(kicad_pcb
	(version 20260206)
	(generator "pcbnew")
	(generator_version "10.0")
	(general
		(thickness 1.6)
		(legacy_teardrops no)
	)
	(paper "A4")
	(layers
		(0 "F.Cu" signal "TOP")
		(4 "In1.Cu" signal "GND")
		(6 "In2.Cu" signal "IN1")
		(8 "In3.Cu" signal "GND1")
		(10 "In4.Cu" signal "IN2")
		(12 "In5.Cu" signal "GND2")
		(14 "In6.Cu" signal "IN3")
		(16 "In7.Cu" signal "GND3")
		(18 "In8.Cu" signal "VCC")
		(20 "In9.Cu" signal "VCC1")
		(22 "In10.Cu" signal "GND4")
		(24 "In11.Cu" signal "IN4")
		(26 "In12.Cu" signal "GND5")
		(28 "In13.Cu" signal "IN5")
		(30 "In14.Cu" signal "GND6")
		(32 "In15.Cu" signal "IN6")
		(34 "In16.Cu" signal "GND7")
		(2 "B.Cu" signal "BOTTOM")
		(9 "F.Adhes" user "F.Adhesive")
		(11 "B.Adhes" user "B.Adhesive")
		(13 "F.Paste" user "Package Geometry/Pastemask Top")
		(15 "B.Paste" user "Package Geometry/Pastemask Bottom")
		(5 "F.SilkS" user "Ref Des/Silkscreen Top")
		(7 "B.SilkS" user "Ref Des/Silkscreen Bottom")
		(1 "F.Mask" user "Board Geometry/Soldermask Top")
		(3 "B.Mask" user "Board Geometry/Soldermask Bottom")
		(17 "Dwgs.User" user "User.Drawings")
		(19 "Cmts.User" user "User.Comments")
		(21 "Eco1.User" user "User.Eco1")
		(23 "Eco2.User" user "User.Eco2")
		(25 "Edge.Cuts" user "Board Geometry/Outline")
		(27 "Margin" user)
		(31 "F.CrtYd" user "Package Geometry/Place Bound Top")
		(29 "B.CrtYd" user "Package Geometry/Place Bound Bottom")
		(35 "F.Fab" user "Ref Des/Assembly Top")
		(33 "B.Fab" user "Ref Des/Assembly Bottom")
	)
	(setup
		(pad_to_mask_clearance 0)
		(allow_soldermask_bridges_in_footprints no)
		(tenting
			(front yes)
			(back yes)
		)
		(covering
			(front no)
			(back no)
		)
		(plugging
			(front no)
			(back no)
		)
		(capping no)
		(filling no)
		(pcbplotparams
			(layerselection 0x00000000_00000000_55555555_5755f5ff)
			(plot_on_all_layers_selection 0x00000000_00000000_00000000_00000000)
			(disableapertmacros no)
			(usegerberextensions no)
			(usegerberattributes yes)
			(usegerberadvancedattributes yes)
			(creategerberjobfile yes)
			(dashed_line_dash_ratio 12)
			(dashed_line_gap_ratio 3)
			(svgprecision 4)
			(plotframeref no)
			(mode 1)
			(useauxorigin no)
			(pdf_front_fp_property_popups yes)
			(pdf_back_fp_property_popups yes)
			(pdf_metadata yes)
			(pdf_single_document no)
			(dxfpolygonmode yes)
			(dxfimperialunits yes)
			(dxfusepcbnewfont yes)
			(psnegative no)
			(psa4output no)
			(plot_black_and_white yes)
			(sketchpadsonfab no)
			(plotpadnumbers no)
			(hidednponfab no)
			(sketchdnponfab yes)
			(crossoutdnponfab yes)
			(subtractmaskfromsilk no)
			(outputformat 1)
			(mirror no)
			(drillshape 1)
			(scaleselection 1)
			(outputdirectory "")
		)
	)
	(footprint ""
		(layer "F.Cu")
		(at 72.26681 -74.901552 -90)
		(property "Reference" "R3095"
			(at 0 0 270)
			(layer "F.SilkS")
			(hide yes)
			(effects
				(font
					(size 1.27 1.27)
				)
			)
		)
		(property "Value" ""
			(at 0 0 270)
			(layer "F.Fab")
			(effects
				(font
					(size 1.27 1.27)
				)
			)
		)
		(duplicate_pad_numbers_are_jumpers no)
		(fp_line
			(start -0.7874 0.4064)
			(end -0.7874 -0.4064)
			(stroke
				(width 0.1524)
				(type default)
			)
			(layer "F.SilkS")
		)
		(fp_line
			(start 0.7874 0.4064)
			(end -0.7874 0.4064)
			(stroke
				(width 0.1524)
				(type default)
			)
			(layer "F.SilkS")
		)
		(fp_line
			(start -0.7874 -0.4064)
			(end 0.7874 -0.4064)
			(stroke
				(width 0.1524)
				(type default)
			)
			(layer "F.SilkS")
		)
		(fp_line
			(start 0.7874 -0.4064)
			(end 0.7874 0.4064)
			(stroke
				(width 0.1524)
				(type default)
			)
			(layer "F.SilkS")
		)
		(fp_line
			(start -0.67945 0.3048)
			(end -0.67945 -0.305054)
			(stroke
				(width 0.1)
				(type default)
			)
			(layer "F.Fab")
		)
		(fp_line
			(start -0.12065 0.3048)
			(end -0.67945 0.3048)
			(stroke
				(width 0.1)
				(type default)
			)
			(layer "F.Fab")
		)
		(fp_line
			(start 0.120396 0.3048)
			(end 0.120396 0.2794)
			(stroke
				(width 0.1)
				(type default)
			)
			(layer "F.Fab")
		)
		(fp_line
			(start 0.67945 0.3048)
			(end 0.120396 0.3048)
			(stroke
				(width 0.1)
				(type default)
			)
			(layer "F.Fab")
		)
		(fp_line
			(start -0.12065 0.2794)
			(end -0.12065 0.3048)
			(stroke
				(width 0.1)
				(type default)
			)
			(layer "F.Fab")
		)
		(fp_line
			(start 0.120396 0.2794)
			(end -0.12065 0.2794)
			(stroke
				(width 0.1)
				(type default)
			)
			(layer "F.Fab")
		)
		(fp_line
			(start -0.12065 -0.2794)
			(end 0.12065 -0.2794)
			(stroke
				(width 0.1)
				(type default)
			)
			(layer "F.Fab")
		)
		(fp_line
			(start 0.12065 -0.2794)
			(end 0.12065 -0.3048)
			(stroke
				(width 0.1)
				(type default)
			)
			(layer "F.Fab")
		)
		(fp_line
			(start 0.12065 -0.3048)
			(end 0.67945 -0.3048)
			(stroke
				(width 0.1)
				(type default)
			)
			(layer "F.Fab")
		)
		(fp_line
			(start 0.67945 -0.3048)
			(end 0.67945 0.3048)
			(stroke
				(width 0.1)
				(type default)
			)
			(layer "F.Fab")
		)
		(fp_line
			(start -0.67945 -0.305054)
			(end -0.12065 -0.305054)
			(stroke
				(width 0.1)
				(type default)
			)
			(layer "F.Fab")
		)
		(fp_line
			(start -0.12065 -0.305054)
			(end -0.12065 -0.2794)
			(stroke
				(width 0.1)
				(type default)
			)
			(layer "F.Fab")
		)
		(pad "1" smd circle
			(at -0.40005 0 270)
			(size 0 0)
			(layers "F.Cu" "F.Mask" "F.Paste")
			(net "LED_PWRGD_PVCCFA_EHV_FIVRA_CPU1")
		)
		(pad "2" smd circle
			(at 0.40005 0 270)
			(size 0 0)
			(layers "F.Cu" "F.Mask" "F.Paste")
			(net "P3V3_AUX")
		)
	)
	(footprint ""
		(layer "F.Cu")
		(at 398.133824 -186.865514)
		(property "Reference" "PR521"
			(at 0 0 0)
			(layer "F.SilkS")
			(hide yes)
			(effects
				(font
					(size 1.27 1.27)
				)
			)
		)
		(property "Value" ""
			(at 0 0 0)
			(layer "F.Fab")
			(effects
				(font
					(size 1.27 1.27)
				)
			)
		)
		(duplicate_pad_numbers_are_jumpers no)
		(fp_line
			(start -0.7874 -0.4064)
			(end 0.7874 -0.4064)
			(stroke
				(width 0.1524)
				(type default)
			)
			(layer "F.SilkS")
		)
		(fp_line
			(start -0.7874 0.4064)
			(end -0.7874 -0.4064)
			(stroke
				(width 0.1524)
				(type default)
			)
			(layer "F.SilkS")
		)
		(fp_line
			(start 0.7874 -0.4064)
			(end 0.7874 0.4064)
			(stroke
				(width 0.1524)
				(type default)
			)
			(layer "F.SilkS")
		)
		(fp_line
			(start 0.7874 0.4064)
			(end -0.7874 0.4064)
			(stroke
				(width 0.1524)
				(type default)
			)
			(layer "F.SilkS")
		)
		(fp_line
			(start -0.67945 -0.305054)
			(end -0.12065 -0.305054)
			(stroke
				(width 0.1)
				(type default)
			)
			(layer "F.Fab")
		)
		(fp_line
			(start -0.67945 0.3048)
			(end -0.67945 -0.305054)
			(stroke
				(width 0.1)
				(type default)
			)
			(layer "F.Fab")
		)
		(fp_line
			(start -0.12065 -0.305054)
			(end -0.12065 -0.2794)
			(stroke
				(width 0.1)
				(type default)
			)
			(layer "F.Fab")
		)
		(fp_line
			(start -0.12065 -0.2794)
			(end 0.12065 -0.2794)
			(stroke
				(width 0.1)
				(type default)
			)
			(layer "F.Fab")
		)
		(fp_line
			(start -0.12065 0.2794)
			(end -0.12065 0.3048)
			(stroke
				(width 0.1)
				(type default)
			)
			(layer "F.Fab")
		)
		(fp_line
			(start -0.12065 0.3048)
			(end -0.67945 0.3048)
			(stroke
				(width 0.1)
				(type default)
			)
			(layer "F.Fab")
		)
		(fp_line
			(start 0.120396 0.2794)
			(end -0.12065 0.2794)
			(stroke
				(width 0.1)
				(type default)
			)
			(layer "F.Fab")
		)
		(fp_line
			(start 0.120396 0.3048)
			(end 0.120396 0.2794)
			(stroke
				(width 0.1)
				(type default)
			)
			(layer "F.Fab")
		)
		(fp_line
			(start 0.12065 -0.3048)
			(end 0.67945 -0.3048)
			(stroke
				(width 0.1)
				(type default)
			)
			(layer "F.Fab")
		)
		(fp_line
			(start 0.12065 -0.2794)
			(end 0.12065 -0.3048)
			(stroke
				(width 0.1)
				(type default)
			)
			(layer "F.Fab")
		)
		(fp_line
			(start 0.67945 -0.3048)
			(end 0.67945 0.3048)
			(stroke
				(width 0.1)
				(type default)
			)
			(layer "F.Fab")
		)
		(fp_line
			(start 0.67945 0.3048)
			(end 0.120396 0.3048)
			(stroke
				(width 0.1)
				(type default)
			)
			(layer "F.Fab")
		)
		(pad "1" smd circle
			(at -0.40005 0)
			(size 0 0)
			(layers "F.Cu" "F.Mask" "F.Paste")
			(net "VSENSE_PVCCINFAON_CPU0_DP")
		)
		(pad "2" smd circle
			(at 0.40005 0)
			(size 0 0)
			(layers "F.Cu" "F.Mask" "F.Paste")
			(net "PVCCINFAON_CPU0")
		)
	)
	(footprint ""
		(layer "F.Cu")
		(at 209.74558 -128.544828 180)
		(property "Reference" "R1693"
			(at 0 0 180)
			(layer "F.SilkS")
			(hide yes)
			(effects
				(font
					(size 1.27 1.27)
				)
			)
		)
		(property "Value" ""
			(at 0 0 180)
			(layer "F.Fab")
			(effects
				(font
					(size 1.27 1.27)
				)
			)
		)
		(duplicate_pad_numbers_are_jumpers no)
		(fp_line
			(start 0.7874 0.4064)
			(end -0.7874 0.4064)
			(stroke
				(width 0.1524)
				(type default)
			)
			(layer "F.SilkS")
		)
		(fp_line
			(start 0.7874 -0.4064)
			(end 0.7874 0.4064)
			(stroke
				(width 0.1524)
				(type default)
			)
			(layer "F.SilkS")
		)
		(fp_line
			(start -0.7874 0.4064)
			(end -0.7874 -0.4064)
			(stroke
				(width 0.1524)
				(type default)
			)
			(layer "F.SilkS")
		)
		(fp_line
			(start -0.7874 -0.4064)
			(end 0.7874 -0.4064)
			(stroke
				(width 0.1524)
				(type default)
			)
			(layer "F.SilkS")
		)
		(fp_line
			(start 0.67945 0.3048)
			(end 0.120396 0.3048)
			(stroke
				(width 0.1)
				(type default)
			)
			(layer "F.Fab")
		)
		(fp_line
			(start 0.67945 -0.3048)
			(end 0.67945 0.3048)
			(stroke
				(width 0.1)
				(type default)
			)
			(layer "F.Fab")
		)
		(fp_line
			(start 0.12065 -0.2794)
			(end 0.12065 -0.3048)
			(stroke
				(width 0.1)
				(type default)
			)
			(layer "F.Fab")
		)
		(fp_line
			(start 0.12065 -0.3048)
			(end 0.67945 -0.3048)
			(stroke
				(width 0.1)
				(type default)
			)
			(layer "F.Fab")
		)
		(fp_line
			(start 0.120396 0.3048)
			(end 0.120396 0.2794)
			(stroke
				(width 0.1)
				(type default)
			)
			(layer "F.Fab")
		)
		(fp_line
			(start 0.120396 0.2794)
			(end -0.12065 0.2794)
			(stroke
				(width 0.1)
				(type default)
			)
			(layer "F.Fab")
		)
		(fp_line
			(start -0.12065 0.3048)
			(end -0.67945 0.3048)
			(stroke
				(width 0.1)
				(type default)
			)
			(layer "F.Fab")
		)
		(fp_line
			(start -0.12065 0.2794)
			(end -0.12065 0.3048)
			(stroke
				(width 0.1)
				(type default)
			)
			(layer "F.Fab")
		)
		(fp_line
			(start -0.12065 -0.2794)
			(end 0.12065 -0.2794)
			(stroke
				(width 0.1)
				(type default)
			)
			(layer "F.Fab")
		)
		(fp_line
			(start -0.12065 -0.305054)
			(end -0.12065 -0.2794)
			(stroke
				(width 0.1)
				(type default)
			)
			(layer "F.Fab")
		)
		(fp_line
			(start -0.67945 0.3048)
			(end -0.67945 -0.305054)
			(stroke
				(width 0.1)
				(type default)
			)
			(layer "F.Fab")
		)
		(fp_line
			(start -0.67945 -0.305054)
			(end -0.12065 -0.305054)
			(stroke
				(width 0.1)
				(type default)
			)
			(layer "F.Fab")
		)
		(pad "1" smd circle
			(at -0.40005 0 180)
			(size 0 0)
			(layers "F.Cu" "F.Mask" "F.Paste")
			(net "PWRGD_DSW_PWROK_R2")
		)
		(pad "2" smd circle
			(at 0.40005 0 180)
			(size 0 0)
			(layers "F.Cu" "F.Mask" "F.Paste")
			(net "PWRGD_DSW_PWROK")
		)
	)
	(footprint ""
		(layer "F.Cu")
		(at 196.329808 -402.766022 90)
		(property "Reference" "PC1525"
			(at 0 0 90)
			(layer "F.SilkS")
			(hide yes)
			(effects
				(font
					(size 1.27 1.27)
				)
			)
		)
		(property "Value" ""
			(at 0 0 90)
			(layer "F.Fab")
			(effects
				(font
					(size 1.27 1.27)
				)
			)
		)
		(duplicate_pad_numbers_are_jumpers no)
		(fp_line
			(start 0.7874 -0.4064)
			(end 0.7874 0.4064)
			(stroke
				(width 0.1524)
				(type default)
			)
			(layer "F.SilkS")
		)
		(fp_line
			(start -0.7874 -0.4064)
			(end 0.7874 -0.4064)
			(stroke
				(width 0.1524)
				(type default)
			)
			(layer "F.SilkS")
		)
		(fp_line
			(start 0.7874 0.4064)
			(end -0.7874 0.4064)
			(stroke
				(width 0.1524)
				(type default)
			)
			(layer "F.SilkS")
		)
		(fp_line
			(start -0.7874 0.4064)
			(end -0.7874 -0.4064)
			(stroke
				(width 0.1524)
				(type default)
			)
			(layer "F.SilkS")
		)
		(fp_line
			(start -0.12065 -0.305054)
			(end -0.12065 -0.2794)
			(stroke
				(width 0.1)
				(type default)
			)
			(layer "F.Fab")
		)
		(fp_line
			(start -0.67945 -0.305054)
			(end -0.12065 -0.305054)
			(stroke
				(width 0.1)
				(type default)
			)
			(layer "F.Fab")
		)
		(fp_line
			(start 0.67945 -0.3048)
			(end 0.67945 0.3048)
			(stroke
				(width 0.1)
				(type default)
			)
			(layer "F.Fab")
		)
		(fp_line
			(start 0.12065 -0.3048)
			(end 0.67945 -0.3048)
			(stroke
				(width 0.1)
				(type default)
			)
			(layer "F.Fab")
		)
		(fp_line
			(start 0.12065 -0.2794)
			(end 0.12065 -0.3048)
			(stroke
				(width 0.1)
				(type default)
			)
			(layer "F.Fab")
		)
		(fp_line
			(start -0.12065 -0.2794)
			(end 0.12065 -0.2794)
			(stroke
				(width 0.1)
				(type default)
			)
			(layer "F.Fab")
		)
		(fp_line
			(start 0.120396 0.2794)
			(end -0.12065 0.2794)
			(stroke
				(width 0.1)
				(type default)
			)
			(layer "F.Fab")
		)
		(fp_line
			(start -0.12065 0.2794)
			(end -0.12065 0.3048)
			(stroke
				(width 0.1)
				(type default)
			)
			(layer "F.Fab")
		)
		(fp_line
			(start 0.67945 0.3048)
			(end 0.120396 0.3048)
			(stroke
				(width 0.1)
				(type default)
			)
			(layer "F.Fab")
		)
		(fp_line
			(start 0.120396 0.3048)
			(end 0.120396 0.2794)
			(stroke
				(width 0.1)
				(type default)
			)
			(layer "F.Fab")
		)
		(fp_line
			(start -0.12065 0.3048)
			(end -0.67945 0.3048)
			(stroke
				(width 0.1)
				(type default)
			)
			(layer "F.Fab")
		)
		(fp_line
			(start -0.67945 0.3048)
			(end -0.67945 -0.305054)
			(stroke
				(width 0.1)
				(type default)
			)
			(layer "F.Fab")
		)
		(pad "1" smd circle
			(at -0.40005 0 90)
			(size 0 0)
			(layers "F.Cu" "F.Mask" "F.Paste")
			(net "HSC_VDD_R_1")
		)
		(pad "2" smd circle
			(at 0.40005 0 90)
			(size 0 0)
			(layers "F.Cu" "F.Mask" "F.Paste")
			(net "AGND_HSC")
		)
	)
	(footprint ""
		(layer "F.Cu")
		(at 438.87771 -44.976288 180)
		(property "Reference" "R3240"
			(at 0 0 180)
			(layer "F.SilkS")
			(hide yes)
			(effects
				(font
					(size 1.27 1.27)
				)
			)
		)
		(property "Value" ""
			(at 0 0 180)
			(layer "F.Fab")
			(effects
				(font
					(size 1.27 1.27)
				)
			)
		)
		(duplicate_pad_numbers_are_jumpers no)
		(fp_line
			(start 0.7874 0.4064)
			(end -0.7874 0.4064)
			(stroke
				(width 0.1524)
				(type default)
			)
			(layer "F.SilkS")
		)
		(fp_line
			(start 0.7874 -0.4064)
			(end 0.7874 0.4064)
			(stroke
				(width 0.1524)
				(type default)
			)
			(layer "F.SilkS")
		)
		(fp_line
			(start -0.7874 0.4064)
			(end -0.7874 -0.4064)
			(stroke
				(width 0.1524)
				(type default)
			)
			(layer "F.SilkS")
		)
		(fp_line
			(start -0.7874 -0.4064)
			(end 0.7874 -0.4064)
			(stroke
				(width 0.1524)
				(type default)
			)
			(layer "F.SilkS")
		)
		(fp_line
			(start 0.67945 0.3048)
			(end 0.120396 0.3048)
			(stroke
				(width 0.1)
				(type default)
			)
			(layer "F.Fab")
		)
		(fp_line
			(start 0.67945 -0.3048)
			(end 0.67945 0.3048)
			(stroke
				(width 0.1)
				(type default)
			)
			(layer "F.Fab")
		)
		(fp_line
			(start 0.12065 -0.2794)
			(end 0.12065 -0.3048)
			(stroke
				(width 0.1)
				(type default)
			)
			(layer "F.Fab")
		)
		(fp_line
			(start 0.12065 -0.3048)
			(end 0.67945 -0.3048)
			(stroke
				(width 0.1)
				(type default)
			)
			(layer "F.Fab")
		)
		(fp_line
			(start 0.120396 0.3048)
			(end 0.120396 0.2794)
			(stroke
				(width 0.1)
				(type default)
			)
			(layer "F.Fab")
		)
		(fp_line
			(start 0.120396 0.2794)
			(end -0.12065 0.2794)
			(stroke
				(width 0.1)
				(type default)
			)
			(layer "F.Fab")
		)
		(fp_line
			(start -0.12065 0.3048)
			(end -0.67945 0.3048)
			(stroke
				(width 0.1)
				(type default)
			)
			(layer "F.Fab")
		)
		(fp_line
			(start -0.12065 0.2794)
			(end -0.12065 0.3048)
			(stroke
				(width 0.1)
				(type default)
			)
			(layer "F.Fab")
		)
		(fp_line
			(start -0.12065 -0.2794)
			(end 0.12065 -0.2794)
			(stroke
				(width 0.1)
				(type default)
			)
			(layer "F.Fab")
		)
		(fp_line
			(start -0.12065 -0.305054)
			(end -0.12065 -0.2794)
			(stroke
				(width 0.1)
				(type default)
			)
			(layer "F.Fab")
		)
		(fp_line
			(start -0.67945 0.3048)
			(end -0.67945 -0.305054)
			(stroke
				(width 0.1)
				(type default)
			)
			(layer "F.Fab")
		)
		(fp_line
			(start -0.67945 -0.305054)
			(end -0.12065 -0.305054)
			(stroke
				(width 0.1)
				(type default)
			)
			(layer "F.Fab")
		)
		(pad "1" smd circle
			(at -0.40005 0 180)
			(size 0 0)
			(layers "F.Cu" "F.Mask" "F.Paste")
			(net "SMB_OCP_SFF_3V3AUX_SCL")
		)
		(pad "2" smd circle
			(at 0.40005 0 180)
			(size 0 0)
			(layers "F.Cu" "F.Mask" "F.Paste")
			(net "P3V3_AUX")
		)
	)
	(footprint ""
		(layer "F.Cu")
		(at 349.100648 -408.517344 -90)
		(property "Reference" "C931"
			(at 0 0 270)
			(layer "F.SilkS")
			(hide yes)
			(effects
				(font
					(size 1.27 1.27)
				)
			)
		)
		(property "Value" ""
			(at 0 0 270)
			(layer "F.Fab")
			(effects
				(font
					(size 1.27 1.27)
				)
			)
		)
		(duplicate_pad_numbers_are_jumpers no)
		(fp_line
			(start -0.299974 0.150114)
			(end -0.299974 -0.150114)
			(stroke
				(width 0.1)
				(type default)
			)
			(layer "F.Fab")
		)
		(fp_line
			(start 0.299974 0.150114)
			(end -0.299974 0.150114)
			(stroke
				(width 0.1)
				(type default)
			)
			(layer "F.Fab")
		)
		(fp_line
			(start -0.299974 -0.150114)
			(end 0.299974 -0.150114)
			(stroke
				(width 0.1)
				(type default)
			)
			(layer "F.Fab")
		)
		(fp_line
			(start 0.299974 -0.150114)
			(end 0.299974 0.150114)
			(stroke
				(width 0.1)
				(type default)
			)
			(layer "F.Fab")
		)
		(pad "1" smd rect
			(at -0.2667 0 270)
			(size 0.3048 0.381)
			(layers "F.Cu" "F.Mask" "F.Paste")
			(net "P5E_CPU0_PE0_TX_C_DP<1>")
		)
		(pad "2" smd rect
			(at 0.2667 0 270)
			(size 0.3048 0.381)
			(layers "F.Cu" "F.Mask" "F.Paste")
			(net "P5E_CPU0_PE0_TX_DP<1>")
		)
	)
	(footprint ""
		(layer "F.Cu")
		(at 203.7588 -92.6338 -90)
		(property "Reference" "C2381"
			(at 0 0 270)
			(layer "F.SilkS")
			(hide yes)
			(effects
				(font
					(size 1.27 1.27)
				)
			)
		)
		(property "Value" ""
			(at 0 0 270)
			(layer "F.Fab")
			(effects
				(font
					(size 1.27 1.27)
				)
			)
		)
		(duplicate_pad_numbers_are_jumpers no)
		(fp_line
			(start -0.7874 0.4064)
			(end -0.7874 -0.4064)
			(stroke
				(width 0.1524)
				(type default)
			)
			(layer "F.SilkS")
		)
		(fp_line
			(start 0.7874 0.4064)
			(end -0.7874 0.4064)
			(stroke
				(width 0.1524)
				(type default)
			)
			(layer "F.SilkS")
		)
		(fp_line
			(start -0.7874 -0.4064)
			(end 0.7874 -0.4064)
			(stroke
				(width 0.1524)
				(type default)
			)
			(layer "F.SilkS")
		)
		(fp_line
			(start 0.7874 -0.4064)
			(end 0.7874 0.4064)
			(stroke
				(width 0.1524)
				(type default)
			)
			(layer "F.SilkS")
		)
		(fp_line
			(start -0.67945 0.3048)
			(end -0.67945 -0.305054)
			(stroke
				(width 0.1)
				(type default)
			)
			(layer "F.Fab")
		)
		(fp_line
			(start -0.12065 0.3048)
			(end -0.67945 0.3048)
			(stroke
				(width 0.1)
				(type default)
			)
			(layer "F.Fab")
		)
		(fp_line
			(start 0.120396 0.3048)
			(end 0.120396 0.2794)
			(stroke
				(width 0.1)
				(type default)
			)
			(layer "F.Fab")
		)
		(fp_line
			(start 0.67945 0.3048)
			(end 0.120396 0.3048)
			(stroke
				(width 0.1)
				(type default)
			)
			(layer "F.Fab")
		)
		(fp_line
			(start -0.12065 0.2794)
			(end -0.12065 0.3048)
			(stroke
				(width 0.1)
				(type default)
			)
			(layer "F.Fab")
		)
		(fp_line
			(start 0.120396 0.2794)
			(end -0.12065 0.2794)
			(stroke
				(width 0.1)
				(type default)
			)
			(layer "F.Fab")
		)
		(fp_line
			(start -0.12065 -0.2794)
			(end 0.12065 -0.2794)
			(stroke
				(width 0.1)
				(type default)
			)
			(layer "F.Fab")
		)
		(fp_line
			(start 0.12065 -0.2794)
			(end 0.12065 -0.3048)
			(stroke
				(width 0.1)
				(type default)
			)
			(layer "F.Fab")
		)
		(fp_line
			(start 0.12065 -0.3048)
			(end 0.67945 -0.3048)
			(stroke
				(width 0.1)
				(type default)
			)
			(layer "F.Fab")
		)
		(fp_line
			(start 0.67945 -0.3048)
			(end 0.67945 0.3048)
			(stroke
				(width 0.1)
				(type default)
			)
			(layer "F.Fab")
		)
		(fp_line
			(start -0.67945 -0.305054)
			(end -0.12065 -0.305054)
			(stroke
				(width 0.1)
				(type default)
			)
			(layer "F.Fab")
		)
		(fp_line
			(start -0.12065 -0.305054)
			(end -0.12065 -0.2794)
			(stroke
				(width 0.1)
				(type default)
			)
			(layer "F.Fab")
		)
		(pad "1" smd circle
			(at -0.40005 0 270)
			(size 0 0)
			(layers "F.Cu" "F.Mask" "F.Paste")
			(net "P12V_AUX_UV_ADR_TRIGGER")
		)
		(pad "2" smd circle
			(at 0.40005 0 270)
			(size 0 0)
			(layers "F.Cu" "F.Mask" "F.Paste")
			(net "GND")
		)
	)
	(footprint ""
		(layer "F.Cu")
		(at 180.528468 -50.974498 180)
		(property "Reference" "C1102"
			(at 0 0 180)
			(layer "F.SilkS")
			(hide yes)
			(effects
				(font
					(size 1.27 1.27)
				)
			)
		)
		(property "Value" ""
			(at 0 0 180)
			(layer "F.Fab")
			(effects
				(font
					(size 1.27 1.27)
				)
			)
		)
		(duplicate_pad_numbers_are_jumpers no)
		(fp_line
			(start 0.299974 0.150114)
			(end -0.299974 0.150114)
			(stroke
				(width 0.1)
				(type default)
			)
			(layer "F.Fab")
		)
		(fp_line
			(start 0.299974 -0.150114)
			(end 0.299974 0.150114)
			(stroke
				(width 0.1)
				(type default)
			)
			(layer "F.Fab")
		)
		(fp_line
			(start -0.299974 0.150114)
			(end -0.299974 -0.150114)
			(stroke
				(width 0.1)
				(type default)
			)
			(layer "F.Fab")
		)
		(fp_line
			(start -0.299974 -0.150114)
			(end 0.299974 -0.150114)
			(stroke
				(width 0.1)
				(type default)
			)
			(layer "F.Fab")
		)
		(pad "1" smd rect
			(at -0.2667 0 180)
			(size 0.3048 0.381)
			(layers "F.Cu" "F.Mask" "F.Paste")
			(net "P3E_PCH_M2_TX_DP<1>")
		)
		(pad "2" smd rect
			(at 0.2667 0 180)
			(size 0.3048 0.381)
			(layers "F.Cu" "F.Mask" "F.Paste")
			(net "P3E_PCH_M2_TX_C_DP<1>")
		)
		(zone
			(layer "In1.Cu")
			(hatch none 0.5)
			(connect_pads
				(clearance 0)
			)
			(min_thickness 0.25)
			(keepout
				(tracks not_allowed)
				(vias allowed)
				(pads allowed)
				(copperpour not_allowed)
				(footprints allowed)
			)
			(placement
				(enabled no)
				(sheetname "")
			)
			(fill
				(thermal_gap 0.5)
				(thermal_bridge_width 0.5)
				(island_removal_mode 0)
			)
			(polygon
				(pts
					(arc
						(start 180.388768 -51.215798)
						(mid 180.44265 -51.19348)
						(end 180.464968 -51.139598)
					)
					(arc
						(start 180.464968 -50.809398)
						(mid 180.44265 -50.755516)
						(end 180.388768 -50.733198)
					)
					(arc
						(start 180.134768 -50.733198)
						(mid 180.080886 -50.755516)
						(end 180.058568 -50.809398)
					)
					(arc
						(start 180.058568 -51.139598)
						(mid 180.080886 -51.19348)
						(end 180.134768 -51.215798)
					)
				)
			)
		)
		(zone
			(layer "In1.Cu")
			(hatch none 0.5)
			(connect_pads
				(clearance 0)
			)
			(min_thickness 0.25)
			(keepout
				(tracks not_allowed)
				(vias allowed)
				(pads allowed)
				(copperpour not_allowed)
				(footprints allowed)
			)
			(placement
				(enabled no)
				(sheetname "")
			)
			(fill
				(thermal_gap 0.5)
				(thermal_bridge_width 0.5)
				(island_removal_mode 0)
			)
			(polygon
				(pts
					(arc
						(start 180.922168 -51.215798)
						(mid 180.97605 -51.19348)
						(end 180.998368 -51.139598)
					)
					(arc
						(start 180.998368 -50.809398)
						(mid 180.97605 -50.755516)
						(end 180.922168 -50.733198)
					)
					(arc
						(start 180.668168 -50.733198)
						(mid 180.614286 -50.755516)
						(end 180.591968 -50.809398)
					)
					(arc
						(start 180.591968 -51.139598)
						(mid 180.614286 -51.19348)
						(end 180.668168 -51.215798)
					)
				)
			)
		)
	)
	(footprint ""
		(layer "F.Cu")
		(at 438.28208 -16.220948 -90)
		(property "Reference" "R416"
			(at 0 0 270)
			(layer "F.SilkS")
			(hide yes)
			(effects
				(font
					(size 1.27 1.27)
				)
			)
		)
		(property "Value" ""
			(at 0 0 270)
			(layer "F.Fab")
			(effects
				(font
					(size 1.27 1.27)
				)
			)
		)
		(duplicate_pad_numbers_are_jumpers no)
		(fp_line
			(start -0.7874 0.4064)
			(end -0.7874 -0.4064)
			(stroke
				(width 0.1524)
				(type default)
			)
			(layer "F.SilkS")
		)
		(fp_line
			(start 0.7874 0.4064)
			(end -0.7874 0.4064)
			(stroke
				(width 0.1524)
				(type default)
			)
			(layer "F.SilkS")
		)
		(fp_line
			(start -0.7874 -0.4064)
			(end 0.7874 -0.4064)
			(stroke
				(width 0.1524)
				(type default)
			)
			(layer "F.SilkS")
		)
		(fp_line
			(start 0.7874 -0.4064)
			(end 0.7874 0.4064)
			(stroke
				(width 0.1524)
				(type default)
			)
			(layer "F.SilkS")
		)
		(fp_line
			(start -0.67945 0.3048)
			(end -0.67945 -0.305054)
			(stroke
				(width 0.1)
				(type default)
			)
			(layer "F.Fab")
		)
		(fp_line
			(start -0.12065 0.3048)
			(end -0.67945 0.3048)
			(stroke
				(width 0.1)
				(type default)
			)
			(layer "F.Fab")
		)
		(fp_line
			(start 0.120396 0.3048)
			(end 0.120396 0.2794)
			(stroke
				(width 0.1)
				(type default)
			)
			(layer "F.Fab")
		)
		(fp_line
			(start 0.67945 0.3048)
			(end 0.120396 0.3048)
			(stroke
				(width 0.1)
				(type default)
			)
			(layer "F.Fab")
		)
		(fp_line
			(start -0.12065 0.2794)
			(end -0.12065 0.3048)
			(stroke
				(width 0.1)
				(type default)
			)
			(layer "F.Fab")
		)
		(fp_line
			(start 0.120396 0.2794)
			(end -0.12065 0.2794)
			(stroke
				(width 0.1)
				(type default)
			)
			(layer "F.Fab")
		)
		(fp_line
			(start -0.12065 -0.2794)
			(end 0.12065 -0.2794)
			(stroke
				(width 0.1)
				(type default)
			)
			(layer "F.Fab")
		)
		(fp_line
			(start 0.12065 -0.2794)
			(end 0.12065 -0.3048)
			(stroke
				(width 0.1)
				(type default)
			)
			(layer "F.Fab")
		)
		(fp_line
			(start 0.12065 -0.3048)
			(end 0.67945 -0.3048)
			(stroke
				(width 0.1)
				(type default)
			)
			(layer "F.Fab")
		)
		(fp_line
			(start 0.67945 -0.3048)
			(end 0.67945 0.3048)
			(stroke
				(width 0.1)
				(type default)
			)
			(layer "F.Fab")
		)
		(fp_line
			(start -0.67945 -0.305054)
			(end -0.12065 -0.305054)
			(stroke
				(width 0.1)
				(type default)
			)
			(layer "F.Fab")
		)
		(fp_line
			(start -0.12065 -0.305054)
			(end -0.12065 -0.2794)
			(stroke
				(width 0.1)
				(type default)
			)
			(layer "F.Fab")
		)
		(pad "1" smd circle
			(at -0.40005 0 270)
			(size 0 0)
			(layers "F.Cu" "F.Mask" "F.Paste")
			(net "OCP_SFF_ISO_BIF0_EN")
		)
		(pad "2" smd circle
			(at 0.40005 0 270)
			(size 0 0)
			(layers "F.Cu" "F.Mask" "F.Paste")
			(net "OCP_SFF_BIF0_R_N")
		)
	)
	(footprint ""
		(layer "F.Cu")
		(at 145.940018 -251.76988)
		(property "Reference" "H26"
			(at 2.44602 -1.372108 0)
			(unlocked yes)
			(layer "F.SilkS")
			(effects
				(font
					(size 0.7874 0.5842)
					(thickness 0.1524)
				)
				(justify left)
			)
		)
		(property "Value" ""
			(at 0 0 0)
			(layer "F.Fab")
			(effects
				(font
					(size 1.27 1.27)
				)
			)
		)
		(duplicate_pad_numbers_are_jumpers no)
		(fp_circle
			(center 0 0)
			(end 2.5273 0)
			(stroke
				(width 0.1524)
				(type default)
			)
			(fill no)
			(layer "F.SilkS")
		)
		(fp_circle
			(center 0 0)
			(end 2.5273 0)
			(stroke
				(width 0.1524)
				(type default)
			)
			(fill no)
			(layer "B.SilkS")
		)
		(fp_circle
			(center 0 0)
			(end 2.5273 0)
			(stroke
				(width 0.1)
				(type default)
			)
			(fill no)
			(layer "B.Fab")
		)
		(fp_circle
			(center 0 0)
			(end 2.5273 0)
			(stroke
				(width 0.1)
				(type default)
			)
			(fill no)
			(layer "F.Fab")
		)
		(pad "" np_thru_hole circle
			(at 0 0)
			(size 3.429 3.429)
			(drill 3.429)
			(layers "*.Cu" "*.Mask")
			(clearance 0.381)
			(thermal_gap 0.381)
		)
	)
	(footprint ""
		(layer "F.Cu")
		(at 440.60491 -179.92217)
		(property "Reference" "PL120"
			(at -0.05842 4.39293 0)
			(unlocked yes)
			(layer "F.SilkS")
			(effects
				(font
					(size 0.7874 0.5842)
					(thickness 0.1524)
				)
				(justify left)
			)
		)
		(property "Value" ""
			(at 0 0 0)
			(layer "F.Fab")
			(effects
				(font
					(size 1.27 1.27)
				)
			)
		)
		(duplicate_pad_numbers_are_jumpers no)
		(fp_line
			(start -3.6576 -3.350006)
			(end 3.64998 -3.350006)
			(stroke
				(width 0.1524)
				(type default)
			)
			(layer "F.SilkS")
		)
		(fp_line
			(start -3.64998 -1.8034)
			(end -3.64998 -3.350006)
			(stroke
				(width 0.1524)
				(type default)
			)
			(layer "F.SilkS")
		)
		(fp_line
			(start -3.64998 3.350006)
			(end -3.64998 1.8288)
			(stroke
				(width 0.1524)
				(type default)
			)
			(layer "F.SilkS")
		)
		(fp_line
			(start 3.64998 -3.350006)
			(end 3.64998 -1.8034)
			(stroke
				(width 0.1524)
				(type default)
			)
			(layer "F.SilkS")
		)
		(fp_line
			(start 3.64998 1.8034)
			(end 3.64998 3.350006)
			(stroke
				(width 0.1524)
				(type default)
			)
			(layer "F.SilkS")
		)
		(fp_line
			(start 3.64998 3.350006)
			(end -3.64998 3.350006)
			(stroke
				(width 0.1524)
				(type default)
			)
			(layer "F.SilkS")
		)
		(fp_line
			(start -3.64998 -3.350006)
			(end 3.64998 -3.350006)
			(stroke
				(width 0.1)
				(type default)
			)
			(layer "F.Fab")
		)
		(fp_line
			(start -3.64998 3.350006)
			(end -3.64998 -3.350006)
			(stroke
				(width 0.1)
				(type default)
			)
			(layer "F.Fab")
		)
		(fp_line
			(start 3.64998 -3.350006)
			(end 3.64998 3.350006)
			(stroke
				(width 0.1)
				(type default)
			)
			(layer "F.Fab")
		)
		(fp_line
			(start 3.64998 3.350006)
			(end -3.64998 3.350006)
			(stroke
				(width 0.1)
				(type default)
			)
			(layer "F.Fab")
		)
		(pad "1" smd rect
			(at -2.92481 0)
			(size 2.15392 3.302)
			(layers "F.Cu" "F.Mask" "F.Paste")
			(net "SW_PVNN_MAIN_CPU0_SW")
		)
		(pad "2" smd rect
			(at 2.92481 0)
			(size 2.15392 3.302)
			(layers "F.Cu" "F.Mask" "F.Paste")
			(net "PVNN_MAIN_CPU0")
		)
	)
	(footprint ""
		(layer "F.Cu")
		(at 381.148844 -337.214718 -90)
		(property "Reference" "PC255_P0_5"
			(at 0 0 270)
			(layer "F.SilkS")
			(hide yes)
			(effects
				(font
					(size 1.27 1.27)
				)
			)
		)
		(property "Value" ""
			(at 0 0 270)
			(layer "F.Fab")
			(effects
				(font
					(size 1.27 1.27)
				)
			)
		)
		(duplicate_pad_numbers_are_jumpers no)
		(fp_line
			(start -0.7874 0.4064)
			(end -0.7874 -0.4064)
			(stroke
				(width 0.1524)
				(type default)
			)
			(layer "F.SilkS")
		)
		(fp_line
			(start 0.7874 0.4064)
			(end -0.7874 0.4064)
			(stroke
				(width 0.1524)
				(type default)
			)
			(layer "F.SilkS")
		)
		(fp_line
			(start -0.7874 -0.4064)
			(end 0.7874 -0.4064)
			(stroke
				(width 0.1524)
				(type default)
			)
			(layer "F.SilkS")
		)
		(fp_line
			(start 0.7874 -0.4064)
			(end 0.7874 0.4064)
			(stroke
				(width 0.1524)
				(type default)
			)
			(layer "F.SilkS")
		)
		(fp_line
			(start -0.67945 0.3048)
			(end -0.67945 -0.305054)
			(stroke
				(width 0.1)
				(type default)
			)
			(layer "F.Fab")
		)
		(fp_line
			(start -0.12065 0.3048)
			(end -0.67945 0.3048)
			(stroke
				(width 0.1)
				(type default)
			)
			(layer "F.Fab")
		)
		(fp_line
			(start 0.120396 0.3048)
			(end 0.120396 0.2794)
			(stroke
				(width 0.1)
				(type default)
			)
			(layer "F.Fab")
		)
		(fp_line
			(start 0.67945 0.3048)
			(end 0.120396 0.3048)
			(stroke
				(width 0.1)
				(type default)
			)
			(layer "F.Fab")
		)
		(fp_line
			(start -0.12065 0.2794)
			(end -0.12065 0.3048)
			(stroke
				(width 0.1)
				(type default)
			)
			(layer "F.Fab")
		)
		(fp_line
			(start 0.120396 0.2794)
			(end -0.12065 0.2794)
			(stroke
				(width 0.1)
				(type default)
			)
			(layer "F.Fab")
		)
		(fp_line
			(start -0.12065 -0.2794)
			(end 0.12065 -0.2794)
			(stroke
				(width 0.1)
				(type default)
			)
			(layer "F.Fab")
		)
		(fp_line
			(start 0.12065 -0.2794)
			(end 0.12065 -0.3048)
			(stroke
				(width 0.1)
				(type default)
			)
			(layer "F.Fab")
		)
		(fp_line
			(start 0.12065 -0.3048)
			(end 0.67945 -0.3048)
			(stroke
				(width 0.1)
				(type default)
			)
			(layer "F.Fab")
		)
		(fp_line
			(start 0.67945 -0.3048)
			(end 0.67945 0.3048)
			(stroke
				(width 0.1)
				(type default)
			)
			(layer "F.Fab")
		)
		(fp_line
			(start -0.67945 -0.305054)
			(end -0.12065 -0.305054)
			(stroke
				(width 0.1)
				(type default)
			)
			(layer "F.Fab")
		)
		(fp_line
			(start -0.12065 -0.305054)
			(end -0.12065 -0.2794)
			(stroke
				(width 0.1)
				(type default)
			)
			(layer "F.Fab")
		)
		(pad "1" smd circle
			(at -0.40005 0 270)
			(size 0 0)
			(layers "F.Cu" "F.Mask" "F.Paste")
			(net "SW_P12V_PVCCIN_CPU0_FLT")
		)
		(pad "2" smd circle
			(at 0.40005 0 270)
			(size 0 0)
			(layers "F.Cu" "F.Mask" "F.Paste")
			(net "GND")
		)
	)
	(footprint ""
		(layer "F.Cu")
		(at 189.28588 -133.695948 90)
		(property "Reference" "R1742"
			(at 0 0 90)
			(layer "F.SilkS")
			(hide yes)
			(effects
				(font
					(size 1.27 1.27)
				)
			)
		)
		(property "Value" ""
			(at 0 0 90)
			(layer "F.Fab")
			(effects
				(font
					(size 1.27 1.27)
				)
			)
		)
		(duplicate_pad_numbers_are_jumpers no)
		(fp_line
			(start 0.7874 -0.4064)
			(end 0.7874 0.4064)
			(stroke
				(width 0.1524)
				(type default)
			)
			(layer "F.SilkS")
		)
		(fp_line
			(start -0.7874 -0.4064)
			(end 0.7874 -0.4064)
			(stroke
				(width 0.1524)
				(type default)
			)
			(layer "F.SilkS")
		)
		(fp_line
			(start 0.7874 0.4064)
			(end -0.7874 0.4064)
			(stroke
				(width 0.1524)
				(type default)
			)
			(layer "F.SilkS")
		)
		(fp_line
			(start -0.7874 0.4064)
			(end -0.7874 -0.4064)
			(stroke
				(width 0.1524)
				(type default)
			)
			(layer "F.SilkS")
		)
		(fp_line
			(start -0.12065 -0.305054)
			(end -0.12065 -0.2794)
			(stroke
				(width 0.1)
				(type default)
			)
			(layer "F.Fab")
		)
		(fp_line
			(start -0.67945 -0.305054)
			(end -0.12065 -0.305054)
			(stroke
				(width 0.1)
				(type default)
			)
			(layer "F.Fab")
		)
		(fp_line
			(start 0.67945 -0.3048)
			(end 0.67945 0.3048)
			(stroke
				(width 0.1)
				(type default)
			)
			(layer "F.Fab")
		)
		(fp_line
			(start 0.12065 -0.3048)
			(end 0.67945 -0.3048)
			(stroke
				(width 0.1)
				(type default)
			)
			(layer "F.Fab")
		)
		(fp_line
			(start 0.12065 -0.2794)
			(end 0.12065 -0.3048)
			(stroke
				(width 0.1)
				(type default)
			)
			(layer "F.Fab")
		)
		(fp_line
			(start -0.12065 -0.2794)
			(end 0.12065 -0.2794)
			(stroke
				(width 0.1)
				(type default)
			)
			(layer "F.Fab")
		)
		(fp_line
			(start 0.120396 0.2794)
			(end -0.12065 0.2794)
			(stroke
				(width 0.1)
				(type default)
			)
			(layer "F.Fab")
		)
		(fp_line
			(start -0.12065 0.2794)
			(end -0.12065 0.3048)
			(stroke
				(width 0.1)
				(type default)
			)
			(layer "F.Fab")
		)
		(fp_line
			(start 0.67945 0.3048)
			(end 0.120396 0.3048)
			(stroke
				(width 0.1)
				(type default)
			)
			(layer "F.Fab")
		)
		(fp_line
			(start 0.120396 0.3048)
			(end 0.120396 0.2794)
			(stroke
				(width 0.1)
				(type default)
			)
			(layer "F.Fab")
		)
		(fp_line
			(start -0.12065 0.3048)
			(end -0.67945 0.3048)
			(stroke
				(width 0.1)
				(type default)
			)
			(layer "F.Fab")
		)
		(fp_line
			(start -0.67945 0.3048)
			(end -0.67945 -0.305054)
			(stroke
				(width 0.1)
				(type default)
			)
			(layer "F.Fab")
		)
		(pad "1" smd circle
			(at -0.40005 0 90)
			(size 0 0)
			(layers "F.Cu" "F.Mask" "F.Paste")
			(net "FM_RST_PERST_BIT0")
		)
		(pad "2" smd circle
			(at 0.40005 0 90)
			(size 0 0)
			(layers "F.Cu" "F.Mask" "F.Paste")
			(net "GND")
		)
	)
	(footprint ""
		(layer "F.Cu")
		(at 351.249488 -408.517344 -90)
		(property "Reference" "C932"
			(at 0 0 270)
			(layer "F.SilkS")
			(hide yes)
			(effects
				(font
					(size 1.27 1.27)
				)
			)
		)
		(property "Value" ""
			(at 0 0 270)
			(layer "F.Fab")
			(effects
				(font
					(size 1.27 1.27)
				)
			)
		)
		(duplicate_pad_numbers_are_jumpers no)
		(fp_line
			(start -0.299974 0.150114)
			(end -0.299974 -0.150114)
			(stroke
				(width 0.1)
				(type default)
			)
			(layer "F.Fab")
		)
		(fp_line
			(start 0.299974 0.150114)
			(end -0.299974 0.150114)
			(stroke
				(width 0.1)
				(type default)
			)
			(layer "F.Fab")
		)
		(fp_line
			(start -0.299974 -0.150114)
			(end 0.299974 -0.150114)
			(stroke
				(width 0.1)
				(type default)
			)
			(layer "F.Fab")
		)
		(fp_line
			(start 0.299974 -0.150114)
			(end 0.299974 0.150114)
			(stroke
				(width 0.1)
				(type default)
			)
			(layer "F.Fab")
		)
		(pad "1" smd rect
			(at -0.2667 0 270)
			(size 0.3048 0.381)
			(layers "F.Cu" "F.Mask" "F.Paste")
			(net "P5E_CPU0_PE0_TX_C_DN<0>")
		)
		(pad "2" smd rect
			(at 0.2667 0 270)
			(size 0.3048 0.381)
			(layers "F.Cu" "F.Mask" "F.Paste")
			(net "P5E_CPU0_PE0_TX_DN<0>")
		)
	)
	(footprint ""
		(layer "F.Cu")
		(at 104.93121 -60.128404)
		(property "Reference" "U85"
			(at -3.9243 0.42545 0)
			(unlocked yes)
			(layer "F.SilkS")
			(effects
				(font
					(size 0.7874 0.5842)
					(thickness 0.1524)
				)
			)
		)
		(property "Value" ""
			(at 0 0 0)
			(layer "F.Fab")
			(effects
				(font
					(size 1.27 1.27)
				)
			)
		)
		(duplicate_pad_numbers_are_jumpers no)
		(fp_line
			(start -1.7272 1.1176)
			(end -1.7272 -1.1176)
			(stroke
				(width 0.1524)
				(type default)
			)
			(layer "F.SilkS")
		)
		(fp_line
			(start -0.254 -1.1176)
			(end -1.7272 -1.1176)
			(stroke
				(width 0.1524)
				(type default)
			)
			(layer "F.SilkS")
		)
		(fp_line
			(start 0 -0.7366)
			(end -0.254 -1.1176)
			(stroke
				(width 0.1524)
				(type default)
			)
			(layer "F.SilkS")
		)
		(fp_line
			(start 0.254 -1.1176)
			(end 0 -0.7366)
			(stroke
				(width 0.1524)
				(type default)
			)
			(layer "F.SilkS")
		)
		(fp_line
			(start 1.7272 -1.1176)
			(end 0.254 -1.1176)
			(stroke
				(width 0.1524)
				(type default)
			)
			(layer "F.SilkS")
		)
		(fp_line
			(start 1.7272 -1.1176)
			(end 1.7272 1.1176)
			(stroke
				(width 0.1524)
				(type default)
			)
			(layer "F.SilkS")
		)
		(fp_line
			(start 1.7272 1.1176)
			(end -1.7272 1.1176)
			(stroke
				(width 0.1524)
				(type default)
			)
			(layer "F.SilkS")
		)
		(fp_poly
			(pts
				(xy -2.7178 -0.268986) (xy -2.7178 -1.030986) (xy -1.9558 -0.649986)
			)
			(stroke
				(width 0)
				(type default)
			)
			(fill yes)
			(layer "F.SilkS")
		)
		(fp_line
			(start -1.5748 -1.1176)
			(end -1.5748 1.1176)
			(stroke
				(width 0.1)
				(type default)
			)
			(layer "F.Fab")
		)
		(fp_line
			(start -1.5748 1.1176)
			(end 1.5748 1.1176)
			(stroke
				(width 0.1)
				(type default)
			)
			(layer "F.Fab")
		)
		(fp_line
			(start 1.5748 -1.1176)
			(end -1.5748 -1.1176)
			(stroke
				(width 0.1)
				(type default)
			)
			(layer "F.Fab")
		)
		(fp_line
			(start 1.5748 1.1176)
			(end 1.5748 -1.1176)
			(stroke
				(width 0.1)
				(type default)
			)
			(layer "F.Fab")
		)
		(fp_poly
			(pts
				(xy -1.9558 -0.649986) (xy -2.7178 -0.268986) (xy -2.7178 -1.030986)
			)
			(stroke
				(width 0)
				(type default)
			)
			(fill yes)
			(layer "F.Fab")
		)
		(pad "1" smd rect
			(at -0.999998 -0.649986 270)
			(size 0.3556 1.1176)
			(layers "F.Cu" "F.Mask" "F.Paste")
			(net "JTAG_BMC_PCH_TCK")
		)
		(pad "2" smd rect
			(at -0.999998 0 270)
			(size 0.3556 1.1176)
			(layers "F.Cu" "F.Mask" "F.Paste")
			(net "GND")
		)
		(pad "3" smd rect
			(at -0.999998 0.649986 270)
			(size 0.3556 1.1176)
			(layers "F.Cu" "F.Mask" "F.Paste")
			(net "JTAG_BMC_CPU_TCK")
		)
		(pad "4" smd rect
			(at 0.999998 0.649986 270)
			(size 0.3556 1.1176)
			(layers "F.Cu" "F.Mask" "F.Paste")
			(net "JTAG_BMC_DBP_TCK")
		)
		(pad "5" smd rect
			(at 0.999998 0 270)
			(size 0.3556 1.1176)
			(layers "F.Cu" "F.Mask" "F.Paste")
			(net "P3V3_AUX")
		)
		(pad "6" smd rect
			(at 0.999998 -0.649986 270)
			(size 0.3556 1.1176)
			(layers "F.Cu" "F.Mask" "F.Paste")
			(net "FM_JTAG_TCK_MUX_SEL")
		)
	)
	(footprint ""
		(layer "F.Cu")
		(at 314.058808 -402.371052 -90)
		(property "Reference" "C1573"
			(at 0 0 270)
			(layer "F.SilkS")
			(hide yes)
			(effects
				(font
					(size 1.27 1.27)
				)
			)
		)
		(property "Value" ""
			(at 0 0 270)
			(layer "F.Fab")
			(effects
				(font
					(size 1.27 1.27)
				)
			)
		)
		(duplicate_pad_numbers_are_jumpers no)
		(fp_line
			(start -0.299974 0.150114)
			(end -0.299974 -0.150114)
			(stroke
				(width 0.1)
				(type default)
			)
			(layer "F.Fab")
		)
		(fp_line
			(start 0.299974 0.150114)
			(end -0.299974 0.150114)
			(stroke
				(width 0.1)
				(type default)
			)
			(layer "F.Fab")
		)
		(fp_line
			(start -0.299974 -0.150114)
			(end 0.299974 -0.150114)
			(stroke
				(width 0.1)
				(type default)
			)
			(layer "F.Fab")
		)
		(fp_line
			(start 0.299974 -0.150114)
			(end 0.299974 0.150114)
			(stroke
				(width 0.1)
				(type default)
			)
			(layer "F.Fab")
		)
		(pad "1" smd rect
			(at -0.2667 0 270)
			(size 0.3048 0.381)
			(layers "F.Cu" "F.Mask" "F.Paste")
			(net "P5E_CPU0_PE4_TX_C_DP<3>")
		)
		(pad "2" smd rect
			(at 0.2667 0 270)
			(size 0.3048 0.381)
			(layers "F.Cu" "F.Mask" "F.Paste")
			(net "P5E_CPU0_PE4_TX_DP<3>")
		)
	)
	(footprint ""
		(layer "F.Cu")
		(at 83.338924 -152.621742 90)
		(property "Reference" "R661"
			(at 0 0 90)
			(layer "F.SilkS")
			(hide yes)
			(effects
				(font
					(size 1.27 1.27)
				)
			)
		)
		(property "Value" ""
			(at 0 0 90)
			(layer "F.Fab")
			(effects
				(font
					(size 1.27 1.27)
				)
			)
		)
		(duplicate_pad_numbers_are_jumpers no)
		(fp_line
			(start 0.7874 -0.4064)
			(end 0.7874 0.4064)
			(stroke
				(width 0.1524)
				(type default)
			)
			(layer "F.SilkS")
		)
		(fp_line
			(start -0.7874 -0.4064)
			(end 0.7874 -0.4064)
			(stroke
				(width 0.1524)
				(type default)
			)
			(layer "F.SilkS")
		)
		(fp_line
			(start 0.7874 0.4064)
			(end -0.7874 0.4064)
			(stroke
				(width 0.1524)
				(type default)
			)
			(layer "F.SilkS")
		)
		(fp_line
			(start -0.7874 0.4064)
			(end -0.7874 -0.4064)
			(stroke
				(width 0.1524)
				(type default)
			)
			(layer "F.SilkS")
		)
		(fp_line
			(start -0.12065 -0.305054)
			(end -0.12065 -0.2794)
			(stroke
				(width 0.1)
				(type default)
			)
			(layer "F.Fab")
		)
		(fp_line
			(start -0.67945 -0.305054)
			(end -0.12065 -0.305054)
			(stroke
				(width 0.1)
				(type default)
			)
			(layer "F.Fab")
		)
		(fp_line
			(start 0.67945 -0.3048)
			(end 0.67945 0.3048)
			(stroke
				(width 0.1)
				(type default)
			)
			(layer "F.Fab")
		)
		(fp_line
			(start 0.12065 -0.3048)
			(end 0.67945 -0.3048)
			(stroke
				(width 0.1)
				(type default)
			)
			(layer "F.Fab")
		)
		(fp_line
			(start 0.12065 -0.2794)
			(end 0.12065 -0.3048)
			(stroke
				(width 0.1)
				(type default)
			)
			(layer "F.Fab")
		)
		(fp_line
			(start -0.12065 -0.2794)
			(end 0.12065 -0.2794)
			(stroke
				(width 0.1)
				(type default)
			)
			(layer "F.Fab")
		)
		(fp_line
			(start 0.120396 0.2794)
			(end -0.12065 0.2794)
			(stroke
				(width 0.1)
				(type default)
			)
			(layer "F.Fab")
		)
		(fp_line
			(start -0.12065 0.2794)
			(end -0.12065 0.3048)
			(stroke
				(width 0.1)
				(type default)
			)
			(layer "F.Fab")
		)
		(fp_line
			(start 0.67945 0.3048)
			(end 0.120396 0.3048)
			(stroke
				(width 0.1)
				(type default)
			)
			(layer "F.Fab")
		)
		(fp_line
			(start 0.120396 0.3048)
			(end 0.120396 0.2794)
			(stroke
				(width 0.1)
				(type default)
			)
			(layer "F.Fab")
		)
		(fp_line
			(start -0.12065 0.3048)
			(end -0.67945 0.3048)
			(stroke
				(width 0.1)
				(type default)
			)
			(layer "F.Fab")
		)
		(fp_line
			(start -0.67945 0.3048)
			(end -0.67945 -0.305054)
			(stroke
				(width 0.1)
				(type default)
			)
			(layer "F.Fab")
		)
		(pad "1" smd circle
			(at -0.40005 0 90)
			(size 0 0)
			(layers "F.Cu" "F.Mask" "F.Paste")
			(net "PD_I3C_SPD_DDR_CPU1_OE_N")
		)
		(pad "2" smd circle
			(at 0.40005 0 90)
			(size 0 0)
			(layers "F.Cu" "F.Mask" "F.Paste")
			(net "GND")
		)
	)
	(footprint ""
		(layer "F.Cu")
		(at 51.25339 -353.547934)
		(property "Reference" "PU76_P1_2"
			(at 6.21411 -1.416304 0)
			(unlocked yes)
			(layer "F.SilkS")
			(effects
				(font
					(size 0.7874 0.5842)
					(thickness 0.1524)
				)
				(justify left)
			)
		)
		(property "Value" ""
			(at 0 0 0)
			(layer "F.Fab")
			(effects
				(font
					(size 1.27 1.27)
				)
			)
		)
		(duplicate_pad_numbers_are_jumpers no)
		(fp_line
			(start -2.500122 -2.999994)
			(end -2.24409 -2.999994)
			(stroke
				(width 0.1524)
				(type default)
			)
			(layer "F.SilkS")
		)
		(fp_line
			(start -2.500122 -2.529078)
			(end -2.500122 -2.999994)
			(stroke
				(width 0.1524)
				(type default)
			)
			(layer "F.SilkS")
		)
		(fp_line
			(start -2.500122 0.6604)
			(end -2.500122 0.229108)
			(stroke
				(width 0.1524)
				(type default)
			)
			(layer "F.SilkS")
		)
		(fp_line
			(start -2.500122 2.999994)
			(end -2.500122 2.339594)
			(stroke
				(width 0.1524)
				(type default)
			)
			(layer "F.SilkS")
		)
		(fp_line
			(start -2.2987 2.999994)
			(end -2.500122 2.999994)
			(stroke
				(width 0.1524)
				(type default)
			)
			(layer "F.SilkS")
		)
		(fp_line
			(start 2.31394 -2.999994)
			(end 2.500122 -2.999994)
			(stroke
				(width 0.1524)
				(type default)
			)
			(layer "F.SilkS")
		)
		(fp_line
			(start 2.500122 -2.999994)
			(end 2.500122 -2.44348)
			(stroke
				(width 0.1524)
				(type default)
			)
			(layer "F.SilkS")
		)
		(fp_line
			(start 2.500122 2.339594)
			(end 2.500122 2.999994)
			(stroke
				(width 0.1524)
				(type default)
			)
			(layer "F.SilkS")
		)
		(fp_line
			(start 2.500122 2.999994)
			(end 2.2987 2.999994)
			(stroke
				(width 0.1524)
				(type default)
			)
			(layer "F.SilkS")
		)
		(fp_poly
			(pts
				(xy -5.285232 -2.866898) (xy -4.269232 -2.358898) (xy -5.285232 -1.850898)
			)
			(stroke
				(width 0)
				(type default)
			)
			(fill yes)
			(layer "F.SilkS")
		)
		(fp_line
			(start -2.500122 -2.999994)
			(end 2.500122 -2.999994)
			(stroke
				(width 0.1)
				(type default)
			)
			(layer "F.Fab")
		)
		(fp_line
			(start -2.500122 2.999994)
			(end -2.500122 -2.999994)
			(stroke
				(width 0.1)
				(type default)
			)
			(layer "F.Fab")
		)
		(fp_line
			(start 2.500122 -2.999994)
			(end 2.500122 2.999994)
			(stroke
				(width 0.1)
				(type default)
			)
			(layer "F.Fab")
		)
		(fp_line
			(start 2.500122 2.999994)
			(end -2.500122 2.999994)
			(stroke
				(width 0.1)
				(type default)
			)
			(layer "F.Fab")
		)
		(fp_poly
			(pts
				(xy -4.218432 -2.783078) (xy -4.218432 -1.767078) (xy -3.202432 -2.275078)
			)
			(stroke
				(width 0)
				(type default)
			)
			(fill yes)
			(layer "F.Fab")
		)
		(pad "1" smd rect
			(at -2.400046 -2.275078 90)
			(size 0.2286 0.6096)
			(layers "F.Cu" "F.Mask" "F.Paste")
			(net "PVCCFA_EHV_FIVRA_CPU1_VOS2")
		)
		(pad "2" smd rect
			(at -2.400046 -1.82499 90)
			(size 0.2286 0.6096)
			(layers "F.Cu" "F.Mask" "F.Paste")
			(net "GND")
		)
		(pad "3" smd rect
			(at -2.400046 -1.374902 90)
			(size 0.2286 0.6096)
			(layers "F.Cu" "F.Mask" "F.Paste")
			(net "PVCCFA_EHV_FIVRA_CPU1_VDD2")
		)
		(pad "4" smd rect
			(at -2.400046 -0.925068 90)
			(size 0.2286 0.6096)
			(layers "F.Cu" "F.Mask" "F.Paste")
			(net "PVCCFA_EHV_FIVRA_CPU1_PVCC2")
		)
		(pad "5" smd rect
			(at -2.400046 -0.47498 90)
			(size 0.2286 0.6096)
			(layers "F.Cu" "F.Mask" "F.Paste")
			(net "GND")
		)
		(pad "6" smd rect
			(at -2.400046 -0.024892 90)
			(size 0.2286 0.6096)
			(layers "F.Cu" "F.Mask" "F.Paste")
			(net "Net_8502")
		)
		(pad "7_9-20_24" smd circle
			(at 0 1.150112 90)
			(size 0 0)
			(layers "F.Cu" "F.Mask" "F.Paste")
			(net "GND")
		)
		(pad "10_19" smd rect
			(at 0 2.899918 90)
			(size 0.6096 4.318)
			(layers "F.Cu" "F.Mask" "F.Paste")
			(net "SW_PVCCFA_EHV_FIVRA_CPU1_SW2")
		)
		(pad "25_29" smd rect
			(at 1.549908 -1.279906 270)
			(size 2.0574 2.3114)
			(layers "F.Cu" "F.Mask" "F.Paste")
			(net "SW_P12V_PVCCFA_EHV_FIVRA_CPU1_L")
		)
		(pad "30" smd rect
			(at 2.05994 -2.899918)
			(size 0.2286 0.6096)
			(layers "F.Cu" "F.Mask" "F.Paste")
			(net "SW_P12V_PVCCFA_EHV_FIVRA_CPU1_L")
		)
		(pad "31" smd rect
			(at 1.610106 -2.899918)
			(size 0.2286 0.6096)
			(layers "F.Cu" "F.Mask" "F.Paste")
			(net "Net_8503")
		)
		(pad "32" smd rect
			(at 1.160018 -2.899918)
			(size 0.2286 0.6096)
			(layers "F.Cu" "F.Mask" "F.Paste")
			(net "SW_PVCCFA_EHV_FIVRA_CPU1_BOOTR2")
		)
		(pad "33" smd rect
			(at 0.70993 -2.899918)
			(size 0.2286 0.6096)
			(layers "F.Cu" "F.Mask" "F.Paste")
			(net "SW_PVCCFA_EHV_FIVRA_CPU1_BOOT2")
		)
		(pad "34" smd rect
			(at 0.260096 -2.899918)
			(size 0.2286 0.6096)
			(layers "F.Cu" "F.Mask" "F.Paste")
			(net "PVCCFA_EHV_FIVRA_CPU1_PWM2")
		)
		(pad "35" smd rect
			(at -0.189992 -2.899918)
			(size 0.2286 0.6096)
			(layers "F.Cu" "F.Mask" "F.Paste")
			(net "PVCCFA_EHV_FIVRA_CPU1_VDD2")
		)
		(pad "36" smd rect
			(at -0.64008 -2.899918)
			(size 0.2286 0.6096)
			(layers "F.Cu" "F.Mask" "F.Paste")
			(net "PVCCFA_EHV_FIVRA_CPU1_BTSEN")
		)
		(pad "37" smd rect
			(at -1.089914 -2.899918)
			(size 0.2286 0.6096)
			(layers "F.Cu" "F.Mask" "F.Paste")
			(net "PVCCFA_EHV_FIVRA_CPU1_LSET2")
		)
		(pad "38" smd rect
			(at -1.540002 -2.899918)
			(size 0.2286 0.6096)
			(layers "F.Cu" "F.Mask" "F.Paste")
			(net "PVCCFA_EHV_FIVRA_CPU1_IMON2")
		)
		(pad "39" smd rect
			(at -1.99009 -2.899918)
			(size 0.2286 0.6096)
			(layers "F.Cu" "F.Mask" "F.Paste")
			(net "PVCCIN_CPU1_VREF")
		)
		(pad "40" smd rect
			(at -0.87503 -1.27508)
			(size 1.7526 1.9558)
			(layers "F.Cu" "F.Mask" "F.Paste")
			(net "GND")
		)
		(pad "41" smd rect
			(at -1.525016 0.249936 270)
			(size 0.3048 0.4572)
			(layers "F.Cu" "F.Mask" "F.Paste")
			(net "Net_8501")
		)
		(zone
			(layer "F.Cu")
			(hatch none 0.5)
			(connect_pads
				(clearance 0)
			)
			(min_thickness 0.25)
			(keepout
				(tracks not_allowed)
				(vias allowed)
				(pads allowed)
				(copperpour not_allowed)
				(footprints allowed)
			)
			(placement
				(enabled no)
				(sheetname "")
			)
			(fill
				(thermal_gap 0.5)
				(thermal_bridge_width 0.5)
				(island_removal_mode 0)
			)
			(polygon
				(pts
					(xy 48.753268 -350.54794) (xy 48.753268 -351.262188) (xy 53.753512 -351.262188) (xy 53.753512 -350.54794)
					(xy 53.46319 -350.54794) (xy 53.46319 -351.003616) (xy 49.04359 -351.003616) (xy 49.04359 -350.54794)
				)
			)
		)
		(zone
			(layer "F.Cu")
			(hatch none 0.5)
			(connect_pads
				(clearance 0)
			)
			(min_thickness 0.25)
			(keepout
				(tracks not_allowed)
				(vias allowed)
				(pads allowed)
				(copperpour not_allowed)
				(footprints allowed)
			)
			(placement
				(enabled no)
				(sheetname "")
			)
			(fill
				(thermal_gap 0.5)
				(thermal_bridge_width 0.5)
				(island_removal_mode 0)
			)
			(polygon
				(pts
					(xy 49.5046 -353.794314) (xy 50.27676 -353.794314) (xy 50.27676 -353.466908) (xy 50.302668 -353.466908)
					(xy 50.302668 -352.844862) (xy 50.25644 -352.798634) (xy 48.753268 -352.798634) (xy 48.753268 -353.255326)
					(xy 49.448974 -353.255326) (xy 49.448974 -353.094798) (xy 50.007774 -353.094798) (xy 50.007774 -353.501198)
					(xy 49.448974 -353.501198) (xy 49.448974 -353.280726) (xy 48.753268 -353.280726) (xy 48.753268 -353.407726)
					(xy 49.208944 -353.407726) (xy 49.208944 -353.774248) (xy 49.5046 -353.774248)
				)
			)
		)
	)
	(footprint ""
		(layer "F.Cu")
		(at 46.582584 -109.444282 180)
		(property "Reference" "R3005"
			(at 0 0 180)
			(layer "F.SilkS")
			(hide yes)
			(effects
				(font
					(size 1.27 1.27)
				)
			)
		)
		(property "Value" ""
			(at 0 0 180)
			(layer "F.Fab")
			(effects
				(font
					(size 1.27 1.27)
				)
			)
		)
		(duplicate_pad_numbers_are_jumpers no)
		(fp_line
			(start 0.7874 0.4064)
			(end -0.7874 0.4064)
			(stroke
				(width 0.1524)
				(type default)
			)
			(layer "F.SilkS")
		)
		(fp_line
			(start 0.7874 -0.4064)
			(end 0.7874 0.4064)
			(stroke
				(width 0.1524)
				(type default)
			)
			(layer "F.SilkS")
		)
		(fp_line
			(start -0.7874 0.4064)
			(end -0.7874 -0.4064)
			(stroke
				(width 0.1524)
				(type default)
			)
			(layer "F.SilkS")
		)
		(fp_line
			(start -0.7874 -0.4064)
			(end 0.7874 -0.4064)
			(stroke
				(width 0.1524)
				(type default)
			)
			(layer "F.SilkS")
		)
		(fp_line
			(start 0.67945 0.3048)
			(end 0.120396 0.3048)
			(stroke
				(width 0.1)
				(type default)
			)
			(layer "F.Fab")
		)
		(fp_line
			(start 0.67945 -0.3048)
			(end 0.67945 0.3048)
			(stroke
				(width 0.1)
				(type default)
			)
			(layer "F.Fab")
		)
		(fp_line
			(start 0.12065 -0.2794)
			(end 0.12065 -0.3048)
			(stroke
				(width 0.1)
				(type default)
			)
			(layer "F.Fab")
		)
		(fp_line
			(start 0.12065 -0.3048)
			(end 0.67945 -0.3048)
			(stroke
				(width 0.1)
				(type default)
			)
			(layer "F.Fab")
		)
		(fp_line
			(start 0.120396 0.3048)
			(end 0.120396 0.2794)
			(stroke
				(width 0.1)
				(type default)
			)
			(layer "F.Fab")
		)
		(fp_line
			(start 0.120396 0.2794)
			(end -0.12065 0.2794)
			(stroke
				(width 0.1)
				(type default)
			)
			(layer "F.Fab")
		)
		(fp_line
			(start -0.12065 0.3048)
			(end -0.67945 0.3048)
			(stroke
				(width 0.1)
				(type default)
			)
			(layer "F.Fab")
		)
		(fp_line
			(start -0.12065 0.2794)
			(end -0.12065 0.3048)
			(stroke
				(width 0.1)
				(type default)
			)
			(layer "F.Fab")
		)
		(fp_line
			(start -0.12065 -0.2794)
			(end 0.12065 -0.2794)
			(stroke
				(width 0.1)
				(type default)
			)
			(layer "F.Fab")
		)
		(fp_line
			(start -0.12065 -0.305054)
			(end -0.12065 -0.2794)
			(stroke
				(width 0.1)
				(type default)
			)
			(layer "F.Fab")
		)
		(fp_line
			(start -0.67945 0.3048)
			(end -0.67945 -0.305054)
			(stroke
				(width 0.1)
				(type default)
			)
			(layer "F.Fab")
		)
		(fp_line
			(start -0.67945 -0.305054)
			(end -0.12065 -0.305054)
			(stroke
				(width 0.1)
				(type default)
			)
			(layer "F.Fab")
		)
		(pad "1" smd circle
			(at -0.40005 0 180)
			(size 0 0)
			(layers "F.Cu" "F.Mask" "F.Paste")
			(net "P5V")
		)
		(pad "2" smd circle
			(at 0.40005 0 180)
			(size 0 0)
			(layers "F.Cu" "F.Mask" "F.Paste")
			(net "P5V_ADC")
		)
	)
	(footprint ""
		(layer "F.Cu")
		(at 357.683816 -333.525368 -90)
		(property "Reference" "PC273_P0_3"
			(at 0 0 270)
			(layer "F.SilkS")
			(hide yes)
			(effects
				(font
					(size 1.27 1.27)
				)
			)
		)
		(property "Value" ""
			(at 0 0 270)
			(layer "F.Fab")
			(effects
				(font
					(size 1.27 1.27)
				)
			)
		)
		(duplicate_pad_numbers_are_jumpers no)
		(fp_line
			(start -0.7874 0.4064)
			(end -0.7874 -0.4064)
			(stroke
				(width 0.1524)
				(type default)
			)
			(layer "F.SilkS")
		)
		(fp_line
			(start 0.7874 0.4064)
			(end -0.7874 0.4064)
			(stroke
				(width 0.1524)
				(type default)
			)
			(layer "F.SilkS")
		)
		(fp_line
			(start -0.7874 -0.4064)
			(end 0.7874 -0.4064)
			(stroke
				(width 0.1524)
				(type default)
			)
			(layer "F.SilkS")
		)
		(fp_line
			(start 0.7874 -0.4064)
			(end 0.7874 0.4064)
			(stroke
				(width 0.1524)
				(type default)
			)
			(layer "F.SilkS")
		)
		(fp_line
			(start -0.67945 0.3048)
			(end -0.67945 -0.305054)
			(stroke
				(width 0.1)
				(type default)
			)
			(layer "F.Fab")
		)
		(fp_line
			(start -0.12065 0.3048)
			(end -0.67945 0.3048)
			(stroke
				(width 0.1)
				(type default)
			)
			(layer "F.Fab")
		)
		(fp_line
			(start 0.120396 0.3048)
			(end 0.120396 0.2794)
			(stroke
				(width 0.1)
				(type default)
			)
			(layer "F.Fab")
		)
		(fp_line
			(start 0.67945 0.3048)
			(end 0.120396 0.3048)
			(stroke
				(width 0.1)
				(type default)
			)
			(layer "F.Fab")
		)
		(fp_line
			(start -0.12065 0.2794)
			(end -0.12065 0.3048)
			(stroke
				(width 0.1)
				(type default)
			)
			(layer "F.Fab")
		)
		(fp_line
			(start 0.120396 0.2794)
			(end -0.12065 0.2794)
			(stroke
				(width 0.1)
				(type default)
			)
			(layer "F.Fab")
		)
		(fp_line
			(start -0.12065 -0.2794)
			(end 0.12065 -0.2794)
			(stroke
				(width 0.1)
				(type default)
			)
			(layer "F.Fab")
		)
		(fp_line
			(start 0.12065 -0.2794)
			(end 0.12065 -0.3048)
			(stroke
				(width 0.1)
				(type default)
			)
			(layer "F.Fab")
		)
		(fp_line
			(start 0.12065 -0.3048)
			(end 0.67945 -0.3048)
			(stroke
				(width 0.1)
				(type default)
			)
			(layer "F.Fab")
		)
		(fp_line
			(start 0.67945 -0.3048)
			(end 0.67945 0.3048)
			(stroke
				(width 0.1)
				(type default)
			)
			(layer "F.Fab")
		)
		(fp_line
			(start -0.67945 -0.305054)
			(end -0.12065 -0.305054)
			(stroke
				(width 0.1)
				(type default)
			)
			(layer "F.Fab")
		)
		(fp_line
			(start -0.12065 -0.305054)
			(end -0.12065 -0.2794)
			(stroke
				(width 0.1)
				(type default)
			)
			(layer "F.Fab")
		)
		(pad "1" smd circle
			(at -0.40005 0 270)
			(size 0 0)
			(layers "F.Cu" "F.Mask" "F.Paste")
			(net "PVCCIN_CPU0_PVCC")
		)
		(pad "2" smd circle
			(at 0.40005 0 270)
			(size 0 0)
			(layers "F.Cu" "F.Mask" "F.Paste")
			(net "GND")
		)
	)
	(footprint ""
		(layer "F.Cu")
		(at 84.455 -38.699948 90)
		(property "Reference" "U323"
			(at 4.41833 -0.508 0)
			(unlocked yes)
			(layer "F.SilkS")
			(effects
				(font
					(size 0.7874 0.5842)
					(thickness 0.1524)
				)
				(justify left)
			)
		)
		(property "Value" ""
			(at 0 0 90)
			(layer "F.Fab")
			(effects
				(font
					(size 1.27 1.27)
				)
			)
		)
		(duplicate_pad_numbers_are_jumpers no)
		(fp_line
			(start 1.733296 -1.549908)
			(end 0.660908 -1.549908)
			(stroke
				(width 0.1524)
				(type default)
			)
			(layer "F.SilkS")
		)
		(fp_line
			(start 0.660908 -1.549908)
			(end 0 -0.889)
			(stroke
				(width 0.1524)
				(type default)
			)
			(layer "F.SilkS")
		)
		(fp_line
			(start -0.660908 -1.549908)
			(end -1.733296 -1.549908)
			(stroke
				(width 0.1524)
				(type default)
			)
			(layer "F.SilkS")
		)
		(fp_line
			(start -1.733296 -1.549908)
			(end -1.733296 1.549908)
			(stroke
				(width 0.1524)
				(type default)
			)
			(layer "F.SilkS")
		)
		(fp_line
			(start 0 -0.889)
			(end -0.660908 -1.549908)
			(stroke
				(width 0.1524)
				(type default)
			)
			(layer "F.SilkS")
		)
		(fp_line
			(start 1.733296 1.549908)
			(end 1.733296 -1.549908)
			(stroke
				(width 0.1524)
				(type default)
			)
			(layer "F.SilkS")
		)
		(fp_line
			(start -1.733296 1.549908)
			(end 1.733296 1.549908)
			(stroke
				(width 0.1524)
				(type default)
			)
			(layer "F.SilkS")
		)
		(fp_poly
			(pts
				(xy -2.299716 -2.047748) (xy -2.646934 -1.676654) (xy -2.102358 -1.51511)
			)
			(stroke
				(width 0)
				(type default)
			)
			(fill yes)
			(layer "F.SilkS")
		)
		(fp_line
			(start 0.849884 -1.549908)
			(end -0.849884 -1.549908)
			(stroke
				(width 0.1)
				(type default)
			)
			(layer "F.Fab")
		)
		(fp_line
			(start -0.849884 -1.549908)
			(end -0.849884 1.549908)
			(stroke
				(width 0.1)
				(type default)
			)
			(layer "F.Fab")
		)
		(fp_line
			(start 0.849884 1.549908)
			(end 0.849884 -1.549908)
			(stroke
				(width 0.1)
				(type default)
			)
			(layer "F.Fab")
		)
		(fp_line
			(start -0.849884 1.549908)
			(end 0.849884 1.549908)
			(stroke
				(width 0.1)
				(type default)
			)
			(layer "F.Fab")
		)
		(fp_poly
			(pts
				(xy -2.4384 -1.20396) (xy -2.4384 -0.69596) (xy -1.9304 -0.94996)
			)
			(stroke
				(width 0)
				(type default)
			)
			(fill yes)
			(layer "F.Fab")
		)
		(pad "1" smd rect
			(at -1.199896 -0.94996)
			(size 0.5588 0.8128)
			(layers "F.Cu" "F.Mask" "F.Paste")
			(net "HP_OCP_V3_2_RST_R")
		)
		(pad "2" smd rect
			(at -1.199896 0)
			(size 0.5588 0.8128)
			(layers "F.Cu" "F.Mask" "F.Paste")
			(net "HP_LVC3_OCP_V3_2_P12V_PWRGD")
		)
		(pad "3" smd rect
			(at -1.199896 0.94996)
			(size 0.5588 0.8128)
			(layers "F.Cu" "F.Mask" "F.Paste")
			(net "GND")
		)
		(pad "4" smd rect
			(at 1.199896 0.94996)
			(size 0.5588 0.8128)
			(layers "F.Cu" "F.Mask" "F.Paste")
			(net "HP_LVC3_OCP_V3_2_PWRGD")
		)
		(pad "5" smd rect
			(at 1.199896 -0.94996)
			(size 0.5588 0.8128)
			(layers "F.Cu" "F.Mask" "F.Paste")
			(net "P3V3_AUX")
		)
	)
	(footprint ""
		(layer "F.Cu")
		(at 169.441622 -421.527478 180)
		(property "Reference" "R3463"
			(at 0 0 180)
			(layer "F.SilkS")
			(hide yes)
			(effects
				(font
					(size 1.27 1.27)
				)
			)
		)
		(property "Value" ""
			(at 0 0 180)
			(layer "F.Fab")
			(effects
				(font
					(size 1.27 1.27)
				)
			)
		)
		(duplicate_pad_numbers_are_jumpers no)
		(fp_line
			(start 0.7874 0.4064)
			(end -0.7874 0.4064)
			(stroke
				(width 0.1524)
				(type default)
			)
			(layer "F.SilkS")
		)
		(fp_line
			(start 0.7874 -0.4064)
			(end 0.7874 0.4064)
			(stroke
				(width 0.1524)
				(type default)
			)
			(layer "F.SilkS")
		)
		(fp_line
			(start -0.7874 0.4064)
			(end -0.7874 -0.4064)
			(stroke
				(width 0.1524)
				(type default)
			)
			(layer "F.SilkS")
		)
		(fp_line
			(start -0.7874 -0.4064)
			(end 0.7874 -0.4064)
			(stroke
				(width 0.1524)
				(type default)
			)
			(layer "F.SilkS")
		)
		(fp_line
			(start 0.67945 0.3048)
			(end 0.120396 0.3048)
			(stroke
				(width 0.1)
				(type default)
			)
			(layer "F.Fab")
		)
		(fp_line
			(start 0.67945 -0.3048)
			(end 0.67945 0.3048)
			(stroke
				(width 0.1)
				(type default)
			)
			(layer "F.Fab")
		)
		(fp_line
			(start 0.12065 -0.2794)
			(end 0.12065 -0.3048)
			(stroke
				(width 0.1)
				(type default)
			)
			(layer "F.Fab")
		)
		(fp_line
			(start 0.12065 -0.3048)
			(end 0.67945 -0.3048)
			(stroke
				(width 0.1)
				(type default)
			)
			(layer "F.Fab")
		)
		(fp_line
			(start 0.120396 0.3048)
			(end 0.120396 0.2794)
			(stroke
				(width 0.1)
				(type default)
			)
			(layer "F.Fab")
		)
		(fp_line
			(start 0.120396 0.2794)
			(end -0.12065 0.2794)
			(stroke
				(width 0.1)
				(type default)
			)
			(layer "F.Fab")
		)
		(fp_line
			(start -0.12065 0.3048)
			(end -0.67945 0.3048)
			(stroke
				(width 0.1)
				(type default)
			)
			(layer "F.Fab")
		)
		(fp_line
			(start -0.12065 0.2794)
			(end -0.12065 0.3048)
			(stroke
				(width 0.1)
				(type default)
			)
			(layer "F.Fab")
		)
		(fp_line
			(start -0.12065 -0.2794)
			(end 0.12065 -0.2794)
			(stroke
				(width 0.1)
				(type default)
			)
			(layer "F.Fab")
		)
		(fp_line
			(start -0.12065 -0.305054)
			(end -0.12065 -0.2794)
			(stroke
				(width 0.1)
				(type default)
			)
			(layer "F.Fab")
		)
		(fp_line
			(start -0.67945 0.3048)
			(end -0.67945 -0.305054)
			(stroke
				(width 0.1)
				(type default)
			)
			(layer "F.Fab")
		)
		(fp_line
			(start -0.67945 -0.305054)
			(end -0.12065 -0.305054)
			(stroke
				(width 0.1)
				(type default)
			)
			(layer "F.Fab")
		)
		(pad "1" smd circle
			(at -0.40005 0 180)
			(size 0 0)
			(layers "F.Cu" "F.Mask" "F.Paste")
			(net "GPU_BASE_HMC_READY")
		)
		(pad "2" smd circle
			(at 0.40005 0 180)
			(size 0 0)
			(layers "F.Cu" "F.Mask" "F.Paste")
			(net "GND")
		)
	)
	(footprint ""
		(layer "F.Cu")
		(at 68.085716 -107.37469)
		(property "Reference" "R3722"
			(at 0 0 0)
			(layer "F.SilkS")
			(hide yes)
			(effects
				(font
					(size 1.27 1.27)
				)
			)
		)
		(property "Value" ""
			(at 0 0 0)
			(layer "F.Fab")
			(effects
				(font
					(size 1.27 1.27)
				)
			)
		)
		(duplicate_pad_numbers_are_jumpers no)
		(fp_line
			(start -0.7874 -0.4064)
			(end 0.7874 -0.4064)
			(stroke
				(width 0.1524)
				(type default)
			)
			(layer "F.SilkS")
		)
		(fp_line
			(start -0.7874 0.4064)
			(end -0.7874 -0.4064)
			(stroke
				(width 0.1524)
				(type default)
			)
			(layer "F.SilkS")
		)
		(fp_line
			(start 0.7874 -0.4064)
			(end 0.7874 0.4064)
			(stroke
				(width 0.1524)
				(type default)
			)
			(layer "F.SilkS")
		)
		(fp_line
			(start 0.7874 0.4064)
			(end -0.7874 0.4064)
			(stroke
				(width 0.1524)
				(type default)
			)
			(layer "F.SilkS")
		)
		(fp_line
			(start -0.67945 -0.305054)
			(end -0.12065 -0.305054)
			(stroke
				(width 0.1)
				(type default)
			)
			(layer "F.Fab")
		)
		(fp_line
			(start -0.67945 0.3048)
			(end -0.67945 -0.305054)
			(stroke
				(width 0.1)
				(type default)
			)
			(layer "F.Fab")
		)
		(fp_line
			(start -0.12065 -0.305054)
			(end -0.12065 -0.2794)
			(stroke
				(width 0.1)
				(type default)
			)
			(layer "F.Fab")
		)
		(fp_line
			(start -0.12065 -0.2794)
			(end 0.12065 -0.2794)
			(stroke
				(width 0.1)
				(type default)
			)
			(layer "F.Fab")
		)
		(fp_line
			(start -0.12065 0.2794)
			(end -0.12065 0.3048)
			(stroke
				(width 0.1)
				(type default)
			)
			(layer "F.Fab")
		)
		(fp_line
			(start -0.12065 0.3048)
			(end -0.67945 0.3048)
			(stroke
				(width 0.1)
				(type default)
			)
			(layer "F.Fab")
		)
		(fp_line
			(start 0.120396 0.2794)
			(end -0.12065 0.2794)
			(stroke
				(width 0.1)
				(type default)
			)
			(layer "F.Fab")
		)
		(fp_line
			(start 0.120396 0.3048)
			(end 0.120396 0.2794)
			(stroke
				(width 0.1)
				(type default)
			)
			(layer "F.Fab")
		)
		(fp_line
			(start 0.12065 -0.3048)
			(end 0.67945 -0.3048)
			(stroke
				(width 0.1)
				(type default)
			)
			(layer "F.Fab")
		)
		(fp_line
			(start 0.12065 -0.2794)
			(end 0.12065 -0.3048)
			(stroke
				(width 0.1)
				(type default)
			)
			(layer "F.Fab")
		)
		(fp_line
			(start 0.67945 -0.3048)
			(end 0.67945 0.3048)
			(stroke
				(width 0.1)
				(type default)
			)
			(layer "F.Fab")
		)
		(fp_line
			(start 0.67945 0.3048)
			(end 0.120396 0.3048)
			(stroke
				(width 0.1)
				(type default)
			)
			(layer "F.Fab")
		)
		(pad "1" smd circle
			(at -0.40005 0)
			(size 0 0)
			(layers "F.Cu" "F.Mask" "F.Paste")
			(net "SMB_LM75_3_3V3AUX_SDA_R")
		)
		(pad "2" smd circle
			(at 0.40005 0)
			(size 0 0)
			(layers "F.Cu" "F.Mask" "F.Paste")
			(net "SMB_LM75_3_3V3AUX_SDA")
		)
	)
	(footprint ""
		(layer "F.Cu")
		(at 309.522622 -33.772348 180)
		(property "Reference" "R1600"
			(at 0 0 180)
			(layer "F.SilkS")
			(hide yes)
			(effects
				(font
					(size 1.27 1.27)
				)
			)
		)
		(property "Value" ""
			(at 0 0 180)
			(layer "F.Fab")
			(effects
				(font
					(size 1.27 1.27)
				)
			)
		)
		(duplicate_pad_numbers_are_jumpers no)
		(fp_line
			(start 0.7874 0.4064)
			(end -0.7874 0.4064)
			(stroke
				(width 0.1524)
				(type default)
			)
			(layer "F.SilkS")
		)
		(fp_line
			(start 0.7874 -0.4064)
			(end 0.7874 0.4064)
			(stroke
				(width 0.1524)
				(type default)
			)
			(layer "F.SilkS")
		)
		(fp_line
			(start -0.7874 0.4064)
			(end -0.7874 -0.4064)
			(stroke
				(width 0.1524)
				(type default)
			)
			(layer "F.SilkS")
		)
		(fp_line
			(start -0.7874 -0.4064)
			(end 0.7874 -0.4064)
			(stroke
				(width 0.1524)
				(type default)
			)
			(layer "F.SilkS")
		)
		(fp_line
			(start 0.67945 0.3048)
			(end 0.120396 0.3048)
			(stroke
				(width 0.1)
				(type default)
			)
			(layer "F.Fab")
		)
		(fp_line
			(start 0.67945 -0.3048)
			(end 0.67945 0.3048)
			(stroke
				(width 0.1)
				(type default)
			)
			(layer "F.Fab")
		)
		(fp_line
			(start 0.12065 -0.2794)
			(end 0.12065 -0.3048)
			(stroke
				(width 0.1)
				(type default)
			)
			(layer "F.Fab")
		)
		(fp_line
			(start 0.12065 -0.3048)
			(end 0.67945 -0.3048)
			(stroke
				(width 0.1)
				(type default)
			)
			(layer "F.Fab")
		)
		(fp_line
			(start 0.120396 0.3048)
			(end 0.120396 0.2794)
			(stroke
				(width 0.1)
				(type default)
			)
			(layer "F.Fab")
		)
		(fp_line
			(start 0.120396 0.2794)
			(end -0.12065 0.2794)
			(stroke
				(width 0.1)
				(type default)
			)
			(layer "F.Fab")
		)
		(fp_line
			(start -0.12065 0.3048)
			(end -0.67945 0.3048)
			(stroke
				(width 0.1)
				(type default)
			)
			(layer "F.Fab")
		)
		(fp_line
			(start -0.12065 0.2794)
			(end -0.12065 0.3048)
			(stroke
				(width 0.1)
				(type default)
			)
			(layer "F.Fab")
		)
		(fp_line
			(start -0.12065 -0.2794)
			(end 0.12065 -0.2794)
			(stroke
				(width 0.1)
				(type default)
			)
			(layer "F.Fab")
		)
		(fp_line
			(start -0.12065 -0.305054)
			(end -0.12065 -0.2794)
			(stroke
				(width 0.1)
				(type default)
			)
			(layer "F.Fab")
		)
		(fp_line
			(start -0.67945 0.3048)
			(end -0.67945 -0.305054)
			(stroke
				(width 0.1)
				(type default)
			)
			(layer "F.Fab")
		)
		(fp_line
			(start -0.67945 -0.305054)
			(end -0.12065 -0.305054)
			(stroke
				(width 0.1)
				(type default)
			)
			(layer "F.Fab")
		)
		(pad "1" smd circle
			(at -0.40005 0 180)
			(size 0 0)
			(layers "F.Cu" "F.Mask" "F.Paste")
			(net "IRQ_SML0_ALERT_N")
		)
		(pad "2" smd circle
			(at 0.40005 0 180)
			(size 0 0)
			(layers "F.Cu" "F.Mask" "F.Paste")
			(net "IRQ_SML0_ALERT_R_N")
		)
	)
	(footprint ""
		(layer "F.Cu")
		(at 205.968092 -101.006656)
		(property "Reference" "Q34"
			(at -3.937 -1.92913 0)
			(unlocked yes)
			(layer "F.SilkS")
			(effects
				(font
					(size 0.7874 0.5842)
					(thickness 0.1524)
				)
				(justify left)
			)
		)
		(property "Value" ""
			(at 0 0 0)
			(layer "F.Fab")
			(effects
				(font
					(size 1.27 1.27)
				)
			)
		)
		(duplicate_pad_numbers_are_jumpers no)
		(fp_line
			(start -1.603248 -1.500124)
			(end 1.603248 -1.500124)
			(stroke
				(width 0.1524)
				(type default)
			)
			(layer "F.SilkS")
		)
		(fp_line
			(start -1.603248 1.500124)
			(end -1.603248 -1.500124)
			(stroke
				(width 0.1524)
				(type default)
			)
			(layer "F.SilkS")
		)
		(fp_line
			(start 1.603248 -1.500124)
			(end 1.603248 1.500124)
			(stroke
				(width 0.1524)
				(type default)
			)
			(layer "F.SilkS")
		)
		(fp_line
			(start 1.603248 1.500124)
			(end -1.603248 1.500124)
			(stroke
				(width 0.1524)
				(type default)
			)
			(layer "F.SilkS")
		)
		(fp_line
			(start -1.249934 -1.169924)
			(end -1.249934 -0.729996)
			(stroke
				(width 0.1)
				(type default)
			)
			(layer "F.Fab")
		)
		(fp_line
			(start -1.249934 -0.729996)
			(end -0.6985 -0.729996)
			(stroke
				(width 0.1)
				(type default)
			)
			(layer "F.Fab")
		)
		(fp_line
			(start -1.249934 0.729996)
			(end -1.249934 1.169924)
			(stroke
				(width 0.1)
				(type default)
			)
			(layer "F.Fab")
		)
		(fp_line
			(start -1.249934 1.169924)
			(end -0.700024 1.169924)
			(stroke
				(width 0.1)
				(type default)
			)
			(layer "F.Fab")
		)
		(fp_line
			(start -0.700024 -1.500124)
			(end -0.700024 -1.169924)
			(stroke
				(width 0.1)
				(type default)
			)
			(layer "F.Fab")
		)
		(fp_line
			(start -0.700024 -1.169924)
			(end -1.249934 -1.169924)
			(stroke
				(width 0.1)
				(type default)
			)
			(layer "F.Fab")
		)
		(fp_line
			(start -0.700024 1.169924)
			(end -0.700024 1.500124)
			(stroke
				(width 0.1)
				(type default)
			)
			(layer "F.Fab")
		)
		(fp_line
			(start -0.700024 1.500124)
			(end 0.700024 1.500124)
			(stroke
				(width 0.1)
				(type default)
			)
			(layer "F.Fab")
		)
		(fp_line
			(start -0.6985 -0.729996)
			(end -0.6985 0.729996)
			(stroke
				(width 0.1)
				(type default)
			)
			(layer "F.Fab")
		)
		(fp_line
			(start -0.6985 0.729996)
			(end -1.249934 0.729996)
			(stroke
				(width 0.1)
				(type default)
			)
			(layer "F.Fab")
		)
		(fp_line
			(start 0.700024 -1.500124)
			(end -0.700024 -1.500124)
			(stroke
				(width 0.1)
				(type default)
			)
			(layer "F.Fab")
		)
		(fp_line
			(start 0.700024 -0.219964)
			(end 0.700024 -1.500124)
			(stroke
				(width 0.1)
				(type default)
			)
			(layer "F.Fab")
		)
		(fp_line
			(start 0.700024 0.219964)
			(end 1.249934 0.219964)
			(stroke
				(width 0.1)
				(type default)
			)
			(layer "F.Fab")
		)
		(fp_line
			(start 0.700024 1.500124)
			(end 0.700024 0.219964)
			(stroke
				(width 0.1)
				(type default)
			)
			(layer "F.Fab")
		)
		(fp_line
			(start 1.249934 -0.219964)
			(end 0.700024 -0.219964)
			(stroke
				(width 0.1)
				(type default)
			)
			(layer "F.Fab")
		)
		(fp_line
			(start 1.249934 0.219964)
			(end 1.249934 -0.219964)
			(stroke
				(width 0.1)
				(type default)
			)
			(layer "F.Fab")
		)
		(fp_rect
			(start -0.700024 1.500124)
			(end 0.700024 -1.500124)
			(stroke
				(width 0)
				(type default)
			)
			(fill no)
			(layer "F.Fab")
		)
		(pad "D" smd rect
			(at 0.999998 0 270)
			(size 0.8128 0.9144)
			(layers "F.Cu" "F.Mask" "F.Paste")
			(net "RST_RTCRST_N")
		)
		(pad "G" smd rect
			(at -0.999998 -0.94996 270)
			(size 0.8128 0.9144)
			(layers "F.Cu" "F.Mask" "F.Paste")
			(net "RST_PFR_OVR_RTC")
		)
		(pad "S" smd rect
			(at -0.999998 0.94996 270)
			(size 0.8128 0.9144)
			(layers "F.Cu" "F.Mask" "F.Paste")
			(net "GND")
		)
	)
	(footprint ""
		(layer "F.Cu")
		(at 119.508016 -247.715278 90)
		(property "Reference" "C427"
			(at 0 0 90)
			(layer "F.SilkS")
			(hide yes)
			(effects
				(font
					(size 1.27 1.27)
				)
			)
		)
		(property "Value" ""
			(at 0 0 90)
			(layer "F.Fab")
			(effects
				(font
					(size 1.27 1.27)
				)
			)
		)
		(duplicate_pad_numbers_are_jumpers no)
		(fp_line
			(start 0.7874 -0.4064)
			(end 0.7874 0.4064)
			(stroke
				(width 0.1524)
				(type default)
			)
			(layer "F.SilkS")
		)
		(fp_line
			(start -0.7874 -0.4064)
			(end 0.7874 -0.4064)
			(stroke
				(width 0.1524)
				(type default)
			)
			(layer "F.SilkS")
		)
		(fp_line
			(start 0.7874 0.4064)
			(end -0.7874 0.4064)
			(stroke
				(width 0.1524)
				(type default)
			)
			(layer "F.SilkS")
		)
		(fp_line
			(start -0.7874 0.4064)
			(end -0.7874 -0.4064)
			(stroke
				(width 0.1524)
				(type default)
			)
			(layer "F.SilkS")
		)
		(fp_line
			(start -0.12065 -0.305054)
			(end -0.12065 -0.2794)
			(stroke
				(width 0.1)
				(type default)
			)
			(layer "F.Fab")
		)
		(fp_line
			(start -0.67945 -0.305054)
			(end -0.12065 -0.305054)
			(stroke
				(width 0.1)
				(type default)
			)
			(layer "F.Fab")
		)
		(fp_line
			(start 0.67945 -0.3048)
			(end 0.67945 0.3048)
			(stroke
				(width 0.1)
				(type default)
			)
			(layer "F.Fab")
		)
		(fp_line
			(start 0.12065 -0.3048)
			(end 0.67945 -0.3048)
			(stroke
				(width 0.1)
				(type default)
			)
			(layer "F.Fab")
		)
		(fp_line
			(start 0.12065 -0.2794)
			(end 0.12065 -0.3048)
			(stroke
				(width 0.1)
				(type default)
			)
			(layer "F.Fab")
		)
		(fp_line
			(start -0.12065 -0.2794)
			(end 0.12065 -0.2794)
			(stroke
				(width 0.1)
				(type default)
			)
			(layer "F.Fab")
		)
		(fp_line
			(start 0.120396 0.2794)
			(end -0.12065 0.2794)
			(stroke
				(width 0.1)
				(type default)
			)
			(layer "F.Fab")
		)
		(fp_line
			(start -0.12065 0.2794)
			(end -0.12065 0.3048)
			(stroke
				(width 0.1)
				(type default)
			)
			(layer "F.Fab")
		)
		(fp_line
			(start 0.67945 0.3048)
			(end 0.120396 0.3048)
			(stroke
				(width 0.1)
				(type default)
			)
			(layer "F.Fab")
		)
		(fp_line
			(start 0.120396 0.3048)
			(end 0.120396 0.2794)
			(stroke
				(width 0.1)
				(type default)
			)
			(layer "F.Fab")
		)
		(fp_line
			(start -0.12065 0.3048)
			(end -0.67945 0.3048)
			(stroke
				(width 0.1)
				(type default)
			)
			(layer "F.Fab")
		)
		(fp_line
			(start -0.67945 0.3048)
			(end -0.67945 -0.305054)
			(stroke
				(width 0.1)
				(type default)
			)
			(layer "F.Fab")
		)
		(pad "1" smd circle
			(at -0.40005 0 90)
			(size 0 0)
			(layers "F.Cu" "F.Mask" "F.Paste")
			(net "PVCCD_HV_CPU1")
		)
		(pad "2" smd circle
			(at 0.40005 0 90)
			(size 0 0)
			(layers "F.Cu" "F.Mask" "F.Paste")
			(net "GND")
		)
	)
	(footprint ""
		(layer "F.Cu")
		(at 136.00684 -33.477708)
		(property "Reference" "U245"
			(at -1.64084 2.55143 0)
			(unlocked yes)
			(layer "F.SilkS")
			(effects
				(font
					(size 0.7874 0.5842)
					(thickness 0.1524)
				)
			)
		)
		(property "Value" ""
			(at 0 0 0)
			(layer "F.Fab")
			(effects
				(font
					(size 1.27 1.27)
				)
			)
		)
		(duplicate_pad_numbers_are_jumpers no)
		(fp_line
			(start -1.7272 1.1176)
			(end -1.7272 -1.1176)
			(stroke
				(width 0.1524)
				(type default)
			)
			(layer "F.SilkS")
		)
		(fp_line
			(start -0.254 -1.1176)
			(end -1.7272 -1.1176)
			(stroke
				(width 0.1524)
				(type default)
			)
			(layer "F.SilkS")
		)
		(fp_line
			(start 0 -0.7366)
			(end -0.254 -1.1176)
			(stroke
				(width 0.1524)
				(type default)
			)
			(layer "F.SilkS")
		)
		(fp_line
			(start 0.254 -1.1176)
			(end 0 -0.7366)
			(stroke
				(width 0.1524)
				(type default)
			)
			(layer "F.SilkS")
		)
		(fp_line
			(start 1.7272 -1.1176)
			(end 0.254 -1.1176)
			(stroke
				(width 0.1524)
				(type default)
			)
			(layer "F.SilkS")
		)
		(fp_line
			(start 1.7272 -1.1176)
			(end 1.7272 1.1176)
			(stroke
				(width 0.1524)
				(type default)
			)
			(layer "F.SilkS")
		)
		(fp_line
			(start 1.7272 1.1176)
			(end -1.7272 1.1176)
			(stroke
				(width 0.1524)
				(type default)
			)
			(layer "F.SilkS")
		)
		(fp_poly
			(pts
				(xy -2.7178 -0.268986) (xy -2.7178 -1.030986) (xy -1.9558 -0.649986)
			)
			(stroke
				(width 0)
				(type default)
			)
			(fill yes)
			(layer "F.SilkS")
		)
		(fp_line
			(start -1.5748 -1.1176)
			(end -1.5748 1.1176)
			(stroke
				(width 0.1)
				(type default)
			)
			(layer "F.Fab")
		)
		(fp_line
			(start -1.5748 1.1176)
			(end 1.5748 1.1176)
			(stroke
				(width 0.1)
				(type default)
			)
			(layer "F.Fab")
		)
		(fp_line
			(start 1.5748 -1.1176)
			(end -1.5748 -1.1176)
			(stroke
				(width 0.1)
				(type default)
			)
			(layer "F.Fab")
		)
		(fp_line
			(start 1.5748 1.1176)
			(end 1.5748 -1.1176)
			(stroke
				(width 0.1)
				(type default)
			)
			(layer "F.Fab")
		)
		(fp_poly
			(pts
				(xy -1.9558 -0.649986) (xy -2.7178 -0.268986) (xy -2.7178 -1.030986)
			)
			(stroke
				(width 0)
				(type default)
			)
			(fill yes)
			(layer "F.Fab")
		)
		(pad "1" smd rect
			(at -0.999998 -0.649986 270)
			(size 0.3556 1.1176)
			(layers "F.Cu" "F.Mask" "F.Paste")
			(net "OCP_V3_2_NOT_PRSNT_RBT_ARB_IN")
		)
		(pad "2" smd rect
			(at -0.999998 0 270)
			(size 0.3556 1.1176)
			(layers "F.Cu" "F.Mask" "F.Paste")
			(net "GND")
		)
		(pad "3" smd rect
			(at -0.999998 0.649986 270)
			(size 0.3556 1.1176)
			(layers "F.Cu" "F.Mask" "F.Paste")
			(net "OCP_V3_2_RBT_ARB_IN")
		)
		(pad "4" smd rect
			(at 0.999998 0.649986 270)
			(size 0.3556 1.1176)
			(layers "F.Cu" "F.Mask" "F.Paste")
			(net "OCP_SFF_RBT_ARB_IN_MUX2_R")
		)
		(pad "5" smd rect
			(at 0.999998 0 270)
			(size 0.3556 1.1176)
			(layers "F.Cu" "F.Mask" "F.Paste")
			(net "P3V3_AUX")
		)
		(pad "6" smd rect
			(at 0.999998 -0.649986 270)
			(size 0.3556 1.1176)
			(layers "F.Cu" "F.Mask" "F.Paste")
			(net "OCP_V3_2_PRSNT_ALL_R3_N")
		)
	)
	(footprint ""
		(layer "F.Cu")
		(at 306.71262 -56.020208 90)
		(property "Reference" "R1297"
			(at 0 0 90)
			(layer "F.SilkS")
			(hide yes)
			(effects
				(font
					(size 1.27 1.27)
				)
			)
		)
		(property "Value" ""
			(at 0 0 90)
			(layer "F.Fab")
			(effects
				(font
					(size 1.27 1.27)
				)
			)
		)
		(duplicate_pad_numbers_are_jumpers no)
		(fp_line
			(start 0.7874 -0.4064)
			(end 0.7874 0.4064)
			(stroke
				(width 0.1524)
				(type default)
			)
			(layer "F.SilkS")
		)
		(fp_line
			(start -0.7874 -0.4064)
			(end 0.7874 -0.4064)
			(stroke
				(width 0.1524)
				(type default)
			)
			(layer "F.SilkS")
		)
		(fp_line
			(start 0.7874 0.4064)
			(end -0.7874 0.4064)
			(stroke
				(width 0.1524)
				(type default)
			)
			(layer "F.SilkS")
		)
		(fp_line
			(start -0.7874 0.4064)
			(end -0.7874 -0.4064)
			(stroke
				(width 0.1524)
				(type default)
			)
			(layer "F.SilkS")
		)
		(fp_line
			(start -0.12065 -0.305054)
			(end -0.12065 -0.2794)
			(stroke
				(width 0.1)
				(type default)
			)
			(layer "F.Fab")
		)
		(fp_line
			(start -0.67945 -0.305054)
			(end -0.12065 -0.305054)
			(stroke
				(width 0.1)
				(type default)
			)
			(layer "F.Fab")
		)
		(fp_line
			(start 0.67945 -0.3048)
			(end 0.67945 0.3048)
			(stroke
				(width 0.1)
				(type default)
			)
			(layer "F.Fab")
		)
		(fp_line
			(start 0.12065 -0.3048)
			(end 0.67945 -0.3048)
			(stroke
				(width 0.1)
				(type default)
			)
			(layer "F.Fab")
		)
		(fp_line
			(start 0.12065 -0.2794)
			(end 0.12065 -0.3048)
			(stroke
				(width 0.1)
				(type default)
			)
			(layer "F.Fab")
		)
		(fp_line
			(start -0.12065 -0.2794)
			(end 0.12065 -0.2794)
			(stroke
				(width 0.1)
				(type default)
			)
			(layer "F.Fab")
		)
		(fp_line
			(start 0.120396 0.2794)
			(end -0.12065 0.2794)
			(stroke
				(width 0.1)
				(type default)
			)
			(layer "F.Fab")
		)
		(fp_line
			(start -0.12065 0.2794)
			(end -0.12065 0.3048)
			(stroke
				(width 0.1)
				(type default)
			)
			(layer "F.Fab")
		)
		(fp_line
			(start 0.67945 0.3048)
			(end 0.120396 0.3048)
			(stroke
				(width 0.1)
				(type default)
			)
			(layer "F.Fab")
		)
		(fp_line
			(start 0.120396 0.3048)
			(end 0.120396 0.2794)
			(stroke
				(width 0.1)
				(type default)
			)
			(layer "F.Fab")
		)
		(fp_line
			(start -0.12065 0.3048)
			(end -0.67945 0.3048)
			(stroke
				(width 0.1)
				(type default)
			)
			(layer "F.Fab")
		)
		(fp_line
			(start -0.67945 0.3048)
			(end -0.67945 -0.305054)
			(stroke
				(width 0.1)
				(type default)
			)
			(layer "F.Fab")
		)
		(pad "1" smd circle
			(at -0.40005 0 90)
			(size 0 0)
			(layers "F.Cu" "F.Mask" "F.Paste")
			(net "PECI_BMC_R")
		)
		(pad "2" smd circle
			(at 0.40005 0 90)
			(size 0 0)
			(layers "F.Cu" "F.Mask" "F.Paste")
			(net "PECI_BMC_B1")
		)
	)
	(footprint ""
		(layer "F.Cu")
		(at 104.347264 -260.36524 -90)
		(property "Reference" "C428"
			(at 0 0 270)
			(layer "F.SilkS")
			(hide yes)
			(effects
				(font
					(size 1.27 1.27)
				)
			)
		)
		(property "Value" ""
			(at 0 0 270)
			(layer "F.Fab")
			(effects
				(font
					(size 1.27 1.27)
				)
			)
		)
		(duplicate_pad_numbers_are_jumpers no)
		(fp_line
			(start -0.7874 0.4064)
			(end -0.7874 -0.4064)
			(stroke
				(width 0.1524)
				(type default)
			)
			(layer "F.SilkS")
		)
		(fp_line
			(start 0.7874 0.4064)
			(end -0.7874 0.4064)
			(stroke
				(width 0.1524)
				(type default)
			)
			(layer "F.SilkS")
		)
		(fp_line
			(start -0.7874 -0.4064)
			(end 0.7874 -0.4064)
			(stroke
				(width 0.1524)
				(type default)
			)
			(layer "F.SilkS")
		)
		(fp_line
			(start 0.7874 -0.4064)
			(end 0.7874 0.4064)
			(stroke
				(width 0.1524)
				(type default)
			)
			(layer "F.SilkS")
		)
		(fp_line
			(start -0.67945 0.3048)
			(end -0.67945 -0.305054)
			(stroke
				(width 0.1)
				(type default)
			)
			(layer "F.Fab")
		)
		(fp_line
			(start -0.12065 0.3048)
			(end -0.67945 0.3048)
			(stroke
				(width 0.1)
				(type default)
			)
			(layer "F.Fab")
		)
		(fp_line
			(start 0.120396 0.3048)
			(end 0.120396 0.2794)
			(stroke
				(width 0.1)
				(type default)
			)
			(layer "F.Fab")
		)
		(fp_line
			(start 0.67945 0.3048)
			(end 0.120396 0.3048)
			(stroke
				(width 0.1)
				(type default)
			)
			(layer "F.Fab")
		)
		(fp_line
			(start -0.12065 0.2794)
			(end -0.12065 0.3048)
			(stroke
				(width 0.1)
				(type default)
			)
			(layer "F.Fab")
		)
		(fp_line
			(start 0.120396 0.2794)
			(end -0.12065 0.2794)
			(stroke
				(width 0.1)
				(type default)
			)
			(layer "F.Fab")
		)
		(fp_line
			(start -0.12065 -0.2794)
			(end 0.12065 -0.2794)
			(stroke
				(width 0.1)
				(type default)
			)
			(layer "F.Fab")
		)
		(fp_line
			(start 0.12065 -0.2794)
			(end 0.12065 -0.3048)
			(stroke
				(width 0.1)
				(type default)
			)
			(layer "F.Fab")
		)
		(fp_line
			(start 0.12065 -0.3048)
			(end 0.67945 -0.3048)
			(stroke
				(width 0.1)
				(type default)
			)
			(layer "F.Fab")
		)
		(fp_line
			(start 0.67945 -0.3048)
			(end 0.67945 0.3048)
			(stroke
				(width 0.1)
				(type default)
			)
			(layer "F.Fab")
		)
		(fp_line
			(start -0.67945 -0.305054)
			(end -0.12065 -0.305054)
			(stroke
				(width 0.1)
				(type default)
			)
			(layer "F.Fab")
		)
		(fp_line
			(start -0.12065 -0.305054)
			(end -0.12065 -0.2794)
			(stroke
				(width 0.1)
				(type default)
			)
			(layer "F.Fab")
		)
		(pad "1" smd circle
			(at -0.40005 0 270)
			(size 0 0)
			(layers "F.Cu" "F.Mask" "F.Paste")
			(net "PVCCFA_EHV_FIVRA_CPU1")
		)
		(pad "2" smd circle
			(at 0.40005 0 270)
			(size 0 0)
			(layers "F.Cu" "F.Mask" "F.Paste")
			(net "GND")
		)
	)
	(footprint ""
		(layer "F.Cu")
		(at 362.646468 -357.91775)
		(property "Reference" "PC336"
			(at 0 0 0)
			(layer "F.SilkS")
			(hide yes)
			(effects
				(font
					(size 1.27 1.27)
				)
			)
		)
		(property "Value" ""
			(at 0 0 0)
			(layer "F.Fab")
			(effects
				(font
					(size 1.27 1.27)
				)
			)
		)
		(duplicate_pad_numbers_are_jumpers no)
		(fp_line
			(start -0.7874 -0.4064)
			(end 0.7874 -0.4064)
			(stroke
				(width 0.1524)
				(type default)
			)
			(layer "F.SilkS")
		)
		(fp_line
			(start -0.7874 0.4064)
			(end -0.7874 -0.4064)
			(stroke
				(width 0.1524)
				(type default)
			)
			(layer "F.SilkS")
		)
		(fp_line
			(start 0.7874 -0.4064)
			(end 0.7874 0.4064)
			(stroke
				(width 0.1524)
				(type default)
			)
			(layer "F.SilkS")
		)
		(fp_line
			(start 0.7874 0.4064)
			(end -0.7874 0.4064)
			(stroke
				(width 0.1524)
				(type default)
			)
			(layer "F.SilkS")
		)
		(fp_line
			(start -0.67945 -0.305054)
			(end -0.12065 -0.305054)
			(stroke
				(width 0.1)
				(type default)
			)
			(layer "F.Fab")
		)
		(fp_line
			(start -0.67945 0.3048)
			(end -0.67945 -0.305054)
			(stroke
				(width 0.1)
				(type default)
			)
			(layer "F.Fab")
		)
		(fp_line
			(start -0.12065 -0.305054)
			(end -0.12065 -0.2794)
			(stroke
				(width 0.1)
				(type default)
			)
			(layer "F.Fab")
		)
		(fp_line
			(start -0.12065 -0.2794)
			(end 0.12065 -0.2794)
			(stroke
				(width 0.1)
				(type default)
			)
			(layer "F.Fab")
		)
		(fp_line
			(start -0.12065 0.2794)
			(end -0.12065 0.3048)
			(stroke
				(width 0.1)
				(type default)
			)
			(layer "F.Fab")
		)
		(fp_line
			(start -0.12065 0.3048)
			(end -0.67945 0.3048)
			(stroke
				(width 0.1)
				(type default)
			)
			(layer "F.Fab")
		)
		(fp_line
			(start 0.120396 0.2794)
			(end -0.12065 0.2794)
			(stroke
				(width 0.1)
				(type default)
			)
			(layer "F.Fab")
		)
		(fp_line
			(start 0.120396 0.3048)
			(end 0.120396 0.2794)
			(stroke
				(width 0.1)
				(type default)
			)
			(layer "F.Fab")
		)
		(fp_line
			(start 0.12065 -0.3048)
			(end 0.67945 -0.3048)
			(stroke
				(width 0.1)
				(type default)
			)
			(layer "F.Fab")
		)
		(fp_line
			(start 0.12065 -0.2794)
			(end 0.12065 -0.3048)
			(stroke
				(width 0.1)
				(type default)
			)
			(layer "F.Fab")
		)
		(fp_line
			(start 0.67945 -0.3048)
			(end 0.67945 0.3048)
			(stroke
				(width 0.1)
				(type default)
			)
			(layer "F.Fab")
		)
		(fp_line
			(start 0.67945 0.3048)
			(end 0.120396 0.3048)
			(stroke
				(width 0.1)
				(type default)
			)
			(layer "F.Fab")
		)
		(pad "1" smd circle
			(at -0.40005 0)
			(size 0 0)
			(layers "F.Cu" "F.Mask" "F.Paste")
			(net "PVCCIN_CPU0_ATSEN")
		)
		(pad "2" smd circle
			(at 0.40005 0)
			(size 0 0)
			(layers "F.Cu" "F.Mask" "F.Paste")
			(net "GND")
		)
	)
	(footprint ""
		(layer "F.Cu")
		(at 10.339832 -160.50006)
		(property "Reference" "H128"
			(at -6.202172 -5.15239 0)
			(unlocked yes)
			(layer "F.SilkS")
			(effects
				(font
					(size 0.7874 0.5842)
					(thickness 0.1524)
				)
				(justify left)
			)
		)
		(property "Value" ""
			(at 0 0 0)
			(layer "F.Fab")
			(effects
				(font
					(size 1.27 1.27)
				)
			)
		)
		(duplicate_pad_numbers_are_jumpers no)
		(pad "1" thru_hole circle
			(at 0 0)
			(size 10.0076 10.0076)
			(drill 5.6134)
			(layers "*.Cu" "*.Mask")
			(remove_unused_layers no)
			(net "GND")
			(clearance -1.9431)
		)
	)
	(footprint ""
		(layer "F.Cu")
		(at 109.695742 -65.22212 -90)
		(property "Reference" "R3099"
			(at 0 0 270)
			(layer "F.SilkS")
			(hide yes)
			(effects
				(font
					(size 1.27 1.27)
				)
			)
		)
		(property "Value" ""
			(at 0 0 270)
			(layer "F.Fab")
			(effects
				(font
					(size 1.27 1.27)
				)
			)
		)
		(duplicate_pad_numbers_are_jumpers no)
		(fp_line
			(start -0.7874 0.4064)
			(end -0.7874 -0.4064)
			(stroke
				(width 0.1524)
				(type default)
			)
			(layer "F.SilkS")
		)
		(fp_line
			(start 0.7874 0.4064)
			(end -0.7874 0.4064)
			(stroke
				(width 0.1524)
				(type default)
			)
			(layer "F.SilkS")
		)
		(fp_line
			(start -0.7874 -0.4064)
			(end 0.7874 -0.4064)
			(stroke
				(width 0.1524)
				(type default)
			)
			(layer "F.SilkS")
		)
		(fp_line
			(start 0.7874 -0.4064)
			(end 0.7874 0.4064)
			(stroke
				(width 0.1524)
				(type default)
			)
			(layer "F.SilkS")
		)
		(fp_line
			(start -0.67945 0.3048)
			(end -0.67945 -0.305054)
			(stroke
				(width 0.1)
				(type default)
			)
			(layer "F.Fab")
		)
		(fp_line
			(start -0.12065 0.3048)
			(end -0.67945 0.3048)
			(stroke
				(width 0.1)
				(type default)
			)
			(layer "F.Fab")
		)
		(fp_line
			(start 0.120396 0.3048)
			(end 0.120396 0.2794)
			(stroke
				(width 0.1)
				(type default)
			)
			(layer "F.Fab")
		)
		(fp_line
			(start 0.67945 0.3048)
			(end 0.120396 0.3048)
			(stroke
				(width 0.1)
				(type default)
			)
			(layer "F.Fab")
		)
		(fp_line
			(start -0.12065 0.2794)
			(end -0.12065 0.3048)
			(stroke
				(width 0.1)
				(type default)
			)
			(layer "F.Fab")
		)
		(fp_line
			(start 0.120396 0.2794)
			(end -0.12065 0.2794)
			(stroke
				(width 0.1)
				(type default)
			)
			(layer "F.Fab")
		)
		(fp_line
			(start -0.12065 -0.2794)
			(end 0.12065 -0.2794)
			(stroke
				(width 0.1)
				(type default)
			)
			(layer "F.Fab")
		)
		(fp_line
			(start 0.12065 -0.2794)
			(end 0.12065 -0.3048)
			(stroke
				(width 0.1)
				(type default)
			)
			(layer "F.Fab")
		)
		(fp_line
			(start 0.12065 -0.3048)
			(end 0.67945 -0.3048)
			(stroke
				(width 0.1)
				(type default)
			)
			(layer "F.Fab")
		)
		(fp_line
			(start 0.67945 -0.3048)
			(end 0.67945 0.3048)
			(stroke
				(width 0.1)
				(type default)
			)
			(layer "F.Fab")
		)
		(fp_line
			(start -0.67945 -0.305054)
			(end -0.12065 -0.305054)
			(stroke
				(width 0.1)
				(type default)
			)
			(layer "F.Fab")
		)
		(fp_line
			(start -0.12065 -0.305054)
			(end -0.12065 -0.2794)
			(stroke
				(width 0.1)
				(type default)
			)
			(layer "F.Fab")
		)
		(pad "1" smd circle
			(at -0.40005 0 270)
			(size 0 0)
			(layers "F.Cu" "F.Mask" "F.Paste")
			(net "LED_PWRGD_PVCCINFAON_CPU1")
		)
		(pad "2" smd circle
			(at 0.40005 0 270)
			(size 0 0)
			(layers "F.Cu" "F.Mask" "F.Paste")
			(net "P3V3_AUX")
		)
	)
	(footprint ""
		(layer "F.Cu")
		(at 118.542816 -256.6543 -90)
		(property "Reference" "C248"
			(at 0 0 270)
			(layer "F.SilkS")
			(hide yes)
			(effects
				(font
					(size 1.27 1.27)
				)
			)
		)
		(property "Value" ""
			(at 0 0 270)
			(layer "F.Fab")
			(effects
				(font
					(size 1.27 1.27)
				)
			)
		)
		(duplicate_pad_numbers_are_jumpers no)
		(fp_line
			(start -0.7874 0.4064)
			(end -0.7874 -0.4064)
			(stroke
				(width 0.1524)
				(type default)
			)
			(layer "F.SilkS")
		)
		(fp_line
			(start 0.7874 0.4064)
			(end -0.7874 0.4064)
			(stroke
				(width 0.1524)
				(type default)
			)
			(layer "F.SilkS")
		)
		(fp_line
			(start -0.7874 -0.4064)
			(end 0.7874 -0.4064)
			(stroke
				(width 0.1524)
				(type default)
			)
			(layer "F.SilkS")
		)
		(fp_line
			(start 0.7874 -0.4064)
			(end 0.7874 0.4064)
			(stroke
				(width 0.1524)
				(type default)
			)
			(layer "F.SilkS")
		)
		(fp_line
			(start -0.67945 0.3048)
			(end -0.67945 -0.305054)
			(stroke
				(width 0.1)
				(type default)
			)
			(layer "F.Fab")
		)
		(fp_line
			(start -0.12065 0.3048)
			(end -0.67945 0.3048)
			(stroke
				(width 0.1)
				(type default)
			)
			(layer "F.Fab")
		)
		(fp_line
			(start 0.120396 0.3048)
			(end 0.120396 0.2794)
			(stroke
				(width 0.1)
				(type default)
			)
			(layer "F.Fab")
		)
		(fp_line
			(start 0.67945 0.3048)
			(end 0.120396 0.3048)
			(stroke
				(width 0.1)
				(type default)
			)
			(layer "F.Fab")
		)
		(fp_line
			(start -0.12065 0.2794)
			(end -0.12065 0.3048)
			(stroke
				(width 0.1)
				(type default)
			)
			(layer "F.Fab")
		)
		(fp_line
			(start 0.120396 0.2794)
			(end -0.12065 0.2794)
			(stroke
				(width 0.1)
				(type default)
			)
			(layer "F.Fab")
		)
		(fp_line
			(start -0.12065 -0.2794)
			(end 0.12065 -0.2794)
			(stroke
				(width 0.1)
				(type default)
			)
			(layer "F.Fab")
		)
		(fp_line
			(start 0.12065 -0.2794)
			(end 0.12065 -0.3048)
			(stroke
				(width 0.1)
				(type default)
			)
			(layer "F.Fab")
		)
		(fp_line
			(start 0.12065 -0.3048)
			(end 0.67945 -0.3048)
			(stroke
				(width 0.1)
				(type default)
			)
			(layer "F.Fab")
		)
		(fp_line
			(start 0.67945 -0.3048)
			(end 0.67945 0.3048)
			(stroke
				(width 0.1)
				(type default)
			)
			(layer "F.Fab")
		)
		(fp_line
			(start -0.67945 -0.305054)
			(end -0.12065 -0.305054)
			(stroke
				(width 0.1)
				(type default)
			)
			(layer "F.Fab")
		)
		(fp_line
			(start -0.12065 -0.305054)
			(end -0.12065 -0.2794)
			(stroke
				(width 0.1)
				(type default)
			)
			(layer "F.Fab")
		)
		(pad "1" smd circle
			(at -0.40005 0 270)
			(size 0 0)
			(layers "F.Cu" "F.Mask" "F.Paste")
			(net "PVCCIN_CPU1")
		)
		(pad "2" smd circle
			(at 0.40005 0 270)
			(size 0 0)
			(layers "F.Cu" "F.Mask" "F.Paste")
			(net "GND")
		)
	)
	(footprint ""
		(layer "F.Cu")
		(at 122.301 -75.021948 90)
		(property "Reference" "R2506"
			(at 0 0 90)
			(layer "F.SilkS")
			(hide yes)
			(effects
				(font
					(size 1.27 1.27)
				)
			)
		)
		(property "Value" ""
			(at 0 0 90)
			(layer "F.Fab")
			(effects
				(font
					(size 1.27 1.27)
				)
			)
		)
		(duplicate_pad_numbers_are_jumpers no)
		(fp_line
			(start 0.7874 -0.4064)
			(end 0.7874 0.4064)
			(stroke
				(width 0.1524)
				(type default)
			)
			(layer "F.SilkS")
		)
		(fp_line
			(start -0.7874 -0.4064)
			(end 0.7874 -0.4064)
			(stroke
				(width 0.1524)
				(type default)
			)
			(layer "F.SilkS")
		)
		(fp_line
			(start 0.7874 0.4064)
			(end -0.7874 0.4064)
			(stroke
				(width 0.1524)
				(type default)
			)
			(layer "F.SilkS")
		)
		(fp_line
			(start -0.7874 0.4064)
			(end -0.7874 -0.4064)
			(stroke
				(width 0.1524)
				(type default)
			)
			(layer "F.SilkS")
		)
		(fp_line
			(start -0.12065 -0.305054)
			(end -0.12065 -0.2794)
			(stroke
				(width 0.1)
				(type default)
			)
			(layer "F.Fab")
		)
		(fp_line
			(start -0.67945 -0.305054)
			(end -0.12065 -0.305054)
			(stroke
				(width 0.1)
				(type default)
			)
			(layer "F.Fab")
		)
		(fp_line
			(start 0.67945 -0.3048)
			(end 0.67945 0.3048)
			(stroke
				(width 0.1)
				(type default)
			)
			(layer "F.Fab")
		)
		(fp_line
			(start 0.12065 -0.3048)
			(end 0.67945 -0.3048)
			(stroke
				(width 0.1)
				(type default)
			)
			(layer "F.Fab")
		)
		(fp_line
			(start 0.12065 -0.2794)
			(end 0.12065 -0.3048)
			(stroke
				(width 0.1)
				(type default)
			)
			(layer "F.Fab")
		)
		(fp_line
			(start -0.12065 -0.2794)
			(end 0.12065 -0.2794)
			(stroke
				(width 0.1)
				(type default)
			)
			(layer "F.Fab")
		)
		(fp_line
			(start 0.120396 0.2794)
			(end -0.12065 0.2794)
			(stroke
				(width 0.1)
				(type default)
			)
			(layer "F.Fab")
		)
		(fp_line
			(start -0.12065 0.2794)
			(end -0.12065 0.3048)
			(stroke
				(width 0.1)
				(type default)
			)
			(layer "F.Fab")
		)
		(fp_line
			(start 0.67945 0.3048)
			(end 0.120396 0.3048)
			(stroke
				(width 0.1)
				(type default)
			)
			(layer "F.Fab")
		)
		(fp_line
			(start 0.120396 0.3048)
			(end 0.120396 0.2794)
			(stroke
				(width 0.1)
				(type default)
			)
			(layer "F.Fab")
		)
		(fp_line
			(start -0.12065 0.3048)
			(end -0.67945 0.3048)
			(stroke
				(width 0.1)
				(type default)
			)
			(layer "F.Fab")
		)
		(fp_line
			(start -0.67945 0.3048)
			(end -0.67945 -0.305054)
			(stroke
				(width 0.1)
				(type default)
			)
			(layer "F.Fab")
		)
		(pad "1" smd circle
			(at -0.40005 0 90)
			(size 0 0)
			(layers "F.Cu" "F.Mask" "F.Paste")
			(net "P3V3_AUX")
		)
		(pad "2" smd circle
			(at 0.40005 0 90)
			(size 0 0)
			(layers "F.Cu" "F.Mask" "F.Paste")
			(net "JTAG_BMC_DBP_TMS")
		)
	)
	(footprint ""
		(layer "F.Cu")
		(at 257.85953 -51.669442)
		(property "Reference" "PC2281"
			(at 0 0 0)
			(layer "F.SilkS")
			(hide yes)
			(effects
				(font
					(size 1.27 1.27)
				)
			)
		)
		(property "Value" ""
			(at 0 0 0)
			(layer "F.Fab")
			(effects
				(font
					(size 1.27 1.27)
				)
			)
		)
		(duplicate_pad_numbers_are_jumpers no)
		(fp_line
			(start -0.7874 -0.4064)
			(end 0.7874 -0.4064)
			(stroke
				(width 0.1524)
				(type default)
			)
			(layer "F.SilkS")
		)
		(fp_line
			(start -0.7874 0.4064)
			(end -0.7874 -0.4064)
			(stroke
				(width 0.1524)
				(type default)
			)
			(layer "F.SilkS")
		)
		(fp_line
			(start 0.7874 -0.4064)
			(end 0.7874 0.4064)
			(stroke
				(width 0.1524)
				(type default)
			)
			(layer "F.SilkS")
		)
		(fp_line
			(start 0.7874 0.4064)
			(end -0.7874 0.4064)
			(stroke
				(width 0.1524)
				(type default)
			)
			(layer "F.SilkS")
		)
		(fp_line
			(start -0.67945 -0.305054)
			(end -0.12065 -0.305054)
			(stroke
				(width 0.1)
				(type default)
			)
			(layer "F.Fab")
		)
		(fp_line
			(start -0.67945 0.3048)
			(end -0.67945 -0.305054)
			(stroke
				(width 0.1)
				(type default)
			)
			(layer "F.Fab")
		)
		(fp_line
			(start -0.12065 -0.305054)
			(end -0.12065 -0.2794)
			(stroke
				(width 0.1)
				(type default)
			)
			(layer "F.Fab")
		)
		(fp_line
			(start -0.12065 -0.2794)
			(end 0.12065 -0.2794)
			(stroke
				(width 0.1)
				(type default)
			)
			(layer "F.Fab")
		)
		(fp_line
			(start -0.12065 0.2794)
			(end -0.12065 0.3048)
			(stroke
				(width 0.1)
				(type default)
			)
			(layer "F.Fab")
		)
		(fp_line
			(start -0.12065 0.3048)
			(end -0.67945 0.3048)
			(stroke
				(width 0.1)
				(type default)
			)
			(layer "F.Fab")
		)
		(fp_line
			(start 0.120396 0.2794)
			(end -0.12065 0.2794)
			(stroke
				(width 0.1)
				(type default)
			)
			(layer "F.Fab")
		)
		(fp_line
			(start 0.120396 0.3048)
			(end 0.120396 0.2794)
			(stroke
				(width 0.1)
				(type default)
			)
			(layer "F.Fab")
		)
		(fp_line
			(start 0.12065 -0.3048)
			(end 0.67945 -0.3048)
			(stroke
				(width 0.1)
				(type default)
			)
			(layer "F.Fab")
		)
		(fp_line
			(start 0.12065 -0.2794)
			(end 0.12065 -0.3048)
			(stroke
				(width 0.1)
				(type default)
			)
			(layer "F.Fab")
		)
		(fp_line
			(start 0.67945 -0.3048)
			(end 0.67945 0.3048)
			(stroke
				(width 0.1)
				(type default)
			)
			(layer "F.Fab")
		)
		(fp_line
			(start 0.67945 0.3048)
			(end 0.120396 0.3048)
			(stroke
				(width 0.1)
				(type default)
			)
			(layer "F.Fab")
		)
		(pad "1" smd circle
			(at -0.40005 0)
			(size 0 0)
			(layers "F.Cu" "F.Mask" "F.Paste")
			(net "P12V_E1S_SS_0")
		)
		(pad "2" smd circle
			(at 0.40005 0)
			(size 0 0)
			(layers "F.Cu" "F.Mask" "F.Paste")
			(net "GND")
		)
	)
	(footprint ""
		(layer "F.Cu")
		(at 117.526816 -244.032024 90)
		(property "Reference" "C274"
			(at 0 0 90)
			(layer "F.SilkS")
			(hide yes)
			(effects
				(font
					(size 1.27 1.27)
				)
			)
		)
		(property "Value" ""
			(at 0 0 90)
			(layer "F.Fab")
			(effects
				(font
					(size 1.27 1.27)
				)
			)
		)
		(duplicate_pad_numbers_are_jumpers no)
		(fp_line
			(start 0.7874 -0.4064)
			(end 0.7874 0.4064)
			(stroke
				(width 0.1524)
				(type default)
			)
			(layer "F.SilkS")
		)
		(fp_line
			(start -0.7874 -0.4064)
			(end 0.7874 -0.4064)
			(stroke
				(width 0.1524)
				(type default)
			)
			(layer "F.SilkS")
		)
		(fp_line
			(start 0.7874 0.4064)
			(end -0.7874 0.4064)
			(stroke
				(width 0.1524)
				(type default)
			)
			(layer "F.SilkS")
		)
		(fp_line
			(start -0.7874 0.4064)
			(end -0.7874 -0.4064)
			(stroke
				(width 0.1524)
				(type default)
			)
			(layer "F.SilkS")
		)
		(fp_line
			(start -0.12065 -0.305054)
			(end -0.12065 -0.2794)
			(stroke
				(width 0.1)
				(type default)
			)
			(layer "F.Fab")
		)
		(fp_line
			(start -0.67945 -0.305054)
			(end -0.12065 -0.305054)
			(stroke
				(width 0.1)
				(type default)
			)
			(layer "F.Fab")
		)
		(fp_line
			(start 0.67945 -0.3048)
			(end 0.67945 0.3048)
			(stroke
				(width 0.1)
				(type default)
			)
			(layer "F.Fab")
		)
		(fp_line
			(start 0.12065 -0.3048)
			(end 0.67945 -0.3048)
			(stroke
				(width 0.1)
				(type default)
			)
			(layer "F.Fab")
		)
		(fp_line
			(start 0.12065 -0.2794)
			(end 0.12065 -0.3048)
			(stroke
				(width 0.1)
				(type default)
			)
			(layer "F.Fab")
		)
		(fp_line
			(start -0.12065 -0.2794)
			(end 0.12065 -0.2794)
			(stroke
				(width 0.1)
				(type default)
			)
			(layer "F.Fab")
		)
		(fp_line
			(start 0.120396 0.2794)
			(end -0.12065 0.2794)
			(stroke
				(width 0.1)
				(type default)
			)
			(layer "F.Fab")
		)
		(fp_line
			(start -0.12065 0.2794)
			(end -0.12065 0.3048)
			(stroke
				(width 0.1)
				(type default)
			)
			(layer "F.Fab")
		)
		(fp_line
			(start 0.67945 0.3048)
			(end 0.120396 0.3048)
			(stroke
				(width 0.1)
				(type default)
			)
			(layer "F.Fab")
		)
		(fp_line
			(start 0.120396 0.3048)
			(end 0.120396 0.2794)
			(stroke
				(width 0.1)
				(type default)
			)
			(layer "F.Fab")
		)
		(fp_line
			(start -0.12065 0.3048)
			(end -0.67945 0.3048)
			(stroke
				(width 0.1)
				(type default)
			)
			(layer "F.Fab")
		)
		(fp_line
			(start -0.67945 0.3048)
			(end -0.67945 -0.305054)
			(stroke
				(width 0.1)
				(type default)
			)
			(layer "F.Fab")
		)
		(pad "1" smd circle
			(at -0.40005 0 90)
			(size 0 0)
			(layers "F.Cu" "F.Mask" "F.Paste")
			(net "PVCCIN_CPU1")
		)
		(pad "2" smd circle
			(at 0.40005 0 90)
			(size 0 0)
			(layers "F.Cu" "F.Mask" "F.Paste")
			(net "GND")
		)
	)
	(footprint ""
		(layer "F.Cu")
		(at 258.130548 -258.091686)
		(property "Reference" "J7"
			(at -3.683 -81.702148 0)
			(unlocked yes)
			(layer "F.SilkS")
			(effects
				(font
					(size 0.7874 0.5842)
					(thickness 0.1524)
				)
				(justify left)
			)
		)
		(property "Value" ""
			(at 0 0 0)
			(layer "F.Fab")
			(effects
				(font
					(size 1.27 1.27)
				)
			)
		)
		(duplicate_pad_numbers_are_jumpers no)
		(fp_line
			(start -3.24993 -81.000092)
			(end -3.24993 81.000092)
			(stroke
				(width 0.1524)
				(type default)
			)
			(layer "F.SilkS")
		)
		(fp_line
			(start -3.24993 81.000092)
			(end 3.24993 81.000092)
			(stroke
				(width 0.1524)
				(type default)
			)
			(layer "F.SilkS")
		)
		(fp_line
			(start 3.24993 -81.000092)
			(end -3.24993 -81.000092)
			(stroke
				(width 0.1524)
				(type default)
			)
			(layer "F.SilkS")
		)
		(fp_line
			(start 3.24993 -72.00011)
			(end -3.24993 -72.00011)
			(stroke
				(width 0.1524)
				(type default)
			)
			(layer "F.SilkS")
		)
		(fp_line
			(start 3.24993 72.00011)
			(end -3.24993 72.00011)
			(stroke
				(width 0.1524)
				(type default)
			)
			(layer "F.SilkS")
		)
		(fp_line
			(start 3.24993 81.000092)
			(end 3.24993 -81.000092)
			(stroke
				(width 0.1524)
				(type default)
			)
			(layer "F.SilkS")
		)
		(fp_poly
			(pts
				(xy -3.381756 -63.576454) (xy -4.397756 -63.068454) (xy -4.397756 -64.084454)
			)
			(stroke
				(width 0)
				(type default)
			)
			(fill yes)
			(layer "F.SilkS")
		)
		(fp_line
			(start -3.24993 -81.000092)
			(end -3.24993 81.000092)
			(stroke
				(width 0.1)
				(type default)
			)
			(layer "F.Fab")
		)
		(fp_line
			(start -3.24993 81.000092)
			(end 3.24993 81.000092)
			(stroke
				(width 0.1)
				(type default)
			)
			(layer "F.Fab")
		)
		(fp_line
			(start 3.24993 -81.000092)
			(end -3.24993 -81.000092)
			(stroke
				(width 0.1)
				(type default)
			)
			(layer "F.Fab")
		)
		(fp_line
			(start 3.24993 -72.00011)
			(end -3.24993 -72.00011)
			(stroke
				(width 0.1)
				(type default)
			)
			(layer "F.Fab")
		)
		(fp_line
			(start 3.24993 -71.000112)
			(end -3.24993 -71.000112)
			(stroke
				(width 0.1)
				(type default)
			)
			(layer "F.Fab")
		)
		(fp_line
			(start 3.24993 71.000112)
			(end -3.24993 71.000112)
			(stroke
				(width 0.1)
				(type default)
			)
			(layer "F.Fab")
		)
		(fp_line
			(start 3.24993 72.00011)
			(end -3.24993 72.00011)
			(stroke
				(width 0.1)
				(type default)
			)
			(layer "F.Fab")
		)
		(fp_line
			(start 3.24993 81.000092)
			(end 3.24993 -81.000092)
			(stroke
				(width 0.1)
				(type default)
			)
			(layer "F.Fab")
		)
		(fp_poly
			(pts
				(xy -4.445 -63.832994) (xy -4.445 -62.816994) (xy -3.429 -63.324994)
			)
			(stroke
				(width 0)
				(type default)
			)
			(fill yes)
			(layer "F.Fab")
		)
		(pad "1" smd rect
			(at -2.050034 -63.324994 270)
			(size 0.519938 1.4986)
			(layers "F.Cu" "F.Mask" "F.Paste")
			(net "P12V_S3_AUX_CPU0_NVDIMM")
		)
		(pad "2" smd rect
			(at -2.050034 -62.47511 270)
			(size 0.519938 1.4986)
			(layers "F.Cu" "F.Mask" "F.Paste")
			(net "TP_CHD_CPU0_DIMM1_FRU_0")
		)
		(pad "3" smd rect
			(at -2.050034 -61.624972 270)
			(size 0.519938 1.4986)
			(layers "F.Cu" "F.Mask" "F.Paste")
			(net "P3V3_AUX")
		)
		(pad "4" smd rect
			(at -2.050034 -60.775088 270)
			(size 0.519938 1.4986)
			(layers "F.Cu" "F.Mask" "F.Paste")
			(net "I3C_SPD_DDRABCD_CPU0_LVC1_SCL_6")
		)
		(pad "5" smd rect
			(at -2.050034 -59.92495 270)
			(size 0.519938 1.4986)
			(layers "F.Cu" "F.Mask" "F.Paste")
			(net "I3C_SPD_DDRABCD_CPU0_LVC1_SDA")
		)
		(pad "6" smd rect
			(at -2.050034 -59.075066 270)
			(size 0.519938 1.4986)
			(layers "F.Cu" "F.Mask" "F.Paste")
			(net "GND")
		)
		(pad "7" smd rect
			(at -2.050034 -58.224928 270)
			(size 0.519938 1.4986)
			(layers "F.Cu" "F.Mask" "F.Paste")
			(net "M_D_CPU0_SA_DQ<0>")
		)
		(pad "8" smd rect
			(at -2.050034 -57.375044 270)
			(size 0.519938 1.4986)
			(layers "F.Cu" "F.Mask" "F.Paste")
			(net "GND")
		)
		(pad "9" smd rect
			(at -2.050034 -56.524906 270)
			(size 0.519938 1.4986)
			(layers "F.Cu" "F.Mask" "F.Paste")
			(net "M_D_CPU0_SA_DQ<1>")
		)
		(pad "10" smd rect
			(at -2.050034 -55.675022 270)
			(size 0.519938 1.4986)
			(layers "F.Cu" "F.Mask" "F.Paste")
			(net "GND")
		)
		(pad "11" smd rect
			(at -2.050034 -54.824884 270)
			(size 0.519938 1.4986)
			(layers "F.Cu" "F.Mask" "F.Paste")
			(net "M_D_CPU0_SA_DQS_DP<0>")
		)
		(pad "12" smd rect
			(at -2.050034 -53.975 270)
			(size 0.519938 1.4986)
			(layers "F.Cu" "F.Mask" "F.Paste")
			(net "M_D_CPU0_SA_DQS_DN<0>")
		)
		(pad "13" smd rect
			(at -2.050034 -53.125116 270)
			(size 0.519938 1.4986)
			(layers "F.Cu" "F.Mask" "F.Paste")
			(net "GND")
		)
		(pad "14" smd rect
			(at -2.050034 -52.274978 270)
			(size 0.519938 1.4986)
			(layers "F.Cu" "F.Mask" "F.Paste")
			(net "M_D_CPU0_SA_DQ<4>")
		)
		(pad "15" smd rect
			(at -2.050034 -51.425094 270)
			(size 0.519938 1.4986)
			(layers "F.Cu" "F.Mask" "F.Paste")
			(net "GND")
		)
		(pad "16" smd rect
			(at -2.050034 -50.574956 270)
			(size 0.519938 1.4986)
			(layers "F.Cu" "F.Mask" "F.Paste")
			(net "M_D_CPU0_SA_DQ<5>")
		)
		(pad "17" smd rect
			(at -2.050034 -49.725072 270)
			(size 0.519938 1.4986)
			(layers "F.Cu" "F.Mask" "F.Paste")
			(net "GND")
		)
		(pad "18" smd rect
			(at -2.050034 -48.874934 270)
			(size 0.519938 1.4986)
			(layers "F.Cu" "F.Mask" "F.Paste")
			(net "M_D_CPU0_SA_DQ<8>")
		)
		(pad "19" smd rect
			(at -2.050034 -48.02505 270)
			(size 0.519938 1.4986)
			(layers "F.Cu" "F.Mask" "F.Paste")
			(net "GND")
		)
		(pad "20" smd rect
			(at -2.050034 -47.174912 270)
			(size 0.519938 1.4986)
			(layers "F.Cu" "F.Mask" "F.Paste")
			(net "M_D_CPU0_SA_DQ<9>")
		)
		(pad "21" smd rect
			(at -2.050034 -46.325028 270)
			(size 0.519938 1.4986)
			(layers "F.Cu" "F.Mask" "F.Paste")
			(net "GND")
		)
		(pad "22" smd rect
			(at -2.050034 -45.47489 270)
			(size 0.519938 1.4986)
			(layers "F.Cu" "F.Mask" "F.Paste")
			(net "M_D_CPU0_SA_DQS_DP<1>")
		)
		(pad "23" smd rect
			(at -2.050034 -44.625006 270)
			(size 0.519938 1.4986)
			(layers "F.Cu" "F.Mask" "F.Paste")
			(net "M_D_CPU0_SA_DQS_DN<1>")
		)
		(pad "24" smd rect
			(at -2.050034 -43.775122 270)
			(size 0.519938 1.4986)
			(layers "F.Cu" "F.Mask" "F.Paste")
			(net "GND")
		)
		(pad "25" smd rect
			(at -2.050034 -42.924984 270)
			(size 0.519938 1.4986)
			(layers "F.Cu" "F.Mask" "F.Paste")
			(net "M_D_CPU0_SA_DQ<12>")
		)
		(pad "26" smd rect
			(at -2.050034 -42.0751 270)
			(size 0.519938 1.4986)
			(layers "F.Cu" "F.Mask" "F.Paste")
			(net "GND")
		)
		(pad "27" smd rect
			(at -2.050034 -41.224962 270)
			(size 0.519938 1.4986)
			(layers "F.Cu" "F.Mask" "F.Paste")
			(net "M_D_CPU0_SA_DQ<13>")
		)
		(pad "28" smd rect
			(at -2.050034 -40.375078 270)
			(size 0.519938 1.4986)
			(layers "F.Cu" "F.Mask" "F.Paste")
			(net "GND")
		)
		(pad "29" smd rect
			(at -2.050034 -39.52494 270)
			(size 0.519938 1.4986)
			(layers "F.Cu" "F.Mask" "F.Paste")
			(net "M_D_CPU0_SA_DQ<16>")
		)
		(pad "30" smd rect
			(at -2.050034 -38.675056 270)
			(size 0.519938 1.4986)
			(layers "F.Cu" "F.Mask" "F.Paste")
			(net "GND")
		)
		(pad "31" smd rect
			(at -2.050034 -37.824918 270)
			(size 0.519938 1.4986)
			(layers "F.Cu" "F.Mask" "F.Paste")
			(net "M_D_CPU0_SA_DQ<17>")
		)
		(pad "32" smd rect
			(at -2.050034 -36.975034 270)
			(size 0.519938 1.4986)
			(layers "F.Cu" "F.Mask" "F.Paste")
			(net "GND")
		)
		(pad "33" smd rect
			(at -2.050034 -36.124896 270)
			(size 0.519938 1.4986)
			(layers "F.Cu" "F.Mask" "F.Paste")
			(net "M_D_CPU0_SA_DQS_DP<2>")
		)
		(pad "34" smd rect
			(at -2.050034 -35.275012 270)
			(size 0.519938 1.4986)
			(layers "F.Cu" "F.Mask" "F.Paste")
			(net "M_D_CPU0_SA_DQS_DN<2>")
		)
		(pad "35" smd rect
			(at -2.050034 -34.425128 270)
			(size 0.519938 1.4986)
			(layers "F.Cu" "F.Mask" "F.Paste")
			(net "GND")
		)
		(pad "36" smd rect
			(at -2.050034 -33.57499 270)
			(size 0.519938 1.4986)
			(layers "F.Cu" "F.Mask" "F.Paste")
			(net "M_D_CPU0_SA_DQ<20>")
		)
		(pad "37" smd rect
			(at -2.050034 -32.725106 270)
			(size 0.519938 1.4986)
			(layers "F.Cu" "F.Mask" "F.Paste")
			(net "GND")
		)
		(pad "38" smd rect
			(at -2.050034 -31.874968 270)
			(size 0.519938 1.4986)
			(layers "F.Cu" "F.Mask" "F.Paste")
			(net "M_D_CPU0_SA_DQ<21>")
		)
		(pad "39" smd rect
			(at -2.050034 -31.025084 270)
			(size 0.519938 1.4986)
			(layers "F.Cu" "F.Mask" "F.Paste")
			(net "GND")
		)
		(pad "40" smd rect
			(at -2.050034 -30.174946 270)
			(size 0.519938 1.4986)
			(layers "F.Cu" "F.Mask" "F.Paste")
			(net "M_D_CPU0_SA_DQ<24>")
		)
		(pad "41" smd rect
			(at -2.050034 -29.325062 270)
			(size 0.519938 1.4986)
			(layers "F.Cu" "F.Mask" "F.Paste")
			(net "GND")
		)
		(pad "42" smd rect
			(at -2.050034 -28.474924 270)
			(size 0.519938 1.4986)
			(layers "F.Cu" "F.Mask" "F.Paste")
			(net "M_D_CPU0_SA_DQ<25>")
		)
		(pad "43" smd rect
			(at -2.050034 -27.62504 270)
			(size 0.519938 1.4986)
			(layers "F.Cu" "F.Mask" "F.Paste")
			(net "GND")
		)
		(pad "44" smd rect
			(at -2.050034 -26.774902 270)
			(size 0.519938 1.4986)
			(layers "F.Cu" "F.Mask" "F.Paste")
			(net "M_D_CPU0_SA_DQS_DP<3>")
		)
		(pad "45" smd rect
			(at -2.050034 -25.925018 270)
			(size 0.519938 1.4986)
			(layers "F.Cu" "F.Mask" "F.Paste")
			(net "M_D_CPU0_SA_DQS_DN<3>")
		)
		(pad "46" smd rect
			(at -2.050034 -25.07488 270)
			(size 0.519938 1.4986)
			(layers "F.Cu" "F.Mask" "F.Paste")
			(net "GND")
		)
		(pad "47" smd rect
			(at -2.050034 -24.224996 270)
			(size 0.519938 1.4986)
			(layers "F.Cu" "F.Mask" "F.Paste")
			(net "M_D_CPU0_SA_DQ<28>")
		)
		(pad "48" smd rect
			(at -2.050034 -23.375112 270)
			(size 0.519938 1.4986)
			(layers "F.Cu" "F.Mask" "F.Paste")
			(net "GND")
		)
		(pad "49" smd rect
			(at -2.050034 -22.524974 270)
			(size 0.519938 1.4986)
			(layers "F.Cu" "F.Mask" "F.Paste")
			(net "M_D_CPU0_SA_DQ<29>")
		)
		(pad "50" smd rect
			(at -2.050034 -21.67509 270)
			(size 0.519938 1.4986)
			(layers "F.Cu" "F.Mask" "F.Paste")
			(net "GND")
		)
		(pad "51" smd rect
			(at -2.050034 -20.824952 270)
			(size 0.519938 1.4986)
			(layers "F.Cu" "F.Mask" "F.Paste")
			(net "M_D_CPU0_SA_CB<0>")
		)
		(pad "52" smd rect
			(at -2.050034 -19.975068 270)
			(size 0.519938 1.4986)
			(layers "F.Cu" "F.Mask" "F.Paste")
			(net "GND")
		)
		(pad "53" smd rect
			(at -2.050034 -19.12493 270)
			(size 0.519938 1.4986)
			(layers "F.Cu" "F.Mask" "F.Paste")
			(net "M_D_CPU0_SA_CB<1>")
		)
		(pad "54" smd rect
			(at -2.050034 -18.275046 270)
			(size 0.519938 1.4986)
			(layers "F.Cu" "F.Mask" "F.Paste")
			(net "GND")
		)
		(pad "55" smd rect
			(at -2.050034 -17.424908 270)
			(size 0.519938 1.4986)
			(layers "F.Cu" "F.Mask" "F.Paste")
			(net "M_D_CPU0_SA_DQS_DP<4>")
		)
		(pad "56" smd rect
			(at -2.050034 -16.575024 270)
			(size 0.519938 1.4986)
			(layers "F.Cu" "F.Mask" "F.Paste")
			(net "M_D_CPU0_SA_DQS_DN<4>")
		)
		(pad "57" smd rect
			(at -2.050034 -15.724886 270)
			(size 0.519938 1.4986)
			(layers "F.Cu" "F.Mask" "F.Paste")
			(net "GND")
		)
		(pad "58" smd rect
			(at -2.050034 -14.875002 270)
			(size 0.519938 1.4986)
			(layers "F.Cu" "F.Mask" "F.Paste")
			(net "M_D_CPU0_SA_CB<4>")
		)
		(pad "59" smd rect
			(at -2.050034 -14.025118 270)
			(size 0.519938 1.4986)
			(layers "F.Cu" "F.Mask" "F.Paste")
			(net "GND")
		)
		(pad "60" smd rect
			(at -2.050034 -13.17498 270)
			(size 0.519938 1.4986)
			(layers "F.Cu" "F.Mask" "F.Paste")
			(net "M_D_CPU0_SA_CB<5>")
		)
		(pad "61" smd rect
			(at -2.050034 -12.325096 270)
			(size 0.519938 1.4986)
			(layers "F.Cu" "F.Mask" "F.Paste")
			(net "GND")
		)
		(pad "62" smd rect
			(at -2.050034 -11.474958 270)
			(size 0.519938 1.4986)
			(layers "F.Cu" "F.Mask" "F.Paste")
			(net "M_D_CPU0_ALERT_N")
		)
		(pad "63" smd rect
			(at -2.050034 -10.625074 270)
			(size 0.519938 1.4986)
			(layers "F.Cu" "F.Mask" "F.Paste")
			(net "GND")
		)
		(pad "64" smd rect
			(at -2.050034 -9.774936 270)
			(size 0.519938 1.4986)
			(layers "F.Cu" "F.Mask" "F.Paste")
			(net "M_D_CPU0_SA_CS_N<0>")
		)
		(pad "65" smd rect
			(at -2.050034 -8.925052 270)
			(size 0.519938 1.4986)
			(layers "F.Cu" "F.Mask" "F.Paste")
			(net "GND")
		)
		(pad "66" smd rect
			(at -2.050034 -8.074914 270)
			(size 0.519938 1.4986)
			(layers "F.Cu" "F.Mask" "F.Paste")
			(net "M_D_CPU0_SA_CA<0>")
		)
		(pad "67" smd rect
			(at -2.050034 -7.22503 270)
			(size 0.519938 1.4986)
			(layers "F.Cu" "F.Mask" "F.Paste")
			(net "GND")
		)
		(pad "68" smd rect
			(at -2.050034 -6.374892 270)
			(size 0.519938 1.4986)
			(layers "F.Cu" "F.Mask" "F.Paste")
			(net "M_D_CPU0_SA_CA<2>")
		)
		(pad "69" smd rect
			(at -2.050034 -5.525008 270)
			(size 0.519938 1.4986)
			(layers "F.Cu" "F.Mask" "F.Paste")
			(net "GND")
		)
		(pad "70" smd rect
			(at -2.050034 -4.675124 270)
			(size 0.519938 1.4986)
			(layers "F.Cu" "F.Mask" "F.Paste")
			(net "M_D_CPU0_SA_CA<4>")
		)
		(pad "71" smd rect
			(at -2.050034 -3.824986 270)
			(size 0.519938 1.4986)
			(layers "F.Cu" "F.Mask" "F.Paste")
			(net "GND")
		)
		(pad "72" smd rect
			(at -2.050034 -2.975102 270)
			(size 0.519938 1.4986)
			(layers "F.Cu" "F.Mask" "F.Paste")
			(net "M_D_CPU0_SA_CA<6>")
		)
		(pad "73" smd rect
			(at -2.050034 -2.124964 270)
			(size 0.519938 1.4986)
			(layers "F.Cu" "F.Mask" "F.Paste")
			(net "GND")
		)
		(pad "74" smd rect
			(at -2.050034 -1.27508 270)
			(size 0.519938 1.4986)
			(layers "F.Cu" "F.Mask" "F.Paste")
			(net "M_D_CPU0_SA_PAR")
		)
		(pad "75" smd rect
			(at -2.050034 -0.424942 270)
			(size 0.519938 1.4986)
			(layers "F.Cu" "F.Mask" "F.Paste")
			(net "GND")
		)
		(pad "76" smd rect
			(at -2.050034 5.525008 270)
			(size 0.519938 1.4986)
			(layers "F.Cu" "F.Mask" "F.Paste")
			(net "M_D_CPU0_SB_CA<0>")
		)
		(pad "77" smd rect
			(at -2.050034 6.374892 270)
			(size 0.519938 1.4986)
			(layers "F.Cu" "F.Mask" "F.Paste")
			(net "GND")
		)
		(pad "78" smd rect
			(at -2.050034 7.22503 270)
			(size 0.519938 1.4986)
			(layers "F.Cu" "F.Mask" "F.Paste")
			(net "M_D_CPU0_SB_CA<2>")
		)
		(pad "79" smd rect
			(at -2.050034 8.074914 270)
			(size 0.519938 1.4986)
			(layers "F.Cu" "F.Mask" "F.Paste")
			(net "GND")
		)
		(pad "80" smd rect
			(at -2.050034 8.925052 270)
			(size 0.519938 1.4986)
			(layers "F.Cu" "F.Mask" "F.Paste")
			(net "M_D_CPU0_SB_CA<4>")
		)
		(pad "81" smd rect
			(at -2.050034 9.774936 270)
			(size 0.519938 1.4986)
			(layers "F.Cu" "F.Mask" "F.Paste")
			(net "GND")
		)
		(pad "82" smd rect
			(at -2.050034 10.625074 270)
			(size 0.519938 1.4986)
			(layers "F.Cu" "F.Mask" "F.Paste")
			(net "M_D_CPU0_SB_CA<6>")
		)
		(pad "83" smd rect
			(at -2.050034 11.474958 270)
			(size 0.519938 1.4986)
			(layers "F.Cu" "F.Mask" "F.Paste")
			(net "GND")
		)
		(pad "84" smd rect
			(at -2.050034 12.325096 270)
			(size 0.519938 1.4986)
			(layers "F.Cu" "F.Mask" "F.Paste")
			(net "M_D_CPU0_SB_CS_N<0>")
		)
		(pad "85" smd rect
			(at -2.050034 13.17498 270)
			(size 0.519938 1.4986)
			(layers "F.Cu" "F.Mask" "F.Paste")
			(net "GND")
		)
		(pad "86" smd rect
			(at -2.050034 14.025118 270)
			(size 0.519938 1.4986)
			(layers "F.Cu" "F.Mask" "F.Paste")
			(net "M_D_CPU0_SA_RSP<0>")
		)
		(pad "87" smd rect
			(at -2.050034 14.875002 270)
			(size 0.519938 1.4986)
			(layers "F.Cu" "F.Mask" "F.Paste")
			(net "M_D_CPU0_SB_RSP<0>")
		)
		(pad "88" smd rect
			(at -2.050034 15.724886 270)
			(size 0.519938 1.4986)
			(layers "F.Cu" "F.Mask" "F.Paste")
			(net "GND")
		)
		(pad "89" smd rect
			(at -2.050034 16.575024 270)
			(size 0.519938 1.4986)
			(layers "F.Cu" "F.Mask" "F.Paste")
			(net "M_D_CPU0_SB_CB<4>")
		)
		(pad "90" smd rect
			(at -2.050034 17.424908 270)
			(size 0.519938 1.4986)
			(layers "F.Cu" "F.Mask" "F.Paste")
			(net "GND")
		)
		(pad "91" smd rect
			(at -2.050034 18.275046 270)
			(size 0.519938 1.4986)
			(layers "F.Cu" "F.Mask" "F.Paste")
			(net "M_D_CPU0_SB_CB<5>")
		)
		(pad "92" smd rect
			(at -2.050034 19.12493 270)
			(size 0.519938 1.4986)
			(layers "F.Cu" "F.Mask" "F.Paste")
			(net "GND")
		)
		(pad "93" smd rect
			(at -2.050034 19.975068 270)
			(size 0.519938 1.4986)
			(layers "F.Cu" "F.Mask" "F.Paste")
			(net "M_D_CPU0_SB_DQS_DP<9>")
		)
		(pad "94" smd rect
			(at -2.050034 20.824952 270)
			(size 0.519938 1.4986)
			(layers "F.Cu" "F.Mask" "F.Paste")
			(net "M_D_CPU0_SB_DQS_DN<9>")
		)
		(pad "95" smd rect
			(at -2.050034 21.67509 270)
			(size 0.519938 1.4986)
			(layers "F.Cu" "F.Mask" "F.Paste")
			(net "GND")
		)
		(pad "96" smd rect
			(at -2.050034 22.524974 270)
			(size 0.519938 1.4986)
			(layers "F.Cu" "F.Mask" "F.Paste")
			(net "M_D_CPU0_SB_CB<0>")
		)
		(pad "97" smd rect
			(at -2.050034 23.375112 270)
			(size 0.519938 1.4986)
			(layers "F.Cu" "F.Mask" "F.Paste")
			(net "GND")
		)
		(pad "98" smd rect
			(at -2.050034 24.224996 270)
			(size 0.519938 1.4986)
			(layers "F.Cu" "F.Mask" "F.Paste")
			(net "M_D_CPU0_SB_CB<1>")
		)
		(pad "99" smd rect
			(at -2.050034 25.07488 270)
			(size 0.519938 1.4986)
			(layers "F.Cu" "F.Mask" "F.Paste")
			(net "GND")
		)
		(pad "100" smd rect
			(at -2.050034 25.925018 270)
			(size 0.519938 1.4986)
			(layers "F.Cu" "F.Mask" "F.Paste")
			(net "M_D_CPU0_SB_DQ<0>")
		)
		(pad "101" smd rect
			(at -2.050034 26.774902 270)
			(size 0.519938 1.4986)
			(layers "F.Cu" "F.Mask" "F.Paste")
			(net "GND")
		)
		(pad "102" smd rect
			(at -2.050034 27.62504 270)
			(size 0.519938 1.4986)
			(layers "F.Cu" "F.Mask" "F.Paste")
			(net "M_D_CPU0_SB_DQ<1>")
		)
		(pad "103" smd rect
			(at -2.050034 28.474924 270)
			(size 0.519938 1.4986)
			(layers "F.Cu" "F.Mask" "F.Paste")
			(net "GND")
		)
		(pad "104" smd rect
			(at -2.050034 29.325062 270)
			(size 0.519938 1.4986)
			(layers "F.Cu" "F.Mask" "F.Paste")
			(net "M_D_CPU0_SB_DQS_DP<0>")
		)
		(pad "105" smd rect
			(at -2.050034 30.174946 270)
			(size 0.519938 1.4986)
			(layers "F.Cu" "F.Mask" "F.Paste")
			(net "M_D_CPU0_SB_DQS_DN<0>")
		)
		(pad "106" smd rect
			(at -2.050034 31.025084 270)
			(size 0.519938 1.4986)
			(layers "F.Cu" "F.Mask" "F.Paste")
			(net "GND")
		)
		(pad "107" smd rect
			(at -2.050034 31.874968 270)
			(size 0.519938 1.4986)
			(layers "F.Cu" "F.Mask" "F.Paste")
			(net "M_D_CPU0_SB_DQ<4>")
		)
		(pad "108" smd rect
			(at -2.050034 32.725106 270)
			(size 0.519938 1.4986)
			(layers "F.Cu" "F.Mask" "F.Paste")
			(net "GND")
		)
		(pad "109" smd rect
			(at -2.050034 33.57499 270)
			(size 0.519938 1.4986)
			(layers "F.Cu" "F.Mask" "F.Paste")
			(net "M_D_CPU0_SB_DQ<5>")
		)
		(pad "110" smd rect
			(at -2.050034 34.425128 270)
			(size 0.519938 1.4986)
			(layers "F.Cu" "F.Mask" "F.Paste")
			(net "GND")
		)
		(pad "111" smd rect
			(at -2.050034 35.275012 270)
			(size 0.519938 1.4986)
			(layers "F.Cu" "F.Mask" "F.Paste")
			(net "M_D_CPU0_SB_DQ<8>")
		)
		(pad "112" smd rect
			(at -2.050034 36.124896 270)
			(size 0.519938 1.4986)
			(layers "F.Cu" "F.Mask" "F.Paste")
			(net "GND")
		)
		(pad "113" smd rect
			(at -2.050034 36.975034 270)
			(size 0.519938 1.4986)
			(layers "F.Cu" "F.Mask" "F.Paste")
			(net "M_D_CPU0_SB_DQ<9>")
		)
		(pad "114" smd rect
			(at -2.050034 37.824918 270)
			(size 0.519938 1.4986)
			(layers "F.Cu" "F.Mask" "F.Paste")
			(net "GND")
		)
		(pad "115" smd rect
			(at -2.050034 38.675056 270)
			(size 0.519938 1.4986)
			(layers "F.Cu" "F.Mask" "F.Paste")
			(net "M_D_CPU0_SB_DQS_DP<1>")
		)
		(pad "116" smd rect
			(at -2.050034 39.52494 270)
			(size 0.519938 1.4986)
			(layers "F.Cu" "F.Mask" "F.Paste")
			(net "M_D_CPU0_SB_DQS_DN<1>")
		)
		(pad "117" smd rect
			(at -2.050034 40.375078 270)
			(size 0.519938 1.4986)
			(layers "F.Cu" "F.Mask" "F.Paste")
			(net "GND")
		)
		(pad "118" smd rect
			(at -2.050034 41.224962 270)
			(size 0.519938 1.4986)
			(layers "F.Cu" "F.Mask" "F.Paste")
			(net "M_D_CPU0_SB_DQ<12>")
		)
		(pad "119" smd rect
			(at -2.050034 42.0751 270)
			(size 0.519938 1.4986)
			(layers "F.Cu" "F.Mask" "F.Paste")
			(net "GND")
		)
		(pad "120" smd rect
			(at -2.050034 42.924984 270)
			(size 0.519938 1.4986)
			(layers "F.Cu" "F.Mask" "F.Paste")
			(net "M_D_CPU0_SB_DQ<13>")
		)
		(pad "121" smd rect
			(at -2.050034 43.775122 270)
			(size 0.519938 1.4986)
			(layers "F.Cu" "F.Mask" "F.Paste")
			(net "GND")
		)
		(pad "122" smd rect
			(at -2.050034 44.625006 270)
			(size 0.519938 1.4986)
			(layers "F.Cu" "F.Mask" "F.Paste")
			(net "M_D_CPU0_SB_DQ<16>")
		)
		(pad "123" smd rect
			(at -2.050034 45.47489 270)
			(size 0.519938 1.4986)
			(layers "F.Cu" "F.Mask" "F.Paste")
			(net "GND")
		)
		(pad "124" smd rect
			(at -2.050034 46.325028 270)
			(size 0.519938 1.4986)
			(layers "F.Cu" "F.Mask" "F.Paste")
			(net "M_D_CPU0_SB_DQ<17>")
		)
		(pad "125" smd rect
			(at -2.050034 47.174912 270)
			(size 0.519938 1.4986)
			(layers "F.Cu" "F.Mask" "F.Paste")
			(net "GND")
		)
		(pad "126" smd rect
			(at -2.050034 48.02505 270)
			(size 0.519938 1.4986)
			(layers "F.Cu" "F.Mask" "F.Paste")
			(net "M_D_CPU0_SB_DQS_DP<2>")
		)
		(pad "127" smd rect
			(at -2.050034 48.874934 270)
			(size 0.519938 1.4986)
			(layers "F.Cu" "F.Mask" "F.Paste")
			(net "M_D_CPU0_SB_DQS_DN<2>")
		)
		(pad "128" smd rect
			(at -2.050034 49.725072 270)
			(size 0.519938 1.4986)
			(layers "F.Cu" "F.Mask" "F.Paste")
			(net "GND")
		)
		(pad "129" smd rect
			(at -2.050034 50.574956 270)
			(size 0.519938 1.4986)
			(layers "F.Cu" "F.Mask" "F.Paste")
			(net "M_D_CPU0_SB_DQ<20>")
		)
		(pad "130" smd rect
			(at -2.050034 51.425094 270)
			(size 0.519938 1.4986)
			(layers "F.Cu" "F.Mask" "F.Paste")
			(net "GND")
		)
		(pad "131" smd rect
			(at -2.050034 52.274978 270)
			(size 0.519938 1.4986)
			(layers "F.Cu" "F.Mask" "F.Paste")
			(net "M_D_CPU0_SB_DQ<21>")
		)
		(pad "132" smd rect
			(at -2.050034 53.125116 270)
			(size 0.519938 1.4986)
			(layers "F.Cu" "F.Mask" "F.Paste")
			(net "GND")
		)
		(pad "133" smd rect
			(at -2.050034 53.975 270)
			(size 0.519938 1.4986)
			(layers "F.Cu" "F.Mask" "F.Paste")
			(net "M_D_CPU0_SB_DQ<24>")
		)
		(pad "134" smd rect
			(at -2.050034 54.824884 270)
			(size 0.519938 1.4986)
			(layers "F.Cu" "F.Mask" "F.Paste")
			(net "GND")
		)
		(pad "135" smd rect
			(at -2.050034 55.675022 270)
			(size 0.519938 1.4986)
			(layers "F.Cu" "F.Mask" "F.Paste")
			(net "M_D_CPU0_SB_DQ<25>")
		)
		(pad "136" smd rect
			(at -2.050034 56.524906 270)
			(size 0.519938 1.4986)
			(layers "F.Cu" "F.Mask" "F.Paste")
			(net "GND")
		)
		(pad "137" smd rect
			(at -2.050034 57.375044 270)
			(size 0.519938 1.4986)
			(layers "F.Cu" "F.Mask" "F.Paste")
			(net "M_D_CPU0_SB_DQS_DP<3>")
		)
		(pad "138" smd rect
			(at -2.050034 58.224928 270)
			(size 0.519938 1.4986)
			(layers "F.Cu" "F.Mask" "F.Paste")
			(net "M_D_CPU0_SB_DQS_DN<3>")
		)
		(pad "139" smd rect
			(at -2.050034 59.075066 270)
			(size 0.519938 1.4986)
			(layers "F.Cu" "F.Mask" "F.Paste")
			(net "GND")
		)
		(pad "140" smd rect
			(at -2.050034 59.92495 270)
			(size 0.519938 1.4986)
			(layers "F.Cu" "F.Mask" "F.Paste")
			(net "M_D_CPU0_SB_DQ<28>")
		)
		(pad "141" smd rect
			(at -2.050034 60.775088 270)
			(size 0.519938 1.4986)
			(layers "F.Cu" "F.Mask" "F.Paste")
			(net "GND")
		)
		(pad "142" smd rect
			(at -2.050034 61.624972 270)
			(size 0.519938 1.4986)
			(layers "F.Cu" "F.Mask" "F.Paste")
			(net "M_D_CPU0_SB_DQ<29>")
		)
		(pad "143" smd rect
			(at -2.050034 62.47511 270)
			(size 0.519938 1.4986)
			(layers "F.Cu" "F.Mask" "F.Paste")
			(net "GND")
		)
		(pad "144" smd rect
			(at -2.050034 63.324994 270)
			(size 0.519938 1.4986)
			(layers "F.Cu" "F.Mask" "F.Paste")
			(net "TP_CHD_CPU0_DIMM1_FRU_1")
		)
		(pad "145" smd rect
			(at 2.050034 -63.324994 270)
			(size 0.519938 1.4986)
			(layers "F.Cu" "F.Mask" "F.Paste")
			(net "P12V_S3_AUX_CPU0_NVDIMM")
		)
		(pad "146" smd rect
			(at 2.050034 -62.47511 270)
			(size 0.519938 1.4986)
			(layers "F.Cu" "F.Mask" "F.Paste")
			(net "P12V_S3_AUX_CPU0_NVDIMM")
		)
		(pad "147" smd rect
			(at 2.050034 -61.624972 270)
			(size 0.519938 1.4986)
			(layers "F.Cu" "F.Mask" "F.Paste")
			(net "PWRGD_CHD_CPU0_DIMM1")
		)
		(pad "148" smd rect
			(at 2.050034 -60.775088 270)
			(size 0.519938 1.4986)
			(layers "F.Cu" "F.Mask" "F.Paste")
			(net "PD_CHD_CPU0_DIMM1_SAA")
		)
		(pad "149" smd rect
			(at 2.050034 -59.92495 270)
			(size 0.519938 1.4986)
			(layers "F.Cu" "F.Mask" "F.Paste")
			(net "TP_CHD_CPU0_DIMM1_FRU_2")
		)
		(pad "150" smd rect
			(at 2.050034 -59.075066 270)
			(size 0.519938 1.4986)
			(layers "F.Cu" "F.Mask" "F.Paste")
			(net "TP_CHD_CPU0_DIMM1_FRU_3")
		)
		(pad "151" smd rect
			(at 2.050034 -58.224928 270)
			(size 0.519938 1.4986)
			(layers "F.Cu" "F.Mask" "F.Paste")
			(net "GND")
		)
		(pad "152" smd rect
			(at 2.050034 -57.375044 270)
			(size 0.519938 1.4986)
			(layers "F.Cu" "F.Mask" "F.Paste")
			(net "M_D_CPU0_SA_DQ<2>")
		)
		(pad "153" smd rect
			(at 2.050034 -56.524906 270)
			(size 0.519938 1.4986)
			(layers "F.Cu" "F.Mask" "F.Paste")
			(net "GND")
		)
		(pad "154" smd rect
			(at 2.050034 -55.675022 270)
			(size 0.519938 1.4986)
			(layers "F.Cu" "F.Mask" "F.Paste")
			(net "M_D_CPU0_SA_DQ<3>")
		)
		(pad "155" smd rect
			(at 2.050034 -54.824884 270)
			(size 0.519938 1.4986)
			(layers "F.Cu" "F.Mask" "F.Paste")
			(net "GND")
		)
		(pad "156" smd rect
			(at 2.050034 -53.975 270)
			(size 0.519938 1.4986)
			(layers "F.Cu" "F.Mask" "F.Paste")
			(net "M_D_CPU0_SA_DQS_DN<5>")
		)
		(pad "157" smd rect
			(at 2.050034 -53.125116 270)
			(size 0.519938 1.4986)
			(layers "F.Cu" "F.Mask" "F.Paste")
			(net "M_D_CPU0_SA_DQS_DP<5>")
		)
		(pad "158" smd rect
			(at 2.050034 -52.274978 270)
			(size 0.519938 1.4986)
			(layers "F.Cu" "F.Mask" "F.Paste")
			(net "GND")
		)
		(pad "159" smd rect
			(at 2.050034 -51.425094 270)
			(size 0.519938 1.4986)
			(layers "F.Cu" "F.Mask" "F.Paste")
			(net "M_D_CPU0_SA_DQ<6>")
		)
		(pad "160" smd rect
			(at 2.050034 -50.574956 270)
			(size 0.519938 1.4986)
			(layers "F.Cu" "F.Mask" "F.Paste")
			(net "GND")
		)
		(pad "161" smd rect
			(at 2.050034 -49.725072 270)
			(size 0.519938 1.4986)
			(layers "F.Cu" "F.Mask" "F.Paste")
			(net "M_D_CPU0_SA_DQ<7>")
		)
		(pad "162" smd rect
			(at 2.050034 -48.874934 270)
			(size 0.519938 1.4986)
			(layers "F.Cu" "F.Mask" "F.Paste")
			(net "GND")
		)
		(pad "163" smd rect
			(at 2.050034 -48.02505 270)
			(size 0.519938 1.4986)
			(layers "F.Cu" "F.Mask" "F.Paste")
			(net "M_D_CPU0_SA_DQ<10>")
		)
		(pad "164" smd rect
			(at 2.050034 -47.174912 270)
			(size 0.519938 1.4986)
			(layers "F.Cu" "F.Mask" "F.Paste")
			(net "GND")
		)
		(pad "165" smd rect
			(at 2.050034 -46.325028 270)
			(size 0.519938 1.4986)
			(layers "F.Cu" "F.Mask" "F.Paste")
			(net "M_D_CPU0_SA_DQ<11>")
		)
		(pad "166" smd rect
			(at 2.050034 -45.47489 270)
			(size 0.519938 1.4986)
			(layers "F.Cu" "F.Mask" "F.Paste")
			(net "GND")
		)
		(pad "167" smd rect
			(at 2.050034 -44.625006 270)
			(size 0.519938 1.4986)
			(layers "F.Cu" "F.Mask" "F.Paste")
			(net "M_D_CPU0_SA_DQS_DN<6>")
		)
		(pad "168" smd rect
			(at 2.050034 -43.775122 270)
			(size 0.519938 1.4986)
			(layers "F.Cu" "F.Mask" "F.Paste")
			(net "M_D_CPU0_SA_DQS_DP<6>")
		)
		(pad "169" smd rect
			(at 2.050034 -42.924984 270)
			(size 0.519938 1.4986)
			(layers "F.Cu" "F.Mask" "F.Paste")
			(net "GND")
		)
		(pad "170" smd rect
			(at 2.050034 -42.0751 270)
			(size 0.519938 1.4986)
			(layers "F.Cu" "F.Mask" "F.Paste")
			(net "M_D_CPU0_SA_DQ<14>")
		)
		(pad "171" smd rect
			(at 2.050034 -41.224962 270)
			(size 0.519938 1.4986)
			(layers "F.Cu" "F.Mask" "F.Paste")
			(net "GND")
		)
		(pad "172" smd rect
			(at 2.050034 -40.375078 270)
			(size 0.519938 1.4986)
			(layers "F.Cu" "F.Mask" "F.Paste")
			(net "M_D_CPU0_SA_DQ<15>")
		)
		(pad "173" smd rect
			(at 2.050034 -39.52494 270)
			(size 0.519938 1.4986)
			(layers "F.Cu" "F.Mask" "F.Paste")
			(net "GND")
		)
		(pad "174" smd rect
			(at 2.050034 -38.675056 270)
			(size 0.519938 1.4986)
			(layers "F.Cu" "F.Mask" "F.Paste")
			(net "M_D_CPU0_SA_DQ<18>")
		)
		(pad "175" smd rect
			(at 2.050034 -37.824918 270)
			(size 0.519938 1.4986)
			(layers "F.Cu" "F.Mask" "F.Paste")
			(net "GND")
		)
		(pad "176" smd rect
			(at 2.050034 -36.975034 270)
			(size 0.519938 1.4986)
			(layers "F.Cu" "F.Mask" "F.Paste")
			(net "M_D_CPU0_SA_DQ<19>")
		)
		(pad "177" smd rect
			(at 2.050034 -36.124896 270)
			(size 0.519938 1.4986)
			(layers "F.Cu" "F.Mask" "F.Paste")
			(net "GND")
		)
		(pad "178" smd rect
			(at 2.050034 -35.275012 270)
			(size 0.519938 1.4986)
			(layers "F.Cu" "F.Mask" "F.Paste")
			(net "M_D_CPU0_SA_DQS_DN<7>")
		)
		(pad "179" smd rect
			(at 2.050034 -34.425128 270)
			(size 0.519938 1.4986)
			(layers "F.Cu" "F.Mask" "F.Paste")
			(net "M_D_CPU0_SA_DQS_DP<7>")
		)
		(pad "180" smd rect
			(at 2.050034 -33.57499 270)
			(size 0.519938 1.4986)
			(layers "F.Cu" "F.Mask" "F.Paste")
			(net "GND")
		)
		(pad "181" smd rect
			(at 2.050034 -32.725106 270)
			(size 0.519938 1.4986)
			(layers "F.Cu" "F.Mask" "F.Paste")
			(net "M_D_CPU0_SA_DQ<22>")
		)
		(pad "182" smd rect
			(at 2.050034 -31.874968 270)
			(size 0.519938 1.4986)
			(layers "F.Cu" "F.Mask" "F.Paste")
			(net "GND")
		)
		(pad "183" smd rect
			(at 2.050034 -31.025084 270)
			(size 0.519938 1.4986)
			(layers "F.Cu" "F.Mask" "F.Paste")
			(net "M_D_CPU0_SA_DQ<23>")
		)
		(pad "184" smd rect
			(at 2.050034 -30.174946 270)
			(size 0.519938 1.4986)
			(layers "F.Cu" "F.Mask" "F.Paste")
			(net "GND")
		)
		(pad "185" smd rect
			(at 2.050034 -29.325062 270)
			(size 0.519938 1.4986)
			(layers "F.Cu" "F.Mask" "F.Paste")
			(net "M_D_CPU0_SA_DQ<26>")
		)
		(pad "186" smd rect
			(at 2.050034 -28.474924 270)
			(size 0.519938 1.4986)
			(layers "F.Cu" "F.Mask" "F.Paste")
			(net "GND")
		)
		(pad "187" smd rect
			(at 2.050034 -27.62504 270)
			(size 0.519938 1.4986)
			(layers "F.Cu" "F.Mask" "F.Paste")
			(net "M_D_CPU0_SA_DQ<27>")
		)
		(pad "188" smd rect
			(at 2.050034 -26.774902 270)
			(size 0.519938 1.4986)
			(layers "F.Cu" "F.Mask" "F.Paste")
			(net "GND")
		)
		(pad "189" smd rect
			(at 2.050034 -25.925018 270)
			(size 0.519938 1.4986)
			(layers "F.Cu" "F.Mask" "F.Paste")
			(net "M_D_CPU0_SA_DQS_DN<8>")
		)
		(pad "190" smd rect
			(at 2.050034 -25.07488 270)
			(size 0.519938 1.4986)
			(layers "F.Cu" "F.Mask" "F.Paste")
			(net "M_D_CPU0_SA_DQS_DP<8>")
		)
		(pad "191" smd rect
			(at 2.050034 -24.224996 270)
			(size 0.519938 1.4986)
			(layers "F.Cu" "F.Mask" "F.Paste")
			(net "GND")
		)
		(pad "192" smd rect
			(at 2.050034 -23.375112 270)
			(size 0.519938 1.4986)
			(layers "F.Cu" "F.Mask" "F.Paste")
			(net "M_D_CPU0_SA_DQ<30>")
		)
		(pad "193" smd rect
			(at 2.050034 -22.524974 270)
			(size 0.519938 1.4986)
			(layers "F.Cu" "F.Mask" "F.Paste")
			(net "GND")
		)
		(pad "194" smd rect
			(at 2.050034 -21.67509 270)
			(size 0.519938 1.4986)
			(layers "F.Cu" "F.Mask" "F.Paste")
			(net "M_D_CPU0_SA_DQ<31>")
		)
		(pad "195" smd rect
			(at 2.050034 -20.824952 270)
			(size 0.519938 1.4986)
			(layers "F.Cu" "F.Mask" "F.Paste")
			(net "GND")
		)
		(pad "196" smd rect
			(at 2.050034 -19.975068 270)
			(size 0.519938 1.4986)
			(layers "F.Cu" "F.Mask" "F.Paste")
			(net "M_D_CPU0_SA_CB<2>")
		)
		(pad "197" smd rect
			(at 2.050034 -19.12493 270)
			(size 0.519938 1.4986)
			(layers "F.Cu" "F.Mask" "F.Paste")
			(net "GND")
		)
		(pad "198" smd rect
			(at 2.050034 -18.275046 270)
			(size 0.519938 1.4986)
			(layers "F.Cu" "F.Mask" "F.Paste")
			(net "M_D_CPU0_SA_CB<3>")
		)
		(pad "199" smd rect
			(at 2.050034 -17.424908 270)
			(size 0.519938 1.4986)
			(layers "F.Cu" "F.Mask" "F.Paste")
			(net "GND")
		)
		(pad "200" smd rect
			(at 2.050034 -16.575024 270)
			(size 0.519938 1.4986)
			(layers "F.Cu" "F.Mask" "F.Paste")
			(net "M_D_CPU0_SA_DQS_DN<9>")
		)
		(pad "201" smd rect
			(at 2.050034 -15.724886 270)
			(size 0.519938 1.4986)
			(layers "F.Cu" "F.Mask" "F.Paste")
			(net "M_D_CPU0_SA_DQS_DP<9>")
		)
		(pad "202" smd rect
			(at 2.050034 -14.875002 270)
			(size 0.519938 1.4986)
			(layers "F.Cu" "F.Mask" "F.Paste")
			(net "GND")
		)
		(pad "203" smd rect
			(at 2.050034 -14.025118 270)
			(size 0.519938 1.4986)
			(layers "F.Cu" "F.Mask" "F.Paste")
			(net "M_D_CPU0_SA_CB<6>")
		)
		(pad "204" smd rect
			(at 2.050034 -13.17498 270)
			(size 0.519938 1.4986)
			(layers "F.Cu" "F.Mask" "F.Paste")
			(net "GND")
		)
		(pad "205" smd rect
			(at 2.050034 -12.325096 270)
			(size 0.519938 1.4986)
			(layers "F.Cu" "F.Mask" "F.Paste")
			(net "M_D_CPU0_SA_CB<7>")
		)
		(pad "206" smd rect
			(at 2.050034 -11.474958 270)
			(size 0.519938 1.4986)
			(layers "F.Cu" "F.Mask" "F.Paste")
			(net "GND")
		)
		(pad "207" smd rect
			(at 2.050034 -10.625074 270)
			(size 0.519938 1.4986)
			(layers "F.Cu" "F.Mask" "F.Paste")
			(net "RST_M_CD_CPU0_FPGA_N")
		)
		(pad "208" smd rect
			(at 2.050034 -9.774936 270)
			(size 0.519938 1.4986)
			(layers "F.Cu" "F.Mask" "F.Paste")
			(net "GND")
		)
		(pad "209" smd rect
			(at 2.050034 -8.925052 270)
			(size 0.519938 1.4986)
			(layers "F.Cu" "F.Mask" "F.Paste")
			(net "M_D_CPU0_SA_CS_N<1>")
		)
		(pad "210" smd rect
			(at 2.050034 -8.074914 270)
			(size 0.519938 1.4986)
			(layers "F.Cu" "F.Mask" "F.Paste")
			(net "GND")
		)
		(pad "211" smd rect
			(at 2.050034 -7.22503 270)
			(size 0.519938 1.4986)
			(layers "F.Cu" "F.Mask" "F.Paste")
			(net "M_D_CPU0_SA_CA<1>")
		)
		(pad "212" smd rect
			(at 2.050034 -6.374892 270)
			(size 0.519938 1.4986)
			(layers "F.Cu" "F.Mask" "F.Paste")
			(net "GND")
		)
		(pad "213" smd rect
			(at 2.050034 -5.525008 270)
			(size 0.519938 1.4986)
			(layers "F.Cu" "F.Mask" "F.Paste")
			(net "M_D_CPU0_SA_CA<3>")
		)
		(pad "214" smd rect
			(at 2.050034 -4.675124 270)
			(size 0.519938 1.4986)
			(layers "F.Cu" "F.Mask" "F.Paste")
			(net "GND")
		)
		(pad "215" smd rect
			(at 2.050034 -3.824986 270)
			(size 0.519938 1.4986)
			(layers "F.Cu" "F.Mask" "F.Paste")
			(net "M_D_CPU0_SA_CA<5>")
		)
		(pad "216" smd rect
			(at 2.050034 -2.975102 270)
			(size 0.519938 1.4986)
			(layers "F.Cu" "F.Mask" "F.Paste")
			(net "GND")
		)
		(pad "217" smd rect
			(at 2.050034 -2.124964 270)
			(size 0.519938 1.4986)
			(layers "F.Cu" "F.Mask" "F.Paste")
			(net "M_D_CPU0_CLK_DP<0>")
		)
		(pad "218" smd rect
			(at 2.050034 -1.27508 270)
			(size 0.519938 1.4986)
			(layers "F.Cu" "F.Mask" "F.Paste")
			(net "M_D_CPU0_CLK_DN<0>")
		)
		(pad "219" smd rect
			(at 2.050034 -0.424942 270)
			(size 0.519938 1.4986)
			(layers "F.Cu" "F.Mask" "F.Paste")
			(net "GND")
		)
		(pad "220" smd rect
			(at 2.050034 5.525008 270)
			(size 0.519938 1.4986)
			(layers "F.Cu" "F.Mask" "F.Paste")
			(net "TP_CHD_CPU0_DIMM1_FRU_4")
		)
		(pad "221" smd rect
			(at 2.050034 6.374892 270)
			(size 0.519938 1.4986)
			(layers "F.Cu" "F.Mask" "F.Paste")
			(net "M_D_CPU0_SB_CA<1>")
		)
		(pad "222" smd rect
			(at 2.050034 7.22503 270)
			(size 0.519938 1.4986)
			(layers "F.Cu" "F.Mask" "F.Paste")
			(net "GND")
		)
		(pad "223" smd rect
			(at 2.050034 8.074914 270)
			(size 0.519938 1.4986)
			(layers "F.Cu" "F.Mask" "F.Paste")
			(net "M_D_CPU0_SB_CA<3>")
		)
		(pad "224" smd rect
			(at 2.050034 8.925052 270)
			(size 0.519938 1.4986)
			(layers "F.Cu" "F.Mask" "F.Paste")
			(net "GND")
		)
		(pad "225" smd rect
			(at 2.050034 9.774936 270)
			(size 0.519938 1.4986)
			(layers "F.Cu" "F.Mask" "F.Paste")
			(net "M_D_CPU0_SB_CA<5>")
		)
		(pad "226" smd rect
			(at 2.050034 10.625074 270)
			(size 0.519938 1.4986)
			(layers "F.Cu" "F.Mask" "F.Paste")
			(net "GND")
		)
		(pad "227" smd rect
			(at 2.050034 11.474958 270)
			(size 0.519938 1.4986)
			(layers "F.Cu" "F.Mask" "F.Paste")
			(net "M_D_CPU0_SB_PAR")
		)
		(pad "228" smd rect
			(at 2.050034 12.325096 270)
			(size 0.519938 1.4986)
			(layers "F.Cu" "F.Mask" "F.Paste")
			(net "GND")
		)
		(pad "229" smd rect
			(at 2.050034 13.17498 270)
			(size 0.519938 1.4986)
			(layers "F.Cu" "F.Mask" "F.Paste")
			(net "M_D_CPU0_SB_CS_N<1>")
		)
		(pad "230" smd rect
			(at 2.050034 14.025118 270)
			(size 0.519938 1.4986)
			(layers "F.Cu" "F.Mask" "F.Paste")
			(net "GND")
		)
		(pad "231" smd rect
			(at 2.050034 14.875002 270)
			(size 0.519938 1.4986)
			(layers "F.Cu" "F.Mask" "F.Paste")
			(net "TP_CHD_CPU0_DIMM1_FRU_5")
		)
		(pad "232" smd rect
			(at 2.050034 15.724886 270)
			(size 0.519938 1.4986)
			(layers "F.Cu" "F.Mask" "F.Paste")
			(net "TP_CHD_CPU0_DIMM1_FRU_6")
		)
		(pad "233" smd rect
			(at 2.050034 16.575024 270)
			(size 0.519938 1.4986)
			(layers "F.Cu" "F.Mask" "F.Paste")
			(net "GND")
		)
		(pad "234" smd rect
			(at 2.050034 17.424908 270)
			(size 0.519938 1.4986)
			(layers "F.Cu" "F.Mask" "F.Paste")
			(net "M_D_CPU0_SB_CB<6>")
		)
		(pad "235" smd rect
			(at 2.050034 18.275046 270)
			(size 0.519938 1.4986)
			(layers "F.Cu" "F.Mask" "F.Paste")
			(net "GND")
		)
		(pad "236" smd rect
			(at 2.050034 19.12493 270)
			(size 0.519938 1.4986)
			(layers "F.Cu" "F.Mask" "F.Paste")
			(net "M_D_CPU0_SB_CB<7>")
		)
		(pad "237" smd rect
			(at 2.050034 19.975068 270)
			(size 0.519938 1.4986)
			(layers "F.Cu" "F.Mask" "F.Paste")
			(net "GND")
		)
		(pad "238" smd rect
			(at 2.050034 20.824952 270)
			(size 0.519938 1.4986)
			(layers "F.Cu" "F.Mask" "F.Paste")
			(net "M_D_CPU0_SB_DQS_DN<4>")
		)
		(pad "239" smd rect
			(at 2.050034 21.67509 270)
			(size 0.519938 1.4986)
			(layers "F.Cu" "F.Mask" "F.Paste")
			(net "M_D_CPU0_SB_DQS_DP<4>")
		)
		(pad "240" smd rect
			(at 2.050034 22.524974 270)
			(size 0.519938 1.4986)
			(layers "F.Cu" "F.Mask" "F.Paste")
			(net "GND")
		)
		(pad "241" smd rect
			(at 2.050034 23.375112 270)
			(size 0.519938 1.4986)
			(layers "F.Cu" "F.Mask" "F.Paste")
			(net "M_D_CPU0_SB_CB<2>")
		)
		(pad "242" smd rect
			(at 2.050034 24.224996 270)
			(size 0.519938 1.4986)
			(layers "F.Cu" "F.Mask" "F.Paste")
			(net "GND")
		)
		(pad "243" smd rect
			(at 2.050034 25.07488 270)
			(size 0.519938 1.4986)
			(layers "F.Cu" "F.Mask" "F.Paste")
			(net "M_D_CPU0_SB_CB<3>")
		)
		(pad "244" smd rect
			(at 2.050034 25.925018 270)
			(size 0.519938 1.4986)
			(layers "F.Cu" "F.Mask" "F.Paste")
			(net "GND")
		)
		(pad "245" smd rect
			(at 2.050034 26.774902 270)
			(size 0.519938 1.4986)
			(layers "F.Cu" "F.Mask" "F.Paste")
			(net "M_D_CPU0_SB_DQ<2>")
		)
		(pad "246" smd rect
			(at 2.050034 27.62504 270)
			(size 0.519938 1.4986)
			(layers "F.Cu" "F.Mask" "F.Paste")
			(net "GND")
		)
		(pad "247" smd rect
			(at 2.050034 28.474924 270)
			(size 0.519938 1.4986)
			(layers "F.Cu" "F.Mask" "F.Paste")
			(net "M_D_CPU0_SB_DQ<3>")
		)
		(pad "248" smd rect
			(at 2.050034 29.325062 270)
			(size 0.519938 1.4986)
			(layers "F.Cu" "F.Mask" "F.Paste")
			(net "GND")
		)
		(pad "249" smd rect
			(at 2.050034 30.174946 270)
			(size 0.519938 1.4986)
			(layers "F.Cu" "F.Mask" "F.Paste")
			(net "M_D_CPU0_SB_DQS_DN<5>")
		)
		(pad "250" smd rect
			(at 2.050034 31.025084 270)
			(size 0.519938 1.4986)
			(layers "F.Cu" "F.Mask" "F.Paste")
			(net "M_D_CPU0_SB_DQS_DP<5>")
		)
		(pad "251" smd rect
			(at 2.050034 31.874968 270)
			(size 0.519938 1.4986)
			(layers "F.Cu" "F.Mask" "F.Paste")
			(net "GND")
		)
		(pad "252" smd rect
			(at 2.050034 32.725106 270)
			(size 0.519938 1.4986)
			(layers "F.Cu" "F.Mask" "F.Paste")
			(net "M_D_CPU0_SB_DQ<6>")
		)
		(pad "253" smd rect
			(at 2.050034 33.57499 270)
			(size 0.519938 1.4986)
			(layers "F.Cu" "F.Mask" "F.Paste")
			(net "GND")
		)
		(pad "254" smd rect
			(at 2.050034 34.425128 270)
			(size 0.519938 1.4986)
			(layers "F.Cu" "F.Mask" "F.Paste")
			(net "M_D_CPU0_SB_DQ<7>")
		)
		(pad "255" smd rect
			(at 2.050034 35.275012 270)
			(size 0.519938 1.4986)
			(layers "F.Cu" "F.Mask" "F.Paste")
			(net "GND")
		)
		(pad "256" smd rect
			(at 2.050034 36.124896 270)
			(size 0.519938 1.4986)
			(layers "F.Cu" "F.Mask" "F.Paste")
			(net "M_D_CPU0_SB_DQ<10>")
		)
		(pad "257" smd rect
			(at 2.050034 36.975034 270)
			(size 0.519938 1.4986)
			(layers "F.Cu" "F.Mask" "F.Paste")
			(net "GND")
		)
		(pad "258" smd rect
			(at 2.050034 37.824918 270)
			(size 0.519938 1.4986)
			(layers "F.Cu" "F.Mask" "F.Paste")
			(net "M_D_CPU0_SB_DQ<11>")
		)
		(pad "259" smd rect
			(at 2.050034 38.675056 270)
			(size 0.519938 1.4986)
			(layers "F.Cu" "F.Mask" "F.Paste")
			(net "GND")
		)
		(pad "260" smd rect
			(at 2.050034 39.52494 270)
			(size 0.519938 1.4986)
			(layers "F.Cu" "F.Mask" "F.Paste")
			(net "M_D_CPU0_SB_DQS_DN<6>")
		)
		(pad "261" smd rect
			(at 2.050034 40.375078 270)
			(size 0.519938 1.4986)
			(layers "F.Cu" "F.Mask" "F.Paste")
			(net "M_D_CPU0_SB_DQS_DP<6>")
		)
		(pad "262" smd rect
			(at 2.050034 41.224962 270)
			(size 0.519938 1.4986)
			(layers "F.Cu" "F.Mask" "F.Paste")
			(net "GND")
		)
		(pad "263" smd rect
			(at 2.050034 42.0751 270)
			(size 0.519938 1.4986)
			(layers "F.Cu" "F.Mask" "F.Paste")
			(net "M_D_CPU0_SB_DQ<14>")
		)
		(pad "264" smd rect
			(at 2.050034 42.924984 270)
			(size 0.519938 1.4986)
			(layers "F.Cu" "F.Mask" "F.Paste")
			(net "GND")
		)
		(pad "265" smd rect
			(at 2.050034 43.775122 270)
			(size 0.519938 1.4986)
			(layers "F.Cu" "F.Mask" "F.Paste")
			(net "M_D_CPU0_SB_DQ<15>")
		)
		(pad "266" smd rect
			(at 2.050034 44.625006 270)
			(size 0.519938 1.4986)
			(layers "F.Cu" "F.Mask" "F.Paste")
			(net "GND")
		)
		(pad "267" smd rect
			(at 2.050034 45.47489 270)
			(size 0.519938 1.4986)
			(layers "F.Cu" "F.Mask" "F.Paste")
			(net "M_D_CPU0_SB_DQ<18>")
		)
		(pad "268" smd rect
			(at 2.050034 46.325028 270)
			(size 0.519938 1.4986)
			(layers "F.Cu" "F.Mask" "F.Paste")
			(net "GND")
		)
		(pad "269" smd rect
			(at 2.050034 47.174912 270)
			(size 0.519938 1.4986)
			(layers "F.Cu" "F.Mask" "F.Paste")
			(net "M_D_CPU0_SB_DQ<19>")
		)
		(pad "270" smd rect
			(at 2.050034 48.02505 270)
			(size 0.519938 1.4986)
			(layers "F.Cu" "F.Mask" "F.Paste")
			(net "GND")
		)
		(pad "271" smd rect
			(at 2.050034 48.874934 270)
			(size 0.519938 1.4986)
			(layers "F.Cu" "F.Mask" "F.Paste")
			(net "M_D_CPU0_SB_DQS_DN<7>")
		)
		(pad "272" smd rect
			(at 2.050034 49.725072 270)
			(size 0.519938 1.4986)
			(layers "F.Cu" "F.Mask" "F.Paste")
			(net "M_D_CPU0_SB_DQS_DP<7>")
		)
		(pad "273" smd rect
			(at 2.050034 50.574956 270)
			(size 0.519938 1.4986)
			(layers "F.Cu" "F.Mask" "F.Paste")
			(net "GND")
		)
		(pad "274" smd rect
			(at 2.050034 51.425094 270)
			(size 0.519938 1.4986)
			(layers "F.Cu" "F.Mask" "F.Paste")
			(net "M_D_CPU0_SB_DQ<22>")
		)
		(pad "275" smd rect
			(at 2.050034 52.274978 270)
			(size 0.519938 1.4986)
			(layers "F.Cu" "F.Mask" "F.Paste")
			(net "GND")
		)
		(pad "276" smd rect
			(at 2.050034 53.125116 270)
			(size 0.519938 1.4986)
			(layers "F.Cu" "F.Mask" "F.Paste")
			(net "M_D_CPU0_SB_DQ<23>")
		)
		(pad "277" smd rect
			(at 2.050034 53.975 270)
			(size 0.519938 1.4986)
			(layers "F.Cu" "F.Mask" "F.Paste")
			(net "GND")
		)
		(pad "278" smd rect
			(at 2.050034 54.824884 270)
			(size 0.519938 1.4986)
			(layers "F.Cu" "F.Mask" "F.Paste")
			(net "M_D_CPU0_SB_DQ<26>")
		)
		(pad "279" smd rect
			(at 2.050034 55.675022 270)
			(size 0.519938 1.4986)
			(layers "F.Cu" "F.Mask" "F.Paste")
			(net "GND")
		)
		(pad "280" smd rect
			(at 2.050034 56.524906 270)
			(size 0.519938 1.4986)
			(layers "F.Cu" "F.Mask" "F.Paste")
			(net "M_D_CPU0_SB_DQ<27>")
		)
		(pad "281" smd rect
			(at 2.050034 57.375044 270)
			(size 0.519938 1.4986)
			(layers "F.Cu" "F.Mask" "F.Paste")
			(net "GND")
		)
		(pad "282" smd rect
			(at 2.050034 58.224928 270)
			(size 0.519938 1.4986)
			(layers "F.Cu" "F.Mask" "F.Paste")
			(net "M_D_CPU0_SB_DQS_DN<8>")
		)
		(pad "283" smd rect
			(at 2.050034 59.075066 270)
			(size 0.519938 1.4986)
			(layers "F.Cu" "F.Mask" "F.Paste")
			(net "M_D_CPU0_SB_DQS_DP<8>")
		)
		(pad "284" smd rect
			(at 2.050034 59.92495 270)
			(size 0.519938 1.4986)
			(layers "F.Cu" "F.Mask" "F.Paste")
			(net "GND")
		)
		(pad "285" smd rect
			(at 2.050034 60.775088 270)
			(size 0.519938 1.4986)
			(layers "F.Cu" "F.Mask" "F.Paste")
			(net "M_D_CPU0_SB_DQ<30>")
		)
		(pad "286" smd rect
			(at 2.050034 61.624972 270)
			(size 0.519938 1.4986)
			(layers "F.Cu" "F.Mask" "F.Paste")
			(net "GND")
		)
		(pad "287" smd rect
			(at 2.050034 62.47511 270)
			(size 0.519938 1.4986)
			(layers "F.Cu" "F.Mask" "F.Paste")
			(net "M_D_CPU0_SB_DQ<31>")
		)
		(pad "288" smd rect
			(at 2.050034 63.324994 270)
			(size 0.519938 1.4986)
			(layers "F.Cu" "F.Mask" "F.Paste")
			(net "GND")
		)
		(pad "G1" thru_hole oval
			(at 0 -68.97497)
			(size 2.8194 1.5748)
			(drill oval 2.4384 1.1938)
			(layers "*.Cu" "*.Mask")
			(remove_unused_layers no)
			(net "GND")
			(clearance 0.127)
			(thermal_gap 0.127)
		)
		(pad "G2" thru_hole oval
			(at 0 3.875024)
			(size 2.8194 1.5748)
			(drill oval 2.4384 1.1938)
			(layers "*.Cu" "*.Mask")
			(remove_unused_layers no)
			(net "GND")
			(clearance 0.127)
			(thermal_gap 0.127)
		)
		(pad "G3" thru_hole oval
			(at 0 68.97497)
			(size 2.8194 1.5748)
			(drill oval 2.4384 1.1938)
			(layers "*.Cu" "*.Mask")
			(remove_unused_layers no)
			(net "GND")
			(clearance 0.127)
			(thermal_gap 0.127)
		)
	)
	(footprint ""
		(layer "F.Cu")
		(at 204.93736 -119.344948)
		(property "Reference" "R4175"
			(at 0 0 0)
			(layer "F.SilkS")
			(hide yes)
			(effects
				(font
					(size 1.27 1.27)
				)
			)
		)
		(property "Value" ""
			(at 0 0 0)
			(layer "F.Fab")
			(effects
				(font
					(size 1.27 1.27)
				)
			)
		)
		(duplicate_pad_numbers_are_jumpers no)
		(fp_line
			(start -0.7874 -0.4064)
			(end 0.7874 -0.4064)
			(stroke
				(width 0.1524)
				(type default)
			)
			(layer "F.SilkS")
		)
		(fp_line
			(start -0.7874 0.4064)
			(end -0.7874 -0.4064)
			(stroke
				(width 0.1524)
				(type default)
			)
			(layer "F.SilkS")
		)
		(fp_line
			(start 0.7874 -0.4064)
			(end 0.7874 0.4064)
			(stroke
				(width 0.1524)
				(type default)
			)
			(layer "F.SilkS")
		)
		(fp_line
			(start 0.7874 0.4064)
			(end -0.7874 0.4064)
			(stroke
				(width 0.1524)
				(type default)
			)
			(layer "F.SilkS")
		)
		(fp_line
			(start -0.67945 -0.305054)
			(end -0.12065 -0.305054)
			(stroke
				(width 0.1)
				(type default)
			)
			(layer "F.Fab")
		)
		(fp_line
			(start -0.67945 0.3048)
			(end -0.67945 -0.305054)
			(stroke
				(width 0.1)
				(type default)
			)
			(layer "F.Fab")
		)
		(fp_line
			(start -0.12065 -0.305054)
			(end -0.12065 -0.2794)
			(stroke
				(width 0.1)
				(type default)
			)
			(layer "F.Fab")
		)
		(fp_line
			(start -0.12065 -0.2794)
			(end 0.12065 -0.2794)
			(stroke
				(width 0.1)
				(type default)
			)
			(layer "F.Fab")
		)
		(fp_line
			(start -0.12065 0.2794)
			(end -0.12065 0.3048)
			(stroke
				(width 0.1)
				(type default)
			)
			(layer "F.Fab")
		)
		(fp_line
			(start -0.12065 0.3048)
			(end -0.67945 0.3048)
			(stroke
				(width 0.1)
				(type default)
			)
			(layer "F.Fab")
		)
		(fp_line
			(start 0.120396 0.2794)
			(end -0.12065 0.2794)
			(stroke
				(width 0.1)
				(type default)
			)
			(layer "F.Fab")
		)
		(fp_line
			(start 0.120396 0.3048)
			(end 0.120396 0.2794)
			(stroke
				(width 0.1)
				(type default)
			)
			(layer "F.Fab")
		)
		(fp_line
			(start 0.12065 -0.3048)
			(end 0.67945 -0.3048)
			(stroke
				(width 0.1)
				(type default)
			)
			(layer "F.Fab")
		)
		(fp_line
			(start 0.12065 -0.2794)
			(end 0.12065 -0.3048)
			(stroke
				(width 0.1)
				(type default)
			)
			(layer "F.Fab")
		)
		(fp_line
			(start 0.67945 -0.3048)
			(end 0.67945 0.3048)
			(stroke
				(width 0.1)
				(type default)
			)
			(layer "F.Fab")
		)
		(fp_line
			(start 0.67945 0.3048)
			(end 0.120396 0.3048)
			(stroke
				(width 0.1)
				(type default)
			)
			(layer "F.Fab")
		)
		(pad "1" smd circle
			(at -0.40005 0)
			(size 0 0)
			(layers "F.Cu" "F.Mask" "F.Paste")
			(net "RST_PCIE_PCH_DEV_PERST_N")
		)
		(pad "2" smd circle
			(at 0.40005 0)
			(size 0 0)
			(layers "F.Cu" "F.Mask" "F.Paste")
			(net "RST_PCIE_PCH_DEV_PERST_M2_R_N")
		)
	)
	(footprint ""
		(layer "F.Cu")
		(at 17.737582 -428.024036 90)
		(property "Reference" "R3443"
			(at 0 0 90)
			(layer "F.SilkS")
			(hide yes)
			(effects
				(font
					(size 1.27 1.27)
				)
			)
		)
		(property "Value" ""
			(at 0 0 90)
			(layer "F.Fab")
			(effects
				(font
					(size 1.27 1.27)
				)
			)
		)
		(duplicate_pad_numbers_are_jumpers no)
		(fp_line
			(start 0.7874 -0.4064)
			(end 0.7874 0.4064)
			(stroke
				(width 0.1524)
				(type default)
			)
			(layer "F.SilkS")
		)
		(fp_line
			(start -0.7874 -0.4064)
			(end 0.7874 -0.4064)
			(stroke
				(width 0.1524)
				(type default)
			)
			(layer "F.SilkS")
		)
		(fp_line
			(start 0.7874 0.4064)
			(end -0.7874 0.4064)
			(stroke
				(width 0.1524)
				(type default)
			)
			(layer "F.SilkS")
		)
		(fp_line
			(start -0.7874 0.4064)
			(end -0.7874 -0.4064)
			(stroke
				(width 0.1524)
				(type default)
			)
			(layer "F.SilkS")
		)
		(fp_line
			(start -0.12065 -0.305054)
			(end -0.12065 -0.2794)
			(stroke
				(width 0.1)
				(type default)
			)
			(layer "F.Fab")
		)
		(fp_line
			(start -0.67945 -0.305054)
			(end -0.12065 -0.305054)
			(stroke
				(width 0.1)
				(type default)
			)
			(layer "F.Fab")
		)
		(fp_line
			(start 0.67945 -0.3048)
			(end 0.67945 0.3048)
			(stroke
				(width 0.1)
				(type default)
			)
			(layer "F.Fab")
		)
		(fp_line
			(start 0.12065 -0.3048)
			(end 0.67945 -0.3048)
			(stroke
				(width 0.1)
				(type default)
			)
			(layer "F.Fab")
		)
		(fp_line
			(start 0.12065 -0.2794)
			(end 0.12065 -0.3048)
			(stroke
				(width 0.1)
				(type default)
			)
			(layer "F.Fab")
		)
		(fp_line
			(start -0.12065 -0.2794)
			(end 0.12065 -0.2794)
			(stroke
				(width 0.1)
				(type default)
			)
			(layer "F.Fab")
		)
		(fp_line
			(start 0.120396 0.2794)
			(end -0.12065 0.2794)
			(stroke
				(width 0.1)
				(type default)
			)
			(layer "F.Fab")
		)
		(fp_line
			(start -0.12065 0.2794)
			(end -0.12065 0.3048)
			(stroke
				(width 0.1)
				(type default)
			)
			(layer "F.Fab")
		)
		(fp_line
			(start 0.67945 0.3048)
			(end 0.120396 0.3048)
			(stroke
				(width 0.1)
				(type default)
			)
			(layer "F.Fab")
		)
		(fp_line
			(start 0.120396 0.3048)
			(end 0.120396 0.2794)
			(stroke
				(width 0.1)
				(type default)
			)
			(layer "F.Fab")
		)
		(fp_line
			(start -0.12065 0.3048)
			(end -0.67945 0.3048)
			(stroke
				(width 0.1)
				(type default)
			)
			(layer "F.Fab")
		)
		(fp_line
			(start -0.67945 0.3048)
			(end -0.67945 -0.305054)
			(stroke
				(width 0.1)
				(type default)
			)
			(layer "F.Fab")
		)
		(pad "1" smd circle
			(at -0.40005 0 90)
			(size 0 0)
			(layers "F.Cu" "F.Mask" "F.Paste")
			(net "GPU_PEX_STRAP1")
		)
		(pad "2" smd circle
			(at 0.40005 0 90)
			(size 0 0)
			(layers "F.Cu" "F.Mask" "F.Paste")
			(net "GND")
		)
	)
	(footprint ""
		(layer "F.Cu")
		(at 450.558154 -110.183422 180)
		(property "Reference" "U49"
			(at 1.041908 -2.61874 0)
			(unlocked yes)
			(layer "F.SilkS")
			(effects
				(font
					(size 0.7874 0.5842)
					(thickness 0.1524)
				)
			)
		)
		(property "Value" ""
			(at 0 0 180)
			(layer "F.Fab")
			(effects
				(font
					(size 1.27 1.27)
				)
			)
		)
		(duplicate_pad_numbers_are_jumpers no)
		(fp_line
			(start 1.949958 1.610106)
			(end -1.949958 1.610106)
			(stroke
				(width 0.1524)
				(type default)
			)
			(layer "F.SilkS")
		)
		(fp_line
			(start 1.949958 -1.560068)
			(end 1.949958 1.610106)
			(stroke
				(width 0.1524)
				(type default)
			)
			(layer "F.SilkS")
		)
		(fp_line
			(start -1.949958 1.610106)
			(end -1.949958 -1.610106)
			(stroke
				(width 0.1524)
				(type default)
			)
			(layer "F.SilkS")
		)
		(fp_line
			(start -1.949958 -1.610106)
			(end 1.949958 -1.610106)
			(stroke
				(width 0.1524)
				(type default)
			)
			(layer "F.SilkS")
		)
		(fp_line
			(start 0.750062 1.560068)
			(end -0.750062 1.560068)
			(stroke
				(width 0.1)
				(type default)
			)
			(layer "F.Fab")
		)
		(fp_line
			(start 0.750062 -1.560068)
			(end 0.750062 1.560068)
			(stroke
				(width 0.1)
				(type default)
			)
			(layer "F.Fab")
		)
		(fp_line
			(start -0.750062 1.560068)
			(end -0.750062 -1.560068)
			(stroke
				(width 0.1)
				(type default)
			)
			(layer "F.Fab")
		)
		(fp_line
			(start -0.750062 -1.560068)
			(end 0.750062 -1.560068)
			(stroke
				(width 0.1)
				(type default)
			)
			(layer "F.Fab")
		)
		(pad "D" smd rect
			(at 1.100074 0 90)
			(size 1.016 1.4224)
			(layers "F.Cu" "F.Mask" "F.Paste")
			(net "HP_LVC3_OCP_V3_1_PRSNT2")
		)
		(pad "G" smd rect
			(at -1.100074 -0.94996 90)
			(size 1.016 1.4224)
			(layers "F.Cu" "F.Mask" "F.Paste")
			(net "HP_LVC3_OCP_V3_1_PRSNT2_N")
		)
		(pad "S" smd rect
			(at -1.100074 0.94996 90)
			(size 1.016 1.4224)
			(layers "F.Cu" "F.Mask" "F.Paste")
			(net "GND")
		)
	)
	(footprint ""
		(layer "F.Cu")
		(at 80.913478 -24.333962 180)
		(property "Reference" "C2148"
			(at 0 0 180)
			(layer "F.SilkS")
			(hide yes)
			(effects
				(font
					(size 1.27 1.27)
				)
			)
		)
		(property "Value" ""
			(at 0 0 180)
			(layer "F.Fab")
			(effects
				(font
					(size 1.27 1.27)
				)
			)
		)
		(duplicate_pad_numbers_are_jumpers no)
		(fp_line
			(start 0.7874 0.4064)
			(end -0.7874 0.4064)
			(stroke
				(width 0.1524)
				(type default)
			)
			(layer "F.SilkS")
		)
		(fp_line
			(start 0.7874 -0.4064)
			(end 0.7874 0.4064)
			(stroke
				(width 0.1524)
				(type default)
			)
			(layer "F.SilkS")
		)
		(fp_line
			(start -0.7874 0.4064)
			(end -0.7874 -0.4064)
			(stroke
				(width 0.1524)
				(type default)
			)
			(layer "F.SilkS")
		)
		(fp_line
			(start -0.7874 -0.4064)
			(end 0.7874 -0.4064)
			(stroke
				(width 0.1524)
				(type default)
			)
			(layer "F.SilkS")
		)
		(fp_line
			(start 0.67945 0.3048)
			(end 0.120396 0.3048)
			(stroke
				(width 0.1)
				(type default)
			)
			(layer "F.Fab")
		)
		(fp_line
			(start 0.67945 -0.3048)
			(end 0.67945 0.3048)
			(stroke
				(width 0.1)
				(type default)
			)
			(layer "F.Fab")
		)
		(fp_line
			(start 0.12065 -0.2794)
			(end 0.12065 -0.3048)
			(stroke
				(width 0.1)
				(type default)
			)
			(layer "F.Fab")
		)
		(fp_line
			(start 0.12065 -0.3048)
			(end 0.67945 -0.3048)
			(stroke
				(width 0.1)
				(type default)
			)
			(layer "F.Fab")
		)
		(fp_line
			(start 0.120396 0.3048)
			(end 0.120396 0.2794)
			(stroke
				(width 0.1)
				(type default)
			)
			(layer "F.Fab")
		)
		(fp_line
			(start 0.120396 0.2794)
			(end -0.12065 0.2794)
			(stroke
				(width 0.1)
				(type default)
			)
			(layer "F.Fab")
		)
		(fp_line
			(start -0.12065 0.3048)
			(end -0.67945 0.3048)
			(stroke
				(width 0.1)
				(type default)
			)
			(layer "F.Fab")
		)
		(fp_line
			(start -0.12065 0.2794)
			(end -0.12065 0.3048)
			(stroke
				(width 0.1)
				(type default)
			)
			(layer "F.Fab")
		)
		(fp_line
			(start -0.12065 -0.2794)
			(end 0.12065 -0.2794)
			(stroke
				(width 0.1)
				(type default)
			)
			(layer "F.Fab")
		)
		(fp_line
			(start -0.12065 -0.305054)
			(end -0.12065 -0.2794)
			(stroke
				(width 0.1)
				(type default)
			)
			(layer "F.Fab")
		)
		(fp_line
			(start -0.67945 0.3048)
			(end -0.67945 -0.305054)
			(stroke
				(width 0.1)
				(type default)
			)
			(layer "F.Fab")
		)
		(fp_line
			(start -0.67945 -0.305054)
			(end -0.12065 -0.305054)
			(stroke
				(width 0.1)
				(type default)
			)
			(layer "F.Fab")
		)
		(pad "1" smd circle
			(at -0.40005 0 180)
			(size 0 0)
			(layers "F.Cu" "F.Mask" "F.Paste")
			(net "P12V_OCP_V3_2")
		)
		(pad "2" smd circle
			(at 0.40005 0 180)
			(size 0 0)
			(layers "F.Cu" "F.Mask" "F.Paste")
			(net "P12V_OCP_GATE_2")
		)
	)
	(footprint ""
		(layer "F.Cu")
		(at 341.52459 -70.03796 90)
		(property "Reference" "C154"
			(at 0 0 90)
			(layer "F.SilkS")
			(hide yes)
			(effects
				(font
					(size 1.27 1.27)
				)
			)
		)
		(property "Value" ""
			(at 0 0 90)
			(layer "F.Fab")
			(effects
				(font
					(size 1.27 1.27)
				)
			)
		)
		(duplicate_pad_numbers_are_jumpers no)
		(fp_line
			(start 0.299974 -0.150114)
			(end 0.299974 0.150114)
			(stroke
				(width 0.1)
				(type default)
			)
			(layer "F.Fab")
		)
		(fp_line
			(start -0.299974 -0.150114)
			(end 0.299974 -0.150114)
			(stroke
				(width 0.1)
				(type default)
			)
			(layer "F.Fab")
		)
		(fp_line
			(start 0.299974 0.150114)
			(end -0.299974 0.150114)
			(stroke
				(width 0.1)
				(type default)
			)
			(layer "F.Fab")
		)
		(fp_line
			(start -0.299974 0.150114)
			(end -0.299974 -0.150114)
			(stroke
				(width 0.1)
				(type default)
			)
			(layer "F.Fab")
		)
		(pad "1" smd rect
			(at -0.2667 0 90)
			(size 0.3048 0.381)
			(layers "F.Cu" "F.Mask" "F.Paste")
			(net "DMI_CPU0_PCH_TX_C_DP<0>")
		)
		(pad "2" smd rect
			(at 0.2667 0 90)
			(size 0.3048 0.381)
			(layers "F.Cu" "F.Mask" "F.Paste")
			(net "DMI_CPU0_PCH_TX_DP<0>")
		)
	)
	(footprint ""
		(layer "F.Cu")
		(at 92.185998 -408.517344 -90)
		(property "Reference" "C680"
			(at 0 0 270)
			(layer "F.SilkS")
			(hide yes)
			(effects
				(font
					(size 1.27 1.27)
				)
			)
		)
		(property "Value" ""
			(at 0 0 270)
			(layer "F.Fab")
			(effects
				(font
					(size 1.27 1.27)
				)
			)
		)
		(duplicate_pad_numbers_are_jumpers no)
		(fp_line
			(start -0.299974 0.150114)
			(end -0.299974 -0.150114)
			(stroke
				(width 0.1)
				(type default)
			)
			(layer "F.Fab")
		)
		(fp_line
			(start 0.299974 0.150114)
			(end -0.299974 0.150114)
			(stroke
				(width 0.1)
				(type default)
			)
			(layer "F.Fab")
		)
		(fp_line
			(start -0.299974 -0.150114)
			(end 0.299974 -0.150114)
			(stroke
				(width 0.1)
				(type default)
			)
			(layer "F.Fab")
		)
		(fp_line
			(start 0.299974 -0.150114)
			(end 0.299974 0.150114)
			(stroke
				(width 0.1)
				(type default)
			)
			(layer "F.Fab")
		)
		(pad "1" smd rect
			(at -0.2667 0 270)
			(size 0.3048 0.381)
			(layers "F.Cu" "F.Mask" "F.Paste")
			(net "P5E_CPU1_PE4_TX_C_DN<14>")
		)
		(pad "2" smd rect
			(at 0.2667 0 270)
			(size 0.3048 0.381)
			(layers "F.Cu" "F.Mask" "F.Paste")
			(net "P5E_CPU1_PE4_TX_DN<14>")
		)
	)
	(footprint ""
		(layer "F.Cu")
		(at 270.08582 -93.970348 90)
		(property "Reference" "U70"
			(at -2.84099 -0.26416 0)
			(unlocked yes)
			(layer "F.SilkS")
			(effects
				(font
					(size 0.7874 0.5842)
					(thickness 0.1524)
				)
			)
		)
		(property "Value" ""
			(at 0 0 90)
			(layer "F.Fab")
			(effects
				(font
					(size 1.27 1.27)
				)
			)
		)
		(duplicate_pad_numbers_are_jumpers no)
		(fp_line
			(start -1.949958 -1.610106)
			(end 1.949958 -1.610106)
			(stroke
				(width 0.1524)
				(type default)
			)
			(layer "F.SilkS")
		)
		(fp_line
			(start 1.949958 -1.560068)
			(end 1.949958 1.610106)
			(stroke
				(width 0.1524)
				(type default)
			)
			(layer "F.SilkS")
		)
		(fp_line
			(start 1.949958 1.610106)
			(end -1.949958 1.610106)
			(stroke
				(width 0.1524)
				(type default)
			)
			(layer "F.SilkS")
		)
		(fp_line
			(start -1.949958 1.610106)
			(end -1.949958 -1.610106)
			(stroke
				(width 0.1524)
				(type default)
			)
			(layer "F.SilkS")
		)
		(fp_line
			(start 0.750062 -1.560068)
			(end 0.750062 1.560068)
			(stroke
				(width 0.1)
				(type default)
			)
			(layer "F.Fab")
		)
		(fp_line
			(start -0.750062 -1.560068)
			(end 0.750062 -1.560068)
			(stroke
				(width 0.1)
				(type default)
			)
			(layer "F.Fab")
		)
		(fp_line
			(start 0.750062 1.560068)
			(end -0.750062 1.560068)
			(stroke
				(width 0.1)
				(type default)
			)
			(layer "F.Fab")
		)
		(fp_line
			(start -0.750062 1.560068)
			(end -0.750062 -1.560068)
			(stroke
				(width 0.1)
				(type default)
			)
			(layer "F.Fab")
		)
		(pad "D" smd rect
			(at 1.100074 0)
			(size 1.016 1.4224)
			(layers "F.Cu" "F.Mask" "F.Paste")
			(net "FM_PLD_CLKS_OE_R_N")
		)
		(pad "G" smd rect
			(at -1.100074 -0.94996)
			(size 1.016 1.4224)
			(layers "F.Cu" "F.Mask" "F.Paste")
			(net "FM_PLD_CLKS_DEV_EN")
		)
		(pad "S" smd rect
			(at -1.100074 0.94996)
			(size 1.016 1.4224)
			(layers "F.Cu" "F.Mask" "F.Paste")
			(net "GND")
		)
	)
	(footprint ""
		(layer "F.Cu")
		(at 29.332428 -98.570034 180)
		(property "Reference" "R3860"
			(at 0 0 180)
			(layer "F.SilkS")
			(hide yes)
			(effects
				(font
					(size 1.27 1.27)
				)
			)
		)
		(property "Value" ""
			(at 0 0 180)
			(layer "F.Fab")
			(effects
				(font
					(size 1.27 1.27)
				)
			)
		)
		(duplicate_pad_numbers_are_jumpers no)
		(fp_line
			(start 0.7874 0.4064)
			(end -0.7874 0.4064)
			(stroke
				(width 0.1524)
				(type default)
			)
			(layer "F.SilkS")
		)
		(fp_line
			(start 0.7874 -0.4064)
			(end 0.7874 0.4064)
			(stroke
				(width 0.1524)
				(type default)
			)
			(layer "F.SilkS")
		)
		(fp_line
			(start -0.7874 0.4064)
			(end -0.7874 -0.4064)
			(stroke
				(width 0.1524)
				(type default)
			)
			(layer "F.SilkS")
		)
		(fp_line
			(start -0.7874 -0.4064)
			(end 0.7874 -0.4064)
			(stroke
				(width 0.1524)
				(type default)
			)
			(layer "F.SilkS")
		)
		(fp_line
			(start 0.67945 0.3048)
			(end 0.120396 0.3048)
			(stroke
				(width 0.1)
				(type default)
			)
			(layer "F.Fab")
		)
		(fp_line
			(start 0.67945 -0.3048)
			(end 0.67945 0.3048)
			(stroke
				(width 0.1)
				(type default)
			)
			(layer "F.Fab")
		)
		(fp_line
			(start 0.12065 -0.2794)
			(end 0.12065 -0.3048)
			(stroke
				(width 0.1)
				(type default)
			)
			(layer "F.Fab")
		)
		(fp_line
			(start 0.12065 -0.3048)
			(end 0.67945 -0.3048)
			(stroke
				(width 0.1)
				(type default)
			)
			(layer "F.Fab")
		)
		(fp_line
			(start 0.120396 0.3048)
			(end 0.120396 0.2794)
			(stroke
				(width 0.1)
				(type default)
			)
			(layer "F.Fab")
		)
		(fp_line
			(start 0.120396 0.2794)
			(end -0.12065 0.2794)
			(stroke
				(width 0.1)
				(type default)
			)
			(layer "F.Fab")
		)
		(fp_line
			(start -0.12065 0.3048)
			(end -0.67945 0.3048)
			(stroke
				(width 0.1)
				(type default)
			)
			(layer "F.Fab")
		)
		(fp_line
			(start -0.12065 0.2794)
			(end -0.12065 0.3048)
			(stroke
				(width 0.1)
				(type default)
			)
			(layer "F.Fab")
		)
		(fp_line
			(start -0.12065 -0.2794)
			(end 0.12065 -0.2794)
			(stroke
				(width 0.1)
				(type default)
			)
			(layer "F.Fab")
		)
		(fp_line
			(start -0.12065 -0.305054)
			(end -0.12065 -0.2794)
			(stroke
				(width 0.1)
				(type default)
			)
			(layer "F.Fab")
		)
		(fp_line
			(start -0.67945 0.3048)
			(end -0.67945 -0.305054)
			(stroke
				(width 0.1)
				(type default)
			)
			(layer "F.Fab")
		)
		(fp_line
			(start -0.67945 -0.305054)
			(end -0.12065 -0.305054)
			(stroke
				(width 0.1)
				(type default)
			)
			(layer "F.Fab")
		)
		(pad "1" smd rect
			(at -0.40005 0)
			(size 0.4572 0.508)
			(layers "F.Cu" "F.Mask" "F.Paste")
			(net "P12V_OCP_V3_2_ISENSE_MPS_MAM")
		)
		(pad "2" smd rect
			(at 0.40005 0)
			(size 0.4572 0.508)
			(layers "F.Cu" "F.Mask" "F.Paste")
			(net "P12V_OCP_V3_2_ISENSE_MAM")
		)
	)
	(footprint ""
		(layer "F.Cu")
		(at 121.475754 -408.517344 -90)
		(property "Reference" "C1516"
			(at 0 0 270)
			(layer "F.SilkS")
			(hide yes)
			(effects
				(font
					(size 1.27 1.27)
				)
			)
		)
		(property "Value" ""
			(at 0 0 270)
			(layer "F.Fab")
			(effects
				(font
					(size 1.27 1.27)
				)
			)
		)
		(duplicate_pad_numbers_are_jumpers no)
		(fp_line
			(start -0.299974 0.150114)
			(end -0.299974 -0.150114)
			(stroke
				(width 0.1)
				(type default)
			)
			(layer "F.Fab")
		)
		(fp_line
			(start 0.299974 0.150114)
			(end -0.299974 0.150114)
			(stroke
				(width 0.1)
				(type default)
			)
			(layer "F.Fab")
		)
		(fp_line
			(start -0.299974 -0.150114)
			(end 0.299974 -0.150114)
			(stroke
				(width 0.1)
				(type default)
			)
			(layer "F.Fab")
		)
		(fp_line
			(start 0.299974 -0.150114)
			(end 0.299974 0.150114)
			(stroke
				(width 0.1)
				(type default)
			)
			(layer "F.Fab")
		)
		(pad "1" smd rect
			(at -0.2667 0 270)
			(size 0.3048 0.381)
			(layers "F.Cu" "F.Mask" "F.Paste")
			(net "P5E_CPU1_PE3_TX_C_DN<15>")
		)
		(pad "2" smd rect
			(at 0.2667 0 270)
			(size 0.3048 0.381)
			(layers "F.Cu" "F.Mask" "F.Paste")
			(net "P5E_CPU1_PE3_TX_DN<15>")
		)
	)
	(footprint ""
		(layer "F.Cu")
		(at 392.763248 -162.360864 -90)
		(property "Reference" "R994"
			(at 0 0 270)
			(layer "F.SilkS")
			(hide yes)
			(effects
				(font
					(size 1.27 1.27)
				)
			)
		)
		(property "Value" ""
			(at 0 0 270)
			(layer "F.Fab")
			(effects
				(font
					(size 1.27 1.27)
				)
			)
		)
		(duplicate_pad_numbers_are_jumpers no)
		(fp_line
			(start -0.7874 0.4064)
			(end -0.7874 -0.4064)
			(stroke
				(width 0.1524)
				(type default)
			)
			(layer "F.SilkS")
		)
		(fp_line
			(start 0.7874 0.4064)
			(end -0.7874 0.4064)
			(stroke
				(width 0.1524)
				(type default)
			)
			(layer "F.SilkS")
		)
		(fp_line
			(start -0.7874 -0.4064)
			(end 0.7874 -0.4064)
			(stroke
				(width 0.1524)
				(type default)
			)
			(layer "F.SilkS")
		)
		(fp_line
			(start 0.7874 -0.4064)
			(end 0.7874 0.4064)
			(stroke
				(width 0.1524)
				(type default)
			)
			(layer "F.SilkS")
		)
		(fp_line
			(start -0.67945 0.3048)
			(end -0.67945 -0.305054)
			(stroke
				(width 0.1)
				(type default)
			)
			(layer "F.Fab")
		)
		(fp_line
			(start -0.12065 0.3048)
			(end -0.67945 0.3048)
			(stroke
				(width 0.1)
				(type default)
			)
			(layer "F.Fab")
		)
		(fp_line
			(start 0.120396 0.3048)
			(end 0.120396 0.2794)
			(stroke
				(width 0.1)
				(type default)
			)
			(layer "F.Fab")
		)
		(fp_line
			(start 0.67945 0.3048)
			(end 0.120396 0.3048)
			(stroke
				(width 0.1)
				(type default)
			)
			(layer "F.Fab")
		)
		(fp_line
			(start -0.12065 0.2794)
			(end -0.12065 0.3048)
			(stroke
				(width 0.1)
				(type default)
			)
			(layer "F.Fab")
		)
		(fp_line
			(start 0.120396 0.2794)
			(end -0.12065 0.2794)
			(stroke
				(width 0.1)
				(type default)
			)
			(layer "F.Fab")
		)
		(fp_line
			(start -0.12065 -0.2794)
			(end 0.12065 -0.2794)
			(stroke
				(width 0.1)
				(type default)
			)
			(layer "F.Fab")
		)
		(fp_line
			(start 0.12065 -0.2794)
			(end 0.12065 -0.3048)
			(stroke
				(width 0.1)
				(type default)
			)
			(layer "F.Fab")
		)
		(fp_line
			(start 0.12065 -0.3048)
			(end 0.67945 -0.3048)
			(stroke
				(width 0.1)
				(type default)
			)
			(layer "F.Fab")
		)
		(fp_line
			(start 0.67945 -0.3048)
			(end 0.67945 0.3048)
			(stroke
				(width 0.1)
				(type default)
			)
			(layer "F.Fab")
		)
		(fp_line
			(start -0.67945 -0.305054)
			(end -0.12065 -0.305054)
			(stroke
				(width 0.1)
				(type default)
			)
			(layer "F.Fab")
		)
		(fp_line
			(start -0.12065 -0.305054)
			(end -0.12065 -0.2794)
			(stroke
				(width 0.1)
				(type default)
			)
			(layer "F.Fab")
		)
		(pad "1" smd circle
			(at -0.40005 0 270)
			(size 0 0)
			(layers "F.Cu" "F.Mask" "F.Paste")
			(net "SMB_S3M_CPU0_SDA")
		)
		(pad "2" smd circle
			(at 0.40005 0 270)
			(size 0 0)
			(layers "F.Cu" "F.Mask" "F.Paste")
			(net "SMB_S3M_CPU0_R_SDA")
		)
	)
	(footprint ""
		(layer "F.Cu")
		(at 399.88109 -402.371052 -90)
		(property "Reference" "C952"
			(at 0 0 270)
			(layer "F.SilkS")
			(hide yes)
			(effects
				(font
					(size 1.27 1.27)
				)
			)
		)
		(property "Value" ""
			(at 0 0 270)
			(layer "F.Fab")
			(effects
				(font
					(size 1.27 1.27)
				)
			)
		)
		(duplicate_pad_numbers_are_jumpers no)
		(fp_line
			(start -0.299974 0.150114)
			(end -0.299974 -0.150114)
			(stroke
				(width 0.1)
				(type default)
			)
			(layer "F.Fab")
		)
		(fp_line
			(start 0.299974 0.150114)
			(end -0.299974 0.150114)
			(stroke
				(width 0.1)
				(type default)
			)
			(layer "F.Fab")
		)
		(fp_line
			(start -0.299974 -0.150114)
			(end 0.299974 -0.150114)
			(stroke
				(width 0.1)
				(type default)
			)
			(layer "F.Fab")
		)
		(fp_line
			(start 0.299974 -0.150114)
			(end 0.299974 0.150114)
			(stroke
				(width 0.1)
				(type default)
			)
			(layer "F.Fab")
		)
		(pad "1" smd rect
			(at -0.2667 0 270)
			(size 0.3048 0.381)
			(layers "F.Cu" "F.Mask" "F.Paste")
			(net "P5E_CPU0_PE2_TX_C_DN<6>")
		)
		(pad "2" smd rect
			(at 0.2667 0 270)
			(size 0.3048 0.381)
			(layers "F.Cu" "F.Mask" "F.Paste")
			(net "P5E_CPU0_PE2_TX_DN<6>")
		)
	)
	(footprint ""
		(layer "F.Cu")
		(at 135.86841 -41.840404)
		(property "Reference" "U259"
			(at -0.31496 -1.85547 0)
			(unlocked yes)
			(layer "F.SilkS")
			(effects
				(font
					(size 0.7874 0.5842)
					(thickness 0.1524)
				)
			)
		)
		(property "Value" ""
			(at 0 0 0)
			(layer "F.Fab")
			(effects
				(font
					(size 1.27 1.27)
				)
			)
		)
		(duplicate_pad_numbers_are_jumpers no)
		(fp_line
			(start -1.7272 1.1176)
			(end -1.7272 -1.1176)
			(stroke
				(width 0.1524)
				(type default)
			)
			(layer "F.SilkS")
		)
		(fp_line
			(start -0.254 -1.1176)
			(end -1.7272 -1.1176)
			(stroke
				(width 0.1524)
				(type default)
			)
			(layer "F.SilkS")
		)
		(fp_line
			(start 0 -0.7366)
			(end -0.254 -1.1176)
			(stroke
				(width 0.1524)
				(type default)
			)
			(layer "F.SilkS")
		)
		(fp_line
			(start 0.254 -1.1176)
			(end 0 -0.7366)
			(stroke
				(width 0.1524)
				(type default)
			)
			(layer "F.SilkS")
		)
		(fp_line
			(start 1.7272 -1.1176)
			(end 0.254 -1.1176)
			(stroke
				(width 0.1524)
				(type default)
			)
			(layer "F.SilkS")
		)
		(fp_line
			(start 1.7272 -1.1176)
			(end 1.7272 1.1176)
			(stroke
				(width 0.1524)
				(type default)
			)
			(layer "F.SilkS")
		)
		(fp_line
			(start 1.7272 1.1176)
			(end -1.7272 1.1176)
			(stroke
				(width 0.1524)
				(type default)
			)
			(layer "F.SilkS")
		)
		(fp_poly
			(pts
				(xy -2.7178 -0.268986) (xy -2.7178 -1.030986) (xy -1.9558 -0.649986)
			)
			(stroke
				(width 0)
				(type default)
			)
			(fill yes)
			(layer "F.SilkS")
		)
		(fp_line
			(start -1.5748 -1.1176)
			(end -1.5748 1.1176)
			(stroke
				(width 0.1)
				(type default)
			)
			(layer "F.Fab")
		)
		(fp_line
			(start -1.5748 1.1176)
			(end 1.5748 1.1176)
			(stroke
				(width 0.1)
				(type default)
			)
			(layer "F.Fab")
		)
		(fp_line
			(start 1.5748 -1.1176)
			(end -1.5748 -1.1176)
			(stroke
				(width 0.1)
				(type default)
			)
			(layer "F.Fab")
		)
		(fp_line
			(start 1.5748 1.1176)
			(end 1.5748 -1.1176)
			(stroke
				(width 0.1)
				(type default)
			)
			(layer "F.Fab")
		)
		(fp_poly
			(pts
				(xy -1.9558 -0.649986) (xy -2.7178 -0.268986) (xy -2.7178 -1.030986)
			)
			(stroke
				(width 0)
				(type default)
			)
			(fill yes)
			(layer "F.Fab")
		)
		(pad "1" smd rect
			(at -0.999998 -0.649986 270)
			(size 0.3556 1.1176)
			(layers "F.Cu" "F.Mask" "F.Paste")
			(net "M2_SSD0_CLKREQ_EN_N")
		)
		(pad "2" smd rect
			(at -0.999998 0 270)
			(size 0.3556 1.1176)
			(layers "F.Cu" "F.Mask" "F.Paste")
			(net "GND")
		)
		(pad "3" smd rect
			(at -0.999998 0.649986 270)
			(size 0.3556 1.1176)
			(layers "F.Cu" "F.Mask" "F.Paste")
			(net "RST_PCIE_PCH_DEV_PERST_M2_R_N")
		)
		(pad "4" smd rect
			(at 0.999998 0.649986 270)
			(size 0.3556 1.1176)
			(layers "F.Cu" "F.Mask" "F.Paste")
			(net "RST_PCIE_PCH_DEV_BUF_M2_0_PERST")
		)
		(pad "5" smd rect
			(at 0.999998 0 270)
			(size 0.3556 1.1176)
			(layers "F.Cu" "F.Mask" "F.Paste")
			(net "P3V3_AUX")
		)
		(pad "6" smd rect
			(at 0.999998 -0.649986 270)
			(size 0.3556 1.1176)
			(layers "F.Cu" "F.Mask" "F.Paste")
			(net "HDD_ACTIVITY_BUF")
		)
	)
	(footprint ""
		(layer "F.Cu")
		(at 277.61946 -93.741494)
		(property "Reference" "R713"
			(at 0 0 0)
			(layer "F.SilkS")
			(hide yes)
			(effects
				(font
					(size 1.27 1.27)
				)
			)
		)
		(property "Value" ""
			(at 0 0 0)
			(layer "F.Fab")
			(effects
				(font
					(size 1.27 1.27)
				)
			)
		)
		(duplicate_pad_numbers_are_jumpers no)
		(fp_line
			(start -0.7874 -0.4064)
			(end 0.7874 -0.4064)
			(stroke
				(width 0.1524)
				(type default)
			)
			(layer "F.SilkS")
		)
		(fp_line
			(start -0.7874 0.4064)
			(end -0.7874 -0.4064)
			(stroke
				(width 0.1524)
				(type default)
			)
			(layer "F.SilkS")
		)
		(fp_line
			(start 0.7874 -0.4064)
			(end 0.7874 0.4064)
			(stroke
				(width 0.1524)
				(type default)
			)
			(layer "F.SilkS")
		)
		(fp_line
			(start 0.7874 0.4064)
			(end -0.7874 0.4064)
			(stroke
				(width 0.1524)
				(type default)
			)
			(layer "F.SilkS")
		)
		(fp_line
			(start -0.67945 -0.305054)
			(end -0.12065 -0.305054)
			(stroke
				(width 0.1)
				(type default)
			)
			(layer "F.Fab")
		)
		(fp_line
			(start -0.67945 0.3048)
			(end -0.67945 -0.305054)
			(stroke
				(width 0.1)
				(type default)
			)
			(layer "F.Fab")
		)
		(fp_line
			(start -0.12065 -0.305054)
			(end -0.12065 -0.2794)
			(stroke
				(width 0.1)
				(type default)
			)
			(layer "F.Fab")
		)
		(fp_line
			(start -0.12065 -0.2794)
			(end 0.12065 -0.2794)
			(stroke
				(width 0.1)
				(type default)
			)
			(layer "F.Fab")
		)
		(fp_line
			(start -0.12065 0.2794)
			(end -0.12065 0.3048)
			(stroke
				(width 0.1)
				(type default)
			)
			(layer "F.Fab")
		)
		(fp_line
			(start -0.12065 0.3048)
			(end -0.67945 0.3048)
			(stroke
				(width 0.1)
				(type default)
			)
			(layer "F.Fab")
		)
		(fp_line
			(start 0.120396 0.2794)
			(end -0.12065 0.2794)
			(stroke
				(width 0.1)
				(type default)
			)
			(layer "F.Fab")
		)
		(fp_line
			(start 0.120396 0.3048)
			(end 0.120396 0.2794)
			(stroke
				(width 0.1)
				(type default)
			)
			(layer "F.Fab")
		)
		(fp_line
			(start 0.12065 -0.3048)
			(end 0.67945 -0.3048)
			(stroke
				(width 0.1)
				(type default)
			)
			(layer "F.Fab")
		)
		(fp_line
			(start 0.12065 -0.2794)
			(end 0.12065 -0.3048)
			(stroke
				(width 0.1)
				(type default)
			)
			(layer "F.Fab")
		)
		(fp_line
			(start 0.67945 -0.3048)
			(end 0.67945 0.3048)
			(stroke
				(width 0.1)
				(type default)
			)
			(layer "F.Fab")
		)
		(fp_line
			(start 0.67945 0.3048)
			(end 0.120396 0.3048)
			(stroke
				(width 0.1)
				(type default)
			)
			(layer "F.Fab")
		)
		(pad "1" smd circle
			(at -0.40005 0)
			(size 0 0)
			(layers "F.Cu" "F.Mask" "F.Paste")
			(net "P3V3_AUX")
		)
		(pad "2" smd circle
			(at 0.40005 0)
			(size 0 0)
			(layers "F.Cu" "F.Mask" "F.Paste")
			(net "MB_FRU_ADDR2")
		)
	)
	(footprint ""
		(layer "F.Cu")
		(at 421.292528 -346.017342)
		(property "Reference" "PC1183"
			(at 0 0 0)
			(layer "F.SilkS")
			(hide yes)
			(effects
				(font
					(size 1.27 1.27)
				)
			)
		)
		(property "Value" ""
			(at 0 0 0)
			(layer "F.Fab")
			(effects
				(font
					(size 1.27 1.27)
				)
			)
		)
		(duplicate_pad_numbers_are_jumpers no)
		(fp_line
			(start 2.750058 0.999998)
			(end -2.750058 0.999998)
			(stroke
				(width 0.1524)
				(type default)
			)
			(layer "F.SilkS")
		)
		(fp_circle
			(center 0 0.999998)
			(end 2.750058 0.999998)
			(stroke
				(width 0.1524)
				(type default)
			)
			(fill no)
			(layer "F.SilkS")
		)
		(fp_poly
			(pts
				(arc
					(start 2.750058 0.999998)
					(mid 0 3.750056)
					(end -2.750058 0.999998)
				)
			)
			(stroke
				(width 0)
				(type default)
			)
			(fill yes)
			(layer "F.SilkS")
		)
		(fp_circle
			(center 0 0.999998)
			(end 2.750058 0.999998)
			(stroke
				(width 0.1)
				(type default)
			)
			(fill no)
			(layer "F.Fab")
		)
		(pad "1" thru_hole rect
			(at 0 0)
			(size 1.5748 1.5748)
			(drill 1.0668)
			(layers "*.Cu" "*.Mask")
			(remove_unused_layers no)
			(net "PVCCFA_EHV_FIVRA_CPU0")
			(clearance 0)
			(padstack
				(mode front_inner_back)
				(layer "Inner"
					(shape circle)
					(size 1.5748 1.5748)
					(clearance 0)
				)
				(layer "B.Cu"
					(shape rect)
					(size 1.5748 1.5748)
					(clearance 0)
				)
			)
		)
		(pad "2" thru_hole circle
			(at 0 1.999996)
			(size 1.5748 1.5748)
			(drill 1.0668)
			(layers "*.Cu" "*.Mask")
			(remove_unused_layers no)
			(net "GND")
			(clearance 0)
		)
	)
	(footprint ""
		(layer "F.Cu")
		(at 327.281032 -15.829534)
		(property "Reference" "C513"
			(at 0 0 0)
			(layer "F.SilkS")
			(hide yes)
			(effects
				(font
					(size 1.27 1.27)
				)
			)
		)
		(property "Value" ""
			(at 0 0 0)
			(layer "F.Fab")
			(effects
				(font
					(size 1.27 1.27)
				)
			)
		)
		(duplicate_pad_numbers_are_jumpers no)
		(fp_line
			(start -1.524 -0.762)
			(end 1.524 -0.762)
			(stroke
				(width 0.1524)
				(type default)
			)
			(layer "F.SilkS")
		)
		(fp_line
			(start -1.524 0.762)
			(end -1.524 -0.762)
			(stroke
				(width 0.1524)
				(type default)
			)
			(layer "F.SilkS")
		)
		(fp_line
			(start 1.524 -0.762)
			(end 1.524 0.762)
			(stroke
				(width 0.1524)
				(type default)
			)
			(layer "F.SilkS")
		)
		(fp_line
			(start 1.524 0.762)
			(end -1.524 0.762)
			(stroke
				(width 0.1524)
				(type default)
			)
			(layer "F.SilkS")
		)
		(fp_line
			(start -1.1049 -0.724916)
			(end -1.1049 0.724916)
			(stroke
				(width 0.1)
				(type default)
			)
			(layer "F.Fab")
		)
		(fp_line
			(start -1.1049 0.724916)
			(end 1.1049 0.724916)
			(stroke
				(width 0.1)
				(type default)
			)
			(layer "F.Fab")
		)
		(fp_line
			(start 1.1049 -0.724916)
			(end -1.1049 -0.724916)
			(stroke
				(width 0.1)
				(type default)
			)
			(layer "F.Fab")
		)
		(fp_line
			(start 1.1049 0.724916)
			(end 1.1049 -0.724916)
			(stroke
				(width 0.1)
				(type default)
			)
			(layer "F.Fab")
		)
		(pad "1" smd rect
			(at -0.889 0 180)
			(size 1.016 1.27)
			(layers "F.Cu" "F.Mask" "F.Paste")
			(net "PGPPA_AUX")
		)
		(pad "2" smd rect
			(at 0.889 0 180)
			(size 1.016 1.27)
			(layers "F.Cu" "F.Mask" "F.Paste")
			(net "GND")
		)
	)
	(footprint ""
		(layer "F.Cu")
		(at 437.242966 -121.632726)
		(property "Reference" "R2405"
			(at 0 0 0)
			(layer "F.SilkS")
			(hide yes)
			(effects
				(font
					(size 1.27 1.27)
				)
			)
		)
		(property "Value" ""
			(at 0 0 0)
			(layer "F.Fab")
			(effects
				(font
					(size 1.27 1.27)
				)
			)
		)
		(duplicate_pad_numbers_are_jumpers no)
		(fp_line
			(start -0.7874 -0.4064)
			(end 0.7874 -0.4064)
			(stroke
				(width 0.1524)
				(type default)
			)
			(layer "F.SilkS")
		)
		(fp_line
			(start -0.7874 0.4064)
			(end -0.7874 -0.4064)
			(stroke
				(width 0.1524)
				(type default)
			)
			(layer "F.SilkS")
		)
		(fp_line
			(start 0.7874 -0.4064)
			(end 0.7874 0.4064)
			(stroke
				(width 0.1524)
				(type default)
			)
			(layer "F.SilkS")
		)
		(fp_line
			(start 0.7874 0.4064)
			(end -0.7874 0.4064)
			(stroke
				(width 0.1524)
				(type default)
			)
			(layer "F.SilkS")
		)
		(fp_line
			(start -0.67945 -0.305054)
			(end -0.12065 -0.305054)
			(stroke
				(width 0.1)
				(type default)
			)
			(layer "F.Fab")
		)
		(fp_line
			(start -0.67945 0.3048)
			(end -0.67945 -0.305054)
			(stroke
				(width 0.1)
				(type default)
			)
			(layer "F.Fab")
		)
		(fp_line
			(start -0.12065 -0.305054)
			(end -0.12065 -0.2794)
			(stroke
				(width 0.1)
				(type default)
			)
			(layer "F.Fab")
		)
		(fp_line
			(start -0.12065 -0.2794)
			(end 0.12065 -0.2794)
			(stroke
				(width 0.1)
				(type default)
			)
			(layer "F.Fab")
		)
		(fp_line
			(start -0.12065 0.2794)
			(end -0.12065 0.3048)
			(stroke
				(width 0.1)
				(type default)
			)
			(layer "F.Fab")
		)
		(fp_line
			(start -0.12065 0.3048)
			(end -0.67945 0.3048)
			(stroke
				(width 0.1)
				(type default)
			)
			(layer "F.Fab")
		)
		(fp_line
			(start 0.120396 0.2794)
			(end -0.12065 0.2794)
			(stroke
				(width 0.1)
				(type default)
			)
			(layer "F.Fab")
		)
		(fp_line
			(start 0.120396 0.3048)
			(end 0.120396 0.2794)
			(stroke
				(width 0.1)
				(type default)
			)
			(layer "F.Fab")
		)
		(fp_line
			(start 0.12065 -0.3048)
			(end 0.67945 -0.3048)
			(stroke
				(width 0.1)
				(type default)
			)
			(layer "F.Fab")
		)
		(fp_line
			(start 0.12065 -0.2794)
			(end 0.12065 -0.3048)
			(stroke
				(width 0.1)
				(type default)
			)
			(layer "F.Fab")
		)
		(fp_line
			(start 0.67945 -0.3048)
			(end 0.67945 0.3048)
			(stroke
				(width 0.1)
				(type default)
			)
			(layer "F.Fab")
		)
		(fp_line
			(start 0.67945 0.3048)
			(end 0.120396 0.3048)
			(stroke
				(width 0.1)
				(type default)
			)
			(layer "F.Fab")
		)
		(pad "1" smd circle
			(at -0.40005 0)
			(size 0 0)
			(layers "F.Cu" "F.Mask" "F.Paste")
			(net "IRQ_PVCCD_CPU0_VRHOT_LVC3_R_N")
		)
		(pad "2" smd circle
			(at 0.40005 0)
			(size 0 0)
			(layers "F.Cu" "F.Mask" "F.Paste")
			(net "IRQ_PVCCD_CPU0_VRHOT_LVC3_N")
		)
	)
	(footprint ""
		(layer "F.Cu")
		(at 176.58588 -133.695948 -90)
		(property "Reference" "R4259"
			(at 0 0 270)
			(layer "F.SilkS")
			(hide yes)
			(effects
				(font
					(size 1.27 1.27)
				)
			)
		)
		(property "Value" ""
			(at 0 0 270)
			(layer "F.Fab")
			(effects
				(font
					(size 1.27 1.27)
				)
			)
		)
		(duplicate_pad_numbers_are_jumpers no)
		(fp_line
			(start -0.7874 0.4064)
			(end -0.7874 -0.4064)
			(stroke
				(width 0.1524)
				(type default)
			)
			(layer "F.SilkS")
		)
		(fp_line
			(start 0.7874 0.4064)
			(end -0.7874 0.4064)
			(stroke
				(width 0.1524)
				(type default)
			)
			(layer "F.SilkS")
		)
		(fp_line
			(start -0.7874 -0.4064)
			(end 0.7874 -0.4064)
			(stroke
				(width 0.1524)
				(type default)
			)
			(layer "F.SilkS")
		)
		(fp_line
			(start 0.7874 -0.4064)
			(end 0.7874 0.4064)
			(stroke
				(width 0.1524)
				(type default)
			)
			(layer "F.SilkS")
		)
		(fp_line
			(start -0.67945 0.3048)
			(end -0.67945 -0.305054)
			(stroke
				(width 0.1)
				(type default)
			)
			(layer "F.Fab")
		)
		(fp_line
			(start -0.12065 0.3048)
			(end -0.67945 0.3048)
			(stroke
				(width 0.1)
				(type default)
			)
			(layer "F.Fab")
		)
		(fp_line
			(start 0.120396 0.3048)
			(end 0.120396 0.2794)
			(stroke
				(width 0.1)
				(type default)
			)
			(layer "F.Fab")
		)
		(fp_line
			(start 0.67945 0.3048)
			(end 0.120396 0.3048)
			(stroke
				(width 0.1)
				(type default)
			)
			(layer "F.Fab")
		)
		(fp_line
			(start -0.12065 0.2794)
			(end -0.12065 0.3048)
			(stroke
				(width 0.1)
				(type default)
			)
			(layer "F.Fab")
		)
		(fp_line
			(start 0.120396 0.2794)
			(end -0.12065 0.2794)
			(stroke
				(width 0.1)
				(type default)
			)
			(layer "F.Fab")
		)
		(fp_line
			(start -0.12065 -0.2794)
			(end 0.12065 -0.2794)
			(stroke
				(width 0.1)
				(type default)
			)
			(layer "F.Fab")
		)
		(fp_line
			(start 0.12065 -0.2794)
			(end 0.12065 -0.3048)
			(stroke
				(width 0.1)
				(type default)
			)
			(layer "F.Fab")
		)
		(fp_line
			(start 0.12065 -0.3048)
			(end 0.67945 -0.3048)
			(stroke
				(width 0.1)
				(type default)
			)
			(layer "F.Fab")
		)
		(fp_line
			(start 0.67945 -0.3048)
			(end 0.67945 0.3048)
			(stroke
				(width 0.1)
				(type default)
			)
			(layer "F.Fab")
		)
		(fp_line
			(start -0.67945 -0.305054)
			(end -0.12065 -0.305054)
			(stroke
				(width 0.1)
				(type default)
			)
			(layer "F.Fab")
		)
		(fp_line
			(start -0.12065 -0.305054)
			(end -0.12065 -0.2794)
			(stroke
				(width 0.1)
				(type default)
			)
			(layer "F.Fab")
		)
		(pad "1" smd circle
			(at -0.40005 0 270)
			(size 0 0)
			(layers "F.Cu" "F.Mask" "F.Paste")
			(net "FM_THERMAL_ALERT_N")
		)
		(pad "2" smd circle
			(at 0.40005 0 270)
			(size 0 0)
			(layers "F.Cu" "F.Mask" "F.Paste")
			(net "FM_THERMAL_ALERT_R_N")
		)
	)
	(footprint ""
		(layer "F.Cu")
		(at 368.005868 -357.11638 90)
		(property "Reference" "PR1337"
			(at 0 0 90)
			(layer "F.SilkS")
			(hide yes)
			(effects
				(font
					(size 1.27 1.27)
				)
			)
		)
		(property "Value" ""
			(at 0 0 90)
			(layer "F.Fab")
			(effects
				(font
					(size 1.27 1.27)
				)
			)
		)
		(duplicate_pad_numbers_are_jumpers no)
		(fp_line
			(start 0.7874 -0.4064)
			(end 0.7874 0.4064)
			(stroke
				(width 0.1524)
				(type default)
			)
			(layer "F.SilkS")
		)
		(fp_line
			(start -0.7874 -0.4064)
			(end 0.7874 -0.4064)
			(stroke
				(width 0.1524)
				(type default)
			)
			(layer "F.SilkS")
		)
		(fp_line
			(start 0.7874 0.4064)
			(end -0.7874 0.4064)
			(stroke
				(width 0.1524)
				(type default)
			)
			(layer "F.SilkS")
		)
		(fp_line
			(start -0.7874 0.4064)
			(end -0.7874 -0.4064)
			(stroke
				(width 0.1524)
				(type default)
			)
			(layer "F.SilkS")
		)
		(fp_line
			(start -0.12065 -0.305054)
			(end -0.12065 -0.2794)
			(stroke
				(width 0.1)
				(type default)
			)
			(layer "F.Fab")
		)
		(fp_line
			(start -0.67945 -0.305054)
			(end -0.12065 -0.305054)
			(stroke
				(width 0.1)
				(type default)
			)
			(layer "F.Fab")
		)
		(fp_line
			(start 0.67945 -0.3048)
			(end 0.67945 0.3048)
			(stroke
				(width 0.1)
				(type default)
			)
			(layer "F.Fab")
		)
		(fp_line
			(start 0.12065 -0.3048)
			(end 0.67945 -0.3048)
			(stroke
				(width 0.1)
				(type default)
			)
			(layer "F.Fab")
		)
		(fp_line
			(start 0.12065 -0.2794)
			(end 0.12065 -0.3048)
			(stroke
				(width 0.1)
				(type default)
			)
			(layer "F.Fab")
		)
		(fp_line
			(start -0.12065 -0.2794)
			(end 0.12065 -0.2794)
			(stroke
				(width 0.1)
				(type default)
			)
			(layer "F.Fab")
		)
		(fp_line
			(start 0.120396 0.2794)
			(end -0.12065 0.2794)
			(stroke
				(width 0.1)
				(type default)
			)
			(layer "F.Fab")
		)
		(fp_line
			(start -0.12065 0.2794)
			(end -0.12065 0.3048)
			(stroke
				(width 0.1)
				(type default)
			)
			(layer "F.Fab")
		)
		(fp_line
			(start 0.67945 0.3048)
			(end 0.120396 0.3048)
			(stroke
				(width 0.1)
				(type default)
			)
			(layer "F.Fab")
		)
		(fp_line
			(start 0.120396 0.3048)
			(end 0.120396 0.2794)
			(stroke
				(width 0.1)
				(type default)
			)
			(layer "F.Fab")
		)
		(fp_line
			(start -0.12065 0.3048)
			(end -0.67945 0.3048)
			(stroke
				(width 0.1)
				(type default)
			)
			(layer "F.Fab")
		)
		(fp_line
			(start -0.67945 0.3048)
			(end -0.67945 -0.305054)
			(stroke
				(width 0.1)
				(type default)
			)
			(layer "F.Fab")
		)
		(pad "1" smd circle
			(at -0.40005 0 90)
			(size 0 0)
			(layers "F.Cu" "F.Mask" "F.Paste")
			(net "PVPP_HBM_CPU0_FB")
		)
		(pad "2" smd circle
			(at 0.40005 0 90)
			(size 0 0)
			(layers "F.Cu" "F.Mask" "F.Paste")
			(net "SH_PVPP_HBM_CPU0_P")
		)
	)
	(footprint ""
		(layer "F.Cu")
		(at 120.0658 -343.906348 90)
		(property "Reference" "PC585"
			(at 0 0 90)
			(layer "F.SilkS")
			(hide yes)
			(effects
				(font
					(size 1.27 1.27)
				)
			)
		)
		(property "Value" ""
			(at 0 0 90)
			(layer "F.Fab")
			(effects
				(font
					(size 1.27 1.27)
				)
			)
		)
		(duplicate_pad_numbers_are_jumpers no)
		(fp_line
			(start -3.400044 1.249934)
			(end 3.400044 1.249934)
			(stroke
				(width 0.1524)
				(type default)
			)
			(layer "F.SilkS")
		)
		(fp_circle
			(center 0 1.249934)
			(end 0 4.649978)
			(stroke
				(width 0.1524)
				(type default)
			)
			(fill no)
			(layer "F.SilkS")
		)
		(fp_poly
			(pts
				(arc
					(start -3.400044 1.249934)
					(mid 0 4.649978)
					(end 3.400044 1.249934)
				)
			)
			(stroke
				(width 0)
				(type default)
			)
			(fill yes)
			(layer "F.SilkS")
		)
		(fp_circle
			(center 0 1.249934)
			(end 0 4.649978)
			(stroke
				(width 0.1)
				(type default)
			)
			(fill no)
			(layer "F.Fab")
		)
		(pad "1" thru_hole rect
			(at 0 0 90)
			(size 1.524 1.524)
			(drill 1.016)
			(layers "*.Cu" "*.Mask")
			(remove_unused_layers no)
			(net "SW_P12V_PVCCIN_CPU1_FLT")
			(clearance 0)
			(padstack
				(mode front_inner_back)
				(layer "Inner"
					(shape circle)
					(size 1.524 1.524)
					(clearance 0)
				)
				(layer "B.Cu"
					(shape rect)
					(size 1.524 1.524)
					(clearance 0)
				)
			)
		)
		(pad "2" thru_hole circle
			(at 0 2.500122 90)
			(size 1.524 1.524)
			(drill 1.016)
			(layers "*.Cu" "*.Mask")
			(remove_unused_layers no)
			(net "GND")
			(clearance 0)
		)
	)
	(footprint ""
		(layer "F.Cu")
		(at 335.209134 -18.79727 -90)
		(property "Reference" "R1748"
			(at 0 0 270)
			(layer "F.SilkS")
			(hide yes)
			(effects
				(font
					(size 1.27 1.27)
				)
			)
		)
		(property "Value" ""
			(at 0 0 270)
			(layer "F.Fab")
			(effects
				(font
					(size 1.27 1.27)
				)
			)
		)
		(duplicate_pad_numbers_are_jumpers no)
		(fp_line
			(start -0.7874 0.4064)
			(end -0.7874 -0.4064)
			(stroke
				(width 0.1524)
				(type default)
			)
			(layer "F.SilkS")
		)
		(fp_line
			(start 0.7874 0.4064)
			(end -0.7874 0.4064)
			(stroke
				(width 0.1524)
				(type default)
			)
			(layer "F.SilkS")
		)
		(fp_line
			(start -0.7874 -0.4064)
			(end 0.7874 -0.4064)
			(stroke
				(width 0.1524)
				(type default)
			)
			(layer "F.SilkS")
		)
		(fp_line
			(start 0.7874 -0.4064)
			(end 0.7874 0.4064)
			(stroke
				(width 0.1524)
				(type default)
			)
			(layer "F.SilkS")
		)
		(fp_line
			(start -0.67945 0.3048)
			(end -0.67945 -0.305054)
			(stroke
				(width 0.1)
				(type default)
			)
			(layer "F.Fab")
		)
		(fp_line
			(start -0.12065 0.3048)
			(end -0.67945 0.3048)
			(stroke
				(width 0.1)
				(type default)
			)
			(layer "F.Fab")
		)
		(fp_line
			(start 0.120396 0.3048)
			(end 0.120396 0.2794)
			(stroke
				(width 0.1)
				(type default)
			)
			(layer "F.Fab")
		)
		(fp_line
			(start 0.67945 0.3048)
			(end 0.120396 0.3048)
			(stroke
				(width 0.1)
				(type default)
			)
			(layer "F.Fab")
		)
		(fp_line
			(start -0.12065 0.2794)
			(end -0.12065 0.3048)
			(stroke
				(width 0.1)
				(type default)
			)
			(layer "F.Fab")
		)
		(fp_line
			(start 0.120396 0.2794)
			(end -0.12065 0.2794)
			(stroke
				(width 0.1)
				(type default)
			)
			(layer "F.Fab")
		)
		(fp_line
			(start -0.12065 -0.2794)
			(end 0.12065 -0.2794)
			(stroke
				(width 0.1)
				(type default)
			)
			(layer "F.Fab")
		)
		(fp_line
			(start 0.12065 -0.2794)
			(end 0.12065 -0.3048)
			(stroke
				(width 0.1)
				(type default)
			)
			(layer "F.Fab")
		)
		(fp_line
			(start 0.12065 -0.3048)
			(end 0.67945 -0.3048)
			(stroke
				(width 0.1)
				(type default)
			)
			(layer "F.Fab")
		)
		(fp_line
			(start 0.67945 -0.3048)
			(end 0.67945 0.3048)
			(stroke
				(width 0.1)
				(type default)
			)
			(layer "F.Fab")
		)
		(fp_line
			(start -0.67945 -0.305054)
			(end -0.12065 -0.305054)
			(stroke
				(width 0.1)
				(type default)
			)
			(layer "F.Fab")
		)
		(fp_line
			(start -0.12065 -0.305054)
			(end -0.12065 -0.2794)
			(stroke
				(width 0.1)
				(type default)
			)
			(layer "F.Fab")
		)
		(pad "1" smd circle
			(at -0.40005 0 270)
			(size 0 0)
			(layers "F.Cu" "F.Mask" "F.Paste")
			(net "FM_ESPI_PLD_EN")
		)
		(pad "2" smd circle
			(at 0.40005 0 270)
			(size 0 0)
			(layers "F.Cu" "F.Mask" "F.Paste")
			(net "FM_ESPI_PLD_R_EN_BUF")
		)
	)
	(footprint ""
		(layer "F.Cu")
		(at 68.64096 -61.158628 -90)
		(property "Reference" "R3631"
			(at 0 0 270)
			(layer "F.SilkS")
			(hide yes)
			(effects
				(font
					(size 1.27 1.27)
				)
			)
		)
		(property "Value" ""
			(at 0 0 270)
			(layer "F.Fab")
			(effects
				(font
					(size 1.27 1.27)
				)
			)
		)
		(duplicate_pad_numbers_are_jumpers no)
		(fp_line
			(start -0.7874 0.4064)
			(end -0.7874 -0.4064)
			(stroke
				(width 0.1524)
				(type default)
			)
			(layer "F.SilkS")
		)
		(fp_line
			(start 0.7874 0.4064)
			(end -0.7874 0.4064)
			(stroke
				(width 0.1524)
				(type default)
			)
			(layer "F.SilkS")
		)
		(fp_line
			(start -0.7874 -0.4064)
			(end 0.7874 -0.4064)
			(stroke
				(width 0.1524)
				(type default)
			)
			(layer "F.SilkS")
		)
		(fp_line
			(start 0.7874 -0.4064)
			(end 0.7874 0.4064)
			(stroke
				(width 0.1524)
				(type default)
			)
			(layer "F.SilkS")
		)
		(fp_line
			(start -0.67945 0.3048)
			(end -0.67945 -0.305054)
			(stroke
				(width 0.1)
				(type default)
			)
			(layer "F.Fab")
		)
		(fp_line
			(start -0.12065 0.3048)
			(end -0.67945 0.3048)
			(stroke
				(width 0.1)
				(type default)
			)
			(layer "F.Fab")
		)
		(fp_line
			(start 0.120396 0.3048)
			(end 0.120396 0.2794)
			(stroke
				(width 0.1)
				(type default)
			)
			(layer "F.Fab")
		)
		(fp_line
			(start 0.67945 0.3048)
			(end 0.120396 0.3048)
			(stroke
				(width 0.1)
				(type default)
			)
			(layer "F.Fab")
		)
		(fp_line
			(start -0.12065 0.2794)
			(end -0.12065 0.3048)
			(stroke
				(width 0.1)
				(type default)
			)
			(layer "F.Fab")
		)
		(fp_line
			(start 0.120396 0.2794)
			(end -0.12065 0.2794)
			(stroke
				(width 0.1)
				(type default)
			)
			(layer "F.Fab")
		)
		(fp_line
			(start -0.12065 -0.2794)
			(end 0.12065 -0.2794)
			(stroke
				(width 0.1)
				(type default)
			)
			(layer "F.Fab")
		)
		(fp_line
			(start 0.12065 -0.2794)
			(end 0.12065 -0.3048)
			(stroke
				(width 0.1)
				(type default)
			)
			(layer "F.Fab")
		)
		(fp_line
			(start 0.12065 -0.3048)
			(end 0.67945 -0.3048)
			(stroke
				(width 0.1)
				(type default)
			)
			(layer "F.Fab")
		)
		(fp_line
			(start 0.67945 -0.3048)
			(end 0.67945 0.3048)
			(stroke
				(width 0.1)
				(type default)
			)
			(layer "F.Fab")
		)
		(fp_line
			(start -0.67945 -0.305054)
			(end -0.12065 -0.305054)
			(stroke
				(width 0.1)
				(type default)
			)
			(layer "F.Fab")
		)
		(fp_line
			(start -0.12065 -0.305054)
			(end -0.12065 -0.2794)
			(stroke
				(width 0.1)
				(type default)
			)
			(layer "F.Fab")
		)
		(pad "1" smd circle
			(at -0.40005 0 270)
			(size 0 0)
			(layers "F.Cu" "F.Mask" "F.Paste")
			(net "HP_LVC3_OCP_V3_2_EN")
		)
		(pad "2" smd circle
			(at 0.40005 0 270)
			(size 0 0)
			(layers "F.Cu" "F.Mask" "F.Paste")
			(net "P3V3_OCP_EN_2")
		)
	)
	(footprint ""
		(layer "F.Cu")
		(at 9.908032 -92.687648 90)
		(property "Reference" "R3654"
			(at 0 0 90)
			(layer "F.SilkS")
			(hide yes)
			(effects
				(font
					(size 1.27 1.27)
				)
			)
		)
		(property "Value" ""
			(at 0 0 90)
			(layer "F.Fab")
			(effects
				(font
					(size 1.27 1.27)
				)
			)
		)
		(duplicate_pad_numbers_are_jumpers no)
		(fp_line
			(start 0.7874 -0.4064)
			(end 0.7874 0.4064)
			(stroke
				(width 0.1524)
				(type default)
			)
			(layer "F.SilkS")
		)
		(fp_line
			(start -0.7874 -0.4064)
			(end 0.7874 -0.4064)
			(stroke
				(width 0.1524)
				(type default)
			)
			(layer "F.SilkS")
		)
		(fp_line
			(start 0.7874 0.4064)
			(end -0.7874 0.4064)
			(stroke
				(width 0.1524)
				(type default)
			)
			(layer "F.SilkS")
		)
		(fp_line
			(start -0.7874 0.4064)
			(end -0.7874 -0.4064)
			(stroke
				(width 0.1524)
				(type default)
			)
			(layer "F.SilkS")
		)
		(fp_line
			(start -0.12065 -0.305054)
			(end -0.12065 -0.2794)
			(stroke
				(width 0.1)
				(type default)
			)
			(layer "F.Fab")
		)
		(fp_line
			(start -0.67945 -0.305054)
			(end -0.12065 -0.305054)
			(stroke
				(width 0.1)
				(type default)
			)
			(layer "F.Fab")
		)
		(fp_line
			(start 0.67945 -0.3048)
			(end 0.67945 0.3048)
			(stroke
				(width 0.1)
				(type default)
			)
			(layer "F.Fab")
		)
		(fp_line
			(start 0.12065 -0.3048)
			(end 0.67945 -0.3048)
			(stroke
				(width 0.1)
				(type default)
			)
			(layer "F.Fab")
		)
		(fp_line
			(start 0.12065 -0.2794)
			(end 0.12065 -0.3048)
			(stroke
				(width 0.1)
				(type default)
			)
			(layer "F.Fab")
		)
		(fp_line
			(start -0.12065 -0.2794)
			(end 0.12065 -0.2794)
			(stroke
				(width 0.1)
				(type default)
			)
			(layer "F.Fab")
		)
		(fp_line
			(start 0.120396 0.2794)
			(end -0.12065 0.2794)
			(stroke
				(width 0.1)
				(type default)
			)
			(layer "F.Fab")
		)
		(fp_line
			(start -0.12065 0.2794)
			(end -0.12065 0.3048)
			(stroke
				(width 0.1)
				(type default)
			)
			(layer "F.Fab")
		)
		(fp_line
			(start 0.67945 0.3048)
			(end 0.120396 0.3048)
			(stroke
				(width 0.1)
				(type default)
			)
			(layer "F.Fab")
		)
		(fp_line
			(start 0.120396 0.3048)
			(end 0.120396 0.2794)
			(stroke
				(width 0.1)
				(type default)
			)
			(layer "F.Fab")
		)
		(fp_line
			(start -0.12065 0.3048)
			(end -0.67945 0.3048)
			(stroke
				(width 0.1)
				(type default)
			)
			(layer "F.Fab")
		)
		(fp_line
			(start -0.67945 0.3048)
			(end -0.67945 -0.305054)
			(stroke
				(width 0.1)
				(type default)
			)
			(layer "F.Fab")
		)
		(pad "1" smd circle
			(at -0.40005 0 90)
			(size 0 0)
			(layers "F.Cu" "F.Mask" "F.Paste")
			(net "RST_USB_HUB_N")
		)
		(pad "2" smd circle
			(at 0.40005 0 90)
			(size 0 0)
			(layers "F.Cu" "F.Mask" "F.Paste")
			(net "RST_USB_HUB_R_N")
		)
	)
	(footprint ""
		(layer "F.Cu")
		(at 182.964582 -425.831)
		(property "Reference" "R4769"
			(at 0 0 0)
			(layer "F.SilkS")
			(hide yes)
			(effects
				(font
					(size 1.27 1.27)
				)
			)
		)
		(property "Value" ""
			(at 0 0 0)
			(layer "F.Fab")
			(effects
				(font
					(size 1.27 1.27)
				)
			)
		)
		(duplicate_pad_numbers_are_jumpers no)
		(fp_line
			(start -0.7874 -0.4064)
			(end 0.7874 -0.4064)
			(stroke
				(width 0.1524)
				(type default)
			)
			(layer "F.SilkS")
		)
		(fp_line
			(start -0.7874 0.4064)
			(end -0.7874 -0.4064)
			(stroke
				(width 0.1524)
				(type default)
			)
			(layer "F.SilkS")
		)
		(fp_line
			(start 0.7874 -0.4064)
			(end 0.7874 0.4064)
			(stroke
				(width 0.1524)
				(type default)
			)
			(layer "F.SilkS")
		)
		(fp_line
			(start 0.7874 0.4064)
			(end -0.7874 0.4064)
			(stroke
				(width 0.1524)
				(type default)
			)
			(layer "F.SilkS")
		)
		(fp_line
			(start -0.67945 -0.305054)
			(end -0.12065 -0.305054)
			(stroke
				(width 0.1)
				(type default)
			)
			(layer "F.Fab")
		)
		(fp_line
			(start -0.67945 0.3048)
			(end -0.67945 -0.305054)
			(stroke
				(width 0.1)
				(type default)
			)
			(layer "F.Fab")
		)
		(fp_line
			(start -0.12065 -0.305054)
			(end -0.12065 -0.2794)
			(stroke
				(width 0.1)
				(type default)
			)
			(layer "F.Fab")
		)
		(fp_line
			(start -0.12065 -0.2794)
			(end 0.12065 -0.2794)
			(stroke
				(width 0.1)
				(type default)
			)
			(layer "F.Fab")
		)
		(fp_line
			(start -0.12065 0.2794)
			(end -0.12065 0.3048)
			(stroke
				(width 0.1)
				(type default)
			)
			(layer "F.Fab")
		)
		(fp_line
			(start -0.12065 0.3048)
			(end -0.67945 0.3048)
			(stroke
				(width 0.1)
				(type default)
			)
			(layer "F.Fab")
		)
		(fp_line
			(start 0.120396 0.2794)
			(end -0.12065 0.2794)
			(stroke
				(width 0.1)
				(type default)
			)
			(layer "F.Fab")
		)
		(fp_line
			(start 0.120396 0.3048)
			(end 0.120396 0.2794)
			(stroke
				(width 0.1)
				(type default)
			)
			(layer "F.Fab")
		)
		(fp_line
			(start 0.12065 -0.3048)
			(end 0.67945 -0.3048)
			(stroke
				(width 0.1)
				(type default)
			)
			(layer "F.Fab")
		)
		(fp_line
			(start 0.12065 -0.2794)
			(end 0.12065 -0.3048)
			(stroke
				(width 0.1)
				(type default)
			)
			(layer "F.Fab")
		)
		(fp_line
			(start 0.67945 -0.3048)
			(end 0.67945 0.3048)
			(stroke
				(width 0.1)
				(type default)
			)
			(layer "F.Fab")
		)
		(fp_line
			(start 0.67945 0.3048)
			(end 0.120396 0.3048)
			(stroke
				(width 0.1)
				(type default)
			)
			(layer "F.Fab")
		)
		(pad "1" smd circle
			(at -0.40005 0)
			(size 0 0)
			(layers "F.Cu" "F.Mask" "F.Paste")
			(net "FM_PDB_BUF_EN_R")
		)
		(pad "2" smd circle
			(at 0.40005 0)
			(size 0 0)
			(layers "F.Cu" "F.Mask" "F.Paste")
			(net "GND")
		)
	)
	(footprint ""
		(layer "F.Cu")
		(at 364.2868 -350.357948 90)
		(property "Reference" "PC2345"
			(at 0 0 90)
			(layer "F.SilkS")
			(hide yes)
			(effects
				(font
					(size 1.27 1.27)
				)
			)
		)
		(property "Value" ""
			(at 0 0 90)
			(layer "F.Fab")
			(effects
				(font
					(size 1.27 1.27)
				)
			)
		)
		(duplicate_pad_numbers_are_jumpers no)
		(fp_line
			(start -3.400044 1.249934)
			(end 3.400044 1.249934)
			(stroke
				(width 0.1524)
				(type default)
			)
			(layer "F.SilkS")
		)
		(fp_circle
			(center 0 1.249934)
			(end 0 4.649978)
			(stroke
				(width 0.1524)
				(type default)
			)
			(fill no)
			(layer "F.SilkS")
		)
		(fp_poly
			(pts
				(arc
					(start -3.400044 1.249934)
					(mid 0 4.649978)
					(end 3.400044 1.249934)
				)
			)
			(stroke
				(width 0)
				(type default)
			)
			(fill yes)
			(layer "F.SilkS")
		)
		(fp_circle
			(center 0 1.249934)
			(end 0 4.649978)
			(stroke
				(width 0.1)
				(type default)
			)
			(fill no)
			(layer "F.Fab")
		)
		(pad "1" thru_hole rect
			(at 0 0 90)
			(size 1.524 1.524)
			(drill 1.016)
			(layers "*.Cu" "*.Mask")
			(remove_unused_layers no)
			(net "SW_P12V_PVCCIN_CPU0_FLT")
			(clearance 0)
			(padstack
				(mode front_inner_back)
				(layer "Inner"
					(shape circle)
					(size 1.524 1.524)
					(clearance 0)
				)
				(layer "B.Cu"
					(shape rect)
					(size 1.524 1.524)
					(clearance 0)
				)
			)
		)
		(pad "2" thru_hole circle
			(at 0 2.500122 90)
			(size 1.524 1.524)
			(drill 1.016)
			(layers "*.Cu" "*.Mask")
			(remove_unused_layers no)
			(net "GND")
			(clearance 0)
		)
	)
	(footprint ""
		(layer "F.Cu")
		(at 439.37174 -100.27158 90)
		(property "Reference" "R4746"
			(at 0 0 90)
			(layer "F.SilkS")
			(hide yes)
			(effects
				(font
					(size 1.27 1.27)
				)
			)
		)
		(property "Value" ""
			(at 0 0 90)
			(layer "F.Fab")
			(effects
				(font
					(size 1.27 1.27)
				)
			)
		)
		(duplicate_pad_numbers_are_jumpers no)
		(fp_line
			(start 0.7874 -0.4064)
			(end 0.7874 0.4064)
			(stroke
				(width 0.1524)
				(type default)
			)
			(layer "F.SilkS")
		)
		(fp_line
			(start -0.7874 -0.4064)
			(end 0.7874 -0.4064)
			(stroke
				(width 0.1524)
				(type default)
			)
			(layer "F.SilkS")
		)
		(fp_line
			(start 0.7874 0.4064)
			(end -0.7874 0.4064)
			(stroke
				(width 0.1524)
				(type default)
			)
			(layer "F.SilkS")
		)
		(fp_line
			(start -0.7874 0.4064)
			(end -0.7874 -0.4064)
			(stroke
				(width 0.1524)
				(type default)
			)
			(layer "F.SilkS")
		)
		(fp_line
			(start -0.12065 -0.305054)
			(end -0.12065 -0.2794)
			(stroke
				(width 0.1)
				(type default)
			)
			(layer "F.Fab")
		)
		(fp_line
			(start -0.67945 -0.305054)
			(end -0.12065 -0.305054)
			(stroke
				(width 0.1)
				(type default)
			)
			(layer "F.Fab")
		)
		(fp_line
			(start 0.67945 -0.3048)
			(end 0.67945 0.3048)
			(stroke
				(width 0.1)
				(type default)
			)
			(layer "F.Fab")
		)
		(fp_line
			(start 0.12065 -0.3048)
			(end 0.67945 -0.3048)
			(stroke
				(width 0.1)
				(type default)
			)
			(layer "F.Fab")
		)
		(fp_line
			(start 0.12065 -0.2794)
			(end 0.12065 -0.3048)
			(stroke
				(width 0.1)
				(type default)
			)
			(layer "F.Fab")
		)
		(fp_line
			(start -0.12065 -0.2794)
			(end 0.12065 -0.2794)
			(stroke
				(width 0.1)
				(type default)
			)
			(layer "F.Fab")
		)
		(fp_line
			(start 0.120396 0.2794)
			(end -0.12065 0.2794)
			(stroke
				(width 0.1)
				(type default)
			)
			(layer "F.Fab")
		)
		(fp_line
			(start -0.12065 0.2794)
			(end -0.12065 0.3048)
			(stroke
				(width 0.1)
				(type default)
			)
			(layer "F.Fab")
		)
		(fp_line
			(start 0.67945 0.3048)
			(end 0.120396 0.3048)
			(stroke
				(width 0.1)
				(type default)
			)
			(layer "F.Fab")
		)
		(fp_line
			(start 0.120396 0.3048)
			(end 0.120396 0.2794)
			(stroke
				(width 0.1)
				(type default)
			)
			(layer "F.Fab")
		)
		(fp_line
			(start -0.12065 0.3048)
			(end -0.67945 0.3048)
			(stroke
				(width 0.1)
				(type default)
			)
			(layer "F.Fab")
		)
		(fp_line
			(start -0.67945 0.3048)
			(end -0.67945 -0.305054)
			(stroke
				(width 0.1)
				(type default)
			)
			(layer "F.Fab")
		)
		(pad "1" smd circle
			(at -0.40005 0 90)
			(size 0 0)
			(layers "F.Cu" "F.Mask" "F.Paste")
			(net "HP_LVC3_OCP_V3_1_PWRGD_R")
		)
		(pad "2" smd circle
			(at 0.40005 0 90)
			(size 0 0)
			(layers "F.Cu" "F.Mask" "F.Paste")
			(net "HP_LVC3_OCP_V3_1_PWRGD_R2")
		)
	)
	(footprint ""
		(layer "F.Cu")
		(at 63.194438 -28.382722)
		(property "Reference" "R3848"
			(at 0 0 0)
			(layer "F.SilkS")
			(hide yes)
			(effects
				(font
					(size 1.27 1.27)
				)
			)
		)
		(property "Value" ""
			(at 0 0 0)
			(layer "F.Fab")
			(effects
				(font
					(size 1.27 1.27)
				)
			)
		)
		(duplicate_pad_numbers_are_jumpers no)
		(fp_line
			(start -0.7874 -0.4064)
			(end 0.7874 -0.4064)
			(stroke
				(width 0.1524)
				(type default)
			)
			(layer "F.SilkS")
		)
		(fp_line
			(start -0.7874 0.4064)
			(end -0.7874 -0.4064)
			(stroke
				(width 0.1524)
				(type default)
			)
			(layer "F.SilkS")
		)
		(fp_line
			(start 0.7874 -0.4064)
			(end 0.7874 0.4064)
			(stroke
				(width 0.1524)
				(type default)
			)
			(layer "F.SilkS")
		)
		(fp_line
			(start 0.7874 0.4064)
			(end -0.7874 0.4064)
			(stroke
				(width 0.1524)
				(type default)
			)
			(layer "F.SilkS")
		)
		(fp_line
			(start -0.67945 -0.305054)
			(end -0.12065 -0.305054)
			(stroke
				(width 0.1)
				(type default)
			)
			(layer "F.Fab")
		)
		(fp_line
			(start -0.67945 0.3048)
			(end -0.67945 -0.305054)
			(stroke
				(width 0.1)
				(type default)
			)
			(layer "F.Fab")
		)
		(fp_line
			(start -0.12065 -0.305054)
			(end -0.12065 -0.2794)
			(stroke
				(width 0.1)
				(type default)
			)
			(layer "F.Fab")
		)
		(fp_line
			(start -0.12065 -0.2794)
			(end 0.12065 -0.2794)
			(stroke
				(width 0.1)
				(type default)
			)
			(layer "F.Fab")
		)
		(fp_line
			(start -0.12065 0.2794)
			(end -0.12065 0.3048)
			(stroke
				(width 0.1)
				(type default)
			)
			(layer "F.Fab")
		)
		(fp_line
			(start -0.12065 0.3048)
			(end -0.67945 0.3048)
			(stroke
				(width 0.1)
				(type default)
			)
			(layer "F.Fab")
		)
		(fp_line
			(start 0.120396 0.2794)
			(end -0.12065 0.2794)
			(stroke
				(width 0.1)
				(type default)
			)
			(layer "F.Fab")
		)
		(fp_line
			(start 0.120396 0.3048)
			(end 0.120396 0.2794)
			(stroke
				(width 0.1)
				(type default)
			)
			(layer "F.Fab")
		)
		(fp_line
			(start 0.12065 -0.3048)
			(end 0.67945 -0.3048)
			(stroke
				(width 0.1)
				(type default)
			)
			(layer "F.Fab")
		)
		(fp_line
			(start 0.12065 -0.2794)
			(end 0.12065 -0.3048)
			(stroke
				(width 0.1)
				(type default)
			)
			(layer "F.Fab")
		)
		(fp_line
			(start 0.67945 -0.3048)
			(end 0.67945 0.3048)
			(stroke
				(width 0.1)
				(type default)
			)
			(layer "F.Fab")
		)
		(fp_line
			(start 0.67945 0.3048)
			(end 0.120396 0.3048)
			(stroke
				(width 0.1)
				(type default)
			)
			(layer "F.Fab")
		)
		(pad "1" smd circle
			(at -0.40005 0)
			(size 0 0)
			(layers "F.Cu" "F.Mask" "F.Paste")
			(net "P3V3_AUX")
		)
		(pad "2" smd circle
			(at 0.40005 0)
			(size 0 0)
			(layers "F.Cu" "F.Mask" "F.Paste")
			(net "HP_LVC3_OCP_V3_2_P12V_PWRGD")
		)
	)
	(footprint ""
		(layer "F.Cu")
		(at 192.898268 -426.355002)
		(property "Reference" "U290"
			(at -1.524508 2.771902 0)
			(unlocked yes)
			(layer "F.SilkS")
			(effects
				(font
					(size 0.7874 0.5842)
					(thickness 0.1524)
				)
				(justify left)
			)
		)
		(property "Value" ""
			(at 0 0 0)
			(layer "F.Fab")
			(effects
				(font
					(size 1.27 1.27)
				)
			)
		)
		(duplicate_pad_numbers_are_jumpers no)
		(fp_line
			(start -1.603248 -1.500124)
			(end 1.603248 -1.500124)
			(stroke
				(width 0.1524)
				(type default)
			)
			(layer "F.SilkS")
		)
		(fp_line
			(start -1.603248 1.500124)
			(end -1.603248 -1.500124)
			(stroke
				(width 0.1524)
				(type default)
			)
			(layer "F.SilkS")
		)
		(fp_line
			(start 1.603248 -1.500124)
			(end 1.603248 1.500124)
			(stroke
				(width 0.1524)
				(type default)
			)
			(layer "F.SilkS")
		)
		(fp_line
			(start 1.603248 1.500124)
			(end -1.603248 1.500124)
			(stroke
				(width 0.1524)
				(type default)
			)
			(layer "F.SilkS")
		)
		(fp_line
			(start -1.249934 -1.169924)
			(end -1.249934 -0.729996)
			(stroke
				(width 0.1)
				(type default)
			)
			(layer "F.Fab")
		)
		(fp_line
			(start -1.249934 -0.729996)
			(end -0.6985 -0.729996)
			(stroke
				(width 0.1)
				(type default)
			)
			(layer "F.Fab")
		)
		(fp_line
			(start -1.249934 0.729996)
			(end -1.249934 1.169924)
			(stroke
				(width 0.1)
				(type default)
			)
			(layer "F.Fab")
		)
		(fp_line
			(start -1.249934 1.169924)
			(end -0.700024 1.169924)
			(stroke
				(width 0.1)
				(type default)
			)
			(layer "F.Fab")
		)
		(fp_line
			(start -0.700024 -1.500124)
			(end -0.700024 -1.169924)
			(stroke
				(width 0.1)
				(type default)
			)
			(layer "F.Fab")
		)
		(fp_line
			(start -0.700024 -1.169924)
			(end -1.249934 -1.169924)
			(stroke
				(width 0.1)
				(type default)
			)
			(layer "F.Fab")
		)
		(fp_line
			(start -0.700024 1.169924)
			(end -0.700024 1.500124)
			(stroke
				(width 0.1)
				(type default)
			)
			(layer "F.Fab")
		)
		(fp_line
			(start -0.700024 1.500124)
			(end 0.700024 1.500124)
			(stroke
				(width 0.1)
				(type default)
			)
			(layer "F.Fab")
		)
		(fp_line
			(start -0.6985 -0.729996)
			(end -0.6985 0.729996)
			(stroke
				(width 0.1)
				(type default)
			)
			(layer "F.Fab")
		)
		(fp_line
			(start -0.6985 0.729996)
			(end -1.249934 0.729996)
			(stroke
				(width 0.1)
				(type default)
			)
			(layer "F.Fab")
		)
		(fp_line
			(start 0.700024 -1.500124)
			(end -0.700024 -1.500124)
			(stroke
				(width 0.1)
				(type default)
			)
			(layer "F.Fab")
		)
		(fp_line
			(start 0.700024 -0.219964)
			(end 0.700024 -1.500124)
			(stroke
				(width 0.1)
				(type default)
			)
			(layer "F.Fab")
		)
		(fp_line
			(start 0.700024 0.219964)
			(end 1.249934 0.219964)
			(stroke
				(width 0.1)
				(type default)
			)
			(layer "F.Fab")
		)
		(fp_line
			(start 0.700024 1.500124)
			(end 0.700024 0.219964)
			(stroke
				(width 0.1)
				(type default)
			)
			(layer "F.Fab")
		)
		(fp_line
			(start 1.249934 -0.219964)
			(end 0.700024 -0.219964)
			(stroke
				(width 0.1)
				(type default)
			)
			(layer "F.Fab")
		)
		(fp_line
			(start 1.249934 0.219964)
			(end 1.249934 -0.219964)
			(stroke
				(width 0.1)
				(type default)
			)
			(layer "F.Fab")
		)
		(fp_rect
			(start 0.700024 1.500124)
			(end -0.700024 -1.500124)
			(stroke
				(width 0)
				(type default)
			)
			(fill no)
			(layer "F.Fab")
		)
		(pad "D" smd rect
			(at 0.999998 0 270)
			(size 0.8128 0.9144)
			(layers "F.Cu" "F.Mask" "F.Paste")
			(net "HSC_EN")
		)
		(pad "G" smd rect
			(at -0.999998 -0.94996 270)
			(size 0.8128 0.9144)
			(layers "F.Cu" "F.Mask" "F.Paste")
			(net "PDB_PRSNT_N")
		)
		(pad "S" smd rect
			(at -0.999998 0.94996 270)
			(size 0.8128 0.9144)
			(layers "F.Cu" "F.Mask" "F.Paste")
			(net "GND")
		)
	)
	(footprint ""
		(layer "F.Cu")
		(at 511.924808 2.33172 -90)
		(property "Reference" "X20"
			(at -1.281684 3.260598 90)
			(unlocked yes)
			(layer "F.SilkS")
			(effects
				(font
					(size 0.7874 0.5842)
					(thickness 0.1524)
				)
				(justify left)
			)
		)
		(property "Value" ""
			(at 0 0 270)
			(layer "F.Fab")
			(effects
				(font
					(size 1.27 1.27)
				)
			)
		)
		(property "Device Type" "TP_TDR_4P_FTS_MPKT4_H025P0200_I"
			(at 1.30175 1.27 0)
			(unlocked yes)
			(layer "F.Fab")
			(hide yes)
			(effects
				(font
					(size 0.635 0.4064)
					(thickness 0.1524)
				)
			)
		)
		(property "User Part Number" "TP15"
			(at 1.30175 1.27 0)
			(unlocked yes)
			(layer "Cmts.User")
			(hide yes)
			(effects
				(font
					(size 0.635 0.4064)
					(thickness 0.1524)
				)
			)
		)
		(duplicate_pad_numbers_are_jumpers no)
		(fp_line
			(start 0 3.81)
			(end 2.54 3.81)
			(stroke
				(width 0.1524)
				(type default)
			)
			(layer "F.SilkS")
		)
		(fp_line
			(start 2.54 3.81)
			(end 2.54 3.6703)
			(stroke
				(width 0.1524)
				(type default)
			)
			(layer "F.SilkS")
		)
		(fp_line
			(start 0 3.175)
			(end 0 3.81)
			(stroke
				(width 0.1524)
				(type default)
			)
			(layer "F.SilkS")
		)
		(fp_line
			(start 2.54 1.4097)
			(end 2.54 1.1303)
			(stroke
				(width 0.1524)
				(type default)
			)
			(layer "F.SilkS")
		)
		(fp_line
			(start 0 0.635)
			(end 0 1.905)
			(stroke
				(width 0.1524)
				(type default)
			)
			(layer "F.SilkS")
		)
		(fp_line
			(start 2.54 -1.1303)
			(end 2.54 -1.27)
			(stroke
				(width 0.1524)
				(type default)
			)
			(layer "F.SilkS")
		)
		(fp_line
			(start 0 -1.27)
			(end 0 -0.635)
			(stroke
				(width 0.1524)
				(type default)
			)
			(layer "F.SilkS")
		)
		(fp_line
			(start 2.54 -1.27)
			(end 0 -1.27)
			(stroke
				(width 0.1524)
				(type default)
			)
			(layer "F.SilkS")
		)
		(fp_poly
			(pts
				(xy -1.33604 -0.088392) (xy -2.86004 0.673608) (xy -2.86004 -0.850392)
			)
			(stroke
				(width 0)
				(type default)
			)
			(fill yes)
			(layer "F.SilkS")
		)
		(fp_line
			(start 0 3.81)
			(end 2.54 3.81)
			(stroke
				(width 0.1)
				(type default)
			)
			(layer "F.Fab")
		)
		(fp_line
			(start 2.54 3.81)
			(end 2.54 -1.27)
			(stroke
				(width 0.1)
				(type default)
			)
			(layer "F.Fab")
		)
		(fp_line
			(start 0 -1.27)
			(end 0 3.81)
			(stroke
				(width 0.1)
				(type default)
			)
			(layer "F.Fab")
		)
		(fp_line
			(start 2.54 -1.27)
			(end 0 -1.27)
			(stroke
				(width 0.1)
				(type default)
			)
			(layer "F.Fab")
		)
		(fp_poly
			(pts
				(xy -0.761746 0) (xy -2.285746 -0.762) (xy -2.285746 0.762)
			)
			(stroke
				(width 0)
				(type default)
			)
			(fill yes)
			(layer "F.Fab")
		)
		(pad "1" thru_hole circle
			(at 0 0 270)
			(size 1.0033 1.0033)
			(drill 0.249936)
			(layers "*.Cu" "*.Mask")
			(remove_unused_layers no)
			(net "TDR_DIFF_100_IN1_DN")
			(clearance 0.10795)
			(thermal_gap 0.10795)
			(padstack
				(mode front_inner_back)
				(layer "Inner"
					(shape circle)
					(size 0.8001 0.8001)
					(clearance 0.1524)
				)
				(layer "B.Cu"
					(shape circle)
					(size 1.0033 1.0033)
					(clearance 0.10795)
				)
			)
		)
		(pad "2" thru_hole circle
			(at 2.54 0 270)
			(size 1.9939 1.9939)
			(drill 0.249936)
			(layers "*.Cu" "*.Mask")
			(remove_unused_layers no)
			(net "T1_GND")
			(clearance 0.10795)
			(thermal_gap 0.10795)
			(padstack
				(mode front_inner_back)
				(layer "Inner"
					(shape circle)
					(size 0.8001 0.8001)
					(clearance 0.1524)
				)
				(layer "B.Cu"
					(shape circle)
					(size 1.9939 1.9939)
					(clearance 0.10795)
				)
			)
		)
		(pad "3" thru_hole circle
			(at 2.54 2.54 270)
			(size 1.9939 1.9939)
			(drill 0.249936)
			(layers "*.Cu" "*.Mask")
			(remove_unused_layers no)
			(net "T1_GND")
			(clearance 0.10795)
			(thermal_gap 0.10795)
			(padstack
				(mode front_inner_back)
				(layer "Inner"
					(shape circle)
					(size 0.8001 0.8001)
					(clearance 0.1524)
				)
				(layer "B.Cu"
					(shape circle)
					(size 1.9939 1.9939)
					(clearance 0.10795)
				)
			)
		)
		(pad "4" thru_hole circle
			(at 0 2.54 270)
			(size 1.0033 1.0033)
			(drill 0.249936)
			(layers "*.Cu" "*.Mask")
			(remove_unused_layers no)
			(net "TDR_DIFF_100_IN1_DP")
			(clearance 0.10795)
			(thermal_gap 0.10795)
			(padstack
				(mode front_inner_back)
				(layer "Inner"
					(shape circle)
					(size 0.8001 0.8001)
					(clearance 0.1524)
				)
				(layer "B.Cu"
					(shape circle)
					(size 1.0033 1.0033)
					(clearance 0.10795)
				)
			)
		)
	)
	(footprint ""
		(layer "F.Cu")
		(at 306.090574 -426.179742)
		(property "Reference" "R4264"
			(at 0 0 0)
			(layer "F.SilkS")
			(hide yes)
			(effects
				(font
					(size 1.27 1.27)
				)
			)
		)
		(property "Value" ""
			(at 0 0 0)
			(layer "F.Fab")
			(effects
				(font
					(size 1.27 1.27)
				)
			)
		)
		(duplicate_pad_numbers_are_jumpers no)
		(fp_line
			(start -0.7874 -0.4064)
			(end 0.7874 -0.4064)
			(stroke
				(width 0.1524)
				(type default)
			)
			(layer "F.SilkS")
		)
		(fp_line
			(start -0.7874 0.4064)
			(end -0.7874 -0.4064)
			(stroke
				(width 0.1524)
				(type default)
			)
			(layer "F.SilkS")
		)
		(fp_line
			(start 0.7874 -0.4064)
			(end 0.7874 0.4064)
			(stroke
				(width 0.1524)
				(type default)
			)
			(layer "F.SilkS")
		)
		(fp_line
			(start 0.7874 0.4064)
			(end -0.7874 0.4064)
			(stroke
				(width 0.1524)
				(type default)
			)
			(layer "F.SilkS")
		)
		(fp_line
			(start -0.67945 -0.305054)
			(end -0.12065 -0.305054)
			(stroke
				(width 0.1)
				(type default)
			)
			(layer "F.Fab")
		)
		(fp_line
			(start -0.67945 0.3048)
			(end -0.67945 -0.305054)
			(stroke
				(width 0.1)
				(type default)
			)
			(layer "F.Fab")
		)
		(fp_line
			(start -0.12065 -0.305054)
			(end -0.12065 -0.2794)
			(stroke
				(width 0.1)
				(type default)
			)
			(layer "F.Fab")
		)
		(fp_line
			(start -0.12065 -0.2794)
			(end 0.12065 -0.2794)
			(stroke
				(width 0.1)
				(type default)
			)
			(layer "F.Fab")
		)
		(fp_line
			(start -0.12065 0.2794)
			(end -0.12065 0.3048)
			(stroke
				(width 0.1)
				(type default)
			)
			(layer "F.Fab")
		)
		(fp_line
			(start -0.12065 0.3048)
			(end -0.67945 0.3048)
			(stroke
				(width 0.1)
				(type default)
			)
			(layer "F.Fab")
		)
		(fp_line
			(start 0.120396 0.2794)
			(end -0.12065 0.2794)
			(stroke
				(width 0.1)
				(type default)
			)
			(layer "F.Fab")
		)
		(fp_line
			(start 0.120396 0.3048)
			(end 0.120396 0.2794)
			(stroke
				(width 0.1)
				(type default)
			)
			(layer "F.Fab")
		)
		(fp_line
			(start 0.12065 -0.3048)
			(end 0.67945 -0.3048)
			(stroke
				(width 0.1)
				(type default)
			)
			(layer "F.Fab")
		)
		(fp_line
			(start 0.12065 -0.2794)
			(end 0.12065 -0.3048)
			(stroke
				(width 0.1)
				(type default)
			)
			(layer "F.Fab")
		)
		(fp_line
			(start 0.67945 -0.3048)
			(end 0.67945 0.3048)
			(stroke
				(width 0.1)
				(type default)
			)
			(layer "F.Fab")
		)
		(fp_line
			(start 0.67945 0.3048)
			(end 0.120396 0.3048)
			(stroke
				(width 0.1)
				(type default)
			)
			(layer "F.Fab")
		)
		(pad "1" smd circle
			(at -0.40005 0)
			(size 0 0)
			(layers "F.Cu" "F.Mask" "F.Paste")
			(net "P3V3_AUX")
		)
		(pad "2" smd circle
			(at 0.40005 0)
			(size 0 0)
			(layers "F.Cu" "F.Mask" "F.Paste")
			(net "PWRGD_P3V3_AUX_PDB_BUF_R")
		)
	)
	(footprint ""
		(layer "F.Cu")
		(at 413.520382 -29.877258)
		(property "Reference" "R1335"
			(at 0 0 0)
			(layer "F.SilkS")
			(hide yes)
			(effects
				(font
					(size 1.27 1.27)
				)
			)
		)
		(property "Value" ""
			(at 0 0 0)
			(layer "F.Fab")
			(effects
				(font
					(size 1.27 1.27)
				)
			)
		)
		(duplicate_pad_numbers_are_jumpers no)
		(fp_line
			(start -0.7874 -0.4064)
			(end 0.7874 -0.4064)
			(stroke
				(width 0.1524)
				(type default)
			)
			(layer "F.SilkS")
		)
		(fp_line
			(start -0.7874 0.4064)
			(end -0.7874 -0.4064)
			(stroke
				(width 0.1524)
				(type default)
			)
			(layer "F.SilkS")
		)
		(fp_line
			(start 0.7874 -0.4064)
			(end 0.7874 0.4064)
			(stroke
				(width 0.1524)
				(type default)
			)
			(layer "F.SilkS")
		)
		(fp_line
			(start 0.7874 0.4064)
			(end -0.7874 0.4064)
			(stroke
				(width 0.1524)
				(type default)
			)
			(layer "F.SilkS")
		)
		(fp_line
			(start -0.67945 -0.305054)
			(end -0.12065 -0.305054)
			(stroke
				(width 0.1)
				(type default)
			)
			(layer "F.Fab")
		)
		(fp_line
			(start -0.67945 0.3048)
			(end -0.67945 -0.305054)
			(stroke
				(width 0.1)
				(type default)
			)
			(layer "F.Fab")
		)
		(fp_line
			(start -0.12065 -0.305054)
			(end -0.12065 -0.2794)
			(stroke
				(width 0.1)
				(type default)
			)
			(layer "F.Fab")
		)
		(fp_line
			(start -0.12065 -0.2794)
			(end 0.12065 -0.2794)
			(stroke
				(width 0.1)
				(type default)
			)
			(layer "F.Fab")
		)
		(fp_line
			(start -0.12065 0.2794)
			(end -0.12065 0.3048)
			(stroke
				(width 0.1)
				(type default)
			)
			(layer "F.Fab")
		)
		(fp_line
			(start -0.12065 0.3048)
			(end -0.67945 0.3048)
			(stroke
				(width 0.1)
				(type default)
			)
			(layer "F.Fab")
		)
		(fp_line
			(start 0.120396 0.2794)
			(end -0.12065 0.2794)
			(stroke
				(width 0.1)
				(type default)
			)
			(layer "F.Fab")
		)
		(fp_line
			(start 0.120396 0.3048)
			(end 0.120396 0.2794)
			(stroke
				(width 0.1)
				(type default)
			)
			(layer "F.Fab")
		)
		(fp_line
			(start 0.12065 -0.3048)
			(end 0.67945 -0.3048)
			(stroke
				(width 0.1)
				(type default)
			)
			(layer "F.Fab")
		)
		(fp_line
			(start 0.12065 -0.2794)
			(end 0.12065 -0.3048)
			(stroke
				(width 0.1)
				(type default)
			)
			(layer "F.Fab")
		)
		(fp_line
			(start 0.67945 -0.3048)
			(end 0.67945 0.3048)
			(stroke
				(width 0.1)
				(type default)
			)
			(layer "F.Fab")
		)
		(fp_line
			(start 0.67945 0.3048)
			(end 0.120396 0.3048)
			(stroke
				(width 0.1)
				(type default)
			)
			(layer "F.Fab")
		)
		(pad "1" smd circle
			(at -0.40005 0)
			(size 0 0)
			(layers "F.Cu" "F.Mask" "F.Paste")
			(net "GND")
		)
		(pad "2" smd circle
			(at 0.40005 0)
			(size 0 0)
			(layers "F.Cu" "F.Mask" "F.Paste")
			(net "PD_PASSWORD_CLEAR")
		)
	)
	(footprint ""
		(layer "F.Cu")
		(at 90.839798 -402.371052 -90)
		(property "Reference" "C738"
			(at 0 0 270)
			(layer "F.SilkS")
			(hide yes)
			(effects
				(font
					(size 1.27 1.27)
				)
			)
		)
		(property "Value" ""
			(at 0 0 270)
			(layer "F.Fab")
			(effects
				(font
					(size 1.27 1.27)
				)
			)
		)
		(duplicate_pad_numbers_are_jumpers no)
		(fp_line
			(start -0.299974 0.150114)
			(end -0.299974 -0.150114)
			(stroke
				(width 0.1)
				(type default)
			)
			(layer "F.Fab")
		)
		(fp_line
			(start 0.299974 0.150114)
			(end -0.299974 0.150114)
			(stroke
				(width 0.1)
				(type default)
			)
			(layer "F.Fab")
		)
		(fp_line
			(start -0.299974 -0.150114)
			(end 0.299974 -0.150114)
			(stroke
				(width 0.1)
				(type default)
			)
			(layer "F.Fab")
		)
		(fp_line
			(start 0.299974 -0.150114)
			(end 0.299974 0.150114)
			(stroke
				(width 0.1)
				(type default)
			)
			(layer "F.Fab")
		)
		(pad "1" smd rect
			(at -0.2667 0 270)
			(size 0.3048 0.381)
			(layers "F.Cu" "F.Mask" "F.Paste")
			(net "P5E_CPU1_PE0_TX_C_DN<1>")
		)
		(pad "2" smd rect
			(at 0.2667 0 270)
			(size 0.3048 0.381)
			(layers "F.Cu" "F.Mask" "F.Paste")
			(net "P5E_CPU1_PE0_TX_DN<1>")
		)
	)
	(footprint ""
		(layer "F.Cu")
		(at 17.045432 -107.123484)
		(property "Reference" "R4483"
			(at 0 0 0)
			(layer "F.SilkS")
			(hide yes)
			(effects
				(font
					(size 1.27 1.27)
				)
			)
		)
		(property "Value" ""
			(at 0 0 0)
			(layer "F.Fab")
			(effects
				(font
					(size 1.27 1.27)
				)
			)
		)
		(duplicate_pad_numbers_are_jumpers no)
		(fp_line
			(start 0.015748 -0.4064)
			(end 0.7874 -0.4064)
			(stroke
				(width 0.1524)
				(type default)
			)
			(layer "F.SilkS")
		)
		(fp_line
			(start 0.7874 -0.4064)
			(end 0.7874 0.4064)
			(stroke
				(width 0.1524)
				(type default)
			)
			(layer "F.SilkS")
		)
		(fp_line
			(start 0.7874 0.4064)
			(end 0.028448 0.4064)
			(stroke
				(width 0.1524)
				(type default)
			)
			(layer "F.SilkS")
		)
		(fp_line
			(start -0.67945 -0.305054)
			(end -0.12065 -0.305054)
			(stroke
				(width 0.1)
				(type default)
			)
			(layer "F.Fab")
		)
		(fp_line
			(start -0.67945 0.3048)
			(end -0.67945 -0.305054)
			(stroke
				(width 0.1)
				(type default)
			)
			(layer "F.Fab")
		)
		(fp_line
			(start -0.12065 -0.305054)
			(end -0.12065 -0.2794)
			(stroke
				(width 0.1)
				(type default)
			)
			(layer "F.Fab")
		)
		(fp_line
			(start -0.12065 -0.2794)
			(end 0.12065 -0.2794)
			(stroke
				(width 0.1)
				(type default)
			)
			(layer "F.Fab")
		)
		(fp_line
			(start -0.12065 0.2794)
			(end -0.12065 0.3048)
			(stroke
				(width 0.1)
				(type default)
			)
			(layer "F.Fab")
		)
		(fp_line
			(start -0.12065 0.3048)
			(end -0.67945 0.3048)
			(stroke
				(width 0.1)
				(type default)
			)
			(layer "F.Fab")
		)
		(fp_line
			(start 0.120396 0.2794)
			(end -0.12065 0.2794)
			(stroke
				(width 0.1)
				(type default)
			)
			(layer "F.Fab")
		)
		(fp_line
			(start 0.120396 0.3048)
			(end 0.120396 0.2794)
			(stroke
				(width 0.1)
				(type default)
			)
			(layer "F.Fab")
		)
		(fp_line
			(start 0.12065 -0.3048)
			(end 0.67945 -0.3048)
			(stroke
				(width 0.1)
				(type default)
			)
			(layer "F.Fab")
		)
		(fp_line
			(start 0.12065 -0.2794)
			(end 0.12065 -0.3048)
			(stroke
				(width 0.1)
				(type default)
			)
			(layer "F.Fab")
		)
		(fp_line
			(start 0.67945 -0.3048)
			(end 0.67945 0.3048)
			(stroke
				(width 0.1)
				(type default)
			)
			(layer "F.Fab")
		)
		(fp_line
			(start 0.67945 0.3048)
			(end 0.120396 0.3048)
			(stroke
				(width 0.1)
				(type default)
			)
			(layer "F.Fab")
		)
		(pad "1" smd circle
			(at -0.40005 0)
			(size 0 0)
			(layers "F.Cu" "F.Mask" "F.Paste")
			(net "USB2_HOST_BMC_B_BUF_DN")
		)
		(pad "2" smd circle
			(at 0.40005 0)
			(size 0 0)
			(layers "F.Cu" "F.Mask" "F.Paste")
			(net "GND")
		)
	)
	(footprint ""
		(layer "F.Cu")
		(at 63.30188 -16.220948 -90)
		(property "Reference" "R3169"
			(at 0 0 270)
			(layer "F.SilkS")
			(hide yes)
			(effects
				(font
					(size 1.27 1.27)
				)
			)
		)
		(property "Value" ""
			(at 0 0 270)
			(layer "F.Fab")
			(effects
				(font
					(size 1.27 1.27)
				)
			)
		)
		(duplicate_pad_numbers_are_jumpers no)
		(fp_line
			(start -0.7874 0.4064)
			(end -0.7874 -0.4064)
			(stroke
				(width 0.1524)
				(type default)
			)
			(layer "F.SilkS")
		)
		(fp_line
			(start 0.7874 0.4064)
			(end -0.7874 0.4064)
			(stroke
				(width 0.1524)
				(type default)
			)
			(layer "F.SilkS")
		)
		(fp_line
			(start -0.7874 -0.4064)
			(end 0.7874 -0.4064)
			(stroke
				(width 0.1524)
				(type default)
			)
			(layer "F.SilkS")
		)
		(fp_line
			(start 0.7874 -0.4064)
			(end 0.7874 0.4064)
			(stroke
				(width 0.1524)
				(type default)
			)
			(layer "F.SilkS")
		)
		(fp_line
			(start -0.67945 0.3048)
			(end -0.67945 -0.305054)
			(stroke
				(width 0.1)
				(type default)
			)
			(layer "F.Fab")
		)
		(fp_line
			(start -0.12065 0.3048)
			(end -0.67945 0.3048)
			(stroke
				(width 0.1)
				(type default)
			)
			(layer "F.Fab")
		)
		(fp_line
			(start 0.120396 0.3048)
			(end 0.120396 0.2794)
			(stroke
				(width 0.1)
				(type default)
			)
			(layer "F.Fab")
		)
		(fp_line
			(start 0.67945 0.3048)
			(end 0.120396 0.3048)
			(stroke
				(width 0.1)
				(type default)
			)
			(layer "F.Fab")
		)
		(fp_line
			(start -0.12065 0.2794)
			(end -0.12065 0.3048)
			(stroke
				(width 0.1)
				(type default)
			)
			(layer "F.Fab")
		)
		(fp_line
			(start 0.120396 0.2794)
			(end -0.12065 0.2794)
			(stroke
				(width 0.1)
				(type default)
			)
			(layer "F.Fab")
		)
		(fp_line
			(start -0.12065 -0.2794)
			(end 0.12065 -0.2794)
			(stroke
				(width 0.1)
				(type default)
			)
			(layer "F.Fab")
		)
		(fp_line
			(start 0.12065 -0.2794)
			(end 0.12065 -0.3048)
			(stroke
				(width 0.1)
				(type default)
			)
			(layer "F.Fab")
		)
		(fp_line
			(start 0.12065 -0.3048)
			(end 0.67945 -0.3048)
			(stroke
				(width 0.1)
				(type default)
			)
			(layer "F.Fab")
		)
		(fp_line
			(start 0.67945 -0.3048)
			(end 0.67945 0.3048)
			(stroke
				(width 0.1)
				(type default)
			)
			(layer "F.Fab")
		)
		(fp_line
			(start -0.67945 -0.305054)
			(end -0.12065 -0.305054)
			(stroke
				(width 0.1)
				(type default)
			)
			(layer "F.Fab")
		)
		(fp_line
			(start -0.12065 -0.305054)
			(end -0.12065 -0.2794)
			(stroke
				(width 0.1)
				(type default)
			)
			(layer "F.Fab")
		)
		(pad "1" smd circle
			(at -0.40005 0 270)
			(size 0 0)
			(layers "F.Cu" "F.Mask" "F.Paste")
			(net "OCP_V3_2_ISO_BIF0_EN")
		)
		(pad "2" smd circle
			(at 0.40005 0 270)
			(size 0 0)
			(layers "F.Cu" "F.Mask" "F.Paste")
			(net "OCP_V3_2_BIF0_R_N")
		)
	)
	(footprint ""
		(layer "F.Cu")
		(at 181.80812 -411.20822 -90)
		(property "Reference" "C2388"
			(at 0 0 270)
			(layer "F.SilkS")
			(hide yes)
			(effects
				(font
					(size 1.27 1.27)
				)
			)
		)
		(property "Value" ""
			(at 0 0 270)
			(layer "F.Fab")
			(effects
				(font
					(size 1.27 1.27)
				)
			)
		)
		(duplicate_pad_numbers_are_jumpers no)
		(fp_line
			(start -0.7874 0.4064)
			(end -0.7874 -0.4064)
			(stroke
				(width 0.1524)
				(type default)
			)
			(layer "F.SilkS")
		)
		(fp_line
			(start 0.7874 0.4064)
			(end -0.7874 0.4064)
			(stroke
				(width 0.1524)
				(type default)
			)
			(layer "F.SilkS")
		)
		(fp_line
			(start -0.7874 -0.4064)
			(end 0.7874 -0.4064)
			(stroke
				(width 0.1524)
				(type default)
			)
			(layer "F.SilkS")
		)
		(fp_line
			(start 0.7874 -0.4064)
			(end 0.7874 0.4064)
			(stroke
				(width 0.1524)
				(type default)
			)
			(layer "F.SilkS")
		)
		(fp_line
			(start -0.67945 0.3048)
			(end -0.67945 -0.305054)
			(stroke
				(width 0.1)
				(type default)
			)
			(layer "F.Fab")
		)
		(fp_line
			(start -0.12065 0.3048)
			(end -0.67945 0.3048)
			(stroke
				(width 0.1)
				(type default)
			)
			(layer "F.Fab")
		)
		(fp_line
			(start 0.120396 0.3048)
			(end 0.120396 0.2794)
			(stroke
				(width 0.1)
				(type default)
			)
			(layer "F.Fab")
		)
		(fp_line
			(start 0.67945 0.3048)
			(end 0.120396 0.3048)
			(stroke
				(width 0.1)
				(type default)
			)
			(layer "F.Fab")
		)
		(fp_line
			(start -0.12065 0.2794)
			(end -0.12065 0.3048)
			(stroke
				(width 0.1)
				(type default)
			)
			(layer "F.Fab")
		)
		(fp_line
			(start 0.120396 0.2794)
			(end -0.12065 0.2794)
			(stroke
				(width 0.1)
				(type default)
			)
			(layer "F.Fab")
		)
		(fp_line
			(start -0.12065 -0.2794)
			(end 0.12065 -0.2794)
			(stroke
				(width 0.1)
				(type default)
			)
			(layer "F.Fab")
		)
		(fp_line
			(start 0.12065 -0.2794)
			(end 0.12065 -0.3048)
			(stroke
				(width 0.1)
				(type default)
			)
			(layer "F.Fab")
		)
		(fp_line
			(start 0.12065 -0.3048)
			(end 0.67945 -0.3048)
			(stroke
				(width 0.1)
				(type default)
			)
			(layer "F.Fab")
		)
		(fp_line
			(start 0.67945 -0.3048)
			(end 0.67945 0.3048)
			(stroke
				(width 0.1)
				(type default)
			)
			(layer "F.Fab")
		)
		(fp_line
			(start -0.67945 -0.305054)
			(end -0.12065 -0.305054)
			(stroke
				(width 0.1)
				(type default)
			)
			(layer "F.Fab")
		)
		(fp_line
			(start -0.12065 -0.305054)
			(end -0.12065 -0.2794)
			(stroke
				(width 0.1)
				(type default)
			)
			(layer "F.Fab")
		)
		(pad "1" smd circle
			(at -0.40005 0 270)
			(size 0 0)
			(layers "F.Cu" "F.Mask" "F.Paste")
			(net "OC_P2V5_COMP")
		)
		(pad "2" smd circle
			(at 0.40005 0 270)
			(size 0 0)
			(layers "F.Cu" "F.Mask" "F.Paste")
			(net "GND")
		)
	)
	(footprint ""
		(layer "F.Cu")
		(at 183.45658 -414.76422 90)
		(property "Reference" "U344"
			(at -0.2413 -3.16611 90)
			(unlocked yes)
			(layer "F.SilkS")
			(effects
				(font
					(size 0.7874 0.5842)
					(thickness 0.1524)
				)
			)
		)
		(property "Value" ""
			(at 0 0 90)
			(layer "F.Fab")
			(effects
				(font
					(size 1.27 1.27)
				)
			)
		)
		(duplicate_pad_numbers_are_jumpers no)
		(fp_line
			(start 2.032 -1.549908)
			(end 2.032 1.549908)
			(stroke
				(width 0.1524)
				(type default)
			)
			(layer "F.SilkS")
		)
		(fp_line
			(start 0.508 -1.549908)
			(end 2.032 -1.549908)
			(stroke
				(width 0.1524)
				(type default)
			)
			(layer "F.SilkS")
		)
		(fp_line
			(start -0.508 -1.549908)
			(end 0 -0.762)
			(stroke
				(width 0.1524)
				(type default)
			)
			(layer "F.SilkS")
		)
		(fp_line
			(start -2.032 -1.549908)
			(end -0.508 -1.549908)
			(stroke
				(width 0.1524)
				(type default)
			)
			(layer "F.SilkS")
		)
		(fp_line
			(start 0 -0.762)
			(end 0.508 -1.549908)
			(stroke
				(width 0.1524)
				(type default)
			)
			(layer "F.SilkS")
		)
		(fp_line
			(start 2.032 1.549908)
			(end -2.032 1.549908)
			(stroke
				(width 0.1524)
				(type default)
			)
			(layer "F.SilkS")
		)
		(fp_line
			(start -2.032 1.549908)
			(end -2.032 -1.549908)
			(stroke
				(width 0.1524)
				(type default)
			)
			(layer "F.SilkS")
		)
		(fp_poly
			(pts
				(xy -1.390396 -2.629408) (xy -2.406396 -2.629154) (xy -1.898396 -1.613408)
			)
			(stroke
				(width 0)
				(type default)
			)
			(fill yes)
			(layer "F.SilkS")
		)
		(fp_line
			(start 0.849884 -1.549908)
			(end 0.849884 1.549908)
			(stroke
				(width 0.1)
				(type default)
			)
			(layer "F.Fab")
		)
		(fp_line
			(start -0.849884 -1.549908)
			(end 0.849884 -1.549908)
			(stroke
				(width 0.1)
				(type default)
			)
			(layer "F.Fab")
		)
		(fp_line
			(start 0.849884 1.549908)
			(end -0.849884 1.549908)
			(stroke
				(width 0.1)
				(type default)
			)
			(layer "F.Fab")
		)
		(fp_line
			(start -0.849884 1.549908)
			(end -0.849884 -1.549908)
			(stroke
				(width 0.1)
				(type default)
			)
			(layer "F.Fab")
		)
		(fp_poly
			(pts
				(xy -3.2004 -1.45796) (xy -3.2004 -0.44196) (xy -2.1844 -0.94996)
			)
			(stroke
				(width 0)
				(type default)
			)
			(fill yes)
			(layer "F.Fab")
		)
		(pad "1" smd rect
			(at -1.35001 -0.94996)
			(size 0.6096 1.0668)
			(layers "F.Cu" "F.Mask" "F.Paste")
			(net "OC_P2V5_COMP")
		)
		(pad "2" smd rect
			(at -1.35001 0)
			(size 0.6096 1.0668)
			(layers "F.Cu" "F.Mask" "F.Paste")
			(net "GND")
		)
		(pad "3" smd rect
			(at -1.35001 0.94996)
			(size 0.6096 1.0668)
			(layers "F.Cu" "F.Mask" "F.Paste")
			(net "HSC_OC_VOL")
		)
		(pad "4" smd rect
			(at 1.35001 0.94996)
			(size 0.6096 1.0668)
			(layers "F.Cu" "F.Mask" "F.Paste")
			(net "HSC_D_OC_R2")
		)
		(pad "5" smd rect
			(at 1.35001 -0.94996)
			(size 0.6096 1.0668)
			(layers "F.Cu" "F.Mask" "F.Paste")
			(net "P12V_AUX")
		)
	)
	(footprint ""
		(layer "F.Cu")
		(at 105.306114 -258.72694 90)
		(property "Reference" "C443"
			(at 0 0 90)
			(layer "F.SilkS")
			(hide yes)
			(effects
				(font
					(size 1.27 1.27)
				)
			)
		)
		(property "Value" ""
			(at 0 0 90)
			(layer "F.Fab")
			(effects
				(font
					(size 1.27 1.27)
				)
			)
		)
		(duplicate_pad_numbers_are_jumpers no)
		(fp_line
			(start 0.7874 -0.4064)
			(end 0.7874 0.4064)
			(stroke
				(width 0.1524)
				(type default)
			)
			(layer "F.SilkS")
		)
		(fp_line
			(start -0.7874 -0.4064)
			(end 0.7874 -0.4064)
			(stroke
				(width 0.1524)
				(type default)
			)
			(layer "F.SilkS")
		)
		(fp_line
			(start 0.7874 0.4064)
			(end -0.7874 0.4064)
			(stroke
				(width 0.1524)
				(type default)
			)
			(layer "F.SilkS")
		)
		(fp_line
			(start -0.7874 0.4064)
			(end -0.7874 -0.4064)
			(stroke
				(width 0.1524)
				(type default)
			)
			(layer "F.SilkS")
		)
		(fp_line
			(start -0.12065 -0.305054)
			(end -0.12065 -0.2794)
			(stroke
				(width 0.1)
				(type default)
			)
			(layer "F.Fab")
		)
		(fp_line
			(start -0.67945 -0.305054)
			(end -0.12065 -0.305054)
			(stroke
				(width 0.1)
				(type default)
			)
			(layer "F.Fab")
		)
		(fp_line
			(start 0.67945 -0.3048)
			(end 0.67945 0.3048)
			(stroke
				(width 0.1)
				(type default)
			)
			(layer "F.Fab")
		)
		(fp_line
			(start 0.12065 -0.3048)
			(end 0.67945 -0.3048)
			(stroke
				(width 0.1)
				(type default)
			)
			(layer "F.Fab")
		)
		(fp_line
			(start 0.12065 -0.2794)
			(end 0.12065 -0.3048)
			(stroke
				(width 0.1)
				(type default)
			)
			(layer "F.Fab")
		)
		(fp_line
			(start -0.12065 -0.2794)
			(end 0.12065 -0.2794)
			(stroke
				(width 0.1)
				(type default)
			)
			(layer "F.Fab")
		)
		(fp_line
			(start 0.120396 0.2794)
			(end -0.12065 0.2794)
			(stroke
				(width 0.1)
				(type default)
			)
			(layer "F.Fab")
		)
		(fp_line
			(start -0.12065 0.2794)
			(end -0.12065 0.3048)
			(stroke
				(width 0.1)
				(type default)
			)
			(layer "F.Fab")
		)
		(fp_line
			(start 0.67945 0.3048)
			(end 0.120396 0.3048)
			(stroke
				(width 0.1)
				(type default)
			)
			(layer "F.Fab")
		)
		(fp_line
			(start 0.120396 0.3048)
			(end 0.120396 0.2794)
			(stroke
				(width 0.1)
				(type default)
			)
			(layer "F.Fab")
		)
		(fp_line
			(start -0.12065 0.3048)
			(end -0.67945 0.3048)
			(stroke
				(width 0.1)
				(type default)
			)
			(layer "F.Fab")
		)
		(fp_line
			(start -0.67945 0.3048)
			(end -0.67945 -0.305054)
			(stroke
				(width 0.1)
				(type default)
			)
			(layer "F.Fab")
		)
		(pad "1" smd circle
			(at -0.40005 0 90)
			(size 0 0)
			(layers "F.Cu" "F.Mask" "F.Paste")
			(net "PVCCFA_EHV_CPU1")
		)
		(pad "2" smd circle
			(at 0.40005 0 90)
			(size 0 0)
			(layers "F.Cu" "F.Mask" "F.Paste")
			(net "GND")
		)
	)
	(footprint ""
		(layer "F.Cu")
		(at 80.31861 -152.381204)
		(property "Reference" "R677"
			(at 0 0 0)
			(layer "F.SilkS")
			(hide yes)
			(effects
				(font
					(size 1.27 1.27)
				)
			)
		)
		(property "Value" ""
			(at 0 0 0)
			(layer "F.Fab")
			(effects
				(font
					(size 1.27 1.27)
				)
			)
		)
		(duplicate_pad_numbers_are_jumpers no)
		(fp_line
			(start -0.7874 -0.4064)
			(end 0.7874 -0.4064)
			(stroke
				(width 0.1524)
				(type default)
			)
			(layer "F.SilkS")
		)
		(fp_line
			(start -0.7874 0.4064)
			(end -0.7874 -0.4064)
			(stroke
				(width 0.1524)
				(type default)
			)
			(layer "F.SilkS")
		)
		(fp_line
			(start 0.7874 -0.4064)
			(end 0.7874 0.4064)
			(stroke
				(width 0.1524)
				(type default)
			)
			(layer "F.SilkS")
		)
		(fp_line
			(start 0.7874 0.4064)
			(end -0.7874 0.4064)
			(stroke
				(width 0.1524)
				(type default)
			)
			(layer "F.SilkS")
		)
		(fp_line
			(start -0.67945 -0.305054)
			(end -0.12065 -0.305054)
			(stroke
				(width 0.1)
				(type default)
			)
			(layer "F.Fab")
		)
		(fp_line
			(start -0.67945 0.3048)
			(end -0.67945 -0.305054)
			(stroke
				(width 0.1)
				(type default)
			)
			(layer "F.Fab")
		)
		(fp_line
			(start -0.12065 -0.305054)
			(end -0.12065 -0.2794)
			(stroke
				(width 0.1)
				(type default)
			)
			(layer "F.Fab")
		)
		(fp_line
			(start -0.12065 -0.2794)
			(end 0.12065 -0.2794)
			(stroke
				(width 0.1)
				(type default)
			)
			(layer "F.Fab")
		)
		(fp_line
			(start -0.12065 0.2794)
			(end -0.12065 0.3048)
			(stroke
				(width 0.1)
				(type default)
			)
			(layer "F.Fab")
		)
		(fp_line
			(start -0.12065 0.3048)
			(end -0.67945 0.3048)
			(stroke
				(width 0.1)
				(type default)
			)
			(layer "F.Fab")
		)
		(fp_line
			(start 0.120396 0.2794)
			(end -0.12065 0.2794)
			(stroke
				(width 0.1)
				(type default)
			)
			(layer "F.Fab")
		)
		(fp_line
			(start 0.120396 0.3048)
			(end 0.120396 0.2794)
			(stroke
				(width 0.1)
				(type default)
			)
			(layer "F.Fab")
		)
		(fp_line
			(start 0.12065 -0.3048)
			(end 0.67945 -0.3048)
			(stroke
				(width 0.1)
				(type default)
			)
			(layer "F.Fab")
		)
		(fp_line
			(start 0.12065 -0.2794)
			(end 0.12065 -0.3048)
			(stroke
				(width 0.1)
				(type default)
			)
			(layer "F.Fab")
		)
		(fp_line
			(start 0.67945 -0.3048)
			(end 0.67945 0.3048)
			(stroke
				(width 0.1)
				(type default)
			)
			(layer "F.Fab")
		)
		(fp_line
			(start 0.67945 0.3048)
			(end 0.120396 0.3048)
			(stroke
				(width 0.1)
				(type default)
			)
			(layer "F.Fab")
		)
		(pad "1" smd circle
			(at -0.40005 0)
			(size 0 0)
			(layers "F.Cu" "F.Mask" "F.Paste")
			(net "I3C_SPD_DDREFGH_CPU1_LVC1_R_SDA")
		)
		(pad "2" smd circle
			(at 0.40005 0)
			(size 0 0)
			(layers "F.Cu" "F.Mask" "F.Paste")
			(net "I3C_SPD_DDREFGH_CPU1_LVC1_SDA")
		)
	)
	(footprint ""
		(layer "F.Cu")
		(at 31.29788 -426.303948)
		(property "Reference" "R3469"
			(at 0 0 0)
			(layer "F.SilkS")
			(hide yes)
			(effects
				(font
					(size 1.27 1.27)
				)
			)
		)
		(property "Value" ""
			(at 0 0 0)
			(layer "F.Fab")
			(effects
				(font
					(size 1.27 1.27)
				)
			)
		)
		(duplicate_pad_numbers_are_jumpers no)
		(fp_line
			(start -0.7874 -0.4064)
			(end 0.7874 -0.4064)
			(stroke
				(width 0.1524)
				(type default)
			)
			(layer "F.SilkS")
		)
		(fp_line
			(start -0.7874 0.4064)
			(end -0.7874 -0.4064)
			(stroke
				(width 0.1524)
				(type default)
			)
			(layer "F.SilkS")
		)
		(fp_line
			(start 0.7874 -0.4064)
			(end 0.7874 0.4064)
			(stroke
				(width 0.1524)
				(type default)
			)
			(layer "F.SilkS")
		)
		(fp_line
			(start 0.7874 0.4064)
			(end -0.7874 0.4064)
			(stroke
				(width 0.1524)
				(type default)
			)
			(layer "F.SilkS")
		)
		(fp_line
			(start -0.67945 -0.305054)
			(end -0.12065 -0.305054)
			(stroke
				(width 0.1)
				(type default)
			)
			(layer "F.Fab")
		)
		(fp_line
			(start -0.67945 0.3048)
			(end -0.67945 -0.305054)
			(stroke
				(width 0.1)
				(type default)
			)
			(layer "F.Fab")
		)
		(fp_line
			(start -0.12065 -0.305054)
			(end -0.12065 -0.2794)
			(stroke
				(width 0.1)
				(type default)
			)
			(layer "F.Fab")
		)
		(fp_line
			(start -0.12065 -0.2794)
			(end 0.12065 -0.2794)
			(stroke
				(width 0.1)
				(type default)
			)
			(layer "F.Fab")
		)
		(fp_line
			(start -0.12065 0.2794)
			(end -0.12065 0.3048)
			(stroke
				(width 0.1)
				(type default)
			)
			(layer "F.Fab")
		)
		(fp_line
			(start -0.12065 0.3048)
			(end -0.67945 0.3048)
			(stroke
				(width 0.1)
				(type default)
			)
			(layer "F.Fab")
		)
		(fp_line
			(start 0.120396 0.2794)
			(end -0.12065 0.2794)
			(stroke
				(width 0.1)
				(type default)
			)
			(layer "F.Fab")
		)
		(fp_line
			(start 0.120396 0.3048)
			(end 0.120396 0.2794)
			(stroke
				(width 0.1)
				(type default)
			)
			(layer "F.Fab")
		)
		(fp_line
			(start 0.12065 -0.3048)
			(end 0.67945 -0.3048)
			(stroke
				(width 0.1)
				(type default)
			)
			(layer "F.Fab")
		)
		(fp_line
			(start 0.12065 -0.2794)
			(end 0.12065 -0.3048)
			(stroke
				(width 0.1)
				(type default)
			)
			(layer "F.Fab")
		)
		(fp_line
			(start 0.67945 -0.3048)
			(end 0.67945 0.3048)
			(stroke
				(width 0.1)
				(type default)
			)
			(layer "F.Fab")
		)
		(fp_line
			(start 0.67945 0.3048)
			(end 0.120396 0.3048)
			(stroke
				(width 0.1)
				(type default)
			)
			(layer "F.Fab")
		)
		(pad "1" smd circle
			(at -0.40005 0)
			(size 0 0)
			(layers "F.Cu" "F.Mask" "F.Paste")
			(net "RST_PERST_0_SWB_BUF_R_N")
		)
		(pad "2" smd circle
			(at 0.40005 0)
			(size 0 0)
			(layers "F.Cu" "F.Mask" "F.Paste")
			(net "RST_PERST_0_SWB_BUF_N")
		)
	)
	(footprint ""
		(layer "F.Cu")
		(at 62.996572 -169.6085 180)
		(property "Reference" "PC381"
			(at 0 0 180)
			(layer "F.SilkS")
			(hide yes)
			(effects
				(font
					(size 1.27 1.27)
				)
			)
		)
		(property "Value" ""
			(at 0 0 180)
			(layer "F.Fab")
			(effects
				(font
					(size 1.27 1.27)
				)
			)
		)
		(duplicate_pad_numbers_are_jumpers no)
		(fp_line
			(start 1.524 0.762)
			(end -1.524 0.762)
			(stroke
				(width 0.1524)
				(type default)
			)
			(layer "F.SilkS")
		)
		(fp_line
			(start 1.524 -0.762)
			(end 1.524 0.762)
			(stroke
				(width 0.1524)
				(type default)
			)
			(layer "F.SilkS")
		)
		(fp_line
			(start -1.524 0.762)
			(end -1.524 -0.762)
			(stroke
				(width 0.1524)
				(type default)
			)
			(layer "F.SilkS")
		)
		(fp_line
			(start -1.524 -0.762)
			(end 1.524 -0.762)
			(stroke
				(width 0.1524)
				(type default)
			)
			(layer "F.SilkS")
		)
		(fp_line
			(start 1.1049 0.724916)
			(end 1.1049 -0.724916)
			(stroke
				(width 0.1)
				(type default)
			)
			(layer "F.Fab")
		)
		(fp_line
			(start 1.1049 -0.724916)
			(end -1.1049 -0.724916)
			(stroke
				(width 0.1)
				(type default)
			)
			(layer "F.Fab")
		)
		(fp_line
			(start -1.1049 0.724916)
			(end 1.1049 0.724916)
			(stroke
				(width 0.1)
				(type default)
			)
			(layer "F.Fab")
		)
		(fp_line
			(start -1.1049 -0.724916)
			(end -1.1049 0.724916)
			(stroke
				(width 0.1)
				(type default)
			)
			(layer "F.Fab")
		)
		(pad "1" smd rect
			(at -0.889 0)
			(size 1.016 1.27)
			(layers "F.Cu" "F.Mask" "F.Paste")
			(net "PVCCD_HV_CPU1")
		)
		(pad "2" smd rect
			(at 0.889 0)
			(size 1.016 1.27)
			(layers "F.Cu" "F.Mask" "F.Paste")
			(net "GND")
		)
	)
	(footprint ""
		(layer "F.Cu")
		(at 77.101954 -342.726264 -90)
		(property "Reference" "PC482_P1_7"
			(at 0 0 270)
			(layer "F.SilkS")
			(hide yes)
			(effects
				(font
					(size 1.27 1.27)
				)
			)
		)
		(property "Value" ""
			(at 0 0 270)
			(layer "F.Fab")
			(effects
				(font
					(size 1.27 1.27)
				)
			)
		)
		(duplicate_pad_numbers_are_jumpers no)
		(fp_line
			(start -0.7874 0.4064)
			(end -0.7874 -0.4064)
			(stroke
				(width 0.1524)
				(type default)
			)
			(layer "F.SilkS")
		)
		(fp_line
			(start 0.7874 0.4064)
			(end -0.7874 0.4064)
			(stroke
				(width 0.1524)
				(type default)
			)
			(layer "F.SilkS")
		)
		(fp_line
			(start -0.7874 -0.4064)
			(end 0.7874 -0.4064)
			(stroke
				(width 0.1524)
				(type default)
			)
			(layer "F.SilkS")
		)
		(fp_line
			(start 0.7874 -0.4064)
			(end 0.7874 0.4064)
			(stroke
				(width 0.1524)
				(type default)
			)
			(layer "F.SilkS")
		)
		(fp_line
			(start -0.67945 0.3048)
			(end -0.67945 -0.305054)
			(stroke
				(width 0.1)
				(type default)
			)
			(layer "F.Fab")
		)
		(fp_line
			(start -0.12065 0.3048)
			(end -0.67945 0.3048)
			(stroke
				(width 0.1)
				(type default)
			)
			(layer "F.Fab")
		)
		(fp_line
			(start 0.120396 0.3048)
			(end 0.120396 0.2794)
			(stroke
				(width 0.1)
				(type default)
			)
			(layer "F.Fab")
		)
		(fp_line
			(start 0.67945 0.3048)
			(end 0.120396 0.3048)
			(stroke
				(width 0.1)
				(type default)
			)
			(layer "F.Fab")
		)
		(fp_line
			(start -0.12065 0.2794)
			(end -0.12065 0.3048)
			(stroke
				(width 0.1)
				(type default)
			)
			(layer "F.Fab")
		)
		(fp_line
			(start 0.120396 0.2794)
			(end -0.12065 0.2794)
			(stroke
				(width 0.1)
				(type default)
			)
			(layer "F.Fab")
		)
		(fp_line
			(start -0.12065 -0.2794)
			(end 0.12065 -0.2794)
			(stroke
				(width 0.1)
				(type default)
			)
			(layer "F.Fab")
		)
		(fp_line
			(start 0.12065 -0.2794)
			(end 0.12065 -0.3048)
			(stroke
				(width 0.1)
				(type default)
			)
			(layer "F.Fab")
		)
		(fp_line
			(start 0.12065 -0.3048)
			(end 0.67945 -0.3048)
			(stroke
				(width 0.1)
				(type default)
			)
			(layer "F.Fab")
		)
		(fp_line
			(start 0.67945 -0.3048)
			(end 0.67945 0.3048)
			(stroke
				(width 0.1)
				(type default)
			)
			(layer "F.Fab")
		)
		(fp_line
			(start -0.67945 -0.305054)
			(end -0.12065 -0.305054)
			(stroke
				(width 0.1)
				(type default)
			)
			(layer "F.Fab")
		)
		(fp_line
			(start -0.12065 -0.305054)
			(end -0.12065 -0.2794)
			(stroke
				(width 0.1)
				(type default)
			)
			(layer "F.Fab")
		)
		(pad "1" smd circle
			(at -0.40005 0 270)
			(size 0 0)
			(layers "F.Cu" "F.Mask" "F.Paste")
			(net "PVCCIN_CPU1_PVCC")
		)
		(pad "2" smd circle
			(at 0.40005 0 270)
			(size 0 0)
			(layers "F.Cu" "F.Mask" "F.Paste")
			(net "GND")
		)
	)
	(footprint ""
		(layer "F.Cu")
		(at 304.1396 -419.10635 -90)
		(property "Reference" "C2264"
			(at 0 0 270)
			(layer "F.SilkS")
			(hide yes)
			(effects
				(font
					(size 1.27 1.27)
				)
			)
		)
		(property "Value" ""
			(at 0 0 270)
			(layer "F.Fab")
			(effects
				(font
					(size 1.27 1.27)
				)
			)
		)
		(duplicate_pad_numbers_are_jumpers no)
		(fp_line
			(start -0.7874 0.4064)
			(end -0.7874 -0.4064)
			(stroke
				(width 0.1524)
				(type default)
			)
			(layer "F.SilkS")
		)
		(fp_line
			(start 0.7874 0.4064)
			(end -0.7874 0.4064)
			(stroke
				(width 0.1524)
				(type default)
			)
			(layer "F.SilkS")
		)
		(fp_line
			(start -0.7874 -0.4064)
			(end 0.7874 -0.4064)
			(stroke
				(width 0.1524)
				(type default)
			)
			(layer "F.SilkS")
		)
		(fp_line
			(start 0.7874 -0.4064)
			(end 0.7874 0.4064)
			(stroke
				(width 0.1524)
				(type default)
			)
			(layer "F.SilkS")
		)
		(fp_line
			(start -0.67945 0.3048)
			(end -0.67945 -0.305054)
			(stroke
				(width 0.1)
				(type default)
			)
			(layer "F.Fab")
		)
		(fp_line
			(start -0.12065 0.3048)
			(end -0.67945 0.3048)
			(stroke
				(width 0.1)
				(type default)
			)
			(layer "F.Fab")
		)
		(fp_line
			(start 0.120396 0.3048)
			(end 0.120396 0.2794)
			(stroke
				(width 0.1)
				(type default)
			)
			(layer "F.Fab")
		)
		(fp_line
			(start 0.67945 0.3048)
			(end 0.120396 0.3048)
			(stroke
				(width 0.1)
				(type default)
			)
			(layer "F.Fab")
		)
		(fp_line
			(start -0.12065 0.2794)
			(end -0.12065 0.3048)
			(stroke
				(width 0.1)
				(type default)
			)
			(layer "F.Fab")
		)
		(fp_line
			(start 0.120396 0.2794)
			(end -0.12065 0.2794)
			(stroke
				(width 0.1)
				(type default)
			)
			(layer "F.Fab")
		)
		(fp_line
			(start -0.12065 -0.2794)
			(end 0.12065 -0.2794)
			(stroke
				(width 0.1)
				(type default)
			)
			(layer "F.Fab")
		)
		(fp_line
			(start 0.12065 -0.2794)
			(end 0.12065 -0.3048)
			(stroke
				(width 0.1)
				(type default)
			)
			(layer "F.Fab")
		)
		(fp_line
			(start 0.12065 -0.3048)
			(end 0.67945 -0.3048)
			(stroke
				(width 0.1)
				(type default)
			)
			(layer "F.Fab")
		)
		(fp_line
			(start 0.67945 -0.3048)
			(end 0.67945 0.3048)
			(stroke
				(width 0.1)
				(type default)
			)
			(layer "F.Fab")
		)
		(fp_line
			(start -0.67945 -0.305054)
			(end -0.12065 -0.305054)
			(stroke
				(width 0.1)
				(type default)
			)
			(layer "F.Fab")
		)
		(fp_line
			(start -0.12065 -0.305054)
			(end -0.12065 -0.2794)
			(stroke
				(width 0.1)
				(type default)
			)
			(layer "F.Fab")
		)
		(pad "1" smd circle
			(at -0.40005 0 270)
			(size 0 0)
			(layers "F.Cu" "F.Mask" "F.Paste")
			(net "GPU_3V3IO_RSVD0_FFU_ISO")
		)
		(pad "2" smd circle
			(at 0.40005 0 270)
			(size 0 0)
			(layers "F.Cu" "F.Mask" "F.Paste")
			(net "GND")
		)
	)
	(footprint ""
		(layer "F.Cu")
		(at 304.09896 -430.65827 -90)
		(property "Reference" "C2267"
			(at 0 0 270)
			(layer "F.SilkS")
			(hide yes)
			(effects
				(font
					(size 1.27 1.27)
				)
			)
		)
		(property "Value" ""
			(at 0 0 270)
			(layer "F.Fab")
			(effects
				(font
					(size 1.27 1.27)
				)
			)
		)
		(duplicate_pad_numbers_are_jumpers no)
		(fp_line
			(start -0.7874 0.4064)
			(end -0.7874 -0.4064)
			(stroke
				(width 0.1524)
				(type default)
			)
			(layer "F.SilkS")
		)
		(fp_line
			(start 0.7874 0.4064)
			(end -0.7874 0.4064)
			(stroke
				(width 0.1524)
				(type default)
			)
			(layer "F.SilkS")
		)
		(fp_line
			(start -0.7874 -0.4064)
			(end 0.7874 -0.4064)
			(stroke
				(width 0.1524)
				(type default)
			)
			(layer "F.SilkS")
		)
		(fp_line
			(start 0.7874 -0.4064)
			(end 0.7874 0.4064)
			(stroke
				(width 0.1524)
				(type default)
			)
			(layer "F.SilkS")
		)
		(fp_line
			(start -0.67945 0.3048)
			(end -0.67945 -0.305054)
			(stroke
				(width 0.1)
				(type default)
			)
			(layer "F.Fab")
		)
		(fp_line
			(start -0.12065 0.3048)
			(end -0.67945 0.3048)
			(stroke
				(width 0.1)
				(type default)
			)
			(layer "F.Fab")
		)
		(fp_line
			(start 0.120396 0.3048)
			(end 0.120396 0.2794)
			(stroke
				(width 0.1)
				(type default)
			)
			(layer "F.Fab")
		)
		(fp_line
			(start 0.67945 0.3048)
			(end 0.120396 0.3048)
			(stroke
				(width 0.1)
				(type default)
			)
			(layer "F.Fab")
		)
		(fp_line
			(start -0.12065 0.2794)
			(end -0.12065 0.3048)
			(stroke
				(width 0.1)
				(type default)
			)
			(layer "F.Fab")
		)
		(fp_line
			(start 0.120396 0.2794)
			(end -0.12065 0.2794)
			(stroke
				(width 0.1)
				(type default)
			)
			(layer "F.Fab")
		)
		(fp_line
			(start -0.12065 -0.2794)
			(end 0.12065 -0.2794)
			(stroke
				(width 0.1)
				(type default)
			)
			(layer "F.Fab")
		)
		(fp_line
			(start 0.12065 -0.2794)
			(end 0.12065 -0.3048)
			(stroke
				(width 0.1)
				(type default)
			)
			(layer "F.Fab")
		)
		(fp_line
			(start 0.12065 -0.3048)
			(end 0.67945 -0.3048)
			(stroke
				(width 0.1)
				(type default)
			)
			(layer "F.Fab")
		)
		(fp_line
			(start 0.67945 -0.3048)
			(end 0.67945 0.3048)
			(stroke
				(width 0.1)
				(type default)
			)
			(layer "F.Fab")
		)
		(fp_line
			(start -0.67945 -0.305054)
			(end -0.12065 -0.305054)
			(stroke
				(width 0.1)
				(type default)
			)
			(layer "F.Fab")
		)
		(fp_line
			(start -0.12065 -0.305054)
			(end -0.12065 -0.2794)
			(stroke
				(width 0.1)
				(type default)
			)
			(layer "F.Fab")
		)
		(pad "1" smd circle
			(at -0.40005 0 270)
			(size 0 0)
			(layers "F.Cu" "F.Mask" "F.Paste")
			(net "GPU_3V3IO_RSVD3_FFU_ISO")
		)
		(pad "2" smd circle
			(at 0.40005 0 270)
			(size 0 0)
			(layers "F.Cu" "F.Mask" "F.Paste")
			(net "GND")
		)
	)
	(footprint ""
		(layer "F.Cu")
		(at 52.423314 -152.903174 180)
		(property "Reference" "PC440"
			(at 0 0 180)
			(layer "F.SilkS")
			(hide yes)
			(effects
				(font
					(size 1.27 1.27)
				)
			)
		)
		(property "Value" ""
			(at 0 0 180)
			(layer "F.Fab")
			(effects
				(font
					(size 1.27 1.27)
				)
			)
		)
		(duplicate_pad_numbers_are_jumpers no)
		(fp_line
			(start 0.7874 0.4064)
			(end -0.7874 0.4064)
			(stroke
				(width 0.1524)
				(type default)
			)
			(layer "F.SilkS")
		)
		(fp_line
			(start 0.7874 -0.4064)
			(end 0.7874 0.4064)
			(stroke
				(width 0.1524)
				(type default)
			)
			(layer "F.SilkS")
		)
		(fp_line
			(start -0.7874 0.4064)
			(end -0.7874 -0.4064)
			(stroke
				(width 0.1524)
				(type default)
			)
			(layer "F.SilkS")
		)
		(fp_line
			(start -0.7874 -0.4064)
			(end 0.7874 -0.4064)
			(stroke
				(width 0.1524)
				(type default)
			)
			(layer "F.SilkS")
		)
		(fp_line
			(start 0.67945 0.3048)
			(end 0.120396 0.3048)
			(stroke
				(width 0.1)
				(type default)
			)
			(layer "F.Fab")
		)
		(fp_line
			(start 0.67945 -0.3048)
			(end 0.67945 0.3048)
			(stroke
				(width 0.1)
				(type default)
			)
			(layer "F.Fab")
		)
		(fp_line
			(start 0.12065 -0.2794)
			(end 0.12065 -0.3048)
			(stroke
				(width 0.1)
				(type default)
			)
			(layer "F.Fab")
		)
		(fp_line
			(start 0.12065 -0.3048)
			(end 0.67945 -0.3048)
			(stroke
				(width 0.1)
				(type default)
			)
			(layer "F.Fab")
		)
		(fp_line
			(start 0.120396 0.3048)
			(end 0.120396 0.2794)
			(stroke
				(width 0.1)
				(type default)
			)
			(layer "F.Fab")
		)
		(fp_line
			(start 0.120396 0.2794)
			(end -0.12065 0.2794)
			(stroke
				(width 0.1)
				(type default)
			)
			(layer "F.Fab")
		)
		(fp_line
			(start -0.12065 0.3048)
			(end -0.67945 0.3048)
			(stroke
				(width 0.1)
				(type default)
			)
			(layer "F.Fab")
		)
		(fp_line
			(start -0.12065 0.2794)
			(end -0.12065 0.3048)
			(stroke
				(width 0.1)
				(type default)
			)
			(layer "F.Fab")
		)
		(fp_line
			(start -0.12065 -0.2794)
			(end 0.12065 -0.2794)
			(stroke
				(width 0.1)
				(type default)
			)
			(layer "F.Fab")
		)
		(fp_line
			(start -0.12065 -0.305054)
			(end -0.12065 -0.2794)
			(stroke
				(width 0.1)
				(type default)
			)
			(layer "F.Fab")
		)
		(fp_line
			(start -0.67945 0.3048)
			(end -0.67945 -0.305054)
			(stroke
				(width 0.1)
				(type default)
			)
			(layer "F.Fab")
		)
		(fp_line
			(start -0.67945 -0.305054)
			(end -0.12065 -0.305054)
			(stroke
				(width 0.1)
				(type default)
			)
			(layer "F.Fab")
		)
		(pad "1" smd circle
			(at -0.40005 0 180)
			(size 0 0)
			(layers "F.Cu" "F.Mask" "F.Paste")
			(net "PVCCINFAON_CPU1_VDD1")
		)
		(pad "2" smd circle
			(at 0.40005 0 180)
			(size 0 0)
			(layers "F.Cu" "F.Mask" "F.Paste")
			(net "GND")
		)
	)
	(footprint ""
		(layer "F.Cu")
		(at 445.175386 -47.627286 180)
		(property "Reference" "C1862"
			(at 0 0 180)
			(layer "F.SilkS")
			(hide yes)
			(effects
				(font
					(size 1.27 1.27)
				)
			)
		)
		(property "Value" ""
			(at 0 0 180)
			(layer "F.Fab")
			(effects
				(font
					(size 1.27 1.27)
				)
			)
		)
		(duplicate_pad_numbers_are_jumpers no)
		(fp_line
			(start 0.7874 0.4064)
			(end -0.7874 0.4064)
			(stroke
				(width 0.1524)
				(type default)
			)
			(layer "F.SilkS")
		)
		(fp_line
			(start 0.7874 -0.4064)
			(end 0.7874 0.4064)
			(stroke
				(width 0.1524)
				(type default)
			)
			(layer "F.SilkS")
		)
		(fp_line
			(start -0.7874 0.4064)
			(end -0.7874 -0.4064)
			(stroke
				(width 0.1524)
				(type default)
			)
			(layer "F.SilkS")
		)
		(fp_line
			(start -0.7874 -0.4064)
			(end 0.7874 -0.4064)
			(stroke
				(width 0.1524)
				(type default)
			)
			(layer "F.SilkS")
		)
		(fp_line
			(start 0.67945 0.3048)
			(end 0.120396 0.3048)
			(stroke
				(width 0.1)
				(type default)
			)
			(layer "F.Fab")
		)
		(fp_line
			(start 0.67945 -0.3048)
			(end 0.67945 0.3048)
			(stroke
				(width 0.1)
				(type default)
			)
			(layer "F.Fab")
		)
		(fp_line
			(start 0.12065 -0.2794)
			(end 0.12065 -0.3048)
			(stroke
				(width 0.1)
				(type default)
			)
			(layer "F.Fab")
		)
		(fp_line
			(start 0.12065 -0.3048)
			(end 0.67945 -0.3048)
			(stroke
				(width 0.1)
				(type default)
			)
			(layer "F.Fab")
		)
		(fp_line
			(start 0.120396 0.3048)
			(end 0.120396 0.2794)
			(stroke
				(width 0.1)
				(type default)
			)
			(layer "F.Fab")
		)
		(fp_line
			(start 0.120396 0.2794)
			(end -0.12065 0.2794)
			(stroke
				(width 0.1)
				(type default)
			)
			(layer "F.Fab")
		)
		(fp_line
			(start -0.12065 0.3048)
			(end -0.67945 0.3048)
			(stroke
				(width 0.1)
				(type default)
			)
			(layer "F.Fab")
		)
		(fp_line
			(start -0.12065 0.2794)
			(end -0.12065 0.3048)
			(stroke
				(width 0.1)
				(type default)
			)
			(layer "F.Fab")
		)
		(fp_line
			(start -0.12065 -0.2794)
			(end 0.12065 -0.2794)
			(stroke
				(width 0.1)
				(type default)
			)
			(layer "F.Fab")
		)
		(fp_line
			(start -0.12065 -0.305054)
			(end -0.12065 -0.2794)
			(stroke
				(width 0.1)
				(type default)
			)
			(layer "F.Fab")
		)
		(fp_line
			(start -0.67945 0.3048)
			(end -0.67945 -0.305054)
			(stroke
				(width 0.1)
				(type default)
			)
			(layer "F.Fab")
		)
		(fp_line
			(start -0.67945 -0.305054)
			(end -0.12065 -0.305054)
			(stroke
				(width 0.1)
				(type default)
			)
			(layer "F.Fab")
		)
		(pad "1" smd circle
			(at -0.40005 0 180)
			(size 0 0)
			(layers "F.Cu" "F.Mask" "F.Paste")
			(net "P3V3_OCP_SFF")
		)
		(pad "2" smd circle
			(at 0.40005 0 180)
			(size 0 0)
			(layers "F.Cu" "F.Mask" "F.Paste")
			(net "GND")
		)
	)
	(footprint ""
		(layer "F.Cu")
		(at 29.035756 -133.04139)
		(property "Reference" "PC469"
			(at 0 0 0)
			(layer "F.SilkS")
			(hide yes)
			(effects
				(font
					(size 1.27 1.27)
				)
			)
		)
		(property "Value" ""
			(at 0 0 0)
			(layer "F.Fab")
			(effects
				(font
					(size 1.27 1.27)
				)
			)
		)
		(duplicate_pad_numbers_are_jumpers no)
		(fp_line
			(start -0.7874 -0.4064)
			(end 0.7874 -0.4064)
			(stroke
				(width 0.1524)
				(type default)
			)
			(layer "F.SilkS")
		)
		(fp_line
			(start -0.7874 0.4064)
			(end -0.7874 -0.4064)
			(stroke
				(width 0.1524)
				(type default)
			)
			(layer "F.SilkS")
		)
		(fp_line
			(start 0.7874 -0.4064)
			(end 0.7874 0.4064)
			(stroke
				(width 0.1524)
				(type default)
			)
			(layer "F.SilkS")
		)
		(fp_line
			(start 0.7874 0.4064)
			(end -0.7874 0.4064)
			(stroke
				(width 0.1524)
				(type default)
			)
			(layer "F.SilkS")
		)
		(fp_line
			(start -0.67945 -0.305054)
			(end -0.12065 -0.305054)
			(stroke
				(width 0.1)
				(type default)
			)
			(layer "F.Fab")
		)
		(fp_line
			(start -0.67945 0.3048)
			(end -0.67945 -0.305054)
			(stroke
				(width 0.1)
				(type default)
			)
			(layer "F.Fab")
		)
		(fp_line
			(start -0.12065 -0.305054)
			(end -0.12065 -0.2794)
			(stroke
				(width 0.1)
				(type default)
			)
			(layer "F.Fab")
		)
		(fp_line
			(start -0.12065 -0.2794)
			(end 0.12065 -0.2794)
			(stroke
				(width 0.1)
				(type default)
			)
			(layer "F.Fab")
		)
		(fp_line
			(start -0.12065 0.2794)
			(end -0.12065 0.3048)
			(stroke
				(width 0.1)
				(type default)
			)
			(layer "F.Fab")
		)
		(fp_line
			(start -0.12065 0.3048)
			(end -0.67945 0.3048)
			(stroke
				(width 0.1)
				(type default)
			)
			(layer "F.Fab")
		)
		(fp_line
			(start 0.120396 0.2794)
			(end -0.12065 0.2794)
			(stroke
				(width 0.1)
				(type default)
			)
			(layer "F.Fab")
		)
		(fp_line
			(start 0.120396 0.3048)
			(end 0.120396 0.2794)
			(stroke
				(width 0.1)
				(type default)
			)
			(layer "F.Fab")
		)
		(fp_line
			(start 0.12065 -0.3048)
			(end 0.67945 -0.3048)
			(stroke
				(width 0.1)
				(type default)
			)
			(layer "F.Fab")
		)
		(fp_line
			(start 0.12065 -0.2794)
			(end 0.12065 -0.3048)
			(stroke
				(width 0.1)
				(type default)
			)
			(layer "F.Fab")
		)
		(fp_line
			(start 0.67945 -0.3048)
			(end 0.67945 0.3048)
			(stroke
				(width 0.1)
				(type default)
			)
			(layer "F.Fab")
		)
		(fp_line
			(start 0.67945 0.3048)
			(end 0.120396 0.3048)
			(stroke
				(width 0.1)
				(type default)
			)
			(layer "F.Fab")
		)
		(pad "1" smd circle
			(at -0.40005 0)
			(size 0 0)
			(layers "F.Cu" "F.Mask" "F.Paste")
			(net "SH_PVCCFA_EHV_CPU1_R")
		)
		(pad "2" smd circle
			(at 0.40005 0)
			(size 0 0)
			(layers "F.Cu" "F.Mask" "F.Paste")
			(net "VSENSE_PVCCFA_EHV_CPU1_DN")
		)
	)
	(footprint ""
		(layer "F.Cu")
		(at 22.460204 -385.778248 -90)
		(property "Reference" "C1869"
			(at 0 0 270)
			(layer "F.SilkS")
			(hide yes)
			(effects
				(font
					(size 1.27 1.27)
				)
			)
		)
		(property "Value" ""
			(at 0 0 270)
			(layer "F.Fab")
			(effects
				(font
					(size 1.27 1.27)
				)
			)
		)
		(duplicate_pad_numbers_are_jumpers no)
		(fp_line
			(start 0.7874 0.4064)
			(end -0.7874 0.4064)
			(stroke
				(width 0.1524)
				(type default)
			)
			(layer "F.SilkS")
		)
		(fp_line
			(start -0.7874 -0.4064)
			(end 0.000508 -0.4064)
			(stroke
				(width 0.1524)
				(type default)
			)
			(layer "F.SilkS")
		)
		(fp_line
			(start 0.7874 -0.4064)
			(end 0.7874 0.4064)
			(stroke
				(width 0.1524)
				(type default)
			)
			(layer "F.SilkS")
		)
		(fp_line
			(start -0.6858 0.3048)
			(end -0.6858 -0.3048)
			(stroke
				(width 0.1)
				(type default)
			)
			(layer "F.Fab")
		)
		(fp_line
			(start -0.1016 0.3048)
			(end -0.6858 0.3048)
			(stroke
				(width 0.1)
				(type default)
			)
			(layer "F.Fab")
		)
		(fp_line
			(start 0.1016 0.3048)
			(end 0.1016 0.2794)
			(stroke
				(width 0.1)
				(type default)
			)
			(layer "F.Fab")
		)
		(fp_line
			(start 0.6858 0.3048)
			(end 0.1016 0.3048)
			(stroke
				(width 0.1)
				(type default)
			)
			(layer "F.Fab")
		)
		(fp_line
			(start -0.1016 0.2794)
			(end -0.1016 0.3048)
			(stroke
				(width 0.1)
				(type default)
			)
			(layer "F.Fab")
		)
		(fp_line
			(start 0.1016 0.2794)
			(end -0.1016 0.2794)
			(stroke
				(width 0.1)
				(type default)
			)
			(layer "F.Fab")
		)
		(fp_line
			(start -0.1016 -0.2794)
			(end 0.1016 -0.2794)
			(stroke
				(width 0.1)
				(type default)
			)
			(layer "F.Fab")
		)
		(fp_line
			(start 0.1016 -0.2794)
			(end 0.1016 -0.3048)
			(stroke
				(width 0.1)
				(type default)
			)
			(layer "F.Fab")
		)
		(fp_line
			(start -0.6858 -0.3048)
			(end -0.1016 -0.3048)
			(stroke
				(width 0.1)
				(type default)
			)
			(layer "F.Fab")
		)
		(fp_line
			(start -0.1016 -0.3048)
			(end -0.1016 -0.2794)
			(stroke
				(width 0.1)
				(type default)
			)
			(layer "F.Fab")
		)
		(fp_line
			(start 0.1016 -0.3048)
			(end 0.6858 -0.3048)
			(stroke
				(width 0.1)
				(type default)
			)
			(layer "F.Fab")
		)
		(fp_line
			(start 0.6858 -0.3048)
			(end 0.6858 0.3048)
			(stroke
				(width 0.1)
				(type default)
			)
			(layer "F.Fab")
		)
		(pad "1" smd rect
			(at -0.40005 0 90)
			(size 0.4572 0.508)
			(layers "F.Cu" "F.Mask" "F.Paste")
			(net "P2E_MB_BMC_RX_BUF_C_DN<0>")
		)
		(pad "2" smd rect
			(at 0.40005 0 90)
			(size 0.4572 0.508)
			(layers "F.Cu" "F.Mask" "F.Paste")
			(net "P2E_MB_BMC_RX_BUF_DN<0>")
		)
	)
	(footprint ""
		(layer "F.Cu")
		(at 432.085496 -109.13745 90)
		(property "Reference" "PR3780"
			(at 0 0 90)
			(layer "F.SilkS")
			(hide yes)
			(effects
				(font
					(size 1.27 1.27)
				)
			)
		)
		(property "Value" ""
			(at 0 0 90)
			(layer "F.Fab")
			(effects
				(font
					(size 1.27 1.27)
				)
			)
		)
		(duplicate_pad_numbers_are_jumpers no)
		(fp_line
			(start 0.7874 -0.4064)
			(end 0.7874 0.4064)
			(stroke
				(width 0.1524)
				(type default)
			)
			(layer "F.SilkS")
		)
		(fp_line
			(start -0.7874 -0.4064)
			(end 0.7874 -0.4064)
			(stroke
				(width 0.1524)
				(type default)
			)
			(layer "F.SilkS")
		)
		(fp_line
			(start 0.7874 0.4064)
			(end -0.7874 0.4064)
			(stroke
				(width 0.1524)
				(type default)
			)
			(layer "F.SilkS")
		)
		(fp_line
			(start -0.7874 0.4064)
			(end -0.7874 -0.4064)
			(stroke
				(width 0.1524)
				(type default)
			)
			(layer "F.SilkS")
		)
		(fp_line
			(start -0.12065 -0.305054)
			(end -0.12065 -0.2794)
			(stroke
				(width 0.1)
				(type default)
			)
			(layer "F.Fab")
		)
		(fp_line
			(start -0.67945 -0.305054)
			(end -0.12065 -0.305054)
			(stroke
				(width 0.1)
				(type default)
			)
			(layer "F.Fab")
		)
		(fp_line
			(start 0.67945 -0.3048)
			(end 0.67945 0.3048)
			(stroke
				(width 0.1)
				(type default)
			)
			(layer "F.Fab")
		)
		(fp_line
			(start 0.12065 -0.3048)
			(end 0.67945 -0.3048)
			(stroke
				(width 0.1)
				(type default)
			)
			(layer "F.Fab")
		)
		(fp_line
			(start 0.12065 -0.2794)
			(end 0.12065 -0.3048)
			(stroke
				(width 0.1)
				(type default)
			)
			(layer "F.Fab")
		)
		(fp_line
			(start -0.12065 -0.2794)
			(end 0.12065 -0.2794)
			(stroke
				(width 0.1)
				(type default)
			)
			(layer "F.Fab")
		)
		(fp_line
			(start 0.120396 0.2794)
			(end -0.12065 0.2794)
			(stroke
				(width 0.1)
				(type default)
			)
			(layer "F.Fab")
		)
		(fp_line
			(start -0.12065 0.2794)
			(end -0.12065 0.3048)
			(stroke
				(width 0.1)
				(type default)
			)
			(layer "F.Fab")
		)
		(fp_line
			(start 0.67945 0.3048)
			(end 0.120396 0.3048)
			(stroke
				(width 0.1)
				(type default)
			)
			(layer "F.Fab")
		)
		(fp_line
			(start 0.120396 0.3048)
			(end 0.120396 0.2794)
			(stroke
				(width 0.1)
				(type default)
			)
			(layer "F.Fab")
		)
		(fp_line
			(start -0.12065 0.3048)
			(end -0.67945 0.3048)
			(stroke
				(width 0.1)
				(type default)
			)
			(layer "F.Fab")
		)
		(fp_line
			(start -0.67945 0.3048)
			(end -0.67945 -0.305054)
			(stroke
				(width 0.1)
				(type default)
			)
			(layer "F.Fab")
		)
		(pad "1" smd circle
			(at -0.40005 0 90)
			(size 0 0)
			(layers "F.Cu" "F.Mask" "F.Paste")
			(net "P3V3_OCP_CB_1")
		)
		(pad "2" smd circle
			(at 0.40005 0 90)
			(size 0 0)
			(layers "F.Cu" "F.Mask" "F.Paste")
			(net "GND")
		)
	)
	(footprint ""
		(layer "F.Cu")
		(at 385.384802 -49.488598 90)
		(property "Reference" "R765"
			(at 0 0 90)
			(layer "F.SilkS")
			(hide yes)
			(effects
				(font
					(size 1.27 1.27)
				)
			)
		)
		(property "Value" ""
			(at 0 0 90)
			(layer "F.Fab")
			(effects
				(font
					(size 1.27 1.27)
				)
			)
		)
		(duplicate_pad_numbers_are_jumpers no)
		(fp_line
			(start 0.7874 -0.4064)
			(end 0.7874 0.4064)
			(stroke
				(width 0.1524)
				(type default)
			)
			(layer "F.SilkS")
		)
		(fp_line
			(start -0.7874 -0.4064)
			(end 0.7874 -0.4064)
			(stroke
				(width 0.1524)
				(type default)
			)
			(layer "F.SilkS")
		)
		(fp_line
			(start 0.7874 0.4064)
			(end -0.7874 0.4064)
			(stroke
				(width 0.1524)
				(type default)
			)
			(layer "F.SilkS")
		)
		(fp_line
			(start -0.7874 0.4064)
			(end -0.7874 -0.4064)
			(stroke
				(width 0.1524)
				(type default)
			)
			(layer "F.SilkS")
		)
		(fp_line
			(start -0.12065 -0.305054)
			(end -0.12065 -0.2794)
			(stroke
				(width 0.1)
				(type default)
			)
			(layer "F.Fab")
		)
		(fp_line
			(start -0.67945 -0.305054)
			(end -0.12065 -0.305054)
			(stroke
				(width 0.1)
				(type default)
			)
			(layer "F.Fab")
		)
		(fp_line
			(start 0.67945 -0.3048)
			(end 0.67945 0.3048)
			(stroke
				(width 0.1)
				(type default)
			)
			(layer "F.Fab")
		)
		(fp_line
			(start 0.12065 -0.3048)
			(end 0.67945 -0.3048)
			(stroke
				(width 0.1)
				(type default)
			)
			(layer "F.Fab")
		)
		(fp_line
			(start 0.12065 -0.2794)
			(end 0.12065 -0.3048)
			(stroke
				(width 0.1)
				(type default)
			)
			(layer "F.Fab")
		)
		(fp_line
			(start -0.12065 -0.2794)
			(end 0.12065 -0.2794)
			(stroke
				(width 0.1)
				(type default)
			)
			(layer "F.Fab")
		)
		(fp_line
			(start 0.120396 0.2794)
			(end -0.12065 0.2794)
			(stroke
				(width 0.1)
				(type default)
			)
			(layer "F.Fab")
		)
		(fp_line
			(start -0.12065 0.2794)
			(end -0.12065 0.3048)
			(stroke
				(width 0.1)
				(type default)
			)
			(layer "F.Fab")
		)
		(fp_line
			(start 0.67945 0.3048)
			(end 0.120396 0.3048)
			(stroke
				(width 0.1)
				(type default)
			)
			(layer "F.Fab")
		)
		(fp_line
			(start 0.120396 0.3048)
			(end 0.120396 0.2794)
			(stroke
				(width 0.1)
				(type default)
			)
			(layer "F.Fab")
		)
		(fp_line
			(start -0.12065 0.3048)
			(end -0.67945 0.3048)
			(stroke
				(width 0.1)
				(type default)
			)
			(layer "F.Fab")
		)
		(fp_line
			(start -0.67945 0.3048)
			(end -0.67945 -0.305054)
			(stroke
				(width 0.1)
				(type default)
			)
			(layer "F.Fab")
		)
		(pad "1" smd circle
			(at -0.40005 0 90)
			(size 0 0)
			(layers "F.Cu" "F.Mask" "F.Paste")
			(net "JTAG_DBP_TCK_PCH")
		)
		(pad "2" smd circle
			(at 0.40005 0 90)
			(size 0 0)
			(layers "F.Cu" "F.Mask" "F.Paste")
			(net "JTAG_DBP_TCK_R_TCK")
		)
	)
	(footprint ""
		(layer "F.Cu")
		(at 54.242716 -106.86669 180)
		(property "Reference" "R3719"
			(at 0 0 180)
			(layer "F.SilkS")
			(hide yes)
			(effects
				(font
					(size 1.27 1.27)
				)
			)
		)
		(property "Value" ""
			(at 0 0 180)
			(layer "F.Fab")
			(effects
				(font
					(size 1.27 1.27)
				)
			)
		)
		(duplicate_pad_numbers_are_jumpers no)
		(fp_line
			(start 0.7874 0.4064)
			(end -0.7874 0.4064)
			(stroke
				(width 0.1524)
				(type default)
			)
			(layer "F.SilkS")
		)
		(fp_line
			(start 0.7874 -0.4064)
			(end 0.7874 0.4064)
			(stroke
				(width 0.1524)
				(type default)
			)
			(layer "F.SilkS")
		)
		(fp_line
			(start -0.7874 0.4064)
			(end -0.7874 -0.4064)
			(stroke
				(width 0.1524)
				(type default)
			)
			(layer "F.SilkS")
		)
		(fp_line
			(start -0.7874 -0.4064)
			(end 0.7874 -0.4064)
			(stroke
				(width 0.1524)
				(type default)
			)
			(layer "F.SilkS")
		)
		(fp_line
			(start 0.67945 0.3048)
			(end 0.120396 0.3048)
			(stroke
				(width 0.1)
				(type default)
			)
			(layer "F.Fab")
		)
		(fp_line
			(start 0.67945 -0.3048)
			(end 0.67945 0.3048)
			(stroke
				(width 0.1)
				(type default)
			)
			(layer "F.Fab")
		)
		(fp_line
			(start 0.12065 -0.2794)
			(end 0.12065 -0.3048)
			(stroke
				(width 0.1)
				(type default)
			)
			(layer "F.Fab")
		)
		(fp_line
			(start 0.12065 -0.3048)
			(end 0.67945 -0.3048)
			(stroke
				(width 0.1)
				(type default)
			)
			(layer "F.Fab")
		)
		(fp_line
			(start 0.120396 0.3048)
			(end 0.120396 0.2794)
			(stroke
				(width 0.1)
				(type default)
			)
			(layer "F.Fab")
		)
		(fp_line
			(start 0.120396 0.2794)
			(end -0.12065 0.2794)
			(stroke
				(width 0.1)
				(type default)
			)
			(layer "F.Fab")
		)
		(fp_line
			(start -0.12065 0.3048)
			(end -0.67945 0.3048)
			(stroke
				(width 0.1)
				(type default)
			)
			(layer "F.Fab")
		)
		(fp_line
			(start -0.12065 0.2794)
			(end -0.12065 0.3048)
			(stroke
				(width 0.1)
				(type default)
			)
			(layer "F.Fab")
		)
		(fp_line
			(start -0.12065 -0.2794)
			(end 0.12065 -0.2794)
			(stroke
				(width 0.1)
				(type default)
			)
			(layer "F.Fab")
		)
		(fp_line
			(start -0.12065 -0.305054)
			(end -0.12065 -0.2794)
			(stroke
				(width 0.1)
				(type default)
			)
			(layer "F.Fab")
		)
		(fp_line
			(start -0.67945 0.3048)
			(end -0.67945 -0.305054)
			(stroke
				(width 0.1)
				(type default)
			)
			(layer "F.Fab")
		)
		(fp_line
			(start -0.67945 -0.305054)
			(end -0.12065 -0.305054)
			(stroke
				(width 0.1)
				(type default)
			)
			(layer "F.Fab")
		)
		(pad "1" smd circle
			(at -0.40005 0 180)
			(size 0 0)
			(layers "F.Cu" "F.Mask" "F.Paste")
			(net "SMB_LM75_2_3V3AUX_SCL_R")
		)
		(pad "2" smd circle
			(at 0.40005 0 180)
			(size 0 0)
			(layers "F.Cu" "F.Mask" "F.Paste")
			(net "SMB_LM75_2_3V3AUX_SCL")
		)
	)
	(footprint ""
		(layer "F.Cu")
		(at 345.123008 -408.517344 -90)
		(property "Reference" "C928"
			(at 0 0 270)
			(layer "F.SilkS")
			(hide yes)
			(effects
				(font
					(size 1.27 1.27)
				)
			)
		)
		(property "Value" ""
			(at 0 0 270)
			(layer "F.Fab")
			(effects
				(font
					(size 1.27 1.27)
				)
			)
		)
		(duplicate_pad_numbers_are_jumpers no)
		(fp_line
			(start -0.299974 0.150114)
			(end -0.299974 -0.150114)
			(stroke
				(width 0.1)
				(type default)
			)
			(layer "F.Fab")
		)
		(fp_line
			(start 0.299974 0.150114)
			(end -0.299974 0.150114)
			(stroke
				(width 0.1)
				(type default)
			)
			(layer "F.Fab")
		)
		(fp_line
			(start -0.299974 -0.150114)
			(end 0.299974 -0.150114)
			(stroke
				(width 0.1)
				(type default)
			)
			(layer "F.Fab")
		)
		(fp_line
			(start 0.299974 -0.150114)
			(end 0.299974 0.150114)
			(stroke
				(width 0.1)
				(type default)
			)
			(layer "F.Fab")
		)
		(pad "1" smd rect
			(at -0.2667 0 270)
			(size 0.3048 0.381)
			(layers "F.Cu" "F.Mask" "F.Paste")
			(net "P5E_CPU0_PE0_TX_C_DN<2>")
		)
		(pad "2" smd rect
			(at 0.2667 0 270)
			(size 0.3048 0.381)
			(layers "F.Cu" "F.Mask" "F.Paste")
			(net "P5E_CPU0_PE0_TX_DN<2>")
		)
	)
	(footprint ""
		(layer "F.Cu")
		(at 252.780292 -407.416 -90)
		(property "Reference" "PR2533"
			(at 0 0 270)
			(layer "F.SilkS")
			(hide yes)
			(effects
				(font
					(size 1.27 1.27)
				)
			)
		)
		(property "Value" ""
			(at 0 0 270)
			(layer "F.Fab")
			(effects
				(font
					(size 1.27 1.27)
				)
			)
		)
		(duplicate_pad_numbers_are_jumpers no)
		(fp_line
			(start -3.9878 3.5814)
			(end -3.9878 -3.5814)
			(stroke
				(width 0.1524)
				(type default)
			)
			(layer "F.SilkS")
		)
		(fp_line
			(start 3.9878 3.5814)
			(end -3.9878 3.5814)
			(stroke
				(width 0.1524)
				(type default)
			)
			(layer "F.SilkS")
		)
		(fp_line
			(start -3.9878 -3.5814)
			(end 3.9878 -3.5814)
			(stroke
				(width 0.1524)
				(type default)
			)
			(layer "F.SilkS")
		)
		(fp_line
			(start 3.9878 -3.5814)
			(end 3.9878 3.5814)
			(stroke
				(width 0.1524)
				(type default)
			)
			(layer "F.SilkS")
		)
		(fp_line
			(start -3.5306 3.353054)
			(end -3.5306 -3.353054)
			(stroke
				(width 0.1)
				(type default)
			)
			(layer "F.Fab")
		)
		(fp_line
			(start 3.5306 3.353054)
			(end -3.5306 3.353054)
			(stroke
				(width 0.1)
				(type default)
			)
			(layer "F.Fab")
		)
		(fp_line
			(start -3.5306 -3.353054)
			(end 3.5306 -3.353054)
			(stroke
				(width 0.1)
				(type default)
			)
			(layer "F.Fab")
		)
		(fp_line
			(start 3.5306 -3.353054)
			(end 3.5306 3.353054)
			(stroke
				(width 0.1)
				(type default)
			)
			(layer "F.Fab")
		)
		(pad "1A" smd rect
			(at -2.249932 0 90)
			(size 3.2004 6.858)
			(layers "F.Cu" "F.Mask" "F.Paste")
			(net "P12V_PSU")
		)
		(pad "1B" smd rect
			(at -0.776732 0 270)
			(size 0.254 0.508)
			(layers "F.Cu" "F.Mask" "F.Paste")
			(net "P12V_HSC_SENSE2_R3_P")
		)
		(pad "2A" smd rect
			(at 2.249932 0 90)
			(size 3.2004 6.858)
			(layers "F.Cu" "F.Mask" "F.Paste")
			(net "P12V_MAIN_R")
		)
		(pad "2B" smd rect
			(at 0.776732 0 270)
			(size 0.254 0.508)
			(layers "F.Cu" "F.Mask" "F.Paste")
			(net "P12V_HSC_SENSE2_R3_N")
		)
	)
	(footprint ""
		(layer "F.Cu")
		(at 354.731828 -400.328638 180)
		(property "Reference" "R2666"
			(at 0 0 180)
			(layer "F.SilkS")
			(hide yes)
			(effects
				(font
					(size 1.27 1.27)
				)
			)
		)
		(property "Value" ""
			(at 0 0 180)
			(layer "F.Fab")
			(effects
				(font
					(size 1.27 1.27)
				)
			)
		)
		(duplicate_pad_numbers_are_jumpers no)
		(fp_line
			(start 0.7874 0.4064)
			(end -0.7874 0.4064)
			(stroke
				(width 0.1524)
				(type default)
			)
			(layer "F.SilkS")
		)
		(fp_line
			(start 0.7874 -0.4064)
			(end 0.7874 0.4064)
			(stroke
				(width 0.1524)
				(type default)
			)
			(layer "F.SilkS")
		)
		(fp_line
			(start -0.7874 0.4064)
			(end -0.7874 -0.4064)
			(stroke
				(width 0.1524)
				(type default)
			)
			(layer "F.SilkS")
		)
		(fp_line
			(start -0.7874 -0.4064)
			(end 0.7874 -0.4064)
			(stroke
				(width 0.1524)
				(type default)
			)
			(layer "F.SilkS")
		)
		(fp_line
			(start 0.67945 0.3048)
			(end 0.120396 0.3048)
			(stroke
				(width 0.1)
				(type default)
			)
			(layer "F.Fab")
		)
		(fp_line
			(start 0.67945 -0.3048)
			(end 0.67945 0.3048)
			(stroke
				(width 0.1)
				(type default)
			)
			(layer "F.Fab")
		)
		(fp_line
			(start 0.12065 -0.2794)
			(end 0.12065 -0.3048)
			(stroke
				(width 0.1)
				(type default)
			)
			(layer "F.Fab")
		)
		(fp_line
			(start 0.12065 -0.3048)
			(end 0.67945 -0.3048)
			(stroke
				(width 0.1)
				(type default)
			)
			(layer "F.Fab")
		)
		(fp_line
			(start 0.120396 0.3048)
			(end 0.120396 0.2794)
			(stroke
				(width 0.1)
				(type default)
			)
			(layer "F.Fab")
		)
		(fp_line
			(start 0.120396 0.2794)
			(end -0.12065 0.2794)
			(stroke
				(width 0.1)
				(type default)
			)
			(layer "F.Fab")
		)
		(fp_line
			(start -0.12065 0.3048)
			(end -0.67945 0.3048)
			(stroke
				(width 0.1)
				(type default)
			)
			(layer "F.Fab")
		)
		(fp_line
			(start -0.12065 0.2794)
			(end -0.12065 0.3048)
			(stroke
				(width 0.1)
				(type default)
			)
			(layer "F.Fab")
		)
		(fp_line
			(start -0.12065 -0.2794)
			(end 0.12065 -0.2794)
			(stroke
				(width 0.1)
				(type default)
			)
			(layer "F.Fab")
		)
		(fp_line
			(start -0.12065 -0.305054)
			(end -0.12065 -0.2794)
			(stroke
				(width 0.1)
				(type default)
			)
			(layer "F.Fab")
		)
		(fp_line
			(start -0.67945 0.3048)
			(end -0.67945 -0.305054)
			(stroke
				(width 0.1)
				(type default)
			)
			(layer "F.Fab")
		)
		(fp_line
			(start -0.67945 -0.305054)
			(end -0.12065 -0.305054)
			(stroke
				(width 0.1)
				(type default)
			)
			(layer "F.Fab")
		)
		(pad "1" smd circle
			(at -0.40005 0 180)
			(size 0 0)
			(layers "F.Cu" "F.Mask" "F.Paste")
			(net "SMB_BMC_SWB_EN")
		)
		(pad "2" smd circle
			(at 0.40005 0 180)
			(size 0 0)
			(layers "F.Cu" "F.Mask" "F.Paste")
			(net "GND")
		)
	)
	(footprint ""
		(layer "F.Cu")
		(at 297.41622 -421.41521 90)
		(property "Reference" "R4133"
			(at 0 0 90)
			(layer "F.SilkS")
			(hide yes)
			(effects
				(font
					(size 1.27 1.27)
				)
			)
		)
		(property "Value" ""
			(at 0 0 90)
			(layer "F.Fab")
			(effects
				(font
					(size 1.27 1.27)
				)
			)
		)
		(duplicate_pad_numbers_are_jumpers no)
		(fp_line
			(start 0.7874 -0.4064)
			(end 0.7874 0.4064)
			(stroke
				(width 0.1524)
				(type default)
			)
			(layer "F.SilkS")
		)
		(fp_line
			(start -0.7874 -0.4064)
			(end 0.7874 -0.4064)
			(stroke
				(width 0.1524)
				(type default)
			)
			(layer "F.SilkS")
		)
		(fp_line
			(start 0.7874 0.4064)
			(end -0.7874 0.4064)
			(stroke
				(width 0.1524)
				(type default)
			)
			(layer "F.SilkS")
		)
		(fp_line
			(start -0.7874 0.4064)
			(end -0.7874 -0.4064)
			(stroke
				(width 0.1524)
				(type default)
			)
			(layer "F.SilkS")
		)
		(fp_line
			(start -0.12065 -0.305054)
			(end -0.12065 -0.2794)
			(stroke
				(width 0.1)
				(type default)
			)
			(layer "F.Fab")
		)
		(fp_line
			(start -0.67945 -0.305054)
			(end -0.12065 -0.305054)
			(stroke
				(width 0.1)
				(type default)
			)
			(layer "F.Fab")
		)
		(fp_line
			(start 0.67945 -0.3048)
			(end 0.67945 0.3048)
			(stroke
				(width 0.1)
				(type default)
			)
			(layer "F.Fab")
		)
		(fp_line
			(start 0.12065 -0.3048)
			(end 0.67945 -0.3048)
			(stroke
				(width 0.1)
				(type default)
			)
			(layer "F.Fab")
		)
		(fp_line
			(start 0.12065 -0.2794)
			(end 0.12065 -0.3048)
			(stroke
				(width 0.1)
				(type default)
			)
			(layer "F.Fab")
		)
		(fp_line
			(start -0.12065 -0.2794)
			(end 0.12065 -0.2794)
			(stroke
				(width 0.1)
				(type default)
			)
			(layer "F.Fab")
		)
		(fp_line
			(start 0.120396 0.2794)
			(end -0.12065 0.2794)
			(stroke
				(width 0.1)
				(type default)
			)
			(layer "F.Fab")
		)
		(fp_line
			(start -0.12065 0.2794)
			(end -0.12065 0.3048)
			(stroke
				(width 0.1)
				(type default)
			)
			(layer "F.Fab")
		)
		(fp_line
			(start 0.67945 0.3048)
			(end 0.120396 0.3048)
			(stroke
				(width 0.1)
				(type default)
			)
			(layer "F.Fab")
		)
		(fp_line
			(start 0.120396 0.3048)
			(end 0.120396 0.2794)
			(stroke
				(width 0.1)
				(type default)
			)
			(layer "F.Fab")
		)
		(fp_line
			(start -0.12065 0.3048)
			(end -0.67945 0.3048)
			(stroke
				(width 0.1)
				(type default)
			)
			(layer "F.Fab")
		)
		(fp_line
			(start -0.67945 0.3048)
			(end -0.67945 -0.305054)
			(stroke
				(width 0.1)
				(type default)
			)
			(layer "F.Fab")
		)
		(pad "1" smd circle
			(at -0.40005 0 90)
			(size 0 0)
			(layers "F.Cu" "F.Mask" "F.Paste")
			(net "P3V3_AUX")
		)
		(pad "2" smd circle
			(at 0.40005 0 90)
			(size 0 0)
			(layers "F.Cu" "F.Mask" "F.Paste")
			(net "GPU_3V3IO_RSVD5_FFU")
		)
	)
	(footprint ""
		(layer "F.Cu")
		(at 23.431754 -399.532094 90)
		(property "Reference" "R3284"
			(at 0 0 90)
			(layer "F.SilkS")
			(hide yes)
			(effects
				(font
					(size 1.27 1.27)
				)
			)
		)
		(property "Value" ""
			(at 0 0 90)
			(layer "F.Fab")
			(effects
				(font
					(size 1.27 1.27)
				)
			)
		)
		(duplicate_pad_numbers_are_jumpers no)
		(fp_line
			(start 0.7874 -0.4064)
			(end 0.7874 0.4064)
			(stroke
				(width 0.1524)
				(type default)
			)
			(layer "F.SilkS")
		)
		(fp_line
			(start -0.7874 -0.4064)
			(end 0.7874 -0.4064)
			(stroke
				(width 0.1524)
				(type default)
			)
			(layer "F.SilkS")
		)
		(fp_line
			(start 0.7874 0.4064)
			(end -0.7874 0.4064)
			(stroke
				(width 0.1524)
				(type default)
			)
			(layer "F.SilkS")
		)
		(fp_line
			(start -0.7874 0.4064)
			(end -0.7874 -0.4064)
			(stroke
				(width 0.1524)
				(type default)
			)
			(layer "F.SilkS")
		)
		(fp_line
			(start -0.12065 -0.305054)
			(end -0.12065 -0.2794)
			(stroke
				(width 0.1)
				(type default)
			)
			(layer "F.Fab")
		)
		(fp_line
			(start -0.67945 -0.305054)
			(end -0.12065 -0.305054)
			(stroke
				(width 0.1)
				(type default)
			)
			(layer "F.Fab")
		)
		(fp_line
			(start 0.67945 -0.3048)
			(end 0.67945 0.3048)
			(stroke
				(width 0.1)
				(type default)
			)
			(layer "F.Fab")
		)
		(fp_line
			(start 0.12065 -0.3048)
			(end 0.67945 -0.3048)
			(stroke
				(width 0.1)
				(type default)
			)
			(layer "F.Fab")
		)
		(fp_line
			(start 0.12065 -0.2794)
			(end 0.12065 -0.3048)
			(stroke
				(width 0.1)
				(type default)
			)
			(layer "F.Fab")
		)
		(fp_line
			(start -0.12065 -0.2794)
			(end 0.12065 -0.2794)
			(stroke
				(width 0.1)
				(type default)
			)
			(layer "F.Fab")
		)
		(fp_line
			(start 0.120396 0.2794)
			(end -0.12065 0.2794)
			(stroke
				(width 0.1)
				(type default)
			)
			(layer "F.Fab")
		)
		(fp_line
			(start -0.12065 0.2794)
			(end -0.12065 0.3048)
			(stroke
				(width 0.1)
				(type default)
			)
			(layer "F.Fab")
		)
		(fp_line
			(start 0.67945 0.3048)
			(end 0.120396 0.3048)
			(stroke
				(width 0.1)
				(type default)
			)
			(layer "F.Fab")
		)
		(fp_line
			(start 0.120396 0.3048)
			(end 0.120396 0.2794)
			(stroke
				(width 0.1)
				(type default)
			)
			(layer "F.Fab")
		)
		(fp_line
			(start -0.12065 0.3048)
			(end -0.67945 0.3048)
			(stroke
				(width 0.1)
				(type default)
			)
			(layer "F.Fab")
		)
		(fp_line
			(start -0.67945 0.3048)
			(end -0.67945 -0.305054)
			(stroke
				(width 0.1)
				(type default)
			)
			(layer "F.Fab")
		)
		(pad "1" smd circle
			(at -0.40005 0 90)
			(size 0 0)
			(layers "F.Cu" "F.Mask" "F.Paste")
			(net "FM_P2E_EQB0")
		)
		(pad "2" smd circle
			(at 0.40005 0 90)
			(size 0 0)
			(layers "F.Cu" "F.Mask" "F.Paste")
			(net "GND")
		)
	)
	(footprint ""
		(layer "F.Cu")
		(at 114.706654 -357.91775)
		(property "Reference" "PC554"
			(at 0 0 0)
			(layer "F.SilkS")
			(hide yes)
			(effects
				(font
					(size 1.27 1.27)
				)
			)
		)
		(property "Value" ""
			(at 0 0 0)
			(layer "F.Fab")
			(effects
				(font
					(size 1.27 1.27)
				)
			)
		)
		(duplicate_pad_numbers_are_jumpers no)
		(fp_line
			(start -0.7874 -0.4064)
			(end 0.7874 -0.4064)
			(stroke
				(width 0.1524)
				(type default)
			)
			(layer "F.SilkS")
		)
		(fp_line
			(start -0.7874 0.4064)
			(end -0.7874 -0.4064)
			(stroke
				(width 0.1524)
				(type default)
			)
			(layer "F.SilkS")
		)
		(fp_line
			(start 0.7874 -0.4064)
			(end 0.7874 0.4064)
			(stroke
				(width 0.1524)
				(type default)
			)
			(layer "F.SilkS")
		)
		(fp_line
			(start 0.7874 0.4064)
			(end -0.7874 0.4064)
			(stroke
				(width 0.1524)
				(type default)
			)
			(layer "F.SilkS")
		)
		(fp_line
			(start -0.67945 -0.305054)
			(end -0.12065 -0.305054)
			(stroke
				(width 0.1)
				(type default)
			)
			(layer "F.Fab")
		)
		(fp_line
			(start -0.67945 0.3048)
			(end -0.67945 -0.305054)
			(stroke
				(width 0.1)
				(type default)
			)
			(layer "F.Fab")
		)
		(fp_line
			(start -0.12065 -0.305054)
			(end -0.12065 -0.2794)
			(stroke
				(width 0.1)
				(type default)
			)
			(layer "F.Fab")
		)
		(fp_line
			(start -0.12065 -0.2794)
			(end 0.12065 -0.2794)
			(stroke
				(width 0.1)
				(type default)
			)
			(layer "F.Fab")
		)
		(fp_line
			(start -0.12065 0.2794)
			(end -0.12065 0.3048)
			(stroke
				(width 0.1)
				(type default)
			)
			(layer "F.Fab")
		)
		(fp_line
			(start -0.12065 0.3048)
			(end -0.67945 0.3048)
			(stroke
				(width 0.1)
				(type default)
			)
			(layer "F.Fab")
		)
		(fp_line
			(start 0.120396 0.2794)
			(end -0.12065 0.2794)
			(stroke
				(width 0.1)
				(type default)
			)
			(layer "F.Fab")
		)
		(fp_line
			(start 0.120396 0.3048)
			(end 0.120396 0.2794)
			(stroke
				(width 0.1)
				(type default)
			)
			(layer "F.Fab")
		)
		(fp_line
			(start 0.12065 -0.3048)
			(end 0.67945 -0.3048)
			(stroke
				(width 0.1)
				(type default)
			)
			(layer "F.Fab")
		)
		(fp_line
			(start 0.12065 -0.2794)
			(end 0.12065 -0.3048)
			(stroke
				(width 0.1)
				(type default)
			)
			(layer "F.Fab")
		)
		(fp_line
			(start 0.67945 -0.3048)
			(end 0.67945 0.3048)
			(stroke
				(width 0.1)
				(type default)
			)
			(layer "F.Fab")
		)
		(fp_line
			(start 0.67945 0.3048)
			(end 0.120396 0.3048)
			(stroke
				(width 0.1)
				(type default)
			)
			(layer "F.Fab")
		)
		(pad "1" smd circle
			(at -0.40005 0)
			(size 0 0)
			(layers "F.Cu" "F.Mask" "F.Paste")
			(net "PVCCIN_CPU1_ATSEN")
		)
		(pad "2" smd circle
			(at 0.40005 0)
			(size 0 0)
			(layers "F.Cu" "F.Mask" "F.Paste")
			(net "GND")
		)
	)
	(footprint ""
		(layer "F.Cu")
		(at 243.03228 -121.986548)
		(property "Reference" "R3200"
			(at 0 0 0)
			(layer "F.SilkS")
			(hide yes)
			(effects
				(font
					(size 1.27 1.27)
				)
			)
		)
		(property "Value" ""
			(at 0 0 0)
			(layer "F.Fab")
			(effects
				(font
					(size 1.27 1.27)
				)
			)
		)
		(duplicate_pad_numbers_are_jumpers no)
		(fp_line
			(start -0.7874 0.4064)
			(end -0.7874 -0.057912)
			(stroke
				(width 0.1524)
				(type default)
			)
			(layer "F.SilkS")
		)
		(fp_line
			(start -0.45212 -0.4064)
			(end 0.47498 -0.4064)
			(stroke
				(width 0.1524)
				(type default)
			)
			(layer "F.SilkS")
		)
		(fp_line
			(start 0.7874 -0.113792)
			(end 0.7874 0.4064)
			(stroke
				(width 0.1524)
				(type default)
			)
			(layer "F.SilkS")
		)
		(fp_line
			(start 0.7874 0.4064)
			(end -0.7874 0.4064)
			(stroke
				(width 0.1524)
				(type default)
			)
			(layer "F.SilkS")
		)
		(fp_line
			(start -0.67945 -0.305054)
			(end -0.12065 -0.305054)
			(stroke
				(width 0.1)
				(type default)
			)
			(layer "F.Fab")
		)
		(fp_line
			(start -0.67945 0.3048)
			(end -0.67945 -0.305054)
			(stroke
				(width 0.1)
				(type default)
			)
			(layer "F.Fab")
		)
		(fp_line
			(start -0.12065 -0.305054)
			(end -0.12065 -0.2794)
			(stroke
				(width 0.1)
				(type default)
			)
			(layer "F.Fab")
		)
		(fp_line
			(start -0.12065 -0.2794)
			(end 0.12065 -0.2794)
			(stroke
				(width 0.1)
				(type default)
			)
			(layer "F.Fab")
		)
		(fp_line
			(start -0.12065 0.2794)
			(end -0.12065 0.3048)
			(stroke
				(width 0.1)
				(type default)
			)
			(layer "F.Fab")
		)
		(fp_line
			(start -0.12065 0.3048)
			(end -0.67945 0.3048)
			(stroke
				(width 0.1)
				(type default)
			)
			(layer "F.Fab")
		)
		(fp_line
			(start 0.120396 0.2794)
			(end -0.12065 0.2794)
			(stroke
				(width 0.1)
				(type default)
			)
			(layer "F.Fab")
		)
		(fp_line
			(start 0.120396 0.3048)
			(end 0.120396 0.2794)
			(stroke
				(width 0.1)
				(type default)
			)
			(layer "F.Fab")
		)
		(fp_line
			(start 0.12065 -0.3048)
			(end 0.67945 -0.3048)
			(stroke
				(width 0.1)
				(type default)
			)
			(layer "F.Fab")
		)
		(fp_line
			(start 0.12065 -0.2794)
			(end 0.12065 -0.3048)
			(stroke
				(width 0.1)
				(type default)
			)
			(layer "F.Fab")
		)
		(fp_line
			(start 0.67945 -0.3048)
			(end 0.67945 0.3048)
			(stroke
				(width 0.1)
				(type default)
			)
			(layer "F.Fab")
		)
		(fp_line
			(start 0.67945 0.3048)
			(end 0.120396 0.3048)
			(stroke
				(width 0.1)
				(type default)
			)
			(layer "F.Fab")
		)
		(pad "1" smd circle
			(at -0.40005 0)
			(size 0 0)
			(layers "F.Cu" "F.Mask" "F.Paste")
			(net "CLK_100M_OCP_V3_2_D_R_DP")
		)
		(pad "2" smd circle
			(at 0.40005 0)
			(size 0 0)
			(layers "F.Cu" "F.Mask" "F.Paste")
			(net "CLK_100M_OCP_V3_2_D_DP")
		)
	)
	(footprint ""
		(layer "F.Cu")
		(at 236.649768 -272.499836)
		(property "Reference" "H99"
			(at -4.60756 -4.956048 0)
			(unlocked yes)
			(layer "F.SilkS")
			(effects
				(font
					(size 0.7874 0.5842)
					(thickness 0.1524)
				)
				(justify left)
			)
		)
		(property "Value" ""
			(at 0 0 0)
			(layer "F.Fab")
			(effects
				(font
					(size 1.27 1.27)
				)
			)
		)
		(duplicate_pad_numbers_are_jumpers no)
		(pad "1" thru_hole circle
			(at 0 0)
			(size 10.0076 10.0076)
			(drill 5.6134)
			(layers "*.Cu" "*.Mask")
			(remove_unused_layers no)
			(net "GND")
			(clearance -1.9431)
		)
	)
	(footprint ""
		(layer "F.Cu")
		(at 106.86542 -418.392864 180)
		(property "Reference" "R4477"
			(at 0 0 180)
			(layer "F.SilkS")
			(hide yes)
			(effects
				(font
					(size 1.27 1.27)
				)
			)
		)
		(property "Value" ""
			(at 0 0 180)
			(layer "F.Fab")
			(effects
				(font
					(size 1.27 1.27)
				)
			)
		)
		(duplicate_pad_numbers_are_jumpers no)
		(fp_line
			(start 0.7874 0.4064)
			(end -0.7874 0.4064)
			(stroke
				(width 0.1524)
				(type default)
			)
			(layer "F.SilkS")
		)
		(fp_line
			(start 0.7874 -0.4064)
			(end 0.7874 0.4064)
			(stroke
				(width 0.1524)
				(type default)
			)
			(layer "F.SilkS")
		)
		(fp_line
			(start -0.7874 0.4064)
			(end -0.7874 -0.4064)
			(stroke
				(width 0.1524)
				(type default)
			)
			(layer "F.SilkS")
		)
		(fp_line
			(start -0.7874 -0.4064)
			(end 0.7874 -0.4064)
			(stroke
				(width 0.1524)
				(type default)
			)
			(layer "F.SilkS")
		)
		(fp_line
			(start 0.67945 0.3048)
			(end 0.120396 0.3048)
			(stroke
				(width 0.1)
				(type default)
			)
			(layer "F.Fab")
		)
		(fp_line
			(start 0.67945 -0.3048)
			(end 0.67945 0.3048)
			(stroke
				(width 0.1)
				(type default)
			)
			(layer "F.Fab")
		)
		(fp_line
			(start 0.12065 -0.2794)
			(end 0.12065 -0.3048)
			(stroke
				(width 0.1)
				(type default)
			)
			(layer "F.Fab")
		)
		(fp_line
			(start 0.12065 -0.3048)
			(end 0.67945 -0.3048)
			(stroke
				(width 0.1)
				(type default)
			)
			(layer "F.Fab")
		)
		(fp_line
			(start 0.120396 0.3048)
			(end 0.120396 0.2794)
			(stroke
				(width 0.1)
				(type default)
			)
			(layer "F.Fab")
		)
		(fp_line
			(start 0.120396 0.2794)
			(end -0.12065 0.2794)
			(stroke
				(width 0.1)
				(type default)
			)
			(layer "F.Fab")
		)
		(fp_line
			(start -0.12065 0.3048)
			(end -0.67945 0.3048)
			(stroke
				(width 0.1)
				(type default)
			)
			(layer "F.Fab")
		)
		(fp_line
			(start -0.12065 0.2794)
			(end -0.12065 0.3048)
			(stroke
				(width 0.1)
				(type default)
			)
			(layer "F.Fab")
		)
		(fp_line
			(start -0.12065 -0.2794)
			(end 0.12065 -0.2794)
			(stroke
				(width 0.1)
				(type default)
			)
			(layer "F.Fab")
		)
		(fp_line
			(start -0.12065 -0.305054)
			(end -0.12065 -0.2794)
			(stroke
				(width 0.1)
				(type default)
			)
			(layer "F.Fab")
		)
		(fp_line
			(start -0.67945 0.3048)
			(end -0.67945 -0.305054)
			(stroke
				(width 0.1)
				(type default)
			)
			(layer "F.Fab")
		)
		(fp_line
			(start -0.67945 -0.305054)
			(end -0.12065 -0.305054)
			(stroke
				(width 0.1)
				(type default)
			)
			(layer "F.Fab")
		)
		(pad "1" smd circle
			(at -0.40005 0 180)
			(size 0 0)
			(layers "F.Cu" "F.Mask" "F.Paste")
			(net "FM_9ZXL045_0_OE_N")
		)
		(pad "2" smd circle
			(at 0.40005 0 180)
			(size 0 0)
			(layers "F.Cu" "F.Mask" "F.Paste")
			(net "CLK_SWB_BUF2_OE_N")
		)
	)
	(footprint ""
		(layer "F.Cu")
		(at 357.548942 -389.19277 180)
		(property "Reference" "C2273"
			(at 0 0 180)
			(layer "F.SilkS")
			(hide yes)
			(effects
				(font
					(size 1.27 1.27)
				)
			)
		)
		(property "Value" ""
			(at 0 0 180)
			(layer "F.Fab")
			(effects
				(font
					(size 1.27 1.27)
				)
			)
		)
		(duplicate_pad_numbers_are_jumpers no)
		(fp_line
			(start 0.7874 0.4064)
			(end -0.7874 0.4064)
			(stroke
				(width 0.1524)
				(type default)
			)
			(layer "F.SilkS")
		)
		(fp_line
			(start 0.7874 -0.4064)
			(end 0.7874 0.4064)
			(stroke
				(width 0.1524)
				(type default)
			)
			(layer "F.SilkS")
		)
		(fp_line
			(start -0.7874 0.4064)
			(end -0.7874 -0.4064)
			(stroke
				(width 0.1524)
				(type default)
			)
			(layer "F.SilkS")
		)
		(fp_line
			(start -0.7874 -0.4064)
			(end 0.7874 -0.4064)
			(stroke
				(width 0.1524)
				(type default)
			)
			(layer "F.SilkS")
		)
		(fp_line
			(start 0.67945 0.3048)
			(end 0.120396 0.3048)
			(stroke
				(width 0.1)
				(type default)
			)
			(layer "F.Fab")
		)
		(fp_line
			(start 0.67945 -0.3048)
			(end 0.67945 0.3048)
			(stroke
				(width 0.1)
				(type default)
			)
			(layer "F.Fab")
		)
		(fp_line
			(start 0.12065 -0.2794)
			(end 0.12065 -0.3048)
			(stroke
				(width 0.1)
				(type default)
			)
			(layer "F.Fab")
		)
		(fp_line
			(start 0.12065 -0.3048)
			(end 0.67945 -0.3048)
			(stroke
				(width 0.1)
				(type default)
			)
			(layer "F.Fab")
		)
		(fp_line
			(start 0.120396 0.3048)
			(end 0.120396 0.2794)
			(stroke
				(width 0.1)
				(type default)
			)
			(layer "F.Fab")
		)
		(fp_line
			(start 0.120396 0.2794)
			(end -0.12065 0.2794)
			(stroke
				(width 0.1)
				(type default)
			)
			(layer "F.Fab")
		)
		(fp_line
			(start -0.12065 0.3048)
			(end -0.67945 0.3048)
			(stroke
				(width 0.1)
				(type default)
			)
			(layer "F.Fab")
		)
		(fp_line
			(start -0.12065 0.2794)
			(end -0.12065 0.3048)
			(stroke
				(width 0.1)
				(type default)
			)
			(layer "F.Fab")
		)
		(fp_line
			(start -0.12065 -0.2794)
			(end 0.12065 -0.2794)
			(stroke
				(width 0.1)
				(type default)
			)
			(layer "F.Fab")
		)
		(fp_line
			(start -0.12065 -0.305054)
			(end -0.12065 -0.2794)
			(stroke
				(width 0.1)
				(type default)
			)
			(layer "F.Fab")
		)
		(fp_line
			(start -0.67945 0.3048)
			(end -0.67945 -0.305054)
			(stroke
				(width 0.1)
				(type default)
			)
			(layer "F.Fab")
		)
		(fp_line
			(start -0.67945 -0.305054)
			(end -0.12065 -0.305054)
			(stroke
				(width 0.1)
				(type default)
			)
			(layer "F.Fab")
		)
		(pad "1" smd circle
			(at -0.40005 0 180)
			(size 0 0)
			(layers "F.Cu" "F.Mask" "F.Paste")
			(net "GPU_3V3IO_RSVD3_ISO")
		)
		(pad "2" smd circle
			(at 0.40005 0 180)
			(size 0 0)
			(layers "F.Cu" "F.Mask" "F.Paste")
			(net "GND")
		)
	)
	(footprint ""
		(layer "F.Cu")
		(at 459.437486 -93.627448)
		(property "Reference" "U224"
			(at -1.651 -1.793748 0)
			(unlocked yes)
			(layer "F.SilkS")
			(effects
				(font
					(size 0.7874 0.5842)
					(thickness 0.1524)
				)
				(justify left)
			)
		)
		(property "Value" ""
			(at 0 0 0)
			(layer "F.Fab")
			(effects
				(font
					(size 1.27 1.27)
				)
			)
		)
		(duplicate_pad_numbers_are_jumpers no)
		(fp_line
			(start -1.400048 1.100074)
			(end -1.400048 -1.100074)
			(stroke
				(width 0.1524)
				(type default)
			)
			(layer "F.SilkS")
		)
		(fp_line
			(start 1.400048 -1.100074)
			(end -1.400048 -1.100074)
			(stroke
				(width 0.1524)
				(type default)
			)
			(layer "F.SilkS")
		)
		(fp_line
			(start 1.400048 -1.100074)
			(end 1.400048 1.100074)
			(stroke
				(width 0.1524)
				(type default)
			)
			(layer "F.SilkS")
		)
		(fp_line
			(start 1.400048 1.100074)
			(end -1.400048 1.100074)
			(stroke
				(width 0.1524)
				(type default)
			)
			(layer "F.SilkS")
		)
		(fp_poly
			(pts
				(xy -1.590548 -0.649986) (xy -2.606548 -0.141986) (xy -2.606548 -1.157986)
			)
			(stroke
				(width 0)
				(type default)
			)
			(fill yes)
			(layer "F.SilkS")
		)
		(fp_line
			(start -0.674878 -1.100074)
			(end 0.674878 -1.100074)
			(stroke
				(width 0.1)
				(type default)
			)
			(layer "F.Fab")
		)
		(fp_line
			(start -0.674878 1.100074)
			(end -0.674878 -1.100074)
			(stroke
				(width 0.1)
				(type default)
			)
			(layer "F.Fab")
		)
		(fp_line
			(start 0.674878 -1.100074)
			(end 0.674878 1.100074)
			(stroke
				(width 0.1)
				(type default)
			)
			(layer "F.Fab")
		)
		(fp_line
			(start 0.674878 1.100074)
			(end -0.674878 1.100074)
			(stroke
				(width 0.1)
				(type default)
			)
			(layer "F.Fab")
		)
		(fp_poly
			(pts
				(xy -1.590548 -0.649986) (xy -2.606548 -1.157986) (xy -2.606548 -0.141986)
			)
			(stroke
				(width 0)
				(type default)
			)
			(fill yes)
			(layer "F.Fab")
		)
		(pad "1" smd rect
			(at -0.94996 -0.649986 270)
			(size 0.4318 0.6096)
			(layers "F.Cu" "F.Mask" "F.Paste")
			(net "OCP_SFF_AUX_PWR_EN_R4")
		)
		(pad "2" smd rect
			(at -0.94996 0 270)
			(size 0.4318 0.6096)
			(layers "F.Cu" "F.Mask" "F.Paste")
			(net "RST_SMB_SWITCH_N")
		)
		(pad "3" smd rect
			(at -0.94996 0.649986 270)
			(size 0.4318 0.6096)
			(layers "F.Cu" "F.Mask" "F.Paste")
			(net "GND")
		)
		(pad "4" smd rect
			(at 0.94996 0.649986 270)
			(size 0.4318 0.6096)
			(layers "F.Cu" "F.Mask" "F.Paste")
			(net "RST_HP_OCP_SFF_R_N")
		)
		(pad "5" smd rect
			(at 0.94996 -0.649986 270)
			(size 0.4318 0.6096)
			(layers "F.Cu" "F.Mask" "F.Paste")
			(net "P3V3_AUX")
		)
	)
	(footprint ""
		(layer "F.Cu")
		(at 436.526432 -27.275536 90)
		(property "Reference" "PR3840"
			(at 0 0 90)
			(layer "F.SilkS")
			(hide yes)
			(effects
				(font
					(size 1.27 1.27)
				)
			)
		)
		(property "Value" ""
			(at 0 0 90)
			(layer "F.Fab")
			(effects
				(font
					(size 1.27 1.27)
				)
			)
		)
		(duplicate_pad_numbers_are_jumpers no)
		(fp_line
			(start 0.7874 -0.4064)
			(end 0.7874 0.4064)
			(stroke
				(width 0.1524)
				(type default)
			)
			(layer "F.SilkS")
		)
		(fp_line
			(start -0.7874 -0.4064)
			(end 0.7874 -0.4064)
			(stroke
				(width 0.1524)
				(type default)
			)
			(layer "F.SilkS")
		)
		(fp_line
			(start 0.7874 0.4064)
			(end -0.7874 0.4064)
			(stroke
				(width 0.1524)
				(type default)
			)
			(layer "F.SilkS")
		)
		(fp_line
			(start -0.7874 0.4064)
			(end -0.7874 -0.4064)
			(stroke
				(width 0.1524)
				(type default)
			)
			(layer "F.SilkS")
		)
		(fp_line
			(start -0.12065 -0.305054)
			(end -0.12065 -0.2794)
			(stroke
				(width 0.1)
				(type default)
			)
			(layer "F.Fab")
		)
		(fp_line
			(start -0.67945 -0.305054)
			(end -0.12065 -0.305054)
			(stroke
				(width 0.1)
				(type default)
			)
			(layer "F.Fab")
		)
		(fp_line
			(start 0.67945 -0.3048)
			(end 0.67945 0.3048)
			(stroke
				(width 0.1)
				(type default)
			)
			(layer "F.Fab")
		)
		(fp_line
			(start 0.12065 -0.3048)
			(end 0.67945 -0.3048)
			(stroke
				(width 0.1)
				(type default)
			)
			(layer "F.Fab")
		)
		(fp_line
			(start 0.12065 -0.2794)
			(end 0.12065 -0.3048)
			(stroke
				(width 0.1)
				(type default)
			)
			(layer "F.Fab")
		)
		(fp_line
			(start -0.12065 -0.2794)
			(end 0.12065 -0.2794)
			(stroke
				(width 0.1)
				(type default)
			)
			(layer "F.Fab")
		)
		(fp_line
			(start 0.120396 0.2794)
			(end -0.12065 0.2794)
			(stroke
				(width 0.1)
				(type default)
			)
			(layer "F.Fab")
		)
		(fp_line
			(start -0.12065 0.2794)
			(end -0.12065 0.3048)
			(stroke
				(width 0.1)
				(type default)
			)
			(layer "F.Fab")
		)
		(fp_line
			(start 0.67945 0.3048)
			(end 0.120396 0.3048)
			(stroke
				(width 0.1)
				(type default)
			)
			(layer "F.Fab")
		)
		(fp_line
			(start 0.120396 0.3048)
			(end 0.120396 0.2794)
			(stroke
				(width 0.1)
				(type default)
			)
			(layer "F.Fab")
		)
		(fp_line
			(start -0.12065 0.3048)
			(end -0.67945 0.3048)
			(stroke
				(width 0.1)
				(type default)
			)
			(layer "F.Fab")
		)
		(fp_line
			(start -0.67945 0.3048)
			(end -0.67945 -0.305054)
			(stroke
				(width 0.1)
				(type default)
			)
			(layer "F.Fab")
		)
		(pad "1" smd circle
			(at -0.40005 0 90)
			(size 0 0)
			(layers "F.Cu" "F.Mask" "F.Paste")
			(net "P12V_OCP_SFF")
		)
		(pad "2" smd circle
			(at 0.40005 0 90)
			(size 0 0)
			(layers "F.Cu" "F.Mask" "F.Paste")
			(net "P12V_OCP_OV_FB_1")
		)
	)
	(footprint ""
		(layer "F.Cu")
		(at 106.322114 -260.36524 -90)
		(property "Reference" "C435"
			(at 0 0 270)
			(layer "F.SilkS")
			(hide yes)
			(effects
				(font
					(size 1.27 1.27)
				)
			)
		)
		(property "Value" ""
			(at 0 0 270)
			(layer "F.Fab")
			(effects
				(font
					(size 1.27 1.27)
				)
			)
		)
		(duplicate_pad_numbers_are_jumpers no)
		(fp_line
			(start -0.7874 0.4064)
			(end -0.7874 -0.4064)
			(stroke
				(width 0.1524)
				(type default)
			)
			(layer "F.SilkS")
		)
		(fp_line
			(start 0.7874 0.4064)
			(end -0.7874 0.4064)
			(stroke
				(width 0.1524)
				(type default)
			)
			(layer "F.SilkS")
		)
		(fp_line
			(start -0.7874 -0.4064)
			(end 0.7874 -0.4064)
			(stroke
				(width 0.1524)
				(type default)
			)
			(layer "F.SilkS")
		)
		(fp_line
			(start 0.7874 -0.4064)
			(end 0.7874 0.4064)
			(stroke
				(width 0.1524)
				(type default)
			)
			(layer "F.SilkS")
		)
		(fp_line
			(start -0.67945 0.3048)
			(end -0.67945 -0.305054)
			(stroke
				(width 0.1)
				(type default)
			)
			(layer "F.Fab")
		)
		(fp_line
			(start -0.12065 0.3048)
			(end -0.67945 0.3048)
			(stroke
				(width 0.1)
				(type default)
			)
			(layer "F.Fab")
		)
		(fp_line
			(start 0.120396 0.3048)
			(end 0.120396 0.2794)
			(stroke
				(width 0.1)
				(type default)
			)
			(layer "F.Fab")
		)
		(fp_line
			(start 0.67945 0.3048)
			(end 0.120396 0.3048)
			(stroke
				(width 0.1)
				(type default)
			)
			(layer "F.Fab")
		)
		(fp_line
			(start -0.12065 0.2794)
			(end -0.12065 0.3048)
			(stroke
				(width 0.1)
				(type default)
			)
			(layer "F.Fab")
		)
		(fp_line
			(start 0.120396 0.2794)
			(end -0.12065 0.2794)
			(stroke
				(width 0.1)
				(type default)
			)
			(layer "F.Fab")
		)
		(fp_line
			(start -0.12065 -0.2794)
			(end 0.12065 -0.2794)
			(stroke
				(width 0.1)
				(type default)
			)
			(layer "F.Fab")
		)
		(fp_line
			(start 0.12065 -0.2794)
			(end 0.12065 -0.3048)
			(stroke
				(width 0.1)
				(type default)
			)
			(layer "F.Fab")
		)
		(fp_line
			(start 0.12065 -0.3048)
			(end 0.67945 -0.3048)
			(stroke
				(width 0.1)
				(type default)
			)
			(layer "F.Fab")
		)
		(fp_line
			(start 0.67945 -0.3048)
			(end 0.67945 0.3048)
			(stroke
				(width 0.1)
				(type default)
			)
			(layer "F.Fab")
		)
		(fp_line
			(start -0.67945 -0.305054)
			(end -0.12065 -0.305054)
			(stroke
				(width 0.1)
				(type default)
			)
			(layer "F.Fab")
		)
		(fp_line
			(start -0.12065 -0.305054)
			(end -0.12065 -0.2794)
			(stroke
				(width 0.1)
				(type default)
			)
			(layer "F.Fab")
		)
		(pad "1" smd circle
			(at -0.40005 0 270)
			(size 0 0)
			(layers "F.Cu" "F.Mask" "F.Paste")
			(net "PVCCFA_EHV_FIVRA_CPU1")
		)
		(pad "2" smd circle
			(at 0.40005 0 270)
			(size 0 0)
			(layers "F.Cu" "F.Mask" "F.Paste")
			(net "GND")
		)
	)
	(footprint ""
		(layer "F.Cu")
		(at 132.51688 -100.167948 -90)
		(property "Reference" "R202"
			(at 0 0 270)
			(layer "F.SilkS")
			(hide yes)
			(effects
				(font
					(size 1.27 1.27)
				)
			)
		)
		(property "Value" ""
			(at 0 0 270)
			(layer "F.Fab")
			(effects
				(font
					(size 1.27 1.27)
				)
			)
		)
		(duplicate_pad_numbers_are_jumpers no)
		(fp_line
			(start -0.7874 0.4064)
			(end -0.7874 -0.4064)
			(stroke
				(width 0.1524)
				(type default)
			)
			(layer "F.SilkS")
		)
		(fp_line
			(start 0.7874 0.4064)
			(end -0.7874 0.4064)
			(stroke
				(width 0.1524)
				(type default)
			)
			(layer "F.SilkS")
		)
		(fp_line
			(start -0.7874 -0.4064)
			(end 0.7874 -0.4064)
			(stroke
				(width 0.1524)
				(type default)
			)
			(layer "F.SilkS")
		)
		(fp_line
			(start 0.7874 -0.4064)
			(end 0.7874 0.4064)
			(stroke
				(width 0.1524)
				(type default)
			)
			(layer "F.SilkS")
		)
		(fp_line
			(start -0.67945 0.3048)
			(end -0.67945 -0.305054)
			(stroke
				(width 0.1)
				(type default)
			)
			(layer "F.Fab")
		)
		(fp_line
			(start -0.12065 0.3048)
			(end -0.67945 0.3048)
			(stroke
				(width 0.1)
				(type default)
			)
			(layer "F.Fab")
		)
		(fp_line
			(start 0.120396 0.3048)
			(end 0.120396 0.2794)
			(stroke
				(width 0.1)
				(type default)
			)
			(layer "F.Fab")
		)
		(fp_line
			(start 0.67945 0.3048)
			(end 0.120396 0.3048)
			(stroke
				(width 0.1)
				(type default)
			)
			(layer "F.Fab")
		)
		(fp_line
			(start -0.12065 0.2794)
			(end -0.12065 0.3048)
			(stroke
				(width 0.1)
				(type default)
			)
			(layer "F.Fab")
		)
		(fp_line
			(start 0.120396 0.2794)
			(end -0.12065 0.2794)
			(stroke
				(width 0.1)
				(type default)
			)
			(layer "F.Fab")
		)
		(fp_line
			(start -0.12065 -0.2794)
			(end 0.12065 -0.2794)
			(stroke
				(width 0.1)
				(type default)
			)
			(layer "F.Fab")
		)
		(fp_line
			(start 0.12065 -0.2794)
			(end 0.12065 -0.3048)
			(stroke
				(width 0.1)
				(type default)
			)
			(layer "F.Fab")
		)
		(fp_line
			(start 0.12065 -0.3048)
			(end 0.67945 -0.3048)
			(stroke
				(width 0.1)
				(type default)
			)
			(layer "F.Fab")
		)
		(fp_line
			(start 0.67945 -0.3048)
			(end 0.67945 0.3048)
			(stroke
				(width 0.1)
				(type default)
			)
			(layer "F.Fab")
		)
		(fp_line
			(start -0.67945 -0.305054)
			(end -0.12065 -0.305054)
			(stroke
				(width 0.1)
				(type default)
			)
			(layer "F.Fab")
		)
		(fp_line
			(start -0.12065 -0.305054)
			(end -0.12065 -0.2794)
			(stroke
				(width 0.1)
				(type default)
			)
			(layer "F.Fab")
		)
		(pad "1" smd circle
			(at -0.40005 0 270)
			(size 0 0)
			(layers "F.Cu" "F.Mask" "F.Paste")
			(net "PVNN_TERM_CPU1")
		)
		(pad "2" smd circle
			(at 0.40005 0 270)
			(size 0 0)
			(layers "F.Cu" "F.Mask" "F.Paste")
			(net "H_CPU1_MEMTRIP_LVC1_R_N")
		)
	)
	(footprint ""
		(layer "F.Cu")
		(at 13.546582 -423.629836 -90)
		(property "Reference" "R2982"
			(at 0 0 270)
			(layer "F.SilkS")
			(hide yes)
			(effects
				(font
					(size 1.27 1.27)
				)
			)
		)
		(property "Value" ""
			(at 0 0 270)
			(layer "F.Fab")
			(effects
				(font
					(size 1.27 1.27)
				)
			)
		)
		(duplicate_pad_numbers_are_jumpers no)
		(fp_line
			(start -0.7874 0.4064)
			(end -0.7874 -0.4064)
			(stroke
				(width 0.1524)
				(type default)
			)
			(layer "F.SilkS")
		)
		(fp_line
			(start 0.7874 0.4064)
			(end -0.7874 0.4064)
			(stroke
				(width 0.1524)
				(type default)
			)
			(layer "F.SilkS")
		)
		(fp_line
			(start -0.7874 -0.4064)
			(end 0.7874 -0.4064)
			(stroke
				(width 0.1524)
				(type default)
			)
			(layer "F.SilkS")
		)
		(fp_line
			(start 0.7874 -0.4064)
			(end 0.7874 0.4064)
			(stroke
				(width 0.1524)
				(type default)
			)
			(layer "F.SilkS")
		)
		(fp_line
			(start -0.67945 0.3048)
			(end -0.67945 -0.305054)
			(stroke
				(width 0.1)
				(type default)
			)
			(layer "F.Fab")
		)
		(fp_line
			(start -0.12065 0.3048)
			(end -0.67945 0.3048)
			(stroke
				(width 0.1)
				(type default)
			)
			(layer "F.Fab")
		)
		(fp_line
			(start 0.120396 0.3048)
			(end 0.120396 0.2794)
			(stroke
				(width 0.1)
				(type default)
			)
			(layer "F.Fab")
		)
		(fp_line
			(start 0.67945 0.3048)
			(end 0.120396 0.3048)
			(stroke
				(width 0.1)
				(type default)
			)
			(layer "F.Fab")
		)
		(fp_line
			(start -0.12065 0.2794)
			(end -0.12065 0.3048)
			(stroke
				(width 0.1)
				(type default)
			)
			(layer "F.Fab")
		)
		(fp_line
			(start 0.120396 0.2794)
			(end -0.12065 0.2794)
			(stroke
				(width 0.1)
				(type default)
			)
			(layer "F.Fab")
		)
		(fp_line
			(start -0.12065 -0.2794)
			(end 0.12065 -0.2794)
			(stroke
				(width 0.1)
				(type default)
			)
			(layer "F.Fab")
		)
		(fp_line
			(start 0.12065 -0.2794)
			(end 0.12065 -0.3048)
			(stroke
				(width 0.1)
				(type default)
			)
			(layer "F.Fab")
		)
		(fp_line
			(start 0.12065 -0.3048)
			(end 0.67945 -0.3048)
			(stroke
				(width 0.1)
				(type default)
			)
			(layer "F.Fab")
		)
		(fp_line
			(start 0.67945 -0.3048)
			(end 0.67945 0.3048)
			(stroke
				(width 0.1)
				(type default)
			)
			(layer "F.Fab")
		)
		(fp_line
			(start -0.67945 -0.305054)
			(end -0.12065 -0.305054)
			(stroke
				(width 0.1)
				(type default)
			)
			(layer "F.Fab")
		)
		(fp_line
			(start -0.12065 -0.305054)
			(end -0.12065 -0.2794)
			(stroke
				(width 0.1)
				(type default)
			)
			(layer "F.Fab")
		)
		(pad "1" smd circle
			(at -0.40005 0 270)
			(size 0 0)
			(layers "F.Cu" "F.Mask" "F.Paste")
			(net "SMB_IOEXP_3V3AUX_SCL")
		)
		(pad "2" smd circle
			(at 0.40005 0 270)
			(size 0 0)
			(layers "F.Cu" "F.Mask" "F.Paste")
			(net "SMB_IOEXP_3V3AUX_SCL_R1")
		)
	)
	(footprint ""
		(layer "F.Cu")
		(at 9.58088 -59.019948)
		(property "Reference" "R3059"
			(at 0 0 0)
			(layer "F.SilkS")
			(hide yes)
			(effects
				(font
					(size 1.27 1.27)
				)
			)
		)
		(property "Value" ""
			(at 0 0 0)
			(layer "F.Fab")
			(effects
				(font
					(size 1.27 1.27)
				)
			)
		)
		(duplicate_pad_numbers_are_jumpers no)
		(fp_line
			(start -0.7874 -0.4064)
			(end 0.7874 -0.4064)
			(stroke
				(width 0.1524)
				(type default)
			)
			(layer "F.SilkS")
		)
		(fp_line
			(start -0.7874 0.4064)
			(end -0.7874 -0.4064)
			(stroke
				(width 0.1524)
				(type default)
			)
			(layer "F.SilkS")
		)
		(fp_line
			(start 0.7874 -0.4064)
			(end 0.7874 0.4064)
			(stroke
				(width 0.1524)
				(type default)
			)
			(layer "F.SilkS")
		)
		(fp_line
			(start 0.7874 0.4064)
			(end -0.7874 0.4064)
			(stroke
				(width 0.1524)
				(type default)
			)
			(layer "F.SilkS")
		)
		(fp_line
			(start -0.67945 -0.305054)
			(end -0.12065 -0.305054)
			(stroke
				(width 0.1)
				(type default)
			)
			(layer "F.Fab")
		)
		(fp_line
			(start -0.67945 0.3048)
			(end -0.67945 -0.305054)
			(stroke
				(width 0.1)
				(type default)
			)
			(layer "F.Fab")
		)
		(fp_line
			(start -0.12065 -0.305054)
			(end -0.12065 -0.2794)
			(stroke
				(width 0.1)
				(type default)
			)
			(layer "F.Fab")
		)
		(fp_line
			(start -0.12065 -0.2794)
			(end 0.12065 -0.2794)
			(stroke
				(width 0.1)
				(type default)
			)
			(layer "F.Fab")
		)
		(fp_line
			(start -0.12065 0.2794)
			(end -0.12065 0.3048)
			(stroke
				(width 0.1)
				(type default)
			)
			(layer "F.Fab")
		)
		(fp_line
			(start -0.12065 0.3048)
			(end -0.67945 0.3048)
			(stroke
				(width 0.1)
				(type default)
			)
			(layer "F.Fab")
		)
		(fp_line
			(start 0.120396 0.2794)
			(end -0.12065 0.2794)
			(stroke
				(width 0.1)
				(type default)
			)
			(layer "F.Fab")
		)
		(fp_line
			(start 0.120396 0.3048)
			(end 0.120396 0.2794)
			(stroke
				(width 0.1)
				(type default)
			)
			(layer "F.Fab")
		)
		(fp_line
			(start 0.12065 -0.3048)
			(end 0.67945 -0.3048)
			(stroke
				(width 0.1)
				(type default)
			)
			(layer "F.Fab")
		)
		(fp_line
			(start 0.12065 -0.2794)
			(end 0.12065 -0.3048)
			(stroke
				(width 0.1)
				(type default)
			)
			(layer "F.Fab")
		)
		(fp_line
			(start 0.67945 -0.3048)
			(end 0.67945 0.3048)
			(stroke
				(width 0.1)
				(type default)
			)
			(layer "F.Fab")
		)
		(fp_line
			(start 0.67945 0.3048)
			(end 0.120396 0.3048)
			(stroke
				(width 0.1)
				(type default)
			)
			(layer "F.Fab")
		)
		(pad "1" smd circle
			(at -0.40005 0)
			(size 0 0)
			(layers "F.Cu" "F.Mask" "F.Paste")
			(net "SMB_SML0_3V3AUX_SDA")
		)
		(pad "2" smd circle
			(at 0.40005 0)
			(size 0 0)
			(layers "F.Cu" "F.Mask" "F.Paste")
			(net "SMB_SML0_ME_SDA")
		)
	)
	(footprint ""
		(layer "F.Cu")
		(at 421.038528 -140.186156 -90)
		(property "Reference" "PR121"
			(at 0 0 270)
			(layer "F.SilkS")
			(hide yes)
			(effects
				(font
					(size 1.27 1.27)
				)
			)
		)
		(property "Value" ""
			(at 0 0 270)
			(layer "F.Fab")
			(effects
				(font
					(size 1.27 1.27)
				)
			)
		)
		(duplicate_pad_numbers_are_jumpers no)
		(fp_line
			(start -0.7874 0.4064)
			(end -0.7874 -0.4064)
			(stroke
				(width 0.1524)
				(type default)
			)
			(layer "F.SilkS")
		)
		(fp_line
			(start 0.7874 0.4064)
			(end -0.7874 0.4064)
			(stroke
				(width 0.1524)
				(type default)
			)
			(layer "F.SilkS")
		)
		(fp_line
			(start -0.7874 -0.4064)
			(end 0.7874 -0.4064)
			(stroke
				(width 0.1524)
				(type default)
			)
			(layer "F.SilkS")
		)
		(fp_line
			(start 0.7874 -0.4064)
			(end 0.7874 0.4064)
			(stroke
				(width 0.1524)
				(type default)
			)
			(layer "F.SilkS")
		)
		(fp_line
			(start -0.67945 0.3048)
			(end -0.67945 -0.305054)
			(stroke
				(width 0.1)
				(type default)
			)
			(layer "F.Fab")
		)
		(fp_line
			(start -0.12065 0.3048)
			(end -0.67945 0.3048)
			(stroke
				(width 0.1)
				(type default)
			)
			(layer "F.Fab")
		)
		(fp_line
			(start 0.120396 0.3048)
			(end 0.120396 0.2794)
			(stroke
				(width 0.1)
				(type default)
			)
			(layer "F.Fab")
		)
		(fp_line
			(start 0.67945 0.3048)
			(end 0.120396 0.3048)
			(stroke
				(width 0.1)
				(type default)
			)
			(layer "F.Fab")
		)
		(fp_line
			(start -0.12065 0.2794)
			(end -0.12065 0.3048)
			(stroke
				(width 0.1)
				(type default)
			)
			(layer "F.Fab")
		)
		(fp_line
			(start 0.120396 0.2794)
			(end -0.12065 0.2794)
			(stroke
				(width 0.1)
				(type default)
			)
			(layer "F.Fab")
		)
		(fp_line
			(start -0.12065 -0.2794)
			(end 0.12065 -0.2794)
			(stroke
				(width 0.1)
				(type default)
			)
			(layer "F.Fab")
		)
		(fp_line
			(start 0.12065 -0.2794)
			(end 0.12065 -0.3048)
			(stroke
				(width 0.1)
				(type default)
			)
			(layer "F.Fab")
		)
		(fp_line
			(start 0.12065 -0.3048)
			(end 0.67945 -0.3048)
			(stroke
				(width 0.1)
				(type default)
			)
			(layer "F.Fab")
		)
		(fp_line
			(start 0.67945 -0.3048)
			(end 0.67945 0.3048)
			(stroke
				(width 0.1)
				(type default)
			)
			(layer "F.Fab")
		)
		(fp_line
			(start -0.67945 -0.305054)
			(end -0.12065 -0.305054)
			(stroke
				(width 0.1)
				(type default)
			)
			(layer "F.Fab")
		)
		(fp_line
			(start -0.12065 -0.305054)
			(end -0.12065 -0.2794)
			(stroke
				(width 0.1)
				(type default)
			)
			(layer "F.Fab")
		)
		(pad "1" smd circle
			(at -0.40005 0 270)
			(size 0 0)
			(layers "F.Cu" "F.Mask" "F.Paste")
			(net "SH_PVCCFA_EHV_CPU0")
		)
		(pad "2" smd circle
			(at 0.40005 0 270)
			(size 0 0)
			(layers "F.Cu" "F.Mask" "F.Paste")
			(net "SH_PVCCFA_EHV_CPU0_R")
		)
	)
	(footprint ""
		(layer "F.Cu")
		(at 367.44783 -258.726686 90)
		(property "Reference" "C980"
			(at 0 0 90)
			(layer "F.SilkS")
			(hide yes)
			(effects
				(font
					(size 1.27 1.27)
				)
			)
		)
		(property "Value" ""
			(at 0 0 90)
			(layer "F.Fab")
			(effects
				(font
					(size 1.27 1.27)
				)
			)
		)
		(duplicate_pad_numbers_are_jumpers no)
		(fp_line
			(start 0.7874 -0.4064)
			(end 0.7874 0.4064)
			(stroke
				(width 0.1524)
				(type default)
			)
			(layer "F.SilkS")
		)
		(fp_line
			(start -0.7874 -0.4064)
			(end 0.7874 -0.4064)
			(stroke
				(width 0.1524)
				(type default)
			)
			(layer "F.SilkS")
		)
		(fp_line
			(start 0.7874 0.4064)
			(end -0.7874 0.4064)
			(stroke
				(width 0.1524)
				(type default)
			)
			(layer "F.SilkS")
		)
		(fp_line
			(start -0.7874 0.4064)
			(end -0.7874 -0.4064)
			(stroke
				(width 0.1524)
				(type default)
			)
			(layer "F.SilkS")
		)
		(fp_line
			(start -0.12065 -0.305054)
			(end -0.12065 -0.2794)
			(stroke
				(width 0.1)
				(type default)
			)
			(layer "F.Fab")
		)
		(fp_line
			(start -0.67945 -0.305054)
			(end -0.12065 -0.305054)
			(stroke
				(width 0.1)
				(type default)
			)
			(layer "F.Fab")
		)
		(fp_line
			(start 0.67945 -0.3048)
			(end 0.67945 0.3048)
			(stroke
				(width 0.1)
				(type default)
			)
			(layer "F.Fab")
		)
		(fp_line
			(start 0.12065 -0.3048)
			(end 0.67945 -0.3048)
			(stroke
				(width 0.1)
				(type default)
			)
			(layer "F.Fab")
		)
		(fp_line
			(start 0.12065 -0.2794)
			(end 0.12065 -0.3048)
			(stroke
				(width 0.1)
				(type default)
			)
			(layer "F.Fab")
		)
		(fp_line
			(start -0.12065 -0.2794)
			(end 0.12065 -0.2794)
			(stroke
				(width 0.1)
				(type default)
			)
			(layer "F.Fab")
		)
		(fp_line
			(start 0.120396 0.2794)
			(end -0.12065 0.2794)
			(stroke
				(width 0.1)
				(type default)
			)
			(layer "F.Fab")
		)
		(fp_line
			(start -0.12065 0.2794)
			(end -0.12065 0.3048)
			(stroke
				(width 0.1)
				(type default)
			)
			(layer "F.Fab")
		)
		(fp_line
			(start 0.67945 0.3048)
			(end 0.120396 0.3048)
			(stroke
				(width 0.1)
				(type default)
			)
			(layer "F.Fab")
		)
		(fp_line
			(start 0.120396 0.3048)
			(end 0.120396 0.2794)
			(stroke
				(width 0.1)
				(type default)
			)
			(layer "F.Fab")
		)
		(fp_line
			(start -0.12065 0.3048)
			(end -0.67945 0.3048)
			(stroke
				(width 0.1)
				(type default)
			)
			(layer "F.Fab")
		)
		(fp_line
			(start -0.67945 0.3048)
			(end -0.67945 -0.305054)
			(stroke
				(width 0.1)
				(type default)
			)
			(layer "F.Fab")
		)
		(pad "1" smd circle
			(at -0.40005 0 90)
			(size 0 0)
			(layers "F.Cu" "F.Mask" "F.Paste")
			(net "PVCCIN_CPU0")
		)
		(pad "2" smd circle
			(at 0.40005 0 90)
			(size 0 0)
			(layers "F.Cu" "F.Mask" "F.Paste")
			(net "GND")
		)
	)
	(footprint ""
		(layer "F.Cu")
		(at 116.561616 -245.634256 -90)
		(property "Reference" "C294"
			(at 0 0 270)
			(layer "F.SilkS")
			(hide yes)
			(effects
				(font
					(size 1.27 1.27)
				)
			)
		)
		(property "Value" ""
			(at 0 0 270)
			(layer "F.Fab")
			(effects
				(font
					(size 1.27 1.27)
				)
			)
		)
		(duplicate_pad_numbers_are_jumpers no)
		(fp_line
			(start -0.7874 0.4064)
			(end -0.7874 -0.4064)
			(stroke
				(width 0.1524)
				(type default)
			)
			(layer "F.SilkS")
		)
		(fp_line
			(start 0.7874 0.4064)
			(end -0.7874 0.4064)
			(stroke
				(width 0.1524)
				(type default)
			)
			(layer "F.SilkS")
		)
		(fp_line
			(start -0.7874 -0.4064)
			(end 0.7874 -0.4064)
			(stroke
				(width 0.1524)
				(type default)
			)
			(layer "F.SilkS")
		)
		(fp_line
			(start 0.7874 -0.4064)
			(end 0.7874 0.4064)
			(stroke
				(width 0.1524)
				(type default)
			)
			(layer "F.SilkS")
		)
		(fp_line
			(start -0.67945 0.3048)
			(end -0.67945 -0.305054)
			(stroke
				(width 0.1)
				(type default)
			)
			(layer "F.Fab")
		)
		(fp_line
			(start -0.12065 0.3048)
			(end -0.67945 0.3048)
			(stroke
				(width 0.1)
				(type default)
			)
			(layer "F.Fab")
		)
		(fp_line
			(start 0.120396 0.3048)
			(end 0.120396 0.2794)
			(stroke
				(width 0.1)
				(type default)
			)
			(layer "F.Fab")
		)
		(fp_line
			(start 0.67945 0.3048)
			(end 0.120396 0.3048)
			(stroke
				(width 0.1)
				(type default)
			)
			(layer "F.Fab")
		)
		(fp_line
			(start -0.12065 0.2794)
			(end -0.12065 0.3048)
			(stroke
				(width 0.1)
				(type default)
			)
			(layer "F.Fab")
		)
		(fp_line
			(start 0.120396 0.2794)
			(end -0.12065 0.2794)
			(stroke
				(width 0.1)
				(type default)
			)
			(layer "F.Fab")
		)
		(fp_line
			(start -0.12065 -0.2794)
			(end 0.12065 -0.2794)
			(stroke
				(width 0.1)
				(type default)
			)
			(layer "F.Fab")
		)
		(fp_line
			(start 0.12065 -0.2794)
			(end 0.12065 -0.3048)
			(stroke
				(width 0.1)
				(type default)
			)
			(layer "F.Fab")
		)
		(fp_line
			(start 0.12065 -0.3048)
			(end 0.67945 -0.3048)
			(stroke
				(width 0.1)
				(type default)
			)
			(layer "F.Fab")
		)
		(fp_line
			(start 0.67945 -0.3048)
			(end 0.67945 0.3048)
			(stroke
				(width 0.1)
				(type default)
			)
			(layer "F.Fab")
		)
		(fp_line
			(start -0.67945 -0.305054)
			(end -0.12065 -0.305054)
			(stroke
				(width 0.1)
				(type default)
			)
			(layer "F.Fab")
		)
		(fp_line
			(start -0.12065 -0.305054)
			(end -0.12065 -0.2794)
			(stroke
				(width 0.1)
				(type default)
			)
			(layer "F.Fab")
		)
		(pad "1" smd circle
			(at -0.40005 0 270)
			(size 0 0)
			(layers "F.Cu" "F.Mask" "F.Paste")
			(net "PVCCIN_CPU1")
		)
		(pad "2" smd circle
			(at 0.40005 0 270)
			(size 0 0)
			(layers "F.Cu" "F.Mask" "F.Paste")
			(net "GND")
		)
	)
	(footprint ""
		(layer "F.Cu")
		(at 153.370788 -81.88198 90)
		(property "Reference" "R3124"
			(at 0 0 90)
			(layer "F.SilkS")
			(hide yes)
			(effects
				(font
					(size 1.27 1.27)
				)
			)
		)
		(property "Value" ""
			(at 0 0 90)
			(layer "F.Fab")
			(effects
				(font
					(size 1.27 1.27)
				)
			)
		)
		(duplicate_pad_numbers_are_jumpers no)
		(fp_line
			(start 0.7874 -0.4064)
			(end 0.7874 0.4064)
			(stroke
				(width 0.1524)
				(type default)
			)
			(layer "F.SilkS")
		)
		(fp_line
			(start -0.7874 -0.4064)
			(end 0.7874 -0.4064)
			(stroke
				(width 0.1524)
				(type default)
			)
			(layer "F.SilkS")
		)
		(fp_line
			(start 0.7874 0.4064)
			(end -0.7874 0.4064)
			(stroke
				(width 0.1524)
				(type default)
			)
			(layer "F.SilkS")
		)
		(fp_line
			(start -0.7874 0.4064)
			(end -0.7874 -0.4064)
			(stroke
				(width 0.1524)
				(type default)
			)
			(layer "F.SilkS")
		)
		(fp_line
			(start -0.12065 -0.305054)
			(end -0.12065 -0.2794)
			(stroke
				(width 0.1)
				(type default)
			)
			(layer "F.Fab")
		)
		(fp_line
			(start -0.67945 -0.305054)
			(end -0.12065 -0.305054)
			(stroke
				(width 0.1)
				(type default)
			)
			(layer "F.Fab")
		)
		(fp_line
			(start 0.67945 -0.3048)
			(end 0.67945 0.3048)
			(stroke
				(width 0.1)
				(type default)
			)
			(layer "F.Fab")
		)
		(fp_line
			(start 0.12065 -0.3048)
			(end 0.67945 -0.3048)
			(stroke
				(width 0.1)
				(type default)
			)
			(layer "F.Fab")
		)
		(fp_line
			(start 0.12065 -0.2794)
			(end 0.12065 -0.3048)
			(stroke
				(width 0.1)
				(type default)
			)
			(layer "F.Fab")
		)
		(fp_line
			(start -0.12065 -0.2794)
			(end 0.12065 -0.2794)
			(stroke
				(width 0.1)
				(type default)
			)
			(layer "F.Fab")
		)
		(fp_line
			(start 0.120396 0.2794)
			(end -0.12065 0.2794)
			(stroke
				(width 0.1)
				(type default)
			)
			(layer "F.Fab")
		)
		(fp_line
			(start -0.12065 0.2794)
			(end -0.12065 0.3048)
			(stroke
				(width 0.1)
				(type default)
			)
			(layer "F.Fab")
		)
		(fp_line
			(start 0.67945 0.3048)
			(end 0.120396 0.3048)
			(stroke
				(width 0.1)
				(type default)
			)
			(layer "F.Fab")
		)
		(fp_line
			(start 0.120396 0.3048)
			(end 0.120396 0.2794)
			(stroke
				(width 0.1)
				(type default)
			)
			(layer "F.Fab")
		)
		(fp_line
			(start -0.12065 0.3048)
			(end -0.67945 0.3048)
			(stroke
				(width 0.1)
				(type default)
			)
			(layer "F.Fab")
		)
		(fp_line
			(start -0.67945 0.3048)
			(end -0.67945 -0.305054)
			(stroke
				(width 0.1)
				(type default)
			)
			(layer "F.Fab")
		)
		(pad "1" smd circle
			(at -0.40005 0 90)
			(size 0 0)
			(layers "F.Cu" "F.Mask" "F.Paste")
			(net "SMB_S3M_CPU0_PIROM_3V3AUX_SDA_R")
		)
		(pad "2" smd circle
			(at 0.40005 0 90)
			(size 0 0)
			(layers "F.Cu" "F.Mask" "F.Paste")
			(net "SMB_S3M_CPU0_PIROM_3V3AUX_SDA")
		)
	)
	(footprint ""
		(layer "F.Cu")
		(at 336.32648 -22.836632 -90)
		(property "Reference" "R1214"
			(at 0 0 270)
			(layer "F.SilkS")
			(hide yes)
			(effects
				(font
					(size 1.27 1.27)
				)
			)
		)
		(property "Value" ""
			(at 0 0 270)
			(layer "F.Fab")
			(effects
				(font
					(size 1.27 1.27)
				)
			)
		)
		(duplicate_pad_numbers_are_jumpers no)
		(fp_line
			(start -0.7874 0.4064)
			(end -0.7874 -0.4064)
			(stroke
				(width 0.1524)
				(type default)
			)
			(layer "F.SilkS")
		)
		(fp_line
			(start 0.7874 0.4064)
			(end -0.7874 0.4064)
			(stroke
				(width 0.1524)
				(type default)
			)
			(layer "F.SilkS")
		)
		(fp_line
			(start -0.7874 -0.4064)
			(end 0.7874 -0.4064)
			(stroke
				(width 0.1524)
				(type default)
			)
			(layer "F.SilkS")
		)
		(fp_line
			(start 0.7874 -0.4064)
			(end 0.7874 0.4064)
			(stroke
				(width 0.1524)
				(type default)
			)
			(layer "F.SilkS")
		)
		(fp_line
			(start -0.67945 0.3048)
			(end -0.67945 -0.305054)
			(stroke
				(width 0.1)
				(type default)
			)
			(layer "F.Fab")
		)
		(fp_line
			(start -0.12065 0.3048)
			(end -0.67945 0.3048)
			(stroke
				(width 0.1)
				(type default)
			)
			(layer "F.Fab")
		)
		(fp_line
			(start 0.120396 0.3048)
			(end 0.120396 0.2794)
			(stroke
				(width 0.1)
				(type default)
			)
			(layer "F.Fab")
		)
		(fp_line
			(start 0.67945 0.3048)
			(end 0.120396 0.3048)
			(stroke
				(width 0.1)
				(type default)
			)
			(layer "F.Fab")
		)
		(fp_line
			(start -0.12065 0.2794)
			(end -0.12065 0.3048)
			(stroke
				(width 0.1)
				(type default)
			)
			(layer "F.Fab")
		)
		(fp_line
			(start 0.120396 0.2794)
			(end -0.12065 0.2794)
			(stroke
				(width 0.1)
				(type default)
			)
			(layer "F.Fab")
		)
		(fp_line
			(start -0.12065 -0.2794)
			(end 0.12065 -0.2794)
			(stroke
				(width 0.1)
				(type default)
			)
			(layer "F.Fab")
		)
		(fp_line
			(start 0.12065 -0.2794)
			(end 0.12065 -0.3048)
			(stroke
				(width 0.1)
				(type default)
			)
			(layer "F.Fab")
		)
		(fp_line
			(start 0.12065 -0.3048)
			(end 0.67945 -0.3048)
			(stroke
				(width 0.1)
				(type default)
			)
			(layer "F.Fab")
		)
		(fp_line
			(start 0.67945 -0.3048)
			(end 0.67945 0.3048)
			(stroke
				(width 0.1)
				(type default)
			)
			(layer "F.Fab")
		)
		(fp_line
			(start -0.67945 -0.305054)
			(end -0.12065 -0.305054)
			(stroke
				(width 0.1)
				(type default)
			)
			(layer "F.Fab")
		)
		(fp_line
			(start -0.12065 -0.305054)
			(end -0.12065 -0.2794)
			(stroke
				(width 0.1)
				(type default)
			)
			(layer "F.Fab")
		)
		(pad "1" smd circle
			(at -0.40005 0 270)
			(size 0 0)
			(layers "F.Cu" "F.Mask" "F.Paste")
			(net "IRQ_LPC_PIRQA_N_ESPI_ALERT0_N")
		)
		(pad "2" smd circle
			(at 0.40005 0 270)
			(size 0 0)
			(layers "F.Cu" "F.Mask" "F.Paste")
			(net "IRQ_LPC_PIRQA_N_ESPI_ALERT0_R_N")
		)
	)
	(footprint ""
		(layer "F.Cu")
		(at 209.069432 -71.09079)
		(property "Reference" "R1295"
			(at 0 0 0)
			(layer "F.SilkS")
			(hide yes)
			(effects
				(font
					(size 1.27 1.27)
				)
			)
		)
		(property "Value" ""
			(at 0 0 0)
			(layer "F.Fab")
			(effects
				(font
					(size 1.27 1.27)
				)
			)
		)
		(duplicate_pad_numbers_are_jumpers no)
		(fp_line
			(start -0.7874 -0.4064)
			(end 0.7874 -0.4064)
			(stroke
				(width 0.1524)
				(type default)
			)
			(layer "F.SilkS")
		)
		(fp_line
			(start -0.7874 0.4064)
			(end -0.7874 -0.4064)
			(stroke
				(width 0.1524)
				(type default)
			)
			(layer "F.SilkS")
		)
		(fp_line
			(start 0.7874 -0.4064)
			(end 0.7874 0.4064)
			(stroke
				(width 0.1524)
				(type default)
			)
			(layer "F.SilkS")
		)
		(fp_line
			(start 0.7874 0.4064)
			(end -0.7874 0.4064)
			(stroke
				(width 0.1524)
				(type default)
			)
			(layer "F.SilkS")
		)
		(fp_line
			(start -0.67945 -0.305054)
			(end -0.12065 -0.305054)
			(stroke
				(width 0.1)
				(type default)
			)
			(layer "F.Fab")
		)
		(fp_line
			(start -0.67945 0.3048)
			(end -0.67945 -0.305054)
			(stroke
				(width 0.1)
				(type default)
			)
			(layer "F.Fab")
		)
		(fp_line
			(start -0.12065 -0.305054)
			(end -0.12065 -0.2794)
			(stroke
				(width 0.1)
				(type default)
			)
			(layer "F.Fab")
		)
		(fp_line
			(start -0.12065 -0.2794)
			(end 0.12065 -0.2794)
			(stroke
				(width 0.1)
				(type default)
			)
			(layer "F.Fab")
		)
		(fp_line
			(start -0.12065 0.2794)
			(end -0.12065 0.3048)
			(stroke
				(width 0.1)
				(type default)
			)
			(layer "F.Fab")
		)
		(fp_line
			(start -0.12065 0.3048)
			(end -0.67945 0.3048)
			(stroke
				(width 0.1)
				(type default)
			)
			(layer "F.Fab")
		)
		(fp_line
			(start 0.120396 0.2794)
			(end -0.12065 0.2794)
			(stroke
				(width 0.1)
				(type default)
			)
			(layer "F.Fab")
		)
		(fp_line
			(start 0.120396 0.3048)
			(end 0.120396 0.2794)
			(stroke
				(width 0.1)
				(type default)
			)
			(layer "F.Fab")
		)
		(fp_line
			(start 0.12065 -0.3048)
			(end 0.67945 -0.3048)
			(stroke
				(width 0.1)
				(type default)
			)
			(layer "F.Fab")
		)
		(fp_line
			(start 0.12065 -0.2794)
			(end 0.12065 -0.3048)
			(stroke
				(width 0.1)
				(type default)
			)
			(layer "F.Fab")
		)
		(fp_line
			(start 0.67945 -0.3048)
			(end 0.67945 0.3048)
			(stroke
				(width 0.1)
				(type default)
			)
			(layer "F.Fab")
		)
		(fp_line
			(start 0.67945 0.3048)
			(end 0.120396 0.3048)
			(stroke
				(width 0.1)
				(type default)
			)
			(layer "F.Fab")
		)
		(pad "1" smd circle
			(at -0.40005 0)
			(size 0 0)
			(layers "F.Cu" "F.Mask" "F.Paste")
			(net "NCSI_BMC_TXD0_R")
		)
		(pad "2" smd circle
			(at 0.40005 0)
			(size 0 0)
			(layers "F.Cu" "F.Mask" "F.Paste")
			(net "RMII_BMC_OCP_TXD_0")
		)
	)
	(footprint ""
		(layer "F.Cu")
		(at 294.045894 -414.04286)
		(property "Reference" "R4688"
			(at 0 0 0)
			(layer "F.SilkS")
			(hide yes)
			(effects
				(font
					(size 1.27 1.27)
				)
			)
		)
		(property "Value" ""
			(at 0 0 0)
			(layer "F.Fab")
			(effects
				(font
					(size 1.27 1.27)
				)
			)
		)
		(duplicate_pad_numbers_are_jumpers no)
		(fp_line
			(start -0.7874 -0.4064)
			(end 0.7874 -0.4064)
			(stroke
				(width 0.1524)
				(type default)
			)
			(layer "F.SilkS")
		)
		(fp_line
			(start -0.7874 0.4064)
			(end -0.7874 -0.4064)
			(stroke
				(width 0.1524)
				(type default)
			)
			(layer "F.SilkS")
		)
		(fp_line
			(start 0.7874 -0.4064)
			(end 0.7874 0.4064)
			(stroke
				(width 0.1524)
				(type default)
			)
			(layer "F.SilkS")
		)
		(fp_line
			(start 0.7874 0.4064)
			(end -0.7874 0.4064)
			(stroke
				(width 0.1524)
				(type default)
			)
			(layer "F.SilkS")
		)
		(fp_line
			(start -0.67945 -0.305054)
			(end -0.12065 -0.305054)
			(stroke
				(width 0.1)
				(type default)
			)
			(layer "F.Fab")
		)
		(fp_line
			(start -0.67945 0.3048)
			(end -0.67945 -0.305054)
			(stroke
				(width 0.1)
				(type default)
			)
			(layer "F.Fab")
		)
		(fp_line
			(start -0.12065 -0.305054)
			(end -0.12065 -0.2794)
			(stroke
				(width 0.1)
				(type default)
			)
			(layer "F.Fab")
		)
		(fp_line
			(start -0.12065 -0.2794)
			(end 0.12065 -0.2794)
			(stroke
				(width 0.1)
				(type default)
			)
			(layer "F.Fab")
		)
		(fp_line
			(start -0.12065 0.2794)
			(end -0.12065 0.3048)
			(stroke
				(width 0.1)
				(type default)
			)
			(layer "F.Fab")
		)
		(fp_line
			(start -0.12065 0.3048)
			(end -0.67945 0.3048)
			(stroke
				(width 0.1)
				(type default)
			)
			(layer "F.Fab")
		)
		(fp_line
			(start 0.120396 0.2794)
			(end -0.12065 0.2794)
			(stroke
				(width 0.1)
				(type default)
			)
			(layer "F.Fab")
		)
		(fp_line
			(start 0.120396 0.3048)
			(end 0.120396 0.2794)
			(stroke
				(width 0.1)
				(type default)
			)
			(layer "F.Fab")
		)
		(fp_line
			(start 0.12065 -0.3048)
			(end 0.67945 -0.3048)
			(stroke
				(width 0.1)
				(type default)
			)
			(layer "F.Fab")
		)
		(fp_line
			(start 0.12065 -0.2794)
			(end 0.12065 -0.3048)
			(stroke
				(width 0.1)
				(type default)
			)
			(layer "F.Fab")
		)
		(fp_line
			(start 0.67945 -0.3048)
			(end 0.67945 0.3048)
			(stroke
				(width 0.1)
				(type default)
			)
			(layer "F.Fab")
		)
		(fp_line
			(start 0.67945 0.3048)
			(end 0.120396 0.3048)
			(stroke
				(width 0.1)
				(type default)
			)
			(layer "F.Fab")
		)
		(pad "1" smd circle
			(at -0.40005 0)
			(size 0 0)
			(layers "F.Cu" "F.Mask" "F.Paste")
			(net "GND")
		)
		(pad "2" smd circle
			(at 0.40005 0)
			(size 0 0)
			(layers "F.Cu" "F.Mask" "F.Paste")
			(net "HSC_TYPE_ADC_A0")
		)
	)
	(footprint ""
		(layer "F.Cu")
		(at 227.048568 -233.76255 180)
		(property "Reference" "R980"
			(at 0 0 180)
			(layer "F.SilkS")
			(hide yes)
			(effects
				(font
					(size 1.27 1.27)
				)
			)
		)
		(property "Value" ""
			(at 0 0 180)
			(layer "F.Fab")
			(effects
				(font
					(size 1.27 1.27)
				)
			)
		)
		(duplicate_pad_numbers_are_jumpers no)
		(fp_line
			(start 0.7874 0.4064)
			(end -0.7874 0.4064)
			(stroke
				(width 0.1524)
				(type default)
			)
			(layer "F.SilkS")
		)
		(fp_line
			(start 0.7874 -0.4064)
			(end 0.7874 0.4064)
			(stroke
				(width 0.1524)
				(type default)
			)
			(layer "F.SilkS")
		)
		(fp_line
			(start -0.7874 0.4064)
			(end -0.7874 -0.4064)
			(stroke
				(width 0.1524)
				(type default)
			)
			(layer "F.SilkS")
		)
		(fp_line
			(start -0.7874 -0.4064)
			(end 0.7874 -0.4064)
			(stroke
				(width 0.1524)
				(type default)
			)
			(layer "F.SilkS")
		)
		(fp_line
			(start 0.67945 0.3048)
			(end 0.120396 0.3048)
			(stroke
				(width 0.1)
				(type default)
			)
			(layer "F.Fab")
		)
		(fp_line
			(start 0.67945 -0.3048)
			(end 0.67945 0.3048)
			(stroke
				(width 0.1)
				(type default)
			)
			(layer "F.Fab")
		)
		(fp_line
			(start 0.12065 -0.2794)
			(end 0.12065 -0.3048)
			(stroke
				(width 0.1)
				(type default)
			)
			(layer "F.Fab")
		)
		(fp_line
			(start 0.12065 -0.3048)
			(end 0.67945 -0.3048)
			(stroke
				(width 0.1)
				(type default)
			)
			(layer "F.Fab")
		)
		(fp_line
			(start 0.120396 0.3048)
			(end 0.120396 0.2794)
			(stroke
				(width 0.1)
				(type default)
			)
			(layer "F.Fab")
		)
		(fp_line
			(start 0.120396 0.2794)
			(end -0.12065 0.2794)
			(stroke
				(width 0.1)
				(type default)
			)
			(layer "F.Fab")
		)
		(fp_line
			(start -0.12065 0.3048)
			(end -0.67945 0.3048)
			(stroke
				(width 0.1)
				(type default)
			)
			(layer "F.Fab")
		)
		(fp_line
			(start -0.12065 0.2794)
			(end -0.12065 0.3048)
			(stroke
				(width 0.1)
				(type default)
			)
			(layer "F.Fab")
		)
		(fp_line
			(start -0.12065 -0.2794)
			(end 0.12065 -0.2794)
			(stroke
				(width 0.1)
				(type default)
			)
			(layer "F.Fab")
		)
		(fp_line
			(start -0.12065 -0.305054)
			(end -0.12065 -0.2794)
			(stroke
				(width 0.1)
				(type default)
			)
			(layer "F.Fab")
		)
		(fp_line
			(start -0.67945 0.3048)
			(end -0.67945 -0.305054)
			(stroke
				(width 0.1)
				(type default)
			)
			(layer "F.Fab")
		)
		(fp_line
			(start -0.67945 -0.305054)
			(end -0.12065 -0.305054)
			(stroke
				(width 0.1)
				(type default)
			)
			(layer "F.Fab")
		)
		(pad "1" smd circle
			(at -0.40005 0 180)
			(size 0 0)
			(layers "F.Cu" "F.Mask" "F.Paste")
			(net "P3V3_AUX")
		)
		(pad "2" smd circle
			(at 0.40005 0 180)
			(size 0 0)
			(layers "F.Cu" "F.Mask" "F.Paste")
			(net "SMB_S3M_CPU1_3V3AUX_SDA")
		)
	)
	(footprint ""
		(layer "F.Cu")
		(at 163.929314 -402.371052 -90)
		(property "Reference" "C770"
			(at 0 0 270)
			(layer "F.SilkS")
			(hide yes)
			(effects
				(font
					(size 1.27 1.27)
				)
			)
		)
		(property "Value" ""
			(at 0 0 270)
			(layer "F.Fab")
			(effects
				(font
					(size 1.27 1.27)
				)
			)
		)
		(duplicate_pad_numbers_are_jumpers no)
		(fp_line
			(start -0.299974 0.150114)
			(end -0.299974 -0.150114)
			(stroke
				(width 0.1)
				(type default)
			)
			(layer "F.Fab")
		)
		(fp_line
			(start 0.299974 0.150114)
			(end -0.299974 0.150114)
			(stroke
				(width 0.1)
				(type default)
			)
			(layer "F.Fab")
		)
		(fp_line
			(start -0.299974 -0.150114)
			(end 0.299974 -0.150114)
			(stroke
				(width 0.1)
				(type default)
			)
			(layer "F.Fab")
		)
		(fp_line
			(start 0.299974 -0.150114)
			(end 0.299974 0.150114)
			(stroke
				(width 0.1)
				(type default)
			)
			(layer "F.Fab")
		)
		(pad "1" smd rect
			(at -0.2667 0 270)
			(size 0.3048 0.381)
			(layers "F.Cu" "F.Mask" "F.Paste")
			(net "P5E_CPU1_PE2_TX_C_DN<1>")
		)
		(pad "2" smd rect
			(at 0.2667 0 270)
			(size 0.3048 0.381)
			(layers "F.Cu" "F.Mask" "F.Paste")
			(net "P5E_CPU1_PE2_TX_DN<1>")
		)
	)
	(footprint ""
		(layer "F.Cu")
		(at 209.743802 -125.476)
		(property "Reference" "R4808"
			(at 0 0 0)
			(layer "F.SilkS")
			(hide yes)
			(effects
				(font
					(size 1.27 1.27)
				)
			)
		)
		(property "Value" ""
			(at 0 0 0)
			(layer "F.Fab")
			(effects
				(font
					(size 1.27 1.27)
				)
			)
		)
		(duplicate_pad_numbers_are_jumpers no)
		(fp_line
			(start -0.7874 -0.4064)
			(end 0.7874 -0.4064)
			(stroke
				(width 0.1524)
				(type default)
			)
			(layer "F.SilkS")
		)
		(fp_line
			(start -0.7874 0.4064)
			(end -0.7874 -0.4064)
			(stroke
				(width 0.1524)
				(type default)
			)
			(layer "F.SilkS")
		)
		(fp_line
			(start 0.7874 -0.4064)
			(end 0.7874 0.4064)
			(stroke
				(width 0.1524)
				(type default)
			)
			(layer "F.SilkS")
		)
		(fp_line
			(start 0.7874 0.4064)
			(end -0.7874 0.4064)
			(stroke
				(width 0.1524)
				(type default)
			)
			(layer "F.SilkS")
		)
		(fp_line
			(start -0.67945 -0.305054)
			(end -0.12065 -0.305054)
			(stroke
				(width 0.1)
				(type default)
			)
			(layer "F.Fab")
		)
		(fp_line
			(start -0.67945 0.3048)
			(end -0.67945 -0.305054)
			(stroke
				(width 0.1)
				(type default)
			)
			(layer "F.Fab")
		)
		(fp_line
			(start -0.12065 -0.305054)
			(end -0.12065 -0.2794)
			(stroke
				(width 0.1)
				(type default)
			)
			(layer "F.Fab")
		)
		(fp_line
			(start -0.12065 -0.2794)
			(end 0.12065 -0.2794)
			(stroke
				(width 0.1)
				(type default)
			)
			(layer "F.Fab")
		)
		(fp_line
			(start -0.12065 0.2794)
			(end -0.12065 0.3048)
			(stroke
				(width 0.1)
				(type default)
			)
			(layer "F.Fab")
		)
		(fp_line
			(start -0.12065 0.3048)
			(end -0.67945 0.3048)
			(stroke
				(width 0.1)
				(type default)
			)
			(layer "F.Fab")
		)
		(fp_line
			(start 0.120396 0.2794)
			(end -0.12065 0.2794)
			(stroke
				(width 0.1)
				(type default)
			)
			(layer "F.Fab")
		)
		(fp_line
			(start 0.120396 0.3048)
			(end 0.120396 0.2794)
			(stroke
				(width 0.1)
				(type default)
			)
			(layer "F.Fab")
		)
		(fp_line
			(start 0.12065 -0.3048)
			(end 0.67945 -0.3048)
			(stroke
				(width 0.1)
				(type default)
			)
			(layer "F.Fab")
		)
		(fp_line
			(start 0.12065 -0.2794)
			(end 0.12065 -0.3048)
			(stroke
				(width 0.1)
				(type default)
			)
			(layer "F.Fab")
		)
		(fp_line
			(start 0.67945 -0.3048)
			(end 0.67945 0.3048)
			(stroke
				(width 0.1)
				(type default)
			)
			(layer "F.Fab")
		)
		(fp_line
			(start 0.67945 0.3048)
			(end 0.120396 0.3048)
			(stroke
				(width 0.1)
				(type default)
			)
			(layer "F.Fab")
		)
		(pad "1" smd circle
			(at -0.40005 0)
			(size 0 0)
			(layers "F.Cu" "F.Mask" "F.Paste")
			(net "PWRGD_DSW_PWROK")
		)
		(pad "2" smd circle
			(at 0.40005 0)
			(size 0 0)
			(layers "F.Cu" "F.Mask" "F.Paste")
			(net "GND")
		)
	)
	(footprint ""
		(layer "F.Cu")
		(at 20.802346 -161.06394 90)
		(property "Reference" "PJ48"
			(at -2.825242 -1.264666 0)
			(unlocked yes)
			(layer "F.SilkS")
			(effects
				(font
					(size 0.7874 0.5842)
					(thickness 0.1524)
				)
				(justify left)
			)
		)
		(property "Value" ""
			(at 0 0 90)
			(layer "F.Fab")
			(effects
				(font
					(size 1.27 1.27)
				)
			)
		)
		(duplicate_pad_numbers_are_jumpers no)
		(pad "1" smd circle
			(at -0.7493 0 180)
			(size 0 0)
			(layers "F.Cu" "F.Mask" "F.Paste")
			(net "VSENSE_PVCCD_HV_CPU1_DP")
		)
		(pad "2" smd rect
			(at 0.7493 0)
			(size 0.7112 0.8128)
			(layers "F.Cu" "F.Mask" "F.Paste")
			(net "SH_PVCCD_HV_CPU1")
		)
		(zone
			(layer "F.Cu")
			(hatch none 0.5)
			(connect_pads
				(clearance 0)
			)
			(min_thickness 0.25)
			(keepout
				(tracks allowed)
				(vias not_allowed)
				(pads allowed)
				(copperpour not_allowed)
				(footprints allowed)
			)
			(placement
				(enabled no)
				(sheetname "")
			)
			(fill
				(thermal_gap 0.5)
				(thermal_bridge_width 0.5)
				(island_removal_mode 0)
			)
			(polygon
				(pts
					(xy 20.395946 -159.88284) (xy 21.213572 -159.88284) (xy 21.213572 -162.27044) (xy 20.395946 -162.27044)
				)
			)
		)
	)
	(footprint ""
		(layer "F.Cu")
		(at 32.780478 -439.720228)
		(property "Reference" "R3108"
			(at 0 0 0)
			(layer "F.SilkS")
			(hide yes)
			(effects
				(font
					(size 1.27 1.27)
				)
			)
		)
		(property "Value" ""
			(at 0 0 0)
			(layer "F.Fab")
			(effects
				(font
					(size 1.27 1.27)
				)
			)
		)
		(duplicate_pad_numbers_are_jumpers no)
		(fp_line
			(start -0.7874 -0.4064)
			(end 0.7874 -0.4064)
			(stroke
				(width 0.1524)
				(type default)
			)
			(layer "F.SilkS")
		)
		(fp_line
			(start -0.7874 0.4064)
			(end -0.7874 -0.4064)
			(stroke
				(width 0.1524)
				(type default)
			)
			(layer "F.SilkS")
		)
		(fp_line
			(start 0.7874 -0.4064)
			(end 0.7874 0.4064)
			(stroke
				(width 0.1524)
				(type default)
			)
			(layer "F.SilkS")
		)
		(fp_line
			(start 0.7874 0.4064)
			(end -0.7874 0.4064)
			(stroke
				(width 0.1524)
				(type default)
			)
			(layer "F.SilkS")
		)
		(fp_line
			(start -0.67945 -0.305054)
			(end -0.12065 -0.305054)
			(stroke
				(width 0.1)
				(type default)
			)
			(layer "F.Fab")
		)
		(fp_line
			(start -0.67945 0.3048)
			(end -0.67945 -0.305054)
			(stroke
				(width 0.1)
				(type default)
			)
			(layer "F.Fab")
		)
		(fp_line
			(start -0.12065 -0.305054)
			(end -0.12065 -0.2794)
			(stroke
				(width 0.1)
				(type default)
			)
			(layer "F.Fab")
		)
		(fp_line
			(start -0.12065 -0.2794)
			(end 0.12065 -0.2794)
			(stroke
				(width 0.1)
				(type default)
			)
			(layer "F.Fab")
		)
		(fp_line
			(start -0.12065 0.2794)
			(end -0.12065 0.3048)
			(stroke
				(width 0.1)
				(type default)
			)
			(layer "F.Fab")
		)
		(fp_line
			(start -0.12065 0.3048)
			(end -0.67945 0.3048)
			(stroke
				(width 0.1)
				(type default)
			)
			(layer "F.Fab")
		)
		(fp_line
			(start 0.120396 0.2794)
			(end -0.12065 0.2794)
			(stroke
				(width 0.1)
				(type default)
			)
			(layer "F.Fab")
		)
		(fp_line
			(start 0.120396 0.3048)
			(end 0.120396 0.2794)
			(stroke
				(width 0.1)
				(type default)
			)
			(layer "F.Fab")
		)
		(fp_line
			(start 0.12065 -0.3048)
			(end 0.67945 -0.3048)
			(stroke
				(width 0.1)
				(type default)
			)
			(layer "F.Fab")
		)
		(fp_line
			(start 0.12065 -0.2794)
			(end 0.12065 -0.3048)
			(stroke
				(width 0.1)
				(type default)
			)
			(layer "F.Fab")
		)
		(fp_line
			(start 0.67945 -0.3048)
			(end 0.67945 0.3048)
			(stroke
				(width 0.1)
				(type default)
			)
			(layer "F.Fab")
		)
		(fp_line
			(start 0.67945 0.3048)
			(end 0.120396 0.3048)
			(stroke
				(width 0.1)
				(type default)
			)
			(layer "F.Fab")
		)
		(pad "1" smd circle
			(at -0.40005 0)
			(size 0 0)
			(layers "F.Cu" "F.Mask" "F.Paste")
			(net "SMB_2_BMC_GPU_SDA")
		)
		(pad "2" smd circle
			(at 0.40005 0)
			(size 0 0)
			(layers "F.Cu" "F.Mask" "F.Paste")
			(net "SMB_2_BMC_GPU_R_SDA")
		)
	)
	(footprint ""
		(layer "F.Cu")
		(at 119.508016 -249.320558 -90)
		(property "Reference" "C234"
			(at 0 0 270)
			(layer "F.SilkS")
			(hide yes)
			(effects
				(font
					(size 1.27 1.27)
				)
			)
		)
		(property "Value" ""
			(at 0 0 270)
			(layer "F.Fab")
			(effects
				(font
					(size 1.27 1.27)
				)
			)
		)
		(duplicate_pad_numbers_are_jumpers no)
		(fp_line
			(start -0.7874 0.4064)
			(end -0.7874 -0.4064)
			(stroke
				(width 0.1524)
				(type default)
			)
			(layer "F.SilkS")
		)
		(fp_line
			(start 0.7874 0.4064)
			(end -0.7874 0.4064)
			(stroke
				(width 0.1524)
				(type default)
			)
			(layer "F.SilkS")
		)
		(fp_line
			(start -0.7874 -0.4064)
			(end 0.7874 -0.4064)
			(stroke
				(width 0.1524)
				(type default)
			)
			(layer "F.SilkS")
		)
		(fp_line
			(start 0.7874 -0.4064)
			(end 0.7874 0.4064)
			(stroke
				(width 0.1524)
				(type default)
			)
			(layer "F.SilkS")
		)
		(fp_line
			(start -0.67945 0.3048)
			(end -0.67945 -0.305054)
			(stroke
				(width 0.1)
				(type default)
			)
			(layer "F.Fab")
		)
		(fp_line
			(start -0.12065 0.3048)
			(end -0.67945 0.3048)
			(stroke
				(width 0.1)
				(type default)
			)
			(layer "F.Fab")
		)
		(fp_line
			(start 0.120396 0.3048)
			(end 0.120396 0.2794)
			(stroke
				(width 0.1)
				(type default)
			)
			(layer "F.Fab")
		)
		(fp_line
			(start 0.67945 0.3048)
			(end 0.120396 0.3048)
			(stroke
				(width 0.1)
				(type default)
			)
			(layer "F.Fab")
		)
		(fp_line
			(start -0.12065 0.2794)
			(end -0.12065 0.3048)
			(stroke
				(width 0.1)
				(type default)
			)
			(layer "F.Fab")
		)
		(fp_line
			(start 0.120396 0.2794)
			(end -0.12065 0.2794)
			(stroke
				(width 0.1)
				(type default)
			)
			(layer "F.Fab")
		)
		(fp_line
			(start -0.12065 -0.2794)
			(end 0.12065 -0.2794)
			(stroke
				(width 0.1)
				(type default)
			)
			(layer "F.Fab")
		)
		(fp_line
			(start 0.12065 -0.2794)
			(end 0.12065 -0.3048)
			(stroke
				(width 0.1)
				(type default)
			)
			(layer "F.Fab")
		)
		(fp_line
			(start 0.12065 -0.3048)
			(end 0.67945 -0.3048)
			(stroke
				(width 0.1)
				(type default)
			)
			(layer "F.Fab")
		)
		(fp_line
			(start 0.67945 -0.3048)
			(end 0.67945 0.3048)
			(stroke
				(width 0.1)
				(type default)
			)
			(layer "F.Fab")
		)
		(fp_line
			(start -0.67945 -0.305054)
			(end -0.12065 -0.305054)
			(stroke
				(width 0.1)
				(type default)
			)
			(layer "F.Fab")
		)
		(fp_line
			(start -0.12065 -0.305054)
			(end -0.12065 -0.2794)
			(stroke
				(width 0.1)
				(type default)
			)
			(layer "F.Fab")
		)
		(pad "1" smd circle
			(at -0.40005 0 270)
			(size 0 0)
			(layers "F.Cu" "F.Mask" "F.Paste")
			(net "PVCCIN_CPU1")
		)
		(pad "2" smd circle
			(at 0.40005 0 270)
			(size 0 0)
			(layers "F.Cu" "F.Mask" "F.Paste")
			(net "GND")
		)
	)
	(footprint ""
		(layer "F.Cu")
		(at 100.820728 -355.257862 180)
		(property "Reference" "R2555"
			(at 0 0 180)
			(layer "F.SilkS")
			(hide yes)
			(effects
				(font
					(size 1.27 1.27)
				)
			)
		)
		(property "Value" ""
			(at 0 0 180)
			(layer "F.Fab")
			(effects
				(font
					(size 1.27 1.27)
				)
			)
		)
		(duplicate_pad_numbers_are_jumpers no)
		(fp_line
			(start 0.7874 0.4064)
			(end -0.7874 0.4064)
			(stroke
				(width 0.1524)
				(type default)
			)
			(layer "F.SilkS")
		)
		(fp_line
			(start 0.7874 -0.4064)
			(end 0.7874 0.4064)
			(stroke
				(width 0.1524)
				(type default)
			)
			(layer "F.SilkS")
		)
		(fp_line
			(start -0.7874 0.4064)
			(end -0.7874 -0.4064)
			(stroke
				(width 0.1524)
				(type default)
			)
			(layer "F.SilkS")
		)
		(fp_line
			(start -0.7874 -0.4064)
			(end 0.7874 -0.4064)
			(stroke
				(width 0.1524)
				(type default)
			)
			(layer "F.SilkS")
		)
		(fp_line
			(start 0.67945 0.3048)
			(end 0.120396 0.3048)
			(stroke
				(width 0.1)
				(type default)
			)
			(layer "F.Fab")
		)
		(fp_line
			(start 0.67945 -0.3048)
			(end 0.67945 0.3048)
			(stroke
				(width 0.1)
				(type default)
			)
			(layer "F.Fab")
		)
		(fp_line
			(start 0.12065 -0.2794)
			(end 0.12065 -0.3048)
			(stroke
				(width 0.1)
				(type default)
			)
			(layer "F.Fab")
		)
		(fp_line
			(start 0.12065 -0.3048)
			(end 0.67945 -0.3048)
			(stroke
				(width 0.1)
				(type default)
			)
			(layer "F.Fab")
		)
		(fp_line
			(start 0.120396 0.3048)
			(end 0.120396 0.2794)
			(stroke
				(width 0.1)
				(type default)
			)
			(layer "F.Fab")
		)
		(fp_line
			(start 0.120396 0.2794)
			(end -0.12065 0.2794)
			(stroke
				(width 0.1)
				(type default)
			)
			(layer "F.Fab")
		)
		(fp_line
			(start -0.12065 0.3048)
			(end -0.67945 0.3048)
			(stroke
				(width 0.1)
				(type default)
			)
			(layer "F.Fab")
		)
		(fp_line
			(start -0.12065 0.2794)
			(end -0.12065 0.3048)
			(stroke
				(width 0.1)
				(type default)
			)
			(layer "F.Fab")
		)
		(fp_line
			(start -0.12065 -0.2794)
			(end 0.12065 -0.2794)
			(stroke
				(width 0.1)
				(type default)
			)
			(layer "F.Fab")
		)
		(fp_line
			(start -0.12065 -0.305054)
			(end -0.12065 -0.2794)
			(stroke
				(width 0.1)
				(type default)
			)
			(layer "F.Fab")
		)
		(fp_line
			(start -0.67945 0.3048)
			(end -0.67945 -0.305054)
			(stroke
				(width 0.1)
				(type default)
			)
			(layer "F.Fab")
		)
		(fp_line
			(start -0.67945 -0.305054)
			(end -0.12065 -0.305054)
			(stroke
				(width 0.1)
				(type default)
			)
			(layer "F.Fab")
		)
		(pad "1" smd circle
			(at -0.40005 0 180)
			(size 0 0)
			(layers "F.Cu" "F.Mask" "F.Paste")
			(net "SVID_ALERT0_CPU1_R_N")
		)
		(pad "2" smd circle
			(at 0.40005 0 180)
			(size 0 0)
			(layers "F.Cu" "F.Mask" "F.Paste")
			(net "PVNN_TERM_CPU1")
		)
	)
	(footprint ""
		(layer "F.Cu")
		(at 154.739594 -402.371052 -90)
		(property "Reference" "C764"
			(at 0 0 270)
			(layer "F.SilkS")
			(hide yes)
			(effects
				(font
					(size 1.27 1.27)
				)
			)
		)
		(property "Value" ""
			(at 0 0 270)
			(layer "F.Fab")
			(effects
				(font
					(size 1.27 1.27)
				)
			)
		)
		(duplicate_pad_numbers_are_jumpers no)
		(fp_line
			(start -0.299974 0.150114)
			(end -0.299974 -0.150114)
			(stroke
				(width 0.1)
				(type default)
			)
			(layer "F.Fab")
		)
		(fp_line
			(start 0.299974 0.150114)
			(end -0.299974 0.150114)
			(stroke
				(width 0.1)
				(type default)
			)
			(layer "F.Fab")
		)
		(fp_line
			(start -0.299974 -0.150114)
			(end 0.299974 -0.150114)
			(stroke
				(width 0.1)
				(type default)
			)
			(layer "F.Fab")
		)
		(fp_line
			(start 0.299974 -0.150114)
			(end 0.299974 0.150114)
			(stroke
				(width 0.1)
				(type default)
			)
			(layer "F.Fab")
		)
		(pad "1" smd rect
			(at -0.2667 0 270)
			(size 0.3048 0.381)
			(layers "F.Cu" "F.Mask" "F.Paste")
			(net "P5E_CPU1_PE2_TX_C_DN<4>")
		)
		(pad "2" smd rect
			(at 0.2667 0 270)
			(size 0.3048 0.381)
			(layers "F.Cu" "F.Mask" "F.Paste")
			(net "P5E_CPU1_PE2_TX_DN<4>")
		)
	)
	(footprint ""
		(layer "F.Cu")
		(at 100.936806 -102.693216)
		(property "Reference" "Q79"
			(at 1.7399 -0.815848 0)
			(unlocked yes)
			(layer "F.SilkS")
			(effects
				(font
					(size 0.7874 0.5842)
					(thickness 0.1524)
				)
				(justify left)
			)
		)
		(property "Value" ""
			(at 0 0 0)
			(layer "F.Fab")
			(effects
				(font
					(size 1.27 1.27)
				)
			)
		)
		(duplicate_pad_numbers_are_jumpers no)
		(fp_line
			(start -1.332738 -1.100074)
			(end -0.4826 -1.100074)
			(stroke
				(width 0.1524)
				(type default)
			)
			(layer "F.SilkS")
		)
		(fp_line
			(start -1.332738 1.100074)
			(end -1.332738 -1.100074)
			(stroke
				(width 0.1524)
				(type default)
			)
			(layer "F.SilkS")
		)
		(fp_line
			(start -0.4826 -1.100074)
			(end 0 -0.541274)
			(stroke
				(width 0.1524)
				(type default)
			)
			(layer "F.SilkS")
		)
		(fp_line
			(start 0 -0.541274)
			(end 0.4826 -1.100074)
			(stroke
				(width 0.1524)
				(type default)
			)
			(layer "F.SilkS")
		)
		(fp_line
			(start 0.4826 -1.100074)
			(end 1.332738 -1.100074)
			(stroke
				(width 0.1524)
				(type default)
			)
			(layer "F.SilkS")
		)
		(fp_line
			(start 1.332738 -1.100074)
			(end 1.332738 1.100074)
			(stroke
				(width 0.1524)
				(type default)
			)
			(layer "F.SilkS")
		)
		(fp_line
			(start 1.332738 1.100074)
			(end -1.332738 1.100074)
			(stroke
				(width 0.1524)
				(type default)
			)
			(layer "F.SilkS")
		)
		(fp_poly
			(pts
				(xy -0.603504 -1.950466) (xy -0.954532 -1.24841) (xy -1.30556 -1.950466)
			)
			(stroke
				(width 0)
				(type default)
			)
			(fill yes)
			(layer "F.SilkS")
		)
		(fp_line
			(start -0.674878 -1.100074)
			(end 0.674878 -1.100074)
			(stroke
				(width 0.1)
				(type default)
			)
			(layer "F.Fab")
		)
		(fp_line
			(start -0.674878 1.100074)
			(end -0.674878 -1.100074)
			(stroke
				(width 0.1)
				(type default)
			)
			(layer "F.Fab")
		)
		(fp_line
			(start 0.674878 -1.100074)
			(end 0.674878 1.100074)
			(stroke
				(width 0.1)
				(type default)
			)
			(layer "F.Fab")
		)
		(fp_line
			(start 0.674878 1.100074)
			(end -0.674878 1.100074)
			(stroke
				(width 0.1)
				(type default)
			)
			(layer "F.Fab")
		)
		(fp_poly
			(pts
				(xy -2.2352 -0.298958) (xy -2.2352 -1.001014) (xy -1.533144 -0.649986)
			)
			(stroke
				(width 0)
				(type default)
			)
			(fill yes)
			(layer "F.Fab")
		)
		(pad "1" smd rect
			(at -0.94996 -0.649986 90)
			(size 0.4318 0.508)
			(layers "F.Cu" "F.Mask" "F.Paste")
			(net "GND")
		)
		(pad "2" smd rect
			(at -0.94996 0 90)
			(size 0.4318 0.508)
			(layers "F.Cu" "F.Mask" "F.Paste")
			(net "PWRGD_PVCCD_HV_CPU0")
		)
		(pad "3" smd rect
			(at -0.94996 0.649986 90)
			(size 0.4318 0.508)
			(layers "F.Cu" "F.Mask" "F.Paste")
			(net "LED_PWRGD_PVPP_HBM_CPU0_D")
		)
		(pad "4" smd rect
			(at 0.94996 0.649986 90)
			(size 0.4318 0.508)
			(layers "F.Cu" "F.Mask" "F.Paste")
			(net "GND")
		)
		(pad "5" smd rect
			(at 0.94996 0 90)
			(size 0.4318 0.508)
			(layers "F.Cu" "F.Mask" "F.Paste")
			(net "PWRGD_PVPP_HBM_CPU0")
		)
		(pad "6" smd rect
			(at 0.94996 -0.649986 90)
			(size 0.4318 0.508)
			(layers "F.Cu" "F.Mask" "F.Paste")
			(net "LED_PWRGD_PVCCD_HV_CPU0_D")
		)
	)
	(footprint ""
		(layer "F.Cu")
		(at 350.817688 -402.371052 -90)
		(property "Reference" "C1549"
			(at 0 0 270)
			(layer "F.SilkS")
			(hide yes)
			(effects
				(font
					(size 1.27 1.27)
				)
			)
		)
		(property "Value" ""
			(at 0 0 270)
			(layer "F.Fab")
			(effects
				(font
					(size 1.27 1.27)
				)
			)
		)
		(duplicate_pad_numbers_are_jumpers no)
		(fp_line
			(start -0.299974 0.150114)
			(end -0.299974 -0.150114)
			(stroke
				(width 0.1)
				(type default)
			)
			(layer "F.Fab")
		)
		(fp_line
			(start 0.299974 0.150114)
			(end -0.299974 0.150114)
			(stroke
				(width 0.1)
				(type default)
			)
			(layer "F.Fab")
		)
		(fp_line
			(start -0.299974 -0.150114)
			(end 0.299974 -0.150114)
			(stroke
				(width 0.1)
				(type default)
			)
			(layer "F.Fab")
		)
		(fp_line
			(start 0.299974 -0.150114)
			(end 0.299974 0.150114)
			(stroke
				(width 0.1)
				(type default)
			)
			(layer "F.Fab")
		)
		(pad "1" smd rect
			(at -0.2667 0 270)
			(size 0.3048 0.381)
			(layers "F.Cu" "F.Mask" "F.Paste")
			(net "P5E_CPU0_PE4_TX_C_DP<15>")
		)
		(pad "2" smd rect
			(at 0.2667 0 270)
			(size 0.3048 0.381)
			(layers "F.Cu" "F.Mask" "F.Paste")
			(net "P5E_CPU0_PE4_TX_DP<15>")
		)
	)
	(footprint ""
		(layer "F.Cu")
		(at 149.368256 -64.059308)
		(property "Reference" "R2457"
			(at 0 0 0)
			(layer "F.SilkS")
			(hide yes)
			(effects
				(font
					(size 1.27 1.27)
				)
			)
		)
		(property "Value" ""
			(at 0 0 0)
			(layer "F.Fab")
			(effects
				(font
					(size 1.27 1.27)
				)
			)
		)
		(duplicate_pad_numbers_are_jumpers no)
		(fp_line
			(start -0.7874 -0.4064)
			(end 0.7874 -0.4064)
			(stroke
				(width 0.1524)
				(type default)
			)
			(layer "F.SilkS")
		)
		(fp_line
			(start -0.7874 0.4064)
			(end -0.7874 -0.4064)
			(stroke
				(width 0.1524)
				(type default)
			)
			(layer "F.SilkS")
		)
		(fp_line
			(start 0.7874 -0.4064)
			(end 0.7874 0.4064)
			(stroke
				(width 0.1524)
				(type default)
			)
			(layer "F.SilkS")
		)
		(fp_line
			(start 0.7874 0.4064)
			(end -0.7874 0.4064)
			(stroke
				(width 0.1524)
				(type default)
			)
			(layer "F.SilkS")
		)
		(fp_line
			(start -0.67945 -0.305054)
			(end -0.12065 -0.305054)
			(stroke
				(width 0.1)
				(type default)
			)
			(layer "F.Fab")
		)
		(fp_line
			(start -0.67945 0.3048)
			(end -0.67945 -0.305054)
			(stroke
				(width 0.1)
				(type default)
			)
			(layer "F.Fab")
		)
		(fp_line
			(start -0.12065 -0.305054)
			(end -0.12065 -0.2794)
			(stroke
				(width 0.1)
				(type default)
			)
			(layer "F.Fab")
		)
		(fp_line
			(start -0.12065 -0.2794)
			(end 0.12065 -0.2794)
			(stroke
				(width 0.1)
				(type default)
			)
			(layer "F.Fab")
		)
		(fp_line
			(start -0.12065 0.2794)
			(end -0.12065 0.3048)
			(stroke
				(width 0.1)
				(type default)
			)
			(layer "F.Fab")
		)
		(fp_line
			(start -0.12065 0.3048)
			(end -0.67945 0.3048)
			(stroke
				(width 0.1)
				(type default)
			)
			(layer "F.Fab")
		)
		(fp_line
			(start 0.120396 0.2794)
			(end -0.12065 0.2794)
			(stroke
				(width 0.1)
				(type default)
			)
			(layer "F.Fab")
		)
		(fp_line
			(start 0.120396 0.3048)
			(end 0.120396 0.2794)
			(stroke
				(width 0.1)
				(type default)
			)
			(layer "F.Fab")
		)
		(fp_line
			(start 0.12065 -0.3048)
			(end 0.67945 -0.3048)
			(stroke
				(width 0.1)
				(type default)
			)
			(layer "F.Fab")
		)
		(fp_line
			(start 0.12065 -0.2794)
			(end 0.12065 -0.3048)
			(stroke
				(width 0.1)
				(type default)
			)
			(layer "F.Fab")
		)
		(fp_line
			(start 0.67945 -0.3048)
			(end 0.67945 0.3048)
			(stroke
				(width 0.1)
				(type default)
			)
			(layer "F.Fab")
		)
		(fp_line
			(start 0.67945 0.3048)
			(end 0.120396 0.3048)
			(stroke
				(width 0.1)
				(type default)
			)
			(layer "F.Fab")
		)
		(pad "1" smd circle
			(at -0.40005 0)
			(size 0 0)
			(layers "F.Cu" "F.Mask" "F.Paste")
			(net "E1S_0_EN")
		)
		(pad "2" smd circle
			(at 0.40005 0)
			(size 0 0)
			(layers "F.Cu" "F.Mask" "F.Paste")
			(net "GND")
		)
	)
	(footprint ""
		(layer "F.Cu")
		(at 431.062638 -368.79149)
		(property "Reference" "PC1673"
			(at 0 0 0)
			(layer "F.SilkS")
			(hide yes)
			(effects
				(font
					(size 1.27 1.27)
				)
			)
		)
		(property "Value" ""
			(at 0 0 0)
			(layer "F.Fab")
			(effects
				(font
					(size 1.27 1.27)
				)
			)
		)
		(duplicate_pad_numbers_are_jumpers no)
		(fp_line
			(start -1.524 -0.762)
			(end 1.524 -0.762)
			(stroke
				(width 0.1524)
				(type default)
			)
			(layer "F.SilkS")
		)
		(fp_line
			(start -1.524 0.762)
			(end -1.524 -0.762)
			(stroke
				(width 0.1524)
				(type default)
			)
			(layer "F.SilkS")
		)
		(fp_line
			(start 1.524 -0.762)
			(end 1.524 0.762)
			(stroke
				(width 0.1524)
				(type default)
			)
			(layer "F.SilkS")
		)
		(fp_line
			(start 1.524 0.762)
			(end -1.524 0.762)
			(stroke
				(width 0.1524)
				(type default)
			)
			(layer "F.SilkS")
		)
		(fp_line
			(start -1.1049 -0.724916)
			(end -1.1049 0.724916)
			(stroke
				(width 0.1)
				(type default)
			)
			(layer "F.Fab")
		)
		(fp_line
			(start -1.1049 0.724916)
			(end 1.1049 0.724916)
			(stroke
				(width 0.1)
				(type default)
			)
			(layer "F.Fab")
		)
		(fp_line
			(start 1.1049 -0.724916)
			(end -1.1049 -0.724916)
			(stroke
				(width 0.1)
				(type default)
			)
			(layer "F.Fab")
		)
		(fp_line
			(start 1.1049 0.724916)
			(end 1.1049 -0.724916)
			(stroke
				(width 0.1)
				(type default)
			)
			(layer "F.Fab")
		)
		(pad "1" smd rect
			(at -0.889 0 180)
			(size 1.016 1.27)
			(layers "F.Cu" "F.Mask" "F.Paste")
			(net "SW_P12V_PVCCFA_EHV_FIVRA_CPU0_R")
		)
		(pad "2" smd rect
			(at 0.889 0 180)
			(size 1.016 1.27)
			(layers "F.Cu" "F.Mask" "F.Paste")
			(net "GND")
		)
	)
	(footprint ""
		(layer "F.Cu")
		(at 39.827454 -112.603026 180)
		(property "Reference" "R3680"
			(at 0 0 180)
			(layer "F.SilkS")
			(hide yes)
			(effects
				(font
					(size 1.27 1.27)
				)
			)
		)
		(property "Value" ""
			(at 0 0 180)
			(layer "F.Fab")
			(effects
				(font
					(size 1.27 1.27)
				)
			)
		)
		(duplicate_pad_numbers_are_jumpers no)
		(fp_line
			(start 0.7874 0.4064)
			(end -0.7874 0.4064)
			(stroke
				(width 0.1524)
				(type default)
			)
			(layer "F.SilkS")
		)
		(fp_line
			(start 0.7874 -0.4064)
			(end 0.7874 0.4064)
			(stroke
				(width 0.1524)
				(type default)
			)
			(layer "F.SilkS")
		)
		(fp_line
			(start -0.7874 0.4064)
			(end -0.7874 -0.4064)
			(stroke
				(width 0.1524)
				(type default)
			)
			(layer "F.SilkS")
		)
		(fp_line
			(start -0.7874 -0.4064)
			(end 0.7874 -0.4064)
			(stroke
				(width 0.1524)
				(type default)
			)
			(layer "F.SilkS")
		)
		(fp_line
			(start 0.67945 0.3048)
			(end 0.120396 0.3048)
			(stroke
				(width 0.1)
				(type default)
			)
			(layer "F.Fab")
		)
		(fp_line
			(start 0.67945 -0.3048)
			(end 0.67945 0.3048)
			(stroke
				(width 0.1)
				(type default)
			)
			(layer "F.Fab")
		)
		(fp_line
			(start 0.12065 -0.2794)
			(end 0.12065 -0.3048)
			(stroke
				(width 0.1)
				(type default)
			)
			(layer "F.Fab")
		)
		(fp_line
			(start 0.12065 -0.3048)
			(end 0.67945 -0.3048)
			(stroke
				(width 0.1)
				(type default)
			)
			(layer "F.Fab")
		)
		(fp_line
			(start 0.120396 0.3048)
			(end 0.120396 0.2794)
			(stroke
				(width 0.1)
				(type default)
			)
			(layer "F.Fab")
		)
		(fp_line
			(start 0.120396 0.2794)
			(end -0.12065 0.2794)
			(stroke
				(width 0.1)
				(type default)
			)
			(layer "F.Fab")
		)
		(fp_line
			(start -0.12065 0.3048)
			(end -0.67945 0.3048)
			(stroke
				(width 0.1)
				(type default)
			)
			(layer "F.Fab")
		)
		(fp_line
			(start -0.12065 0.2794)
			(end -0.12065 0.3048)
			(stroke
				(width 0.1)
				(type default)
			)
			(layer "F.Fab")
		)
		(fp_line
			(start -0.12065 -0.2794)
			(end 0.12065 -0.2794)
			(stroke
				(width 0.1)
				(type default)
			)
			(layer "F.Fab")
		)
		(fp_line
			(start -0.12065 -0.305054)
			(end -0.12065 -0.2794)
			(stroke
				(width 0.1)
				(type default)
			)
			(layer "F.Fab")
		)
		(fp_line
			(start -0.67945 0.3048)
			(end -0.67945 -0.305054)
			(stroke
				(width 0.1)
				(type default)
			)
			(layer "F.Fab")
		)
		(fp_line
			(start -0.67945 -0.305054)
			(end -0.12065 -0.305054)
			(stroke
				(width 0.1)
				(type default)
			)
			(layer "F.Fab")
		)
		(pad "1" smd rect
			(at -0.40005 0)
			(size 0.4572 0.508)
			(layers "F.Cu" "F.Mask" "F.Paste")
			(net "P12V_AUX_ADC")
		)
		(pad "2" smd rect
			(at 0.40005 0)
			(size 0.4572 0.508)
			(layers "F.Cu" "F.Mask" "F.Paste")
			(net "P12V_AUX_ADC_TIC")
		)
	)
	(footprint ""
		(layer "F.Cu")
		(at 50.95875 -440.187588)
		(property "Reference" "R2999"
			(at 0 0 0)
			(layer "F.SilkS")
			(hide yes)
			(effects
				(font
					(size 1.27 1.27)
				)
			)
		)
		(property "Value" ""
			(at 0 0 0)
			(layer "F.Fab")
			(effects
				(font
					(size 1.27 1.27)
				)
			)
		)
		(duplicate_pad_numbers_are_jumpers no)
		(fp_line
			(start -0.7874 -0.4064)
			(end 0.7874 -0.4064)
			(stroke
				(width 0.1524)
				(type default)
			)
			(layer "F.SilkS")
		)
		(fp_line
			(start -0.7874 0.4064)
			(end -0.7874 -0.4064)
			(stroke
				(width 0.1524)
				(type default)
			)
			(layer "F.SilkS")
		)
		(fp_line
			(start 0.7874 -0.4064)
			(end 0.7874 0.4064)
			(stroke
				(width 0.1524)
				(type default)
			)
			(layer "F.SilkS")
		)
		(fp_line
			(start 0.7874 0.4064)
			(end -0.7874 0.4064)
			(stroke
				(width 0.1524)
				(type default)
			)
			(layer "F.SilkS")
		)
		(fp_line
			(start -0.67945 -0.305054)
			(end -0.12065 -0.305054)
			(stroke
				(width 0.1)
				(type default)
			)
			(layer "F.Fab")
		)
		(fp_line
			(start -0.67945 0.3048)
			(end -0.67945 -0.305054)
			(stroke
				(width 0.1)
				(type default)
			)
			(layer "F.Fab")
		)
		(fp_line
			(start -0.12065 -0.305054)
			(end -0.12065 -0.2794)
			(stroke
				(width 0.1)
				(type default)
			)
			(layer "F.Fab")
		)
		(fp_line
			(start -0.12065 -0.2794)
			(end 0.12065 -0.2794)
			(stroke
				(width 0.1)
				(type default)
			)
			(layer "F.Fab")
		)
		(fp_line
			(start -0.12065 0.2794)
			(end -0.12065 0.3048)
			(stroke
				(width 0.1)
				(type default)
			)
			(layer "F.Fab")
		)
		(fp_line
			(start -0.12065 0.3048)
			(end -0.67945 0.3048)
			(stroke
				(width 0.1)
				(type default)
			)
			(layer "F.Fab")
		)
		(fp_line
			(start 0.120396 0.2794)
			(end -0.12065 0.2794)
			(stroke
				(width 0.1)
				(type default)
			)
			(layer "F.Fab")
		)
		(fp_line
			(start 0.120396 0.3048)
			(end 0.120396 0.2794)
			(stroke
				(width 0.1)
				(type default)
			)
			(layer "F.Fab")
		)
		(fp_line
			(start 0.12065 -0.3048)
			(end 0.67945 -0.3048)
			(stroke
				(width 0.1)
				(type default)
			)
			(layer "F.Fab")
		)
		(fp_line
			(start 0.12065 -0.2794)
			(end 0.12065 -0.3048)
			(stroke
				(width 0.1)
				(type default)
			)
			(layer "F.Fab")
		)
		(fp_line
			(start 0.67945 -0.3048)
			(end 0.67945 0.3048)
			(stroke
				(width 0.1)
				(type default)
			)
			(layer "F.Fab")
		)
		(fp_line
			(start 0.67945 0.3048)
			(end 0.120396 0.3048)
			(stroke
				(width 0.1)
				(type default)
			)
			(layer "F.Fab")
		)
		(pad "1" smd circle
			(at -0.40005 0)
			(size 0 0)
			(layers "F.Cu" "F.Mask" "F.Paste")
			(net "SMB_2_BMC_GPU_SCL")
		)
		(pad "2" smd circle
			(at 0.40005 0)
			(size 0 0)
			(layers "F.Cu" "F.Mask" "F.Paste")
			(net "P3V3_AUX")
		)
	)
	(footprint ""
		(layer "F.Cu")
		(at 87.382096 -70.78599)
		(property "Reference" "D89"
			(at -44.586906 50.178462 90)
			(unlocked yes)
			(layer "F.SilkS")
			(effects
				(font
					(size 0.635 0.4064)
					(thickness 0.1524)
				)
				(justify left)
			)
		)
		(property "Value" ""
			(at 0 0 0)
			(layer "F.Fab")
			(effects
				(font
					(size 1.27 1.27)
				)
			)
		)
		(duplicate_pad_numbers_are_jumpers no)
		(fp_line
			(start -0.90678 0.4826)
			(end -0.90678 -0.4699)
			(stroke
				(width 0.1524)
				(type default)
			)
			(layer "F.SilkS")
		)
		(fp_line
			(start -0.89408 -0.4826)
			(end 0.90678 -0.4826)
			(stroke
				(width 0.1524)
				(type default)
			)
			(layer "F.SilkS")
		)
		(fp_line
			(start -0.79248 -0.4826)
			(end 1.03378 -0.4826)
			(stroke
				(width 0.1524)
				(type default)
			)
			(layer "F.SilkS")
		)
		(fp_line
			(start -0.64008 -0.4826)
			(end 1.16078 -0.4826)
			(stroke
				(width 0.1524)
				(type default)
			)
			(layer "F.SilkS")
		)
		(fp_line
			(start 0.90678 -0.4826)
			(end 0.90678 0.4826)
			(stroke
				(width 0.1524)
				(type default)
			)
			(layer "F.SilkS")
		)
		(fp_line
			(start 0.90678 0.4826)
			(end -0.90678 0.4826)
			(stroke
				(width 0.1524)
				(type default)
			)
			(layer "F.SilkS")
		)
		(fp_line
			(start 1.03378 -0.4826)
			(end 1.03378 0.4826)
			(stroke
				(width 0.1524)
				(type default)
			)
			(layer "F.SilkS")
		)
		(fp_line
			(start 1.03378 0.4826)
			(end -0.79248 0.4826)
			(stroke
				(width 0.1524)
				(type default)
			)
			(layer "F.SilkS")
		)
		(fp_line
			(start 1.16078 -0.4826)
			(end 1.16078 0.4826)
			(stroke
				(width 0.1524)
				(type default)
			)
			(layer "F.SilkS")
		)
		(fp_line
			(start 1.16078 0.4826)
			(end -0.64008 0.4826)
			(stroke
				(width 0.1524)
				(type default)
			)
			(layer "F.SilkS")
		)
		(fp_line
			(start -0.499872 -0.249936)
			(end 0.499872 -0.249936)
			(stroke
				(width 0.1)
				(type default)
			)
			(layer "F.Fab")
		)
		(fp_line
			(start -0.499872 0.249936)
			(end -0.499872 -0.249936)
			(stroke
				(width 0.1)
				(type default)
			)
			(layer "F.Fab")
		)
		(fp_line
			(start 0.499872 -0.249936)
			(end 0.499872 0.249936)
			(stroke
				(width 0.1)
				(type default)
			)
			(layer "F.Fab")
		)
		(fp_line
			(start 0.499872 0.249936)
			(end -0.499872 0.249936)
			(stroke
				(width 0.1)
				(type default)
			)
			(layer "F.Fab")
		)
		(pad "A" smd rect
			(at -0.47498 0)
			(size 0.6096 0.7112)
			(layers "F.Cu" "F.Mask" "F.Paste")
			(net "LED_PWRGD_CPUPWRGD_GTL")
		)
		(pad "C" smd rect
			(at 0.47498 0)
			(size 0.6096 0.7112)
			(layers "F.Cu" "F.Mask" "F.Paste")
			(net "LED_PWRGD_CPUPWRGD_GTL_D")
		)
	)
	(footprint ""
		(layer "F.Cu")
		(at 107.2769 -256.6543 -90)
		(property "Reference" "C299"
			(at 0 0 270)
			(layer "F.SilkS")
			(hide yes)
			(effects
				(font
					(size 1.27 1.27)
				)
			)
		)
		(property "Value" ""
			(at 0 0 270)
			(layer "F.Fab")
			(effects
				(font
					(size 1.27 1.27)
				)
			)
		)
		(duplicate_pad_numbers_are_jumpers no)
		(fp_line
			(start -0.7874 0.4064)
			(end -0.7874 -0.4064)
			(stroke
				(width 0.1524)
				(type default)
			)
			(layer "F.SilkS")
		)
		(fp_line
			(start 0.7874 0.4064)
			(end -0.7874 0.4064)
			(stroke
				(width 0.1524)
				(type default)
			)
			(layer "F.SilkS")
		)
		(fp_line
			(start -0.7874 -0.4064)
			(end 0.7874 -0.4064)
			(stroke
				(width 0.1524)
				(type default)
			)
			(layer "F.SilkS")
		)
		(fp_line
			(start 0.7874 -0.4064)
			(end 0.7874 0.4064)
			(stroke
				(width 0.1524)
				(type default)
			)
			(layer "F.SilkS")
		)
		(fp_line
			(start -0.67945 0.3048)
			(end -0.67945 -0.305054)
			(stroke
				(width 0.1)
				(type default)
			)
			(layer "F.Fab")
		)
		(fp_line
			(start -0.12065 0.3048)
			(end -0.67945 0.3048)
			(stroke
				(width 0.1)
				(type default)
			)
			(layer "F.Fab")
		)
		(fp_line
			(start 0.120396 0.3048)
			(end 0.120396 0.2794)
			(stroke
				(width 0.1)
				(type default)
			)
			(layer "F.Fab")
		)
		(fp_line
			(start 0.67945 0.3048)
			(end 0.120396 0.3048)
			(stroke
				(width 0.1)
				(type default)
			)
			(layer "F.Fab")
		)
		(fp_line
			(start -0.12065 0.2794)
			(end -0.12065 0.3048)
			(stroke
				(width 0.1)
				(type default)
			)
			(layer "F.Fab")
		)
		(fp_line
			(start 0.120396 0.2794)
			(end -0.12065 0.2794)
			(stroke
				(width 0.1)
				(type default)
			)
			(layer "F.Fab")
		)
		(fp_line
			(start -0.12065 -0.2794)
			(end 0.12065 -0.2794)
			(stroke
				(width 0.1)
				(type default)
			)
			(layer "F.Fab")
		)
		(fp_line
			(start 0.12065 -0.2794)
			(end 0.12065 -0.3048)
			(stroke
				(width 0.1)
				(type default)
			)
			(layer "F.Fab")
		)
		(fp_line
			(start 0.12065 -0.3048)
			(end 0.67945 -0.3048)
			(stroke
				(width 0.1)
				(type default)
			)
			(layer "F.Fab")
		)
		(fp_line
			(start 0.67945 -0.3048)
			(end 0.67945 0.3048)
			(stroke
				(width 0.1)
				(type default)
			)
			(layer "F.Fab")
		)
		(fp_line
			(start -0.67945 -0.305054)
			(end -0.12065 -0.305054)
			(stroke
				(width 0.1)
				(type default)
			)
			(layer "F.Fab")
		)
		(fp_line
			(start -0.12065 -0.305054)
			(end -0.12065 -0.2794)
			(stroke
				(width 0.1)
				(type default)
			)
			(layer "F.Fab")
		)
		(pad "1" smd circle
			(at -0.40005 0 270)
			(size 0 0)
			(layers "F.Cu" "F.Mask" "F.Paste")
			(net "PVCCIN_CPU1")
		)
		(pad "2" smd circle
			(at 0.40005 0 270)
			(size 0 0)
			(layers "F.Cu" "F.Mask" "F.Paste")
			(net "GND")
		)
	)
	(footprint ""
		(layer "F.Cu")
		(at 104.34193 -240.277142 90)
		(property "Reference" "C430"
			(at 0 0 90)
			(layer "F.SilkS")
			(hide yes)
			(effects
				(font
					(size 1.27 1.27)
				)
			)
		)
		(property "Value" ""
			(at 0 0 90)
			(layer "F.Fab")
			(effects
				(font
					(size 1.27 1.27)
				)
			)
		)
		(duplicate_pad_numbers_are_jumpers no)
		(fp_line
			(start 0.7874 -0.4064)
			(end 0.7874 0.4064)
			(stroke
				(width 0.1524)
				(type default)
			)
			(layer "F.SilkS")
		)
		(fp_line
			(start -0.7874 -0.4064)
			(end 0.7874 -0.4064)
			(stroke
				(width 0.1524)
				(type default)
			)
			(layer "F.SilkS")
		)
		(fp_line
			(start 0.7874 0.4064)
			(end -0.7874 0.4064)
			(stroke
				(width 0.1524)
				(type default)
			)
			(layer "F.SilkS")
		)
		(fp_line
			(start -0.7874 0.4064)
			(end -0.7874 -0.4064)
			(stroke
				(width 0.1524)
				(type default)
			)
			(layer "F.SilkS")
		)
		(fp_line
			(start -0.12065 -0.305054)
			(end -0.12065 -0.2794)
			(stroke
				(width 0.1)
				(type default)
			)
			(layer "F.Fab")
		)
		(fp_line
			(start -0.67945 -0.305054)
			(end -0.12065 -0.305054)
			(stroke
				(width 0.1)
				(type default)
			)
			(layer "F.Fab")
		)
		(fp_line
			(start 0.67945 -0.3048)
			(end 0.67945 0.3048)
			(stroke
				(width 0.1)
				(type default)
			)
			(layer "F.Fab")
		)
		(fp_line
			(start 0.12065 -0.3048)
			(end 0.67945 -0.3048)
			(stroke
				(width 0.1)
				(type default)
			)
			(layer "F.Fab")
		)
		(fp_line
			(start 0.12065 -0.2794)
			(end 0.12065 -0.3048)
			(stroke
				(width 0.1)
				(type default)
			)
			(layer "F.Fab")
		)
		(fp_line
			(start -0.12065 -0.2794)
			(end 0.12065 -0.2794)
			(stroke
				(width 0.1)
				(type default)
			)
			(layer "F.Fab")
		)
		(fp_line
			(start 0.120396 0.2794)
			(end -0.12065 0.2794)
			(stroke
				(width 0.1)
				(type default)
			)
			(layer "F.Fab")
		)
		(fp_line
			(start -0.12065 0.2794)
			(end -0.12065 0.3048)
			(stroke
				(width 0.1)
				(type default)
			)
			(layer "F.Fab")
		)
		(fp_line
			(start 0.67945 0.3048)
			(end 0.120396 0.3048)
			(stroke
				(width 0.1)
				(type default)
			)
			(layer "F.Fab")
		)
		(fp_line
			(start 0.120396 0.3048)
			(end 0.120396 0.2794)
			(stroke
				(width 0.1)
				(type default)
			)
			(layer "F.Fab")
		)
		(fp_line
			(start -0.12065 0.3048)
			(end -0.67945 0.3048)
			(stroke
				(width 0.1)
				(type default)
			)
			(layer "F.Fab")
		)
		(fp_line
			(start -0.67945 0.3048)
			(end -0.67945 -0.305054)
			(stroke
				(width 0.1)
				(type default)
			)
			(layer "F.Fab")
		)
		(pad "1" smd circle
			(at -0.40005 0 90)
			(size 0 0)
			(layers "F.Cu" "F.Mask" "F.Paste")
			(net "PVCCFA_EHV_FIVRA_CPU1")
		)
		(pad "2" smd circle
			(at 0.40005 0 90)
			(size 0 0)
			(layers "F.Cu" "F.Mask" "F.Paste")
			(net "GND")
		)
	)
	(footprint ""
		(layer "F.Cu")
		(at 374.112282 -59.295792)
		(property "Reference" "R752"
			(at 0 0 0)
			(layer "F.SilkS")
			(hide yes)
			(effects
				(font
					(size 1.27 1.27)
				)
			)
		)
		(property "Value" ""
			(at 0 0 0)
			(layer "F.Fab")
			(effects
				(font
					(size 1.27 1.27)
				)
			)
		)
		(duplicate_pad_numbers_are_jumpers no)
		(fp_line
			(start -0.7874 -0.4064)
			(end 0.7874 -0.4064)
			(stroke
				(width 0.1524)
				(type default)
			)
			(layer "F.SilkS")
		)
		(fp_line
			(start -0.7874 0.4064)
			(end -0.7874 -0.4064)
			(stroke
				(width 0.1524)
				(type default)
			)
			(layer "F.SilkS")
		)
		(fp_line
			(start 0.7874 -0.4064)
			(end 0.7874 0.4064)
			(stroke
				(width 0.1524)
				(type default)
			)
			(layer "F.SilkS")
		)
		(fp_line
			(start 0.7874 0.4064)
			(end -0.7874 0.4064)
			(stroke
				(width 0.1524)
				(type default)
			)
			(layer "F.SilkS")
		)
		(fp_line
			(start -0.67945 -0.305054)
			(end -0.12065 -0.305054)
			(stroke
				(width 0.1)
				(type default)
			)
			(layer "F.Fab")
		)
		(fp_line
			(start -0.67945 0.3048)
			(end -0.67945 -0.305054)
			(stroke
				(width 0.1)
				(type default)
			)
			(layer "F.Fab")
		)
		(fp_line
			(start -0.12065 -0.305054)
			(end -0.12065 -0.2794)
			(stroke
				(width 0.1)
				(type default)
			)
			(layer "F.Fab")
		)
		(fp_line
			(start -0.12065 -0.2794)
			(end 0.12065 -0.2794)
			(stroke
				(width 0.1)
				(type default)
			)
			(layer "F.Fab")
		)
		(fp_line
			(start -0.12065 0.2794)
			(end -0.12065 0.3048)
			(stroke
				(width 0.1)
				(type default)
			)
			(layer "F.Fab")
		)
		(fp_line
			(start -0.12065 0.3048)
			(end -0.67945 0.3048)
			(stroke
				(width 0.1)
				(type default)
			)
			(layer "F.Fab")
		)
		(fp_line
			(start 0.120396 0.2794)
			(end -0.12065 0.2794)
			(stroke
				(width 0.1)
				(type default)
			)
			(layer "F.Fab")
		)
		(fp_line
			(start 0.120396 0.3048)
			(end 0.120396 0.2794)
			(stroke
				(width 0.1)
				(type default)
			)
			(layer "F.Fab")
		)
		(fp_line
			(start 0.12065 -0.3048)
			(end 0.67945 -0.3048)
			(stroke
				(width 0.1)
				(type default)
			)
			(layer "F.Fab")
		)
		(fp_line
			(start 0.12065 -0.2794)
			(end 0.12065 -0.3048)
			(stroke
				(width 0.1)
				(type default)
			)
			(layer "F.Fab")
		)
		(fp_line
			(start 0.67945 -0.3048)
			(end 0.67945 0.3048)
			(stroke
				(width 0.1)
				(type default)
			)
			(layer "F.Fab")
		)
		(fp_line
			(start 0.67945 0.3048)
			(end 0.120396 0.3048)
			(stroke
				(width 0.1)
				(type default)
			)
			(layer "F.Fab")
		)
		(pad "1" smd circle
			(at -0.40005 0)
			(size 0 0)
			(layers "F.Cu" "F.Mask" "F.Paste")
			(net "JTAG_DBP_TDO")
		)
		(pad "2" smd circle
			(at 0.40005 0)
			(size 0 0)
			(layers "F.Cu" "F.Mask" "F.Paste")
			(net "JTAG_DBP_TDO_PCH")
		)
	)
	(footprint ""
		(layer "F.Cu")
		(at 313.53506 -26.062432 180)
		(property "Reference" "R1545"
			(at 0 0 180)
			(layer "F.SilkS")
			(hide yes)
			(effects
				(font
					(size 1.27 1.27)
				)
			)
		)
		(property "Value" ""
			(at 0 0 180)
			(layer "F.Fab")
			(effects
				(font
					(size 1.27 1.27)
				)
			)
		)
		(duplicate_pad_numbers_are_jumpers no)
		(fp_line
			(start 0.7874 0.4064)
			(end -0.7874 0.4064)
			(stroke
				(width 0.1524)
				(type default)
			)
			(layer "F.SilkS")
		)
		(fp_line
			(start 0.7874 -0.4064)
			(end 0.7874 0.4064)
			(stroke
				(width 0.1524)
				(type default)
			)
			(layer "F.SilkS")
		)
		(fp_line
			(start -0.7874 0.4064)
			(end -0.7874 -0.4064)
			(stroke
				(width 0.1524)
				(type default)
			)
			(layer "F.SilkS")
		)
		(fp_line
			(start -0.7874 -0.4064)
			(end 0.7874 -0.4064)
			(stroke
				(width 0.1524)
				(type default)
			)
			(layer "F.SilkS")
		)
		(fp_line
			(start 0.67945 0.3048)
			(end 0.120396 0.3048)
			(stroke
				(width 0.1)
				(type default)
			)
			(layer "F.Fab")
		)
		(fp_line
			(start 0.67945 -0.3048)
			(end 0.67945 0.3048)
			(stroke
				(width 0.1)
				(type default)
			)
			(layer "F.Fab")
		)
		(fp_line
			(start 0.12065 -0.2794)
			(end 0.12065 -0.3048)
			(stroke
				(width 0.1)
				(type default)
			)
			(layer "F.Fab")
		)
		(fp_line
			(start 0.12065 -0.3048)
			(end 0.67945 -0.3048)
			(stroke
				(width 0.1)
				(type default)
			)
			(layer "F.Fab")
		)
		(fp_line
			(start 0.120396 0.3048)
			(end 0.120396 0.2794)
			(stroke
				(width 0.1)
				(type default)
			)
			(layer "F.Fab")
		)
		(fp_line
			(start 0.120396 0.2794)
			(end -0.12065 0.2794)
			(stroke
				(width 0.1)
				(type default)
			)
			(layer "F.Fab")
		)
		(fp_line
			(start -0.12065 0.3048)
			(end -0.67945 0.3048)
			(stroke
				(width 0.1)
				(type default)
			)
			(layer "F.Fab")
		)
		(fp_line
			(start -0.12065 0.2794)
			(end -0.12065 0.3048)
			(stroke
				(width 0.1)
				(type default)
			)
			(layer "F.Fab")
		)
		(fp_line
			(start -0.12065 -0.2794)
			(end 0.12065 -0.2794)
			(stroke
				(width 0.1)
				(type default)
			)
			(layer "F.Fab")
		)
		(fp_line
			(start -0.12065 -0.305054)
			(end -0.12065 -0.2794)
			(stroke
				(width 0.1)
				(type default)
			)
			(layer "F.Fab")
		)
		(fp_line
			(start -0.67945 0.3048)
			(end -0.67945 -0.305054)
			(stroke
				(width 0.1)
				(type default)
			)
			(layer "F.Fab")
		)
		(fp_line
			(start -0.67945 -0.305054)
			(end -0.12065 -0.305054)
			(stroke
				(width 0.1)
				(type default)
			)
			(layer "F.Fab")
		)
		(pad "1" smd circle
			(at -0.40005 0 180)
			(size 0 0)
			(layers "F.Cu" "F.Mask" "F.Paste")
			(net "SMB_SML0B_3V3AUX_SCL")
		)
		(pad "2" smd circle
			(at 0.40005 0 180)
			(size 0 0)
			(layers "F.Cu" "F.Mask" "F.Paste")
			(net "P3V3_AUX")
		)
	)
	(footprint ""
		(layer "F.Cu")
		(at 164.64788 -112.232948)
		(property "Reference" "R3477"
			(at 0 0 0)
			(layer "F.SilkS")
			(hide yes)
			(effects
				(font
					(size 1.27 1.27)
				)
			)
		)
		(property "Value" ""
			(at 0 0 0)
			(layer "F.Fab")
			(effects
				(font
					(size 1.27 1.27)
				)
			)
		)
		(duplicate_pad_numbers_are_jumpers no)
		(fp_line
			(start -0.7874 -0.4064)
			(end 0.7874 -0.4064)
			(stroke
				(width 0.1524)
				(type default)
			)
			(layer "F.SilkS")
		)
		(fp_line
			(start -0.7874 0.4064)
			(end -0.7874 -0.4064)
			(stroke
				(width 0.1524)
				(type default)
			)
			(layer "F.SilkS")
		)
		(fp_line
			(start 0.7874 -0.4064)
			(end 0.7874 0.4064)
			(stroke
				(width 0.1524)
				(type default)
			)
			(layer "F.SilkS")
		)
		(fp_line
			(start 0.7874 0.4064)
			(end -0.7874 0.4064)
			(stroke
				(width 0.1524)
				(type default)
			)
			(layer "F.SilkS")
		)
		(fp_line
			(start -0.67945 -0.305054)
			(end -0.12065 -0.305054)
			(stroke
				(width 0.1)
				(type default)
			)
			(layer "F.Fab")
		)
		(fp_line
			(start -0.67945 0.3048)
			(end -0.67945 -0.305054)
			(stroke
				(width 0.1)
				(type default)
			)
			(layer "F.Fab")
		)
		(fp_line
			(start -0.12065 -0.305054)
			(end -0.12065 -0.2794)
			(stroke
				(width 0.1)
				(type default)
			)
			(layer "F.Fab")
		)
		(fp_line
			(start -0.12065 -0.2794)
			(end 0.12065 -0.2794)
			(stroke
				(width 0.1)
				(type default)
			)
			(layer "F.Fab")
		)
		(fp_line
			(start -0.12065 0.2794)
			(end -0.12065 0.3048)
			(stroke
				(width 0.1)
				(type default)
			)
			(layer "F.Fab")
		)
		(fp_line
			(start -0.12065 0.3048)
			(end -0.67945 0.3048)
			(stroke
				(width 0.1)
				(type default)
			)
			(layer "F.Fab")
		)
		(fp_line
			(start 0.120396 0.2794)
			(end -0.12065 0.2794)
			(stroke
				(width 0.1)
				(type default)
			)
			(layer "F.Fab")
		)
		(fp_line
			(start 0.120396 0.3048)
			(end 0.120396 0.2794)
			(stroke
				(width 0.1)
				(type default)
			)
			(layer "F.Fab")
		)
		(fp_line
			(start 0.12065 -0.3048)
			(end 0.67945 -0.3048)
			(stroke
				(width 0.1)
				(type default)
			)
			(layer "F.Fab")
		)
		(fp_line
			(start 0.12065 -0.2794)
			(end 0.12065 -0.3048)
			(stroke
				(width 0.1)
				(type default)
			)
			(layer "F.Fab")
		)
		(fp_line
			(start 0.67945 -0.3048)
			(end 0.67945 0.3048)
			(stroke
				(width 0.1)
				(type default)
			)
			(layer "F.Fab")
		)
		(fp_line
			(start 0.67945 0.3048)
			(end 0.120396 0.3048)
			(stroke
				(width 0.1)
				(type default)
			)
			(layer "F.Fab")
		)
		(pad "1" smd circle
			(at -0.40005 0)
			(size 0 0)
			(layers "F.Cu" "F.Mask" "F.Paste")
			(net "GPU_NVS_PWR_BRAKE_N")
		)
		(pad "2" smd circle
			(at 0.40005 0)
			(size 0 0)
			(layers "F.Cu" "F.Mask" "F.Paste")
			(net "GPU_NVS_PWR_BRAKE_R_N")
		)
	)
	(footprint ""
		(layer "F.Cu")
		(at 323.680328 -408.517344 -90)
		(property "Reference" "C914"
			(at 0 0 270)
			(layer "F.SilkS")
			(hide yes)
			(effects
				(font
					(size 1.27 1.27)
				)
			)
		)
		(property "Value" ""
			(at 0 0 270)
			(layer "F.Fab")
			(effects
				(font
					(size 1.27 1.27)
				)
			)
		)
		(duplicate_pad_numbers_are_jumpers no)
		(fp_line
			(start -0.299974 0.150114)
			(end -0.299974 -0.150114)
			(stroke
				(width 0.1)
				(type default)
			)
			(layer "F.Fab")
		)
		(fp_line
			(start 0.299974 0.150114)
			(end -0.299974 0.150114)
			(stroke
				(width 0.1)
				(type default)
			)
			(layer "F.Fab")
		)
		(fp_line
			(start -0.299974 -0.150114)
			(end 0.299974 -0.150114)
			(stroke
				(width 0.1)
				(type default)
			)
			(layer "F.Fab")
		)
		(fp_line
			(start 0.299974 -0.150114)
			(end 0.299974 0.150114)
			(stroke
				(width 0.1)
				(type default)
			)
			(layer "F.Fab")
		)
		(pad "1" smd rect
			(at -0.2667 0 270)
			(size 0.3048 0.381)
			(layers "F.Cu" "F.Mask" "F.Paste")
			(net "P5E_CPU0_PE0_TX_C_DN<9>")
		)
		(pad "2" smd rect
			(at 0.2667 0 270)
			(size 0.3048 0.381)
			(layers "F.Cu" "F.Mask" "F.Paste")
			(net "P5E_CPU0_PE0_TX_DN<9>")
		)
	)
	(footprint ""
		(layer "F.Cu")
		(at 101.833934 -395.42974)
		(property "Reference" "R3492"
			(at 0 0 0)
			(layer "F.SilkS")
			(hide yes)
			(effects
				(font
					(size 1.27 1.27)
				)
			)
		)
		(property "Value" ""
			(at 0 0 0)
			(layer "F.Fab")
			(effects
				(font
					(size 1.27 1.27)
				)
			)
		)
		(duplicate_pad_numbers_are_jumpers no)
		(fp_line
			(start -0.7874 -0.4064)
			(end 0.7874 -0.4064)
			(stroke
				(width 0.1524)
				(type default)
			)
			(layer "F.SilkS")
		)
		(fp_line
			(start -0.7874 0.4064)
			(end -0.7874 -0.4064)
			(stroke
				(width 0.1524)
				(type default)
			)
			(layer "F.SilkS")
		)
		(fp_line
			(start 0.7874 -0.4064)
			(end 0.7874 0.4064)
			(stroke
				(width 0.1524)
				(type default)
			)
			(layer "F.SilkS")
		)
		(fp_line
			(start 0.7874 0.4064)
			(end -0.7874 0.4064)
			(stroke
				(width 0.1524)
				(type default)
			)
			(layer "F.SilkS")
		)
		(fp_line
			(start -0.67945 -0.305054)
			(end -0.12065 -0.305054)
			(stroke
				(width 0.1)
				(type default)
			)
			(layer "F.Fab")
		)
		(fp_line
			(start -0.67945 0.3048)
			(end -0.67945 -0.305054)
			(stroke
				(width 0.1)
				(type default)
			)
			(layer "F.Fab")
		)
		(fp_line
			(start -0.12065 -0.305054)
			(end -0.12065 -0.2794)
			(stroke
				(width 0.1)
				(type default)
			)
			(layer "F.Fab")
		)
		(fp_line
			(start -0.12065 -0.2794)
			(end 0.12065 -0.2794)
			(stroke
				(width 0.1)
				(type default)
			)
			(layer "F.Fab")
		)
		(fp_line
			(start -0.12065 0.2794)
			(end -0.12065 0.3048)
			(stroke
				(width 0.1)
				(type default)
			)
			(layer "F.Fab")
		)
		(fp_line
			(start -0.12065 0.3048)
			(end -0.67945 0.3048)
			(stroke
				(width 0.1)
				(type default)
			)
			(layer "F.Fab")
		)
		(fp_line
			(start 0.120396 0.2794)
			(end -0.12065 0.2794)
			(stroke
				(width 0.1)
				(type default)
			)
			(layer "F.Fab")
		)
		(fp_line
			(start 0.120396 0.3048)
			(end 0.120396 0.2794)
			(stroke
				(width 0.1)
				(type default)
			)
			(layer "F.Fab")
		)
		(fp_line
			(start 0.12065 -0.3048)
			(end 0.67945 -0.3048)
			(stroke
				(width 0.1)
				(type default)
			)
			(layer "F.Fab")
		)
		(fp_line
			(start 0.12065 -0.2794)
			(end 0.12065 -0.3048)
			(stroke
				(width 0.1)
				(type default)
			)
			(layer "F.Fab")
		)
		(fp_line
			(start 0.67945 -0.3048)
			(end 0.67945 0.3048)
			(stroke
				(width 0.1)
				(type default)
			)
			(layer "F.Fab")
		)
		(fp_line
			(start 0.67945 0.3048)
			(end 0.120396 0.3048)
			(stroke
				(width 0.1)
				(type default)
			)
			(layer "F.Fab")
		)
		(pad "1" smd circle
			(at -0.40005 0)
			(size 0 0)
			(layers "F.Cu" "F.Mask" "F.Paste")
			(net "P3V3_AUX")
		)
		(pad "2" smd circle
			(at 0.40005 0)
			(size 0 0)
			(layers "F.Cu" "F.Mask" "F.Paste")
			(net "GPU_FPGA_EROT_RST_BUF_R_N")
		)
	)
	(footprint ""
		(layer "F.Cu")
		(at 19.769582 -428.024036 90)
		(property "Reference" "R3441"
			(at 0 0 90)
			(layer "F.SilkS")
			(hide yes)
			(effects
				(font
					(size 1.27 1.27)
				)
			)
		)
		(property "Value" ""
			(at 0 0 90)
			(layer "F.Fab")
			(effects
				(font
					(size 1.27 1.27)
				)
			)
		)
		(duplicate_pad_numbers_are_jumpers no)
		(fp_line
			(start 0.7874 -0.4064)
			(end 0.7874 0.4064)
			(stroke
				(width 0.1524)
				(type default)
			)
			(layer "F.SilkS")
		)
		(fp_line
			(start -0.7874 -0.4064)
			(end 0.7874 -0.4064)
			(stroke
				(width 0.1524)
				(type default)
			)
			(layer "F.SilkS")
		)
		(fp_line
			(start 0.7874 0.4064)
			(end -0.7874 0.4064)
			(stroke
				(width 0.1524)
				(type default)
			)
			(layer "F.SilkS")
		)
		(fp_line
			(start -0.7874 0.4064)
			(end -0.7874 -0.4064)
			(stroke
				(width 0.1524)
				(type default)
			)
			(layer "F.SilkS")
		)
		(fp_line
			(start -0.12065 -0.305054)
			(end -0.12065 -0.2794)
			(stroke
				(width 0.1)
				(type default)
			)
			(layer "F.Fab")
		)
		(fp_line
			(start -0.67945 -0.305054)
			(end -0.12065 -0.305054)
			(stroke
				(width 0.1)
				(type default)
			)
			(layer "F.Fab")
		)
		(fp_line
			(start 0.67945 -0.3048)
			(end 0.67945 0.3048)
			(stroke
				(width 0.1)
				(type default)
			)
			(layer "F.Fab")
		)
		(fp_line
			(start 0.12065 -0.3048)
			(end 0.67945 -0.3048)
			(stroke
				(width 0.1)
				(type default)
			)
			(layer "F.Fab")
		)
		(fp_line
			(start 0.12065 -0.2794)
			(end 0.12065 -0.3048)
			(stroke
				(width 0.1)
				(type default)
			)
			(layer "F.Fab")
		)
		(fp_line
			(start -0.12065 -0.2794)
			(end 0.12065 -0.2794)
			(stroke
				(width 0.1)
				(type default)
			)
			(layer "F.Fab")
		)
		(fp_line
			(start 0.120396 0.2794)
			(end -0.12065 0.2794)
			(stroke
				(width 0.1)
				(type default)
			)
			(layer "F.Fab")
		)
		(fp_line
			(start -0.12065 0.2794)
			(end -0.12065 0.3048)
			(stroke
				(width 0.1)
				(type default)
			)
			(layer "F.Fab")
		)
		(fp_line
			(start 0.67945 0.3048)
			(end 0.120396 0.3048)
			(stroke
				(width 0.1)
				(type default)
			)
			(layer "F.Fab")
		)
		(fp_line
			(start 0.120396 0.3048)
			(end 0.120396 0.2794)
			(stroke
				(width 0.1)
				(type default)
			)
			(layer "F.Fab")
		)
		(fp_line
			(start -0.12065 0.3048)
			(end -0.67945 0.3048)
			(stroke
				(width 0.1)
				(type default)
			)
			(layer "F.Fab")
		)
		(fp_line
			(start -0.67945 0.3048)
			(end -0.67945 -0.305054)
			(stroke
				(width 0.1)
				(type default)
			)
			(layer "F.Fab")
		)
		(pad "1" smd circle
			(at -0.40005 0 90)
			(size 0 0)
			(layers "F.Cu" "F.Mask" "F.Paste")
			(net "GPU_BASE_ID1")
		)
		(pad "2" smd circle
			(at 0.40005 0 90)
			(size 0 0)
			(layers "F.Cu" "F.Mask" "F.Paste")
			(net "GND")
		)
	)
	(footprint ""
		(layer "F.Cu")
		(at 461.459834 -160.50006)
		(property "Reference" "H104"
			(at -6.563614 -4.53263 0)
			(unlocked yes)
			(layer "F.SilkS")
			(effects
				(font
					(size 0.7874 0.5842)
					(thickness 0.1524)
				)
				(justify left)
			)
		)
		(property "Value" ""
			(at 0 0 0)
			(layer "F.Fab")
			(effects
				(font
					(size 1.27 1.27)
				)
			)
		)
		(duplicate_pad_numbers_are_jumpers no)
		(pad "1" thru_hole circle
			(at 0 0)
			(size 10.0076 10.0076)
			(drill 5.6134)
			(layers "*.Cu" "*.Mask")
			(remove_unused_layers no)
			(net "GND")
			(clearance -1.9431)
		)
	)
	(footprint ""
		(layer "F.Cu")
		(at 144.320006 -77.532738)
		(property "Reference" "C1619"
			(at 0 0 0)
			(layer "F.SilkS")
			(hide yes)
			(effects
				(font
					(size 1.27 1.27)
				)
			)
		)
		(property "Value" ""
			(at 0 0 0)
			(layer "F.Fab")
			(effects
				(font
					(size 1.27 1.27)
				)
			)
		)
		(duplicate_pad_numbers_are_jumpers no)
		(fp_line
			(start -0.7874 -0.4064)
			(end 0.7874 -0.4064)
			(stroke
				(width 0.1524)
				(type default)
			)
			(layer "F.SilkS")
		)
		(fp_line
			(start -0.7874 0.4064)
			(end -0.7874 -0.4064)
			(stroke
				(width 0.1524)
				(type default)
			)
			(layer "F.SilkS")
		)
		(fp_line
			(start 0.7874 -0.4064)
			(end 0.7874 0.4064)
			(stroke
				(width 0.1524)
				(type default)
			)
			(layer "F.SilkS")
		)
		(fp_line
			(start 0.7874 0.4064)
			(end -0.7874 0.4064)
			(stroke
				(width 0.1524)
				(type default)
			)
			(layer "F.SilkS")
		)
		(fp_line
			(start -0.67945 -0.305054)
			(end -0.12065 -0.305054)
			(stroke
				(width 0.1)
				(type default)
			)
			(layer "F.Fab")
		)
		(fp_line
			(start -0.67945 0.3048)
			(end -0.67945 -0.305054)
			(stroke
				(width 0.1)
				(type default)
			)
			(layer "F.Fab")
		)
		(fp_line
			(start -0.12065 -0.305054)
			(end -0.12065 -0.2794)
			(stroke
				(width 0.1)
				(type default)
			)
			(layer "F.Fab")
		)
		(fp_line
			(start -0.12065 -0.2794)
			(end 0.12065 -0.2794)
			(stroke
				(width 0.1)
				(type default)
			)
			(layer "F.Fab")
		)
		(fp_line
			(start -0.12065 0.2794)
			(end -0.12065 0.3048)
			(stroke
				(width 0.1)
				(type default)
			)
			(layer "F.Fab")
		)
		(fp_line
			(start -0.12065 0.3048)
			(end -0.67945 0.3048)
			(stroke
				(width 0.1)
				(type default)
			)
			(layer "F.Fab")
		)
		(fp_line
			(start 0.120396 0.2794)
			(end -0.12065 0.2794)
			(stroke
				(width 0.1)
				(type default)
			)
			(layer "F.Fab")
		)
		(fp_line
			(start 0.120396 0.3048)
			(end 0.120396 0.2794)
			(stroke
				(width 0.1)
				(type default)
			)
			(layer "F.Fab")
		)
		(fp_line
			(start 0.12065 -0.3048)
			(end 0.67945 -0.3048)
			(stroke
				(width 0.1)
				(type default)
			)
			(layer "F.Fab")
		)
		(fp_line
			(start 0.12065 -0.2794)
			(end 0.12065 -0.3048)
			(stroke
				(width 0.1)
				(type default)
			)
			(layer "F.Fab")
		)
		(fp_line
			(start 0.67945 -0.3048)
			(end 0.67945 0.3048)
			(stroke
				(width 0.1)
				(type default)
			)
			(layer "F.Fab")
		)
		(fp_line
			(start 0.67945 0.3048)
			(end 0.120396 0.3048)
			(stroke
				(width 0.1)
				(type default)
			)
			(layer "F.Fab")
		)
		(pad "1" smd circle
			(at -0.40005 0)
			(size 0 0)
			(layers "F.Cu" "F.Mask" "F.Paste")
			(net "P3V3_AUX")
		)
		(pad "2" smd circle
			(at 0.40005 0)
			(size 0 0)
			(layers "F.Cu" "F.Mask" "F.Paste")
			(net "GND")
		)
	)
	(footprint ""
		(layer "F.Cu")
		(at 209.959956 -37.769292 90)
		(property "Reference" "C2014"
			(at 0 0 90)
			(layer "F.SilkS")
			(hide yes)
			(effects
				(font
					(size 1.27 1.27)
				)
			)
		)
		(property "Value" ""
			(at 0 0 90)
			(layer "F.Fab")
			(effects
				(font
					(size 1.27 1.27)
				)
			)
		)
		(duplicate_pad_numbers_are_jumpers no)
		(fp_line
			(start 0.7874 -0.4064)
			(end 0.7874 0.4064)
			(stroke
				(width 0.1524)
				(type default)
			)
			(layer "F.SilkS")
		)
		(fp_line
			(start -0.7874 -0.4064)
			(end 0.7874 -0.4064)
			(stroke
				(width 0.1524)
				(type default)
			)
			(layer "F.SilkS")
		)
		(fp_line
			(start 0.7874 0.4064)
			(end -0.7874 0.4064)
			(stroke
				(width 0.1524)
				(type default)
			)
			(layer "F.SilkS")
		)
		(fp_line
			(start -0.7874 0.4064)
			(end -0.7874 -0.4064)
			(stroke
				(width 0.1524)
				(type default)
			)
			(layer "F.SilkS")
		)
		(fp_line
			(start -0.12065 -0.305054)
			(end -0.12065 -0.2794)
			(stroke
				(width 0.1)
				(type default)
			)
			(layer "F.Fab")
		)
		(fp_line
			(start -0.67945 -0.305054)
			(end -0.12065 -0.305054)
			(stroke
				(width 0.1)
				(type default)
			)
			(layer "F.Fab")
		)
		(fp_line
			(start 0.67945 -0.3048)
			(end 0.67945 0.3048)
			(stroke
				(width 0.1)
				(type default)
			)
			(layer "F.Fab")
		)
		(fp_line
			(start 0.12065 -0.3048)
			(end 0.67945 -0.3048)
			(stroke
				(width 0.1)
				(type default)
			)
			(layer "F.Fab")
		)
		(fp_line
			(start 0.12065 -0.2794)
			(end 0.12065 -0.3048)
			(stroke
				(width 0.1)
				(type default)
			)
			(layer "F.Fab")
		)
		(fp_line
			(start -0.12065 -0.2794)
			(end 0.12065 -0.2794)
			(stroke
				(width 0.1)
				(type default)
			)
			(layer "F.Fab")
		)
		(fp_line
			(start 0.120396 0.2794)
			(end -0.12065 0.2794)
			(stroke
				(width 0.1)
				(type default)
			)
			(layer "F.Fab")
		)
		(fp_line
			(start -0.12065 0.2794)
			(end -0.12065 0.3048)
			(stroke
				(width 0.1)
				(type default)
			)
			(layer "F.Fab")
		)
		(fp_line
			(start 0.67945 0.3048)
			(end 0.120396 0.3048)
			(stroke
				(width 0.1)
				(type default)
			)
			(layer "F.Fab")
		)
		(fp_line
			(start 0.120396 0.3048)
			(end 0.120396 0.2794)
			(stroke
				(width 0.1)
				(type default)
			)
			(layer "F.Fab")
		)
		(fp_line
			(start -0.12065 0.3048)
			(end -0.67945 0.3048)
			(stroke
				(width 0.1)
				(type default)
			)
			(layer "F.Fab")
		)
		(fp_line
			(start -0.67945 0.3048)
			(end -0.67945 -0.305054)
			(stroke
				(width 0.1)
				(type default)
			)
			(layer "F.Fab")
		)
		(pad "1" smd circle
			(at -0.40005 0 90)
			(size 0 0)
			(layers "F.Cu" "F.Mask" "F.Paste")
			(net "P3V3_AUX")
		)
		(pad "2" smd circle
			(at 0.40005 0 90)
			(size 0 0)
			(layers "F.Cu" "F.Mask" "F.Paste")
			(net "GND")
		)
	)
	(footprint ""
		(layer "F.Cu")
		(at 131.6736 -124.234448 180)
		(property "Reference" "R3150"
			(at 0 0 180)
			(layer "F.SilkS")
			(hide yes)
			(effects
				(font
					(size 1.27 1.27)
				)
			)
		)
		(property "Value" ""
			(at 0 0 180)
			(layer "F.Fab")
			(effects
				(font
					(size 1.27 1.27)
				)
			)
		)
		(duplicate_pad_numbers_are_jumpers no)
		(fp_line
			(start 0.7874 0.4064)
			(end -0.7874 0.4064)
			(stroke
				(width 0.1524)
				(type default)
			)
			(layer "F.SilkS")
		)
		(fp_line
			(start 0.7874 -0.4064)
			(end 0.7874 0.4064)
			(stroke
				(width 0.1524)
				(type default)
			)
			(layer "F.SilkS")
		)
		(fp_line
			(start -0.7874 0.4064)
			(end -0.7874 -0.4064)
			(stroke
				(width 0.1524)
				(type default)
			)
			(layer "F.SilkS")
		)
		(fp_line
			(start -0.7874 -0.4064)
			(end 0.7874 -0.4064)
			(stroke
				(width 0.1524)
				(type default)
			)
			(layer "F.SilkS")
		)
		(fp_line
			(start 0.67945 0.3048)
			(end 0.120396 0.3048)
			(stroke
				(width 0.1)
				(type default)
			)
			(layer "F.Fab")
		)
		(fp_line
			(start 0.67945 -0.3048)
			(end 0.67945 0.3048)
			(stroke
				(width 0.1)
				(type default)
			)
			(layer "F.Fab")
		)
		(fp_line
			(start 0.12065 -0.2794)
			(end 0.12065 -0.3048)
			(stroke
				(width 0.1)
				(type default)
			)
			(layer "F.Fab")
		)
		(fp_line
			(start 0.12065 -0.3048)
			(end 0.67945 -0.3048)
			(stroke
				(width 0.1)
				(type default)
			)
			(layer "F.Fab")
		)
		(fp_line
			(start 0.120396 0.3048)
			(end 0.120396 0.2794)
			(stroke
				(width 0.1)
				(type default)
			)
			(layer "F.Fab")
		)
		(fp_line
			(start 0.120396 0.2794)
			(end -0.12065 0.2794)
			(stroke
				(width 0.1)
				(type default)
			)
			(layer "F.Fab")
		)
		(fp_line
			(start -0.12065 0.3048)
			(end -0.67945 0.3048)
			(stroke
				(width 0.1)
				(type default)
			)
			(layer "F.Fab")
		)
		(fp_line
			(start -0.12065 0.2794)
			(end -0.12065 0.3048)
			(stroke
				(width 0.1)
				(type default)
			)
			(layer "F.Fab")
		)
		(fp_line
			(start -0.12065 -0.2794)
			(end 0.12065 -0.2794)
			(stroke
				(width 0.1)
				(type default)
			)
			(layer "F.Fab")
		)
		(fp_line
			(start -0.12065 -0.305054)
			(end -0.12065 -0.2794)
			(stroke
				(width 0.1)
				(type default)
			)
			(layer "F.Fab")
		)
		(fp_line
			(start -0.67945 0.3048)
			(end -0.67945 -0.305054)
			(stroke
				(width 0.1)
				(type default)
			)
			(layer "F.Fab")
		)
		(fp_line
			(start -0.67945 -0.305054)
			(end -0.12065 -0.305054)
			(stroke
				(width 0.1)
				(type default)
			)
			(layer "F.Fab")
		)
		(pad "1" smd circle
			(at -0.40005 0 180)
			(size 0 0)
			(layers "F.Cu" "F.Mask" "F.Paste")
			(net "PD_SMB_OCP2_HP_ADD2")
		)
		(pad "2" smd circle
			(at 0.40005 0 180)
			(size 0 0)
			(layers "F.Cu" "F.Mask" "F.Paste")
			(net "GND")
		)
	)
	(footprint ""
		(layer "F.Cu")
		(at 285.211266 -362.584746 -90)
		(property "Reference" "PC1214_P0_4"
			(at 0 0 270)
			(layer "F.SilkS")
			(hide yes)
			(effects
				(font
					(size 1.27 1.27)
				)
			)
		)
		(property "Value" ""
			(at 0 0 270)
			(layer "F.Fab")
			(effects
				(font
					(size 1.27 1.27)
				)
			)
		)
		(duplicate_pad_numbers_are_jumpers no)
		(fp_line
			(start -0.7874 0.4064)
			(end -0.7874 -0.4064)
			(stroke
				(width 0.1524)
				(type default)
			)
			(layer "F.SilkS")
		)
		(fp_line
			(start 0.7874 0.4064)
			(end -0.7874 0.4064)
			(stroke
				(width 0.1524)
				(type default)
			)
			(layer "F.SilkS")
		)
		(fp_line
			(start -0.7874 -0.4064)
			(end 0.7874 -0.4064)
			(stroke
				(width 0.1524)
				(type default)
			)
			(layer "F.SilkS")
		)
		(fp_line
			(start 0.7874 -0.4064)
			(end 0.7874 0.4064)
			(stroke
				(width 0.1524)
				(type default)
			)
			(layer "F.SilkS")
		)
		(fp_line
			(start -0.67945 0.3048)
			(end -0.67945 -0.305054)
			(stroke
				(width 0.1)
				(type default)
			)
			(layer "F.Fab")
		)
		(fp_line
			(start -0.12065 0.3048)
			(end -0.67945 0.3048)
			(stroke
				(width 0.1)
				(type default)
			)
			(layer "F.Fab")
		)
		(fp_line
			(start 0.120396 0.3048)
			(end 0.120396 0.2794)
			(stroke
				(width 0.1)
				(type default)
			)
			(layer "F.Fab")
		)
		(fp_line
			(start 0.67945 0.3048)
			(end 0.120396 0.3048)
			(stroke
				(width 0.1)
				(type default)
			)
			(layer "F.Fab")
		)
		(fp_line
			(start -0.12065 0.2794)
			(end -0.12065 0.3048)
			(stroke
				(width 0.1)
				(type default)
			)
			(layer "F.Fab")
		)
		(fp_line
			(start 0.120396 0.2794)
			(end -0.12065 0.2794)
			(stroke
				(width 0.1)
				(type default)
			)
			(layer "F.Fab")
		)
		(fp_line
			(start -0.12065 -0.2794)
			(end 0.12065 -0.2794)
			(stroke
				(width 0.1)
				(type default)
			)
			(layer "F.Fab")
		)
		(fp_line
			(start 0.12065 -0.2794)
			(end 0.12065 -0.3048)
			(stroke
				(width 0.1)
				(type default)
			)
			(layer "F.Fab")
		)
		(fp_line
			(start 0.12065 -0.3048)
			(end 0.67945 -0.3048)
			(stroke
				(width 0.1)
				(type default)
			)
			(layer "F.Fab")
		)
		(fp_line
			(start 0.67945 -0.3048)
			(end 0.67945 0.3048)
			(stroke
				(width 0.1)
				(type default)
			)
			(layer "F.Fab")
		)
		(fp_line
			(start -0.67945 -0.305054)
			(end -0.12065 -0.305054)
			(stroke
				(width 0.1)
				(type default)
			)
			(layer "F.Fab")
		)
		(fp_line
			(start -0.12065 -0.305054)
			(end -0.12065 -0.2794)
			(stroke
				(width 0.1)
				(type default)
			)
			(layer "F.Fab")
		)
		(pad "1" smd circle
			(at -0.40005 0 270)
			(size 0 0)
			(layers "F.Cu" "F.Mask" "F.Paste")
			(net "PVCCFA_EHV_FIVRA_CPU0_PVCC2")
		)
		(pad "2" smd circle
			(at 0.40005 0 270)
			(size 0 0)
			(layers "F.Cu" "F.Mask" "F.Paste")
			(net "GND")
		)
	)
	(footprint ""
		(layer "F.Cu")
		(at 146.896074 -408.517344 -90)
		(property "Reference" "C1533"
			(at 0 0 270)
			(layer "F.SilkS")
			(hide yes)
			(effects
				(font
					(size 1.27 1.27)
				)
			)
		)
		(property "Value" ""
			(at 0 0 270)
			(layer "F.Fab")
			(effects
				(font
					(size 1.27 1.27)
				)
			)
		)
		(duplicate_pad_numbers_are_jumpers no)
		(fp_line
			(start -0.299974 0.150114)
			(end -0.299974 -0.150114)
			(stroke
				(width 0.1)
				(type default)
			)
			(layer "F.Fab")
		)
		(fp_line
			(start 0.299974 0.150114)
			(end -0.299974 0.150114)
			(stroke
				(width 0.1)
				(type default)
			)
			(layer "F.Fab")
		)
		(fp_line
			(start -0.299974 -0.150114)
			(end 0.299974 -0.150114)
			(stroke
				(width 0.1)
				(type default)
			)
			(layer "F.Fab")
		)
		(fp_line
			(start 0.299974 -0.150114)
			(end 0.299974 0.150114)
			(stroke
				(width 0.1)
				(type default)
			)
			(layer "F.Fab")
		)
		(pad "1" smd rect
			(at -0.2667 0 270)
			(size 0.3048 0.381)
			(layers "F.Cu" "F.Mask" "F.Paste")
			(net "P5E_CPU1_PE3_TX_C_DP<7>")
		)
		(pad "2" smd rect
			(at 0.2667 0 270)
			(size 0.3048 0.381)
			(layers "F.Cu" "F.Mask" "F.Paste")
			(net "P5E_CPU1_PE3_TX_DP<7>")
		)
	)
	(footprint ""
		(layer "F.Cu")
		(at 367.44783 -238.162338 90)
		(property "Reference" "C408"
			(at 0 0 90)
			(layer "F.SilkS")
			(hide yes)
			(effects
				(font
					(size 1.27 1.27)
				)
			)
		)
		(property "Value" ""
			(at 0 0 90)
			(layer "F.Fab")
			(effects
				(font
					(size 1.27 1.27)
				)
			)
		)
		(duplicate_pad_numbers_are_jumpers no)
		(fp_line
			(start 0.7874 -0.4064)
			(end 0.7874 0.4064)
			(stroke
				(width 0.1524)
				(type default)
			)
			(layer "F.SilkS")
		)
		(fp_line
			(start -0.7874 -0.4064)
			(end 0.7874 -0.4064)
			(stroke
				(width 0.1524)
				(type default)
			)
			(layer "F.SilkS")
		)
		(fp_line
			(start 0.7874 0.4064)
			(end -0.7874 0.4064)
			(stroke
				(width 0.1524)
				(type default)
			)
			(layer "F.SilkS")
		)
		(fp_line
			(start -0.7874 0.4064)
			(end -0.7874 -0.4064)
			(stroke
				(width 0.1524)
				(type default)
			)
			(layer "F.SilkS")
		)
		(fp_line
			(start -0.12065 -0.305054)
			(end -0.12065 -0.2794)
			(stroke
				(width 0.1)
				(type default)
			)
			(layer "F.Fab")
		)
		(fp_line
			(start -0.67945 -0.305054)
			(end -0.12065 -0.305054)
			(stroke
				(width 0.1)
				(type default)
			)
			(layer "F.Fab")
		)
		(fp_line
			(start 0.67945 -0.3048)
			(end 0.67945 0.3048)
			(stroke
				(width 0.1)
				(type default)
			)
			(layer "F.Fab")
		)
		(fp_line
			(start 0.12065 -0.3048)
			(end 0.67945 -0.3048)
			(stroke
				(width 0.1)
				(type default)
			)
			(layer "F.Fab")
		)
		(fp_line
			(start 0.12065 -0.2794)
			(end 0.12065 -0.3048)
			(stroke
				(width 0.1)
				(type default)
			)
			(layer "F.Fab")
		)
		(fp_line
			(start -0.12065 -0.2794)
			(end 0.12065 -0.2794)
			(stroke
				(width 0.1)
				(type default)
			)
			(layer "F.Fab")
		)
		(fp_line
			(start 0.120396 0.2794)
			(end -0.12065 0.2794)
			(stroke
				(width 0.1)
				(type default)
			)
			(layer "F.Fab")
		)
		(fp_line
			(start -0.12065 0.2794)
			(end -0.12065 0.3048)
			(stroke
				(width 0.1)
				(type default)
			)
			(layer "F.Fab")
		)
		(fp_line
			(start 0.67945 0.3048)
			(end 0.120396 0.3048)
			(stroke
				(width 0.1)
				(type default)
			)
			(layer "F.Fab")
		)
		(fp_line
			(start 0.120396 0.3048)
			(end 0.120396 0.2794)
			(stroke
				(width 0.1)
				(type default)
			)
			(layer "F.Fab")
		)
		(fp_line
			(start -0.12065 0.3048)
			(end -0.67945 0.3048)
			(stroke
				(width 0.1)
				(type default)
			)
			(layer "F.Fab")
		)
		(fp_line
			(start -0.67945 0.3048)
			(end -0.67945 -0.305054)
			(stroke
				(width 0.1)
				(type default)
			)
			(layer "F.Fab")
		)
		(pad "1" smd circle
			(at -0.40005 0 90)
			(size 0 0)
			(layers "F.Cu" "F.Mask" "F.Paste")
			(net "PVCCINFAON_CPU0")
		)
		(pad "2" smd circle
			(at 0.40005 0 90)
			(size 0 0)
			(layers "F.Cu" "F.Mask" "F.Paste")
			(net "GND")
		)
	)
	(footprint ""
		(layer "F.Cu")
		(at 60.527438 -31.887922 -90)
		(property "Reference" "R3867"
			(at 0 0 270)
			(layer "F.SilkS")
			(hide yes)
			(effects
				(font
					(size 1.27 1.27)
				)
			)
		)
		(property "Value" ""
			(at 0 0 270)
			(layer "F.Fab")
			(effects
				(font
					(size 1.27 1.27)
				)
			)
		)
		(duplicate_pad_numbers_are_jumpers no)
		(fp_line
			(start -0.7874 0.4064)
			(end -0.7874 -0.4064)
			(stroke
				(width 0.1524)
				(type default)
			)
			(layer "F.SilkS")
		)
		(fp_line
			(start 0.7874 0.4064)
			(end -0.7874 0.4064)
			(stroke
				(width 0.1524)
				(type default)
			)
			(layer "F.SilkS")
		)
		(fp_line
			(start -0.7874 -0.4064)
			(end 0.7874 -0.4064)
			(stroke
				(width 0.1524)
				(type default)
			)
			(layer "F.SilkS")
		)
		(fp_line
			(start 0.7874 -0.4064)
			(end 0.7874 0.4064)
			(stroke
				(width 0.1524)
				(type default)
			)
			(layer "F.SilkS")
		)
		(fp_line
			(start -0.67945 0.3048)
			(end -0.67945 -0.305054)
			(stroke
				(width 0.1)
				(type default)
			)
			(layer "F.Fab")
		)
		(fp_line
			(start -0.12065 0.3048)
			(end -0.67945 0.3048)
			(stroke
				(width 0.1)
				(type default)
			)
			(layer "F.Fab")
		)
		(fp_line
			(start 0.120396 0.3048)
			(end 0.120396 0.2794)
			(stroke
				(width 0.1)
				(type default)
			)
			(layer "F.Fab")
		)
		(fp_line
			(start 0.67945 0.3048)
			(end 0.120396 0.3048)
			(stroke
				(width 0.1)
				(type default)
			)
			(layer "F.Fab")
		)
		(fp_line
			(start -0.12065 0.2794)
			(end -0.12065 0.3048)
			(stroke
				(width 0.1)
				(type default)
			)
			(layer "F.Fab")
		)
		(fp_line
			(start 0.120396 0.2794)
			(end -0.12065 0.2794)
			(stroke
				(width 0.1)
				(type default)
			)
			(layer "F.Fab")
		)
		(fp_line
			(start -0.12065 -0.2794)
			(end 0.12065 -0.2794)
			(stroke
				(width 0.1)
				(type default)
			)
			(layer "F.Fab")
		)
		(fp_line
			(start 0.12065 -0.2794)
			(end 0.12065 -0.3048)
			(stroke
				(width 0.1)
				(type default)
			)
			(layer "F.Fab")
		)
		(fp_line
			(start 0.12065 -0.3048)
			(end 0.67945 -0.3048)
			(stroke
				(width 0.1)
				(type default)
			)
			(layer "F.Fab")
		)
		(fp_line
			(start 0.67945 -0.3048)
			(end 0.67945 0.3048)
			(stroke
				(width 0.1)
				(type default)
			)
			(layer "F.Fab")
		)
		(fp_line
			(start -0.67945 -0.305054)
			(end -0.12065 -0.305054)
			(stroke
				(width 0.1)
				(type default)
			)
			(layer "F.Fab")
		)
		(fp_line
			(start -0.12065 -0.305054)
			(end -0.12065 -0.2794)
			(stroke
				(width 0.1)
				(type default)
			)
			(layer "F.Fab")
		)
		(pad "1" smd rect
			(at -0.40005 0 90)
			(size 0.4572 0.508)
			(layers "F.Cu" "F.Mask" "F.Paste")
			(net "P12V_OCP_SENSE_2")
		)
		(pad "2" smd rect
			(at 0.40005 0 90)
			(size 0.4572 0.508)
			(layers "F.Cu" "F.Mask" "F.Paste")
			(net "P12V_OCP_V3_2_ISENSE_MAM_MAM")
		)
	)
	(footprint ""
		(layer "F.Cu")
		(at 130.73888 -92.674948 90)
		(property "Reference" "R4405"
			(at 0 0 90)
			(layer "F.SilkS")
			(hide yes)
			(effects
				(font
					(size 1.27 1.27)
				)
			)
		)
		(property "Value" ""
			(at 0 0 90)
			(layer "F.Fab")
			(effects
				(font
					(size 1.27 1.27)
				)
			)
		)
		(duplicate_pad_numbers_are_jumpers no)
		(fp_line
			(start 0.7874 -0.4064)
			(end 0.7874 0.4064)
			(stroke
				(width 0.1524)
				(type default)
			)
			(layer "F.SilkS")
		)
		(fp_line
			(start -0.7874 -0.4064)
			(end 0.7874 -0.4064)
			(stroke
				(width 0.1524)
				(type default)
			)
			(layer "F.SilkS")
		)
		(fp_line
			(start 0.7874 0.4064)
			(end -0.7874 0.4064)
			(stroke
				(width 0.1524)
				(type default)
			)
			(layer "F.SilkS")
		)
		(fp_line
			(start -0.7874 0.4064)
			(end -0.7874 -0.4064)
			(stroke
				(width 0.1524)
				(type default)
			)
			(layer "F.SilkS")
		)
		(fp_line
			(start -0.12065 -0.305054)
			(end -0.12065 -0.2794)
			(stroke
				(width 0.1)
				(type default)
			)
			(layer "F.Fab")
		)
		(fp_line
			(start -0.67945 -0.305054)
			(end -0.12065 -0.305054)
			(stroke
				(width 0.1)
				(type default)
			)
			(layer "F.Fab")
		)
		(fp_line
			(start 0.67945 -0.3048)
			(end 0.67945 0.3048)
			(stroke
				(width 0.1)
				(type default)
			)
			(layer "F.Fab")
		)
		(fp_line
			(start 0.12065 -0.3048)
			(end 0.67945 -0.3048)
			(stroke
				(width 0.1)
				(type default)
			)
			(layer "F.Fab")
		)
		(fp_line
			(start 0.12065 -0.2794)
			(end 0.12065 -0.3048)
			(stroke
				(width 0.1)
				(type default)
			)
			(layer "F.Fab")
		)
		(fp_line
			(start -0.12065 -0.2794)
			(end 0.12065 -0.2794)
			(stroke
				(width 0.1)
				(type default)
			)
			(layer "F.Fab")
		)
		(fp_line
			(start 0.120396 0.2794)
			(end -0.12065 0.2794)
			(stroke
				(width 0.1)
				(type default)
			)
			(layer "F.Fab")
		)
		(fp_line
			(start -0.12065 0.2794)
			(end -0.12065 0.3048)
			(stroke
				(width 0.1)
				(type default)
			)
			(layer "F.Fab")
		)
		(fp_line
			(start 0.67945 0.3048)
			(end 0.120396 0.3048)
			(stroke
				(width 0.1)
				(type default)
			)
			(layer "F.Fab")
		)
		(fp_line
			(start 0.120396 0.3048)
			(end 0.120396 0.2794)
			(stroke
				(width 0.1)
				(type default)
			)
			(layer "F.Fab")
		)
		(fp_line
			(start -0.12065 0.3048)
			(end -0.67945 0.3048)
			(stroke
				(width 0.1)
				(type default)
			)
			(layer "F.Fab")
		)
		(fp_line
			(start -0.67945 0.3048)
			(end -0.67945 -0.305054)
			(stroke
				(width 0.1)
				(type default)
			)
			(layer "F.Fab")
		)
		(pad "1" smd circle
			(at -0.40005 0 90)
			(size 0 0)
			(layers "F.Cu" "F.Mask" "F.Paste")
			(net "P3V3")
		)
		(pad "2" smd circle
			(at 0.40005 0 90)
			(size 0 0)
			(layers "F.Cu" "F.Mask" "F.Paste")
			(net "H_CPU0_MEMHOT_OUT_VT_N")
		)
	)
	(footprint ""
		(layer "F.Cu")
		(at 81.650078 -402.371052 -90)
		(property "Reference" "C732"
			(at 0 0 270)
			(layer "F.SilkS")
			(hide yes)
			(effects
				(font
					(size 1.27 1.27)
				)
			)
		)
		(property "Value" ""
			(at 0 0 270)
			(layer "F.Fab")
			(effects
				(font
					(size 1.27 1.27)
				)
			)
		)
		(duplicate_pad_numbers_are_jumpers no)
		(fp_line
			(start -0.299974 0.150114)
			(end -0.299974 -0.150114)
			(stroke
				(width 0.1)
				(type default)
			)
			(layer "F.Fab")
		)
		(fp_line
			(start 0.299974 0.150114)
			(end -0.299974 0.150114)
			(stroke
				(width 0.1)
				(type default)
			)
			(layer "F.Fab")
		)
		(fp_line
			(start -0.299974 -0.150114)
			(end 0.299974 -0.150114)
			(stroke
				(width 0.1)
				(type default)
			)
			(layer "F.Fab")
		)
		(fp_line
			(start 0.299974 -0.150114)
			(end 0.299974 0.150114)
			(stroke
				(width 0.1)
				(type default)
			)
			(layer "F.Fab")
		)
		(pad "1" smd rect
			(at -0.2667 0 270)
			(size 0.3048 0.381)
			(layers "F.Cu" "F.Mask" "F.Paste")
			(net "P5E_CPU1_PE0_TX_C_DN<4>")
		)
		(pad "2" smd rect
			(at 0.2667 0 270)
			(size 0.3048 0.381)
			(layers "F.Cu" "F.Mask" "F.Paste")
			(net "P5E_CPU1_PE0_TX_DN<4>")
		)
	)
	(footprint ""
		(layer "F.Cu")
		(at 152.76322 -116.506752)
		(property "Reference" "R2343"
			(at 0 0 0)
			(layer "F.SilkS")
			(hide yes)
			(effects
				(font
					(size 1.27 1.27)
				)
			)
		)
		(property "Value" ""
			(at 0 0 0)
			(layer "F.Fab")
			(effects
				(font
					(size 1.27 1.27)
				)
			)
		)
		(duplicate_pad_numbers_are_jumpers no)
		(fp_line
			(start -0.7874 -0.4064)
			(end 0.7874 -0.4064)
			(stroke
				(width 0.1524)
				(type default)
			)
			(layer "F.SilkS")
		)
		(fp_line
			(start -0.7874 0.4064)
			(end -0.7874 -0.4064)
			(stroke
				(width 0.1524)
				(type default)
			)
			(layer "F.SilkS")
		)
		(fp_line
			(start 0.7874 -0.4064)
			(end 0.7874 0.4064)
			(stroke
				(width 0.1524)
				(type default)
			)
			(layer "F.SilkS")
		)
		(fp_line
			(start 0.7874 0.4064)
			(end -0.7874 0.4064)
			(stroke
				(width 0.1524)
				(type default)
			)
			(layer "F.SilkS")
		)
		(fp_line
			(start -0.67945 -0.305054)
			(end -0.12065 -0.305054)
			(stroke
				(width 0.1)
				(type default)
			)
			(layer "F.Fab")
		)
		(fp_line
			(start -0.67945 0.3048)
			(end -0.67945 -0.305054)
			(stroke
				(width 0.1)
				(type default)
			)
			(layer "F.Fab")
		)
		(fp_line
			(start -0.12065 -0.305054)
			(end -0.12065 -0.2794)
			(stroke
				(width 0.1)
				(type default)
			)
			(layer "F.Fab")
		)
		(fp_line
			(start -0.12065 -0.2794)
			(end 0.12065 -0.2794)
			(stroke
				(width 0.1)
				(type default)
			)
			(layer "F.Fab")
		)
		(fp_line
			(start -0.12065 0.2794)
			(end -0.12065 0.3048)
			(stroke
				(width 0.1)
				(type default)
			)
			(layer "F.Fab")
		)
		(fp_line
			(start -0.12065 0.3048)
			(end -0.67945 0.3048)
			(stroke
				(width 0.1)
				(type default)
			)
			(layer "F.Fab")
		)
		(fp_line
			(start 0.120396 0.2794)
			(end -0.12065 0.2794)
			(stroke
				(width 0.1)
				(type default)
			)
			(layer "F.Fab")
		)
		(fp_line
			(start 0.120396 0.3048)
			(end 0.120396 0.2794)
			(stroke
				(width 0.1)
				(type default)
			)
			(layer "F.Fab")
		)
		(fp_line
			(start 0.12065 -0.3048)
			(end 0.67945 -0.3048)
			(stroke
				(width 0.1)
				(type default)
			)
			(layer "F.Fab")
		)
		(fp_line
			(start 0.12065 -0.2794)
			(end 0.12065 -0.3048)
			(stroke
				(width 0.1)
				(type default)
			)
			(layer "F.Fab")
		)
		(fp_line
			(start 0.67945 -0.3048)
			(end 0.67945 0.3048)
			(stroke
				(width 0.1)
				(type default)
			)
			(layer "F.Fab")
		)
		(fp_line
			(start 0.67945 0.3048)
			(end 0.120396 0.3048)
			(stroke
				(width 0.1)
				(type default)
			)
			(layer "F.Fab")
		)
		(pad "1" smd circle
			(at -0.40005 0)
			(size 0 0)
			(layers "F.Cu" "F.Mask" "F.Paste")
			(net "P5V_AUX_VCC")
		)
		(pad "2" smd circle
			(at 0.40005 0)
			(size 0 0)
			(layers "F.Cu" "F.Mask" "F.Paste")
			(net "PWRGD_P5V_AUX")
		)
	)
	(footprint ""
		(layer "F.Cu")
		(at 241.295428 -108.743496 180)
		(property "Reference" "R1014"
			(at 0 0 180)
			(layer "F.SilkS")
			(hide yes)
			(effects
				(font
					(size 1.27 1.27)
				)
			)
		)
		(property "Value" ""
			(at 0 0 180)
			(layer "F.Fab")
			(effects
				(font
					(size 1.27 1.27)
				)
			)
		)
		(duplicate_pad_numbers_are_jumpers no)
		(fp_line
			(start 0.7874 0.4064)
			(end -0.7874 0.4064)
			(stroke
				(width 0.1524)
				(type default)
			)
			(layer "F.SilkS")
		)
		(fp_line
			(start 0.7874 -0.4064)
			(end 0.7874 0.4064)
			(stroke
				(width 0.1524)
				(type default)
			)
			(layer "F.SilkS")
		)
		(fp_line
			(start -0.7874 0.4064)
			(end -0.7874 -0.4064)
			(stroke
				(width 0.1524)
				(type default)
			)
			(layer "F.SilkS")
		)
		(fp_line
			(start -0.7874 -0.4064)
			(end 0.7874 -0.4064)
			(stroke
				(width 0.1524)
				(type default)
			)
			(layer "F.SilkS")
		)
		(fp_line
			(start 0.67945 0.3048)
			(end 0.120396 0.3048)
			(stroke
				(width 0.1)
				(type default)
			)
			(layer "F.Fab")
		)
		(fp_line
			(start 0.67945 -0.3048)
			(end 0.67945 0.3048)
			(stroke
				(width 0.1)
				(type default)
			)
			(layer "F.Fab")
		)
		(fp_line
			(start 0.12065 -0.2794)
			(end 0.12065 -0.3048)
			(stroke
				(width 0.1)
				(type default)
			)
			(layer "F.Fab")
		)
		(fp_line
			(start 0.12065 -0.3048)
			(end 0.67945 -0.3048)
			(stroke
				(width 0.1)
				(type default)
			)
			(layer "F.Fab")
		)
		(fp_line
			(start 0.120396 0.3048)
			(end 0.120396 0.2794)
			(stroke
				(width 0.1)
				(type default)
			)
			(layer "F.Fab")
		)
		(fp_line
			(start 0.120396 0.2794)
			(end -0.12065 0.2794)
			(stroke
				(width 0.1)
				(type default)
			)
			(layer "F.Fab")
		)
		(fp_line
			(start -0.12065 0.3048)
			(end -0.67945 0.3048)
			(stroke
				(width 0.1)
				(type default)
			)
			(layer "F.Fab")
		)
		(fp_line
			(start -0.12065 0.2794)
			(end -0.12065 0.3048)
			(stroke
				(width 0.1)
				(type default)
			)
			(layer "F.Fab")
		)
		(fp_line
			(start -0.12065 -0.2794)
			(end 0.12065 -0.2794)
			(stroke
				(width 0.1)
				(type default)
			)
			(layer "F.Fab")
		)
		(fp_line
			(start -0.12065 -0.305054)
			(end -0.12065 -0.2794)
			(stroke
				(width 0.1)
				(type default)
			)
			(layer "F.Fab")
		)
		(fp_line
			(start -0.67945 0.3048)
			(end -0.67945 -0.305054)
			(stroke
				(width 0.1)
				(type default)
			)
			(layer "F.Fab")
		)
		(fp_line
			(start -0.67945 -0.305054)
			(end -0.12065 -0.305054)
			(stroke
				(width 0.1)
				(type default)
			)
			(layer "F.Fab")
		)
		(pad "1" smd circle
			(at -0.40005 0 180)
			(size 0 0)
			(layers "F.Cu" "F.Mask" "F.Paste")
			(net "CLK_25M_CK440_CPU0_DN")
		)
		(pad "2" smd circle
			(at 0.40005 0 180)
			(size 0 0)
			(layers "F.Cu" "F.Mask" "F.Paste")
			(net "CLK_25M_CK440_CPU0_R_DN")
		)
	)
	(footprint ""
		(layer "F.Cu")
		(at 33.449006 -391.635996 180)
		(property "Reference" "R4658"
			(at 0 0 180)
			(layer "F.SilkS")
			(hide yes)
			(effects
				(font
					(size 1.27 1.27)
				)
			)
		)
		(property "Value" ""
			(at 0 0 180)
			(layer "F.Fab")
			(effects
				(font
					(size 1.27 1.27)
				)
			)
		)
		(duplicate_pad_numbers_are_jumpers no)
		(fp_line
			(start 0.7874 0.4064)
			(end -0.7874 0.4064)
			(stroke
				(width 0.1524)
				(type default)
			)
			(layer "F.SilkS")
		)
		(fp_line
			(start 0.7874 -0.4064)
			(end 0.7874 0.4064)
			(stroke
				(width 0.1524)
				(type default)
			)
			(layer "F.SilkS")
		)
		(fp_line
			(start -0.7874 0.4064)
			(end -0.7874 -0.4064)
			(stroke
				(width 0.1524)
				(type default)
			)
			(layer "F.SilkS")
		)
		(fp_line
			(start -0.7874 -0.4064)
			(end 0.7874 -0.4064)
			(stroke
				(width 0.1524)
				(type default)
			)
			(layer "F.SilkS")
		)
		(fp_line
			(start 0.67945 0.3048)
			(end 0.120396 0.3048)
			(stroke
				(width 0.1)
				(type default)
			)
			(layer "F.Fab")
		)
		(fp_line
			(start 0.67945 -0.3048)
			(end 0.67945 0.3048)
			(stroke
				(width 0.1)
				(type default)
			)
			(layer "F.Fab")
		)
		(fp_line
			(start 0.12065 -0.2794)
			(end 0.12065 -0.3048)
			(stroke
				(width 0.1)
				(type default)
			)
			(layer "F.Fab")
		)
		(fp_line
			(start 0.12065 -0.3048)
			(end 0.67945 -0.3048)
			(stroke
				(width 0.1)
				(type default)
			)
			(layer "F.Fab")
		)
		(fp_line
			(start 0.120396 0.3048)
			(end 0.120396 0.2794)
			(stroke
				(width 0.1)
				(type default)
			)
			(layer "F.Fab")
		)
		(fp_line
			(start 0.120396 0.2794)
			(end -0.12065 0.2794)
			(stroke
				(width 0.1)
				(type default)
			)
			(layer "F.Fab")
		)
		(fp_line
			(start -0.12065 0.3048)
			(end -0.67945 0.3048)
			(stroke
				(width 0.1)
				(type default)
			)
			(layer "F.Fab")
		)
		(fp_line
			(start -0.12065 0.2794)
			(end -0.12065 0.3048)
			(stroke
				(width 0.1)
				(type default)
			)
			(layer "F.Fab")
		)
		(fp_line
			(start -0.12065 -0.2794)
			(end 0.12065 -0.2794)
			(stroke
				(width 0.1)
				(type default)
			)
			(layer "F.Fab")
		)
		(fp_line
			(start -0.12065 -0.305054)
			(end -0.12065 -0.2794)
			(stroke
				(width 0.1)
				(type default)
			)
			(layer "F.Fab")
		)
		(fp_line
			(start -0.67945 0.3048)
			(end -0.67945 -0.305054)
			(stroke
				(width 0.1)
				(type default)
			)
			(layer "F.Fab")
		)
		(fp_line
			(start -0.67945 -0.305054)
			(end -0.12065 -0.305054)
			(stroke
				(width 0.1)
				(type default)
			)
			(layer "F.Fab")
		)
		(pad "1" smd circle
			(at -0.40005 0 180)
			(size 0 0)
			(layers "F.Cu" "F.Mask" "F.Paste")
			(net "FM_P2E_BUF2_VOD_SEL")
		)
		(pad "2" smd circle
			(at 0.40005 0 180)
			(size 0 0)
			(layers "F.Cu" "F.Mask" "F.Paste")
			(net "GND")
		)
	)
	(footprint ""
		(layer "F.Cu")
		(at 24.447754 -399.532094 90)
		(property "Reference" "R3282"
			(at 0 0 90)
			(layer "F.SilkS")
			(hide yes)
			(effects
				(font
					(size 1.27 1.27)
				)
			)
		)
		(property "Value" ""
			(at 0 0 90)
			(layer "F.Fab")
			(effects
				(font
					(size 1.27 1.27)
				)
			)
		)
		(duplicate_pad_numbers_are_jumpers no)
		(fp_line
			(start 0.7874 -0.4064)
			(end 0.7874 0.4064)
			(stroke
				(width 0.1524)
				(type default)
			)
			(layer "F.SilkS")
		)
		(fp_line
			(start -0.7874 -0.4064)
			(end 0.7874 -0.4064)
			(stroke
				(width 0.1524)
				(type default)
			)
			(layer "F.SilkS")
		)
		(fp_line
			(start 0.7874 0.4064)
			(end -0.7874 0.4064)
			(stroke
				(width 0.1524)
				(type default)
			)
			(layer "F.SilkS")
		)
		(fp_line
			(start -0.7874 0.4064)
			(end -0.7874 -0.4064)
			(stroke
				(width 0.1524)
				(type default)
			)
			(layer "F.SilkS")
		)
		(fp_line
			(start -0.12065 -0.305054)
			(end -0.12065 -0.2794)
			(stroke
				(width 0.1)
				(type default)
			)
			(layer "F.Fab")
		)
		(fp_line
			(start -0.67945 -0.305054)
			(end -0.12065 -0.305054)
			(stroke
				(width 0.1)
				(type default)
			)
			(layer "F.Fab")
		)
		(fp_line
			(start 0.67945 -0.3048)
			(end 0.67945 0.3048)
			(stroke
				(width 0.1)
				(type default)
			)
			(layer "F.Fab")
		)
		(fp_line
			(start 0.12065 -0.3048)
			(end 0.67945 -0.3048)
			(stroke
				(width 0.1)
				(type default)
			)
			(layer "F.Fab")
		)
		(fp_line
			(start 0.12065 -0.2794)
			(end 0.12065 -0.3048)
			(stroke
				(width 0.1)
				(type default)
			)
			(layer "F.Fab")
		)
		(fp_line
			(start -0.12065 -0.2794)
			(end 0.12065 -0.2794)
			(stroke
				(width 0.1)
				(type default)
			)
			(layer "F.Fab")
		)
		(fp_line
			(start 0.120396 0.2794)
			(end -0.12065 0.2794)
			(stroke
				(width 0.1)
				(type default)
			)
			(layer "F.Fab")
		)
		(fp_line
			(start -0.12065 0.2794)
			(end -0.12065 0.3048)
			(stroke
				(width 0.1)
				(type default)
			)
			(layer "F.Fab")
		)
		(fp_line
			(start 0.67945 0.3048)
			(end 0.120396 0.3048)
			(stroke
				(width 0.1)
				(type default)
			)
			(layer "F.Fab")
		)
		(fp_line
			(start 0.120396 0.3048)
			(end 0.120396 0.2794)
			(stroke
				(width 0.1)
				(type default)
			)
			(layer "F.Fab")
		)
		(fp_line
			(start -0.12065 0.3048)
			(end -0.67945 0.3048)
			(stroke
				(width 0.1)
				(type default)
			)
			(layer "F.Fab")
		)
		(fp_line
			(start -0.67945 0.3048)
			(end -0.67945 -0.305054)
			(stroke
				(width 0.1)
				(type default)
			)
			(layer "F.Fab")
		)
		(pad "1" smd circle
			(at -0.40005 0 90)
			(size 0 0)
			(layers "F.Cu" "F.Mask" "F.Paste")
			(net "FM_P2E_EQB0")
		)
		(pad "2" smd circle
			(at 0.40005 0 90)
			(size 0 0)
			(layers "F.Cu" "F.Mask" "F.Paste")
			(net "GND")
		)
	)
	(footprint ""
		(layer "F.Cu")
		(at 197.177406 -40.138604)
		(property "Reference" "R3996"
			(at 0 0 0)
			(layer "F.SilkS")
			(hide yes)
			(effects
				(font
					(size 1.27 1.27)
				)
			)
		)
		(property "Value" ""
			(at 0 0 0)
			(layer "F.Fab")
			(effects
				(font
					(size 1.27 1.27)
				)
			)
		)
		(duplicate_pad_numbers_are_jumpers no)
		(fp_line
			(start -0.7874 -0.4064)
			(end 0.7874 -0.4064)
			(stroke
				(width 0.1524)
				(type default)
			)
			(layer "F.SilkS")
		)
		(fp_line
			(start -0.7874 0.4064)
			(end -0.7874 -0.4064)
			(stroke
				(width 0.1524)
				(type default)
			)
			(layer "F.SilkS")
		)
		(fp_line
			(start 0.7874 -0.4064)
			(end 0.7874 0.4064)
			(stroke
				(width 0.1524)
				(type default)
			)
			(layer "F.SilkS")
		)
		(fp_line
			(start 0.7874 0.4064)
			(end -0.7874 0.4064)
			(stroke
				(width 0.1524)
				(type default)
			)
			(layer "F.SilkS")
		)
		(fp_line
			(start -0.67945 -0.305054)
			(end -0.12065 -0.305054)
			(stroke
				(width 0.1)
				(type default)
			)
			(layer "F.Fab")
		)
		(fp_line
			(start -0.67945 0.3048)
			(end -0.67945 -0.305054)
			(stroke
				(width 0.1)
				(type default)
			)
			(layer "F.Fab")
		)
		(fp_line
			(start -0.12065 -0.305054)
			(end -0.12065 -0.2794)
			(stroke
				(width 0.1)
				(type default)
			)
			(layer "F.Fab")
		)
		(fp_line
			(start -0.12065 -0.2794)
			(end 0.12065 -0.2794)
			(stroke
				(width 0.1)
				(type default)
			)
			(layer "F.Fab")
		)
		(fp_line
			(start -0.12065 0.2794)
			(end -0.12065 0.3048)
			(stroke
				(width 0.1)
				(type default)
			)
			(layer "F.Fab")
		)
		(fp_line
			(start -0.12065 0.3048)
			(end -0.67945 0.3048)
			(stroke
				(width 0.1)
				(type default)
			)
			(layer "F.Fab")
		)
		(fp_line
			(start 0.120396 0.2794)
			(end -0.12065 0.2794)
			(stroke
				(width 0.1)
				(type default)
			)
			(layer "F.Fab")
		)
		(fp_line
			(start 0.120396 0.3048)
			(end 0.120396 0.2794)
			(stroke
				(width 0.1)
				(type default)
			)
			(layer "F.Fab")
		)
		(fp_line
			(start 0.12065 -0.3048)
			(end 0.67945 -0.3048)
			(stroke
				(width 0.1)
				(type default)
			)
			(layer "F.Fab")
		)
		(fp_line
			(start 0.12065 -0.2794)
			(end 0.12065 -0.3048)
			(stroke
				(width 0.1)
				(type default)
			)
			(layer "F.Fab")
		)
		(fp_line
			(start 0.67945 -0.3048)
			(end 0.67945 0.3048)
			(stroke
				(width 0.1)
				(type default)
			)
			(layer "F.Fab")
		)
		(fp_line
			(start 0.67945 0.3048)
			(end 0.120396 0.3048)
			(stroke
				(width 0.1)
				(type default)
			)
			(layer "F.Fab")
		)
		(pad "1" smd circle
			(at -0.40005 0)
			(size 0 0)
			(layers "F.Cu" "F.Mask" "F.Paste")
			(net "VIRTUAL_RESEAT_FPGA_N")
		)
		(pad "2" smd circle
			(at 0.40005 0)
			(size 0 0)
			(layers "F.Cu" "F.Mask" "F.Paste")
			(net "P12V_SCM_EN")
		)
	)
	(footprint ""
		(layer "F.Cu")
		(at 439.262266 -123.664726 180)
		(property "Reference" "R1717"
			(at 0 0 180)
			(layer "F.SilkS")
			(hide yes)
			(effects
				(font
					(size 1.27 1.27)
				)
			)
		)
		(property "Value" ""
			(at 0 0 180)
			(layer "F.Fab")
			(effects
				(font
					(size 1.27 1.27)
				)
			)
		)
		(duplicate_pad_numbers_are_jumpers no)
		(fp_line
			(start 0.7874 0.4064)
			(end -0.7874 0.4064)
			(stroke
				(width 0.1524)
				(type default)
			)
			(layer "F.SilkS")
		)
		(fp_line
			(start 0.7874 -0.4064)
			(end 0.7874 0.4064)
			(stroke
				(width 0.1524)
				(type default)
			)
			(layer "F.SilkS")
		)
		(fp_line
			(start -0.7874 0.4064)
			(end -0.7874 -0.4064)
			(stroke
				(width 0.1524)
				(type default)
			)
			(layer "F.SilkS")
		)
		(fp_line
			(start -0.7874 -0.4064)
			(end 0.7874 -0.4064)
			(stroke
				(width 0.1524)
				(type default)
			)
			(layer "F.SilkS")
		)
		(fp_line
			(start 0.67945 0.3048)
			(end 0.120396 0.3048)
			(stroke
				(width 0.1)
				(type default)
			)
			(layer "F.Fab")
		)
		(fp_line
			(start 0.67945 -0.3048)
			(end 0.67945 0.3048)
			(stroke
				(width 0.1)
				(type default)
			)
			(layer "F.Fab")
		)
		(fp_line
			(start 0.12065 -0.2794)
			(end 0.12065 -0.3048)
			(stroke
				(width 0.1)
				(type default)
			)
			(layer "F.Fab")
		)
		(fp_line
			(start 0.12065 -0.3048)
			(end 0.67945 -0.3048)
			(stroke
				(width 0.1)
				(type default)
			)
			(layer "F.Fab")
		)
		(fp_line
			(start 0.120396 0.3048)
			(end 0.120396 0.2794)
			(stroke
				(width 0.1)
				(type default)
			)
			(layer "F.Fab")
		)
		(fp_line
			(start 0.120396 0.2794)
			(end -0.12065 0.2794)
			(stroke
				(width 0.1)
				(type default)
			)
			(layer "F.Fab")
		)
		(fp_line
			(start -0.12065 0.3048)
			(end -0.67945 0.3048)
			(stroke
				(width 0.1)
				(type default)
			)
			(layer "F.Fab")
		)
		(fp_line
			(start -0.12065 0.2794)
			(end -0.12065 0.3048)
			(stroke
				(width 0.1)
				(type default)
			)
			(layer "F.Fab")
		)
		(fp_line
			(start -0.12065 -0.2794)
			(end 0.12065 -0.2794)
			(stroke
				(width 0.1)
				(type default)
			)
			(layer "F.Fab")
		)
		(fp_line
			(start -0.12065 -0.305054)
			(end -0.12065 -0.2794)
			(stroke
				(width 0.1)
				(type default)
			)
			(layer "F.Fab")
		)
		(fp_line
			(start -0.67945 0.3048)
			(end -0.67945 -0.305054)
			(stroke
				(width 0.1)
				(type default)
			)
			(layer "F.Fab")
		)
		(fp_line
			(start -0.67945 -0.305054)
			(end -0.12065 -0.305054)
			(stroke
				(width 0.1)
				(type default)
			)
			(layer "F.Fab")
		)
		(pad "1" smd circle
			(at -0.40005 0 180)
			(size 0 0)
			(layers "F.Cu" "F.Mask" "F.Paste")
			(net "PVNN_TERM_CPU0")
		)
		(pad "2" smd circle
			(at 0.40005 0 180)
			(size 0 0)
			(layers "F.Cu" "F.Mask" "F.Paste")
			(net "SVID_CLK1_CPU0_R")
		)
	)
	(footprint ""
		(layer "F.Cu")
		(at 129.319274 -402.371052 -90)
		(property "Reference" "C749"
			(at 0 0 270)
			(layer "F.SilkS")
			(hide yes)
			(effects
				(font
					(size 1.27 1.27)
				)
			)
		)
		(property "Value" ""
			(at 0 0 270)
			(layer "F.Fab")
			(effects
				(font
					(size 1.27 1.27)
				)
			)
		)
		(duplicate_pad_numbers_are_jumpers no)
		(fp_line
			(start -0.299974 0.150114)
			(end -0.299974 -0.150114)
			(stroke
				(width 0.1)
				(type default)
			)
			(layer "F.Fab")
		)
		(fp_line
			(start 0.299974 0.150114)
			(end -0.299974 0.150114)
			(stroke
				(width 0.1)
				(type default)
			)
			(layer "F.Fab")
		)
		(fp_line
			(start -0.299974 -0.150114)
			(end 0.299974 -0.150114)
			(stroke
				(width 0.1)
				(type default)
			)
			(layer "F.Fab")
		)
		(fp_line
			(start 0.299974 -0.150114)
			(end 0.299974 0.150114)
			(stroke
				(width 0.1)
				(type default)
			)
			(layer "F.Fab")
		)
		(pad "1" smd rect
			(at -0.2667 0 270)
			(size 0.3048 0.381)
			(layers "F.Cu" "F.Mask" "F.Paste")
			(net "P5E_CPU1_PE2_TX_C_DP<12>")
		)
		(pad "2" smd rect
			(at 0.2667 0 270)
			(size 0.3048 0.381)
			(layers "F.Cu" "F.Mask" "F.Paste")
			(net "P5E_CPU1_PE2_TX_DP<12>")
		)
	)
	(footprint ""
		(layer "F.Cu")
		(at 334.587088 -402.371052 -90)
		(property "Reference" "C1558"
			(at 0 0 270)
			(layer "F.SilkS")
			(hide yes)
			(effects
				(font
					(size 1.27 1.27)
				)
			)
		)
		(property "Value" ""
			(at 0 0 270)
			(layer "F.Fab")
			(effects
				(font
					(size 1.27 1.27)
				)
			)
		)
		(duplicate_pad_numbers_are_jumpers no)
		(fp_line
			(start -0.299974 0.150114)
			(end -0.299974 -0.150114)
			(stroke
				(width 0.1)
				(type default)
			)
			(layer "F.Fab")
		)
		(fp_line
			(start 0.299974 0.150114)
			(end -0.299974 0.150114)
			(stroke
				(width 0.1)
				(type default)
			)
			(layer "F.Fab")
		)
		(fp_line
			(start -0.299974 -0.150114)
			(end 0.299974 -0.150114)
			(stroke
				(width 0.1)
				(type default)
			)
			(layer "F.Fab")
		)
		(fp_line
			(start 0.299974 -0.150114)
			(end 0.299974 0.150114)
			(stroke
				(width 0.1)
				(type default)
			)
			(layer "F.Fab")
		)
		(pad "1" smd rect
			(at -0.2667 0 270)
			(size 0.3048 0.381)
			(layers "F.Cu" "F.Mask" "F.Paste")
			(net "P5E_CPU0_PE4_TX_C_DN<10>")
		)
		(pad "2" smd rect
			(at 0.2667 0 270)
			(size 0.3048 0.381)
			(layers "F.Cu" "F.Mask" "F.Paste")
			(net "P5E_CPU0_PE4_TX_DN<10>")
		)
	)
	(footprint ""
		(layer "F.Cu")
		(at 39.394892 -397.42491 90)
		(property "Reference" "R4650"
			(at 0 0 90)
			(layer "F.SilkS")
			(hide yes)
			(effects
				(font
					(size 1.27 1.27)
				)
			)
		)
		(property "Value" ""
			(at 0 0 90)
			(layer "F.Fab")
			(effects
				(font
					(size 1.27 1.27)
				)
			)
		)
		(duplicate_pad_numbers_are_jumpers no)
		(fp_line
			(start 0.7874 -0.4064)
			(end 0.7874 0.4064)
			(stroke
				(width 0.1524)
				(type default)
			)
			(layer "F.SilkS")
		)
		(fp_line
			(start -0.7874 -0.4064)
			(end 0.7874 -0.4064)
			(stroke
				(width 0.1524)
				(type default)
			)
			(layer "F.SilkS")
		)
		(fp_line
			(start 0.7874 0.4064)
			(end -0.7874 0.4064)
			(stroke
				(width 0.1524)
				(type default)
			)
			(layer "F.SilkS")
		)
		(fp_line
			(start -0.7874 0.4064)
			(end -0.7874 -0.4064)
			(stroke
				(width 0.1524)
				(type default)
			)
			(layer "F.SilkS")
		)
		(fp_line
			(start -0.12065 -0.305054)
			(end -0.12065 -0.2794)
			(stroke
				(width 0.1)
				(type default)
			)
			(layer "F.Fab")
		)
		(fp_line
			(start -0.67945 -0.305054)
			(end -0.12065 -0.305054)
			(stroke
				(width 0.1)
				(type default)
			)
			(layer "F.Fab")
		)
		(fp_line
			(start 0.67945 -0.3048)
			(end 0.67945 0.3048)
			(stroke
				(width 0.1)
				(type default)
			)
			(layer "F.Fab")
		)
		(fp_line
			(start 0.12065 -0.3048)
			(end 0.67945 -0.3048)
			(stroke
				(width 0.1)
				(type default)
			)
			(layer "F.Fab")
		)
		(fp_line
			(start 0.12065 -0.2794)
			(end 0.12065 -0.3048)
			(stroke
				(width 0.1)
				(type default)
			)
			(layer "F.Fab")
		)
		(fp_line
			(start -0.12065 -0.2794)
			(end 0.12065 -0.2794)
			(stroke
				(width 0.1)
				(type default)
			)
			(layer "F.Fab")
		)
		(fp_line
			(start 0.120396 0.2794)
			(end -0.12065 0.2794)
			(stroke
				(width 0.1)
				(type default)
			)
			(layer "F.Fab")
		)
		(fp_line
			(start -0.12065 0.2794)
			(end -0.12065 0.3048)
			(stroke
				(width 0.1)
				(type default)
			)
			(layer "F.Fab")
		)
		(fp_line
			(start 0.67945 0.3048)
			(end 0.120396 0.3048)
			(stroke
				(width 0.1)
				(type default)
			)
			(layer "F.Fab")
		)
		(fp_line
			(start 0.120396 0.3048)
			(end 0.120396 0.2794)
			(stroke
				(width 0.1)
				(type default)
			)
			(layer "F.Fab")
		)
		(fp_line
			(start -0.12065 0.3048)
			(end -0.67945 0.3048)
			(stroke
				(width 0.1)
				(type default)
			)
			(layer "F.Fab")
		)
		(fp_line
			(start -0.67945 0.3048)
			(end -0.67945 -0.305054)
			(stroke
				(width 0.1)
				(type default)
			)
			(layer "F.Fab")
		)
		(pad "1" smd circle
			(at -0.40005 0 90)
			(size 0 0)
			(layers "F.Cu" "F.Mask" "F.Paste")
			(net "FM_P2E_BUF2_EQA0")
		)
		(pad "2" smd circle
			(at 0.40005 0 90)
			(size 0 0)
			(layers "F.Cu" "F.Mask" "F.Paste")
			(net "GND")
		)
	)
	(footprint ""
		(layer "F.Cu")
		(at 356.616 -414.111948 180)
		(property "Reference" "C2343"
			(at 0 0 180)
			(layer "F.SilkS")
			(hide yes)
			(effects
				(font
					(size 1.27 1.27)
				)
			)
		)
		(property "Value" ""
			(at 0 0 180)
			(layer "F.Fab")
			(effects
				(font
					(size 1.27 1.27)
				)
			)
		)
		(duplicate_pad_numbers_are_jumpers no)
		(fp_line
			(start 0.7874 0.4064)
			(end -0.7874 0.4064)
			(stroke
				(width 0.1524)
				(type default)
			)
			(layer "F.SilkS")
		)
		(fp_line
			(start 0.7874 -0.4064)
			(end 0.7874 0.4064)
			(stroke
				(width 0.1524)
				(type default)
			)
			(layer "F.SilkS")
		)
		(fp_line
			(start -0.7874 0.4064)
			(end -0.7874 -0.4064)
			(stroke
				(width 0.1524)
				(type default)
			)
			(layer "F.SilkS")
		)
		(fp_line
			(start -0.7874 -0.4064)
			(end 0.7874 -0.4064)
			(stroke
				(width 0.1524)
				(type default)
			)
			(layer "F.SilkS")
		)
		(fp_line
			(start 0.67945 0.3048)
			(end 0.120396 0.3048)
			(stroke
				(width 0.1)
				(type default)
			)
			(layer "F.Fab")
		)
		(fp_line
			(start 0.67945 -0.3048)
			(end 0.67945 0.3048)
			(stroke
				(width 0.1)
				(type default)
			)
			(layer "F.Fab")
		)
		(fp_line
			(start 0.12065 -0.2794)
			(end 0.12065 -0.3048)
			(stroke
				(width 0.1)
				(type default)
			)
			(layer "F.Fab")
		)
		(fp_line
			(start 0.12065 -0.3048)
			(end 0.67945 -0.3048)
			(stroke
				(width 0.1)
				(type default)
			)
			(layer "F.Fab")
		)
		(fp_line
			(start 0.120396 0.3048)
			(end 0.120396 0.2794)
			(stroke
				(width 0.1)
				(type default)
			)
			(layer "F.Fab")
		)
		(fp_line
			(start 0.120396 0.2794)
			(end -0.12065 0.2794)
			(stroke
				(width 0.1)
				(type default)
			)
			(layer "F.Fab")
		)
		(fp_line
			(start -0.12065 0.3048)
			(end -0.67945 0.3048)
			(stroke
				(width 0.1)
				(type default)
			)
			(layer "F.Fab")
		)
		(fp_line
			(start -0.12065 0.2794)
			(end -0.12065 0.3048)
			(stroke
				(width 0.1)
				(type default)
			)
			(layer "F.Fab")
		)
		(fp_line
			(start -0.12065 -0.2794)
			(end 0.12065 -0.2794)
			(stroke
				(width 0.1)
				(type default)
			)
			(layer "F.Fab")
		)
		(fp_line
			(start -0.12065 -0.305054)
			(end -0.12065 -0.2794)
			(stroke
				(width 0.1)
				(type default)
			)
			(layer "F.Fab")
		)
		(fp_line
			(start -0.67945 0.3048)
			(end -0.67945 -0.305054)
			(stroke
				(width 0.1)
				(type default)
			)
			(layer "F.Fab")
		)
		(fp_line
			(start -0.67945 -0.305054)
			(end -0.12065 -0.305054)
			(stroke
				(width 0.1)
				(type default)
			)
			(layer "F.Fab")
		)
		(pad "1" smd circle
			(at -0.40005 0 180)
			(size 0 0)
			(layers "F.Cu" "F.Mask" "F.Paste")
			(net "SWB_HSC_PWRGD_ISO")
		)
		(pad "2" smd circle
			(at 0.40005 0 180)
			(size 0 0)
			(layers "F.Cu" "F.Mask" "F.Paste")
			(net "GND")
		)
	)
	(footprint ""
		(layer "F.Cu")
		(at 368.75212 -103.866188 90)
		(property "Reference" "C1291"
			(at 0 0 90)
			(layer "F.SilkS")
			(hide yes)
			(effects
				(font
					(size 1.27 1.27)
				)
			)
		)
		(property "Value" ""
			(at 0 0 90)
			(layer "F.Fab")
			(effects
				(font
					(size 1.27 1.27)
				)
			)
		)
		(duplicate_pad_numbers_are_jumpers no)
		(fp_line
			(start 0.7874 -0.4064)
			(end 0.7874 0.4064)
			(stroke
				(width 0.1524)
				(type default)
			)
			(layer "F.SilkS")
		)
		(fp_line
			(start -0.7874 -0.4064)
			(end 0.7874 -0.4064)
			(stroke
				(width 0.1524)
				(type default)
			)
			(layer "F.SilkS")
		)
		(fp_line
			(start 0.7874 0.4064)
			(end -0.7874 0.4064)
			(stroke
				(width 0.1524)
				(type default)
			)
			(layer "F.SilkS")
		)
		(fp_line
			(start -0.7874 0.4064)
			(end -0.7874 -0.4064)
			(stroke
				(width 0.1524)
				(type default)
			)
			(layer "F.SilkS")
		)
		(fp_line
			(start -0.12065 -0.305054)
			(end -0.12065 -0.2794)
			(stroke
				(width 0.1)
				(type default)
			)
			(layer "F.Fab")
		)
		(fp_line
			(start -0.67945 -0.305054)
			(end -0.12065 -0.305054)
			(stroke
				(width 0.1)
				(type default)
			)
			(layer "F.Fab")
		)
		(fp_line
			(start 0.67945 -0.3048)
			(end 0.67945 0.3048)
			(stroke
				(width 0.1)
				(type default)
			)
			(layer "F.Fab")
		)
		(fp_line
			(start 0.12065 -0.3048)
			(end 0.67945 -0.3048)
			(stroke
				(width 0.1)
				(type default)
			)
			(layer "F.Fab")
		)
		(fp_line
			(start 0.12065 -0.2794)
			(end 0.12065 -0.3048)
			(stroke
				(width 0.1)
				(type default)
			)
			(layer "F.Fab")
		)
		(fp_line
			(start -0.12065 -0.2794)
			(end 0.12065 -0.2794)
			(stroke
				(width 0.1)
				(type default)
			)
			(layer "F.Fab")
		)
		(fp_line
			(start 0.120396 0.2794)
			(end -0.12065 0.2794)
			(stroke
				(width 0.1)
				(type default)
			)
			(layer "F.Fab")
		)
		(fp_line
			(start -0.12065 0.2794)
			(end -0.12065 0.3048)
			(stroke
				(width 0.1)
				(type default)
			)
			(layer "F.Fab")
		)
		(fp_line
			(start 0.67945 0.3048)
			(end 0.120396 0.3048)
			(stroke
				(width 0.1)
				(type default)
			)
			(layer "F.Fab")
		)
		(fp_line
			(start 0.120396 0.3048)
			(end 0.120396 0.2794)
			(stroke
				(width 0.1)
				(type default)
			)
			(layer "F.Fab")
		)
		(fp_line
			(start -0.12065 0.3048)
			(end -0.67945 0.3048)
			(stroke
				(width 0.1)
				(type default)
			)
			(layer "F.Fab")
		)
		(fp_line
			(start -0.67945 0.3048)
			(end -0.67945 -0.305054)
			(stroke
				(width 0.1)
				(type default)
			)
			(layer "F.Fab")
		)
		(pad "1" smd circle
			(at -0.40005 0 90)
			(size 0 0)
			(layers "F.Cu" "F.Mask" "F.Paste")
			(net "P3V3_AUX")
		)
		(pad "2" smd circle
			(at 0.40005 0 90)
			(size 0 0)
			(layers "F.Cu" "F.Mask" "F.Paste")
			(net "GND")
		)
	)
	(footprint ""
		(layer "F.Cu")
		(at 446.18783 -378.300234)
		(property "Reference" "C1170"
			(at 0 0 0)
			(layer "F.SilkS")
			(hide yes)
			(effects
				(font
					(size 1.27 1.27)
				)
			)
		)
		(property "Value" ""
			(at 0 0 0)
			(layer "F.Fab")
			(effects
				(font
					(size 1.27 1.27)
				)
			)
		)
		(duplicate_pad_numbers_are_jumpers no)
		(fp_line
			(start -1.524 -0.762)
			(end 1.524 -0.762)
			(stroke
				(width 0.1524)
				(type default)
			)
			(layer "F.SilkS")
		)
		(fp_line
			(start -1.524 0.762)
			(end -1.524 -0.762)
			(stroke
				(width 0.1524)
				(type default)
			)
			(layer "F.SilkS")
		)
		(fp_line
			(start 1.524 -0.762)
			(end 1.524 0.762)
			(stroke
				(width 0.1524)
				(type default)
			)
			(layer "F.SilkS")
		)
		(fp_line
			(start 1.524 0.762)
			(end -1.524 0.762)
			(stroke
				(width 0.1524)
				(type default)
			)
			(layer "F.SilkS")
		)
		(fp_line
			(start -1.1049 -0.724916)
			(end -1.1049 0.724916)
			(stroke
				(width 0.1)
				(type default)
			)
			(layer "F.Fab")
		)
		(fp_line
			(start -1.1049 0.724916)
			(end 1.1049 0.724916)
			(stroke
				(width 0.1)
				(type default)
			)
			(layer "F.Fab")
		)
		(fp_line
			(start 1.1049 -0.724916)
			(end -1.1049 -0.724916)
			(stroke
				(width 0.1)
				(type default)
			)
			(layer "F.Fab")
		)
		(fp_line
			(start 1.1049 0.724916)
			(end 1.1049 -0.724916)
			(stroke
				(width 0.1)
				(type default)
			)
			(layer "F.Fab")
		)
		(pad "1" smd rect
			(at -0.889 0 180)
			(size 1.016 1.27)
			(layers "F.Cu" "F.Mask" "F.Paste")
			(net "P5V_AUX")
		)
		(pad "2" smd rect
			(at 0.889 0 180)
			(size 1.016 1.27)
			(layers "F.Cu" "F.Mask" "F.Paste")
			(net "GND")
		)
	)
	(footprint ""
		(layer "F.Cu")
		(at 298.472352 -354.000816 -90)
		(property "Reference" "PL34"
			(at -2.045462 -5.057648 0)
			(unlocked yes)
			(layer "F.SilkS")
			(effects
				(font
					(size 0.7874 0.5842)
					(thickness 0.1524)
				)
				(justify left)
			)
		)
		(property "Value" ""
			(at 0 0 270)
			(layer "F.Fab")
			(effects
				(font
					(size 1.27 1.27)
				)
			)
		)
		(duplicate_pad_numbers_are_jumpers no)
		(fp_line
			(start -4.99999 3.750056)
			(end -4.99999 2.2479)
			(stroke
				(width 0.1524)
				(type default)
			)
			(layer "F.SilkS")
		)
		(fp_line
			(start 0 3.750056)
			(end -4.99999 3.750056)
			(stroke
				(width 0.1524)
				(type default)
			)
			(layer "F.SilkS")
		)
		(fp_line
			(start 4.99999 3.750056)
			(end 0 3.750056)
			(stroke
				(width 0.1524)
				(type default)
			)
			(layer "F.SilkS")
		)
		(fp_line
			(start 4.99999 2.2352)
			(end 4.99999 3.750056)
			(stroke
				(width 0.1524)
				(type default)
			)
			(layer "F.SilkS")
		)
		(fp_line
			(start -4.99999 -2.2479)
			(end -4.99999 -3.750056)
			(stroke
				(width 0.1524)
				(type default)
			)
			(layer "F.SilkS")
		)
		(fp_line
			(start -4.99999 -3.750056)
			(end 4.99999 -3.750056)
			(stroke
				(width 0.1524)
				(type default)
			)
			(layer "F.SilkS")
		)
		(fp_line
			(start 4.99999 -3.750056)
			(end 4.99999 -2.2479)
			(stroke
				(width 0.1524)
				(type default)
			)
			(layer "F.SilkS")
		)
		(fp_line
			(start -4.99999 3.750056)
			(end -4.99999 -3.750056)
			(stroke
				(width 0.1)
				(type default)
			)
			(layer "F.Fab")
		)
		(fp_line
			(start 0 3.750056)
			(end -4.99999 3.750056)
			(stroke
				(width 0.1)
				(type default)
			)
			(layer "F.Fab")
		)
		(fp_line
			(start 4.99999 3.750056)
			(end 0 3.750056)
			(stroke
				(width 0.1)
				(type default)
			)
			(layer "F.Fab")
		)
		(fp_line
			(start -4.99999 -3.750056)
			(end 4.99999 -3.750056)
			(stroke
				(width 0.1)
				(type default)
			)
			(layer "F.Fab")
		)
		(fp_line
			(start 4.99999 -3.750056)
			(end 4.99999 3.750056)
			(stroke
				(width 0.1)
				(type default)
			)
			(layer "F.Fab")
		)
		(pad "1" smd rect
			(at -3.299968 0 270)
			(size 3.302 4.2164)
			(layers "F.Cu" "F.Mask" "F.Paste")
			(net "SW_PVCCFA_EHV_FIVRA_CPU0_SW2")
		)
		(pad "2" smd rect
			(at 3.299968 0 270)
			(size 3.302 4.2164)
			(layers "F.Cu" "F.Mask" "F.Paste")
			(net "PVCCFA_EHV_FIVRA_CPU0")
		)
	)
	(footprint ""
		(layer "F.Cu")
		(at 353.235514 -256.654046 -90)
		(property "Reference" "C422"
			(at 0 0 270)
			(layer "F.SilkS")
			(hide yes)
			(effects
				(font
					(size 1.27 1.27)
				)
			)
		)
		(property "Value" ""
			(at 0 0 270)
			(layer "F.Fab")
			(effects
				(font
					(size 1.27 1.27)
				)
			)
		)
		(duplicate_pad_numbers_are_jumpers no)
		(fp_line
			(start -0.7874 0.4064)
			(end -0.7874 -0.4064)
			(stroke
				(width 0.1524)
				(type default)
			)
			(layer "F.SilkS")
		)
		(fp_line
			(start 0.7874 0.4064)
			(end -0.7874 0.4064)
			(stroke
				(width 0.1524)
				(type default)
			)
			(layer "F.SilkS")
		)
		(fp_line
			(start -0.7874 -0.4064)
			(end 0.7874 -0.4064)
			(stroke
				(width 0.1524)
				(type default)
			)
			(layer "F.SilkS")
		)
		(fp_line
			(start 0.7874 -0.4064)
			(end 0.7874 0.4064)
			(stroke
				(width 0.1524)
				(type default)
			)
			(layer "F.SilkS")
		)
		(fp_line
			(start -0.67945 0.3048)
			(end -0.67945 -0.305054)
			(stroke
				(width 0.1)
				(type default)
			)
			(layer "F.Fab")
		)
		(fp_line
			(start -0.12065 0.3048)
			(end -0.67945 0.3048)
			(stroke
				(width 0.1)
				(type default)
			)
			(layer "F.Fab")
		)
		(fp_line
			(start 0.120396 0.3048)
			(end 0.120396 0.2794)
			(stroke
				(width 0.1)
				(type default)
			)
			(layer "F.Fab")
		)
		(fp_line
			(start 0.67945 0.3048)
			(end 0.120396 0.3048)
			(stroke
				(width 0.1)
				(type default)
			)
			(layer "F.Fab")
		)
		(fp_line
			(start -0.12065 0.2794)
			(end -0.12065 0.3048)
			(stroke
				(width 0.1)
				(type default)
			)
			(layer "F.Fab")
		)
		(fp_line
			(start 0.120396 0.2794)
			(end -0.12065 0.2794)
			(stroke
				(width 0.1)
				(type default)
			)
			(layer "F.Fab")
		)
		(fp_line
			(start -0.12065 -0.2794)
			(end 0.12065 -0.2794)
			(stroke
				(width 0.1)
				(type default)
			)
			(layer "F.Fab")
		)
		(fp_line
			(start 0.12065 -0.2794)
			(end 0.12065 -0.3048)
			(stroke
				(width 0.1)
				(type default)
			)
			(layer "F.Fab")
		)
		(fp_line
			(start 0.12065 -0.3048)
			(end 0.67945 -0.3048)
			(stroke
				(width 0.1)
				(type default)
			)
			(layer "F.Fab")
		)
		(fp_line
			(start 0.67945 -0.3048)
			(end 0.67945 0.3048)
			(stroke
				(width 0.1)
				(type default)
			)
			(layer "F.Fab")
		)
		(fp_line
			(start -0.67945 -0.305054)
			(end -0.12065 -0.305054)
			(stroke
				(width 0.1)
				(type default)
			)
			(layer "F.Fab")
		)
		(fp_line
			(start -0.12065 -0.305054)
			(end -0.12065 -0.2794)
			(stroke
				(width 0.1)
				(type default)
			)
			(layer "F.Fab")
		)
		(pad "1" smd circle
			(at -0.40005 0 270)
			(size 0 0)
			(layers "F.Cu" "F.Mask" "F.Paste")
			(net "PVCCFA_EHV_CPU0")
		)
		(pad "2" smd circle
			(at 0.40005 0 270)
			(size 0 0)
			(layers "F.Cu" "F.Mask" "F.Paste")
			(net "GND")
		)
	)
	(footprint ""
		(layer "F.Cu")
		(at 312.448194 -32.869886 180)
		(property "Reference" "R1454"
			(at 0 0 180)
			(layer "F.SilkS")
			(hide yes)
			(effects
				(font
					(size 1.27 1.27)
				)
			)
		)
		(property "Value" ""
			(at 0 0 180)
			(layer "F.Fab")
			(effects
				(font
					(size 1.27 1.27)
				)
			)
		)
		(duplicate_pad_numbers_are_jumpers no)
		(fp_line
			(start 0.7874 0.4064)
			(end -0.7874 0.4064)
			(stroke
				(width 0.1524)
				(type default)
			)
			(layer "F.SilkS")
		)
		(fp_line
			(start 0.7874 -0.4064)
			(end 0.7874 0.4064)
			(stroke
				(width 0.1524)
				(type default)
			)
			(layer "F.SilkS")
		)
		(fp_line
			(start -0.7874 0.4064)
			(end -0.7874 -0.4064)
			(stroke
				(width 0.1524)
				(type default)
			)
			(layer "F.SilkS")
		)
		(fp_line
			(start -0.7874 -0.4064)
			(end 0.7874 -0.4064)
			(stroke
				(width 0.1524)
				(type default)
			)
			(layer "F.SilkS")
		)
		(fp_line
			(start 0.67945 0.3048)
			(end 0.120396 0.3048)
			(stroke
				(width 0.1)
				(type default)
			)
			(layer "F.Fab")
		)
		(fp_line
			(start 0.67945 -0.3048)
			(end 0.67945 0.3048)
			(stroke
				(width 0.1)
				(type default)
			)
			(layer "F.Fab")
		)
		(fp_line
			(start 0.12065 -0.2794)
			(end 0.12065 -0.3048)
			(stroke
				(width 0.1)
				(type default)
			)
			(layer "F.Fab")
		)
		(fp_line
			(start 0.12065 -0.3048)
			(end 0.67945 -0.3048)
			(stroke
				(width 0.1)
				(type default)
			)
			(layer "F.Fab")
		)
		(fp_line
			(start 0.120396 0.3048)
			(end 0.120396 0.2794)
			(stroke
				(width 0.1)
				(type default)
			)
			(layer "F.Fab")
		)
		(fp_line
			(start 0.120396 0.2794)
			(end -0.12065 0.2794)
			(stroke
				(width 0.1)
				(type default)
			)
			(layer "F.Fab")
		)
		(fp_line
			(start -0.12065 0.3048)
			(end -0.67945 0.3048)
			(stroke
				(width 0.1)
				(type default)
			)
			(layer "F.Fab")
		)
		(fp_line
			(start -0.12065 0.2794)
			(end -0.12065 0.3048)
			(stroke
				(width 0.1)
				(type default)
			)
			(layer "F.Fab")
		)
		(fp_line
			(start -0.12065 -0.2794)
			(end 0.12065 -0.2794)
			(stroke
				(width 0.1)
				(type default)
			)
			(layer "F.Fab")
		)
		(fp_line
			(start -0.12065 -0.305054)
			(end -0.12065 -0.2794)
			(stroke
				(width 0.1)
				(type default)
			)
			(layer "F.Fab")
		)
		(fp_line
			(start -0.67945 0.3048)
			(end -0.67945 -0.305054)
			(stroke
				(width 0.1)
				(type default)
			)
			(layer "F.Fab")
		)
		(fp_line
			(start -0.67945 -0.305054)
			(end -0.12065 -0.305054)
			(stroke
				(width 0.1)
				(type default)
			)
			(layer "F.Fab")
		)
		(pad "1" smd circle
			(at -0.40005 0 180)
			(size 0 0)
			(layers "F.Cu" "F.Mask" "F.Paste")
			(net "PU_SMB_SML4_3V3AUX_PCH_SDA")
		)
		(pad "2" smd circle
			(at 0.40005 0 180)
			(size 0 0)
			(layers "F.Cu" "F.Mask" "F.Paste")
			(net "P3V3_AUX")
		)
	)
	(footprint ""
		(layer "F.Cu")
		(at 27.046428 -102.888034 180)
		(property "Reference" "C1767"
			(at 0 0 180)
			(layer "F.SilkS")
			(hide yes)
			(effects
				(font
					(size 1.27 1.27)
				)
			)
		)
		(property "Value" ""
			(at 0 0 180)
			(layer "F.Fab")
			(effects
				(font
					(size 1.27 1.27)
				)
			)
		)
		(duplicate_pad_numbers_are_jumpers no)
		(fp_line
			(start 1.524 0.762)
			(end -1.524 0.762)
			(stroke
				(width 0.1524)
				(type default)
			)
			(layer "F.SilkS")
		)
		(fp_line
			(start 1.524 -0.762)
			(end 1.524 0.762)
			(stroke
				(width 0.1524)
				(type default)
			)
			(layer "F.SilkS")
		)
		(fp_line
			(start -1.524 0.762)
			(end -1.524 -0.762)
			(stroke
				(width 0.1524)
				(type default)
			)
			(layer "F.SilkS")
		)
		(fp_line
			(start -1.524 -0.762)
			(end 1.524 -0.762)
			(stroke
				(width 0.1524)
				(type default)
			)
			(layer "F.SilkS")
		)
		(fp_line
			(start 1.1049 0.724916)
			(end 1.1049 -0.724916)
			(stroke
				(width 0.1)
				(type default)
			)
			(layer "F.Fab")
		)
		(fp_line
			(start 1.1049 -0.724916)
			(end -1.1049 -0.724916)
			(stroke
				(width 0.1)
				(type default)
			)
			(layer "F.Fab")
		)
		(fp_line
			(start -1.1049 0.724916)
			(end 1.1049 0.724916)
			(stroke
				(width 0.1)
				(type default)
			)
			(layer "F.Fab")
		)
		(fp_line
			(start -1.1049 -0.724916)
			(end -1.1049 0.724916)
			(stroke
				(width 0.1)
				(type default)
			)
			(layer "F.Fab")
		)
		(pad "1" smd rect
			(at -0.889 0)
			(size 1.016 1.27)
			(layers "F.Cu" "F.Mask" "F.Paste")
			(net "MAX11617_VREF")
		)
		(pad "2" smd rect
			(at 0.889 0)
			(size 1.016 1.27)
			(layers "F.Cu" "F.Mask" "F.Paste")
			(net "GND")
		)
	)
	(footprint ""
		(layer "F.Cu")
		(at 422.02354 -52.16652)
		(property "Reference" "U330"
			(at -1.905 -2.174748 0)
			(unlocked yes)
			(layer "F.SilkS")
			(effects
				(font
					(size 0.7874 0.5842)
					(thickness 0.1524)
				)
				(justify left)
			)
		)
		(property "Value" ""
			(at 0 0 0)
			(layer "F.Fab")
			(effects
				(font
					(size 1.27 1.27)
				)
			)
		)
		(duplicate_pad_numbers_are_jumpers no)
		(fp_line
			(start -1.759712 -1.500124)
			(end 1.759712 -1.500124)
			(stroke
				(width 0.1524)
				(type default)
			)
			(layer "F.SilkS")
		)
		(fp_line
			(start -1.759712 1.500124)
			(end -1.759712 -1.500124)
			(stroke
				(width 0.1524)
				(type default)
			)
			(layer "F.SilkS")
		)
		(fp_line
			(start 1.759712 -1.500124)
			(end 1.759712 1.500124)
			(stroke
				(width 0.1524)
				(type default)
			)
			(layer "F.SilkS")
		)
		(fp_line
			(start 1.759712 1.500124)
			(end -1.759712 1.500124)
			(stroke
				(width 0.1524)
				(type default)
			)
			(layer "F.SilkS")
		)
		(fp_line
			(start -0.700024 -1.500124)
			(end 0.700024 -1.500124)
			(stroke
				(width 0.1)
				(type default)
			)
			(layer "F.Fab")
		)
		(fp_line
			(start -0.700024 1.500124)
			(end -0.700024 -1.500124)
			(stroke
				(width 0.1)
				(type default)
			)
			(layer "F.Fab")
		)
		(fp_line
			(start 0.700024 -1.500124)
			(end 0.700024 1.500124)
			(stroke
				(width 0.1)
				(type default)
			)
			(layer "F.Fab")
		)
		(fp_line
			(start 0.700024 1.500124)
			(end -0.700024 1.500124)
			(stroke
				(width 0.1)
				(type default)
			)
			(layer "F.Fab")
		)
		(pad "1" smd rect
			(at -1.150112 -0.94996 270)
			(size 0.6604 0.9652)
			(layers "F.Cu" "F.Mask" "F.Paste")
			(net "GND")
		)
		(pad "2" smd rect
			(at -1.150112 0.94996 270)
			(size 0.6604 0.9652)
			(layers "F.Cu" "F.Mask" "F.Paste")
			(net "PWRGD_P3V3_R1")
		)
		(pad "3" smd rect
			(at 1.150112 0 270)
			(size 0.6604 0.9652)
			(layers "F.Cu" "F.Mask" "F.Paste")
			(net "P3V3")
		)
	)
	(footprint ""
		(layer "F.Cu")
		(at 120.37822 -418.399468 180)
		(property "Reference" "R3317"
			(at 0 0 180)
			(layer "F.SilkS")
			(hide yes)
			(effects
				(font
					(size 1.27 1.27)
				)
			)
		)
		(property "Value" ""
			(at 0 0 180)
			(layer "F.Fab")
			(effects
				(font
					(size 1.27 1.27)
				)
			)
		)
		(duplicate_pad_numbers_are_jumpers no)
		(fp_line
			(start 0.7874 0.4064)
			(end -0.7874 0.4064)
			(stroke
				(width 0.1524)
				(type default)
			)
			(layer "F.SilkS")
		)
		(fp_line
			(start 0.7874 -0.4064)
			(end 0.7874 0.4064)
			(stroke
				(width 0.1524)
				(type default)
			)
			(layer "F.SilkS")
		)
		(fp_line
			(start -0.7874 0.4064)
			(end -0.7874 -0.4064)
			(stroke
				(width 0.1524)
				(type default)
			)
			(layer "F.SilkS")
		)
		(fp_line
			(start -0.7874 -0.4064)
			(end 0.7874 -0.4064)
			(stroke
				(width 0.1524)
				(type default)
			)
			(layer "F.SilkS")
		)
		(fp_line
			(start 0.67945 0.3048)
			(end 0.120396 0.3048)
			(stroke
				(width 0.1)
				(type default)
			)
			(layer "F.Fab")
		)
		(fp_line
			(start 0.67945 -0.3048)
			(end 0.67945 0.3048)
			(stroke
				(width 0.1)
				(type default)
			)
			(layer "F.Fab")
		)
		(fp_line
			(start 0.12065 -0.2794)
			(end 0.12065 -0.3048)
			(stroke
				(width 0.1)
				(type default)
			)
			(layer "F.Fab")
		)
		(fp_line
			(start 0.12065 -0.3048)
			(end 0.67945 -0.3048)
			(stroke
				(width 0.1)
				(type default)
			)
			(layer "F.Fab")
		)
		(fp_line
			(start 0.120396 0.3048)
			(end 0.120396 0.2794)
			(stroke
				(width 0.1)
				(type default)
			)
			(layer "F.Fab")
		)
		(fp_line
			(start 0.120396 0.2794)
			(end -0.12065 0.2794)
			(stroke
				(width 0.1)
				(type default)
			)
			(layer "F.Fab")
		)
		(fp_line
			(start -0.12065 0.3048)
			(end -0.67945 0.3048)
			(stroke
				(width 0.1)
				(type default)
			)
			(layer "F.Fab")
		)
		(fp_line
			(start -0.12065 0.2794)
			(end -0.12065 0.3048)
			(stroke
				(width 0.1)
				(type default)
			)
			(layer "F.Fab")
		)
		(fp_line
			(start -0.12065 -0.2794)
			(end 0.12065 -0.2794)
			(stroke
				(width 0.1)
				(type default)
			)
			(layer "F.Fab")
		)
		(fp_line
			(start -0.12065 -0.305054)
			(end -0.12065 -0.2794)
			(stroke
				(width 0.1)
				(type default)
			)
			(layer "F.Fab")
		)
		(fp_line
			(start -0.67945 0.3048)
			(end -0.67945 -0.305054)
			(stroke
				(width 0.1)
				(type default)
			)
			(layer "F.Fab")
		)
		(fp_line
			(start -0.67945 -0.305054)
			(end -0.12065 -0.305054)
			(stroke
				(width 0.1)
				(type default)
			)
			(layer "F.Fab")
		)
		(pad "1" smd circle
			(at -0.40005 0 180)
			(size 0 0)
			(layers "F.Cu" "F.Mask" "F.Paste")
			(net "P3V3_AUX")
		)
		(pad "2" smd circle
			(at 0.40005 0 180)
			(size 0 0)
			(layers "F.Cu" "F.Mask" "F.Paste")
			(net "GPU_FPGA_RST_R1_BUF_N")
		)
	)
	(footprint ""
		(layer "F.Cu")
		(at 243.03863 -123.004834)
		(property "Reference" "R3201"
			(at 0 0 0)
			(layer "F.SilkS")
			(hide yes)
			(effects
				(font
					(size 1.27 1.27)
				)
			)
		)
		(property "Value" ""
			(at 0 0 0)
			(layer "F.Fab")
			(effects
				(font
					(size 1.27 1.27)
				)
			)
		)
		(duplicate_pad_numbers_are_jumpers no)
		(fp_line
			(start -0.7874 -0.4064)
			(end 0.7874 -0.4064)
			(stroke
				(width 0.1524)
				(type default)
			)
			(layer "F.SilkS")
		)
		(fp_line
			(start -0.7874 0.063754)
			(end -0.7874 -0.4064)
			(stroke
				(width 0.1524)
				(type default)
			)
			(layer "F.SilkS")
		)
		(fp_line
			(start 0.46863 0.4064)
			(end -0.45847 0.4064)
			(stroke
				(width 0.1524)
				(type default)
			)
			(layer "F.SilkS")
		)
		(fp_line
			(start 0.7874 -0.4064)
			(end 0.7874 0.053594)
			(stroke
				(width 0.1524)
				(type default)
			)
			(layer "F.SilkS")
		)
		(fp_line
			(start -0.67945 -0.305054)
			(end -0.12065 -0.305054)
			(stroke
				(width 0.1)
				(type default)
			)
			(layer "F.Fab")
		)
		(fp_line
			(start -0.67945 0.3048)
			(end -0.67945 -0.305054)
			(stroke
				(width 0.1)
				(type default)
			)
			(layer "F.Fab")
		)
		(fp_line
			(start -0.12065 -0.305054)
			(end -0.12065 -0.2794)
			(stroke
				(width 0.1)
				(type default)
			)
			(layer "F.Fab")
		)
		(fp_line
			(start -0.12065 -0.2794)
			(end 0.12065 -0.2794)
			(stroke
				(width 0.1)
				(type default)
			)
			(layer "F.Fab")
		)
		(fp_line
			(start -0.12065 0.2794)
			(end -0.12065 0.3048)
			(stroke
				(width 0.1)
				(type default)
			)
			(layer "F.Fab")
		)
		(fp_line
			(start -0.12065 0.3048)
			(end -0.67945 0.3048)
			(stroke
				(width 0.1)
				(type default)
			)
			(layer "F.Fab")
		)
		(fp_line
			(start 0.120396 0.2794)
			(end -0.12065 0.2794)
			(stroke
				(width 0.1)
				(type default)
			)
			(layer "F.Fab")
		)
		(fp_line
			(start 0.120396 0.3048)
			(end 0.120396 0.2794)
			(stroke
				(width 0.1)
				(type default)
			)
			(layer "F.Fab")
		)
		(fp_line
			(start 0.12065 -0.3048)
			(end 0.67945 -0.3048)
			(stroke
				(width 0.1)
				(type default)
			)
			(layer "F.Fab")
		)
		(fp_line
			(start 0.12065 -0.2794)
			(end 0.12065 -0.3048)
			(stroke
				(width 0.1)
				(type default)
			)
			(layer "F.Fab")
		)
		(fp_line
			(start 0.67945 -0.3048)
			(end 0.67945 0.3048)
			(stroke
				(width 0.1)
				(type default)
			)
			(layer "F.Fab")
		)
		(fp_line
			(start 0.67945 0.3048)
			(end 0.120396 0.3048)
			(stroke
				(width 0.1)
				(type default)
			)
			(layer "F.Fab")
		)
		(pad "1" smd circle
			(at -0.40005 0)
			(size 0 0)
			(layers "F.Cu" "F.Mask" "F.Paste")
			(net "CLK_100M_OCP_V3_2_D_R_DN")
		)
		(pad "2" smd circle
			(at 0.40005 0)
			(size 0 0)
			(layers "F.Cu" "F.Mask" "F.Paste")
			(net "CLK_100M_OCP_V3_2_D_DN")
		)
	)
	(footprint ""
		(layer "F.Cu")
		(at 22.935438 -423.64152 -90)
		(property "Reference" "R3066"
			(at 0 0 270)
			(layer "F.SilkS")
			(hide yes)
			(effects
				(font
					(size 1.27 1.27)
				)
			)
		)
		(property "Value" ""
			(at 0 0 270)
			(layer "F.Fab")
			(effects
				(font
					(size 1.27 1.27)
				)
			)
		)
		(duplicate_pad_numbers_are_jumpers no)
		(fp_line
			(start -0.7874 0.4064)
			(end -0.7874 -0.4064)
			(stroke
				(width 0.1524)
				(type default)
			)
			(layer "F.SilkS")
		)
		(fp_line
			(start 0.7874 0.4064)
			(end -0.7874 0.4064)
			(stroke
				(width 0.1524)
				(type default)
			)
			(layer "F.SilkS")
		)
		(fp_line
			(start -0.7874 -0.4064)
			(end 0.7874 -0.4064)
			(stroke
				(width 0.1524)
				(type default)
			)
			(layer "F.SilkS")
		)
		(fp_line
			(start 0.7874 -0.4064)
			(end 0.7874 0.4064)
			(stroke
				(width 0.1524)
				(type default)
			)
			(layer "F.SilkS")
		)
		(fp_line
			(start -0.67945 0.3048)
			(end -0.67945 -0.305054)
			(stroke
				(width 0.1)
				(type default)
			)
			(layer "F.Fab")
		)
		(fp_line
			(start -0.12065 0.3048)
			(end -0.67945 0.3048)
			(stroke
				(width 0.1)
				(type default)
			)
			(layer "F.Fab")
		)
		(fp_line
			(start 0.120396 0.3048)
			(end 0.120396 0.2794)
			(stroke
				(width 0.1)
				(type default)
			)
			(layer "F.Fab")
		)
		(fp_line
			(start 0.67945 0.3048)
			(end 0.120396 0.3048)
			(stroke
				(width 0.1)
				(type default)
			)
			(layer "F.Fab")
		)
		(fp_line
			(start -0.12065 0.2794)
			(end -0.12065 0.3048)
			(stroke
				(width 0.1)
				(type default)
			)
			(layer "F.Fab")
		)
		(fp_line
			(start 0.120396 0.2794)
			(end -0.12065 0.2794)
			(stroke
				(width 0.1)
				(type default)
			)
			(layer "F.Fab")
		)
		(fp_line
			(start -0.12065 -0.2794)
			(end 0.12065 -0.2794)
			(stroke
				(width 0.1)
				(type default)
			)
			(layer "F.Fab")
		)
		(fp_line
			(start 0.12065 -0.2794)
			(end 0.12065 -0.3048)
			(stroke
				(width 0.1)
				(type default)
			)
			(layer "F.Fab")
		)
		(fp_line
			(start 0.12065 -0.3048)
			(end 0.67945 -0.3048)
			(stroke
				(width 0.1)
				(type default)
			)
			(layer "F.Fab")
		)
		(fp_line
			(start 0.67945 -0.3048)
			(end 0.67945 0.3048)
			(stroke
				(width 0.1)
				(type default)
			)
			(layer "F.Fab")
		)
		(fp_line
			(start -0.67945 -0.305054)
			(end -0.12065 -0.305054)
			(stroke
				(width 0.1)
				(type default)
			)
			(layer "F.Fab")
		)
		(fp_line
			(start -0.12065 -0.305054)
			(end -0.12065 -0.2794)
			(stroke
				(width 0.1)
				(type default)
			)
			(layer "F.Fab")
		)
		(pad "1" smd circle
			(at -0.40005 0 270)
			(size 0 0)
			(layers "F.Cu" "F.Mask" "F.Paste")
			(net "FM_SMB_1_ALERT_GPU_ISO_N")
		)
		(pad "2" smd circle
			(at 0.40005 0 270)
			(size 0 0)
			(layers "F.Cu" "F.Mask" "F.Paste")
			(net "FM_SMB_1_ALERT_GPU_ISO_R_N")
		)
	)
	(footprint ""
		(layer "F.Cu")
		(at 71.657718 -408.517344 -90)
		(property "Reference" "C695"
			(at 0 0 270)
			(layer "F.SilkS")
			(hide yes)
			(effects
				(font
					(size 1.27 1.27)
				)
			)
		)
		(property "Value" ""
			(at 0 0 270)
			(layer "F.Fab")
			(effects
				(font
					(size 1.27 1.27)
				)
			)
		)
		(duplicate_pad_numbers_are_jumpers no)
		(fp_line
			(start -0.299974 0.150114)
			(end -0.299974 -0.150114)
			(stroke
				(width 0.1)
				(type default)
			)
			(layer "F.Fab")
		)
		(fp_line
			(start 0.299974 0.150114)
			(end -0.299974 0.150114)
			(stroke
				(width 0.1)
				(type default)
			)
			(layer "F.Fab")
		)
		(fp_line
			(start -0.299974 -0.150114)
			(end 0.299974 -0.150114)
			(stroke
				(width 0.1)
				(type default)
			)
			(layer "F.Fab")
		)
		(fp_line
			(start 0.299974 -0.150114)
			(end 0.299974 0.150114)
			(stroke
				(width 0.1)
				(type default)
			)
			(layer "F.Fab")
		)
		(pad "1" smd rect
			(at -0.2667 0 270)
			(size 0.3048 0.381)
			(layers "F.Cu" "F.Mask" "F.Paste")
			(net "P5E_CPU1_PE4_TX_C_DP<7>")
		)
		(pad "2" smd rect
			(at 0.2667 0 270)
			(size 0.3048 0.381)
			(layers "F.Cu" "F.Mask" "F.Paste")
			(net "P5E_CPU1_PE4_TX_DP<7>")
		)
	)
	(footprint ""
		(layer "F.Cu")
		(at 201.00036 -112.994948 180)
		(property "Reference" "R4145"
			(at 0 0 180)
			(layer "F.SilkS")
			(hide yes)
			(effects
				(font
					(size 1.27 1.27)
				)
			)
		)
		(property "Value" ""
			(at 0 0 180)
			(layer "F.Fab")
			(effects
				(font
					(size 1.27 1.27)
				)
			)
		)
		(duplicate_pad_numbers_are_jumpers no)
		(fp_line
			(start 0.7874 0.4064)
			(end -0.7874 0.4064)
			(stroke
				(width 0.1524)
				(type default)
			)
			(layer "F.SilkS")
		)
		(fp_line
			(start 0.7874 -0.4064)
			(end 0.7874 0.4064)
			(stroke
				(width 0.1524)
				(type default)
			)
			(layer "F.SilkS")
		)
		(fp_line
			(start -0.7874 0.4064)
			(end -0.7874 -0.4064)
			(stroke
				(width 0.1524)
				(type default)
			)
			(layer "F.SilkS")
		)
		(fp_line
			(start -0.7874 -0.4064)
			(end 0.7874 -0.4064)
			(stroke
				(width 0.1524)
				(type default)
			)
			(layer "F.SilkS")
		)
		(fp_line
			(start 0.67945 0.3048)
			(end 0.120396 0.3048)
			(stroke
				(width 0.1)
				(type default)
			)
			(layer "F.Fab")
		)
		(fp_line
			(start 0.67945 -0.3048)
			(end 0.67945 0.3048)
			(stroke
				(width 0.1)
				(type default)
			)
			(layer "F.Fab")
		)
		(fp_line
			(start 0.12065 -0.2794)
			(end 0.12065 -0.3048)
			(stroke
				(width 0.1)
				(type default)
			)
			(layer "F.Fab")
		)
		(fp_line
			(start 0.12065 -0.3048)
			(end 0.67945 -0.3048)
			(stroke
				(width 0.1)
				(type default)
			)
			(layer "F.Fab")
		)
		(fp_line
			(start 0.120396 0.3048)
			(end 0.120396 0.2794)
			(stroke
				(width 0.1)
				(type default)
			)
			(layer "F.Fab")
		)
		(fp_line
			(start 0.120396 0.2794)
			(end -0.12065 0.2794)
			(stroke
				(width 0.1)
				(type default)
			)
			(layer "F.Fab")
		)
		(fp_line
			(start -0.12065 0.3048)
			(end -0.67945 0.3048)
			(stroke
				(width 0.1)
				(type default)
			)
			(layer "F.Fab")
		)
		(fp_line
			(start -0.12065 0.2794)
			(end -0.12065 0.3048)
			(stroke
				(width 0.1)
				(type default)
			)
			(layer "F.Fab")
		)
		(fp_line
			(start -0.12065 -0.2794)
			(end 0.12065 -0.2794)
			(stroke
				(width 0.1)
				(type default)
			)
			(layer "F.Fab")
		)
		(fp_line
			(start -0.12065 -0.305054)
			(end -0.12065 -0.2794)
			(stroke
				(width 0.1)
				(type default)
			)
			(layer "F.Fab")
		)
		(fp_line
			(start -0.67945 0.3048)
			(end -0.67945 -0.305054)
			(stroke
				(width 0.1)
				(type default)
			)
			(layer "F.Fab")
		)
		(fp_line
			(start -0.67945 -0.305054)
			(end -0.12065 -0.305054)
			(stroke
				(width 0.1)
				(type default)
			)
			(layer "F.Fab")
		)
		(pad "1" smd circle
			(at -0.40005 0 180)
			(size 0 0)
			(layers "F.Cu" "F.Mask" "F.Paste")
			(net "PRSNT_CABLE_GPU_B3_ISO_N")
		)
		(pad "2" smd circle
			(at 0.40005 0 180)
			(size 0 0)
			(layers "F.Cu" "F.Mask" "F.Paste")
			(net "PRSNT_CABLE_GPU_B3_ISO_R_N")
		)
	)
	(footprint ""
		(layer "F.Cu")
		(at 193.004186 -429.41113 90)
		(property "Reference" "R2946"
			(at 0 0 90)
			(layer "F.SilkS")
			(hide yes)
			(effects
				(font
					(size 1.27 1.27)
				)
			)
		)
		(property "Value" ""
			(at 0 0 90)
			(layer "F.Fab")
			(effects
				(font
					(size 1.27 1.27)
				)
			)
		)
		(duplicate_pad_numbers_are_jumpers no)
		(fp_line
			(start 0.7874 -0.4064)
			(end 0.7874 0.4064)
			(stroke
				(width 0.1524)
				(type default)
			)
			(layer "F.SilkS")
		)
		(fp_line
			(start -0.7874 -0.4064)
			(end 0.7874 -0.4064)
			(stroke
				(width 0.1524)
				(type default)
			)
			(layer "F.SilkS")
		)
		(fp_line
			(start 0.7874 0.4064)
			(end -0.7874 0.4064)
			(stroke
				(width 0.1524)
				(type default)
			)
			(layer "F.SilkS")
		)
		(fp_line
			(start -0.7874 0.4064)
			(end -0.7874 -0.4064)
			(stroke
				(width 0.1524)
				(type default)
			)
			(layer "F.SilkS")
		)
		(fp_line
			(start -0.12065 -0.305054)
			(end -0.12065 -0.2794)
			(stroke
				(width 0.1)
				(type default)
			)
			(layer "F.Fab")
		)
		(fp_line
			(start -0.67945 -0.305054)
			(end -0.12065 -0.305054)
			(stroke
				(width 0.1)
				(type default)
			)
			(layer "F.Fab")
		)
		(fp_line
			(start 0.67945 -0.3048)
			(end 0.67945 0.3048)
			(stroke
				(width 0.1)
				(type default)
			)
			(layer "F.Fab")
		)
		(fp_line
			(start 0.12065 -0.3048)
			(end 0.67945 -0.3048)
			(stroke
				(width 0.1)
				(type default)
			)
			(layer "F.Fab")
		)
		(fp_line
			(start 0.12065 -0.2794)
			(end 0.12065 -0.3048)
			(stroke
				(width 0.1)
				(type default)
			)
			(layer "F.Fab")
		)
		(fp_line
			(start -0.12065 -0.2794)
			(end 0.12065 -0.2794)
			(stroke
				(width 0.1)
				(type default)
			)
			(layer "F.Fab")
		)
		(fp_line
			(start 0.120396 0.2794)
			(end -0.12065 0.2794)
			(stroke
				(width 0.1)
				(type default)
			)
			(layer "F.Fab")
		)
		(fp_line
			(start -0.12065 0.2794)
			(end -0.12065 0.3048)
			(stroke
				(width 0.1)
				(type default)
			)
			(layer "F.Fab")
		)
		(fp_line
			(start 0.67945 0.3048)
			(end 0.120396 0.3048)
			(stroke
				(width 0.1)
				(type default)
			)
			(layer "F.Fab")
		)
		(fp_line
			(start 0.120396 0.3048)
			(end 0.120396 0.2794)
			(stroke
				(width 0.1)
				(type default)
			)
			(layer "F.Fab")
		)
		(fp_line
			(start -0.12065 0.3048)
			(end -0.67945 0.3048)
			(stroke
				(width 0.1)
				(type default)
			)
			(layer "F.Fab")
		)
		(fp_line
			(start -0.67945 0.3048)
			(end -0.67945 -0.305054)
			(stroke
				(width 0.1)
				(type default)
			)
			(layer "F.Fab")
		)
		(pad "1" smd circle
			(at -0.40005 0 90)
			(size 0 0)
			(layers "F.Cu" "F.Mask" "F.Paste")
			(net "P3V3_AUX")
		)
		(pad "2" smd circle
			(at 0.40005 0 90)
			(size 0 0)
			(layers "F.Cu" "F.Mask" "F.Paste")
			(net "FM_GPU_HSC_EN_BUF_R")
		)
	)
	(footprint ""
		(layer "F.Cu")
		(at 133.27888 -106.898948)
		(property "Reference" "R4410"
			(at 0 0 0)
			(layer "F.SilkS")
			(hide yes)
			(effects
				(font
					(size 1.27 1.27)
				)
			)
		)
		(property "Value" ""
			(at 0 0 0)
			(layer "F.Fab")
			(effects
				(font
					(size 1.27 1.27)
				)
			)
		)
		(duplicate_pad_numbers_are_jumpers no)
		(fp_line
			(start -0.7874 -0.4064)
			(end 0.7874 -0.4064)
			(stroke
				(width 0.1524)
				(type default)
			)
			(layer "F.SilkS")
		)
		(fp_line
			(start -0.7874 0.4064)
			(end -0.7874 -0.4064)
			(stroke
				(width 0.1524)
				(type default)
			)
			(layer "F.SilkS")
		)
		(fp_line
			(start 0.7874 -0.4064)
			(end 0.7874 0.4064)
			(stroke
				(width 0.1524)
				(type default)
			)
			(layer "F.SilkS")
		)
		(fp_line
			(start 0.7874 0.4064)
			(end -0.7874 0.4064)
			(stroke
				(width 0.1524)
				(type default)
			)
			(layer "F.SilkS")
		)
		(fp_line
			(start -0.67945 -0.305054)
			(end -0.12065 -0.305054)
			(stroke
				(width 0.1)
				(type default)
			)
			(layer "F.Fab")
		)
		(fp_line
			(start -0.67945 0.3048)
			(end -0.67945 -0.305054)
			(stroke
				(width 0.1)
				(type default)
			)
			(layer "F.Fab")
		)
		(fp_line
			(start -0.12065 -0.305054)
			(end -0.12065 -0.2794)
			(stroke
				(width 0.1)
				(type default)
			)
			(layer "F.Fab")
		)
		(fp_line
			(start -0.12065 -0.2794)
			(end 0.12065 -0.2794)
			(stroke
				(width 0.1)
				(type default)
			)
			(layer "F.Fab")
		)
		(fp_line
			(start -0.12065 0.2794)
			(end -0.12065 0.3048)
			(stroke
				(width 0.1)
				(type default)
			)
			(layer "F.Fab")
		)
		(fp_line
			(start -0.12065 0.3048)
			(end -0.67945 0.3048)
			(stroke
				(width 0.1)
				(type default)
			)
			(layer "F.Fab")
		)
		(fp_line
			(start 0.120396 0.2794)
			(end -0.12065 0.2794)
			(stroke
				(width 0.1)
				(type default)
			)
			(layer "F.Fab")
		)
		(fp_line
			(start 0.120396 0.3048)
			(end 0.120396 0.2794)
			(stroke
				(width 0.1)
				(type default)
			)
			(layer "F.Fab")
		)
		(fp_line
			(start 0.12065 -0.3048)
			(end 0.67945 -0.3048)
			(stroke
				(width 0.1)
				(type default)
			)
			(layer "F.Fab")
		)
		(fp_line
			(start 0.12065 -0.2794)
			(end 0.12065 -0.3048)
			(stroke
				(width 0.1)
				(type default)
			)
			(layer "F.Fab")
		)
		(fp_line
			(start 0.67945 -0.3048)
			(end 0.67945 0.3048)
			(stroke
				(width 0.1)
				(type default)
			)
			(layer "F.Fab")
		)
		(fp_line
			(start 0.67945 0.3048)
			(end 0.120396 0.3048)
			(stroke
				(width 0.1)
				(type default)
			)
			(layer "F.Fab")
		)
		(pad "1" smd circle
			(at -0.40005 0)
			(size 0 0)
			(layers "F.Cu" "F.Mask" "F.Paste")
			(net "H_CPU1_MEMTRIP")
		)
		(pad "2" smd circle
			(at 0.40005 0)
			(size 0 0)
			(layers "F.Cu" "F.Mask" "F.Paste")
			(net "H_CPU1_MEMTRIP_R")
		)
	)
	(footprint ""
		(layer "F.Cu")
		(at 179.058062 -32.935672 90)
		(property "Reference" "PC2229"
			(at 0 0 90)
			(layer "F.SilkS")
			(hide yes)
			(effects
				(font
					(size 1.27 1.27)
				)
			)
		)
		(property "Value" ""
			(at 0 0 90)
			(layer "F.Fab")
			(effects
				(font
					(size 1.27 1.27)
				)
			)
		)
		(duplicate_pad_numbers_are_jumpers no)
		(fp_line
			(start 0.7874 -0.4064)
			(end 0.7874 0.4064)
			(stroke
				(width 0.1524)
				(type default)
			)
			(layer "F.SilkS")
		)
		(fp_line
			(start -0.7874 -0.4064)
			(end 0.7874 -0.4064)
			(stroke
				(width 0.1524)
				(type default)
			)
			(layer "F.SilkS")
		)
		(fp_line
			(start 0.7874 0.4064)
			(end -0.7874 0.4064)
			(stroke
				(width 0.1524)
				(type default)
			)
			(layer "F.SilkS")
		)
		(fp_line
			(start -0.7874 0.4064)
			(end -0.7874 -0.4064)
			(stroke
				(width 0.1524)
				(type default)
			)
			(layer "F.SilkS")
		)
		(fp_line
			(start -0.12065 -0.305054)
			(end -0.12065 -0.2794)
			(stroke
				(width 0.1)
				(type default)
			)
			(layer "F.Fab")
		)
		(fp_line
			(start -0.67945 -0.305054)
			(end -0.12065 -0.305054)
			(stroke
				(width 0.1)
				(type default)
			)
			(layer "F.Fab")
		)
		(fp_line
			(start 0.67945 -0.3048)
			(end 0.67945 0.3048)
			(stroke
				(width 0.1)
				(type default)
			)
			(layer "F.Fab")
		)
		(fp_line
			(start 0.12065 -0.3048)
			(end 0.67945 -0.3048)
			(stroke
				(width 0.1)
				(type default)
			)
			(layer "F.Fab")
		)
		(fp_line
			(start 0.12065 -0.2794)
			(end 0.12065 -0.3048)
			(stroke
				(width 0.1)
				(type default)
			)
			(layer "F.Fab")
		)
		(fp_line
			(start -0.12065 -0.2794)
			(end 0.12065 -0.2794)
			(stroke
				(width 0.1)
				(type default)
			)
			(layer "F.Fab")
		)
		(fp_line
			(start 0.120396 0.2794)
			(end -0.12065 0.2794)
			(stroke
				(width 0.1)
				(type default)
			)
			(layer "F.Fab")
		)
		(fp_line
			(start -0.12065 0.2794)
			(end -0.12065 0.3048)
			(stroke
				(width 0.1)
				(type default)
			)
			(layer "F.Fab")
		)
		(fp_line
			(start 0.67945 0.3048)
			(end 0.120396 0.3048)
			(stroke
				(width 0.1)
				(type default)
			)
			(layer "F.Fab")
		)
		(fp_line
			(start 0.120396 0.3048)
			(end 0.120396 0.2794)
			(stroke
				(width 0.1)
				(type default)
			)
			(layer "F.Fab")
		)
		(fp_line
			(start -0.12065 0.3048)
			(end -0.67945 0.3048)
			(stroke
				(width 0.1)
				(type default)
			)
			(layer "F.Fab")
		)
		(fp_line
			(start -0.67945 0.3048)
			(end -0.67945 -0.305054)
			(stroke
				(width 0.1)
				(type default)
			)
			(layer "F.Fab")
		)
		(pad "1" smd circle
			(at -0.40005 0 90)
			(size 0 0)
			(layers "F.Cu" "F.Mask" "F.Paste")
			(net "P12V_SCM_TIMER")
		)
		(pad "2" smd circle
			(at 0.40005 0 90)
			(size 0 0)
			(layers "F.Cu" "F.Mask" "F.Paste")
			(net "GND")
		)
	)
	(footprint ""
		(layer "F.Cu")
		(at 418.69233 -408.517344 -90)
		(property "Reference" "C901"
			(at 0 0 270)
			(layer "F.SilkS")
			(hide yes)
			(effects
				(font
					(size 1.27 1.27)
				)
			)
		)
		(property "Value" ""
			(at 0 0 270)
			(layer "F.Fab")
			(effects
				(font
					(size 1.27 1.27)
				)
			)
		)
		(duplicate_pad_numbers_are_jumpers no)
		(fp_line
			(start -0.299974 0.150114)
			(end -0.299974 -0.150114)
			(stroke
				(width 0.1)
				(type default)
			)
			(layer "F.Fab")
		)
		(fp_line
			(start 0.299974 0.150114)
			(end -0.299974 0.150114)
			(stroke
				(width 0.1)
				(type default)
			)
			(layer "F.Fab")
		)
		(fp_line
			(start -0.299974 -0.150114)
			(end 0.299974 -0.150114)
			(stroke
				(width 0.1)
				(type default)
			)
			(layer "F.Fab")
		)
		(fp_line
			(start 0.299974 -0.150114)
			(end 0.299974 0.150114)
			(stroke
				(width 0.1)
				(type default)
			)
			(layer "F.Fab")
		)
		(pad "1" smd rect
			(at -0.2667 0 270)
			(size 0.3048 0.381)
			(layers "F.Cu" "F.Mask" "F.Paste")
			(net "P5E_CPU0_PE3_TX_C_DP<0>")
		)
		(pad "2" smd rect
			(at 0.2667 0 270)
			(size 0.3048 0.381)
			(layers "F.Cu" "F.Mask" "F.Paste")
			(net "P5E_CPU0_PE3_TX_DP<0>")
		)
	)
	(footprint ""
		(layer "F.Cu")
		(at 218.12758 -130.957828)
		(property "Reference" "C1316"
			(at 0 0 0)
			(layer "F.SilkS")
			(hide yes)
			(effects
				(font
					(size 1.27 1.27)
				)
			)
		)
		(property "Value" ""
			(at 0 0 0)
			(layer "F.Fab")
			(effects
				(font
					(size 1.27 1.27)
				)
			)
		)
		(duplicate_pad_numbers_are_jumpers no)
		(fp_line
			(start -0.7874 -0.4064)
			(end 0.7874 -0.4064)
			(stroke
				(width 0.1524)
				(type default)
			)
			(layer "F.SilkS")
		)
		(fp_line
			(start -0.7874 0.4064)
			(end -0.7874 -0.4064)
			(stroke
				(width 0.1524)
				(type default)
			)
			(layer "F.SilkS")
		)
		(fp_line
			(start 0.7874 -0.4064)
			(end 0.7874 0.4064)
			(stroke
				(width 0.1524)
				(type default)
			)
			(layer "F.SilkS")
		)
		(fp_line
			(start 0.7874 0.4064)
			(end -0.7874 0.4064)
			(stroke
				(width 0.1524)
				(type default)
			)
			(layer "F.SilkS")
		)
		(fp_line
			(start -0.67945 -0.305054)
			(end -0.12065 -0.305054)
			(stroke
				(width 0.1)
				(type default)
			)
			(layer "F.Fab")
		)
		(fp_line
			(start -0.67945 0.3048)
			(end -0.67945 -0.305054)
			(stroke
				(width 0.1)
				(type default)
			)
			(layer "F.Fab")
		)
		(fp_line
			(start -0.12065 -0.305054)
			(end -0.12065 -0.2794)
			(stroke
				(width 0.1)
				(type default)
			)
			(layer "F.Fab")
		)
		(fp_line
			(start -0.12065 -0.2794)
			(end 0.12065 -0.2794)
			(stroke
				(width 0.1)
				(type default)
			)
			(layer "F.Fab")
		)
		(fp_line
			(start -0.12065 0.2794)
			(end -0.12065 0.3048)
			(stroke
				(width 0.1)
				(type default)
			)
			(layer "F.Fab")
		)
		(fp_line
			(start -0.12065 0.3048)
			(end -0.67945 0.3048)
			(stroke
				(width 0.1)
				(type default)
			)
			(layer "F.Fab")
		)
		(fp_line
			(start 0.120396 0.2794)
			(end -0.12065 0.2794)
			(stroke
				(width 0.1)
				(type default)
			)
			(layer "F.Fab")
		)
		(fp_line
			(start 0.120396 0.3048)
			(end 0.120396 0.2794)
			(stroke
				(width 0.1)
				(type default)
			)
			(layer "F.Fab")
		)
		(fp_line
			(start 0.12065 -0.3048)
			(end 0.67945 -0.3048)
			(stroke
				(width 0.1)
				(type default)
			)
			(layer "F.Fab")
		)
		(fp_line
			(start 0.12065 -0.2794)
			(end 0.12065 -0.3048)
			(stroke
				(width 0.1)
				(type default)
			)
			(layer "F.Fab")
		)
		(fp_line
			(start 0.67945 -0.3048)
			(end 0.67945 0.3048)
			(stroke
				(width 0.1)
				(type default)
			)
			(layer "F.Fab")
		)
		(fp_line
			(start 0.67945 0.3048)
			(end 0.120396 0.3048)
			(stroke
				(width 0.1)
				(type default)
			)
			(layer "F.Fab")
		)
		(pad "1" smd circle
			(at -0.40005 0)
			(size 0 0)
			(layers "F.Cu" "F.Mask" "F.Paste")
			(net "FM_COMP_P3V3_STBY_CEXT")
		)
		(pad "2" smd circle
			(at 0.40005 0)
			(size 0 0)
			(layers "F.Cu" "F.Mask" "F.Paste")
			(net "GND")
		)
	)
	(footprint ""
		(layer "F.Cu")
		(at 125.65888 -99.405948)
		(property "Reference" "R4398"
			(at 0 0 0)
			(layer "F.SilkS")
			(hide yes)
			(effects
				(font
					(size 1.27 1.27)
				)
			)
		)
		(property "Value" ""
			(at 0 0 0)
			(layer "F.Fab")
			(effects
				(font
					(size 1.27 1.27)
				)
			)
		)
		(duplicate_pad_numbers_are_jumpers no)
		(fp_line
			(start -0.7874 -0.4064)
			(end 0.7874 -0.4064)
			(stroke
				(width 0.1524)
				(type default)
			)
			(layer "F.SilkS")
		)
		(fp_line
			(start -0.7874 0.4064)
			(end -0.7874 -0.4064)
			(stroke
				(width 0.1524)
				(type default)
			)
			(layer "F.SilkS")
		)
		(fp_line
			(start 0.7874 -0.4064)
			(end 0.7874 0.4064)
			(stroke
				(width 0.1524)
				(type default)
			)
			(layer "F.SilkS")
		)
		(fp_line
			(start 0.7874 0.4064)
			(end -0.7874 0.4064)
			(stroke
				(width 0.1524)
				(type default)
			)
			(layer "F.SilkS")
		)
		(fp_line
			(start -0.67945 -0.305054)
			(end -0.12065 -0.305054)
			(stroke
				(width 0.1)
				(type default)
			)
			(layer "F.Fab")
		)
		(fp_line
			(start -0.67945 0.3048)
			(end -0.67945 -0.305054)
			(stroke
				(width 0.1)
				(type default)
			)
			(layer "F.Fab")
		)
		(fp_line
			(start -0.12065 -0.305054)
			(end -0.12065 -0.2794)
			(stroke
				(width 0.1)
				(type default)
			)
			(layer "F.Fab")
		)
		(fp_line
			(start -0.12065 -0.2794)
			(end 0.12065 -0.2794)
			(stroke
				(width 0.1)
				(type default)
			)
			(layer "F.Fab")
		)
		(fp_line
			(start -0.12065 0.2794)
			(end -0.12065 0.3048)
			(stroke
				(width 0.1)
				(type default)
			)
			(layer "F.Fab")
		)
		(fp_line
			(start -0.12065 0.3048)
			(end -0.67945 0.3048)
			(stroke
				(width 0.1)
				(type default)
			)
			(layer "F.Fab")
		)
		(fp_line
			(start 0.120396 0.2794)
			(end -0.12065 0.2794)
			(stroke
				(width 0.1)
				(type default)
			)
			(layer "F.Fab")
		)
		(fp_line
			(start 0.120396 0.3048)
			(end 0.120396 0.2794)
			(stroke
				(width 0.1)
				(type default)
			)
			(layer "F.Fab")
		)
		(fp_line
			(start 0.12065 -0.3048)
			(end 0.67945 -0.3048)
			(stroke
				(width 0.1)
				(type default)
			)
			(layer "F.Fab")
		)
		(fp_line
			(start 0.12065 -0.2794)
			(end 0.12065 -0.3048)
			(stroke
				(width 0.1)
				(type default)
			)
			(layer "F.Fab")
		)
		(fp_line
			(start 0.67945 -0.3048)
			(end 0.67945 0.3048)
			(stroke
				(width 0.1)
				(type default)
			)
			(layer "F.Fab")
		)
		(fp_line
			(start 0.67945 0.3048)
			(end 0.120396 0.3048)
			(stroke
				(width 0.1)
				(type default)
			)
			(layer "F.Fab")
		)
		(pad "1" smd circle
			(at -0.40005 0)
			(size 0 0)
			(layers "F.Cu" "F.Mask" "F.Paste")
			(net "H_CPU1_THERMTRIP_N")
		)
		(pad "2" smd circle
			(at 0.40005 0)
			(size 0 0)
			(layers "F.Cu" "F.Mask" "F.Paste")
			(net "H_CPU1_THERMTRIP_R_N")
		)
	)
	(footprint ""
		(layer "F.Cu")
		(at 451.81774 -115.22456 90)
		(property "Reference" "R4764"
			(at 0 0 90)
			(layer "F.SilkS")
			(hide yes)
			(effects
				(font
					(size 1.27 1.27)
				)
			)
		)
		(property "Value" ""
			(at 0 0 90)
			(layer "F.Fab")
			(effects
				(font
					(size 1.27 1.27)
				)
			)
		)
		(duplicate_pad_numbers_are_jumpers no)
		(fp_line
			(start 0.7874 -0.4064)
			(end 0.7874 0.4064)
			(stroke
				(width 0.1524)
				(type default)
			)
			(layer "F.SilkS")
		)
		(fp_line
			(start -0.7874 -0.4064)
			(end 0.7874 -0.4064)
			(stroke
				(width 0.1524)
				(type default)
			)
			(layer "F.SilkS")
		)
		(fp_line
			(start 0.7874 0.4064)
			(end -0.7874 0.4064)
			(stroke
				(width 0.1524)
				(type default)
			)
			(layer "F.SilkS")
		)
		(fp_line
			(start -0.7874 0.4064)
			(end -0.7874 -0.4064)
			(stroke
				(width 0.1524)
				(type default)
			)
			(layer "F.SilkS")
		)
		(fp_line
			(start -0.12065 -0.305054)
			(end -0.12065 -0.2794)
			(stroke
				(width 0.1)
				(type default)
			)
			(layer "F.Fab")
		)
		(fp_line
			(start -0.67945 -0.305054)
			(end -0.12065 -0.305054)
			(stroke
				(width 0.1)
				(type default)
			)
			(layer "F.Fab")
		)
		(fp_line
			(start 0.67945 -0.3048)
			(end 0.67945 0.3048)
			(stroke
				(width 0.1)
				(type default)
			)
			(layer "F.Fab")
		)
		(fp_line
			(start 0.12065 -0.3048)
			(end 0.67945 -0.3048)
			(stroke
				(width 0.1)
				(type default)
			)
			(layer "F.Fab")
		)
		(fp_line
			(start 0.12065 -0.2794)
			(end 0.12065 -0.3048)
			(stroke
				(width 0.1)
				(type default)
			)
			(layer "F.Fab")
		)
		(fp_line
			(start -0.12065 -0.2794)
			(end 0.12065 -0.2794)
			(stroke
				(width 0.1)
				(type default)
			)
			(layer "F.Fab")
		)
		(fp_line
			(start 0.120396 0.2794)
			(end -0.12065 0.2794)
			(stroke
				(width 0.1)
				(type default)
			)
			(layer "F.Fab")
		)
		(fp_line
			(start -0.12065 0.2794)
			(end -0.12065 0.3048)
			(stroke
				(width 0.1)
				(type default)
			)
			(layer "F.Fab")
		)
		(fp_line
			(start 0.67945 0.3048)
			(end 0.120396 0.3048)
			(stroke
				(width 0.1)
				(type default)
			)
			(layer "F.Fab")
		)
		(fp_line
			(start 0.120396 0.3048)
			(end 0.120396 0.2794)
			(stroke
				(width 0.1)
				(type default)
			)
			(layer "F.Fab")
		)
		(fp_line
			(start -0.12065 0.3048)
			(end -0.67945 0.3048)
			(stroke
				(width 0.1)
				(type default)
			)
			(layer "F.Fab")
		)
		(fp_line
			(start -0.67945 0.3048)
			(end -0.67945 -0.305054)
			(stroke
				(width 0.1)
				(type default)
			)
			(layer "F.Fab")
		)
		(pad "1" smd circle
			(at -0.40005 0 90)
			(size 0 0)
			(layers "F.Cu" "F.Mask" "F.Paste")
			(net "P3V3_AUX")
		)
		(pad "2" smd circle
			(at 0.40005 0 90)
			(size 0 0)
			(layers "F.Cu" "F.Mask" "F.Paste")
			(net "HP_OCP_V3_1_EN")
		)
	)
	(footprint ""
		(layer "F.Cu")
		(at 29.869638 -125.194314 -90)
		(property "Reference" "PC477"
			(at 0 0 270)
			(layer "F.SilkS")
			(hide yes)
			(effects
				(font
					(size 1.27 1.27)
				)
			)
		)
		(property "Value" ""
			(at 0 0 270)
			(layer "F.Fab")
			(effects
				(font
					(size 1.27 1.27)
				)
			)
		)
		(duplicate_pad_numbers_are_jumpers no)
		(fp_line
			(start -0.7874 0.4064)
			(end -0.7874 -0.4064)
			(stroke
				(width 0.1524)
				(type default)
			)
			(layer "F.SilkS")
		)
		(fp_line
			(start 0.7874 0.4064)
			(end -0.7874 0.4064)
			(stroke
				(width 0.1524)
				(type default)
			)
			(layer "F.SilkS")
		)
		(fp_line
			(start -0.7874 -0.4064)
			(end 0.7874 -0.4064)
			(stroke
				(width 0.1524)
				(type default)
			)
			(layer "F.SilkS")
		)
		(fp_line
			(start 0.7874 -0.4064)
			(end 0.7874 0.4064)
			(stroke
				(width 0.1524)
				(type default)
			)
			(layer "F.SilkS")
		)
		(fp_line
			(start -0.67945 0.3048)
			(end -0.67945 -0.305054)
			(stroke
				(width 0.1)
				(type default)
			)
			(layer "F.Fab")
		)
		(fp_line
			(start -0.12065 0.3048)
			(end -0.67945 0.3048)
			(stroke
				(width 0.1)
				(type default)
			)
			(layer "F.Fab")
		)
		(fp_line
			(start 0.120396 0.3048)
			(end 0.120396 0.2794)
			(stroke
				(width 0.1)
				(type default)
			)
			(layer "F.Fab")
		)
		(fp_line
			(start 0.67945 0.3048)
			(end 0.120396 0.3048)
			(stroke
				(width 0.1)
				(type default)
			)
			(layer "F.Fab")
		)
		(fp_line
			(start -0.12065 0.2794)
			(end -0.12065 0.3048)
			(stroke
				(width 0.1)
				(type default)
			)
			(layer "F.Fab")
		)
		(fp_line
			(start 0.120396 0.2794)
			(end -0.12065 0.2794)
			(stroke
				(width 0.1)
				(type default)
			)
			(layer "F.Fab")
		)
		(fp_line
			(start -0.12065 -0.2794)
			(end 0.12065 -0.2794)
			(stroke
				(width 0.1)
				(type default)
			)
			(layer "F.Fab")
		)
		(fp_line
			(start 0.12065 -0.2794)
			(end 0.12065 -0.3048)
			(stroke
				(width 0.1)
				(type default)
			)
			(layer "F.Fab")
		)
		(fp_line
			(start 0.12065 -0.3048)
			(end 0.67945 -0.3048)
			(stroke
				(width 0.1)
				(type default)
			)
			(layer "F.Fab")
		)
		(fp_line
			(start 0.67945 -0.3048)
			(end 0.67945 0.3048)
			(stroke
				(width 0.1)
				(type default)
			)
			(layer "F.Fab")
		)
		(fp_line
			(start -0.67945 -0.305054)
			(end -0.12065 -0.305054)
			(stroke
				(width 0.1)
				(type default)
			)
			(layer "F.Fab")
		)
		(fp_line
			(start -0.12065 -0.305054)
			(end -0.12065 -0.2794)
			(stroke
				(width 0.1)
				(type default)
			)
			(layer "F.Fab")
		)
		(pad "1" smd circle
			(at -0.40005 0 270)
			(size 0 0)
			(layers "F.Cu" "F.Mask" "F.Paste")
			(net "PVCCINFAON_CPU1_VREF")
		)
		(pad "2" smd circle
			(at 0.40005 0 270)
			(size 0 0)
			(layers "F.Cu" "F.Mask" "F.Paste")
			(net "GND")
		)
	)
	(footprint ""
		(layer "F.Cu")
		(at 355.219 -393.283948 180)
		(property "Reference" "R4571"
			(at 0 0 180)
			(layer "F.SilkS")
			(hide yes)
			(effects
				(font
					(size 1.27 1.27)
				)
			)
		)
		(property "Value" ""
			(at 0 0 180)
			(layer "F.Fab")
			(effects
				(font
					(size 1.27 1.27)
				)
			)
		)
		(duplicate_pad_numbers_are_jumpers no)
		(fp_line
			(start 0.7874 0.4064)
			(end -0.7874 0.4064)
			(stroke
				(width 0.1524)
				(type default)
			)
			(layer "F.SilkS")
		)
		(fp_line
			(start 0.7874 -0.4064)
			(end 0.7874 0.4064)
			(stroke
				(width 0.1524)
				(type default)
			)
			(layer "F.SilkS")
		)
		(fp_line
			(start -0.7874 0.4064)
			(end -0.7874 -0.4064)
			(stroke
				(width 0.1524)
				(type default)
			)
			(layer "F.SilkS")
		)
		(fp_line
			(start -0.7874 -0.4064)
			(end 0.7874 -0.4064)
			(stroke
				(width 0.1524)
				(type default)
			)
			(layer "F.SilkS")
		)
		(fp_line
			(start 0.67945 0.3048)
			(end 0.120396 0.3048)
			(stroke
				(width 0.1)
				(type default)
			)
			(layer "F.Fab")
		)
		(fp_line
			(start 0.67945 -0.3048)
			(end 0.67945 0.3048)
			(stroke
				(width 0.1)
				(type default)
			)
			(layer "F.Fab")
		)
		(fp_line
			(start 0.12065 -0.2794)
			(end 0.12065 -0.3048)
			(stroke
				(width 0.1)
				(type default)
			)
			(layer "F.Fab")
		)
		(fp_line
			(start 0.12065 -0.3048)
			(end 0.67945 -0.3048)
			(stroke
				(width 0.1)
				(type default)
			)
			(layer "F.Fab")
		)
		(fp_line
			(start 0.120396 0.3048)
			(end 0.120396 0.2794)
			(stroke
				(width 0.1)
				(type default)
			)
			(layer "F.Fab")
		)
		(fp_line
			(start 0.120396 0.2794)
			(end -0.12065 0.2794)
			(stroke
				(width 0.1)
				(type default)
			)
			(layer "F.Fab")
		)
		(fp_line
			(start -0.12065 0.3048)
			(end -0.67945 0.3048)
			(stroke
				(width 0.1)
				(type default)
			)
			(layer "F.Fab")
		)
		(fp_line
			(start -0.12065 0.2794)
			(end -0.12065 0.3048)
			(stroke
				(width 0.1)
				(type default)
			)
			(layer "F.Fab")
		)
		(fp_line
			(start -0.12065 -0.2794)
			(end 0.12065 -0.2794)
			(stroke
				(width 0.1)
				(type default)
			)
			(layer "F.Fab")
		)
		(fp_line
			(start -0.12065 -0.305054)
			(end -0.12065 -0.2794)
			(stroke
				(width 0.1)
				(type default)
			)
			(layer "F.Fab")
		)
		(fp_line
			(start -0.67945 0.3048)
			(end -0.67945 -0.305054)
			(stroke
				(width 0.1)
				(type default)
			)
			(layer "F.Fab")
		)
		(fp_line
			(start -0.67945 -0.305054)
			(end -0.12065 -0.305054)
			(stroke
				(width 0.1)
				(type default)
			)
			(layer "F.Fab")
		)
		(pad "1" smd circle
			(at -0.40005 0 180)
			(size 0 0)
			(layers "F.Cu" "F.Mask" "F.Paste")
			(net "GPU_3V3IO_RSVD4")
		)
		(pad "2" smd circle
			(at 0.40005 0 180)
			(size 0 0)
			(layers "F.Cu" "F.Mask" "F.Paste")
			(net "GPU_3V3IO_RSVD4_ISO")
		)
	)
	(footprint ""
		(layer "F.Cu")
		(at 86.741 -41.112948)
		(property "Reference" "R4617"
			(at 0 0 0)
			(layer "F.SilkS")
			(hide yes)
			(effects
				(font
					(size 1.27 1.27)
				)
			)
		)
		(property "Value" ""
			(at 0 0 0)
			(layer "F.Fab")
			(effects
				(font
					(size 1.27 1.27)
				)
			)
		)
		(duplicate_pad_numbers_are_jumpers no)
		(fp_line
			(start -0.7874 -0.4064)
			(end 0.7874 -0.4064)
			(stroke
				(width 0.1524)
				(type default)
			)
			(layer "F.SilkS")
		)
		(fp_line
			(start -0.7874 0.4064)
			(end -0.7874 -0.4064)
			(stroke
				(width 0.1524)
				(type default)
			)
			(layer "F.SilkS")
		)
		(fp_line
			(start 0.7874 -0.4064)
			(end 0.7874 0.4064)
			(stroke
				(width 0.1524)
				(type default)
			)
			(layer "F.SilkS")
		)
		(fp_line
			(start 0.7874 0.4064)
			(end -0.7874 0.4064)
			(stroke
				(width 0.1524)
				(type default)
			)
			(layer "F.SilkS")
		)
		(fp_line
			(start -0.67945 -0.305054)
			(end -0.12065 -0.305054)
			(stroke
				(width 0.1)
				(type default)
			)
			(layer "F.Fab")
		)
		(fp_line
			(start -0.67945 0.3048)
			(end -0.67945 -0.305054)
			(stroke
				(width 0.1)
				(type default)
			)
			(layer "F.Fab")
		)
		(fp_line
			(start -0.12065 -0.305054)
			(end -0.12065 -0.2794)
			(stroke
				(width 0.1)
				(type default)
			)
			(layer "F.Fab")
		)
		(fp_line
			(start -0.12065 -0.2794)
			(end 0.12065 -0.2794)
			(stroke
				(width 0.1)
				(type default)
			)
			(layer "F.Fab")
		)
		(fp_line
			(start -0.12065 0.2794)
			(end -0.12065 0.3048)
			(stroke
				(width 0.1)
				(type default)
			)
			(layer "F.Fab")
		)
		(fp_line
			(start -0.12065 0.3048)
			(end -0.67945 0.3048)
			(stroke
				(width 0.1)
				(type default)
			)
			(layer "F.Fab")
		)
		(fp_line
			(start 0.120396 0.2794)
			(end -0.12065 0.2794)
			(stroke
				(width 0.1)
				(type default)
			)
			(layer "F.Fab")
		)
		(fp_line
			(start 0.120396 0.3048)
			(end 0.120396 0.2794)
			(stroke
				(width 0.1)
				(type default)
			)
			(layer "F.Fab")
		)
		(fp_line
			(start 0.12065 -0.3048)
			(end 0.67945 -0.3048)
			(stroke
				(width 0.1)
				(type default)
			)
			(layer "F.Fab")
		)
		(fp_line
			(start 0.12065 -0.2794)
			(end 0.12065 -0.3048)
			(stroke
				(width 0.1)
				(type default)
			)
			(layer "F.Fab")
		)
		(fp_line
			(start 0.67945 -0.3048)
			(end 0.67945 0.3048)
			(stroke
				(width 0.1)
				(type default)
			)
			(layer "F.Fab")
		)
		(fp_line
			(start 0.67945 0.3048)
			(end 0.120396 0.3048)
			(stroke
				(width 0.1)
				(type default)
			)
			(layer "F.Fab")
		)
		(pad "1" smd circle
			(at -0.40005 0)
			(size 0 0)
			(layers "F.Cu" "F.Mask" "F.Paste")
			(net "HP_LVC3_OCP_V3_2_PWRGD")
		)
		(pad "2" smd circle
			(at 0.40005 0)
			(size 0 0)
			(layers "F.Cu" "F.Mask" "F.Paste")
			(net "HP_LVC3_OCP_V3_2_PWRGD_R")
		)
	)
	(footprint ""
		(layer "F.Cu")
		(at 424.223942 -402.671534 180)
		(property "Reference" "R3471"
			(at 0 0 180)
			(layer "F.SilkS")
			(hide yes)
			(effects
				(font
					(size 1.27 1.27)
				)
			)
		)
		(property "Value" ""
			(at 0 0 180)
			(layer "F.Fab")
			(effects
				(font
					(size 1.27 1.27)
				)
			)
		)
		(duplicate_pad_numbers_are_jumpers no)
		(fp_line
			(start 0.7874 0.4064)
			(end -0.7874 0.4064)
			(stroke
				(width 0.1524)
				(type default)
			)
			(layer "F.SilkS")
		)
		(fp_line
			(start 0.7874 -0.4064)
			(end 0.7874 0.4064)
			(stroke
				(width 0.1524)
				(type default)
			)
			(layer "F.SilkS")
		)
		(fp_line
			(start -0.7874 0.4064)
			(end -0.7874 -0.4064)
			(stroke
				(width 0.1524)
				(type default)
			)
			(layer "F.SilkS")
		)
		(fp_line
			(start -0.7874 -0.4064)
			(end 0.7874 -0.4064)
			(stroke
				(width 0.1524)
				(type default)
			)
			(layer "F.SilkS")
		)
		(fp_line
			(start 0.67945 0.3048)
			(end 0.120396 0.3048)
			(stroke
				(width 0.1)
				(type default)
			)
			(layer "F.Fab")
		)
		(fp_line
			(start 0.67945 -0.3048)
			(end 0.67945 0.3048)
			(stroke
				(width 0.1)
				(type default)
			)
			(layer "F.Fab")
		)
		(fp_line
			(start 0.12065 -0.2794)
			(end 0.12065 -0.3048)
			(stroke
				(width 0.1)
				(type default)
			)
			(layer "F.Fab")
		)
		(fp_line
			(start 0.12065 -0.3048)
			(end 0.67945 -0.3048)
			(stroke
				(width 0.1)
				(type default)
			)
			(layer "F.Fab")
		)
		(fp_line
			(start 0.120396 0.3048)
			(end 0.120396 0.2794)
			(stroke
				(width 0.1)
				(type default)
			)
			(layer "F.Fab")
		)
		(fp_line
			(start 0.120396 0.2794)
			(end -0.12065 0.2794)
			(stroke
				(width 0.1)
				(type default)
			)
			(layer "F.Fab")
		)
		(fp_line
			(start -0.12065 0.3048)
			(end -0.67945 0.3048)
			(stroke
				(width 0.1)
				(type default)
			)
			(layer "F.Fab")
		)
		(fp_line
			(start -0.12065 0.2794)
			(end -0.12065 0.3048)
			(stroke
				(width 0.1)
				(type default)
			)
			(layer "F.Fab")
		)
		(fp_line
			(start -0.12065 -0.2794)
			(end 0.12065 -0.2794)
			(stroke
				(width 0.1)
				(type default)
			)
			(layer "F.Fab")
		)
		(fp_line
			(start -0.12065 -0.305054)
			(end -0.12065 -0.2794)
			(stroke
				(width 0.1)
				(type default)
			)
			(layer "F.Fab")
		)
		(fp_line
			(start -0.67945 0.3048)
			(end -0.67945 -0.305054)
			(stroke
				(width 0.1)
				(type default)
			)
			(layer "F.Fab")
		)
		(fp_line
			(start -0.67945 -0.305054)
			(end -0.12065 -0.305054)
			(stroke
				(width 0.1)
				(type default)
			)
			(layer "F.Fab")
		)
		(pad "1" smd circle
			(at -0.40005 0 180)
			(size 0 0)
			(layers "F.Cu" "F.Mask" "F.Paste")
			(net "GPU_WP_HW_CTRL_N")
		)
		(pad "2" smd circle
			(at 0.40005 0 180)
			(size 0 0)
			(layers "F.Cu" "F.Mask" "F.Paste")
			(net "GND")
		)
	)
	(footprint ""
		(layer "F.Cu")
		(at 338.996528 -408.517344 -90)
		(property "Reference" "C924"
			(at 0 0 270)
			(layer "F.SilkS")
			(hide yes)
			(effects
				(font
					(size 1.27 1.27)
				)
			)
		)
		(property "Value" ""
			(at 0 0 270)
			(layer "F.Fab")
			(effects
				(font
					(size 1.27 1.27)
				)
			)
		)
		(duplicate_pad_numbers_are_jumpers no)
		(fp_line
			(start -0.299974 0.150114)
			(end -0.299974 -0.150114)
			(stroke
				(width 0.1)
				(type default)
			)
			(layer "F.Fab")
		)
		(fp_line
			(start 0.299974 0.150114)
			(end -0.299974 0.150114)
			(stroke
				(width 0.1)
				(type default)
			)
			(layer "F.Fab")
		)
		(fp_line
			(start -0.299974 -0.150114)
			(end 0.299974 -0.150114)
			(stroke
				(width 0.1)
				(type default)
			)
			(layer "F.Fab")
		)
		(fp_line
			(start 0.299974 -0.150114)
			(end 0.299974 0.150114)
			(stroke
				(width 0.1)
				(type default)
			)
			(layer "F.Fab")
		)
		(pad "1" smd rect
			(at -0.2667 0 270)
			(size 0.3048 0.381)
			(layers "F.Cu" "F.Mask" "F.Paste")
			(net "P5E_CPU0_PE0_TX_C_DN<4>")
		)
		(pad "2" smd rect
			(at 0.2667 0 270)
			(size 0.3048 0.381)
			(layers "F.Cu" "F.Mask" "F.Paste")
			(net "P5E_CPU0_PE0_TX_DN<4>")
		)
	)
	(footprint ""
		(layer "F.Cu")
		(at 192.052448 -402.128482 180)
		(property "Reference" "PR3928"
			(at 0 0 180)
			(layer "F.SilkS")
			(hide yes)
			(effects
				(font
					(size 1.27 1.27)
				)
			)
		)
		(property "Value" ""
			(at 0 0 180)
			(layer "F.Fab")
			(effects
				(font
					(size 1.27 1.27)
				)
			)
		)
		(duplicate_pad_numbers_are_jumpers no)
		(fp_line
			(start 0.7874 0.4064)
			(end -0.7874 0.4064)
			(stroke
				(width 0.1524)
				(type default)
			)
			(layer "F.SilkS")
		)
		(fp_line
			(start 0.7874 -0.4064)
			(end 0.7874 0.4064)
			(stroke
				(width 0.1524)
				(type default)
			)
			(layer "F.SilkS")
		)
		(fp_line
			(start -0.7874 0.4064)
			(end -0.7874 -0.4064)
			(stroke
				(width 0.1524)
				(type default)
			)
			(layer "F.SilkS")
		)
		(fp_line
			(start -0.7874 -0.4064)
			(end 0.7874 -0.4064)
			(stroke
				(width 0.1524)
				(type default)
			)
			(layer "F.SilkS")
		)
		(fp_line
			(start 0.67945 0.3048)
			(end 0.120396 0.3048)
			(stroke
				(width 0.1)
				(type default)
			)
			(layer "F.Fab")
		)
		(fp_line
			(start 0.67945 -0.3048)
			(end 0.67945 0.3048)
			(stroke
				(width 0.1)
				(type default)
			)
			(layer "F.Fab")
		)
		(fp_line
			(start 0.12065 -0.2794)
			(end 0.12065 -0.3048)
			(stroke
				(width 0.1)
				(type default)
			)
			(layer "F.Fab")
		)
		(fp_line
			(start 0.12065 -0.3048)
			(end 0.67945 -0.3048)
			(stroke
				(width 0.1)
				(type default)
			)
			(layer "F.Fab")
		)
		(fp_line
			(start 0.120396 0.3048)
			(end 0.120396 0.2794)
			(stroke
				(width 0.1)
				(type default)
			)
			(layer "F.Fab")
		)
		(fp_line
			(start 0.120396 0.2794)
			(end -0.12065 0.2794)
			(stroke
				(width 0.1)
				(type default)
			)
			(layer "F.Fab")
		)
		(fp_line
			(start -0.12065 0.3048)
			(end -0.67945 0.3048)
			(stroke
				(width 0.1)
				(type default)
			)
			(layer "F.Fab")
		)
		(fp_line
			(start -0.12065 0.2794)
			(end -0.12065 0.3048)
			(stroke
				(width 0.1)
				(type default)
			)
			(layer "F.Fab")
		)
		(fp_line
			(start -0.12065 -0.2794)
			(end 0.12065 -0.2794)
			(stroke
				(width 0.1)
				(type default)
			)
			(layer "F.Fab")
		)
		(fp_line
			(start -0.12065 -0.305054)
			(end -0.12065 -0.2794)
			(stroke
				(width 0.1)
				(type default)
			)
			(layer "F.Fab")
		)
		(fp_line
			(start -0.67945 0.3048)
			(end -0.67945 -0.305054)
			(stroke
				(width 0.1)
				(type default)
			)
			(layer "F.Fab")
		)
		(fp_line
			(start -0.67945 -0.305054)
			(end -0.12065 -0.305054)
			(stroke
				(width 0.1)
				(type default)
			)
			(layer "F.Fab")
		)
		(pad "1" smd circle
			(at -0.40005 0 180)
			(size 0 0)
			(layers "F.Cu" "F.Mask" "F.Paste")
			(net "HSC_ON")
		)
		(pad "2" smd circle
			(at 0.40005 0 180)
			(size 0 0)
			(layers "F.Cu" "F.Mask" "F.Paste")
			(net "HSC_ON_R")
		)
	)
	(footprint ""
		(layer "F.Cu")
		(at 385.699 -69.179948 180)
		(property "Reference" "R775"
			(at 0 0 180)
			(layer "F.SilkS")
			(hide yes)
			(effects
				(font
					(size 1.27 1.27)
				)
			)
		)
		(property "Value" ""
			(at 0 0 180)
			(layer "F.Fab")
			(effects
				(font
					(size 1.27 1.27)
				)
			)
		)
		(duplicate_pad_numbers_are_jumpers no)
		(fp_line
			(start 0.7874 0.4064)
			(end -0.7874 0.4064)
			(stroke
				(width 0.1524)
				(type default)
			)
			(layer "F.SilkS")
		)
		(fp_line
			(start 0.7874 -0.4064)
			(end 0.7874 0.4064)
			(stroke
				(width 0.1524)
				(type default)
			)
			(layer "F.SilkS")
		)
		(fp_line
			(start -0.7874 0.4064)
			(end -0.7874 -0.4064)
			(stroke
				(width 0.1524)
				(type default)
			)
			(layer "F.SilkS")
		)
		(fp_line
			(start -0.7874 -0.4064)
			(end 0.7874 -0.4064)
			(stroke
				(width 0.1524)
				(type default)
			)
			(layer "F.SilkS")
		)
		(fp_line
			(start 0.67945 0.3048)
			(end 0.120396 0.3048)
			(stroke
				(width 0.1)
				(type default)
			)
			(layer "F.Fab")
		)
		(fp_line
			(start 0.67945 -0.3048)
			(end 0.67945 0.3048)
			(stroke
				(width 0.1)
				(type default)
			)
			(layer "F.Fab")
		)
		(fp_line
			(start 0.12065 -0.2794)
			(end 0.12065 -0.3048)
			(stroke
				(width 0.1)
				(type default)
			)
			(layer "F.Fab")
		)
		(fp_line
			(start 0.12065 -0.3048)
			(end 0.67945 -0.3048)
			(stroke
				(width 0.1)
				(type default)
			)
			(layer "F.Fab")
		)
		(fp_line
			(start 0.120396 0.3048)
			(end 0.120396 0.2794)
			(stroke
				(width 0.1)
				(type default)
			)
			(layer "F.Fab")
		)
		(fp_line
			(start 0.120396 0.2794)
			(end -0.12065 0.2794)
			(stroke
				(width 0.1)
				(type default)
			)
			(layer "F.Fab")
		)
		(fp_line
			(start -0.12065 0.3048)
			(end -0.67945 0.3048)
			(stroke
				(width 0.1)
				(type default)
			)
			(layer "F.Fab")
		)
		(fp_line
			(start -0.12065 0.2794)
			(end -0.12065 0.3048)
			(stroke
				(width 0.1)
				(type default)
			)
			(layer "F.Fab")
		)
		(fp_line
			(start -0.12065 -0.2794)
			(end 0.12065 -0.2794)
			(stroke
				(width 0.1)
				(type default)
			)
			(layer "F.Fab")
		)
		(fp_line
			(start -0.12065 -0.305054)
			(end -0.12065 -0.2794)
			(stroke
				(width 0.1)
				(type default)
			)
			(layer "F.Fab")
		)
		(fp_line
			(start -0.67945 0.3048)
			(end -0.67945 -0.305054)
			(stroke
				(width 0.1)
				(type default)
			)
			(layer "F.Fab")
		)
		(fp_line
			(start -0.67945 -0.305054)
			(end -0.12065 -0.305054)
			(stroke
				(width 0.1)
				(type default)
			)
			(layer "F.Fab")
		)
		(pad "1" smd circle
			(at -0.40005 0 180)
			(size 0 0)
			(layers "F.Cu" "F.Mask" "F.Paste")
			(net "JTAG_DBP_TMS_R")
		)
		(pad "2" smd circle
			(at 0.40005 0 180)
			(size 0 0)
			(layers "F.Cu" "F.Mask" "F.Paste")
			(net "JTAG_DBP_TMS")
		)
	)
	(footprint ""
		(layer "F.Cu")
		(at 128.778 -73.370948)
		(property "Reference" "R2507"
			(at 0 0 0)
			(layer "F.SilkS")
			(hide yes)
			(effects
				(font
					(size 1.27 1.27)
				)
			)
		)
		(property "Value" ""
			(at 0 0 0)
			(layer "F.Fab")
			(effects
				(font
					(size 1.27 1.27)
				)
			)
		)
		(duplicate_pad_numbers_are_jumpers no)
		(fp_line
			(start -0.7874 -0.4064)
			(end 0.7874 -0.4064)
			(stroke
				(width 0.1524)
				(type default)
			)
			(layer "F.SilkS")
		)
		(fp_line
			(start -0.7874 0.4064)
			(end -0.7874 -0.4064)
			(stroke
				(width 0.1524)
				(type default)
			)
			(layer "F.SilkS")
		)
		(fp_line
			(start 0.7874 -0.4064)
			(end 0.7874 0.4064)
			(stroke
				(width 0.1524)
				(type default)
			)
			(layer "F.SilkS")
		)
		(fp_line
			(start 0.7874 0.4064)
			(end -0.7874 0.4064)
			(stroke
				(width 0.1524)
				(type default)
			)
			(layer "F.SilkS")
		)
		(fp_line
			(start -0.67945 -0.305054)
			(end -0.12065 -0.305054)
			(stroke
				(width 0.1)
				(type default)
			)
			(layer "F.Fab")
		)
		(fp_line
			(start -0.67945 0.3048)
			(end -0.67945 -0.305054)
			(stroke
				(width 0.1)
				(type default)
			)
			(layer "F.Fab")
		)
		(fp_line
			(start -0.12065 -0.305054)
			(end -0.12065 -0.2794)
			(stroke
				(width 0.1)
				(type default)
			)
			(layer "F.Fab")
		)
		(fp_line
			(start -0.12065 -0.2794)
			(end 0.12065 -0.2794)
			(stroke
				(width 0.1)
				(type default)
			)
			(layer "F.Fab")
		)
		(fp_line
			(start -0.12065 0.2794)
			(end -0.12065 0.3048)
			(stroke
				(width 0.1)
				(type default)
			)
			(layer "F.Fab")
		)
		(fp_line
			(start -0.12065 0.3048)
			(end -0.67945 0.3048)
			(stroke
				(width 0.1)
				(type default)
			)
			(layer "F.Fab")
		)
		(fp_line
			(start 0.120396 0.2794)
			(end -0.12065 0.2794)
			(stroke
				(width 0.1)
				(type default)
			)
			(layer "F.Fab")
		)
		(fp_line
			(start 0.120396 0.3048)
			(end 0.120396 0.2794)
			(stroke
				(width 0.1)
				(type default)
			)
			(layer "F.Fab")
		)
		(fp_line
			(start 0.12065 -0.3048)
			(end 0.67945 -0.3048)
			(stroke
				(width 0.1)
				(type default)
			)
			(layer "F.Fab")
		)
		(fp_line
			(start 0.12065 -0.2794)
			(end 0.12065 -0.3048)
			(stroke
				(width 0.1)
				(type default)
			)
			(layer "F.Fab")
		)
		(fp_line
			(start 0.67945 -0.3048)
			(end 0.67945 0.3048)
			(stroke
				(width 0.1)
				(type default)
			)
			(layer "F.Fab")
		)
		(fp_line
			(start 0.67945 0.3048)
			(end 0.120396 0.3048)
			(stroke
				(width 0.1)
				(type default)
			)
			(layer "F.Fab")
		)
		(pad "1" smd circle
			(at -0.40005 0)
			(size 0 0)
			(layers "F.Cu" "F.Mask" "F.Paste")
			(net "P3V3_AUX")
		)
		(pad "2" smd circle
			(at 0.40005 0)
			(size 0 0)
			(layers "F.Cu" "F.Mask" "F.Paste")
			(net "JTAG_BMC_DBP_TDI")
		)
	)
	(footprint ""
		(layer "F.Cu")
		(at 25.9715 -397.688562 90)
		(property "Reference" "R4665"
			(at 0 0 90)
			(layer "F.SilkS")
			(hide yes)
			(effects
				(font
					(size 1.27 1.27)
				)
			)
		)
		(property "Value" ""
			(at 0 0 90)
			(layer "F.Fab")
			(effects
				(font
					(size 1.27 1.27)
				)
			)
		)
		(duplicate_pad_numbers_are_jumpers no)
		(fp_line
			(start -0.013462 -0.4064)
			(end 0.7874 -0.4064)
			(stroke
				(width 0.1524)
				(type default)
			)
			(layer "F.SilkS")
		)
		(fp_line
			(start 0.7874 0.4064)
			(end -0.7874 0.4064)
			(stroke
				(width 0.1524)
				(type default)
			)
			(layer "F.SilkS")
		)
		(fp_line
			(start -0.7874 0.4064)
			(end -0.7874 -0.4064)
			(stroke
				(width 0.1524)
				(type default)
			)
			(layer "F.SilkS")
		)
		(fp_line
			(start -0.12065 -0.305054)
			(end -0.12065 -0.2794)
			(stroke
				(width 0.1)
				(type default)
			)
			(layer "F.Fab")
		)
		(fp_line
			(start -0.67945 -0.305054)
			(end -0.12065 -0.305054)
			(stroke
				(width 0.1)
				(type default)
			)
			(layer "F.Fab")
		)
		(fp_line
			(start 0.67945 -0.3048)
			(end 0.67945 0.3048)
			(stroke
				(width 0.1)
				(type default)
			)
			(layer "F.Fab")
		)
		(fp_line
			(start 0.12065 -0.3048)
			(end 0.67945 -0.3048)
			(stroke
				(width 0.1)
				(type default)
			)
			(layer "F.Fab")
		)
		(fp_line
			(start 0.12065 -0.2794)
			(end 0.12065 -0.3048)
			(stroke
				(width 0.1)
				(type default)
			)
			(layer "F.Fab")
		)
		(fp_line
			(start -0.12065 -0.2794)
			(end 0.12065 -0.2794)
			(stroke
				(width 0.1)
				(type default)
			)
			(layer "F.Fab")
		)
		(fp_line
			(start 0.120396 0.2794)
			(end -0.12065 0.2794)
			(stroke
				(width 0.1)
				(type default)
			)
			(layer "F.Fab")
		)
		(fp_line
			(start -0.12065 0.2794)
			(end -0.12065 0.3048)
			(stroke
				(width 0.1)
				(type default)
			)
			(layer "F.Fab")
		)
		(fp_line
			(start 0.67945 0.3048)
			(end 0.120396 0.3048)
			(stroke
				(width 0.1)
				(type default)
			)
			(layer "F.Fab")
		)
		(fp_line
			(start 0.120396 0.3048)
			(end 0.120396 0.2794)
			(stroke
				(width 0.1)
				(type default)
			)
			(layer "F.Fab")
		)
		(fp_line
			(start -0.12065 0.3048)
			(end -0.67945 0.3048)
			(stroke
				(width 0.1)
				(type default)
			)
			(layer "F.Fab")
		)
		(fp_line
			(start -0.67945 0.3048)
			(end -0.67945 -0.305054)
			(stroke
				(width 0.1)
				(type default)
			)
			(layer "F.Fab")
		)
		(pad "1" smd rect
			(at -0.40005 0 270)
			(size 0.4572 0.508)
			(layers "F.Cu" "F.Mask" "F.Paste")
			(net "P2E_MB_BMC_RX_DP<0>")
		)
		(pad "2" smd rect
			(at 0.40005 0 270)
			(size 0.4572 0.508)
			(layers "F.Cu" "F.Mask" "F.Paste")
			(net "P2E_MB_BMC_RX_R2_DP<0>")
		)
	)
	(footprint ""
		(layer "F.Cu")
		(at 220.087444 -99.21748)
		(property "Reference" "C2394"
			(at 0 0 0)
			(layer "F.SilkS")
			(hide yes)
			(effects
				(font
					(size 1.27 1.27)
				)
			)
		)
		(property "Value" ""
			(at 0 0 0)
			(layer "F.Fab")
			(effects
				(font
					(size 1.27 1.27)
				)
			)
		)
		(duplicate_pad_numbers_are_jumpers no)
		(fp_line
			(start -0.7874 -0.4064)
			(end 0.7874 -0.4064)
			(stroke
				(width 0.1524)
				(type default)
			)
			(layer "F.SilkS")
		)
		(fp_line
			(start -0.7874 0.4064)
			(end -0.7874 -0.4064)
			(stroke
				(width 0.1524)
				(type default)
			)
			(layer "F.SilkS")
		)
		(fp_line
			(start 0.7874 -0.4064)
			(end 0.7874 0.4064)
			(stroke
				(width 0.1524)
				(type default)
			)
			(layer "F.SilkS")
		)
		(fp_line
			(start 0.7874 0.4064)
			(end -0.7874 0.4064)
			(stroke
				(width 0.1524)
				(type default)
			)
			(layer "F.SilkS")
		)
		(fp_line
			(start -0.67945 -0.305054)
			(end -0.12065 -0.305054)
			(stroke
				(width 0.1)
				(type default)
			)
			(layer "F.Fab")
		)
		(fp_line
			(start -0.67945 0.3048)
			(end -0.67945 -0.305054)
			(stroke
				(width 0.1)
				(type default)
			)
			(layer "F.Fab")
		)
		(fp_line
			(start -0.12065 -0.305054)
			(end -0.12065 -0.2794)
			(stroke
				(width 0.1)
				(type default)
			)
			(layer "F.Fab")
		)
		(fp_line
			(start -0.12065 -0.2794)
			(end 0.12065 -0.2794)
			(stroke
				(width 0.1)
				(type default)
			)
			(layer "F.Fab")
		)
		(fp_line
			(start -0.12065 0.2794)
			(end -0.12065 0.3048)
			(stroke
				(width 0.1)
				(type default)
			)
			(layer "F.Fab")
		)
		(fp_line
			(start -0.12065 0.3048)
			(end -0.67945 0.3048)
			(stroke
				(width 0.1)
				(type default)
			)
			(layer "F.Fab")
		)
		(fp_line
			(start 0.120396 0.2794)
			(end -0.12065 0.2794)
			(stroke
				(width 0.1)
				(type default)
			)
			(layer "F.Fab")
		)
		(fp_line
			(start 0.120396 0.3048)
			(end 0.120396 0.2794)
			(stroke
				(width 0.1)
				(type default)
			)
			(layer "F.Fab")
		)
		(fp_line
			(start 0.12065 -0.3048)
			(end 0.67945 -0.3048)
			(stroke
				(width 0.1)
				(type default)
			)
			(layer "F.Fab")
		)
		(fp_line
			(start 0.12065 -0.2794)
			(end 0.12065 -0.3048)
			(stroke
				(width 0.1)
				(type default)
			)
			(layer "F.Fab")
		)
		(fp_line
			(start 0.67945 -0.3048)
			(end 0.67945 0.3048)
			(stroke
				(width 0.1)
				(type default)
			)
			(layer "F.Fab")
		)
		(fp_line
			(start 0.67945 0.3048)
			(end 0.120396 0.3048)
			(stroke
				(width 0.1)
				(type default)
			)
			(layer "F.Fab")
		)
		(pad "1" smd circle
			(at -0.40005 0)
			(size 0 0)
			(layers "F.Cu" "F.Mask" "F.Paste")
			(net "U206_VDD")
		)
		(pad "2" smd circle
			(at 0.40005 0)
			(size 0 0)
			(layers "F.Cu" "F.Mask" "F.Paste")
			(net "GND")
		)
	)
	(footprint ""
		(layer "F.Cu")
		(at 419.91788 -156.632148 90)
		(property "Reference" "PR1779"
			(at 0 0 90)
			(layer "F.SilkS")
			(hide yes)
			(effects
				(font
					(size 1.27 1.27)
				)
			)
		)
		(property "Value" ""
			(at 0 0 90)
			(layer "F.Fab")
			(effects
				(font
					(size 1.27 1.27)
				)
			)
		)
		(duplicate_pad_numbers_are_jumpers no)
		(fp_line
			(start 0.7874 -0.4064)
			(end 0.7874 0.4064)
			(stroke
				(width 0.1524)
				(type default)
			)
			(layer "F.SilkS")
		)
		(fp_line
			(start -0.7874 -0.4064)
			(end 0.7874 -0.4064)
			(stroke
				(width 0.1524)
				(type default)
			)
			(layer "F.SilkS")
		)
		(fp_line
			(start 0.7874 0.4064)
			(end -0.7874 0.4064)
			(stroke
				(width 0.1524)
				(type default)
			)
			(layer "F.SilkS")
		)
		(fp_line
			(start -0.7874 0.4064)
			(end -0.7874 -0.4064)
			(stroke
				(width 0.1524)
				(type default)
			)
			(layer "F.SilkS")
		)
		(fp_line
			(start -0.12065 -0.305054)
			(end -0.12065 -0.2794)
			(stroke
				(width 0.1)
				(type default)
			)
			(layer "F.Fab")
		)
		(fp_line
			(start -0.67945 -0.305054)
			(end -0.12065 -0.305054)
			(stroke
				(width 0.1)
				(type default)
			)
			(layer "F.Fab")
		)
		(fp_line
			(start 0.67945 -0.3048)
			(end 0.67945 0.3048)
			(stroke
				(width 0.1)
				(type default)
			)
			(layer "F.Fab")
		)
		(fp_line
			(start 0.12065 -0.3048)
			(end 0.67945 -0.3048)
			(stroke
				(width 0.1)
				(type default)
			)
			(layer "F.Fab")
		)
		(fp_line
			(start 0.12065 -0.2794)
			(end 0.12065 -0.3048)
			(stroke
				(width 0.1)
				(type default)
			)
			(layer "F.Fab")
		)
		(fp_line
			(start -0.12065 -0.2794)
			(end 0.12065 -0.2794)
			(stroke
				(width 0.1)
				(type default)
			)
			(layer "F.Fab")
		)
		(fp_line
			(start 0.120396 0.2794)
			(end -0.12065 0.2794)
			(stroke
				(width 0.1)
				(type default)
			)
			(layer "F.Fab")
		)
		(fp_line
			(start -0.12065 0.2794)
			(end -0.12065 0.3048)
			(stroke
				(width 0.1)
				(type default)
			)
			(layer "F.Fab")
		)
		(fp_line
			(start 0.67945 0.3048)
			(end 0.120396 0.3048)
			(stroke
				(width 0.1)
				(type default)
			)
			(layer "F.Fab")
		)
		(fp_line
			(start 0.120396 0.3048)
			(end 0.120396 0.2794)
			(stroke
				(width 0.1)
				(type default)
			)
			(layer "F.Fab")
		)
		(fp_line
			(start -0.12065 0.3048)
			(end -0.67945 0.3048)
			(stroke
				(width 0.1)
				(type default)
			)
			(layer "F.Fab")
		)
		(fp_line
			(start -0.67945 0.3048)
			(end -0.67945 -0.305054)
			(stroke
				(width 0.1)
				(type default)
			)
			(layer "F.Fab")
		)
		(pad "1" smd circle
			(at -0.40005 0 90)
			(size 0 0)
			(layers "F.Cu" "F.Mask" "F.Paste")
			(net "PVCCFA_EHV_CPU0_NC1")
		)
		(pad "2" smd circle
			(at 0.40005 0 90)
			(size 0 0)
			(layers "F.Cu" "F.Mask" "F.Paste")
			(net "PVCCFA_EHV_CPU0_VDD1")
		)
	)
	(footprint ""
		(layer "F.Cu")
		(at 185.255662 -410.083762 180)
		(property "Reference" "PC2188"
			(at 0 0 180)
			(layer "F.SilkS")
			(hide yes)
			(effects
				(font
					(size 1.27 1.27)
				)
			)
		)
		(property "Value" ""
			(at 0 0 180)
			(layer "F.Fab")
			(effects
				(font
					(size 1.27 1.27)
				)
			)
		)
		(duplicate_pad_numbers_are_jumpers no)
		(fp_line
			(start 0.7874 0.4064)
			(end -0.7874 0.4064)
			(stroke
				(width 0.1524)
				(type default)
			)
			(layer "F.SilkS")
		)
		(fp_line
			(start 0.7874 -0.4064)
			(end 0.7874 0.4064)
			(stroke
				(width 0.1524)
				(type default)
			)
			(layer "F.SilkS")
		)
		(fp_line
			(start -0.7874 0.4064)
			(end -0.7874 -0.4064)
			(stroke
				(width 0.1524)
				(type default)
			)
			(layer "F.SilkS")
		)
		(fp_line
			(start -0.7874 -0.4064)
			(end 0.7874 -0.4064)
			(stroke
				(width 0.1524)
				(type default)
			)
			(layer "F.SilkS")
		)
		(fp_line
			(start 0.67945 0.3048)
			(end 0.120396 0.3048)
			(stroke
				(width 0.1)
				(type default)
			)
			(layer "F.Fab")
		)
		(fp_line
			(start 0.67945 -0.3048)
			(end 0.67945 0.3048)
			(stroke
				(width 0.1)
				(type default)
			)
			(layer "F.Fab")
		)
		(fp_line
			(start 0.12065 -0.2794)
			(end 0.12065 -0.3048)
			(stroke
				(width 0.1)
				(type default)
			)
			(layer "F.Fab")
		)
		(fp_line
			(start 0.12065 -0.3048)
			(end 0.67945 -0.3048)
			(stroke
				(width 0.1)
				(type default)
			)
			(layer "F.Fab")
		)
		(fp_line
			(start 0.120396 0.3048)
			(end 0.120396 0.2794)
			(stroke
				(width 0.1)
				(type default)
			)
			(layer "F.Fab")
		)
		(fp_line
			(start 0.120396 0.2794)
			(end -0.12065 0.2794)
			(stroke
				(width 0.1)
				(type default)
			)
			(layer "F.Fab")
		)
		(fp_line
			(start -0.12065 0.3048)
			(end -0.67945 0.3048)
			(stroke
				(width 0.1)
				(type default)
			)
			(layer "F.Fab")
		)
		(fp_line
			(start -0.12065 0.2794)
			(end -0.12065 0.3048)
			(stroke
				(width 0.1)
				(type default)
			)
			(layer "F.Fab")
		)
		(fp_line
			(start -0.12065 -0.2794)
			(end 0.12065 -0.2794)
			(stroke
				(width 0.1)
				(type default)
			)
			(layer "F.Fab")
		)
		(fp_line
			(start -0.12065 -0.305054)
			(end -0.12065 -0.2794)
			(stroke
				(width 0.1)
				(type default)
			)
			(layer "F.Fab")
		)
		(fp_line
			(start -0.67945 0.3048)
			(end -0.67945 -0.305054)
			(stroke
				(width 0.1)
				(type default)
			)
			(layer "F.Fab")
		)
		(fp_line
			(start -0.67945 -0.305054)
			(end -0.12065 -0.305054)
			(stroke
				(width 0.1)
				(type default)
			)
			(layer "F.Fab")
		)
		(pad "1" smd circle
			(at -0.40005 0 180)
			(size 0 0)
			(layers "F.Cu" "F.Mask" "F.Paste")
			(net "P12V_PSU")
		)
		(pad "2" smd circle
			(at 0.40005 0 180)
			(size 0 0)
			(layers "F.Cu" "F.Mask" "F.Paste")
			(net "GND")
		)
	)
	(footprint ""
		(layer "F.Cu")
		(at 175.82388 -19.548348 180)
		(property "Reference" "PC2238"
			(at 0 0 180)
			(layer "F.SilkS")
			(hide yes)
			(effects
				(font
					(size 1.27 1.27)
				)
			)
		)
		(property "Value" ""
			(at 0 0 180)
			(layer "F.Fab")
			(effects
				(font
					(size 1.27 1.27)
				)
			)
		)
		(duplicate_pad_numbers_are_jumpers no)
		(fp_line
			(start 0.7874 0.4064)
			(end -0.7874 0.4064)
			(stroke
				(width 0.1524)
				(type default)
			)
			(layer "F.SilkS")
		)
		(fp_line
			(start 0.7874 -0.4064)
			(end 0.7874 0.4064)
			(stroke
				(width 0.1524)
				(type default)
			)
			(layer "F.SilkS")
		)
		(fp_line
			(start -0.7874 0.4064)
			(end -0.7874 -0.4064)
			(stroke
				(width 0.1524)
				(type default)
			)
			(layer "F.SilkS")
		)
		(fp_line
			(start -0.7874 -0.4064)
			(end 0.7874 -0.4064)
			(stroke
				(width 0.1524)
				(type default)
			)
			(layer "F.SilkS")
		)
		(fp_line
			(start 0.67945 0.3048)
			(end 0.120396 0.3048)
			(stroke
				(width 0.1)
				(type default)
			)
			(layer "F.Fab")
		)
		(fp_line
			(start 0.67945 -0.3048)
			(end 0.67945 0.3048)
			(stroke
				(width 0.1)
				(type default)
			)
			(layer "F.Fab")
		)
		(fp_line
			(start 0.12065 -0.2794)
			(end 0.12065 -0.3048)
			(stroke
				(width 0.1)
				(type default)
			)
			(layer "F.Fab")
		)
		(fp_line
			(start 0.12065 -0.3048)
			(end 0.67945 -0.3048)
			(stroke
				(width 0.1)
				(type default)
			)
			(layer "F.Fab")
		)
		(fp_line
			(start 0.120396 0.3048)
			(end 0.120396 0.2794)
			(stroke
				(width 0.1)
				(type default)
			)
			(layer "F.Fab")
		)
		(fp_line
			(start 0.120396 0.2794)
			(end -0.12065 0.2794)
			(stroke
				(width 0.1)
				(type default)
			)
			(layer "F.Fab")
		)
		(fp_line
			(start -0.12065 0.3048)
			(end -0.67945 0.3048)
			(stroke
				(width 0.1)
				(type default)
			)
			(layer "F.Fab")
		)
		(fp_line
			(start -0.12065 0.2794)
			(end -0.12065 0.3048)
			(stroke
				(width 0.1)
				(type default)
			)
			(layer "F.Fab")
		)
		(fp_line
			(start -0.12065 -0.2794)
			(end 0.12065 -0.2794)
			(stroke
				(width 0.1)
				(type default)
			)
			(layer "F.Fab")
		)
		(fp_line
			(start -0.12065 -0.305054)
			(end -0.12065 -0.2794)
			(stroke
				(width 0.1)
				(type default)
			)
			(layer "F.Fab")
		)
		(fp_line
			(start -0.67945 0.3048)
			(end -0.67945 -0.305054)
			(stroke
				(width 0.1)
				(type default)
			)
			(layer "F.Fab")
		)
		(fp_line
			(start -0.67945 -0.305054)
			(end -0.12065 -0.305054)
			(stroke
				(width 0.1)
				(type default)
			)
			(layer "F.Fab")
		)
		(pad "1" smd circle
			(at -0.40005 0 180)
			(size 0 0)
			(layers "F.Cu" "F.Mask" "F.Paste")
			(net "P12V_SCM_R")
		)
		(pad "2" smd circle
			(at 0.40005 0 180)
			(size 0 0)
			(layers "F.Cu" "F.Mask" "F.Paste")
			(net "GND")
		)
	)
	(footprint ""
		(layer "F.Cu")
		(at 127.27432 -23.769828)
		(property "Reference" "C2286"
			(at 0 0 0)
			(layer "F.SilkS")
			(hide yes)
			(effects
				(font
					(size 1.27 1.27)
				)
			)
		)
		(property "Value" ""
			(at 0 0 0)
			(layer "F.Fab")
			(effects
				(font
					(size 1.27 1.27)
				)
			)
		)
		(duplicate_pad_numbers_are_jumpers no)
		(fp_line
			(start -0.7874 -0.4064)
			(end 0.7874 -0.4064)
			(stroke
				(width 0.1524)
				(type default)
			)
			(layer "F.SilkS")
		)
		(fp_line
			(start -0.7874 0.4064)
			(end -0.7874 -0.4064)
			(stroke
				(width 0.1524)
				(type default)
			)
			(layer "F.SilkS")
		)
		(fp_line
			(start 0.7874 -0.4064)
			(end 0.7874 0.4064)
			(stroke
				(width 0.1524)
				(type default)
			)
			(layer "F.SilkS")
		)
		(fp_line
			(start 0.7874 0.4064)
			(end -0.7874 0.4064)
			(stroke
				(width 0.1524)
				(type default)
			)
			(layer "F.SilkS")
		)
		(fp_line
			(start -0.67945 -0.305054)
			(end -0.12065 -0.305054)
			(stroke
				(width 0.1)
				(type default)
			)
			(layer "F.Fab")
		)
		(fp_line
			(start -0.67945 0.3048)
			(end -0.67945 -0.305054)
			(stroke
				(width 0.1)
				(type default)
			)
			(layer "F.Fab")
		)
		(fp_line
			(start -0.12065 -0.305054)
			(end -0.12065 -0.2794)
			(stroke
				(width 0.1)
				(type default)
			)
			(layer "F.Fab")
		)
		(fp_line
			(start -0.12065 -0.2794)
			(end 0.12065 -0.2794)
			(stroke
				(width 0.1)
				(type default)
			)
			(layer "F.Fab")
		)
		(fp_line
			(start -0.12065 0.2794)
			(end -0.12065 0.3048)
			(stroke
				(width 0.1)
				(type default)
			)
			(layer "F.Fab")
		)
		(fp_line
			(start -0.12065 0.3048)
			(end -0.67945 0.3048)
			(stroke
				(width 0.1)
				(type default)
			)
			(layer "F.Fab")
		)
		(fp_line
			(start 0.120396 0.2794)
			(end -0.12065 0.2794)
			(stroke
				(width 0.1)
				(type default)
			)
			(layer "F.Fab")
		)
		(fp_line
			(start 0.120396 0.3048)
			(end 0.120396 0.2794)
			(stroke
				(width 0.1)
				(type default)
			)
			(layer "F.Fab")
		)
		(fp_line
			(start 0.12065 -0.3048)
			(end 0.67945 -0.3048)
			(stroke
				(width 0.1)
				(type default)
			)
			(layer "F.Fab")
		)
		(fp_line
			(start 0.12065 -0.2794)
			(end 0.12065 -0.3048)
			(stroke
				(width 0.1)
				(type default)
			)
			(layer "F.Fab")
		)
		(fp_line
			(start 0.67945 -0.3048)
			(end 0.67945 0.3048)
			(stroke
				(width 0.1)
				(type default)
			)
			(layer "F.Fab")
		)
		(fp_line
			(start 0.67945 0.3048)
			(end 0.120396 0.3048)
			(stroke
				(width 0.1)
				(type default)
			)
			(layer "F.Fab")
		)
		(pad "1" smd circle
			(at -0.40005 0)
			(size 0 0)
			(layers "F.Cu" "F.Mask" "F.Paste")
			(net "P3V3_AUX_USB_BUF")
		)
		(pad "2" smd circle
			(at 0.40005 0)
			(size 0 0)
			(layers "F.Cu" "F.Mask" "F.Paste")
			(net "GND")
		)
	)
	(footprint ""
		(layer "F.Cu")
		(at 139.43838 -38.049708)
		(property "Reference" "C1880"
			(at 0 0 0)
			(layer "F.SilkS")
			(hide yes)
			(effects
				(font
					(size 1.27 1.27)
				)
			)
		)
		(property "Value" ""
			(at 0 0 0)
			(layer "F.Fab")
			(effects
				(font
					(size 1.27 1.27)
				)
			)
		)
		(duplicate_pad_numbers_are_jumpers no)
		(fp_line
			(start -0.7874 -0.4064)
			(end 0.7874 -0.4064)
			(stroke
				(width 0.1524)
				(type default)
			)
			(layer "F.SilkS")
		)
		(fp_line
			(start -0.7874 0.4064)
			(end -0.7874 -0.4064)
			(stroke
				(width 0.1524)
				(type default)
			)
			(layer "F.SilkS")
		)
		(fp_line
			(start 0.7874 -0.4064)
			(end 0.7874 0.4064)
			(stroke
				(width 0.1524)
				(type default)
			)
			(layer "F.SilkS")
		)
		(fp_line
			(start 0.7874 0.4064)
			(end -0.7874 0.4064)
			(stroke
				(width 0.1524)
				(type default)
			)
			(layer "F.SilkS")
		)
		(fp_line
			(start -0.67945 -0.305054)
			(end -0.12065 -0.305054)
			(stroke
				(width 0.1)
				(type default)
			)
			(layer "F.Fab")
		)
		(fp_line
			(start -0.67945 0.3048)
			(end -0.67945 -0.305054)
			(stroke
				(width 0.1)
				(type default)
			)
			(layer "F.Fab")
		)
		(fp_line
			(start -0.12065 -0.305054)
			(end -0.12065 -0.2794)
			(stroke
				(width 0.1)
				(type default)
			)
			(layer "F.Fab")
		)
		(fp_line
			(start -0.12065 -0.2794)
			(end 0.12065 -0.2794)
			(stroke
				(width 0.1)
				(type default)
			)
			(layer "F.Fab")
		)
		(fp_line
			(start -0.12065 0.2794)
			(end -0.12065 0.3048)
			(stroke
				(width 0.1)
				(type default)
			)
			(layer "F.Fab")
		)
		(fp_line
			(start -0.12065 0.3048)
			(end -0.67945 0.3048)
			(stroke
				(width 0.1)
				(type default)
			)
			(layer "F.Fab")
		)
		(fp_line
			(start 0.120396 0.2794)
			(end -0.12065 0.2794)
			(stroke
				(width 0.1)
				(type default)
			)
			(layer "F.Fab")
		)
		(fp_line
			(start 0.120396 0.3048)
			(end 0.120396 0.2794)
			(stroke
				(width 0.1)
				(type default)
			)
			(layer "F.Fab")
		)
		(fp_line
			(start 0.12065 -0.3048)
			(end 0.67945 -0.3048)
			(stroke
				(width 0.1)
				(type default)
			)
			(layer "F.Fab")
		)
		(fp_line
			(start 0.12065 -0.2794)
			(end 0.12065 -0.3048)
			(stroke
				(width 0.1)
				(type default)
			)
			(layer "F.Fab")
		)
		(fp_line
			(start 0.67945 -0.3048)
			(end 0.67945 0.3048)
			(stroke
				(width 0.1)
				(type default)
			)
			(layer "F.Fab")
		)
		(fp_line
			(start 0.67945 0.3048)
			(end 0.120396 0.3048)
			(stroke
				(width 0.1)
				(type default)
			)
			(layer "F.Fab")
		)
		(pad "1" smd circle
			(at -0.40005 0)
			(size 0 0)
			(layers "F.Cu" "F.Mask" "F.Paste")
			(net "P3V3_AUX")
		)
		(pad "2" smd circle
			(at 0.40005 0)
			(size 0 0)
			(layers "F.Cu" "F.Mask" "F.Paste")
			(net "GND")
		)
	)
	(footprint ""
		(layer "F.Cu")
		(at 104.347264 -238.162592 -90)
		(property "Reference" "C431"
			(at 0 0 270)
			(layer "F.SilkS")
			(hide yes)
			(effects
				(font
					(size 1.27 1.27)
				)
			)
		)
		(property "Value" ""
			(at 0 0 270)
			(layer "F.Fab")
			(effects
				(font
					(size 1.27 1.27)
				)
			)
		)
		(duplicate_pad_numbers_are_jumpers no)
		(fp_line
			(start -0.7874 0.4064)
			(end -0.7874 -0.4064)
			(stroke
				(width 0.1524)
				(type default)
			)
			(layer "F.SilkS")
		)
		(fp_line
			(start 0.7874 0.4064)
			(end -0.7874 0.4064)
			(stroke
				(width 0.1524)
				(type default)
			)
			(layer "F.SilkS")
		)
		(fp_line
			(start -0.7874 -0.4064)
			(end 0.7874 -0.4064)
			(stroke
				(width 0.1524)
				(type default)
			)
			(layer "F.SilkS")
		)
		(fp_line
			(start 0.7874 -0.4064)
			(end 0.7874 0.4064)
			(stroke
				(width 0.1524)
				(type default)
			)
			(layer "F.SilkS")
		)
		(fp_line
			(start -0.67945 0.3048)
			(end -0.67945 -0.305054)
			(stroke
				(width 0.1)
				(type default)
			)
			(layer "F.Fab")
		)
		(fp_line
			(start -0.12065 0.3048)
			(end -0.67945 0.3048)
			(stroke
				(width 0.1)
				(type default)
			)
			(layer "F.Fab")
		)
		(fp_line
			(start 0.120396 0.3048)
			(end 0.120396 0.2794)
			(stroke
				(width 0.1)
				(type default)
			)
			(layer "F.Fab")
		)
		(fp_line
			(start 0.67945 0.3048)
			(end 0.120396 0.3048)
			(stroke
				(width 0.1)
				(type default)
			)
			(layer "F.Fab")
		)
		(fp_line
			(start -0.12065 0.2794)
			(end -0.12065 0.3048)
			(stroke
				(width 0.1)
				(type default)
			)
			(layer "F.Fab")
		)
		(fp_line
			(start 0.120396 0.2794)
			(end -0.12065 0.2794)
			(stroke
				(width 0.1)
				(type default)
			)
			(layer "F.Fab")
		)
		(fp_line
			(start -0.12065 -0.2794)
			(end 0.12065 -0.2794)
			(stroke
				(width 0.1)
				(type default)
			)
			(layer "F.Fab")
		)
		(fp_line
			(start 0.12065 -0.2794)
			(end 0.12065 -0.3048)
			(stroke
				(width 0.1)
				(type default)
			)
			(layer "F.Fab")
		)
		(fp_line
			(start 0.12065 -0.3048)
			(end 0.67945 -0.3048)
			(stroke
				(width 0.1)
				(type default)
			)
			(layer "F.Fab")
		)
		(fp_line
			(start 0.67945 -0.3048)
			(end 0.67945 0.3048)
			(stroke
				(width 0.1)
				(type default)
			)
			(layer "F.Fab")
		)
		(fp_line
			(start -0.67945 -0.305054)
			(end -0.12065 -0.305054)
			(stroke
				(width 0.1)
				(type default)
			)
			(layer "F.Fab")
		)
		(fp_line
			(start -0.12065 -0.305054)
			(end -0.12065 -0.2794)
			(stroke
				(width 0.1)
				(type default)
			)
			(layer "F.Fab")
		)
		(pad "1" smd circle
			(at -0.40005 0 270)
			(size 0 0)
			(layers "F.Cu" "F.Mask" "F.Paste")
			(net "PVCCFA_EHV_FIVRA_CPU1")
		)
		(pad "2" smd circle
			(at 0.40005 0 270)
			(size 0 0)
			(layers "F.Cu" "F.Mask" "F.Paste")
			(net "GND")
		)
	)
	(footprint ""
		(layer "F.Cu")
		(at 306.516024 -438.120536 -90)
		(property "Reference" "R4139"
			(at 0 0 270)
			(layer "F.SilkS")
			(hide yes)
			(effects
				(font
					(size 1.27 1.27)
				)
			)
		)
		(property "Value" ""
			(at 0 0 270)
			(layer "F.Fab")
			(effects
				(font
					(size 1.27 1.27)
				)
			)
		)
		(duplicate_pad_numbers_are_jumpers no)
		(fp_line
			(start -0.7874 0.4064)
			(end -0.7874 -0.4064)
			(stroke
				(width 0.1524)
				(type default)
			)
			(layer "F.SilkS")
		)
		(fp_line
			(start 0.7874 0.4064)
			(end -0.7874 0.4064)
			(stroke
				(width 0.1524)
				(type default)
			)
			(layer "F.SilkS")
		)
		(fp_line
			(start -0.7874 -0.4064)
			(end 0.7874 -0.4064)
			(stroke
				(width 0.1524)
				(type default)
			)
			(layer "F.SilkS")
		)
		(fp_line
			(start 0.7874 -0.4064)
			(end 0.7874 0.4064)
			(stroke
				(width 0.1524)
				(type default)
			)
			(layer "F.SilkS")
		)
		(fp_line
			(start -0.67945 0.3048)
			(end -0.67945 -0.305054)
			(stroke
				(width 0.1)
				(type default)
			)
			(layer "F.Fab")
		)
		(fp_line
			(start -0.12065 0.3048)
			(end -0.67945 0.3048)
			(stroke
				(width 0.1)
				(type default)
			)
			(layer "F.Fab")
		)
		(fp_line
			(start 0.120396 0.3048)
			(end 0.120396 0.2794)
			(stroke
				(width 0.1)
				(type default)
			)
			(layer "F.Fab")
		)
		(fp_line
			(start 0.67945 0.3048)
			(end 0.120396 0.3048)
			(stroke
				(width 0.1)
				(type default)
			)
			(layer "F.Fab")
		)
		(fp_line
			(start -0.12065 0.2794)
			(end -0.12065 0.3048)
			(stroke
				(width 0.1)
				(type default)
			)
			(layer "F.Fab")
		)
		(fp_line
			(start 0.120396 0.2794)
			(end -0.12065 0.2794)
			(stroke
				(width 0.1)
				(type default)
			)
			(layer "F.Fab")
		)
		(fp_line
			(start -0.12065 -0.2794)
			(end 0.12065 -0.2794)
			(stroke
				(width 0.1)
				(type default)
			)
			(layer "F.Fab")
		)
		(fp_line
			(start 0.12065 -0.2794)
			(end 0.12065 -0.3048)
			(stroke
				(width 0.1)
				(type default)
			)
			(layer "F.Fab")
		)
		(fp_line
			(start 0.12065 -0.3048)
			(end 0.67945 -0.3048)
			(stroke
				(width 0.1)
				(type default)
			)
			(layer "F.Fab")
		)
		(fp_line
			(start 0.67945 -0.3048)
			(end 0.67945 0.3048)
			(stroke
				(width 0.1)
				(type default)
			)
			(layer "F.Fab")
		)
		(fp_line
			(start -0.67945 -0.305054)
			(end -0.12065 -0.305054)
			(stroke
				(width 0.1)
				(type default)
			)
			(layer "F.Fab")
		)
		(fp_line
			(start -0.12065 -0.305054)
			(end -0.12065 -0.2794)
			(stroke
				(width 0.1)
				(type default)
			)
			(layer "F.Fab")
		)
		(pad "1" smd circle
			(at -0.40005 0 270)
			(size 0 0)
			(layers "F.Cu" "F.Mask" "F.Paste")
			(net "P3V3_AUX")
		)
		(pad "2" smd circle
			(at 0.40005 0 270)
			(size 0 0)
			(layers "F.Cu" "F.Mask" "F.Paste")
			(net "PRSNT_CABLE_GPU_A2")
		)
	)
	(footprint ""
		(layer "F.Cu")
		(at 170.23588 -439.003948 180)
		(property "Reference" "R3453"
			(at 0 0 180)
			(layer "F.SilkS")
			(hide yes)
			(effects
				(font
					(size 1.27 1.27)
				)
			)
		)
		(property "Value" ""
			(at 0 0 180)
			(layer "F.Fab")
			(effects
				(font
					(size 1.27 1.27)
				)
			)
		)
		(duplicate_pad_numbers_are_jumpers no)
		(fp_line
			(start 0.7874 0.4064)
			(end -0.7874 0.4064)
			(stroke
				(width 0.1524)
				(type default)
			)
			(layer "F.SilkS")
		)
		(fp_line
			(start 0.7874 -0.4064)
			(end 0.7874 0.4064)
			(stroke
				(width 0.1524)
				(type default)
			)
			(layer "F.SilkS")
		)
		(fp_line
			(start -0.7874 0.4064)
			(end -0.7874 -0.4064)
			(stroke
				(width 0.1524)
				(type default)
			)
			(layer "F.SilkS")
		)
		(fp_line
			(start -0.7874 -0.4064)
			(end 0.7874 -0.4064)
			(stroke
				(width 0.1524)
				(type default)
			)
			(layer "F.SilkS")
		)
		(fp_line
			(start 0.67945 0.3048)
			(end 0.120396 0.3048)
			(stroke
				(width 0.1)
				(type default)
			)
			(layer "F.Fab")
		)
		(fp_line
			(start 0.67945 -0.3048)
			(end 0.67945 0.3048)
			(stroke
				(width 0.1)
				(type default)
			)
			(layer "F.Fab")
		)
		(fp_line
			(start 0.12065 -0.2794)
			(end 0.12065 -0.3048)
			(stroke
				(width 0.1)
				(type default)
			)
			(layer "F.Fab")
		)
		(fp_line
			(start 0.12065 -0.3048)
			(end 0.67945 -0.3048)
			(stroke
				(width 0.1)
				(type default)
			)
			(layer "F.Fab")
		)
		(fp_line
			(start 0.120396 0.3048)
			(end 0.120396 0.2794)
			(stroke
				(width 0.1)
				(type default)
			)
			(layer "F.Fab")
		)
		(fp_line
			(start 0.120396 0.2794)
			(end -0.12065 0.2794)
			(stroke
				(width 0.1)
				(type default)
			)
			(layer "F.Fab")
		)
		(fp_line
			(start -0.12065 0.3048)
			(end -0.67945 0.3048)
			(stroke
				(width 0.1)
				(type default)
			)
			(layer "F.Fab")
		)
		(fp_line
			(start -0.12065 0.2794)
			(end -0.12065 0.3048)
			(stroke
				(width 0.1)
				(type default)
			)
			(layer "F.Fab")
		)
		(fp_line
			(start -0.12065 -0.2794)
			(end 0.12065 -0.2794)
			(stroke
				(width 0.1)
				(type default)
			)
			(layer "F.Fab")
		)
		(fp_line
			(start -0.12065 -0.305054)
			(end -0.12065 -0.2794)
			(stroke
				(width 0.1)
				(type default)
			)
			(layer "F.Fab")
		)
		(fp_line
			(start -0.67945 0.3048)
			(end -0.67945 -0.305054)
			(stroke
				(width 0.1)
				(type default)
			)
			(layer "F.Fab")
		)
		(fp_line
			(start -0.67945 -0.305054)
			(end -0.12065 -0.305054)
			(stroke
				(width 0.1)
				(type default)
			)
			(layer "F.Fab")
		)
		(pad "1" smd circle
			(at -0.40005 0 180)
			(size 0 0)
			(layers "F.Cu" "F.Mask" "F.Paste")
			(net "P3V3_AUX")
		)
		(pad "2" smd circle
			(at 0.40005 0 180)
			(size 0 0)
			(layers "F.Cu" "F.Mask" "F.Paste")
			(net "GPU_FPGA_BOOT_EN_BUF_R")
		)
	)
	(footprint ""
		(layer "F.Cu")
		(at 182.17388 -130.266948 -90)
		(property "Reference" "R284"
			(at 0 0 270)
			(layer "F.SilkS")
			(hide yes)
			(effects
				(font
					(size 1.27 1.27)
				)
			)
		)
		(property "Value" ""
			(at 0 0 270)
			(layer "F.Fab")
			(effects
				(font
					(size 1.27 1.27)
				)
			)
		)
		(duplicate_pad_numbers_are_jumpers no)
		(fp_line
			(start -0.7874 0.4064)
			(end -0.7874 -0.4064)
			(stroke
				(width 0.1524)
				(type default)
			)
			(layer "F.SilkS")
		)
		(fp_line
			(start 0.7874 0.4064)
			(end -0.7874 0.4064)
			(stroke
				(width 0.1524)
				(type default)
			)
			(layer "F.SilkS")
		)
		(fp_line
			(start -0.7874 -0.4064)
			(end 0.7874 -0.4064)
			(stroke
				(width 0.1524)
				(type default)
			)
			(layer "F.SilkS")
		)
		(fp_line
			(start 0.7874 -0.4064)
			(end 0.7874 0.4064)
			(stroke
				(width 0.1524)
				(type default)
			)
			(layer "F.SilkS")
		)
		(fp_line
			(start -0.67945 0.3048)
			(end -0.67945 -0.305054)
			(stroke
				(width 0.1)
				(type default)
			)
			(layer "F.Fab")
		)
		(fp_line
			(start -0.12065 0.3048)
			(end -0.67945 0.3048)
			(stroke
				(width 0.1)
				(type default)
			)
			(layer "F.Fab")
		)
		(fp_line
			(start 0.120396 0.3048)
			(end 0.120396 0.2794)
			(stroke
				(width 0.1)
				(type default)
			)
			(layer "F.Fab")
		)
		(fp_line
			(start 0.67945 0.3048)
			(end 0.120396 0.3048)
			(stroke
				(width 0.1)
				(type default)
			)
			(layer "F.Fab")
		)
		(fp_line
			(start -0.12065 0.2794)
			(end -0.12065 0.3048)
			(stroke
				(width 0.1)
				(type default)
			)
			(layer "F.Fab")
		)
		(fp_line
			(start 0.120396 0.2794)
			(end -0.12065 0.2794)
			(stroke
				(width 0.1)
				(type default)
			)
			(layer "F.Fab")
		)
		(fp_line
			(start -0.12065 -0.2794)
			(end 0.12065 -0.2794)
			(stroke
				(width 0.1)
				(type default)
			)
			(layer "F.Fab")
		)
		(fp_line
			(start 0.12065 -0.2794)
			(end 0.12065 -0.3048)
			(stroke
				(width 0.1)
				(type default)
			)
			(layer "F.Fab")
		)
		(fp_line
			(start 0.12065 -0.3048)
			(end 0.67945 -0.3048)
			(stroke
				(width 0.1)
				(type default)
			)
			(layer "F.Fab")
		)
		(fp_line
			(start 0.67945 -0.3048)
			(end 0.67945 0.3048)
			(stroke
				(width 0.1)
				(type default)
			)
			(layer "F.Fab")
		)
		(fp_line
			(start -0.67945 -0.305054)
			(end -0.12065 -0.305054)
			(stroke
				(width 0.1)
				(type default)
			)
			(layer "F.Fab")
		)
		(fp_line
			(start -0.12065 -0.305054)
			(end -0.12065 -0.2794)
			(stroke
				(width 0.1)
				(type default)
			)
			(layer "F.Fab")
		)
		(pad "1" smd circle
			(at -0.40005 0 270)
			(size 0 0)
			(layers "F.Cu" "F.Mask" "F.Paste")
			(net "P3V3_AUX")
		)
		(pad "2" smd circle
			(at 0.40005 0 270)
			(size 0 0)
			(layers "F.Cu" "F.Mask" "F.Paste")
			(net "FM_CPU0_PKGID1")
		)
	)
	(footprint ""
		(layer "F.Cu")
		(at 91.754198 -402.371052 -90)
		(property "Reference" "C739"
			(at 0 0 270)
			(layer "F.SilkS")
			(hide yes)
			(effects
				(font
					(size 1.27 1.27)
				)
			)
		)
		(property "Value" ""
			(at 0 0 270)
			(layer "F.Fab")
			(effects
				(font
					(size 1.27 1.27)
				)
			)
		)
		(duplicate_pad_numbers_are_jumpers no)
		(fp_line
			(start -0.299974 0.150114)
			(end -0.299974 -0.150114)
			(stroke
				(width 0.1)
				(type default)
			)
			(layer "F.Fab")
		)
		(fp_line
			(start 0.299974 0.150114)
			(end -0.299974 0.150114)
			(stroke
				(width 0.1)
				(type default)
			)
			(layer "F.Fab")
		)
		(fp_line
			(start -0.299974 -0.150114)
			(end 0.299974 -0.150114)
			(stroke
				(width 0.1)
				(type default)
			)
			(layer "F.Fab")
		)
		(fp_line
			(start 0.299974 -0.150114)
			(end 0.299974 0.150114)
			(stroke
				(width 0.1)
				(type default)
			)
			(layer "F.Fab")
		)
		(pad "1" smd rect
			(at -0.2667 0 270)
			(size 0.3048 0.381)
			(layers "F.Cu" "F.Mask" "F.Paste")
			(net "P5E_CPU1_PE0_TX_C_DP<1>")
		)
		(pad "2" smd rect
			(at 0.2667 0 270)
			(size 0.3048 0.381)
			(layers "F.Cu" "F.Mask" "F.Paste")
			(net "P5E_CPU1_PE0_TX_DP<1>")
		)
	)
	(footprint ""
		(layer "F.Cu")
		(at 122.35688 -99.405948)
		(property "Reference" "R4397"
			(at 0 0 0)
			(layer "F.SilkS")
			(hide yes)
			(effects
				(font
					(size 1.27 1.27)
				)
			)
		)
		(property "Value" ""
			(at 0 0 0)
			(layer "F.Fab")
			(effects
				(font
					(size 1.27 1.27)
				)
			)
		)
		(duplicate_pad_numbers_are_jumpers no)
		(fp_line
			(start -0.7874 -0.4064)
			(end 0.7874 -0.4064)
			(stroke
				(width 0.1524)
				(type default)
			)
			(layer "F.SilkS")
		)
		(fp_line
			(start -0.7874 0.4064)
			(end -0.7874 -0.4064)
			(stroke
				(width 0.1524)
				(type default)
			)
			(layer "F.SilkS")
		)
		(fp_line
			(start 0.7874 -0.4064)
			(end 0.7874 0.4064)
			(stroke
				(width 0.1524)
				(type default)
			)
			(layer "F.SilkS")
		)
		(fp_line
			(start 0.7874 0.4064)
			(end -0.7874 0.4064)
			(stroke
				(width 0.1524)
				(type default)
			)
			(layer "F.SilkS")
		)
		(fp_line
			(start -0.67945 -0.305054)
			(end -0.12065 -0.305054)
			(stroke
				(width 0.1)
				(type default)
			)
			(layer "F.Fab")
		)
		(fp_line
			(start -0.67945 0.3048)
			(end -0.67945 -0.305054)
			(stroke
				(width 0.1)
				(type default)
			)
			(layer "F.Fab")
		)
		(fp_line
			(start -0.12065 -0.305054)
			(end -0.12065 -0.2794)
			(stroke
				(width 0.1)
				(type default)
			)
			(layer "F.Fab")
		)
		(fp_line
			(start -0.12065 -0.2794)
			(end 0.12065 -0.2794)
			(stroke
				(width 0.1)
				(type default)
			)
			(layer "F.Fab")
		)
		(fp_line
			(start -0.12065 0.2794)
			(end -0.12065 0.3048)
			(stroke
				(width 0.1)
				(type default)
			)
			(layer "F.Fab")
		)
		(fp_line
			(start -0.12065 0.3048)
			(end -0.67945 0.3048)
			(stroke
				(width 0.1)
				(type default)
			)
			(layer "F.Fab")
		)
		(fp_line
			(start 0.120396 0.2794)
			(end -0.12065 0.2794)
			(stroke
				(width 0.1)
				(type default)
			)
			(layer "F.Fab")
		)
		(fp_line
			(start 0.120396 0.3048)
			(end 0.120396 0.2794)
			(stroke
				(width 0.1)
				(type default)
			)
			(layer "F.Fab")
		)
		(fp_line
			(start 0.12065 -0.3048)
			(end 0.67945 -0.3048)
			(stroke
				(width 0.1)
				(type default)
			)
			(layer "F.Fab")
		)
		(fp_line
			(start 0.12065 -0.2794)
			(end 0.12065 -0.3048)
			(stroke
				(width 0.1)
				(type default)
			)
			(layer "F.Fab")
		)
		(fp_line
			(start 0.67945 -0.3048)
			(end 0.67945 0.3048)
			(stroke
				(width 0.1)
				(type default)
			)
			(layer "F.Fab")
		)
		(fp_line
			(start 0.67945 0.3048)
			(end 0.120396 0.3048)
			(stroke
				(width 0.1)
				(type default)
			)
			(layer "F.Fab")
		)
		(pad "1" smd circle
			(at -0.40005 0)
			(size 0 0)
			(layers "F.Cu" "F.Mask" "F.Paste")
			(net "H_CPU0_THERMTRIP_N")
		)
		(pad "2" smd circle
			(at 0.40005 0)
			(size 0 0)
			(layers "F.Cu" "F.Mask" "F.Paste")
			(net "H_CPU0_THERMTRIP_R_N")
		)
	)
	(footprint ""
		(layer "F.Cu")
		(at 335.754726 -16.200628 -90)
		(property "Reference" "R1215"
			(at 0 0 270)
			(layer "F.SilkS")
			(hide yes)
			(effects
				(font
					(size 1.27 1.27)
				)
			)
		)
		(property "Value" ""
			(at 0 0 270)
			(layer "F.Fab")
			(effects
				(font
					(size 1.27 1.27)
				)
			)
		)
		(duplicate_pad_numbers_are_jumpers no)
		(fp_line
			(start -0.7874 0.4064)
			(end -0.7874 -0.4064)
			(stroke
				(width 0.1524)
				(type default)
			)
			(layer "F.SilkS")
		)
		(fp_line
			(start 0.7874 0.4064)
			(end -0.7874 0.4064)
			(stroke
				(width 0.1524)
				(type default)
			)
			(layer "F.SilkS")
		)
		(fp_line
			(start -0.7874 -0.4064)
			(end 0.7874 -0.4064)
			(stroke
				(width 0.1524)
				(type default)
			)
			(layer "F.SilkS")
		)
		(fp_line
			(start 0.7874 -0.4064)
			(end 0.7874 0.4064)
			(stroke
				(width 0.1524)
				(type default)
			)
			(layer "F.SilkS")
		)
		(fp_line
			(start -0.67945 0.3048)
			(end -0.67945 -0.305054)
			(stroke
				(width 0.1)
				(type default)
			)
			(layer "F.Fab")
		)
		(fp_line
			(start -0.12065 0.3048)
			(end -0.67945 0.3048)
			(stroke
				(width 0.1)
				(type default)
			)
			(layer "F.Fab")
		)
		(fp_line
			(start 0.120396 0.3048)
			(end 0.120396 0.2794)
			(stroke
				(width 0.1)
				(type default)
			)
			(layer "F.Fab")
		)
		(fp_line
			(start 0.67945 0.3048)
			(end 0.120396 0.3048)
			(stroke
				(width 0.1)
				(type default)
			)
			(layer "F.Fab")
		)
		(fp_line
			(start -0.12065 0.2794)
			(end -0.12065 0.3048)
			(stroke
				(width 0.1)
				(type default)
			)
			(layer "F.Fab")
		)
		(fp_line
			(start 0.120396 0.2794)
			(end -0.12065 0.2794)
			(stroke
				(width 0.1)
				(type default)
			)
			(layer "F.Fab")
		)
		(fp_line
			(start -0.12065 -0.2794)
			(end 0.12065 -0.2794)
			(stroke
				(width 0.1)
				(type default)
			)
			(layer "F.Fab")
		)
		(fp_line
			(start 0.12065 -0.2794)
			(end 0.12065 -0.3048)
			(stroke
				(width 0.1)
				(type default)
			)
			(layer "F.Fab")
		)
		(fp_line
			(start 0.12065 -0.3048)
			(end 0.67945 -0.3048)
			(stroke
				(width 0.1)
				(type default)
			)
			(layer "F.Fab")
		)
		(fp_line
			(start 0.67945 -0.3048)
			(end 0.67945 0.3048)
			(stroke
				(width 0.1)
				(type default)
			)
			(layer "F.Fab")
		)
		(fp_line
			(start -0.67945 -0.305054)
			(end -0.12065 -0.305054)
			(stroke
				(width 0.1)
				(type default)
			)
			(layer "F.Fab")
		)
		(fp_line
			(start -0.12065 -0.305054)
			(end -0.12065 -0.2794)
			(stroke
				(width 0.1)
				(type default)
			)
			(layer "F.Fab")
		)
		(pad "1" smd circle
			(at -0.40005 0 270)
			(size 0 0)
			(layers "F.Cu" "F.Mask" "F.Paste")
			(net "IRQ_ESPI_LPC_SERIRQ_ALERT_N")
		)
		(pad "2" smd circle
			(at 0.40005 0 270)
			(size 0 0)
			(layers "F.Cu" "F.Mask" "F.Paste")
			(net "IRQ_ESPI_LPC_SERIRQ_ALERT_R_N")
		)
	)
	(footprint ""
		(layer "F.Cu")
		(at 114.660934 -113.157762 -90)
		(property "Reference" "U304"
			(at -0.219456 -2.976626 0)
			(unlocked yes)
			(layer "F.SilkS")
			(effects
				(font
					(size 0.7874 0.5842)
					(thickness 0.1524)
				)
				(justify left)
			)
		)
		(property "Value" ""
			(at 0 0 270)
			(layer "F.Fab")
			(effects
				(font
					(size 1.27 1.27)
				)
			)
		)
		(duplicate_pad_numbers_are_jumpers no)
		(fp_line
			(start -2.0066 2.5527)
			(end -2.0066 -2.5527)
			(stroke
				(width 0.1524)
				(type default)
			)
			(layer "F.SilkS")
		)
		(fp_line
			(start 2.0066 2.5527)
			(end -2.0066 2.5527)
			(stroke
				(width 0.1524)
				(type default)
			)
			(layer "F.SilkS")
		)
		(fp_line
			(start 0 -1.9812)
			(end 0.5715 -2.5527)
			(stroke
				(width 0.1524)
				(type default)
			)
			(layer "F.SilkS")
		)
		(fp_line
			(start -2.0066 -2.5527)
			(end -0.5715 -2.5527)
			(stroke
				(width 0.1524)
				(type default)
			)
			(layer "F.SilkS")
		)
		(fp_line
			(start -0.5715 -2.5527)
			(end 0 -1.9812)
			(stroke
				(width 0.1524)
				(type default)
			)
			(layer "F.SilkS")
		)
		(fp_line
			(start 0.5715 -2.5527)
			(end 2.0066 -2.5527)
			(stroke
				(width 0.1524)
				(type default)
			)
			(layer "F.SilkS")
		)
		(fp_line
			(start 2.0066 -2.5527)
			(end 2.0066 2.5527)
			(stroke
				(width 0.1524)
				(type default)
			)
			(layer "F.SilkS")
		)
		(fp_poly
			(pts
				(xy -4.36372 -2.233168) (xy -3.81 -1.905) (xy -4.36372 -1.608328)
			)
			(stroke
				(width 0)
				(type default)
			)
			(fill yes)
			(layer "F.SilkS")
		)
		(fp_line
			(start -2.249932 2.549906)
			(end -2.249932 -2.549906)
			(stroke
				(width 0.1)
				(type default)
			)
			(layer "F.Fab")
		)
		(fp_line
			(start 2.249932 2.549906)
			(end -2.249932 2.549906)
			(stroke
				(width 0.1)
				(type default)
			)
			(layer "F.Fab")
		)
		(fp_line
			(start -2.249932 -2.549906)
			(end 2.249932 -2.549906)
			(stroke
				(width 0.1)
				(type default)
			)
			(layer "F.Fab")
		)
		(fp_line
			(start 2.249932 -2.549906)
			(end 2.249932 2.549906)
			(stroke
				(width 0.1)
				(type default)
			)
			(layer "F.Fab")
		)
		(fp_poly
			(pts
				(xy -4.36372 -1.608328) (xy -4.36372 -2.233168) (xy -3.81 -1.905)
			)
			(stroke
				(width 0)
				(type default)
			)
			(fill yes)
			(layer "F.Fab")
		)
		(pad "1" smd rect
			(at -2.921 -1.949958 180)
			(size 0.3556 1.4986)
			(layers "F.Cu" "F.Mask" "F.Paste")
			(net "PD_GTL2014_BMC_JTAG_DIR_0")
		)
		(pad "2" smd rect
			(at -2.921 -1.299972 180)
			(size 0.3556 1.4986)
			(layers "F.Cu" "F.Mask" "F.Paste")
			(net "RST_CPU0_DRAM_GH_PLD_N")
		)
		(pad "3" smd rect
			(at -2.921 -0.649986 180)
			(size 0.3556 1.4986)
			(layers "F.Cu" "F.Mask" "F.Paste")
			(net "RST_CPU0_DRAM_EF_PLD_N")
		)
		(pad "4" smd rect
			(at -2.921 0 180)
			(size 0.3556 1.4986)
			(layers "F.Cu" "F.Mask" "F.Paste")
			(net "P0V62_CPU0_RST_DDR_VREF")
		)
		(pad "5" smd rect
			(at -2.921 0.649986 180)
			(size 0.3556 1.4986)
			(layers "F.Cu" "F.Mask" "F.Paste")
			(net "RST_CPU0_DRAM_CD_PLD_N")
		)
		(pad "6" smd rect
			(at -2.921 1.299972 180)
			(size 0.3556 1.4986)
			(layers "F.Cu" "F.Mask" "F.Paste")
			(net "RST_CPU0_DRAM_AB_PLD_N")
		)
		(pad "7" smd rect
			(at -2.921 1.949958 180)
			(size 0.3556 1.4986)
			(layers "F.Cu" "F.Mask" "F.Paste")
			(net "GND")
		)
		(pad "8" smd rect
			(at 2.921 1.949958 180)
			(size 0.3556 1.4986)
			(layers "F.Cu" "F.Mask" "F.Paste")
			(net "GND")
		)
		(pad "9" smd rect
			(at 2.921 1.299972 180)
			(size 0.3556 1.4986)
			(layers "F.Cu" "F.Mask" "F.Paste")
			(net "RST_CPU0_DRAM_AB_PLD_LVT3_R_N")
		)
		(pad "10" smd rect
			(at 2.921 0.649986 180)
			(size 0.3556 1.4986)
			(layers "F.Cu" "F.Mask" "F.Paste")
			(net "RST_CPU0_DRAM_CD_PLD_LVT3_R_N")
		)
		(pad "11" smd rect
			(at 2.921 0 180)
			(size 0.3556 1.4986)
			(layers "F.Cu" "F.Mask" "F.Paste")
			(net "GND")
		)
		(pad "12" smd rect
			(at 2.921 -0.649986 180)
			(size 0.3556 1.4986)
			(layers "F.Cu" "F.Mask" "F.Paste")
			(net "RST_CPU0_DRAM_EF_PLD_LVT3_R_N")
		)
		(pad "13" smd rect
			(at 2.921 -1.299972 180)
			(size 0.3556 1.4986)
			(layers "F.Cu" "F.Mask" "F.Paste")
			(net "RST_CPU0_DRAM_GH_PLD_LVT3_R_N")
		)
		(pad "14" smd rect
			(at 2.921 -1.949958 180)
			(size 0.3556 1.4986)
			(layers "F.Cu" "F.Mask" "F.Paste")
			(net "P3V3_AUX")
		)
	)
	(footprint ""
		(layer "F.Cu")
		(at 461.593946 -107.043728)
		(property "Reference" "C592"
			(at 0 0 0)
			(layer "F.SilkS")
			(hide yes)
			(effects
				(font
					(size 1.27 1.27)
				)
			)
		)
		(property "Value" ""
			(at 0 0 0)
			(layer "F.Fab")
			(effects
				(font
					(size 1.27 1.27)
				)
			)
		)
		(duplicate_pad_numbers_are_jumpers no)
		(fp_line
			(start -0.7874 -0.4064)
			(end 0.7874 -0.4064)
			(stroke
				(width 0.1524)
				(type default)
			)
			(layer "F.SilkS")
		)
		(fp_line
			(start -0.7874 0.4064)
			(end -0.7874 -0.4064)
			(stroke
				(width 0.1524)
				(type default)
			)
			(layer "F.SilkS")
		)
		(fp_line
			(start 0.7874 -0.4064)
			(end 0.7874 0.4064)
			(stroke
				(width 0.1524)
				(type default)
			)
			(layer "F.SilkS")
		)
		(fp_line
			(start 0.7874 0.4064)
			(end -0.7874 0.4064)
			(stroke
				(width 0.1524)
				(type default)
			)
			(layer "F.SilkS")
		)
		(fp_line
			(start -0.67945 -0.305054)
			(end -0.12065 -0.305054)
			(stroke
				(width 0.1)
				(type default)
			)
			(layer "F.Fab")
		)
		(fp_line
			(start -0.67945 0.3048)
			(end -0.67945 -0.305054)
			(stroke
				(width 0.1)
				(type default)
			)
			(layer "F.Fab")
		)
		(fp_line
			(start -0.12065 -0.305054)
			(end -0.12065 -0.2794)
			(stroke
				(width 0.1)
				(type default)
			)
			(layer "F.Fab")
		)
		(fp_line
			(start -0.12065 -0.2794)
			(end 0.12065 -0.2794)
			(stroke
				(width 0.1)
				(type default)
			)
			(layer "F.Fab")
		)
		(fp_line
			(start -0.12065 0.2794)
			(end -0.12065 0.3048)
			(stroke
				(width 0.1)
				(type default)
			)
			(layer "F.Fab")
		)
		(fp_line
			(start -0.12065 0.3048)
			(end -0.67945 0.3048)
			(stroke
				(width 0.1)
				(type default)
			)
			(layer "F.Fab")
		)
		(fp_line
			(start 0.120396 0.2794)
			(end -0.12065 0.2794)
			(stroke
				(width 0.1)
				(type default)
			)
			(layer "F.Fab")
		)
		(fp_line
			(start 0.120396 0.3048)
			(end 0.120396 0.2794)
			(stroke
				(width 0.1)
				(type default)
			)
			(layer "F.Fab")
		)
		(fp_line
			(start 0.12065 -0.3048)
			(end 0.67945 -0.3048)
			(stroke
				(width 0.1)
				(type default)
			)
			(layer "F.Fab")
		)
		(fp_line
			(start 0.12065 -0.2794)
			(end 0.12065 -0.3048)
			(stroke
				(width 0.1)
				(type default)
			)
			(layer "F.Fab")
		)
		(fp_line
			(start 0.67945 -0.3048)
			(end 0.67945 0.3048)
			(stroke
				(width 0.1)
				(type default)
			)
			(layer "F.Fab")
		)
		(fp_line
			(start 0.67945 0.3048)
			(end 0.120396 0.3048)
			(stroke
				(width 0.1)
				(type default)
			)
			(layer "F.Fab")
		)
		(pad "1" smd circle
			(at -0.40005 0)
			(size 0 0)
			(layers "F.Cu" "F.Mask" "F.Paste")
			(net "P3V3_AUX")
		)
		(pad "2" smd circle
			(at 0.40005 0)
			(size 0 0)
			(layers "F.Cu" "F.Mask" "F.Paste")
			(net "GND")
		)
	)
	(footprint ""
		(layer "F.Cu")
		(at 194.22618 -80.627728)
		(property "Reference" "R366"
			(at 0 0 0)
			(layer "F.SilkS")
			(hide yes)
			(effects
				(font
					(size 1.27 1.27)
				)
			)
		)
		(property "Value" ""
			(at 0 0 0)
			(layer "F.Fab")
			(effects
				(font
					(size 1.27 1.27)
				)
			)
		)
		(duplicate_pad_numbers_are_jumpers no)
		(fp_line
			(start -0.7874 -0.4064)
			(end 0.7874 -0.4064)
			(stroke
				(width 0.1524)
				(type default)
			)
			(layer "F.SilkS")
		)
		(fp_line
			(start -0.7874 0.4064)
			(end -0.7874 -0.4064)
			(stroke
				(width 0.1524)
				(type default)
			)
			(layer "F.SilkS")
		)
		(fp_line
			(start 0.7874 -0.4064)
			(end 0.7874 0.4064)
			(stroke
				(width 0.1524)
				(type default)
			)
			(layer "F.SilkS")
		)
		(fp_line
			(start 0.7874 0.4064)
			(end -0.7874 0.4064)
			(stroke
				(width 0.1524)
				(type default)
			)
			(layer "F.SilkS")
		)
		(fp_line
			(start -0.67945 -0.305054)
			(end -0.12065 -0.305054)
			(stroke
				(width 0.1)
				(type default)
			)
			(layer "F.Fab")
		)
		(fp_line
			(start -0.67945 0.3048)
			(end -0.67945 -0.305054)
			(stroke
				(width 0.1)
				(type default)
			)
			(layer "F.Fab")
		)
		(fp_line
			(start -0.12065 -0.305054)
			(end -0.12065 -0.2794)
			(stroke
				(width 0.1)
				(type default)
			)
			(layer "F.Fab")
		)
		(fp_line
			(start -0.12065 -0.2794)
			(end 0.12065 -0.2794)
			(stroke
				(width 0.1)
				(type default)
			)
			(layer "F.Fab")
		)
		(fp_line
			(start -0.12065 0.2794)
			(end -0.12065 0.3048)
			(stroke
				(width 0.1)
				(type default)
			)
			(layer "F.Fab")
		)
		(fp_line
			(start -0.12065 0.3048)
			(end -0.67945 0.3048)
			(stroke
				(width 0.1)
				(type default)
			)
			(layer "F.Fab")
		)
		(fp_line
			(start 0.120396 0.2794)
			(end -0.12065 0.2794)
			(stroke
				(width 0.1)
				(type default)
			)
			(layer "F.Fab")
		)
		(fp_line
			(start 0.120396 0.3048)
			(end 0.120396 0.2794)
			(stroke
				(width 0.1)
				(type default)
			)
			(layer "F.Fab")
		)
		(fp_line
			(start 0.12065 -0.3048)
			(end 0.67945 -0.3048)
			(stroke
				(width 0.1)
				(type default)
			)
			(layer "F.Fab")
		)
		(fp_line
			(start 0.12065 -0.2794)
			(end 0.12065 -0.3048)
			(stroke
				(width 0.1)
				(type default)
			)
			(layer "F.Fab")
		)
		(fp_line
			(start 0.67945 -0.3048)
			(end 0.67945 0.3048)
			(stroke
				(width 0.1)
				(type default)
			)
			(layer "F.Fab")
		)
		(fp_line
			(start 0.67945 0.3048)
			(end 0.120396 0.3048)
			(stroke
				(width 0.1)
				(type default)
			)
			(layer "F.Fab")
		)
		(pad "1" smd circle
			(at -0.40005 0)
			(size 0 0)
			(layers "F.Cu" "F.Mask" "F.Paste")
			(net "P3V3_AUX")
		)
		(pad "2" smd circle
			(at 0.40005 0)
			(size 0 0)
			(layers "F.Cu" "F.Mask" "F.Paste")
			(net "LED_CPU_RMCA_CATERR")
		)
	)
	(footprint ""
		(layer "F.Cu")
		(at 419.1762 -16.088614 90)
		(property "Reference" "C858"
			(at 0 0 90)
			(layer "F.SilkS")
			(hide yes)
			(effects
				(font
					(size 1.27 1.27)
				)
			)
		)
		(property "Value" ""
			(at 0 0 90)
			(layer "F.Fab")
			(effects
				(font
					(size 1.27 1.27)
				)
			)
		)
		(duplicate_pad_numbers_are_jumpers no)
		(fp_line
			(start 0.299974 -0.150114)
			(end 0.299974 0.150114)
			(stroke
				(width 0.1)
				(type default)
			)
			(layer "F.Fab")
		)
		(fp_line
			(start -0.299974 -0.150114)
			(end 0.299974 -0.150114)
			(stroke
				(width 0.1)
				(type default)
			)
			(layer "F.Fab")
		)
		(fp_line
			(start 0.299974 0.150114)
			(end -0.299974 0.150114)
			(stroke
				(width 0.1)
				(type default)
			)
			(layer "F.Fab")
		)
		(fp_line
			(start -0.299974 0.150114)
			(end -0.299974 -0.150114)
			(stroke
				(width 0.1)
				(type default)
			)
			(layer "F.Fab")
		)
		(pad "1" smd rect
			(at -0.2667 0 90)
			(size 0.3048 0.381)
			(layers "F.Cu" "F.Mask" "F.Paste")
			(net "P5E_CPU0_PE1_TX_C_DN<5>")
		)
		(pad "2" smd rect
			(at 0.2667 0 90)
			(size 0.3048 0.381)
			(layers "F.Cu" "F.Mask" "F.Paste")
			(net "P5E_CPU0_PE1_TX_DN<5>")
		)
	)
	(footprint ""
		(layer "F.Cu")
		(at 22.809454 -112.399826)
		(property "Reference" "R3671"
			(at 0 0 0)
			(layer "F.SilkS")
			(hide yes)
			(effects
				(font
					(size 1.27 1.27)
				)
			)
		)
		(property "Value" ""
			(at 0 0 0)
			(layer "F.Fab")
			(effects
				(font
					(size 1.27 1.27)
				)
			)
		)
		(duplicate_pad_numbers_are_jumpers no)
		(fp_line
			(start -0.7874 -0.4064)
			(end 0.7874 -0.4064)
			(stroke
				(width 0.1524)
				(type default)
			)
			(layer "F.SilkS")
		)
		(fp_line
			(start -0.7874 0.4064)
			(end -0.7874 -0.4064)
			(stroke
				(width 0.1524)
				(type default)
			)
			(layer "F.SilkS")
		)
		(fp_line
			(start 0.7874 -0.4064)
			(end 0.7874 0.4064)
			(stroke
				(width 0.1524)
				(type default)
			)
			(layer "F.SilkS")
		)
		(fp_line
			(start 0.7874 0.4064)
			(end -0.7874 0.4064)
			(stroke
				(width 0.1524)
				(type default)
			)
			(layer "F.SilkS")
		)
		(fp_line
			(start -0.67945 -0.305054)
			(end -0.12065 -0.305054)
			(stroke
				(width 0.1)
				(type default)
			)
			(layer "F.Fab")
		)
		(fp_line
			(start -0.67945 0.3048)
			(end -0.67945 -0.305054)
			(stroke
				(width 0.1)
				(type default)
			)
			(layer "F.Fab")
		)
		(fp_line
			(start -0.12065 -0.305054)
			(end -0.12065 -0.2794)
			(stroke
				(width 0.1)
				(type default)
			)
			(layer "F.Fab")
		)
		(fp_line
			(start -0.12065 -0.2794)
			(end 0.12065 -0.2794)
			(stroke
				(width 0.1)
				(type default)
			)
			(layer "F.Fab")
		)
		(fp_line
			(start -0.12065 0.2794)
			(end -0.12065 0.3048)
			(stroke
				(width 0.1)
				(type default)
			)
			(layer "F.Fab")
		)
		(fp_line
			(start -0.12065 0.3048)
			(end -0.67945 0.3048)
			(stroke
				(width 0.1)
				(type default)
			)
			(layer "F.Fab")
		)
		(fp_line
			(start 0.120396 0.2794)
			(end -0.12065 0.2794)
			(stroke
				(width 0.1)
				(type default)
			)
			(layer "F.Fab")
		)
		(fp_line
			(start 0.120396 0.3048)
			(end 0.120396 0.2794)
			(stroke
				(width 0.1)
				(type default)
			)
			(layer "F.Fab")
		)
		(fp_line
			(start 0.12065 -0.3048)
			(end 0.67945 -0.3048)
			(stroke
				(width 0.1)
				(type default)
			)
			(layer "F.Fab")
		)
		(fp_line
			(start 0.12065 -0.2794)
			(end 0.12065 -0.3048)
			(stroke
				(width 0.1)
				(type default)
			)
			(layer "F.Fab")
		)
		(fp_line
			(start 0.67945 -0.3048)
			(end 0.67945 0.3048)
			(stroke
				(width 0.1)
				(type default)
			)
			(layer "F.Fab")
		)
		(fp_line
			(start 0.67945 0.3048)
			(end 0.120396 0.3048)
			(stroke
				(width 0.1)
				(type default)
			)
			(layer "F.Fab")
		)
		(pad "1" smd circle
			(at -0.40005 0)
			(size 0 0)
			(layers "F.Cu" "F.Mask" "F.Paste")
			(net "SMB_VR_3V3AUX_SDA_R1")
		)
		(pad "2" smd circle
			(at 0.40005 0)
			(size 0 0)
			(layers "F.Cu" "F.Mask" "F.Paste")
			(net "SMB_SEN_TIC_3V3AUX_SDA")
		)
	)
	(footprint ""
		(layer "F.Cu")
		(at 104.8258 -407.289 180)
		(property "Reference" "C2372"
			(at 0 0 180)
			(layer "F.SilkS")
			(hide yes)
			(effects
				(font
					(size 1.27 1.27)
				)
			)
		)
		(property "Value" ""
			(at 0 0 180)
			(layer "F.Fab")
			(effects
				(font
					(size 1.27 1.27)
				)
			)
		)
		(duplicate_pad_numbers_are_jumpers no)
		(fp_line
			(start 0.7874 0.4064)
			(end -0.7874 0.4064)
			(stroke
				(width 0.1524)
				(type default)
			)
			(layer "F.SilkS")
		)
		(fp_line
			(start 0.7874 -0.4064)
			(end 0.7874 0.4064)
			(stroke
				(width 0.1524)
				(type default)
			)
			(layer "F.SilkS")
		)
		(fp_line
			(start -0.7874 0.4064)
			(end -0.7874 -0.4064)
			(stroke
				(width 0.1524)
				(type default)
			)
			(layer "F.SilkS")
		)
		(fp_line
			(start -0.7874 -0.4064)
			(end 0.7874 -0.4064)
			(stroke
				(width 0.1524)
				(type default)
			)
			(layer "F.SilkS")
		)
		(fp_line
			(start 0.67945 0.3048)
			(end 0.120396 0.3048)
			(stroke
				(width 0.1)
				(type default)
			)
			(layer "F.Fab")
		)
		(fp_line
			(start 0.67945 -0.3048)
			(end 0.67945 0.3048)
			(stroke
				(width 0.1)
				(type default)
			)
			(layer "F.Fab")
		)
		(fp_line
			(start 0.12065 -0.2794)
			(end 0.12065 -0.3048)
			(stroke
				(width 0.1)
				(type default)
			)
			(layer "F.Fab")
		)
		(fp_line
			(start 0.12065 -0.3048)
			(end 0.67945 -0.3048)
			(stroke
				(width 0.1)
				(type default)
			)
			(layer "F.Fab")
		)
		(fp_line
			(start 0.120396 0.3048)
			(end 0.120396 0.2794)
			(stroke
				(width 0.1)
				(type default)
			)
			(layer "F.Fab")
		)
		(fp_line
			(start 0.120396 0.2794)
			(end -0.12065 0.2794)
			(stroke
				(width 0.1)
				(type default)
			)
			(layer "F.Fab")
		)
		(fp_line
			(start -0.12065 0.3048)
			(end -0.67945 0.3048)
			(stroke
				(width 0.1)
				(type default)
			)
			(layer "F.Fab")
		)
		(fp_line
			(start -0.12065 0.2794)
			(end -0.12065 0.3048)
			(stroke
				(width 0.1)
				(type default)
			)
			(layer "F.Fab")
		)
		(fp_line
			(start -0.12065 -0.2794)
			(end 0.12065 -0.2794)
			(stroke
				(width 0.1)
				(type default)
			)
			(layer "F.Fab")
		)
		(fp_line
			(start -0.12065 -0.305054)
			(end -0.12065 -0.2794)
			(stroke
				(width 0.1)
				(type default)
			)
			(layer "F.Fab")
		)
		(fp_line
			(start -0.67945 0.3048)
			(end -0.67945 -0.305054)
			(stroke
				(width 0.1)
				(type default)
			)
			(layer "F.Fab")
		)
		(fp_line
			(start -0.67945 -0.305054)
			(end -0.12065 -0.305054)
			(stroke
				(width 0.1)
				(type default)
			)
			(layer "F.Fab")
		)
		(pad "1" smd circle
			(at -0.40005 0 180)
			(size 0 0)
			(layers "F.Cu" "F.Mask" "F.Paste")
			(net "PRSNT_SWB_ISO_N")
		)
		(pad "2" smd circle
			(at 0.40005 0 180)
			(size 0 0)
			(layers "F.Cu" "F.Mask" "F.Paste")
			(net "GND")
		)
	)
	(footprint ""
		(layer "F.Cu")
		(at 106.32313 -241.97691 -90)
		(property "Reference" "C280"
			(at 0 0 270)
			(layer "F.SilkS")
			(hide yes)
			(effects
				(font
					(size 1.27 1.27)
				)
			)
		)
		(property "Value" ""
			(at 0 0 270)
			(layer "F.Fab")
			(effects
				(font
					(size 1.27 1.27)
				)
			)
		)
		(duplicate_pad_numbers_are_jumpers no)
		(fp_line
			(start -0.7874 0.4064)
			(end -0.7874 -0.4064)
			(stroke
				(width 0.1524)
				(type default)
			)
			(layer "F.SilkS")
		)
		(fp_line
			(start 0.7874 0.4064)
			(end -0.7874 0.4064)
			(stroke
				(width 0.1524)
				(type default)
			)
			(layer "F.SilkS")
		)
		(fp_line
			(start -0.7874 -0.4064)
			(end 0.7874 -0.4064)
			(stroke
				(width 0.1524)
				(type default)
			)
			(layer "F.SilkS")
		)
		(fp_line
			(start 0.7874 -0.4064)
			(end 0.7874 0.4064)
			(stroke
				(width 0.1524)
				(type default)
			)
			(layer "F.SilkS")
		)
		(fp_line
			(start -0.67945 0.3048)
			(end -0.67945 -0.305054)
			(stroke
				(width 0.1)
				(type default)
			)
			(layer "F.Fab")
		)
		(fp_line
			(start -0.12065 0.3048)
			(end -0.67945 0.3048)
			(stroke
				(width 0.1)
				(type default)
			)
			(layer "F.Fab")
		)
		(fp_line
			(start 0.120396 0.3048)
			(end 0.120396 0.2794)
			(stroke
				(width 0.1)
				(type default)
			)
			(layer "F.Fab")
		)
		(fp_line
			(start 0.67945 0.3048)
			(end 0.120396 0.3048)
			(stroke
				(width 0.1)
				(type default)
			)
			(layer "F.Fab")
		)
		(fp_line
			(start -0.12065 0.2794)
			(end -0.12065 0.3048)
			(stroke
				(width 0.1)
				(type default)
			)
			(layer "F.Fab")
		)
		(fp_line
			(start 0.120396 0.2794)
			(end -0.12065 0.2794)
			(stroke
				(width 0.1)
				(type default)
			)
			(layer "F.Fab")
		)
		(fp_line
			(start -0.12065 -0.2794)
			(end 0.12065 -0.2794)
			(stroke
				(width 0.1)
				(type default)
			)
			(layer "F.Fab")
		)
		(fp_line
			(start 0.12065 -0.2794)
			(end 0.12065 -0.3048)
			(stroke
				(width 0.1)
				(type default)
			)
			(layer "F.Fab")
		)
		(fp_line
			(start 0.12065 -0.3048)
			(end 0.67945 -0.3048)
			(stroke
				(width 0.1)
				(type default)
			)
			(layer "F.Fab")
		)
		(fp_line
			(start 0.67945 -0.3048)
			(end 0.67945 0.3048)
			(stroke
				(width 0.1)
				(type default)
			)
			(layer "F.Fab")
		)
		(fp_line
			(start -0.67945 -0.305054)
			(end -0.12065 -0.305054)
			(stroke
				(width 0.1)
				(type default)
			)
			(layer "F.Fab")
		)
		(fp_line
			(start -0.12065 -0.305054)
			(end -0.12065 -0.2794)
			(stroke
				(width 0.1)
				(type default)
			)
			(layer "F.Fab")
		)
		(pad "1" smd circle
			(at -0.40005 0 270)
			(size 0 0)
			(layers "F.Cu" "F.Mask" "F.Paste")
			(net "PVCCIN_CPU1")
		)
		(pad "2" smd circle
			(at 0.40005 0 270)
			(size 0 0)
			(layers "F.Cu" "F.Mask" "F.Paste")
			(net "GND")
		)
	)
	(footprint ""
		(layer "F.Cu")
		(at 84.713318 -402.371052 -90)
		(property "Reference" "C734"
			(at 0 0 270)
			(layer "F.SilkS")
			(hide yes)
			(effects
				(font
					(size 1.27 1.27)
				)
			)
		)
		(property "Value" ""
			(at 0 0 270)
			(layer "F.Fab")
			(effects
				(font
					(size 1.27 1.27)
				)
			)
		)
		(duplicate_pad_numbers_are_jumpers no)
		(fp_line
			(start -0.299974 0.150114)
			(end -0.299974 -0.150114)
			(stroke
				(width 0.1)
				(type default)
			)
			(layer "F.Fab")
		)
		(fp_line
			(start 0.299974 0.150114)
			(end -0.299974 0.150114)
			(stroke
				(width 0.1)
				(type default)
			)
			(layer "F.Fab")
		)
		(fp_line
			(start -0.299974 -0.150114)
			(end 0.299974 -0.150114)
			(stroke
				(width 0.1)
				(type default)
			)
			(layer "F.Fab")
		)
		(fp_line
			(start 0.299974 -0.150114)
			(end 0.299974 0.150114)
			(stroke
				(width 0.1)
				(type default)
			)
			(layer "F.Fab")
		)
		(pad "1" smd rect
			(at -0.2667 0 270)
			(size 0.3048 0.381)
			(layers "F.Cu" "F.Mask" "F.Paste")
			(net "P5E_CPU1_PE0_TX_C_DN<3>")
		)
		(pad "2" smd rect
			(at 0.2667 0 270)
			(size 0.3048 0.381)
			(layers "F.Cu" "F.Mask" "F.Paste")
			(net "P5E_CPU1_PE0_TX_DN<3>")
		)
	)
	(footprint ""
		(layer "F.Cu")
		(at 187.892182 -28.258008 180)
		(property "Reference" "PC2233"
			(at 0 0 180)
			(layer "F.SilkS")
			(hide yes)
			(effects
				(font
					(size 1.27 1.27)
				)
			)
		)
		(property "Value" ""
			(at 0 0 180)
			(layer "F.Fab")
			(effects
				(font
					(size 1.27 1.27)
				)
			)
		)
		(duplicate_pad_numbers_are_jumpers no)
		(fp_line
			(start 0.7874 0.4064)
			(end -0.7874 0.4064)
			(stroke
				(width 0.1524)
				(type default)
			)
			(layer "F.SilkS")
		)
		(fp_line
			(start 0.7874 -0.4064)
			(end 0.7874 0.4064)
			(stroke
				(width 0.1524)
				(type default)
			)
			(layer "F.SilkS")
		)
		(fp_line
			(start -0.7874 0.4064)
			(end -0.7874 -0.4064)
			(stroke
				(width 0.1524)
				(type default)
			)
			(layer "F.SilkS")
		)
		(fp_line
			(start -0.7874 -0.4064)
			(end 0.7874 -0.4064)
			(stroke
				(width 0.1524)
				(type default)
			)
			(layer "F.SilkS")
		)
		(fp_line
			(start 0.67945 0.3048)
			(end 0.120396 0.3048)
			(stroke
				(width 0.1)
				(type default)
			)
			(layer "F.Fab")
		)
		(fp_line
			(start 0.67945 -0.3048)
			(end 0.67945 0.3048)
			(stroke
				(width 0.1)
				(type default)
			)
			(layer "F.Fab")
		)
		(fp_line
			(start 0.12065 -0.2794)
			(end 0.12065 -0.3048)
			(stroke
				(width 0.1)
				(type default)
			)
			(layer "F.Fab")
		)
		(fp_line
			(start 0.12065 -0.3048)
			(end 0.67945 -0.3048)
			(stroke
				(width 0.1)
				(type default)
			)
			(layer "F.Fab")
		)
		(fp_line
			(start 0.120396 0.3048)
			(end 0.120396 0.2794)
			(stroke
				(width 0.1)
				(type default)
			)
			(layer "F.Fab")
		)
		(fp_line
			(start 0.120396 0.2794)
			(end -0.12065 0.2794)
			(stroke
				(width 0.1)
				(type default)
			)
			(layer "F.Fab")
		)
		(fp_line
			(start -0.12065 0.3048)
			(end -0.67945 0.3048)
			(stroke
				(width 0.1)
				(type default)
			)
			(layer "F.Fab")
		)
		(fp_line
			(start -0.12065 0.2794)
			(end -0.12065 0.3048)
			(stroke
				(width 0.1)
				(type default)
			)
			(layer "F.Fab")
		)
		(fp_line
			(start -0.12065 -0.2794)
			(end 0.12065 -0.2794)
			(stroke
				(width 0.1)
				(type default)
			)
			(layer "F.Fab")
		)
		(fp_line
			(start -0.12065 -0.305054)
			(end -0.12065 -0.2794)
			(stroke
				(width 0.1)
				(type default)
			)
			(layer "F.Fab")
		)
		(fp_line
			(start -0.67945 0.3048)
			(end -0.67945 -0.305054)
			(stroke
				(width 0.1)
				(type default)
			)
			(layer "F.Fab")
		)
		(fp_line
			(start -0.67945 -0.305054)
			(end -0.12065 -0.305054)
			(stroke
				(width 0.1)
				(type default)
			)
			(layer "F.Fab")
		)
		(pad "1" smd circle
			(at -0.40005 0 180)
			(size 0 0)
			(layers "F.Cu" "F.Mask" "F.Paste")
			(net "P12V_SCM_VCC")
		)
		(pad "2" smd circle
			(at 0.40005 0 180)
			(size 0 0)
			(layers "F.Cu" "F.Mask" "F.Paste")
			(net "GND")
		)
	)
	(footprint ""
		(layer "F.Cu")
		(at 354.262944 -241.976656 -90)
		(property "Reference" "C1019"
			(at 0 0 270)
			(layer "F.SilkS")
			(hide yes)
			(effects
				(font
					(size 1.27 1.27)
				)
			)
		)
		(property "Value" ""
			(at 0 0 270)
			(layer "F.Fab")
			(effects
				(font
					(size 1.27 1.27)
				)
			)
		)
		(duplicate_pad_numbers_are_jumpers no)
		(fp_line
			(start -0.7874 0.4064)
			(end -0.7874 -0.4064)
			(stroke
				(width 0.1524)
				(type default)
			)
			(layer "F.SilkS")
		)
		(fp_line
			(start 0.7874 0.4064)
			(end -0.7874 0.4064)
			(stroke
				(width 0.1524)
				(type default)
			)
			(layer "F.SilkS")
		)
		(fp_line
			(start -0.7874 -0.4064)
			(end 0.7874 -0.4064)
			(stroke
				(width 0.1524)
				(type default)
			)
			(layer "F.SilkS")
		)
		(fp_line
			(start 0.7874 -0.4064)
			(end 0.7874 0.4064)
			(stroke
				(width 0.1524)
				(type default)
			)
			(layer "F.SilkS")
		)
		(fp_line
			(start -0.67945 0.3048)
			(end -0.67945 -0.305054)
			(stroke
				(width 0.1)
				(type default)
			)
			(layer "F.Fab")
		)
		(fp_line
			(start -0.12065 0.3048)
			(end -0.67945 0.3048)
			(stroke
				(width 0.1)
				(type default)
			)
			(layer "F.Fab")
		)
		(fp_line
			(start 0.120396 0.3048)
			(end 0.120396 0.2794)
			(stroke
				(width 0.1)
				(type default)
			)
			(layer "F.Fab")
		)
		(fp_line
			(start 0.67945 0.3048)
			(end 0.120396 0.3048)
			(stroke
				(width 0.1)
				(type default)
			)
			(layer "F.Fab")
		)
		(fp_line
			(start -0.12065 0.2794)
			(end -0.12065 0.3048)
			(stroke
				(width 0.1)
				(type default)
			)
			(layer "F.Fab")
		)
		(fp_line
			(start 0.120396 0.2794)
			(end -0.12065 0.2794)
			(stroke
				(width 0.1)
				(type default)
			)
			(layer "F.Fab")
		)
		(fp_line
			(start -0.12065 -0.2794)
			(end 0.12065 -0.2794)
			(stroke
				(width 0.1)
				(type default)
			)
			(layer "F.Fab")
		)
		(fp_line
			(start 0.12065 -0.2794)
			(end 0.12065 -0.3048)
			(stroke
				(width 0.1)
				(type default)
			)
			(layer "F.Fab")
		)
		(fp_line
			(start 0.12065 -0.3048)
			(end 0.67945 -0.3048)
			(stroke
				(width 0.1)
				(type default)
			)
			(layer "F.Fab")
		)
		(fp_line
			(start 0.67945 -0.3048)
			(end 0.67945 0.3048)
			(stroke
				(width 0.1)
				(type default)
			)
			(layer "F.Fab")
		)
		(fp_line
			(start -0.67945 -0.305054)
			(end -0.12065 -0.305054)
			(stroke
				(width 0.1)
				(type default)
			)
			(layer "F.Fab")
		)
		(fp_line
			(start -0.12065 -0.305054)
			(end -0.12065 -0.2794)
			(stroke
				(width 0.1)
				(type default)
			)
			(layer "F.Fab")
		)
		(pad "1" smd circle
			(at -0.40005 0 270)
			(size 0 0)
			(layers "F.Cu" "F.Mask" "F.Paste")
			(net "PVCCIN_CPU0")
		)
		(pad "2" smd circle
			(at 0.40005 0 270)
			(size 0 0)
			(layers "F.Cu" "F.Mask" "F.Paste")
			(net "GND")
		)
	)
	(footprint ""
		(layer "F.Cu")
		(at 263.101582 -67.08902)
		(property "Reference" "PR1326"
			(at 0 0 0)
			(layer "F.SilkS")
			(hide yes)
			(effects
				(font
					(size 1.27 1.27)
				)
			)
		)
		(property "Value" ""
			(at 0 0 0)
			(layer "F.Fab")
			(effects
				(font
					(size 1.27 1.27)
				)
			)
		)
		(duplicate_pad_numbers_are_jumpers no)
		(fp_line
			(start -0.7874 -0.4064)
			(end 0.7874 -0.4064)
			(stroke
				(width 0.1524)
				(type default)
			)
			(layer "F.SilkS")
		)
		(fp_line
			(start -0.7874 0.4064)
			(end -0.7874 -0.4064)
			(stroke
				(width 0.1524)
				(type default)
			)
			(layer "F.SilkS")
		)
		(fp_line
			(start 0.7874 -0.4064)
			(end 0.7874 0.4064)
			(stroke
				(width 0.1524)
				(type default)
			)
			(layer "F.SilkS")
		)
		(fp_line
			(start 0.7874 0.4064)
			(end -0.7874 0.4064)
			(stroke
				(width 0.1524)
				(type default)
			)
			(layer "F.SilkS")
		)
		(fp_line
			(start -0.67945 -0.305054)
			(end -0.12065 -0.305054)
			(stroke
				(width 0.1)
				(type default)
			)
			(layer "F.Fab")
		)
		(fp_line
			(start -0.67945 0.3048)
			(end -0.67945 -0.305054)
			(stroke
				(width 0.1)
				(type default)
			)
			(layer "F.Fab")
		)
		(fp_line
			(start -0.12065 -0.305054)
			(end -0.12065 -0.2794)
			(stroke
				(width 0.1)
				(type default)
			)
			(layer "F.Fab")
		)
		(fp_line
			(start -0.12065 -0.2794)
			(end 0.12065 -0.2794)
			(stroke
				(width 0.1)
				(type default)
			)
			(layer "F.Fab")
		)
		(fp_line
			(start -0.12065 0.2794)
			(end -0.12065 0.3048)
			(stroke
				(width 0.1)
				(type default)
			)
			(layer "F.Fab")
		)
		(fp_line
			(start -0.12065 0.3048)
			(end -0.67945 0.3048)
			(stroke
				(width 0.1)
				(type default)
			)
			(layer "F.Fab")
		)
		(fp_line
			(start 0.120396 0.2794)
			(end -0.12065 0.2794)
			(stroke
				(width 0.1)
				(type default)
			)
			(layer "F.Fab")
		)
		(fp_line
			(start 0.120396 0.3048)
			(end 0.120396 0.2794)
			(stroke
				(width 0.1)
				(type default)
			)
			(layer "F.Fab")
		)
		(fp_line
			(start 0.12065 -0.3048)
			(end 0.67945 -0.3048)
			(stroke
				(width 0.1)
				(type default)
			)
			(layer "F.Fab")
		)
		(fp_line
			(start 0.12065 -0.2794)
			(end 0.12065 -0.3048)
			(stroke
				(width 0.1)
				(type default)
			)
			(layer "F.Fab")
		)
		(fp_line
			(start 0.67945 -0.3048)
			(end 0.67945 0.3048)
			(stroke
				(width 0.1)
				(type default)
			)
			(layer "F.Fab")
		)
		(fp_line
			(start 0.67945 0.3048)
			(end 0.120396 0.3048)
			(stroke
				(width 0.1)
				(type default)
			)
			(layer "F.Fab")
		)
		(pad "1" smd circle
			(at -0.40005 0)
			(size 0 0)
			(layers "F.Cu" "F.Mask" "F.Paste")
			(net "P3V3_AUX")
		)
		(pad "2" smd circle
			(at 0.40005 0)
			(size 0 0)
			(layers "F.Cu" "F.Mask" "F.Paste")
			(net "P1V05_PCH_AUX_VCC")
		)
	)
	(footprint ""
		(layer "F.Cu")
		(at 117.36832 -337.955382)
		(property "Reference" "PC528_P1_3"
			(at 0 0 0)
			(layer "F.SilkS")
			(hide yes)
			(effects
				(font
					(size 1.27 1.27)
				)
			)
		)
		(property "Value" ""
			(at 0 0 0)
			(layer "F.Fab")
			(effects
				(font
					(size 1.27 1.27)
				)
			)
		)
		(duplicate_pad_numbers_are_jumpers no)
		(fp_line
			(start -0.7874 -0.4064)
			(end 0.7874 -0.4064)
			(stroke
				(width 0.1524)
				(type default)
			)
			(layer "F.SilkS")
		)
		(fp_line
			(start -0.7874 0.4064)
			(end -0.7874 -0.4064)
			(stroke
				(width 0.1524)
				(type default)
			)
			(layer "F.SilkS")
		)
		(fp_line
			(start 0.7874 -0.4064)
			(end 0.7874 0.4064)
			(stroke
				(width 0.1524)
				(type default)
			)
			(layer "F.SilkS")
		)
		(fp_line
			(start 0.7874 0.4064)
			(end -0.7874 0.4064)
			(stroke
				(width 0.1524)
				(type default)
			)
			(layer "F.SilkS")
		)
		(fp_line
			(start -0.67945 -0.305054)
			(end -0.12065 -0.305054)
			(stroke
				(width 0.1)
				(type default)
			)
			(layer "F.Fab")
		)
		(fp_line
			(start -0.67945 0.3048)
			(end -0.67945 -0.305054)
			(stroke
				(width 0.1)
				(type default)
			)
			(layer "F.Fab")
		)
		(fp_line
			(start -0.12065 -0.305054)
			(end -0.12065 -0.2794)
			(stroke
				(width 0.1)
				(type default)
			)
			(layer "F.Fab")
		)
		(fp_line
			(start -0.12065 -0.2794)
			(end 0.12065 -0.2794)
			(stroke
				(width 0.1)
				(type default)
			)
			(layer "F.Fab")
		)
		(fp_line
			(start -0.12065 0.2794)
			(end -0.12065 0.3048)
			(stroke
				(width 0.1)
				(type default)
			)
			(layer "F.Fab")
		)
		(fp_line
			(start -0.12065 0.3048)
			(end -0.67945 0.3048)
			(stroke
				(width 0.1)
				(type default)
			)
			(layer "F.Fab")
		)
		(fp_line
			(start 0.120396 0.2794)
			(end -0.12065 0.2794)
			(stroke
				(width 0.1)
				(type default)
			)
			(layer "F.Fab")
		)
		(fp_line
			(start 0.120396 0.3048)
			(end 0.120396 0.2794)
			(stroke
				(width 0.1)
				(type default)
			)
			(layer "F.Fab")
		)
		(fp_line
			(start 0.12065 -0.3048)
			(end 0.67945 -0.3048)
			(stroke
				(width 0.1)
				(type default)
			)
			(layer "F.Fab")
		)
		(fp_line
			(start 0.12065 -0.2794)
			(end 0.12065 -0.3048)
			(stroke
				(width 0.1)
				(type default)
			)
			(layer "F.Fab")
		)
		(fp_line
			(start 0.67945 -0.3048)
			(end 0.67945 0.3048)
			(stroke
				(width 0.1)
				(type default)
			)
			(layer "F.Fab")
		)
		(fp_line
			(start 0.67945 0.3048)
			(end 0.120396 0.3048)
			(stroke
				(width 0.1)
				(type default)
			)
			(layer "F.Fab")
		)
		(pad "1" smd circle
			(at -0.40005 0)
			(size 0 0)
			(layers "F.Cu" "F.Mask" "F.Paste")
			(net "SW_P12V_PVCCIN_CPU1_FLT")
		)
		(pad "2" smd circle
			(at 0.40005 0)
			(size 0 0)
			(layers "F.Cu" "F.Mask" "F.Paste")
			(net "GND")
		)
	)
	(footprint ""
		(layer "F.Cu")
		(at 309.522622 -35.804348)
		(property "Reference" "R1546"
			(at 0 0 0)
			(layer "F.SilkS")
			(hide yes)
			(effects
				(font
					(size 1.27 1.27)
				)
			)
		)
		(property "Value" ""
			(at 0 0 0)
			(layer "F.Fab")
			(effects
				(font
					(size 1.27 1.27)
				)
			)
		)
		(duplicate_pad_numbers_are_jumpers no)
		(fp_line
			(start -0.7874 -0.4064)
			(end 0.7874 -0.4064)
			(stroke
				(width 0.1524)
				(type default)
			)
			(layer "F.SilkS")
		)
		(fp_line
			(start -0.7874 0.4064)
			(end -0.7874 -0.4064)
			(stroke
				(width 0.1524)
				(type default)
			)
			(layer "F.SilkS")
		)
		(fp_line
			(start 0.7874 -0.4064)
			(end 0.7874 0.4064)
			(stroke
				(width 0.1524)
				(type default)
			)
			(layer "F.SilkS")
		)
		(fp_line
			(start 0.7874 0.4064)
			(end -0.7874 0.4064)
			(stroke
				(width 0.1524)
				(type default)
			)
			(layer "F.SilkS")
		)
		(fp_line
			(start -0.67945 -0.305054)
			(end -0.12065 -0.305054)
			(stroke
				(width 0.1)
				(type default)
			)
			(layer "F.Fab")
		)
		(fp_line
			(start -0.67945 0.3048)
			(end -0.67945 -0.305054)
			(stroke
				(width 0.1)
				(type default)
			)
			(layer "F.Fab")
		)
		(fp_line
			(start -0.12065 -0.305054)
			(end -0.12065 -0.2794)
			(stroke
				(width 0.1)
				(type default)
			)
			(layer "F.Fab")
		)
		(fp_line
			(start -0.12065 -0.2794)
			(end 0.12065 -0.2794)
			(stroke
				(width 0.1)
				(type default)
			)
			(layer "F.Fab")
		)
		(fp_line
			(start -0.12065 0.2794)
			(end -0.12065 0.3048)
			(stroke
				(width 0.1)
				(type default)
			)
			(layer "F.Fab")
		)
		(fp_line
			(start -0.12065 0.3048)
			(end -0.67945 0.3048)
			(stroke
				(width 0.1)
				(type default)
			)
			(layer "F.Fab")
		)
		(fp_line
			(start 0.120396 0.2794)
			(end -0.12065 0.2794)
			(stroke
				(width 0.1)
				(type default)
			)
			(layer "F.Fab")
		)
		(fp_line
			(start 0.120396 0.3048)
			(end 0.120396 0.2794)
			(stroke
				(width 0.1)
				(type default)
			)
			(layer "F.Fab")
		)
		(fp_line
			(start 0.12065 -0.3048)
			(end 0.67945 -0.3048)
			(stroke
				(width 0.1)
				(type default)
			)
			(layer "F.Fab")
		)
		(fp_line
			(start 0.12065 -0.2794)
			(end 0.12065 -0.3048)
			(stroke
				(width 0.1)
				(type default)
			)
			(layer "F.Fab")
		)
		(fp_line
			(start 0.67945 -0.3048)
			(end 0.67945 0.3048)
			(stroke
				(width 0.1)
				(type default)
			)
			(layer "F.Fab")
		)
		(fp_line
			(start 0.67945 0.3048)
			(end 0.120396 0.3048)
			(stroke
				(width 0.1)
				(type default)
			)
			(layer "F.Fab")
		)
		(pad "1" smd circle
			(at -0.40005 0)
			(size 0 0)
			(layers "F.Cu" "F.Mask" "F.Paste")
			(net "SMB_SML0B_3V3AUX_SDA")
		)
		(pad "2" smd circle
			(at 0.40005 0)
			(size 0 0)
			(layers "F.Cu" "F.Mask" "F.Paste")
			(net "P3V3_AUX")
		)
	)
	(footprint ""
		(layer "F.Cu")
		(at 116.561616 -251.375672 90)
		(property "Reference" "C293"
			(at 0 0 90)
			(layer "F.SilkS")
			(hide yes)
			(effects
				(font
					(size 1.27 1.27)
				)
			)
		)
		(property "Value" ""
			(at 0 0 90)
			(layer "F.Fab")
			(effects
				(font
					(size 1.27 1.27)
				)
			)
		)
		(duplicate_pad_numbers_are_jumpers no)
		(fp_line
			(start 0.7874 -0.4064)
			(end 0.7874 0.4064)
			(stroke
				(width 0.1524)
				(type default)
			)
			(layer "F.SilkS")
		)
		(fp_line
			(start -0.7874 -0.4064)
			(end 0.7874 -0.4064)
			(stroke
				(width 0.1524)
				(type default)
			)
			(layer "F.SilkS")
		)
		(fp_line
			(start 0.7874 0.4064)
			(end -0.7874 0.4064)
			(stroke
				(width 0.1524)
				(type default)
			)
			(layer "F.SilkS")
		)
		(fp_line
			(start -0.7874 0.4064)
			(end -0.7874 -0.4064)
			(stroke
				(width 0.1524)
				(type default)
			)
			(layer "F.SilkS")
		)
		(fp_line
			(start -0.12065 -0.305054)
			(end -0.12065 -0.2794)
			(stroke
				(width 0.1)
				(type default)
			)
			(layer "F.Fab")
		)
		(fp_line
			(start -0.67945 -0.305054)
			(end -0.12065 -0.305054)
			(stroke
				(width 0.1)
				(type default)
			)
			(layer "F.Fab")
		)
		(fp_line
			(start 0.67945 -0.3048)
			(end 0.67945 0.3048)
			(stroke
				(width 0.1)
				(type default)
			)
			(layer "F.Fab")
		)
		(fp_line
			(start 0.12065 -0.3048)
			(end 0.67945 -0.3048)
			(stroke
				(width 0.1)
				(type default)
			)
			(layer "F.Fab")
		)
		(fp_line
			(start 0.12065 -0.2794)
			(end 0.12065 -0.3048)
			(stroke
				(width 0.1)
				(type default)
			)
			(layer "F.Fab")
		)
		(fp_line
			(start -0.12065 -0.2794)
			(end 0.12065 -0.2794)
			(stroke
				(width 0.1)
				(type default)
			)
			(layer "F.Fab")
		)
		(fp_line
			(start 0.120396 0.2794)
			(end -0.12065 0.2794)
			(stroke
				(width 0.1)
				(type default)
			)
			(layer "F.Fab")
		)
		(fp_line
			(start -0.12065 0.2794)
			(end -0.12065 0.3048)
			(stroke
				(width 0.1)
				(type default)
			)
			(layer "F.Fab")
		)
		(fp_line
			(start 0.67945 0.3048)
			(end 0.120396 0.3048)
			(stroke
				(width 0.1)
				(type default)
			)
			(layer "F.Fab")
		)
		(fp_line
			(start 0.120396 0.3048)
			(end 0.120396 0.2794)
			(stroke
				(width 0.1)
				(type default)
			)
			(layer "F.Fab")
		)
		(fp_line
			(start -0.12065 0.3048)
			(end -0.67945 0.3048)
			(stroke
				(width 0.1)
				(type default)
			)
			(layer "F.Fab")
		)
		(fp_line
			(start -0.67945 0.3048)
			(end -0.67945 -0.305054)
			(stroke
				(width 0.1)
				(type default)
			)
			(layer "F.Fab")
		)
		(pad "1" smd circle
			(at -0.40005 0 90)
			(size 0 0)
			(layers "F.Cu" "F.Mask" "F.Paste")
			(net "PVCCIN_CPU1")
		)
		(pad "2" smd circle
			(at 0.40005 0 90)
			(size 0 0)
			(layers "F.Cu" "F.Mask" "F.Paste")
			(net "GND")
		)
	)
	(footprint ""
		(layer "F.Cu")
		(at 268.336522 -394.17117)
		(property "Reference" "PR2530"
			(at 0 0 0)
			(layer "F.SilkS")
			(hide yes)
			(effects
				(font
					(size 1.27 1.27)
				)
			)
		)
		(property "Value" ""
			(at 0 0 0)
			(layer "F.Fab")
			(effects
				(font
					(size 1.27 1.27)
				)
			)
		)
		(duplicate_pad_numbers_are_jumpers no)
		(fp_line
			(start -0.7874 -0.4064)
			(end 0.7874 -0.4064)
			(stroke
				(width 0.1524)
				(type default)
			)
			(layer "F.SilkS")
		)
		(fp_line
			(start -0.7874 0.4064)
			(end -0.7874 -0.4064)
			(stroke
				(width 0.1524)
				(type default)
			)
			(layer "F.SilkS")
		)
		(fp_line
			(start 0.7874 -0.4064)
			(end 0.7874 0.4064)
			(stroke
				(width 0.1524)
				(type default)
			)
			(layer "F.SilkS")
		)
		(fp_line
			(start 0.7874 0.4064)
			(end -0.7874 0.4064)
			(stroke
				(width 0.1524)
				(type default)
			)
			(layer "F.SilkS")
		)
		(fp_line
			(start -0.67945 -0.305054)
			(end -0.12065 -0.305054)
			(stroke
				(width 0.1)
				(type default)
			)
			(layer "F.Fab")
		)
		(fp_line
			(start -0.67945 0.3048)
			(end -0.67945 -0.305054)
			(stroke
				(width 0.1)
				(type default)
			)
			(layer "F.Fab")
		)
		(fp_line
			(start -0.12065 -0.305054)
			(end -0.12065 -0.2794)
			(stroke
				(width 0.1)
				(type default)
			)
			(layer "F.Fab")
		)
		(fp_line
			(start -0.12065 -0.2794)
			(end 0.12065 -0.2794)
			(stroke
				(width 0.1)
				(type default)
			)
			(layer "F.Fab")
		)
		(fp_line
			(start -0.12065 0.2794)
			(end -0.12065 0.3048)
			(stroke
				(width 0.1)
				(type default)
			)
			(layer "F.Fab")
		)
		(fp_line
			(start -0.12065 0.3048)
			(end -0.67945 0.3048)
			(stroke
				(width 0.1)
				(type default)
			)
			(layer "F.Fab")
		)
		(fp_line
			(start 0.120396 0.2794)
			(end -0.12065 0.2794)
			(stroke
				(width 0.1)
				(type default)
			)
			(layer "F.Fab")
		)
		(fp_line
			(start 0.120396 0.3048)
			(end 0.120396 0.2794)
			(stroke
				(width 0.1)
				(type default)
			)
			(layer "F.Fab")
		)
		(fp_line
			(start 0.12065 -0.3048)
			(end 0.67945 -0.3048)
			(stroke
				(width 0.1)
				(type default)
			)
			(layer "F.Fab")
		)
		(fp_line
			(start 0.12065 -0.2794)
			(end 0.12065 -0.3048)
			(stroke
				(width 0.1)
				(type default)
			)
			(layer "F.Fab")
		)
		(fp_line
			(start 0.67945 -0.3048)
			(end 0.67945 0.3048)
			(stroke
				(width 0.1)
				(type default)
			)
			(layer "F.Fab")
		)
		(fp_line
			(start 0.67945 0.3048)
			(end 0.120396 0.3048)
			(stroke
				(width 0.1)
				(type default)
			)
			(layer "F.Fab")
		)
		(pad "1" smd circle
			(at -0.40005 0)
			(size 0 0)
			(layers "F.Cu" "F.Mask" "F.Paste")
			(net "P12V_HSC_GATE_G3")
		)
		(pad "2" smd circle
			(at 0.40005 0)
			(size 0 0)
			(layers "F.Cu" "F.Mask" "F.Paste")
			(net "P12V_HSC_GATE2")
		)
	)
	(footprint ""
		(layer "F.Cu")
		(at 363.556042 -397.959834)
		(property "Reference" "U176"
			(at -0.112522 -2.236724 0)
			(unlocked yes)
			(layer "F.SilkS")
			(effects
				(font
					(size 0.7874 0.5842)
					(thickness 0.1524)
				)
				(justify left)
			)
		)
		(property "Value" ""
			(at 0 0 0)
			(layer "F.Fab")
			(effects
				(font
					(size 1.27 1.27)
				)
			)
		)
		(duplicate_pad_numbers_are_jumpers no)
		(fp_line
			(start -1.3716 -1.524)
			(end -0.508 -1.524)
			(stroke
				(width 0.1524)
				(type default)
			)
			(layer "F.SilkS")
		)
		(fp_line
			(start -1.3716 1.524)
			(end -1.3716 -1.524)
			(stroke
				(width 0.1524)
				(type default)
			)
			(layer "F.SilkS")
		)
		(fp_line
			(start -0.508 -1.524)
			(end 0 -1.016)
			(stroke
				(width 0.1524)
				(type default)
			)
			(layer "F.SilkS")
		)
		(fp_line
			(start 0 -1.016)
			(end 0.508 -1.524)
			(stroke
				(width 0.1524)
				(type default)
			)
			(layer "F.SilkS")
		)
		(fp_line
			(start 0.508 -1.524)
			(end 1.3716 -1.524)
			(stroke
				(width 0.1524)
				(type default)
			)
			(layer "F.SilkS")
		)
		(fp_line
			(start 1.3716 -1.524)
			(end 1.3716 1.524)
			(stroke
				(width 0.1524)
				(type default)
			)
			(layer "F.SilkS")
		)
		(fp_line
			(start 1.3716 1.524)
			(end -1.3716 1.524)
			(stroke
				(width 0.1524)
				(type default)
			)
			(layer "F.SilkS")
		)
		(fp_poly
			(pts
				(xy -1.457452 -2.04724) (xy -1.78562 -1.49352) (xy -2.082292 -2.04724)
			)
			(stroke
				(width 0)
				(type default)
			)
			(fill yes)
			(layer "F.SilkS")
		)
		(fp_line
			(start -2.54 -1.0668)
			(end -1.5494 -1.0668)
			(stroke
				(width 0.1)
				(type default)
			)
			(layer "F.Fab")
		)
		(fp_line
			(start -2.54 1.0668)
			(end -2.54 -1.0668)
			(stroke
				(width 0.1)
				(type default)
			)
			(layer "F.Fab")
		)
		(fp_line
			(start -1.5494 -1.524)
			(end 1.5494 -1.524)
			(stroke
				(width 0.1)
				(type default)
			)
			(layer "F.Fab")
		)
		(fp_line
			(start -1.5494 -1.0668)
			(end -1.5494 -1.524)
			(stroke
				(width 0.1)
				(type default)
			)
			(layer "F.Fab")
		)
		(fp_line
			(start -1.5494 1.0668)
			(end -2.54 1.0668)
			(stroke
				(width 0.1)
				(type default)
			)
			(layer "F.Fab")
		)
		(fp_line
			(start -1.5494 1.0668)
			(end -1.5494 -1.0668)
			(stroke
				(width 0.1)
				(type default)
			)
			(layer "F.Fab")
		)
		(fp_line
			(start -1.5494 1.524)
			(end -1.5494 1.0668)
			(stroke
				(width 0.1)
				(type default)
			)
			(layer "F.Fab")
		)
		(fp_line
			(start 1.5494 -1.524)
			(end 1.5494 -1.0668)
			(stroke
				(width 0.1)
				(type default)
			)
			(layer "F.Fab")
		)
		(fp_line
			(start 1.5494 -1.0668)
			(end 1.5494 1.0668)
			(stroke
				(width 0.1)
				(type default)
			)
			(layer "F.Fab")
		)
		(fp_line
			(start 1.5494 -1.0668)
			(end 2.54 -1.0668)
			(stroke
				(width 0.1)
				(type default)
			)
			(layer "F.Fab")
		)
		(fp_line
			(start 1.5494 1.0668)
			(end 1.5494 1.524)
			(stroke
				(width 0.1)
				(type default)
			)
			(layer "F.Fab")
		)
		(fp_line
			(start 1.5494 1.524)
			(end -1.5494 1.524)
			(stroke
				(width 0.1)
				(type default)
			)
			(layer "F.Fab")
		)
		(fp_line
			(start 2.54 -1.0668)
			(end 2.54 1.0668)
			(stroke
				(width 0.1)
				(type default)
			)
			(layer "F.Fab")
		)
		(fp_line
			(start 2.54 1.0668)
			(end 1.5494 1.0668)
			(stroke
				(width 0.1)
				(type default)
			)
			(layer "F.Fab")
		)
		(fp_poly
			(pts
				(xy -3.60172 -0.719328) (xy -3.60172 -1.344168) (xy -3.048 -1.016)
			)
			(stroke
				(width 0)
				(type default)
			)
			(fill yes)
			(layer "F.Fab")
		)
		(pad "1" smd rect
			(at -2.232406 -0.975106 270)
			(size 0.3556 1.4224)
			(layers "F.Cu" "F.Mask" "F.Paste")
			(net "SMB_BMC_SWB_EN_R2")
		)
		(pad "2" smd rect
			(at -2.232406 -0.32512 270)
			(size 0.3556 1.4224)
			(layers "F.Cu" "F.Mask" "F.Paste")
			(net "I3C_BMC_SWB_BUF_R_SCL")
		)
		(pad "3" smd rect
			(at -2.232406 0.32512 270)
			(size 0.3556 1.4224)
			(layers "F.Cu" "F.Mask" "F.Paste")
			(net "I3C_BMC_SWB_R_SCL")
		)
		(pad "4" smd rect
			(at -2.232406 0.975106 270)
			(size 0.3556 1.4224)
			(layers "F.Cu" "F.Mask" "F.Paste")
			(net "GND")
		)
		(pad "5" smd rect
			(at 2.232406 0.975106 270)
			(size 0.3556 1.4224)
			(layers "F.Cu" "F.Mask" "F.Paste")
			(net "Net_8615")
		)
		(pad "6" smd rect
			(at 2.232406 0.32512 270)
			(size 0.3556 1.4224)
			(layers "F.Cu" "F.Mask" "F.Paste")
			(net "I3C_BMC_SWB_R_SDA")
		)
		(pad "7" smd rect
			(at 2.232406 -0.32512 270)
			(size 0.3556 1.4224)
			(layers "F.Cu" "F.Mask" "F.Paste")
			(net "I3C_BMC_SWB_BUF_R_SDA")
		)
		(pad "8" smd rect
			(at 2.232406 -0.975106 270)
			(size 0.3556 1.4224)
			(layers "F.Cu" "F.Mask" "F.Paste")
			(net "P3V3_AUX")
		)
	)
	(footprint ""
		(layer "F.Cu")
		(at 49.962054 -358.691942)
		(property "Reference" "PR224"
			(at 0 0 0)
			(layer "F.SilkS")
			(hide yes)
			(effects
				(font
					(size 1.27 1.27)
				)
			)
		)
		(property "Value" ""
			(at 0 0 0)
			(layer "F.Fab")
			(effects
				(font
					(size 1.27 1.27)
				)
			)
		)
		(duplicate_pad_numbers_are_jumpers no)
		(fp_line
			(start -0.7874 -0.4064)
			(end 0.7874 -0.4064)
			(stroke
				(width 0.1524)
				(type default)
			)
			(layer "F.SilkS")
		)
		(fp_line
			(start -0.7874 0.4064)
			(end -0.7874 -0.4064)
			(stroke
				(width 0.1524)
				(type default)
			)
			(layer "F.SilkS")
		)
		(fp_line
			(start 0.7874 -0.4064)
			(end 0.7874 0.4064)
			(stroke
				(width 0.1524)
				(type default)
			)
			(layer "F.SilkS")
		)
		(fp_line
			(start 0.7874 0.4064)
			(end -0.7874 0.4064)
			(stroke
				(width 0.1524)
				(type default)
			)
			(layer "F.SilkS")
		)
		(fp_line
			(start -0.67945 -0.305054)
			(end -0.12065 -0.305054)
			(stroke
				(width 0.1)
				(type default)
			)
			(layer "F.Fab")
		)
		(fp_line
			(start -0.67945 0.3048)
			(end -0.67945 -0.305054)
			(stroke
				(width 0.1)
				(type default)
			)
			(layer "F.Fab")
		)
		(fp_line
			(start -0.12065 -0.305054)
			(end -0.12065 -0.2794)
			(stroke
				(width 0.1)
				(type default)
			)
			(layer "F.Fab")
		)
		(fp_line
			(start -0.12065 -0.2794)
			(end 0.12065 -0.2794)
			(stroke
				(width 0.1)
				(type default)
			)
			(layer "F.Fab")
		)
		(fp_line
			(start -0.12065 0.2794)
			(end -0.12065 0.3048)
			(stroke
				(width 0.1)
				(type default)
			)
			(layer "F.Fab")
		)
		(fp_line
			(start -0.12065 0.3048)
			(end -0.67945 0.3048)
			(stroke
				(width 0.1)
				(type default)
			)
			(layer "F.Fab")
		)
		(fp_line
			(start 0.120396 0.2794)
			(end -0.12065 0.2794)
			(stroke
				(width 0.1)
				(type default)
			)
			(layer "F.Fab")
		)
		(fp_line
			(start 0.120396 0.3048)
			(end 0.120396 0.2794)
			(stroke
				(width 0.1)
				(type default)
			)
			(layer "F.Fab")
		)
		(fp_line
			(start 0.12065 -0.3048)
			(end 0.67945 -0.3048)
			(stroke
				(width 0.1)
				(type default)
			)
			(layer "F.Fab")
		)
		(fp_line
			(start 0.12065 -0.2794)
			(end 0.12065 -0.3048)
			(stroke
				(width 0.1)
				(type default)
			)
			(layer "F.Fab")
		)
		(fp_line
			(start 0.67945 -0.3048)
			(end 0.67945 0.3048)
			(stroke
				(width 0.1)
				(type default)
			)
			(layer "F.Fab")
		)
		(fp_line
			(start 0.67945 0.3048)
			(end 0.120396 0.3048)
			(stroke
				(width 0.1)
				(type default)
			)
			(layer "F.Fab")
		)
		(pad "1" smd circle
			(at -0.40005 0)
			(size 0 0)
			(layers "F.Cu" "F.Mask" "F.Paste")
			(net "PVCCFA_EHV_FIVRA_CPU1_LSET2")
		)
		(pad "2" smd circle
			(at 0.40005 0)
			(size 0 0)
			(layers "F.Cu" "F.Mask" "F.Paste")
			(net "GND")
		)
	)
	(footprint ""
		(layer "F.Cu")
		(at 407.86812 -166.253668)
		(property "Reference" "PC639"
			(at 0 0 0)
			(layer "F.SilkS")
			(hide yes)
			(effects
				(font
					(size 1.27 1.27)
				)
			)
		)
		(property "Value" ""
			(at 0 0 0)
			(layer "F.Fab")
			(effects
				(font
					(size 1.27 1.27)
				)
			)
		)
		(duplicate_pad_numbers_are_jumpers no)
		(fp_line
			(start -0.7874 -0.4064)
			(end 0.7874 -0.4064)
			(stroke
				(width 0.1524)
				(type default)
			)
			(layer "F.SilkS")
		)
		(fp_line
			(start -0.7874 0.4064)
			(end -0.7874 -0.4064)
			(stroke
				(width 0.1524)
				(type default)
			)
			(layer "F.SilkS")
		)
		(fp_line
			(start 0.7874 -0.4064)
			(end 0.7874 0.4064)
			(stroke
				(width 0.1524)
				(type default)
			)
			(layer "F.SilkS")
		)
		(fp_line
			(start 0.7874 0.4064)
			(end -0.7874 0.4064)
			(stroke
				(width 0.1524)
				(type default)
			)
			(layer "F.SilkS")
		)
		(fp_line
			(start -0.67945 -0.305054)
			(end -0.12065 -0.305054)
			(stroke
				(width 0.1)
				(type default)
			)
			(layer "F.Fab")
		)
		(fp_line
			(start -0.67945 0.3048)
			(end -0.67945 -0.305054)
			(stroke
				(width 0.1)
				(type default)
			)
			(layer "F.Fab")
		)
		(fp_line
			(start -0.12065 -0.305054)
			(end -0.12065 -0.2794)
			(stroke
				(width 0.1)
				(type default)
			)
			(layer "F.Fab")
		)
		(fp_line
			(start -0.12065 -0.2794)
			(end 0.12065 -0.2794)
			(stroke
				(width 0.1)
				(type default)
			)
			(layer "F.Fab")
		)
		(fp_line
			(start -0.12065 0.2794)
			(end -0.12065 0.3048)
			(stroke
				(width 0.1)
				(type default)
			)
			(layer "F.Fab")
		)
		(fp_line
			(start -0.12065 0.3048)
			(end -0.67945 0.3048)
			(stroke
				(width 0.1)
				(type default)
			)
			(layer "F.Fab")
		)
		(fp_line
			(start 0.120396 0.2794)
			(end -0.12065 0.2794)
			(stroke
				(width 0.1)
				(type default)
			)
			(layer "F.Fab")
		)
		(fp_line
			(start 0.120396 0.3048)
			(end 0.120396 0.2794)
			(stroke
				(width 0.1)
				(type default)
			)
			(layer "F.Fab")
		)
		(fp_line
			(start 0.12065 -0.3048)
			(end 0.67945 -0.3048)
			(stroke
				(width 0.1)
				(type default)
			)
			(layer "F.Fab")
		)
		(fp_line
			(start 0.12065 -0.2794)
			(end 0.12065 -0.3048)
			(stroke
				(width 0.1)
				(type default)
			)
			(layer "F.Fab")
		)
		(fp_line
			(start 0.67945 -0.3048)
			(end 0.67945 0.3048)
			(stroke
				(width 0.1)
				(type default)
			)
			(layer "F.Fab")
		)
		(fp_line
			(start 0.67945 0.3048)
			(end 0.120396 0.3048)
			(stroke
				(width 0.1)
				(type default)
			)
			(layer "F.Fab")
		)
		(pad "1" smd circle
			(at -0.40005 0)
			(size 0 0)
			(layers "F.Cu" "F.Mask" "F.Paste")
			(net "PVCCD_HV_CPU0")
		)
		(pad "2" smd circle
			(at 0.40005 0)
			(size 0 0)
			(layers "F.Cu" "F.Mask" "F.Paste")
			(net "GND")
		)
	)
	(footprint ""
		(layer "F.Cu")
		(at 332.970124 -25.956006 -90)
		(property "Reference" "R1869"
			(at 0 0 270)
			(layer "F.SilkS")
			(hide yes)
			(effects
				(font
					(size 1.27 1.27)
				)
			)
		)
		(property "Value" ""
			(at 0 0 270)
			(layer "F.Fab")
			(effects
				(font
					(size 1.27 1.27)
				)
			)
		)
		(duplicate_pad_numbers_are_jumpers no)
		(fp_line
			(start -0.7874 0.4064)
			(end -0.7874 -0.4064)
			(stroke
				(width 0.1524)
				(type default)
			)
			(layer "F.SilkS")
		)
		(fp_line
			(start 0.7874 0.4064)
			(end -0.7874 0.4064)
			(stroke
				(width 0.1524)
				(type default)
			)
			(layer "F.SilkS")
		)
		(fp_line
			(start -0.7874 -0.4064)
			(end 0.7874 -0.4064)
			(stroke
				(width 0.1524)
				(type default)
			)
			(layer "F.SilkS")
		)
		(fp_line
			(start 0.7874 -0.4064)
			(end 0.7874 0.4064)
			(stroke
				(width 0.1524)
				(type default)
			)
			(layer "F.SilkS")
		)
		(fp_line
			(start -0.67945 0.3048)
			(end -0.67945 -0.305054)
			(stroke
				(width 0.1)
				(type default)
			)
			(layer "F.Fab")
		)
		(fp_line
			(start -0.12065 0.3048)
			(end -0.67945 0.3048)
			(stroke
				(width 0.1)
				(type default)
			)
			(layer "F.Fab")
		)
		(fp_line
			(start 0.120396 0.3048)
			(end 0.120396 0.2794)
			(stroke
				(width 0.1)
				(type default)
			)
			(layer "F.Fab")
		)
		(fp_line
			(start 0.67945 0.3048)
			(end 0.120396 0.3048)
			(stroke
				(width 0.1)
				(type default)
			)
			(layer "F.Fab")
		)
		(fp_line
			(start -0.12065 0.2794)
			(end -0.12065 0.3048)
			(stroke
				(width 0.1)
				(type default)
			)
			(layer "F.Fab")
		)
		(fp_line
			(start 0.120396 0.2794)
			(end -0.12065 0.2794)
			(stroke
				(width 0.1)
				(type default)
			)
			(layer "F.Fab")
		)
		(fp_line
			(start -0.12065 -0.2794)
			(end 0.12065 -0.2794)
			(stroke
				(width 0.1)
				(type default)
			)
			(layer "F.Fab")
		)
		(fp_line
			(start 0.12065 -0.2794)
			(end 0.12065 -0.3048)
			(stroke
				(width 0.1)
				(type default)
			)
			(layer "F.Fab")
		)
		(fp_line
			(start 0.12065 -0.3048)
			(end 0.67945 -0.3048)
			(stroke
				(width 0.1)
				(type default)
			)
			(layer "F.Fab")
		)
		(fp_line
			(start 0.67945 -0.3048)
			(end 0.67945 0.3048)
			(stroke
				(width 0.1)
				(type default)
			)
			(layer "F.Fab")
		)
		(fp_line
			(start -0.67945 -0.305054)
			(end -0.12065 -0.305054)
			(stroke
				(width 0.1)
				(type default)
			)
			(layer "F.Fab")
		)
		(fp_line
			(start -0.12065 -0.305054)
			(end -0.12065 -0.2794)
			(stroke
				(width 0.1)
				(type default)
			)
			(layer "F.Fab")
		)
		(pad "1" smd circle
			(at -0.40005 0 270)
			(size 0 0)
			(layers "F.Cu" "F.Mask" "F.Paste")
			(net "ESPI_LAD0_DATA_IO2")
		)
		(pad "2" smd circle
			(at 0.40005 0 270)
			(size 0 0)
			(layers "F.Cu" "F.Mask" "F.Paste")
			(net "ESPI_LPC_LAD0_IO2")
		)
	)
	(footprint ""
		(layer "F.Cu")
		(at 92.98305 -354.314252 -90)
		(property "Reference" "PL32"
			(at -7.407148 1.378712 0)
			(unlocked yes)
			(layer "F.SilkS")
			(effects
				(font
					(size 0.7874 0.5842)
					(thickness 0.1524)
				)
				(justify left)
			)
		)
		(property "Value" ""
			(at 0 0 270)
			(layer "F.Fab")
			(effects
				(font
					(size 1.27 1.27)
				)
			)
		)
		(duplicate_pad_numbers_are_jumpers no)
		(fp_line
			(start -4.99999 4.150106)
			(end 4.99999 4.150106)
			(stroke
				(width 0.1524)
				(type default)
			)
			(layer "F.SilkS")
		)
		(fp_line
			(start 4.99999 4.150106)
			(end 4.99999 2.4892)
			(stroke
				(width 0.1524)
				(type default)
			)
			(layer "F.SilkS")
		)
		(fp_line
			(start -4.99999 2.4892)
			(end -4.99999 4.150106)
			(stroke
				(width 0.1524)
				(type default)
			)
			(layer "F.SilkS")
		)
		(fp_line
			(start 4.99999 -2.4892)
			(end 4.99999 -4.150106)
			(stroke
				(width 0.1524)
				(type default)
			)
			(layer "F.SilkS")
		)
		(fp_line
			(start -4.99999 -4.150106)
			(end -4.99999 -2.4892)
			(stroke
				(width 0.1524)
				(type default)
			)
			(layer "F.SilkS")
		)
		(fp_line
			(start 4.99999 -4.150106)
			(end -4.99999 -4.150106)
			(stroke
				(width 0.1524)
				(type default)
			)
			(layer "F.SilkS")
		)
		(fp_line
			(start -4.99999 4.150106)
			(end 4.99999 4.150106)
			(stroke
				(width 0.1)
				(type default)
			)
			(layer "F.Fab")
		)
		(fp_line
			(start 4.99999 4.150106)
			(end 4.99999 -4.150106)
			(stroke
				(width 0.1)
				(type default)
			)
			(layer "F.Fab")
		)
		(fp_line
			(start -4.99999 -4.150106)
			(end -4.99999 4.150106)
			(stroke
				(width 0.1)
				(type default)
			)
			(layer "F.Fab")
		)
		(fp_line
			(start 4.99999 -4.150106)
			(end -4.99999 -4.150106)
			(stroke
				(width 0.1)
				(type default)
			)
			(layer "F.Fab")
		)
		(pad "1" smd rect
			(at -4.174998 0 270)
			(size 2.159 4.699)
			(layers "F.Cu" "F.Mask" "F.Paste")
			(net "P12V_AUX")
		)
		(pad "2" smd rect
			(at 4.174998 0 270)
			(size 2.159 4.699)
			(layers "F.Cu" "F.Mask" "F.Paste")
			(net "SW_P12V_PVCCIN_CPU1_FLT")
		)
	)
	(footprint ""
		(layer "F.Cu")
		(at 448.61988 -95.872808 180)
		(property "Reference" "R3587"
			(at 0 0 180)
			(layer "F.SilkS")
			(hide yes)
			(effects
				(font
					(size 1.27 1.27)
				)
			)
		)
		(property "Value" ""
			(at 0 0 180)
			(layer "F.Fab")
			(effects
				(font
					(size 1.27 1.27)
				)
			)
		)
		(duplicate_pad_numbers_are_jumpers no)
		(fp_line
			(start 0.7874 0.4064)
			(end -0.7874 0.4064)
			(stroke
				(width 0.1524)
				(type default)
			)
			(layer "F.SilkS")
		)
		(fp_line
			(start 0.7874 -0.4064)
			(end 0.7874 0.4064)
			(stroke
				(width 0.1524)
				(type default)
			)
			(layer "F.SilkS")
		)
		(fp_line
			(start -0.7874 0.4064)
			(end -0.7874 -0.4064)
			(stroke
				(width 0.1524)
				(type default)
			)
			(layer "F.SilkS")
		)
		(fp_line
			(start -0.7874 -0.4064)
			(end 0.7874 -0.4064)
			(stroke
				(width 0.1524)
				(type default)
			)
			(layer "F.SilkS")
		)
		(fp_line
			(start 0.67945 0.3048)
			(end 0.120396 0.3048)
			(stroke
				(width 0.1)
				(type default)
			)
			(layer "F.Fab")
		)
		(fp_line
			(start 0.67945 -0.3048)
			(end 0.67945 0.3048)
			(stroke
				(width 0.1)
				(type default)
			)
			(layer "F.Fab")
		)
		(fp_line
			(start 0.12065 -0.2794)
			(end 0.12065 -0.3048)
			(stroke
				(width 0.1)
				(type default)
			)
			(layer "F.Fab")
		)
		(fp_line
			(start 0.12065 -0.3048)
			(end 0.67945 -0.3048)
			(stroke
				(width 0.1)
				(type default)
			)
			(layer "F.Fab")
		)
		(fp_line
			(start 0.120396 0.3048)
			(end 0.120396 0.2794)
			(stroke
				(width 0.1)
				(type default)
			)
			(layer "F.Fab")
		)
		(fp_line
			(start 0.120396 0.2794)
			(end -0.12065 0.2794)
			(stroke
				(width 0.1)
				(type default)
			)
			(layer "F.Fab")
		)
		(fp_line
			(start -0.12065 0.3048)
			(end -0.67945 0.3048)
			(stroke
				(width 0.1)
				(type default)
			)
			(layer "F.Fab")
		)
		(fp_line
			(start -0.12065 0.2794)
			(end -0.12065 0.3048)
			(stroke
				(width 0.1)
				(type default)
			)
			(layer "F.Fab")
		)
		(fp_line
			(start -0.12065 -0.2794)
			(end 0.12065 -0.2794)
			(stroke
				(width 0.1)
				(type default)
			)
			(layer "F.Fab")
		)
		(fp_line
			(start -0.12065 -0.305054)
			(end -0.12065 -0.2794)
			(stroke
				(width 0.1)
				(type default)
			)
			(layer "F.Fab")
		)
		(fp_line
			(start -0.67945 0.3048)
			(end -0.67945 -0.305054)
			(stroke
				(width 0.1)
				(type default)
			)
			(layer "F.Fab")
		)
		(fp_line
			(start -0.67945 -0.305054)
			(end -0.12065 -0.305054)
			(stroke
				(width 0.1)
				(type default)
			)
			(layer "F.Fab")
		)
		(pad "1" smd circle
			(at -0.40005 0 180)
			(size 0 0)
			(layers "F.Cu" "F.Mask" "F.Paste")
			(net "SMB_INA230_3V3AUX_SDA")
		)
		(pad "2" smd circle
			(at 0.40005 0 180)
			(size 0 0)
			(layers "F.Cu" "F.Mask" "F.Paste")
			(net "SMB_INA230_1_3V3AUX_SDA_R")
		)
	)
	(footprint ""
		(layer "F.Cu")
		(at 201.73188 -108.422948 -90)
		(property "Reference" "R365"
			(at 0 0 270)
			(layer "F.SilkS")
			(hide yes)
			(effects
				(font
					(size 1.27 1.27)
				)
			)
		)
		(property "Value" ""
			(at 0 0 270)
			(layer "F.Fab")
			(effects
				(font
					(size 1.27 1.27)
				)
			)
		)
		(duplicate_pad_numbers_are_jumpers no)
		(fp_line
			(start -0.7874 0.4064)
			(end -0.7874 -0.4064)
			(stroke
				(width 0.1524)
				(type default)
			)
			(layer "F.SilkS")
		)
		(fp_line
			(start 0.7874 0.4064)
			(end -0.7874 0.4064)
			(stroke
				(width 0.1524)
				(type default)
			)
			(layer "F.SilkS")
		)
		(fp_line
			(start -0.7874 -0.4064)
			(end 0.7874 -0.4064)
			(stroke
				(width 0.1524)
				(type default)
			)
			(layer "F.SilkS")
		)
		(fp_line
			(start 0.7874 -0.4064)
			(end 0.7874 0.4064)
			(stroke
				(width 0.1524)
				(type default)
			)
			(layer "F.SilkS")
		)
		(fp_line
			(start -0.67945 0.3048)
			(end -0.67945 -0.305054)
			(stroke
				(width 0.1)
				(type default)
			)
			(layer "F.Fab")
		)
		(fp_line
			(start -0.12065 0.3048)
			(end -0.67945 0.3048)
			(stroke
				(width 0.1)
				(type default)
			)
			(layer "F.Fab")
		)
		(fp_line
			(start 0.120396 0.3048)
			(end 0.120396 0.2794)
			(stroke
				(width 0.1)
				(type default)
			)
			(layer "F.Fab")
		)
		(fp_line
			(start 0.67945 0.3048)
			(end 0.120396 0.3048)
			(stroke
				(width 0.1)
				(type default)
			)
			(layer "F.Fab")
		)
		(fp_line
			(start -0.12065 0.2794)
			(end -0.12065 0.3048)
			(stroke
				(width 0.1)
				(type default)
			)
			(layer "F.Fab")
		)
		(fp_line
			(start 0.120396 0.2794)
			(end -0.12065 0.2794)
			(stroke
				(width 0.1)
				(type default)
			)
			(layer "F.Fab")
		)
		(fp_line
			(start -0.12065 -0.2794)
			(end 0.12065 -0.2794)
			(stroke
				(width 0.1)
				(type default)
			)
			(layer "F.Fab")
		)
		(fp_line
			(start 0.12065 -0.2794)
			(end 0.12065 -0.3048)
			(stroke
				(width 0.1)
				(type default)
			)
			(layer "F.Fab")
		)
		(fp_line
			(start 0.12065 -0.3048)
			(end 0.67945 -0.3048)
			(stroke
				(width 0.1)
				(type default)
			)
			(layer "F.Fab")
		)
		(fp_line
			(start 0.67945 -0.3048)
			(end 0.67945 0.3048)
			(stroke
				(width 0.1)
				(type default)
			)
			(layer "F.Fab")
		)
		(fp_line
			(start -0.67945 -0.305054)
			(end -0.12065 -0.305054)
			(stroke
				(width 0.1)
				(type default)
			)
			(layer "F.Fab")
		)
		(fp_line
			(start -0.12065 -0.305054)
			(end -0.12065 -0.2794)
			(stroke
				(width 0.1)
				(type default)
			)
			(layer "F.Fab")
		)
		(pad "1" smd circle
			(at -0.40005 0 270)
			(size 0 0)
			(layers "F.Cu" "F.Mask" "F.Paste")
			(net "FM_CPU_RMCA_CATERR_LVT3_R_N")
		)
		(pad "2" smd circle
			(at 0.40005 0 270)
			(size 0 0)
			(layers "F.Cu" "F.Mask" "F.Paste")
			(net "CPU_RMCA_CATERR_LVT3_N")
		)
	)
	(footprint ""
		(layer "F.Cu")
		(at 366.629188 -355.651816 180)
		(property "Reference" "C1301"
			(at 0 0 180)
			(layer "F.SilkS")
			(hide yes)
			(effects
				(font
					(size 1.27 1.27)
				)
			)
		)
		(property "Value" ""
			(at 0 0 180)
			(layer "F.Fab")
			(effects
				(font
					(size 1.27 1.27)
				)
			)
		)
		(duplicate_pad_numbers_are_jumpers no)
		(fp_line
			(start 0.7874 0.4064)
			(end -0.7874 0.4064)
			(stroke
				(width 0.1524)
				(type default)
			)
			(layer "F.SilkS")
		)
		(fp_line
			(start 0.7874 -0.4064)
			(end 0.7874 0.4064)
			(stroke
				(width 0.1524)
				(type default)
			)
			(layer "F.SilkS")
		)
		(fp_line
			(start -0.7874 0.4064)
			(end -0.7874 -0.4064)
			(stroke
				(width 0.1524)
				(type default)
			)
			(layer "F.SilkS")
		)
		(fp_line
			(start -0.7874 -0.4064)
			(end 0.7874 -0.4064)
			(stroke
				(width 0.1524)
				(type default)
			)
			(layer "F.SilkS")
		)
		(fp_line
			(start 0.67945 0.3048)
			(end 0.120396 0.3048)
			(stroke
				(width 0.1)
				(type default)
			)
			(layer "F.Fab")
		)
		(fp_line
			(start 0.67945 -0.3048)
			(end 0.67945 0.3048)
			(stroke
				(width 0.1)
				(type default)
			)
			(layer "F.Fab")
		)
		(fp_line
			(start 0.12065 -0.2794)
			(end 0.12065 -0.3048)
			(stroke
				(width 0.1)
				(type default)
			)
			(layer "F.Fab")
		)
		(fp_line
			(start 0.12065 -0.3048)
			(end 0.67945 -0.3048)
			(stroke
				(width 0.1)
				(type default)
			)
			(layer "F.Fab")
		)
		(fp_line
			(start 0.120396 0.3048)
			(end 0.120396 0.2794)
			(stroke
				(width 0.1)
				(type default)
			)
			(layer "F.Fab")
		)
		(fp_line
			(start 0.120396 0.2794)
			(end -0.12065 0.2794)
			(stroke
				(width 0.1)
				(type default)
			)
			(layer "F.Fab")
		)
		(fp_line
			(start -0.12065 0.3048)
			(end -0.67945 0.3048)
			(stroke
				(width 0.1)
				(type default)
			)
			(layer "F.Fab")
		)
		(fp_line
			(start -0.12065 0.2794)
			(end -0.12065 0.3048)
			(stroke
				(width 0.1)
				(type default)
			)
			(layer "F.Fab")
		)
		(fp_line
			(start -0.12065 -0.2794)
			(end 0.12065 -0.2794)
			(stroke
				(width 0.1)
				(type default)
			)
			(layer "F.Fab")
		)
		(fp_line
			(start -0.12065 -0.305054)
			(end -0.12065 -0.2794)
			(stroke
				(width 0.1)
				(type default)
			)
			(layer "F.Fab")
		)
		(fp_line
			(start -0.67945 0.3048)
			(end -0.67945 -0.305054)
			(stroke
				(width 0.1)
				(type default)
			)
			(layer "F.Fab")
		)
		(fp_line
			(start -0.67945 -0.305054)
			(end -0.12065 -0.305054)
			(stroke
				(width 0.1)
				(type default)
			)
			(layer "F.Fab")
		)
		(pad "1" smd circle
			(at -0.40005 0 180)
			(size 0 0)
			(layers "F.Cu" "F.Mask" "F.Paste")
			(net "PWRGD_PVPP_HBM_CPU0_R")
		)
		(pad "2" smd circle
			(at 0.40005 0 180)
			(size 0 0)
			(layers "F.Cu" "F.Mask" "F.Paste")
			(net "GND")
		)
	)
	(footprint ""
		(layer "F.Cu")
		(at 95.94596 -31.575248)
		(property "Reference" "R3228"
			(at 0 0 0)
			(layer "F.SilkS")
			(hide yes)
			(effects
				(font
					(size 1.27 1.27)
				)
			)
		)
		(property "Value" ""
			(at 0 0 0)
			(layer "F.Fab")
			(effects
				(font
					(size 1.27 1.27)
				)
			)
		)
		(duplicate_pad_numbers_are_jumpers no)
		(fp_line
			(start -0.7874 -0.4064)
			(end 0.7874 -0.4064)
			(stroke
				(width 0.1524)
				(type default)
			)
			(layer "F.SilkS")
		)
		(fp_line
			(start -0.7874 0.4064)
			(end -0.7874 -0.4064)
			(stroke
				(width 0.1524)
				(type default)
			)
			(layer "F.SilkS")
		)
		(fp_line
			(start 0.7874 -0.4064)
			(end 0.7874 0.4064)
			(stroke
				(width 0.1524)
				(type default)
			)
			(layer "F.SilkS")
		)
		(fp_line
			(start 0.7874 0.4064)
			(end -0.7874 0.4064)
			(stroke
				(width 0.1524)
				(type default)
			)
			(layer "F.SilkS")
		)
		(fp_line
			(start -0.67945 -0.305054)
			(end -0.12065 -0.305054)
			(stroke
				(width 0.1)
				(type default)
			)
			(layer "F.Fab")
		)
		(fp_line
			(start -0.67945 0.3048)
			(end -0.67945 -0.305054)
			(stroke
				(width 0.1)
				(type default)
			)
			(layer "F.Fab")
		)
		(fp_line
			(start -0.12065 -0.305054)
			(end -0.12065 -0.2794)
			(stroke
				(width 0.1)
				(type default)
			)
			(layer "F.Fab")
		)
		(fp_line
			(start -0.12065 -0.2794)
			(end 0.12065 -0.2794)
			(stroke
				(width 0.1)
				(type default)
			)
			(layer "F.Fab")
		)
		(fp_line
			(start -0.12065 0.2794)
			(end -0.12065 0.3048)
			(stroke
				(width 0.1)
				(type default)
			)
			(layer "F.Fab")
		)
		(fp_line
			(start -0.12065 0.3048)
			(end -0.67945 0.3048)
			(stroke
				(width 0.1)
				(type default)
			)
			(layer "F.Fab")
		)
		(fp_line
			(start 0.120396 0.2794)
			(end -0.12065 0.2794)
			(stroke
				(width 0.1)
				(type default)
			)
			(layer "F.Fab")
		)
		(fp_line
			(start 0.120396 0.3048)
			(end 0.120396 0.2794)
			(stroke
				(width 0.1)
				(type default)
			)
			(layer "F.Fab")
		)
		(fp_line
			(start 0.12065 -0.3048)
			(end 0.67945 -0.3048)
			(stroke
				(width 0.1)
				(type default)
			)
			(layer "F.Fab")
		)
		(fp_line
			(start 0.12065 -0.2794)
			(end 0.12065 -0.3048)
			(stroke
				(width 0.1)
				(type default)
			)
			(layer "F.Fab")
		)
		(fp_line
			(start 0.67945 -0.3048)
			(end 0.67945 0.3048)
			(stroke
				(width 0.1)
				(type default)
			)
			(layer "F.Fab")
		)
		(fp_line
			(start 0.67945 0.3048)
			(end 0.120396 0.3048)
			(stroke
				(width 0.1)
				(type default)
			)
			(layer "F.Fab")
		)
		(pad "1" smd circle
			(at -0.40005 0)
			(size 0 0)
			(layers "F.Cu" "F.Mask" "F.Paste")
			(net "SMB_OCP_V3_2_3V3AUX_BUF_R_SCL")
		)
		(pad "2" smd circle
			(at 0.40005 0)
			(size 0 0)
			(layers "F.Cu" "F.Mask" "F.Paste")
			(net "SMB_OCP_V3_2_3V3AUX_BUF_SCL")
		)
	)
	(footprint ""
		(layer "F.Cu")
		(at 102.67061 -74.95921 -90)
		(property "Reference" "R3074"
			(at 0 0 270)
			(layer "F.SilkS")
			(hide yes)
			(effects
				(font
					(size 1.27 1.27)
				)
			)
		)
		(property "Value" ""
			(at 0 0 270)
			(layer "F.Fab")
			(effects
				(font
					(size 1.27 1.27)
				)
			)
		)
		(duplicate_pad_numbers_are_jumpers no)
		(fp_line
			(start -0.7874 0.4064)
			(end -0.7874 -0.4064)
			(stroke
				(width 0.1524)
				(type default)
			)
			(layer "F.SilkS")
		)
		(fp_line
			(start 0.7874 0.4064)
			(end -0.7874 0.4064)
			(stroke
				(width 0.1524)
				(type default)
			)
			(layer "F.SilkS")
		)
		(fp_line
			(start -0.7874 -0.4064)
			(end 0.7874 -0.4064)
			(stroke
				(width 0.1524)
				(type default)
			)
			(layer "F.SilkS")
		)
		(fp_line
			(start 0.7874 -0.4064)
			(end 0.7874 0.4064)
			(stroke
				(width 0.1524)
				(type default)
			)
			(layer "F.SilkS")
		)
		(fp_line
			(start -0.67945 0.3048)
			(end -0.67945 -0.305054)
			(stroke
				(width 0.1)
				(type default)
			)
			(layer "F.Fab")
		)
		(fp_line
			(start -0.12065 0.3048)
			(end -0.67945 0.3048)
			(stroke
				(width 0.1)
				(type default)
			)
			(layer "F.Fab")
		)
		(fp_line
			(start 0.120396 0.3048)
			(end 0.120396 0.2794)
			(stroke
				(width 0.1)
				(type default)
			)
			(layer "F.Fab")
		)
		(fp_line
			(start 0.67945 0.3048)
			(end 0.120396 0.3048)
			(stroke
				(width 0.1)
				(type default)
			)
			(layer "F.Fab")
		)
		(fp_line
			(start -0.12065 0.2794)
			(end -0.12065 0.3048)
			(stroke
				(width 0.1)
				(type default)
			)
			(layer "F.Fab")
		)
		(fp_line
			(start 0.120396 0.2794)
			(end -0.12065 0.2794)
			(stroke
				(width 0.1)
				(type default)
			)
			(layer "F.Fab")
		)
		(fp_line
			(start -0.12065 -0.2794)
			(end 0.12065 -0.2794)
			(stroke
				(width 0.1)
				(type default)
			)
			(layer "F.Fab")
		)
		(fp_line
			(start 0.12065 -0.2794)
			(end 0.12065 -0.3048)
			(stroke
				(width 0.1)
				(type default)
			)
			(layer "F.Fab")
		)
		(fp_line
			(start 0.12065 -0.3048)
			(end 0.67945 -0.3048)
			(stroke
				(width 0.1)
				(type default)
			)
			(layer "F.Fab")
		)
		(fp_line
			(start 0.67945 -0.3048)
			(end 0.67945 0.3048)
			(stroke
				(width 0.1)
				(type default)
			)
			(layer "F.Fab")
		)
		(fp_line
			(start -0.67945 -0.305054)
			(end -0.12065 -0.305054)
			(stroke
				(width 0.1)
				(type default)
			)
			(layer "F.Fab")
		)
		(fp_line
			(start -0.12065 -0.305054)
			(end -0.12065 -0.2794)
			(stroke
				(width 0.1)
				(type default)
			)
			(layer "F.Fab")
		)
		(pad "1" smd circle
			(at -0.40005 0 270)
			(size 0 0)
			(layers "F.Cu" "F.Mask" "F.Paste")
			(net "LED_RST_RSMRST_PLD_R_N")
		)
		(pad "2" smd circle
			(at 0.40005 0 270)
			(size 0 0)
			(layers "F.Cu" "F.Mask" "F.Paste")
			(net "P3V3_AUX")
		)
	)
	(footprint ""
		(layer "F.Cu")
		(at 162.34283 -77.862938 180)
		(property "Reference" "R3127"
			(at 0 0 180)
			(layer "F.SilkS")
			(hide yes)
			(effects
				(font
					(size 1.27 1.27)
				)
			)
		)
		(property "Value" ""
			(at 0 0 180)
			(layer "F.Fab")
			(effects
				(font
					(size 1.27 1.27)
				)
			)
		)
		(duplicate_pad_numbers_are_jumpers no)
		(fp_line
			(start 0.7874 0.4064)
			(end -0.7874 0.4064)
			(stroke
				(width 0.1524)
				(type default)
			)
			(layer "F.SilkS")
		)
		(fp_line
			(start 0.7874 -0.4064)
			(end 0.7874 0.4064)
			(stroke
				(width 0.1524)
				(type default)
			)
			(layer "F.SilkS")
		)
		(fp_line
			(start -0.7874 0.4064)
			(end -0.7874 -0.4064)
			(stroke
				(width 0.1524)
				(type default)
			)
			(layer "F.SilkS")
		)
		(fp_line
			(start -0.7874 -0.4064)
			(end 0.7874 -0.4064)
			(stroke
				(width 0.1524)
				(type default)
			)
			(layer "F.SilkS")
		)
		(fp_line
			(start 0.67945 0.3048)
			(end 0.120396 0.3048)
			(stroke
				(width 0.1)
				(type default)
			)
			(layer "F.Fab")
		)
		(fp_line
			(start 0.67945 -0.3048)
			(end 0.67945 0.3048)
			(stroke
				(width 0.1)
				(type default)
			)
			(layer "F.Fab")
		)
		(fp_line
			(start 0.12065 -0.2794)
			(end 0.12065 -0.3048)
			(stroke
				(width 0.1)
				(type default)
			)
			(layer "F.Fab")
		)
		(fp_line
			(start 0.12065 -0.3048)
			(end 0.67945 -0.3048)
			(stroke
				(width 0.1)
				(type default)
			)
			(layer "F.Fab")
		)
		(fp_line
			(start 0.120396 0.3048)
			(end 0.120396 0.2794)
			(stroke
				(width 0.1)
				(type default)
			)
			(layer "F.Fab")
		)
		(fp_line
			(start 0.120396 0.2794)
			(end -0.12065 0.2794)
			(stroke
				(width 0.1)
				(type default)
			)
			(layer "F.Fab")
		)
		(fp_line
			(start -0.12065 0.3048)
			(end -0.67945 0.3048)
			(stroke
				(width 0.1)
				(type default)
			)
			(layer "F.Fab")
		)
		(fp_line
			(start -0.12065 0.2794)
			(end -0.12065 0.3048)
			(stroke
				(width 0.1)
				(type default)
			)
			(layer "F.Fab")
		)
		(fp_line
			(start -0.12065 -0.2794)
			(end 0.12065 -0.2794)
			(stroke
				(width 0.1)
				(type default)
			)
			(layer "F.Fab")
		)
		(fp_line
			(start -0.12065 -0.305054)
			(end -0.12065 -0.2794)
			(stroke
				(width 0.1)
				(type default)
			)
			(layer "F.Fab")
		)
		(fp_line
			(start -0.67945 0.3048)
			(end -0.67945 -0.305054)
			(stroke
				(width 0.1)
				(type default)
			)
			(layer "F.Fab")
		)
		(fp_line
			(start -0.67945 -0.305054)
			(end -0.12065 -0.305054)
			(stroke
				(width 0.1)
				(type default)
			)
			(layer "F.Fab")
		)
		(pad "1" smd circle
			(at -0.40005 0 180)
			(size 0 0)
			(layers "F.Cu" "F.Mask" "F.Paste")
			(net "P3V3_AUX")
		)
		(pad "2" smd circle
			(at 0.40005 0 180)
			(size 0 0)
			(layers "F.Cu" "F.Mask" "F.Paste")
			(net "PCA9543_S3M_INT1_N")
		)
	)
	(footprint ""
		(layer "F.Cu")
		(at 449.950078 -412.660084 180)
		(property "Reference" "JP7"
			(at 1.034796 -2.340356 0)
			(unlocked yes)
			(layer "F.SilkS")
			(effects
				(font
					(size 0.7874 0.5842)
					(thickness 0.1524)
				)
				(justify left)
			)
		)
		(property "Value" ""
			(at 0 0 180)
			(layer "F.Fab")
			(effects
				(font
					(size 1.27 1.27)
				)
			)
		)
		(duplicate_pad_numbers_are_jumpers no)
		(fp_line
			(start 1.249934 6.400038)
			(end -1.249934 6.400038)
			(stroke
				(width 0.1524)
				(type default)
			)
			(layer "F.SilkS")
		)
		(fp_line
			(start 1.249934 -1.320038)
			(end 1.249934 6.400038)
			(stroke
				(width 0.1524)
				(type default)
			)
			(layer "F.SilkS")
		)
		(fp_line
			(start -1.249934 6.400038)
			(end -1.249934 -1.320038)
			(stroke
				(width 0.1524)
				(type default)
			)
			(layer "F.SilkS")
		)
		(fp_line
			(start -1.249934 -1.320038)
			(end 1.249934 -1.320038)
			(stroke
				(width 0.1524)
				(type default)
			)
			(layer "F.SilkS")
		)
		(fp_poly
			(pts
				(xy -1.452372 0) (xy -2.5654 0.556514) (xy -2.5654 -0.556514)
			)
			(stroke
				(width 0)
				(type default)
			)
			(fill yes)
			(layer "F.SilkS")
		)
		(fp_line
			(start 1.249934 6.400038)
			(end -1.249934 6.400038)
			(stroke
				(width 0.1)
				(type default)
			)
			(layer "F.Fab")
		)
		(fp_line
			(start 1.249934 -1.320038)
			(end 1.249934 6.400038)
			(stroke
				(width 0.1)
				(type default)
			)
			(layer "F.Fab")
		)
		(fp_line
			(start -1.249934 6.400038)
			(end -1.249934 -1.320038)
			(stroke
				(width 0.1)
				(type default)
			)
			(layer "F.Fab")
		)
		(fp_line
			(start -1.249934 -1.320038)
			(end 1.249934 -1.320038)
			(stroke
				(width 0.1)
				(type default)
			)
			(layer "F.Fab")
		)
		(fp_poly
			(pts
				(xy -2.5654 -0.556514) (xy -1.452372 0) (xy -2.5654 0.556514)
			)
			(stroke
				(width 0)
				(type default)
			)
			(fill yes)
			(layer "F.Fab")
		)
		(fp_text user "3"
			(at -1.804162 5.177028 0)
			(unlocked yes)
			(layer "F.SilkS")
			(effects
				(font
					(size 0.7874 0.5842)
					(thickness 0.1524)
				)
			)
		)
		(fp_text user "1"
			(at -1.346962 -0.136652 0)
			(unlocked yes)
			(layer "B.SilkS")
			(effects
				(font
					(size 0.7874 0.5842)
					(thickness 0.1524)
				)
				(justify mirror)
			)
		)
		(fp_text user "3"
			(at -1.575562 5.255768 0)
			(unlocked yes)
			(layer "B.SilkS")
			(effects
				(font
					(size 0.7874 0.5842)
					(thickness 0.1524)
				)
				(justify mirror)
			)
		)
		(fp_text user "1"
			(at -1.143 0.02667 180)
			(unlocked yes)
			(layer "B.Fab")
			(effects
				(font
					(size 0.7874 0.5842)
					(thickness 0.1524)
				)
				(justify mirror)
			)
		)
		(fp_text user "3"
			(at -1.1557 5.18287 180)
			(unlocked yes)
			(layer "B.Fab")
			(effects
				(font
					(size 0.7874 0.5842)
					(thickness 0.1524)
				)
				(justify mirror)
			)
		)
		(fp_text user "3"
			(at -1.778 5.13207 180)
			(unlocked yes)
			(layer "F.Fab")
			(effects
				(font
					(size 0.7874 0.5842)
					(thickness 0.1524)
				)
			)
		)
		(pad "1" thru_hole rect
			(at 0 0 180)
			(size 1.5494 1.5494)
			(drill 1.0414)
			(layers "*.Cu" "*.Mask")
			(remove_unused_layers no)
			(net "FM_SMB_PEHPCPU0_PCIE_ALERT_N")
			(clearance 0)
			(padstack
				(mode front_inner_back)
				(layer "Inner"
					(shape circle)
					(size 1.5494 1.5494)
					(clearance 0)
				)
				(layer "B.Cu"
					(shape rect)
					(size 1.5494 1.5494)
					(clearance 0)
				)
			)
		)
		(pad "2" thru_hole circle
			(at 0 2.54 180)
			(size 1.5494 1.5494)
			(drill 1.0414)
			(layers "*.Cu" "*.Mask")
			(remove_unused_layers no)
			(net "GND")
			(clearance 0)
		)
		(pad "3" thru_hole circle
			(at 0 5.08 180)
			(size 1.5494 1.5494)
			(drill 1.0414)
			(layers "*.Cu" "*.Mask")
			(remove_unused_layers no)
			(net "FM_SMB_PEHPCPU1_PCIE_ALERT_N")
			(clearance 0)
		)
	)
	(footprint ""
		(layer "F.Cu")
		(at 389.636 -30.825948 180)
		(property "Reference" "R4613"
			(at 0 0 180)
			(layer "F.SilkS")
			(hide yes)
			(effects
				(font
					(size 1.27 1.27)
				)
			)
		)
		(property "Value" ""
			(at 0 0 180)
			(layer "F.Fab")
			(effects
				(font
					(size 1.27 1.27)
				)
			)
		)
		(duplicate_pad_numbers_are_jumpers no)
		(fp_line
			(start 0.7874 0.4064)
			(end -0.7874 0.4064)
			(stroke
				(width 0.1524)
				(type default)
			)
			(layer "F.SilkS")
		)
		(fp_line
			(start 0.7874 -0.4064)
			(end 0.7874 0.4064)
			(stroke
				(width 0.1524)
				(type default)
			)
			(layer "F.SilkS")
		)
		(fp_line
			(start -0.7874 0.4064)
			(end -0.7874 -0.4064)
			(stroke
				(width 0.1524)
				(type default)
			)
			(layer "F.SilkS")
		)
		(fp_line
			(start -0.7874 -0.4064)
			(end 0.7874 -0.4064)
			(stroke
				(width 0.1524)
				(type default)
			)
			(layer "F.SilkS")
		)
		(fp_line
			(start 0.67945 0.3048)
			(end 0.120396 0.3048)
			(stroke
				(width 0.1)
				(type default)
			)
			(layer "F.Fab")
		)
		(fp_line
			(start 0.67945 -0.3048)
			(end 0.67945 0.3048)
			(stroke
				(width 0.1)
				(type default)
			)
			(layer "F.Fab")
		)
		(fp_line
			(start 0.12065 -0.2794)
			(end 0.12065 -0.3048)
			(stroke
				(width 0.1)
				(type default)
			)
			(layer "F.Fab")
		)
		(fp_line
			(start 0.12065 -0.3048)
			(end 0.67945 -0.3048)
			(stroke
				(width 0.1)
				(type default)
			)
			(layer "F.Fab")
		)
		(fp_line
			(start 0.120396 0.3048)
			(end 0.120396 0.2794)
			(stroke
				(width 0.1)
				(type default)
			)
			(layer "F.Fab")
		)
		(fp_line
			(start 0.120396 0.2794)
			(end -0.12065 0.2794)
			(stroke
				(width 0.1)
				(type default)
			)
			(layer "F.Fab")
		)
		(fp_line
			(start -0.12065 0.3048)
			(end -0.67945 0.3048)
			(stroke
				(width 0.1)
				(type default)
			)
			(layer "F.Fab")
		)
		(fp_line
			(start -0.12065 0.2794)
			(end -0.12065 0.3048)
			(stroke
				(width 0.1)
				(type default)
			)
			(layer "F.Fab")
		)
		(fp_line
			(start -0.12065 -0.2794)
			(end 0.12065 -0.2794)
			(stroke
				(width 0.1)
				(type default)
			)
			(layer "F.Fab")
		)
		(fp_line
			(start -0.12065 -0.305054)
			(end -0.12065 -0.2794)
			(stroke
				(width 0.1)
				(type default)
			)
			(layer "F.Fab")
		)
		(fp_line
			(start -0.67945 0.3048)
			(end -0.67945 -0.305054)
			(stroke
				(width 0.1)
				(type default)
			)
			(layer "F.Fab")
		)
		(fp_line
			(start -0.67945 -0.305054)
			(end -0.12065 -0.305054)
			(stroke
				(width 0.1)
				(type default)
			)
			(layer "F.Fab")
		)
		(pad "1" smd circle
			(at -0.40005 0 180)
			(size 0 0)
			(layers "F.Cu" "F.Mask" "F.Paste")
			(net "OCP_V3_1_P3V3_PWRGD")
		)
		(pad "2" smd circle
			(at 0.40005 0 180)
			(size 0 0)
			(layers "F.Cu" "F.Mask" "F.Paste")
			(net "HP_OCP_V3_1_RST_R")
		)
	)
	(footprint ""
		(layer "F.Cu")
		(at 209.069432 -69.82079)
		(property "Reference" "R1296"
			(at 0 0 0)
			(layer "F.SilkS")
			(hide yes)
			(effects
				(font
					(size 1.27 1.27)
				)
			)
		)
		(property "Value" ""
			(at 0 0 0)
			(layer "F.Fab")
			(effects
				(font
					(size 1.27 1.27)
				)
			)
		)
		(duplicate_pad_numbers_are_jumpers no)
		(fp_line
			(start -0.7874 -0.4064)
			(end 0.7874 -0.4064)
			(stroke
				(width 0.1524)
				(type default)
			)
			(layer "F.SilkS")
		)
		(fp_line
			(start -0.7874 0.4064)
			(end -0.7874 -0.4064)
			(stroke
				(width 0.1524)
				(type default)
			)
			(layer "F.SilkS")
		)
		(fp_line
			(start 0.7874 -0.4064)
			(end 0.7874 0.4064)
			(stroke
				(width 0.1524)
				(type default)
			)
			(layer "F.SilkS")
		)
		(fp_line
			(start 0.7874 0.4064)
			(end -0.7874 0.4064)
			(stroke
				(width 0.1524)
				(type default)
			)
			(layer "F.SilkS")
		)
		(fp_line
			(start -0.67945 -0.305054)
			(end -0.12065 -0.305054)
			(stroke
				(width 0.1)
				(type default)
			)
			(layer "F.Fab")
		)
		(fp_line
			(start -0.67945 0.3048)
			(end -0.67945 -0.305054)
			(stroke
				(width 0.1)
				(type default)
			)
			(layer "F.Fab")
		)
		(fp_line
			(start -0.12065 -0.305054)
			(end -0.12065 -0.2794)
			(stroke
				(width 0.1)
				(type default)
			)
			(layer "F.Fab")
		)
		(fp_line
			(start -0.12065 -0.2794)
			(end 0.12065 -0.2794)
			(stroke
				(width 0.1)
				(type default)
			)
			(layer "F.Fab")
		)
		(fp_line
			(start -0.12065 0.2794)
			(end -0.12065 0.3048)
			(stroke
				(width 0.1)
				(type default)
			)
			(layer "F.Fab")
		)
		(fp_line
			(start -0.12065 0.3048)
			(end -0.67945 0.3048)
			(stroke
				(width 0.1)
				(type default)
			)
			(layer "F.Fab")
		)
		(fp_line
			(start 0.120396 0.2794)
			(end -0.12065 0.2794)
			(stroke
				(width 0.1)
				(type default)
			)
			(layer "F.Fab")
		)
		(fp_line
			(start 0.120396 0.3048)
			(end 0.120396 0.2794)
			(stroke
				(width 0.1)
				(type default)
			)
			(layer "F.Fab")
		)
		(fp_line
			(start 0.12065 -0.3048)
			(end 0.67945 -0.3048)
			(stroke
				(width 0.1)
				(type default)
			)
			(layer "F.Fab")
		)
		(fp_line
			(start 0.12065 -0.2794)
			(end 0.12065 -0.3048)
			(stroke
				(width 0.1)
				(type default)
			)
			(layer "F.Fab")
		)
		(fp_line
			(start 0.67945 -0.3048)
			(end 0.67945 0.3048)
			(stroke
				(width 0.1)
				(type default)
			)
			(layer "F.Fab")
		)
		(fp_line
			(start 0.67945 0.3048)
			(end 0.120396 0.3048)
			(stroke
				(width 0.1)
				(type default)
			)
			(layer "F.Fab")
		)
		(pad "1" smd circle
			(at -0.40005 0)
			(size 0 0)
			(layers "F.Cu" "F.Mask" "F.Paste")
			(net "NCSI_BMC_TXD1_R")
		)
		(pad "2" smd circle
			(at 0.40005 0)
			(size 0 0)
			(layers "F.Cu" "F.Mask" "F.Paste")
			(net "RMII_BMC_OCP_TXD_1")
		)
	)
	(footprint ""
		(layer "F.Cu")
		(at 65.531238 -408.517344 -90)
		(property "Reference" "C699"
			(at 0 0 270)
			(layer "F.SilkS")
			(hide yes)
			(effects
				(font
					(size 1.27 1.27)
				)
			)
		)
		(property "Value" ""
			(at 0 0 270)
			(layer "F.Fab")
			(effects
				(font
					(size 1.27 1.27)
				)
			)
		)
		(duplicate_pad_numbers_are_jumpers no)
		(fp_line
			(start -0.299974 0.150114)
			(end -0.299974 -0.150114)
			(stroke
				(width 0.1)
				(type default)
			)
			(layer "F.Fab")
		)
		(fp_line
			(start 0.299974 0.150114)
			(end -0.299974 0.150114)
			(stroke
				(width 0.1)
				(type default)
			)
			(layer "F.Fab")
		)
		(fp_line
			(start -0.299974 -0.150114)
			(end 0.299974 -0.150114)
			(stroke
				(width 0.1)
				(type default)
			)
			(layer "F.Fab")
		)
		(fp_line
			(start 0.299974 -0.150114)
			(end 0.299974 0.150114)
			(stroke
				(width 0.1)
				(type default)
			)
			(layer "F.Fab")
		)
		(pad "1" smd rect
			(at -0.2667 0 270)
			(size 0.3048 0.381)
			(layers "F.Cu" "F.Mask" "F.Paste")
			(net "P5E_CPU1_PE4_TX_C_DP<5>")
		)
		(pad "2" smd rect
			(at 0.2667 0 270)
			(size 0.3048 0.381)
			(layers "F.Cu" "F.Mask" "F.Paste")
			(net "P5E_CPU1_PE4_TX_DP<5>")
		)
	)
	(footprint ""
		(layer "F.Cu")
		(at 283.826712 -362.984796)
		(property "Reference" "PR633"
			(at 0 0 0)
			(layer "F.SilkS")
			(hide yes)
			(effects
				(font
					(size 1.27 1.27)
				)
			)
		)
		(property "Value" ""
			(at 0 0 0)
			(layer "F.Fab")
			(effects
				(font
					(size 1.27 1.27)
				)
			)
		)
		(duplicate_pad_numbers_are_jumpers no)
		(fp_line
			(start -0.7874 -0.4064)
			(end 0.7874 -0.4064)
			(stroke
				(width 0.1524)
				(type default)
			)
			(layer "F.SilkS")
		)
		(fp_line
			(start -0.7874 0.4064)
			(end -0.7874 -0.4064)
			(stroke
				(width 0.1524)
				(type default)
			)
			(layer "F.SilkS")
		)
		(fp_line
			(start 0.7874 -0.4064)
			(end 0.7874 0.4064)
			(stroke
				(width 0.1524)
				(type default)
			)
			(layer "F.SilkS")
		)
		(fp_line
			(start 0.7874 0.4064)
			(end -0.7874 0.4064)
			(stroke
				(width 0.1524)
				(type default)
			)
			(layer "F.SilkS")
		)
		(fp_line
			(start -0.67945 -0.305054)
			(end -0.12065 -0.305054)
			(stroke
				(width 0.1)
				(type default)
			)
			(layer "F.Fab")
		)
		(fp_line
			(start -0.67945 0.3048)
			(end -0.67945 -0.305054)
			(stroke
				(width 0.1)
				(type default)
			)
			(layer "F.Fab")
		)
		(fp_line
			(start -0.12065 -0.305054)
			(end -0.12065 -0.2794)
			(stroke
				(width 0.1)
				(type default)
			)
			(layer "F.Fab")
		)
		(fp_line
			(start -0.12065 -0.2794)
			(end 0.12065 -0.2794)
			(stroke
				(width 0.1)
				(type default)
			)
			(layer "F.Fab")
		)
		(fp_line
			(start -0.12065 0.2794)
			(end -0.12065 0.3048)
			(stroke
				(width 0.1)
				(type default)
			)
			(layer "F.Fab")
		)
		(fp_line
			(start -0.12065 0.3048)
			(end -0.67945 0.3048)
			(stroke
				(width 0.1)
				(type default)
			)
			(layer "F.Fab")
		)
		(fp_line
			(start 0.120396 0.2794)
			(end -0.12065 0.2794)
			(stroke
				(width 0.1)
				(type default)
			)
			(layer "F.Fab")
		)
		(fp_line
			(start 0.120396 0.3048)
			(end 0.120396 0.2794)
			(stroke
				(width 0.1)
				(type default)
			)
			(layer "F.Fab")
		)
		(fp_line
			(start 0.12065 -0.3048)
			(end 0.67945 -0.3048)
			(stroke
				(width 0.1)
				(type default)
			)
			(layer "F.Fab")
		)
		(fp_line
			(start 0.12065 -0.2794)
			(end 0.12065 -0.3048)
			(stroke
				(width 0.1)
				(type default)
			)
			(layer "F.Fab")
		)
		(fp_line
			(start 0.67945 -0.3048)
			(end 0.67945 0.3048)
			(stroke
				(width 0.1)
				(type default)
			)
			(layer "F.Fab")
		)
		(fp_line
			(start 0.67945 0.3048)
			(end 0.120396 0.3048)
			(stroke
				(width 0.1)
				(type default)
			)
			(layer "F.Fab")
		)
		(pad "1" smd circle
			(at -0.40005 0)
			(size 0 0)
			(layers "F.Cu" "F.Mask" "F.Paste")
			(net "P3V3")
		)
		(pad "2" smd circle
			(at 0.40005 0)
			(size 0 0)
			(layers "F.Cu" "F.Mask" "F.Paste")
			(net "PVCCFA_EHV_FIVRA_CPU0_PVCC2")
		)
	)
	(footprint ""
		(layer "F.Cu")
		(at 454.758552 -382.660652 180)
		(property "Reference" "PC1847"
			(at 0 0 180)
			(layer "F.SilkS")
			(hide yes)
			(effects
				(font
					(size 1.27 1.27)
				)
			)
		)
		(property "Value" ""
			(at 0 0 180)
			(layer "F.Fab")
			(effects
				(font
					(size 1.27 1.27)
				)
			)
		)
		(duplicate_pad_numbers_are_jumpers no)
		(fp_line
			(start 0.7874 0.4064)
			(end -0.7874 0.4064)
			(stroke
				(width 0.1524)
				(type default)
			)
			(layer "F.SilkS")
		)
		(fp_line
			(start 0.7874 -0.4064)
			(end 0.7874 0.4064)
			(stroke
				(width 0.1524)
				(type default)
			)
			(layer "F.SilkS")
		)
		(fp_line
			(start -0.7874 0.4064)
			(end -0.7874 -0.4064)
			(stroke
				(width 0.1524)
				(type default)
			)
			(layer "F.SilkS")
		)
		(fp_line
			(start -0.7874 -0.4064)
			(end 0.7874 -0.4064)
			(stroke
				(width 0.1524)
				(type default)
			)
			(layer "F.SilkS")
		)
		(fp_line
			(start 0.67945 0.3048)
			(end 0.120396 0.3048)
			(stroke
				(width 0.1)
				(type default)
			)
			(layer "F.Fab")
		)
		(fp_line
			(start 0.67945 -0.3048)
			(end 0.67945 0.3048)
			(stroke
				(width 0.1)
				(type default)
			)
			(layer "F.Fab")
		)
		(fp_line
			(start 0.12065 -0.2794)
			(end 0.12065 -0.3048)
			(stroke
				(width 0.1)
				(type default)
			)
			(layer "F.Fab")
		)
		(fp_line
			(start 0.12065 -0.3048)
			(end 0.67945 -0.3048)
			(stroke
				(width 0.1)
				(type default)
			)
			(layer "F.Fab")
		)
		(fp_line
			(start 0.120396 0.3048)
			(end 0.120396 0.2794)
			(stroke
				(width 0.1)
				(type default)
			)
			(layer "F.Fab")
		)
		(fp_line
			(start 0.120396 0.2794)
			(end -0.12065 0.2794)
			(stroke
				(width 0.1)
				(type default)
			)
			(layer "F.Fab")
		)
		(fp_line
			(start -0.12065 0.3048)
			(end -0.67945 0.3048)
			(stroke
				(width 0.1)
				(type default)
			)
			(layer "F.Fab")
		)
		(fp_line
			(start -0.12065 0.2794)
			(end -0.12065 0.3048)
			(stroke
				(width 0.1)
				(type default)
			)
			(layer "F.Fab")
		)
		(fp_line
			(start -0.12065 -0.2794)
			(end 0.12065 -0.2794)
			(stroke
				(width 0.1)
				(type default)
			)
			(layer "F.Fab")
		)
		(fp_line
			(start -0.12065 -0.305054)
			(end -0.12065 -0.2794)
			(stroke
				(width 0.1)
				(type default)
			)
			(layer "F.Fab")
		)
		(fp_line
			(start -0.67945 0.3048)
			(end -0.67945 -0.305054)
			(stroke
				(width 0.1)
				(type default)
			)
			(layer "F.Fab")
		)
		(fp_line
			(start -0.67945 -0.305054)
			(end -0.12065 -0.305054)
			(stroke
				(width 0.1)
				(type default)
			)
			(layer "F.Fab")
		)
		(pad "1" smd circle
			(at -0.40005 0 180)
			(size 0 0)
			(layers "F.Cu" "F.Mask" "F.Paste")
			(net "SW_P5V_AUX_BST")
		)
		(pad "2" smd circle
			(at 0.40005 0 180)
			(size 0 0)
			(layers "F.Cu" "F.Mask" "F.Paste")
			(net "SW_P5V_AUX_SW")
		)
	)
	(footprint ""
		(layer "F.Cu")
		(at 76.839318 -17.777968 -90)
		(property "Reference" "PR3806"
			(at 0 0 270)
			(layer "F.SilkS")
			(hide yes)
			(effects
				(font
					(size 1.27 1.27)
				)
			)
		)
		(property "Value" ""
			(at 0 0 270)
			(layer "F.Fab")
			(effects
				(font
					(size 1.27 1.27)
				)
			)
		)
		(duplicate_pad_numbers_are_jumpers no)
		(fp_line
			(start -0.7874 0.4064)
			(end -0.7874 -0.4064)
			(stroke
				(width 0.1524)
				(type default)
			)
			(layer "F.SilkS")
		)
		(fp_line
			(start 0.7874 0.4064)
			(end -0.7874 0.4064)
			(stroke
				(width 0.1524)
				(type default)
			)
			(layer "F.SilkS")
		)
		(fp_line
			(start -0.7874 -0.4064)
			(end 0.7874 -0.4064)
			(stroke
				(width 0.1524)
				(type default)
			)
			(layer "F.SilkS")
		)
		(fp_line
			(start 0.7874 -0.4064)
			(end 0.7874 0.4064)
			(stroke
				(width 0.1524)
				(type default)
			)
			(layer "F.SilkS")
		)
		(fp_line
			(start -0.67945 0.3048)
			(end -0.67945 -0.305054)
			(stroke
				(width 0.1)
				(type default)
			)
			(layer "F.Fab")
		)
		(fp_line
			(start -0.12065 0.3048)
			(end -0.67945 0.3048)
			(stroke
				(width 0.1)
				(type default)
			)
			(layer "F.Fab")
		)
		(fp_line
			(start 0.120396 0.3048)
			(end 0.120396 0.2794)
			(stroke
				(width 0.1)
				(type default)
			)
			(layer "F.Fab")
		)
		(fp_line
			(start 0.67945 0.3048)
			(end 0.120396 0.3048)
			(stroke
				(width 0.1)
				(type default)
			)
			(layer "F.Fab")
		)
		(fp_line
			(start -0.12065 0.2794)
			(end -0.12065 0.3048)
			(stroke
				(width 0.1)
				(type default)
			)
			(layer "F.Fab")
		)
		(fp_line
			(start 0.120396 0.2794)
			(end -0.12065 0.2794)
			(stroke
				(width 0.1)
				(type default)
			)
			(layer "F.Fab")
		)
		(fp_line
			(start -0.12065 -0.2794)
			(end 0.12065 -0.2794)
			(stroke
				(width 0.1)
				(type default)
			)
			(layer "F.Fab")
		)
		(fp_line
			(start 0.12065 -0.2794)
			(end 0.12065 -0.3048)
			(stroke
				(width 0.1)
				(type default)
			)
			(layer "F.Fab")
		)
		(fp_line
			(start 0.12065 -0.3048)
			(end 0.67945 -0.3048)
			(stroke
				(width 0.1)
				(type default)
			)
			(layer "F.Fab")
		)
		(fp_line
			(start 0.67945 -0.3048)
			(end 0.67945 0.3048)
			(stroke
				(width 0.1)
				(type default)
			)
			(layer "F.Fab")
		)
		(fp_line
			(start -0.67945 -0.305054)
			(end -0.12065 -0.305054)
			(stroke
				(width 0.1)
				(type default)
			)
			(layer "F.Fab")
		)
		(fp_line
			(start -0.12065 -0.305054)
			(end -0.12065 -0.2794)
			(stroke
				(width 0.1)
				(type default)
			)
			(layer "F.Fab")
		)
		(pad "1" smd circle
			(at -0.40005 0 270)
			(size 0 0)
			(layers "F.Cu" "F.Mask" "F.Paste")
			(net "P12V_OCP_UV_2")
		)
		(pad "2" smd circle
			(at 0.40005 0 270)
			(size 0 0)
			(layers "F.Cu" "F.Mask" "F.Paste")
			(net "P12V_OCP_OV_2")
		)
	)
	(footprint ""
		(layer "F.Cu")
		(at 422.022524 -149.239224 -90)
		(property "Reference" "PC177"
			(at 0 0 270)
			(layer "F.SilkS")
			(hide yes)
			(effects
				(font
					(size 1.27 1.27)
				)
			)
		)
		(property "Value" ""
			(at 0 0 270)
			(layer "F.Fab")
			(effects
				(font
					(size 1.27 1.27)
				)
			)
		)
		(duplicate_pad_numbers_are_jumpers no)
		(fp_line
			(start -0.7874 0.4064)
			(end -0.7874 -0.4064)
			(stroke
				(width 0.1524)
				(type default)
			)
			(layer "F.SilkS")
		)
		(fp_line
			(start 0.7874 0.4064)
			(end -0.7874 0.4064)
			(stroke
				(width 0.1524)
				(type default)
			)
			(layer "F.SilkS")
		)
		(fp_line
			(start -0.7874 -0.4064)
			(end 0.7874 -0.4064)
			(stroke
				(width 0.1524)
				(type default)
			)
			(layer "F.SilkS")
		)
		(fp_line
			(start 0.7874 -0.4064)
			(end 0.7874 0.4064)
			(stroke
				(width 0.1524)
				(type default)
			)
			(layer "F.SilkS")
		)
		(fp_line
			(start -0.67945 0.3048)
			(end -0.67945 -0.305054)
			(stroke
				(width 0.1)
				(type default)
			)
			(layer "F.Fab")
		)
		(fp_line
			(start -0.12065 0.3048)
			(end -0.67945 0.3048)
			(stroke
				(width 0.1)
				(type default)
			)
			(layer "F.Fab")
		)
		(fp_line
			(start 0.120396 0.3048)
			(end 0.120396 0.2794)
			(stroke
				(width 0.1)
				(type default)
			)
			(layer "F.Fab")
		)
		(fp_line
			(start 0.67945 0.3048)
			(end 0.120396 0.3048)
			(stroke
				(width 0.1)
				(type default)
			)
			(layer "F.Fab")
		)
		(fp_line
			(start -0.12065 0.2794)
			(end -0.12065 0.3048)
			(stroke
				(width 0.1)
				(type default)
			)
			(layer "F.Fab")
		)
		(fp_line
			(start 0.120396 0.2794)
			(end -0.12065 0.2794)
			(stroke
				(width 0.1)
				(type default)
			)
			(layer "F.Fab")
		)
		(fp_line
			(start -0.12065 -0.2794)
			(end 0.12065 -0.2794)
			(stroke
				(width 0.1)
				(type default)
			)
			(layer "F.Fab")
		)
		(fp_line
			(start 0.12065 -0.2794)
			(end 0.12065 -0.3048)
			(stroke
				(width 0.1)
				(type default)
			)
			(layer "F.Fab")
		)
		(fp_line
			(start 0.12065 -0.3048)
			(end 0.67945 -0.3048)
			(stroke
				(width 0.1)
				(type default)
			)
			(layer "F.Fab")
		)
		(fp_line
			(start 0.67945 -0.3048)
			(end 0.67945 0.3048)
			(stroke
				(width 0.1)
				(type default)
			)
			(layer "F.Fab")
		)
		(fp_line
			(start -0.67945 -0.305054)
			(end -0.12065 -0.305054)
			(stroke
				(width 0.1)
				(type default)
			)
			(layer "F.Fab")
		)
		(fp_line
			(start -0.12065 -0.305054)
			(end -0.12065 -0.2794)
			(stroke
				(width 0.1)
				(type default)
			)
			(layer "F.Fab")
		)
		(pad "1" smd circle
			(at -0.40005 0 270)
			(size 0 0)
			(layers "F.Cu" "F.Mask" "F.Paste")
			(net "SW_P12V_PVCCINFAON_CPU0_FLT")
		)
		(pad "2" smd circle
			(at 0.40005 0 270)
			(size 0 0)
			(layers "F.Cu" "F.Mask" "F.Paste")
			(net "GND")
		)
	)
	(footprint ""
		(layer "F.Cu")
		(at 65.828926 -20.04822 180)
		(property "Reference" "PC2143"
			(at 0 0 180)
			(layer "F.SilkS")
			(hide yes)
			(effects
				(font
					(size 1.27 1.27)
				)
			)
		)
		(property "Value" ""
			(at 0 0 180)
			(layer "F.Fab")
			(effects
				(font
					(size 1.27 1.27)
				)
			)
		)
		(duplicate_pad_numbers_are_jumpers no)
		(fp_line
			(start 1.524 0.762)
			(end -1.524 0.762)
			(stroke
				(width 0.1524)
				(type default)
			)
			(layer "F.SilkS")
		)
		(fp_line
			(start 1.524 -0.762)
			(end 1.524 0.762)
			(stroke
				(width 0.1524)
				(type default)
			)
			(layer "F.SilkS")
		)
		(fp_line
			(start -1.524 0.762)
			(end -1.524 -0.762)
			(stroke
				(width 0.1524)
				(type default)
			)
			(layer "F.SilkS")
		)
		(fp_line
			(start -1.524 -0.762)
			(end 1.524 -0.762)
			(stroke
				(width 0.1524)
				(type default)
			)
			(layer "F.SilkS")
		)
		(fp_line
			(start 1.1049 0.724916)
			(end 1.1049 -0.724916)
			(stroke
				(width 0.1)
				(type default)
			)
			(layer "F.Fab")
		)
		(fp_line
			(start 1.1049 -0.724916)
			(end -1.1049 -0.724916)
			(stroke
				(width 0.1)
				(type default)
			)
			(layer "F.Fab")
		)
		(fp_line
			(start -1.1049 0.724916)
			(end 1.1049 0.724916)
			(stroke
				(width 0.1)
				(type default)
			)
			(layer "F.Fab")
		)
		(fp_line
			(start -1.1049 -0.724916)
			(end -1.1049 0.724916)
			(stroke
				(width 0.1)
				(type default)
			)
			(layer "F.Fab")
		)
		(pad "1" smd rect
			(at -0.889 0)
			(size 1.016 1.27)
			(layers "F.Cu" "F.Mask" "F.Paste")
			(net "P12V_OCP_V3_2")
		)
		(pad "2" smd rect
			(at 0.889 0)
			(size 1.016 1.27)
			(layers "F.Cu" "F.Mask" "F.Paste")
			(net "GND")
		)
	)
	(footprint ""
		(layer "F.Cu")
		(at 336.750914 -327.768204)
		(property "Reference" "PL9"
			(at -6.423914 4.195826 0)
			(unlocked yes)
			(layer "F.SilkS")
			(effects
				(font
					(size 0.7874 0.5842)
					(thickness 0.1524)
				)
				(justify left)
			)
		)
		(property "Value" ""
			(at 0 0 0)
			(layer "F.Fab")
			(effects
				(font
					(size 1.27 1.27)
				)
			)
		)
		(duplicate_pad_numbers_are_jumpers no)
		(fp_line
			(start -3.750056 -5.500116)
			(end -2.393442 -5.500116)
			(stroke
				(width 0.1524)
				(type default)
			)
			(layer "F.SilkS")
		)
		(fp_line
			(start -3.750056 5.500116)
			(end -3.750056 -5.500116)
			(stroke
				(width 0.1524)
				(type default)
			)
			(layer "F.SilkS")
		)
		(fp_line
			(start -2.393442 5.500116)
			(end -3.750056 5.500116)
			(stroke
				(width 0.1524)
				(type default)
			)
			(layer "F.SilkS")
		)
		(fp_line
			(start 2.393442 5.500116)
			(end 3.750056 5.500116)
			(stroke
				(width 0.1524)
				(type default)
			)
			(layer "F.SilkS")
		)
		(fp_line
			(start 3.750056 -5.500116)
			(end 2.393442 -5.500116)
			(stroke
				(width 0.1524)
				(type default)
			)
			(layer "F.SilkS")
		)
		(fp_line
			(start 3.750056 -1.507744)
			(end 3.750056 -5.500116)
			(stroke
				(width 0.1524)
				(type default)
			)
			(layer "F.SilkS")
		)
		(fp_line
			(start 3.750056 5.500116)
			(end 3.750056 -0.364744)
			(stroke
				(width 0.1524)
				(type default)
			)
			(layer "F.SilkS")
		)
		(fp_poly
			(pts
				(xy -3.125978 -6.963664) (xy -2.766822 -5.885942) (xy -3.844544 -6.245352)
			)
			(stroke
				(width 0)
				(type default)
			)
			(fill yes)
			(layer "F.SilkS")
		)
		(fp_line
			(start -3.750056 -5.500116)
			(end -3.750056 5.500116)
			(stroke
				(width 0.1)
				(type default)
			)
			(layer "F.Fab")
		)
		(fp_line
			(start -3.750056 5.500116)
			(end 3.750056 5.500116)
			(stroke
				(width 0.1)
				(type default)
			)
			(layer "F.Fab")
		)
		(fp_line
			(start 3.750056 -5.500116)
			(end -3.750056 -5.500116)
			(stroke
				(width 0.1)
				(type default)
			)
			(layer "F.Fab")
		)
		(fp_line
			(start 3.750056 5.500116)
			(end 3.750056 -5.500116)
			(stroke
				(width 0.1)
				(type default)
			)
			(layer "F.Fab")
		)
		(fp_poly
			(pts
				(xy -4.9276 -4.757928) (xy -4.9276 -3.741928) (xy -3.9116 -4.249928)
			)
			(stroke
				(width 0)
				(type default)
			)
			(fill yes)
			(layer "F.Fab")
		)
		(pad "1" smd rect
			(at 0 -4.249928 270)
			(size 2.413 4.5212)
			(layers "F.Cu" "F.Mask" "F.Paste")
			(net "SW_PVCCIN_CPU0_SW6")
		)
		(pad "2" smd rect
			(at 0 -1.175004 270)
			(size 1.3716 4.5212)
			(layers "F.Cu" "F.Mask" "F.Paste")
			(net "IND_P0_CPL6")
		)
		(pad "3" smd rect
			(at 0 1.175004 270)
			(size 1.3716 4.5212)
			(layers "F.Cu" "F.Mask" "F.Paste")
			(net "IND_P0_CPL1")
		)
		(pad "4" smd rect
			(at 0 4.249928 270)
			(size 2.413 4.5212)
			(layers "F.Cu" "F.Mask" "F.Paste")
			(net "PVCCIN_CPU0")
		)
	)
	(footprint ""
		(layer "F.Cu")
		(at 430.573688 -362.18368 -90)
		(property "Reference" "PC1173_P0_3"
			(at 0 0 270)
			(layer "F.SilkS")
			(hide yes)
			(effects
				(font
					(size 1.27 1.27)
				)
			)
		)
		(property "Value" ""
			(at 0 0 270)
			(layer "F.Fab")
			(effects
				(font
					(size 1.27 1.27)
				)
			)
		)
		(duplicate_pad_numbers_are_jumpers no)
		(fp_line
			(start -0.7874 0.4064)
			(end -0.7874 -0.4064)
			(stroke
				(width 0.1524)
				(type default)
			)
			(layer "F.SilkS")
		)
		(fp_line
			(start 0.7874 0.4064)
			(end -0.7874 0.4064)
			(stroke
				(width 0.1524)
				(type default)
			)
			(layer "F.SilkS")
		)
		(fp_line
			(start -0.7874 -0.4064)
			(end 0.7874 -0.4064)
			(stroke
				(width 0.1524)
				(type default)
			)
			(layer "F.SilkS")
		)
		(fp_line
			(start 0.7874 -0.4064)
			(end 0.7874 0.4064)
			(stroke
				(width 0.1524)
				(type default)
			)
			(layer "F.SilkS")
		)
		(fp_line
			(start -0.67945 0.3048)
			(end -0.67945 -0.305054)
			(stroke
				(width 0.1)
				(type default)
			)
			(layer "F.Fab")
		)
		(fp_line
			(start -0.12065 0.3048)
			(end -0.67945 0.3048)
			(stroke
				(width 0.1)
				(type default)
			)
			(layer "F.Fab")
		)
		(fp_line
			(start 0.120396 0.3048)
			(end 0.120396 0.2794)
			(stroke
				(width 0.1)
				(type default)
			)
			(layer "F.Fab")
		)
		(fp_line
			(start 0.67945 0.3048)
			(end 0.120396 0.3048)
			(stroke
				(width 0.1)
				(type default)
			)
			(layer "F.Fab")
		)
		(fp_line
			(start -0.12065 0.2794)
			(end -0.12065 0.3048)
			(stroke
				(width 0.1)
				(type default)
			)
			(layer "F.Fab")
		)
		(fp_line
			(start 0.120396 0.2794)
			(end -0.12065 0.2794)
			(stroke
				(width 0.1)
				(type default)
			)
			(layer "F.Fab")
		)
		(fp_line
			(start -0.12065 -0.2794)
			(end 0.12065 -0.2794)
			(stroke
				(width 0.1)
				(type default)
			)
			(layer "F.Fab")
		)
		(fp_line
			(start 0.12065 -0.2794)
			(end 0.12065 -0.3048)
			(stroke
				(width 0.1)
				(type default)
			)
			(layer "F.Fab")
		)
		(fp_line
			(start 0.12065 -0.3048)
			(end 0.67945 -0.3048)
			(stroke
				(width 0.1)
				(type default)
			)
			(layer "F.Fab")
		)
		(fp_line
			(start 0.67945 -0.3048)
			(end 0.67945 0.3048)
			(stroke
				(width 0.1)
				(type default)
			)
			(layer "F.Fab")
		)
		(fp_line
			(start -0.67945 -0.305054)
			(end -0.12065 -0.305054)
			(stroke
				(width 0.1)
				(type default)
			)
			(layer "F.Fab")
		)
		(fp_line
			(start -0.12065 -0.305054)
			(end -0.12065 -0.2794)
			(stroke
				(width 0.1)
				(type default)
			)
			(layer "F.Fab")
		)
		(pad "1" smd circle
			(at -0.40005 0 270)
			(size 0 0)
			(layers "F.Cu" "F.Mask" "F.Paste")
			(net "SW_P12V_PVCCFA_EHV_FIVRA_CPU0_R")
		)
		(pad "2" smd circle
			(at 0.40005 0 270)
			(size 0 0)
			(layers "F.Cu" "F.Mask" "F.Paste")
			(net "GND")
		)
	)
	(footprint ""
		(layer "F.Cu")
		(at 385.716272 -64.672464)
		(property "Reference" "R763"
			(at 0 0 0)
			(layer "F.SilkS")
			(hide yes)
			(effects
				(font
					(size 1.27 1.27)
				)
			)
		)
		(property "Value" ""
			(at 0 0 0)
			(layer "F.Fab")
			(effects
				(font
					(size 1.27 1.27)
				)
			)
		)
		(duplicate_pad_numbers_are_jumpers no)
		(fp_line
			(start -0.7874 -0.4064)
			(end 0.7874 -0.4064)
			(stroke
				(width 0.1524)
				(type default)
			)
			(layer "F.SilkS")
		)
		(fp_line
			(start -0.7874 0.4064)
			(end -0.7874 -0.4064)
			(stroke
				(width 0.1524)
				(type default)
			)
			(layer "F.SilkS")
		)
		(fp_line
			(start 0.7874 -0.4064)
			(end 0.7874 0.4064)
			(stroke
				(width 0.1524)
				(type default)
			)
			(layer "F.SilkS")
		)
		(fp_line
			(start 0.7874 0.4064)
			(end -0.7874 0.4064)
			(stroke
				(width 0.1524)
				(type default)
			)
			(layer "F.SilkS")
		)
		(fp_line
			(start -0.67945 -0.305054)
			(end -0.12065 -0.305054)
			(stroke
				(width 0.1)
				(type default)
			)
			(layer "F.Fab")
		)
		(fp_line
			(start -0.67945 0.3048)
			(end -0.67945 -0.305054)
			(stroke
				(width 0.1)
				(type default)
			)
			(layer "F.Fab")
		)
		(fp_line
			(start -0.12065 -0.305054)
			(end -0.12065 -0.2794)
			(stroke
				(width 0.1)
				(type default)
			)
			(layer "F.Fab")
		)
		(fp_line
			(start -0.12065 -0.2794)
			(end 0.12065 -0.2794)
			(stroke
				(width 0.1)
				(type default)
			)
			(layer "F.Fab")
		)
		(fp_line
			(start -0.12065 0.2794)
			(end -0.12065 0.3048)
			(stroke
				(width 0.1)
				(type default)
			)
			(layer "F.Fab")
		)
		(fp_line
			(start -0.12065 0.3048)
			(end -0.67945 0.3048)
			(stroke
				(width 0.1)
				(type default)
			)
			(layer "F.Fab")
		)
		(fp_line
			(start 0.120396 0.2794)
			(end -0.12065 0.2794)
			(stroke
				(width 0.1)
				(type default)
			)
			(layer "F.Fab")
		)
		(fp_line
			(start 0.120396 0.3048)
			(end 0.120396 0.2794)
			(stroke
				(width 0.1)
				(type default)
			)
			(layer "F.Fab")
		)
		(fp_line
			(start 0.12065 -0.3048)
			(end 0.67945 -0.3048)
			(stroke
				(width 0.1)
				(type default)
			)
			(layer "F.Fab")
		)
		(fp_line
			(start 0.12065 -0.2794)
			(end 0.12065 -0.3048)
			(stroke
				(width 0.1)
				(type default)
			)
			(layer "F.Fab")
		)
		(fp_line
			(start 0.67945 -0.3048)
			(end 0.67945 0.3048)
			(stroke
				(width 0.1)
				(type default)
			)
			(layer "F.Fab")
		)
		(fp_line
			(start 0.67945 0.3048)
			(end 0.120396 0.3048)
			(stroke
				(width 0.1)
				(type default)
			)
			(layer "F.Fab")
		)
		(pad "1" smd circle
			(at -0.40005 0)
			(size 0 0)
			(layers "F.Cu" "F.Mask" "F.Paste")
			(net "JTAG_DBP_TDI")
		)
		(pad "2" smd circle
			(at 0.40005 0)
			(size 0 0)
			(layers "F.Cu" "F.Mask" "F.Paste")
			(net "JTAG_DBP_TDI_R")
		)
	)
	(footprint ""
		(layer "F.Cu")
		(at 303.18456 -435.63667 90)
		(property "Reference" "Q130"
			(at -7.3787 -2.588768 90)
			(unlocked yes)
			(layer "F.SilkS")
			(effects
				(font
					(size 0.7874 0.5842)
					(thickness 0.1524)
				)
				(justify left)
			)
		)
		(property "Value" ""
			(at 0 0 90)
			(layer "F.Fab")
			(effects
				(font
					(size 1.27 1.27)
				)
			)
		)
		(duplicate_pad_numbers_are_jumpers no)
		(fp_line
			(start 1.332738 -1.100074)
			(end 1.332738 1.100074)
			(stroke
				(width 0.1524)
				(type default)
			)
			(layer "F.SilkS")
		)
		(fp_line
			(start 0.4826 -1.100074)
			(end 1.332738 -1.100074)
			(stroke
				(width 0.1524)
				(type default)
			)
			(layer "F.SilkS")
		)
		(fp_line
			(start -0.4826 -1.100074)
			(end 0 -0.541274)
			(stroke
				(width 0.1524)
				(type default)
			)
			(layer "F.SilkS")
		)
		(fp_line
			(start -1.332738 -1.100074)
			(end -0.4826 -1.100074)
			(stroke
				(width 0.1524)
				(type default)
			)
			(layer "F.SilkS")
		)
		(fp_line
			(start 0 -0.541274)
			(end 0.4826 -1.100074)
			(stroke
				(width 0.1524)
				(type default)
			)
			(layer "F.SilkS")
		)
		(fp_line
			(start 1.332738 1.100074)
			(end -1.332738 1.100074)
			(stroke
				(width 0.1524)
				(type default)
			)
			(layer "F.SilkS")
		)
		(fp_line
			(start -1.332738 1.100074)
			(end -1.332738 -1.100074)
			(stroke
				(width 0.1524)
				(type default)
			)
			(layer "F.SilkS")
		)
		(fp_poly
			(pts
				(xy -1.893062 -1.670558) (xy -1.644904 -0.926084) (xy -2.389378 -1.174242)
			)
			(stroke
				(width 0)
				(type default)
			)
			(fill yes)
			(layer "F.SilkS")
		)
		(fp_line
			(start 0.674878 -1.100074)
			(end 0.674878 1.100074)
			(stroke
				(width 0.1)
				(type default)
			)
			(layer "F.Fab")
		)
		(fp_line
			(start -0.674878 -1.100074)
			(end 0.674878 -1.100074)
			(stroke
				(width 0.1)
				(type default)
			)
			(layer "F.Fab")
		)
		(fp_line
			(start 0.674878 1.100074)
			(end -0.674878 1.100074)
			(stroke
				(width 0.1)
				(type default)
			)
			(layer "F.Fab")
		)
		(fp_line
			(start -0.674878 1.100074)
			(end -0.674878 -1.100074)
			(stroke
				(width 0.1)
				(type default)
			)
			(layer "F.Fab")
		)
		(fp_poly
			(pts
				(xy -2.2352 -0.298958) (xy -2.2352 -1.001014) (xy -1.533144 -0.649986)
			)
			(stroke
				(width 0)
				(type default)
			)
			(fill yes)
			(layer "F.Fab")
		)
		(pad "1" smd rect
			(at -0.94996 -0.649986 180)
			(size 0.4318 0.508)
			(layers "F.Cu" "F.Mask" "F.Paste")
			(net "GND")
		)
		(pad "2" smd rect
			(at -0.94996 0 180)
			(size 0.4318 0.508)
			(layers "F.Cu" "F.Mask" "F.Paste")
			(net "GPU_3V3IO_RSVD3_FFU")
		)
		(pad "3" smd rect
			(at -0.94996 0.649986 180)
			(size 0.4318 0.508)
			(layers "F.Cu" "F.Mask" "F.Paste")
			(net "GPU_3V3IO_RSVD3_FFU_ISO")
		)
		(pad "4" smd rect
			(at 0.94996 0.649986 180)
			(size 0.4318 0.508)
			(layers "F.Cu" "F.Mask" "F.Paste")
			(net "GND")
		)
		(pad "5" smd rect
			(at 0.94996 0 180)
			(size 0.4318 0.508)
			(layers "F.Cu" "F.Mask" "F.Paste")
			(net "GPU_3V3IO_RSVD3_FFU_N")
		)
		(pad "6" smd rect
			(at 0.94996 -0.649986 180)
			(size 0.4318 0.508)
			(layers "F.Cu" "F.Mask" "F.Paste")
			(net "GPU_3V3IO_RSVD3_FFU_N")
		)
	)
	(footprint ""
		(layer "F.Cu")
		(at 274.69846 -93.741494 180)
		(property "Reference" "R714"
			(at 0 0 180)
			(layer "F.SilkS")
			(hide yes)
			(effects
				(font
					(size 1.27 1.27)
				)
			)
		)
		(property "Value" ""
			(at 0 0 180)
			(layer "F.Fab")
			(effects
				(font
					(size 1.27 1.27)
				)
			)
		)
		(duplicate_pad_numbers_are_jumpers no)
		(fp_line
			(start 0.7874 0.4064)
			(end -0.7874 0.4064)
			(stroke
				(width 0.1524)
				(type default)
			)
			(layer "F.SilkS")
		)
		(fp_line
			(start 0.7874 -0.4064)
			(end 0.7874 0.4064)
			(stroke
				(width 0.1524)
				(type default)
			)
			(layer "F.SilkS")
		)
		(fp_line
			(start -0.7874 0.4064)
			(end -0.7874 -0.4064)
			(stroke
				(width 0.1524)
				(type default)
			)
			(layer "F.SilkS")
		)
		(fp_line
			(start -0.7874 -0.4064)
			(end 0.7874 -0.4064)
			(stroke
				(width 0.1524)
				(type default)
			)
			(layer "F.SilkS")
		)
		(fp_line
			(start 0.67945 0.3048)
			(end 0.120396 0.3048)
			(stroke
				(width 0.1)
				(type default)
			)
			(layer "F.Fab")
		)
		(fp_line
			(start 0.67945 -0.3048)
			(end 0.67945 0.3048)
			(stroke
				(width 0.1)
				(type default)
			)
			(layer "F.Fab")
		)
		(fp_line
			(start 0.12065 -0.2794)
			(end 0.12065 -0.3048)
			(stroke
				(width 0.1)
				(type default)
			)
			(layer "F.Fab")
		)
		(fp_line
			(start 0.12065 -0.3048)
			(end 0.67945 -0.3048)
			(stroke
				(width 0.1)
				(type default)
			)
			(layer "F.Fab")
		)
		(fp_line
			(start 0.120396 0.3048)
			(end 0.120396 0.2794)
			(stroke
				(width 0.1)
				(type default)
			)
			(layer "F.Fab")
		)
		(fp_line
			(start 0.120396 0.2794)
			(end -0.12065 0.2794)
			(stroke
				(width 0.1)
				(type default)
			)
			(layer "F.Fab")
		)
		(fp_line
			(start -0.12065 0.3048)
			(end -0.67945 0.3048)
			(stroke
				(width 0.1)
				(type default)
			)
			(layer "F.Fab")
		)
		(fp_line
			(start -0.12065 0.2794)
			(end -0.12065 0.3048)
			(stroke
				(width 0.1)
				(type default)
			)
			(layer "F.Fab")
		)
		(fp_line
			(start -0.12065 -0.2794)
			(end 0.12065 -0.2794)
			(stroke
				(width 0.1)
				(type default)
			)
			(layer "F.Fab")
		)
		(fp_line
			(start -0.12065 -0.305054)
			(end -0.12065 -0.2794)
			(stroke
				(width 0.1)
				(type default)
			)
			(layer "F.Fab")
		)
		(fp_line
			(start -0.67945 0.3048)
			(end -0.67945 -0.305054)
			(stroke
				(width 0.1)
				(type default)
			)
			(layer "F.Fab")
		)
		(fp_line
			(start -0.67945 -0.305054)
			(end -0.12065 -0.305054)
			(stroke
				(width 0.1)
				(type default)
			)
			(layer "F.Fab")
		)
		(pad "1" smd circle
			(at -0.40005 0 180)
			(size 0 0)
			(layers "F.Cu" "F.Mask" "F.Paste")
			(net "MB_FRU_ADDR2")
		)
		(pad "2" smd circle
			(at 0.40005 0 180)
			(size 0 0)
			(layers "F.Cu" "F.Mask" "F.Paste")
			(net "GND")
		)
	)
	(footprint ""
		(layer "F.Cu")
		(at 285.689548 -413.23514 90)
		(property "Reference" "R4552"
			(at 0 0 90)
			(layer "F.SilkS")
			(hide yes)
			(effects
				(font
					(size 1.27 1.27)
				)
			)
		)
		(property "Value" ""
			(at 0 0 90)
			(layer "F.Fab")
			(effects
				(font
					(size 1.27 1.27)
				)
			)
		)
		(duplicate_pad_numbers_are_jumpers no)
		(fp_line
			(start 0.7874 -0.4064)
			(end 0.7874 0.4064)
			(stroke
				(width 0.1524)
				(type default)
			)
			(layer "F.SilkS")
		)
		(fp_line
			(start -0.7874 -0.4064)
			(end 0.7874 -0.4064)
			(stroke
				(width 0.1524)
				(type default)
			)
			(layer "F.SilkS")
		)
		(fp_line
			(start 0.7874 0.4064)
			(end -0.7874 0.4064)
			(stroke
				(width 0.1524)
				(type default)
			)
			(layer "F.SilkS")
		)
		(fp_line
			(start -0.7874 0.4064)
			(end -0.7874 -0.4064)
			(stroke
				(width 0.1524)
				(type default)
			)
			(layer "F.SilkS")
		)
		(fp_line
			(start -0.12065 -0.305054)
			(end -0.12065 -0.2794)
			(stroke
				(width 0.1)
				(type default)
			)
			(layer "F.Fab")
		)
		(fp_line
			(start -0.67945 -0.305054)
			(end -0.12065 -0.305054)
			(stroke
				(width 0.1)
				(type default)
			)
			(layer "F.Fab")
		)
		(fp_line
			(start 0.67945 -0.3048)
			(end 0.67945 0.3048)
			(stroke
				(width 0.1)
				(type default)
			)
			(layer "F.Fab")
		)
		(fp_line
			(start 0.12065 -0.3048)
			(end 0.67945 -0.3048)
			(stroke
				(width 0.1)
				(type default)
			)
			(layer "F.Fab")
		)
		(fp_line
			(start 0.12065 -0.2794)
			(end 0.12065 -0.3048)
			(stroke
				(width 0.1)
				(type default)
			)
			(layer "F.Fab")
		)
		(fp_line
			(start -0.12065 -0.2794)
			(end 0.12065 -0.2794)
			(stroke
				(width 0.1)
				(type default)
			)
			(layer "F.Fab")
		)
		(fp_line
			(start 0.120396 0.2794)
			(end -0.12065 0.2794)
			(stroke
				(width 0.1)
				(type default)
			)
			(layer "F.Fab")
		)
		(fp_line
			(start -0.12065 0.2794)
			(end -0.12065 0.3048)
			(stroke
				(width 0.1)
				(type default)
			)
			(layer "F.Fab")
		)
		(fp_line
			(start 0.67945 0.3048)
			(end 0.120396 0.3048)
			(stroke
				(width 0.1)
				(type default)
			)
			(layer "F.Fab")
		)
		(fp_line
			(start 0.120396 0.3048)
			(end 0.120396 0.2794)
			(stroke
				(width 0.1)
				(type default)
			)
			(layer "F.Fab")
		)
		(fp_line
			(start -0.12065 0.3048)
			(end -0.67945 0.3048)
			(stroke
				(width 0.1)
				(type default)
			)
			(layer "F.Fab")
		)
		(fp_line
			(start -0.67945 0.3048)
			(end -0.67945 -0.305054)
			(stroke
				(width 0.1)
				(type default)
			)
			(layer "F.Fab")
		)
		(pad "1" smd circle
			(at -0.40005 0 90)
			(size 0 0)
			(layers "F.Cu" "F.Mask" "F.Paste")
			(net "HPDB_HSC_PWRGD")
		)
		(pad "2" smd circle
			(at 0.40005 0 90)
			(size 0 0)
			(layers "F.Cu" "F.Mask" "F.Paste")
			(net "GND")
		)
	)
	(footprint ""
		(layer "F.Cu")
		(at 142.42288 -40.985948)
		(property "Reference" "R2113"
			(at 0 0 0)
			(layer "F.SilkS")
			(hide yes)
			(effects
				(font
					(size 1.27 1.27)
				)
			)
		)
		(property "Value" ""
			(at 0 0 0)
			(layer "F.Fab")
			(effects
				(font
					(size 1.27 1.27)
				)
			)
		)
		(duplicate_pad_numbers_are_jumpers no)
		(fp_line
			(start -0.7874 -0.4064)
			(end 0.7874 -0.4064)
			(stroke
				(width 0.1524)
				(type default)
			)
			(layer "F.SilkS")
		)
		(fp_line
			(start -0.7874 0.4064)
			(end -0.7874 -0.4064)
			(stroke
				(width 0.1524)
				(type default)
			)
			(layer "F.SilkS")
		)
		(fp_line
			(start 0.7874 -0.4064)
			(end 0.7874 0.4064)
			(stroke
				(width 0.1524)
				(type default)
			)
			(layer "F.SilkS")
		)
		(fp_line
			(start 0.7874 0.4064)
			(end -0.7874 0.4064)
			(stroke
				(width 0.1524)
				(type default)
			)
			(layer "F.SilkS")
		)
		(fp_line
			(start -0.67945 -0.305054)
			(end -0.12065 -0.305054)
			(stroke
				(width 0.1)
				(type default)
			)
			(layer "F.Fab")
		)
		(fp_line
			(start -0.67945 0.3048)
			(end -0.67945 -0.305054)
			(stroke
				(width 0.1)
				(type default)
			)
			(layer "F.Fab")
		)
		(fp_line
			(start -0.12065 -0.305054)
			(end -0.12065 -0.2794)
			(stroke
				(width 0.1)
				(type default)
			)
			(layer "F.Fab")
		)
		(fp_line
			(start -0.12065 -0.2794)
			(end 0.12065 -0.2794)
			(stroke
				(width 0.1)
				(type default)
			)
			(layer "F.Fab")
		)
		(fp_line
			(start -0.12065 0.2794)
			(end -0.12065 0.3048)
			(stroke
				(width 0.1)
				(type default)
			)
			(layer "F.Fab")
		)
		(fp_line
			(start -0.12065 0.3048)
			(end -0.67945 0.3048)
			(stroke
				(width 0.1)
				(type default)
			)
			(layer "F.Fab")
		)
		(fp_line
			(start 0.120396 0.2794)
			(end -0.12065 0.2794)
			(stroke
				(width 0.1)
				(type default)
			)
			(layer "F.Fab")
		)
		(fp_line
			(start 0.120396 0.3048)
			(end 0.120396 0.2794)
			(stroke
				(width 0.1)
				(type default)
			)
			(layer "F.Fab")
		)
		(fp_line
			(start 0.12065 -0.3048)
			(end 0.67945 -0.3048)
			(stroke
				(width 0.1)
				(type default)
			)
			(layer "F.Fab")
		)
		(fp_line
			(start 0.12065 -0.2794)
			(end 0.12065 -0.3048)
			(stroke
				(width 0.1)
				(type default)
			)
			(layer "F.Fab")
		)
		(fp_line
			(start 0.67945 -0.3048)
			(end 0.67945 0.3048)
			(stroke
				(width 0.1)
				(type default)
			)
			(layer "F.Fab")
		)
		(fp_line
			(start 0.67945 0.3048)
			(end 0.120396 0.3048)
			(stroke
				(width 0.1)
				(type default)
			)
			(layer "F.Fab")
		)
		(pad "1" smd circle
			(at -0.40005 0)
			(size 0 0)
			(layers "F.Cu" "F.Mask" "F.Paste")
			(net "RST_PCIE_PCH_DEV_BUF_M2_0_PERST")
		)
		(pad "2" smd circle
			(at 0.40005 0)
			(size 0 0)
			(layers "F.Cu" "F.Mask" "F.Paste")
			(net "RST_PCIE_PCH_DEV_0_N")
		)
	)
	(footprint ""
		(layer "F.Cu")
		(at 260.096508 -398.78 90)
		(property "Reference" "PPQ6"
			(at -8.10514 -1.938528 0)
			(unlocked yes)
			(layer "F.SilkS")
			(effects
				(font
					(size 0.7874 0.5842)
					(thickness 0.1524)
				)
				(justify left)
			)
		)
		(property "Value" ""
			(at 0 0 90)
			(layer "F.Fab")
			(effects
				(font
					(size 1.27 1.27)
				)
			)
		)
		(duplicate_pad_numbers_are_jumpers no)
		(fp_line
			(start 2.350008 -2.649982)
			(end 2.350008 -2.4892)
			(stroke
				(width 0.1524)
				(type default)
			)
			(layer "F.SilkS")
		)
		(fp_line
			(start -2.350008 -2.649982)
			(end 2.350008 -2.649982)
			(stroke
				(width 0.1524)
				(type default)
			)
			(layer "F.SilkS")
		)
		(fp_line
			(start -2.350008 -2.4384)
			(end -2.350008 -2.649982)
			(stroke
				(width 0.1524)
				(type default)
			)
			(layer "F.SilkS")
		)
		(fp_line
			(start 2.350008 2.4892)
			(end 2.350008 2.649982)
			(stroke
				(width 0.1524)
				(type default)
			)
			(layer "F.SilkS")
		)
		(fp_line
			(start 2.350008 2.649982)
			(end -2.350008 2.649982)
			(stroke
				(width 0.1524)
				(type default)
			)
			(layer "F.SilkS")
		)
		(fp_line
			(start -2.350008 2.649982)
			(end -2.350008 2.413)
			(stroke
				(width 0.1524)
				(type default)
			)
			(layer "F.SilkS")
		)
		(fp_poly
			(pts
				(xy -3.717544 -1.905) (xy -4.758944 -2.3241) (xy -4.758944 -1.524)
			)
			(stroke
				(width 0)
				(type default)
			)
			(fill yes)
			(layer "F.SilkS")
		)
		(fp_line
			(start 2.350008 -2.649982)
			(end 2.350008 2.649982)
			(stroke
				(width 0.1)
				(type default)
			)
			(layer "F.Fab")
		)
		(fp_line
			(start -2.350008 -2.649982)
			(end 2.350008 -2.649982)
			(stroke
				(width 0.1)
				(type default)
			)
			(layer "F.Fab")
		)
		(fp_line
			(start 2.350008 2.649982)
			(end -2.350008 2.649982)
			(stroke
				(width 0.1)
				(type default)
			)
			(layer "F.Fab")
		)
		(fp_line
			(start -2.350008 2.649982)
			(end -2.350008 -2.649982)
			(stroke
				(width 0.1)
				(type default)
			)
			(layer "F.Fab")
		)
		(fp_poly
			(pts
				(xy -3.717544 -1.905) (xy -4.758944 -2.3241) (xy -4.758944 -1.524)
			)
			(stroke
				(width 0)
				(type default)
			)
			(fill yes)
			(layer "F.Fab")
		)
		(pad "1" smd rect
			(at -2.999994 -1.905)
			(size 0.7112 1.1684)
			(layers "F.Cu" "F.Mask" "F.Paste")
			(net "P12V_AUX")
		)
		(pad "2" smd rect
			(at -2.999994 -0.635)
			(size 0.7112 1.1684)
			(layers "F.Cu" "F.Mask" "F.Paste")
			(net "P12V_AUX")
		)
		(pad "3" smd rect
			(at -2.999994 0.635)
			(size 0.7112 1.1684)
			(layers "F.Cu" "F.Mask" "F.Paste")
			(net "P12V_AUX")
		)
		(pad "4" smd rect
			(at -2.999994 1.905)
			(size 0.7112 1.1684)
			(layers "F.Cu" "F.Mask" "F.Paste")
			(net "P12V_HSC_GATE_G2")
		)
		(pad "5" smd circle
			(at 0.925068 0)
			(size 0 0)
			(layers "F.Cu" "F.Mask" "F.Paste")
			(net "P12V_MAIN_R")
		)
		(zone
			(layer "F.Cu")
			(hatch none 0.5)
			(connect_pads
				(clearance 0)
			)
			(min_thickness 0.25)
			(keepout
				(tracks not_allowed)
				(vias allowed)
				(pads allowed)
				(copperpour not_allowed)
				(footprints allowed)
			)
			(placement
				(enabled no)
				(sheetname "")
			)
			(fill
				(thermal_gap 0.5)
				(thermal_bridge_width 0.5)
				(island_removal_mode 0)
			)
			(polygon
				(pts
					(xy 257.937508 -397.3322) (xy 262.255508 -397.3322) (xy 262.738108 -397.3322) (xy 262.738108 -396.4305)
					(xy 257.454908 -396.4305) (xy 257.454908 -397.3322)
				)
			)
		)
	)
	(footprint ""
		(layer "F.Cu")
		(at 29.904182 -390.084818)
		(property "Reference" "R4655"
			(at 0 0 0)
			(layer "F.SilkS")
			(hide yes)
			(effects
				(font
					(size 1.27 1.27)
				)
			)
		)
		(property "Value" ""
			(at 0 0 0)
			(layer "F.Fab")
			(effects
				(font
					(size 1.27 1.27)
				)
			)
		)
		(duplicate_pad_numbers_are_jumpers no)
		(fp_line
			(start -0.7874 -0.4064)
			(end 0.7874 -0.4064)
			(stroke
				(width 0.1524)
				(type default)
			)
			(layer "F.SilkS")
		)
		(fp_line
			(start -0.7874 0.4064)
			(end -0.7874 -0.4064)
			(stroke
				(width 0.1524)
				(type default)
			)
			(layer "F.SilkS")
		)
		(fp_line
			(start 0.7874 -0.4064)
			(end 0.7874 0.4064)
			(stroke
				(width 0.1524)
				(type default)
			)
			(layer "F.SilkS")
		)
		(fp_line
			(start 0.7874 0.4064)
			(end -0.7874 0.4064)
			(stroke
				(width 0.1524)
				(type default)
			)
			(layer "F.SilkS")
		)
		(fp_line
			(start -0.67945 -0.305054)
			(end -0.12065 -0.305054)
			(stroke
				(width 0.1)
				(type default)
			)
			(layer "F.Fab")
		)
		(fp_line
			(start -0.67945 0.3048)
			(end -0.67945 -0.305054)
			(stroke
				(width 0.1)
				(type default)
			)
			(layer "F.Fab")
		)
		(fp_line
			(start -0.12065 -0.305054)
			(end -0.12065 -0.2794)
			(stroke
				(width 0.1)
				(type default)
			)
			(layer "F.Fab")
		)
		(fp_line
			(start -0.12065 -0.2794)
			(end 0.12065 -0.2794)
			(stroke
				(width 0.1)
				(type default)
			)
			(layer "F.Fab")
		)
		(fp_line
			(start -0.12065 0.2794)
			(end -0.12065 0.3048)
			(stroke
				(width 0.1)
				(type default)
			)
			(layer "F.Fab")
		)
		(fp_line
			(start -0.12065 0.3048)
			(end -0.67945 0.3048)
			(stroke
				(width 0.1)
				(type default)
			)
			(layer "F.Fab")
		)
		(fp_line
			(start 0.120396 0.2794)
			(end -0.12065 0.2794)
			(stroke
				(width 0.1)
				(type default)
			)
			(layer "F.Fab")
		)
		(fp_line
			(start 0.120396 0.3048)
			(end 0.120396 0.2794)
			(stroke
				(width 0.1)
				(type default)
			)
			(layer "F.Fab")
		)
		(fp_line
			(start 0.12065 -0.3048)
			(end 0.67945 -0.3048)
			(stroke
				(width 0.1)
				(type default)
			)
			(layer "F.Fab")
		)
		(fp_line
			(start 0.12065 -0.2794)
			(end 0.12065 -0.3048)
			(stroke
				(width 0.1)
				(type default)
			)
			(layer "F.Fab")
		)
		(fp_line
			(start 0.67945 -0.3048)
			(end 0.67945 0.3048)
			(stroke
				(width 0.1)
				(type default)
			)
			(layer "F.Fab")
		)
		(fp_line
			(start 0.67945 0.3048)
			(end 0.120396 0.3048)
			(stroke
				(width 0.1)
				(type default)
			)
			(layer "F.Fab")
		)
		(pad "1" smd circle
			(at -0.40005 0)
			(size 0 0)
			(layers "F.Cu" "F.Mask" "F.Paste")
			(net "P3V3_AUX")
		)
		(pad "2" smd circle
			(at 0.40005 0)
			(size 0 0)
			(layers "F.Cu" "F.Mask" "F.Paste")
			(net "FM_P2E_BUF2_RXDET")
		)
	)
	(footprint ""
		(layer "F.Cu")
		(at 350.294956 -338.290662 -90)
		(property "Reference" "PC1355"
			(at 0 0 270)
			(layer "F.SilkS")
			(hide yes)
			(effects
				(font
					(size 1.27 1.27)
				)
			)
		)
		(property "Value" ""
			(at 0 0 270)
			(layer "F.Fab")
			(effects
				(font
					(size 1.27 1.27)
				)
			)
		)
		(duplicate_pad_numbers_are_jumpers no)
		(fp_line
			(start -0.7874 0.4064)
			(end -0.7874 -0.4064)
			(stroke
				(width 0.1524)
				(type default)
			)
			(layer "F.SilkS")
		)
		(fp_line
			(start 0.7874 0.4064)
			(end -0.7874 0.4064)
			(stroke
				(width 0.1524)
				(type default)
			)
			(layer "F.SilkS")
		)
		(fp_line
			(start -0.7874 -0.4064)
			(end 0.7874 -0.4064)
			(stroke
				(width 0.1524)
				(type default)
			)
			(layer "F.SilkS")
		)
		(fp_line
			(start 0.7874 -0.4064)
			(end 0.7874 0.4064)
			(stroke
				(width 0.1524)
				(type default)
			)
			(layer "F.SilkS")
		)
		(fp_line
			(start -0.67945 0.3048)
			(end -0.67945 -0.305054)
			(stroke
				(width 0.1)
				(type default)
			)
			(layer "F.Fab")
		)
		(fp_line
			(start -0.12065 0.3048)
			(end -0.67945 0.3048)
			(stroke
				(width 0.1)
				(type default)
			)
			(layer "F.Fab")
		)
		(fp_line
			(start 0.120396 0.3048)
			(end 0.120396 0.2794)
			(stroke
				(width 0.1)
				(type default)
			)
			(layer "F.Fab")
		)
		(fp_line
			(start 0.67945 0.3048)
			(end 0.120396 0.3048)
			(stroke
				(width 0.1)
				(type default)
			)
			(layer "F.Fab")
		)
		(fp_line
			(start -0.12065 0.2794)
			(end -0.12065 0.3048)
			(stroke
				(width 0.1)
				(type default)
			)
			(layer "F.Fab")
		)
		(fp_line
			(start 0.120396 0.2794)
			(end -0.12065 0.2794)
			(stroke
				(width 0.1)
				(type default)
			)
			(layer "F.Fab")
		)
		(fp_line
			(start -0.12065 -0.2794)
			(end 0.12065 -0.2794)
			(stroke
				(width 0.1)
				(type default)
			)
			(layer "F.Fab")
		)
		(fp_line
			(start 0.12065 -0.2794)
			(end 0.12065 -0.3048)
			(stroke
				(width 0.1)
				(type default)
			)
			(layer "F.Fab")
		)
		(fp_line
			(start 0.12065 -0.3048)
			(end 0.67945 -0.3048)
			(stroke
				(width 0.1)
				(type default)
			)
			(layer "F.Fab")
		)
		(fp_line
			(start 0.67945 -0.3048)
			(end 0.67945 0.3048)
			(stroke
				(width 0.1)
				(type default)
			)
			(layer "F.Fab")
		)
		(fp_line
			(start -0.67945 -0.305054)
			(end -0.12065 -0.305054)
			(stroke
				(width 0.1)
				(type default)
			)
			(layer "F.Fab")
		)
		(fp_line
			(start -0.12065 -0.305054)
			(end -0.12065 -0.2794)
			(stroke
				(width 0.1)
				(type default)
			)
			(layer "F.Fab")
		)
		(pad "1" smd circle
			(at -0.40005 0 270)
			(size 0 0)
			(layers "F.Cu" "F.Mask" "F.Paste")
			(net "GND")
		)
		(pad "2" smd circle
			(at 0.40005 0 270)
			(size 0 0)
			(layers "F.Cu" "F.Mask" "F.Paste")
			(net "PVCCIN_CPU0_VREF")
		)
	)
	(footprint ""
		(layer "F.Cu")
		(at 366.678718 -417.14801 90)
		(property "Reference" "R4211"
			(at 0 0 90)
			(layer "F.SilkS")
			(hide yes)
			(effects
				(font
					(size 1.27 1.27)
				)
			)
		)
		(property "Value" ""
			(at 0 0 90)
			(layer "F.Fab")
			(effects
				(font
					(size 1.27 1.27)
				)
			)
		)
		(duplicate_pad_numbers_are_jumpers no)
		(fp_line
			(start 0.7874 -0.4064)
			(end 0.7874 0.4064)
			(stroke
				(width 0.1524)
				(type default)
			)
			(layer "F.SilkS")
		)
		(fp_line
			(start -0.7874 -0.4064)
			(end 0.7874 -0.4064)
			(stroke
				(width 0.1524)
				(type default)
			)
			(layer "F.SilkS")
		)
		(fp_line
			(start 0.7874 0.4064)
			(end -0.7874 0.4064)
			(stroke
				(width 0.1524)
				(type default)
			)
			(layer "F.SilkS")
		)
		(fp_line
			(start -0.7874 0.4064)
			(end -0.7874 -0.4064)
			(stroke
				(width 0.1524)
				(type default)
			)
			(layer "F.SilkS")
		)
		(fp_line
			(start -0.12065 -0.305054)
			(end -0.12065 -0.2794)
			(stroke
				(width 0.1)
				(type default)
			)
			(layer "F.Fab")
		)
		(fp_line
			(start -0.67945 -0.305054)
			(end -0.12065 -0.305054)
			(stroke
				(width 0.1)
				(type default)
			)
			(layer "F.Fab")
		)
		(fp_line
			(start 0.67945 -0.3048)
			(end 0.67945 0.3048)
			(stroke
				(width 0.1)
				(type default)
			)
			(layer "F.Fab")
		)
		(fp_line
			(start 0.12065 -0.3048)
			(end 0.67945 -0.3048)
			(stroke
				(width 0.1)
				(type default)
			)
			(layer "F.Fab")
		)
		(fp_line
			(start 0.12065 -0.2794)
			(end 0.12065 -0.3048)
			(stroke
				(width 0.1)
				(type default)
			)
			(layer "F.Fab")
		)
		(fp_line
			(start -0.12065 -0.2794)
			(end 0.12065 -0.2794)
			(stroke
				(width 0.1)
				(type default)
			)
			(layer "F.Fab")
		)
		(fp_line
			(start 0.120396 0.2794)
			(end -0.12065 0.2794)
			(stroke
				(width 0.1)
				(type default)
			)
			(layer "F.Fab")
		)
		(fp_line
			(start -0.12065 0.2794)
			(end -0.12065 0.3048)
			(stroke
				(width 0.1)
				(type default)
			)
			(layer "F.Fab")
		)
		(fp_line
			(start 0.67945 0.3048)
			(end 0.120396 0.3048)
			(stroke
				(width 0.1)
				(type default)
			)
			(layer "F.Fab")
		)
		(fp_line
			(start 0.120396 0.3048)
			(end 0.120396 0.2794)
			(stroke
				(width 0.1)
				(type default)
			)
			(layer "F.Fab")
		)
		(fp_line
			(start -0.12065 0.3048)
			(end -0.67945 0.3048)
			(stroke
				(width 0.1)
				(type default)
			)
			(layer "F.Fab")
		)
		(fp_line
			(start -0.67945 0.3048)
			(end -0.67945 -0.305054)
			(stroke
				(width 0.1)
				(type default)
			)
			(layer "F.Fab")
		)
		(pad "1" smd circle
			(at -0.40005 0 90)
			(size 0 0)
			(layers "F.Cu" "F.Mask" "F.Paste")
			(net "P3V3_AUX")
		)
		(pad "2" smd circle
			(at 0.40005 0 90)
			(size 0 0)
			(layers "F.Cu" "F.Mask" "F.Paste")
			(net "FM_THERMAL_ALERT_N")
		)
	)
	(footprint ""
		(layer "F.Cu")
		(at 126.67488 -92.674948 -90)
		(property "Reference" "R4400"
			(at 0 0 270)
			(layer "F.SilkS")
			(hide yes)
			(effects
				(font
					(size 1.27 1.27)
				)
			)
		)
		(property "Value" ""
			(at 0 0 270)
			(layer "F.Fab")
			(effects
				(font
					(size 1.27 1.27)
				)
			)
		)
		(duplicate_pad_numbers_are_jumpers no)
		(fp_line
			(start -0.7874 0.4064)
			(end -0.7874 -0.4064)
			(stroke
				(width 0.1524)
				(type default)
			)
			(layer "F.SilkS")
		)
		(fp_line
			(start 0.7874 0.4064)
			(end -0.7874 0.4064)
			(stroke
				(width 0.1524)
				(type default)
			)
			(layer "F.SilkS")
		)
		(fp_line
			(start -0.7874 -0.4064)
			(end 0.7874 -0.4064)
			(stroke
				(width 0.1524)
				(type default)
			)
			(layer "F.SilkS")
		)
		(fp_line
			(start 0.7874 -0.4064)
			(end 0.7874 0.4064)
			(stroke
				(width 0.1524)
				(type default)
			)
			(layer "F.SilkS")
		)
		(fp_line
			(start -0.67945 0.3048)
			(end -0.67945 -0.305054)
			(stroke
				(width 0.1)
				(type default)
			)
			(layer "F.Fab")
		)
		(fp_line
			(start -0.12065 0.3048)
			(end -0.67945 0.3048)
			(stroke
				(width 0.1)
				(type default)
			)
			(layer "F.Fab")
		)
		(fp_line
			(start 0.120396 0.3048)
			(end 0.120396 0.2794)
			(stroke
				(width 0.1)
				(type default)
			)
			(layer "F.Fab")
		)
		(fp_line
			(start 0.67945 0.3048)
			(end 0.120396 0.3048)
			(stroke
				(width 0.1)
				(type default)
			)
			(layer "F.Fab")
		)
		(fp_line
			(start -0.12065 0.2794)
			(end -0.12065 0.3048)
			(stroke
				(width 0.1)
				(type default)
			)
			(layer "F.Fab")
		)
		(fp_line
			(start 0.120396 0.2794)
			(end -0.12065 0.2794)
			(stroke
				(width 0.1)
				(type default)
			)
			(layer "F.Fab")
		)
		(fp_line
			(start -0.12065 -0.2794)
			(end 0.12065 -0.2794)
			(stroke
				(width 0.1)
				(type default)
			)
			(layer "F.Fab")
		)
		(fp_line
			(start 0.12065 -0.2794)
			(end 0.12065 -0.3048)
			(stroke
				(width 0.1)
				(type default)
			)
			(layer "F.Fab")
		)
		(fp_line
			(start 0.12065 -0.3048)
			(end 0.67945 -0.3048)
			(stroke
				(width 0.1)
				(type default)
			)
			(layer "F.Fab")
		)
		(fp_line
			(start 0.67945 -0.3048)
			(end 0.67945 0.3048)
			(stroke
				(width 0.1)
				(type default)
			)
			(layer "F.Fab")
		)
		(fp_line
			(start -0.67945 -0.305054)
			(end -0.12065 -0.305054)
			(stroke
				(width 0.1)
				(type default)
			)
			(layer "F.Fab")
		)
		(fp_line
			(start -0.12065 -0.305054)
			(end -0.12065 -0.2794)
			(stroke
				(width 0.1)
				(type default)
			)
			(layer "F.Fab")
		)
		(pad "1" smd circle
			(at -0.40005 0 270)
			(size 0 0)
			(layers "F.Cu" "F.Mask" "F.Paste")
			(net "H_CPU1_THERMTRIP_VT_N")
		)
		(pad "2" smd circle
			(at 0.40005 0 270)
			(size 0 0)
			(layers "F.Cu" "F.Mask" "F.Paste")
			(net "H_CPU1_THERMTRIP_LVC1_N")
		)
	)
	(footprint ""
		(layer "F.Cu")
		(at 204.724 -92.6338 90)
		(property "Reference" "R4774"
			(at 0 0 90)
			(layer "F.SilkS")
			(hide yes)
			(effects
				(font
					(size 1.27 1.27)
				)
			)
		)
		(property "Value" ""
			(at 0 0 90)
			(layer "F.Fab")
			(effects
				(font
					(size 1.27 1.27)
				)
			)
		)
		(duplicate_pad_numbers_are_jumpers no)
		(fp_line
			(start 0.7874 -0.4064)
			(end 0.7874 0.4064)
			(stroke
				(width 0.1524)
				(type default)
			)
			(layer "F.SilkS")
		)
		(fp_line
			(start -0.7874 -0.4064)
			(end 0.7874 -0.4064)
			(stroke
				(width 0.1524)
				(type default)
			)
			(layer "F.SilkS")
		)
		(fp_line
			(start 0.7874 0.4064)
			(end -0.7874 0.4064)
			(stroke
				(width 0.1524)
				(type default)
			)
			(layer "F.SilkS")
		)
		(fp_line
			(start -0.7874 0.4064)
			(end -0.7874 -0.4064)
			(stroke
				(width 0.1524)
				(type default)
			)
			(layer "F.SilkS")
		)
		(fp_line
			(start -0.12065 -0.305054)
			(end -0.12065 -0.2794)
			(stroke
				(width 0.1)
				(type default)
			)
			(layer "F.Fab")
		)
		(fp_line
			(start -0.67945 -0.305054)
			(end -0.12065 -0.305054)
			(stroke
				(width 0.1)
				(type default)
			)
			(layer "F.Fab")
		)
		(fp_line
			(start 0.67945 -0.3048)
			(end 0.67945 0.3048)
			(stroke
				(width 0.1)
				(type default)
			)
			(layer "F.Fab")
		)
		(fp_line
			(start 0.12065 -0.3048)
			(end 0.67945 -0.3048)
			(stroke
				(width 0.1)
				(type default)
			)
			(layer "F.Fab")
		)
		(fp_line
			(start 0.12065 -0.2794)
			(end 0.12065 -0.3048)
			(stroke
				(width 0.1)
				(type default)
			)
			(layer "F.Fab")
		)
		(fp_line
			(start -0.12065 -0.2794)
			(end 0.12065 -0.2794)
			(stroke
				(width 0.1)
				(type default)
			)
			(layer "F.Fab")
		)
		(fp_line
			(start 0.120396 0.2794)
			(end -0.12065 0.2794)
			(stroke
				(width 0.1)
				(type default)
			)
			(layer "F.Fab")
		)
		(fp_line
			(start -0.12065 0.2794)
			(end -0.12065 0.3048)
			(stroke
				(width 0.1)
				(type default)
			)
			(layer "F.Fab")
		)
		(fp_line
			(start 0.67945 0.3048)
			(end 0.120396 0.3048)
			(stroke
				(width 0.1)
				(type default)
			)
			(layer "F.Fab")
		)
		(fp_line
			(start 0.120396 0.3048)
			(end 0.120396 0.2794)
			(stroke
				(width 0.1)
				(type default)
			)
			(layer "F.Fab")
		)
		(fp_line
			(start -0.12065 0.3048)
			(end -0.67945 0.3048)
			(stroke
				(width 0.1)
				(type default)
			)
			(layer "F.Fab")
		)
		(fp_line
			(start -0.67945 0.3048)
			(end -0.67945 -0.305054)
			(stroke
				(width 0.1)
				(type default)
			)
			(layer "F.Fab")
		)
		(pad "1" smd circle
			(at -0.40005 0 90)
			(size 0 0)
			(layers "F.Cu" "F.Mask" "F.Paste")
			(net "P12V_AUX")
		)
		(pad "2" smd circle
			(at 0.40005 0 90)
			(size 0 0)
			(layers "F.Cu" "F.Mask" "F.Paste")
			(net "P12V_AUX_UV_ADR_TRIGGER")
		)
	)
	(footprint ""
		(layer "F.Cu")
		(at 116.561616 -241.97691 -90)
		(property "Reference" "C286"
			(at 0 0 270)
			(layer "F.SilkS")
			(hide yes)
			(effects
				(font
					(size 1.27 1.27)
				)
			)
		)
		(property "Value" ""
			(at 0 0 270)
			(layer "F.Fab")
			(effects
				(font
					(size 1.27 1.27)
				)
			)
		)
		(duplicate_pad_numbers_are_jumpers no)
		(fp_line
			(start -0.7874 0.4064)
			(end -0.7874 -0.4064)
			(stroke
				(width 0.1524)
				(type default)
			)
			(layer "F.SilkS")
		)
		(fp_line
			(start 0.7874 0.4064)
			(end -0.7874 0.4064)
			(stroke
				(width 0.1524)
				(type default)
			)
			(layer "F.SilkS")
		)
		(fp_line
			(start -0.7874 -0.4064)
			(end 0.7874 -0.4064)
			(stroke
				(width 0.1524)
				(type default)
			)
			(layer "F.SilkS")
		)
		(fp_line
			(start 0.7874 -0.4064)
			(end 0.7874 0.4064)
			(stroke
				(width 0.1524)
				(type default)
			)
			(layer "F.SilkS")
		)
		(fp_line
			(start -0.67945 0.3048)
			(end -0.67945 -0.305054)
			(stroke
				(width 0.1)
				(type default)
			)
			(layer "F.Fab")
		)
		(fp_line
			(start -0.12065 0.3048)
			(end -0.67945 0.3048)
			(stroke
				(width 0.1)
				(type default)
			)
			(layer "F.Fab")
		)
		(fp_line
			(start 0.120396 0.3048)
			(end 0.120396 0.2794)
			(stroke
				(width 0.1)
				(type default)
			)
			(layer "F.Fab")
		)
		(fp_line
			(start 0.67945 0.3048)
			(end 0.120396 0.3048)
			(stroke
				(width 0.1)
				(type default)
			)
			(layer "F.Fab")
		)
		(fp_line
			(start -0.12065 0.2794)
			(end -0.12065 0.3048)
			(stroke
				(width 0.1)
				(type default)
			)
			(layer "F.Fab")
		)
		(fp_line
			(start 0.120396 0.2794)
			(end -0.12065 0.2794)
			(stroke
				(width 0.1)
				(type default)
			)
			(layer "F.Fab")
		)
		(fp_line
			(start -0.12065 -0.2794)
			(end 0.12065 -0.2794)
			(stroke
				(width 0.1)
				(type default)
			)
			(layer "F.Fab")
		)
		(fp_line
			(start 0.12065 -0.2794)
			(end 0.12065 -0.3048)
			(stroke
				(width 0.1)
				(type default)
			)
			(layer "F.Fab")
		)
		(fp_line
			(start 0.12065 -0.3048)
			(end 0.67945 -0.3048)
			(stroke
				(width 0.1)
				(type default)
			)
			(layer "F.Fab")
		)
		(fp_line
			(start 0.67945 -0.3048)
			(end 0.67945 0.3048)
			(stroke
				(width 0.1)
				(type default)
			)
			(layer "F.Fab")
		)
		(fp_line
			(start -0.67945 -0.305054)
			(end -0.12065 -0.305054)
			(stroke
				(width 0.1)
				(type default)
			)
			(layer "F.Fab")
		)
		(fp_line
			(start -0.12065 -0.305054)
			(end -0.12065 -0.2794)
			(stroke
				(width 0.1)
				(type default)
			)
			(layer "F.Fab")
		)
		(pad "1" smd circle
			(at -0.40005 0 270)
			(size 0 0)
			(layers "F.Cu" "F.Mask" "F.Paste")
			(net "PVCCIN_CPU1")
		)
		(pad "2" smd circle
			(at 0.40005 0 270)
			(size 0 0)
			(layers "F.Cu" "F.Mask" "F.Paste")
			(net "GND")
		)
	)
	(footprint ""
		(layer "F.Cu")
		(at 157.28188 -108.295948 180)
		(property "Reference" "R2071"
			(at 0 0 180)
			(layer "F.SilkS")
			(hide yes)
			(effects
				(font
					(size 1.27 1.27)
				)
			)
		)
		(property "Value" ""
			(at 0 0 180)
			(layer "F.Fab")
			(effects
				(font
					(size 1.27 1.27)
				)
			)
		)
		(duplicate_pad_numbers_are_jumpers no)
		(fp_line
			(start 0.7874 0.4064)
			(end -0.7874 0.4064)
			(stroke
				(width 0.1524)
				(type default)
			)
			(layer "F.SilkS")
		)
		(fp_line
			(start 0.7874 -0.4064)
			(end 0.7874 0.4064)
			(stroke
				(width 0.1524)
				(type default)
			)
			(layer "F.SilkS")
		)
		(fp_line
			(start -0.7874 0.4064)
			(end -0.7874 -0.4064)
			(stroke
				(width 0.1524)
				(type default)
			)
			(layer "F.SilkS")
		)
		(fp_line
			(start -0.7874 -0.4064)
			(end 0.7874 -0.4064)
			(stroke
				(width 0.1524)
				(type default)
			)
			(layer "F.SilkS")
		)
		(fp_line
			(start 0.67945 0.3048)
			(end 0.120396 0.3048)
			(stroke
				(width 0.1)
				(type default)
			)
			(layer "F.Fab")
		)
		(fp_line
			(start 0.67945 -0.3048)
			(end 0.67945 0.3048)
			(stroke
				(width 0.1)
				(type default)
			)
			(layer "F.Fab")
		)
		(fp_line
			(start 0.12065 -0.2794)
			(end 0.12065 -0.3048)
			(stroke
				(width 0.1)
				(type default)
			)
			(layer "F.Fab")
		)
		(fp_line
			(start 0.12065 -0.3048)
			(end 0.67945 -0.3048)
			(stroke
				(width 0.1)
				(type default)
			)
			(layer "F.Fab")
		)
		(fp_line
			(start 0.120396 0.3048)
			(end 0.120396 0.2794)
			(stroke
				(width 0.1)
				(type default)
			)
			(layer "F.Fab")
		)
		(fp_line
			(start 0.120396 0.2794)
			(end -0.12065 0.2794)
			(stroke
				(width 0.1)
				(type default)
			)
			(layer "F.Fab")
		)
		(fp_line
			(start -0.12065 0.3048)
			(end -0.67945 0.3048)
			(stroke
				(width 0.1)
				(type default)
			)
			(layer "F.Fab")
		)
		(fp_line
			(start -0.12065 0.2794)
			(end -0.12065 0.3048)
			(stroke
				(width 0.1)
				(type default)
			)
			(layer "F.Fab")
		)
		(fp_line
			(start -0.12065 -0.2794)
			(end 0.12065 -0.2794)
			(stroke
				(width 0.1)
				(type default)
			)
			(layer "F.Fab")
		)
		(fp_line
			(start -0.12065 -0.305054)
			(end -0.12065 -0.2794)
			(stroke
				(width 0.1)
				(type default)
			)
			(layer "F.Fab")
		)
		(fp_line
			(start -0.67945 0.3048)
			(end -0.67945 -0.305054)
			(stroke
				(width 0.1)
				(type default)
			)
			(layer "F.Fab")
		)
		(fp_line
			(start -0.67945 -0.305054)
			(end -0.12065 -0.305054)
			(stroke
				(width 0.1)
				(type default)
			)
			(layer "F.Fab")
		)
		(pad "1" smd circle
			(at -0.40005 0 180)
			(size 0 0)
			(layers "F.Cu" "F.Mask" "F.Paste")
			(net "FM_BMC_SUSACK_R_N")
		)
		(pad "2" smd circle
			(at 0.40005 0 180)
			(size 0 0)
			(layers "F.Cu" "F.Mask" "F.Paste")
			(net "FM_SUSACK_N")
		)
	)
	(footprint ""
		(layer "F.Cu")
		(at 6.999986 -22.29993)
		(property "Reference" "H100"
			(at -4.17322 -5.964428 0)
			(unlocked yes)
			(layer "F.SilkS")
			(effects
				(font
					(size 0.7874 0.5842)
					(thickness 0.1524)
				)
				(justify left)
			)
		)
		(property "Value" ""
			(at 0 0 0)
			(layer "F.Fab")
			(effects
				(font
					(size 1.27 1.27)
				)
			)
		)
		(duplicate_pad_numbers_are_jumpers no)
		(pad "1" thru_hole circle
			(at 0 0)
			(size 10.0076 10.0076)
			(drill 5.6134)
			(layers "*.Cu" "*.Mask")
			(remove_unused_layers no)
			(net "GND")
			(clearance -1.9431)
		)
	)
	(footprint ""
		(layer "F.Cu")
		(at 27.662886 -164.827204 -90)
		(property "Reference" "PU18"
			(at -0.638048 -8.11022 0)
			(unlocked yes)
			(layer "F.SilkS")
			(effects
				(font
					(size 0.7874 0.5842)
					(thickness 0.1524)
				)
			)
		)
		(property "Value" ""
			(at 0 0 270)
			(layer "F.Fab")
			(effects
				(font
					(size 1.27 1.27)
				)
			)
		)
		(duplicate_pad_numbers_are_jumpers no)
		(fp_line
			(start 1.778 3.6322)
			(end 1.778 2.8702)
			(stroke
				(width 0.1524)
				(type default)
			)
			(layer "F.SilkS")
		)
		(fp_line
			(start -0.2032 2.8829)
			(end -0.2032 3.2639)
			(stroke
				(width 0.1524)
				(type default)
			)
			(layer "F.SilkS")
		)
		(fp_line
			(start -2.500122 2.500122)
			(end -2.500122 2.018538)
			(stroke
				(width 0.1524)
				(type default)
			)
			(layer "F.SilkS")
		)
		(fp_line
			(start -2.015998 2.500122)
			(end -2.500122 2.500122)
			(stroke
				(width 0.1524)
				(type default)
			)
			(layer "F.SilkS")
		)
		(fp_line
			(start 2.500122 2.500122)
			(end 2.015998 2.500122)
			(stroke
				(width 0.1524)
				(type default)
			)
			(layer "F.SilkS")
		)
		(fp_line
			(start 2.500122 2.015998)
			(end 2.500122 2.500122)
			(stroke
				(width 0.1524)
				(type default)
			)
			(layer "F.SilkS")
		)
		(fp_line
			(start -3.6576 1.8034)
			(end -2.8956 1.8034)
			(stroke
				(width 0.1524)
				(type default)
			)
			(layer "F.SilkS")
		)
		(fp_line
			(start 2.8829 0.2032)
			(end 3.2639 0.2032)
			(stroke
				(width 0.1524)
				(type default)
			)
			(layer "F.SilkS")
		)
		(fp_line
			(start -3.2639 -0.1778)
			(end -2.8829 -0.1778)
			(stroke
				(width 0.1524)
				(type default)
			)
			(layer "F.SilkS")
		)
		(fp_line
			(start 2.8702 -1.778)
			(end 3.6322 -1.778)
			(stroke
				(width 0.1524)
				(type default)
			)
			(layer "F.SilkS")
		)
		(fp_line
			(start -2.500122 -2.015998)
			(end -2.500122 -2.500122)
			(stroke
				(width 0.1524)
				(type default)
			)
			(layer "F.SilkS")
		)
		(fp_line
			(start -2.500122 -2.500122)
			(end -2.015998 -2.500122)
			(stroke
				(width 0.1524)
				(type default)
			)
			(layer "F.SilkS")
		)
		(fp_line
			(start 2.015998 -2.500122)
			(end 2.500122 -2.500122)
			(stroke
				(width 0.1524)
				(type default)
			)
			(layer "F.SilkS")
		)
		(fp_line
			(start 2.500122 -2.500122)
			(end 2.500122 -2.015998)
			(stroke
				(width 0.1524)
				(type default)
			)
			(layer "F.SilkS")
		)
		(fp_line
			(start -1.8034 -2.8702)
			(end -1.8034 -3.6322)
			(stroke
				(width 0.1524)
				(type default)
			)
			(layer "F.SilkS")
		)
		(fp_line
			(start 0.1778 -3.2385)
			(end 0.1778 -2.8575)
			(stroke
				(width 0.1524)
				(type default)
			)
			(layer "F.SilkS")
		)
		(fp_poly
			(pts
				(xy -3.295142 -2.36601) (xy -2.882646 -2.778506) (xy -2.676398 -2.160016)
			)
			(stroke
				(width 0)
				(type default)
			)
			(fill yes)
			(layer "F.SilkS")
		)
		(fp_line
			(start 1.778 3.6322)
			(end 1.778 2.8702)
			(stroke
				(width 0.1)
				(type default)
			)
			(layer "F.Fab")
		)
		(fp_line
			(start -0.2032 2.8829)
			(end -0.2032 3.2639)
			(stroke
				(width 0.1)
				(type default)
			)
			(layer "F.Fab")
		)
		(fp_line
			(start -2.500122 2.500122)
			(end -2.500122 -2.500122)
			(stroke
				(width 0.1)
				(type default)
			)
			(layer "F.Fab")
		)
		(fp_line
			(start 2.500122 2.500122)
			(end -2.500122 2.500122)
			(stroke
				(width 0.1)
				(type default)
			)
			(layer "F.Fab")
		)
		(fp_line
			(start -3.6576 1.8034)
			(end -2.8956 1.8034)
			(stroke
				(width 0.1)
				(type default)
			)
			(layer "F.Fab")
		)
		(fp_line
			(start 2.8829 0.2032)
			(end 3.2639 0.2032)
			(stroke
				(width 0.1)
				(type default)
			)
			(layer "F.Fab")
		)
		(fp_line
			(start -3.2639 -0.1778)
			(end -2.8829 -0.1778)
			(stroke
				(width 0.1)
				(type default)
			)
			(layer "F.Fab")
		)
		(fp_line
			(start 2.8702 -1.778)
			(end 3.6322 -1.778)
			(stroke
				(width 0.1)
				(type default)
			)
			(layer "F.Fab")
		)
		(fp_line
			(start -2.500122 -2.500122)
			(end 2.500122 -2.500122)
			(stroke
				(width 0.1)
				(type default)
			)
			(layer "F.Fab")
		)
		(fp_line
			(start 2.500122 -2.500122)
			(end 2.500122 2.500122)
			(stroke
				(width 0.1)
				(type default)
			)
			(layer "F.Fab")
		)
		(fp_line
			(start -1.8034 -2.8702)
			(end -1.8034 -3.6322)
			(stroke
				(width 0.1)
				(type default)
			)
			(layer "F.Fab")
		)
		(fp_line
			(start 0.1778 -3.2385)
			(end 0.1778 -2.8575)
			(stroke
				(width 0.1)
				(type default)
			)
			(layer "F.Fab")
		)
		(fp_poly
			(pts
				(xy -2.921 -1.800098) (xy -3.504184 -1.508506) (xy -3.504184 -2.09169)
			)
			(stroke
				(width 0)
				(type default)
			)
			(fill yes)
			(layer "F.Fab")
		)
		(fp_text user "11"
			(at -4.411726 4.152646 0)
			(unlocked yes)
			(layer "F.SilkS")
			(effects
				(font
					(size 0.635 0.4064)
					(thickness 0.1524)
				)
				(justify left)
			)
		)
		(fp_text user "10"
			(at -4.704334 2.981706 0)
			(unlocked yes)
			(layer "F.SilkS")
			(effects
				(font
					(size 0.635 0.4064)
					(thickness 0.1524)
				)
				(justify left)
			)
		)
		(fp_text user "20"
			(at 3.403854 2.908046 0)
			(unlocked yes)
			(layer "F.SilkS")
			(effects
				(font
					(size 0.635 0.4064)
					(thickness 0.1524)
				)
				(justify left)
			)
		)
		(fp_text user "21"
			(at 4.510786 2.796286 0)
			(unlocked yes)
			(layer "F.SilkS")
			(effects
				(font
					(size 0.635 0.4064)
					(thickness 0.1524)
				)
				(justify left)
			)
		)
		(fp_text user "30"
			(at 4.480306 -1.526794 0)
			(unlocked yes)
			(layer "F.SilkS")
			(effects
				(font
					(size 0.635 0.4064)
					(thickness 0.1524)
				)
				(justify left)
			)
		)
		(fp_text user "31"
			(at 3.184906 -2.288794 0)
			(unlocked yes)
			(layer "F.SilkS")
			(effects
				(font
					(size 0.635 0.4064)
					(thickness 0.1524)
				)
				(justify left)
			)
		)
		(fp_text user "40"
			(at -4.485894 -5.463794 0)
			(unlocked yes)
			(layer "F.SilkS")
			(effects
				(font
					(size 0.635 0.4064)
					(thickness 0.1524)
				)
				(justify left)
			)
		)
		(fp_text user "11"
			(at -2.8702 3.278632 270)
			(unlocked yes)
			(layer "F.Fab")
			(effects
				(font
					(size 0.635 0.4064)
					(thickness 0.1524)
				)
				(justify left)
			)
		)
		(fp_text user "20"
			(at 2.0828 3.253232 270)
			(unlocked yes)
			(layer "F.Fab")
			(effects
				(font
					(size 0.635 0.4064)
					(thickness 0.1524)
				)
				(justify left)
			)
		)
		(fp_text user "10"
			(at -3.253232 2.1336 180)
			(unlocked yes)
			(layer "F.Fab")
			(effects
				(font
					(size 0.635 0.4064)
					(thickness 0.1524)
				)
				(justify left)
			)
		)
		(fp_text user "21"
			(at 3.274568 1.8796 180)
			(unlocked yes)
			(layer "F.Fab")
			(effects
				(font
					(size 0.635 0.4064)
					(thickness 0.1524)
				)
				(justify left)
			)
		)
		(fp_text user "40"
			(at -3.2004 -3.096768 270)
			(unlocked yes)
			(layer "F.Fab")
			(effects
				(font
					(size 0.635 0.4064)
					(thickness 0.1524)
				)
				(justify left)
			)
		)
		(fp_text user "30"
			(at 3.223768 -3.0988 180)
			(unlocked yes)
			(layer "F.Fab")
			(effects
				(font
					(size 0.635 0.4064)
					(thickness 0.1524)
				)
				(justify left)
			)
		)
		(fp_text user "31"
			(at 1.8542 -3.172968 270)
			(unlocked yes)
			(layer "F.Fab")
			(effects
				(font
					(size 0.635 0.4064)
					(thickness 0.1524)
				)
				(justify left)
			)
		)
		(pad "1" smd rect
			(at -2.400046 -1.800098 180)
			(size 0.1778 0.6096)
			(layers "F.Cu" "F.Mask" "F.Paste")
			(net "NC_PVCCD_HV_CPU1_APWM8")
		)
		(pad "2" smd rect
			(at -2.400046 -1.400048 180)
			(size 0.1778 0.6096)
			(layers "F.Cu" "F.Mask" "F.Paste")
			(net "NC_PVCCD_HV_CPU1_APWM7")
		)
		(pad "3" smd rect
			(at -2.400046 -0.999998 180)
			(size 0.1778 0.6096)
			(layers "F.Cu" "F.Mask" "F.Paste")
			(net "NC_PVCCD_HV_CPU1_APWM6")
		)
		(pad "4" smd rect
			(at -2.400046 -0.599948 180)
			(size 0.1778 0.6096)
			(layers "F.Cu" "F.Mask" "F.Paste")
			(net "NC_PVCCD_HV_CPU1_APWM5")
		)
		(pad "5" smd rect
			(at -2.400046 -0.199898 180)
			(size 0.1778 0.6096)
			(layers "F.Cu" "F.Mask" "F.Paste")
			(net "NC_PVCCD_HV_CPU1_APWM4")
		)
		(pad "6" smd rect
			(at -2.400046 0.199898 180)
			(size 0.1778 0.6096)
			(layers "F.Cu" "F.Mask" "F.Paste")
			(net "NC_PVCCD_HV_CPU1_APWM3")
		)
		(pad "7" smd rect
			(at -2.400046 0.599948 180)
			(size 0.1778 0.6096)
			(layers "F.Cu" "F.Mask" "F.Paste")
			(net "NC_PVCCD_HV_CPU1_APWM2")
		)
		(pad "8" smd rect
			(at -2.400046 0.999998 180)
			(size 0.1778 0.6096)
			(layers "F.Cu" "F.Mask" "F.Paste")
			(net "PVCCD_HV_CPU1_APWM1")
		)
		(pad "9" smd rect
			(at -2.400046 1.400048 180)
			(size 0.1778 0.6096)
			(layers "F.Cu" "F.Mask" "F.Paste")
			(net "SMB_DIO_PVCCD_HV_CPU1")
		)
		(pad "10" smd rect
			(at -2.400046 1.800098 180)
			(size 0.1778 0.6096)
			(layers "F.Cu" "F.Mask" "F.Paste")
			(net "SMB_CLK_PVCCD_HV_CPU1")
		)
		(pad "11" smd rect
			(at -1.800098 2.400046 270)
			(size 0.1778 0.6096)
			(layers "F.Cu" "F.Mask" "F.Paste")
			(net "NC_PVCCD_HV_CPU1_SMB_ALERT")
		)
		(pad "12" smd rect
			(at -1.400048 2.400046 270)
			(size 0.1778 0.6096)
			(layers "F.Cu" "F.Mask" "F.Paste")
			(net "PWRGD_PVCCD_HV_CPU1_R")
		)
		(pad "13" smd rect
			(at -0.999998 2.400046 270)
			(size 0.1778 0.6096)
			(layers "F.Cu" "F.Mask" "F.Paste")
			(net "PVCCD_HV_CPU1_EN_R")
		)
		(pad "14" smd rect
			(at -0.599948 2.400046 270)
			(size 0.1778 0.6096)
			(layers "F.Cu" "F.Mask" "F.Paste")
			(net "IRQ_PVCCD_CPU1_VRHOT_LVC3_R_N")
		)
		(pad "15" smd rect
			(at -0.199898 2.400046 270)
			(size 0.1778 0.6096)
			(layers "F.Cu" "F.Mask" "F.Paste")
			(net "PVCCD_HV_CPU1_PIN_ALT")
		)
		(pad "16" smd rect
			(at 0.199898 2.400046 270)
			(size 0.1778 0.6096)
			(layers "F.Cu" "F.Mask" "F.Paste")
			(net "NC_PVCCD_HV_CPU1_BVR_RDY")
		)
		(pad "17" smd rect
			(at 0.599948 2.400046 270)
			(size 0.1778 0.6096)
			(layers "F.Cu" "F.Mask" "F.Paste")
			(net "SVID_CLK_PVCCD_HV_CPU1_R")
		)
		(pad "18" smd rect
			(at 0.999998 2.400046 270)
			(size 0.1778 0.6096)
			(layers "F.Cu" "F.Mask" "F.Paste")
			(net "SVID_DIO_PVCCD_HV_CPU1_R")
		)
		(pad "19" smd rect
			(at 1.400048 2.400046 270)
			(size 0.1778 0.6096)
			(layers "F.Cu" "F.Mask" "F.Paste")
			(net "SVID_ALERT_PVCCD_HV_CPU1_R")
		)
		(pad "20" smd rect
			(at 1.800098 2.400046 270)
			(size 0.1778 0.6096)
			(layers "F.Cu" "F.Mask" "F.Paste")
			(net "GND")
		)
		(pad "21" smd rect
			(at 2.400046 1.800098 180)
			(size 0.1778 0.6096)
			(layers "F.Cu" "F.Mask" "F.Paste")
			(net "SH_PVCCD_HV_CPU1_R")
		)
		(pad "22" smd rect
			(at 2.400046 1.400048 180)
			(size 0.1778 0.6096)
			(layers "F.Cu" "F.Mask" "F.Paste")
			(net "VSENSE_PVCCD_HV_CPU1_DN")
		)
		(pad "23" smd rect
			(at 2.400046 0.999998 180)
			(size 0.1778 0.6096)
			(layers "F.Cu" "F.Mask" "F.Paste")
			(net "PVCCD_HV_CPU1_ACSP1")
		)
		(pad "24" smd rect
			(at 2.400046 0.599948 180)
			(size 0.1778 0.6096)
			(layers "F.Cu" "F.Mask" "F.Paste")
			(net "NC_PVCCD_HV_CPU1_ACSP2")
		)
		(pad "25" smd rect
			(at 2.400046 0.199898 180)
			(size 0.1778 0.6096)
			(layers "F.Cu" "F.Mask" "F.Paste")
			(net "NC_PVCCD_HV_CPU1_ACSP3")
		)
		(pad "26" smd rect
			(at 2.400046 -0.199898 180)
			(size 0.1778 0.6096)
			(layers "F.Cu" "F.Mask" "F.Paste")
			(net "NC_PVCCD_HV_CPU1_ACSP4")
		)
		(pad "27" smd rect
			(at 2.400046 -0.599948 180)
			(size 0.1778 0.6096)
			(layers "F.Cu" "F.Mask" "F.Paste")
			(net "NC_PVCCD_HV_CPU1_ACSP5")
		)
		(pad "28" smd rect
			(at 2.400046 -0.999998 180)
			(size 0.1778 0.6096)
			(layers "F.Cu" "F.Mask" "F.Paste")
			(net "NC_PVCCD_HV_CPU1_ACSP6")
		)
		(pad "29" smd rect
			(at 2.400046 -1.400048 180)
			(size 0.1778 0.6096)
			(layers "F.Cu" "F.Mask" "F.Paste")
			(net "NC_PVCCD_HV_CPU1_ACSP7")
		)
		(pad "30" smd rect
			(at 2.400046 -1.800098 180)
			(size 0.1778 0.6096)
			(layers "F.Cu" "F.Mask" "F.Paste")
			(net "NC_PVCCD_HV_CPU1_ACSP8")
		)
		(pad "31" smd rect
			(at 1.800098 -2.400046 270)
			(size 0.1778 0.6096)
			(layers "F.Cu" "F.Mask" "F.Paste")
			(net "GND")
		)
		(pad "32" smd rect
			(at 1.400048 -2.400046 270)
			(size 0.1778 0.6096)
			(layers "F.Cu" "F.Mask" "F.Paste")
			(net "GND")
		)
		(pad "33" smd rect
			(at 0.999998 -2.400046 270)
			(size 0.1778 0.6096)
			(layers "F.Cu" "F.Mask" "F.Paste")
			(net "PVCCD_HV_CPU1_FAULT")
		)
		(pad "34" smd rect
			(at 0.599948 -2.400046 270)
			(size 0.1778 0.6096)
			(layers "F.Cu" "F.Mask" "F.Paste")
			(net "PVCCD_HV_CPU1_ADDR")
		)
		(pad "35" smd rect
			(at 0.199898 -2.400046 270)
			(size 0.1778 0.6096)
			(layers "F.Cu" "F.Mask" "F.Paste")
			(net "PVCCD_HV_CPU1_ATSEN")
		)
		(pad "36" smd rect
			(at -0.199898 -2.400046 270)
			(size 0.1778 0.6096)
			(layers "F.Cu" "F.Mask" "F.Paste")
			(net "PVCCD_HV_CPU1_ISYS_R")
		)
		(pad "37" smd rect
			(at -0.599948 -2.400046 270)
			(size 0.1778 0.6096)
			(layers "F.Cu" "F.Mask" "F.Paste")
			(net "PVCCD_HV_CPU1_ISENSE_P")
		)
		(pad "38" smd rect
			(at -0.999998 -2.400046 270)
			(size 0.1778 0.6096)
			(layers "F.Cu" "F.Mask" "F.Paste")
			(net "PVCCD_HV_CPU1_ISENSE_N")
		)
		(pad "39" smd rect
			(at -1.400048 -2.400046 270)
			(size 0.1778 0.6096)
			(layers "F.Cu" "F.Mask" "F.Paste")
			(net "PVCCD_HV_CPU1_VCC")
		)
		(pad "40" smd rect
			(at -1.800098 -2.400046 270)
			(size 0.1778 0.6096)
			(layers "F.Cu" "F.Mask" "F.Paste")
			(net "PVCCD_HV_CPU1_VREF")
		)
		(pad "TH" smd rect
			(at 0 0 270)
			(size 3.6576 3.6576)
			(layers "F.Cu" "F.Mask" "F.Paste")
			(net "GND")
		)
		(zone
			(layer "F.Cu")
			(hatch none 0.5)
			(connect_pads
				(clearance 0)
			)
			(min_thickness 0.25)
			(keepout
				(tracks not_allowed)
				(vias allowed)
				(pads allowed)
				(copperpour not_allowed)
				(footprints allowed)
			)
			(placement
				(enabled no)
				(sheetname "")
			)
			(fill
				(thermal_gap 0.5)
				(thermal_bridge_width 0.5)
				(island_removal_mode 0)
			)
			(polygon
				(pts
					(xy 25.630886 -166.859204) (xy 29.517086 -166.859204) (xy 29.517086 -166.706804) (xy 25.783286 -166.706804)
					(xy 25.783286 -163.154868) (xy 25.630886 -163.154868)
				)
			)
		)
	)
	(footprint ""
		(layer "F.Cu")
		(at 342.14181 -338.298282 -90)
		(property "Reference" "PC1356"
			(at 0 0 270)
			(layer "F.SilkS")
			(hide yes)
			(effects
				(font
					(size 1.27 1.27)
				)
			)
		)
		(property "Value" ""
			(at 0 0 270)
			(layer "F.Fab")
			(effects
				(font
					(size 1.27 1.27)
				)
			)
		)
		(duplicate_pad_numbers_are_jumpers no)
		(fp_line
			(start -0.7874 0.4064)
			(end -0.7874 -0.4064)
			(stroke
				(width 0.1524)
				(type default)
			)
			(layer "F.SilkS")
		)
		(fp_line
			(start 0.7874 0.4064)
			(end -0.7874 0.4064)
			(stroke
				(width 0.1524)
				(type default)
			)
			(layer "F.SilkS")
		)
		(fp_line
			(start -0.7874 -0.4064)
			(end 0.7874 -0.4064)
			(stroke
				(width 0.1524)
				(type default)
			)
			(layer "F.SilkS")
		)
		(fp_line
			(start 0.7874 -0.4064)
			(end 0.7874 0.4064)
			(stroke
				(width 0.1524)
				(type default)
			)
			(layer "F.SilkS")
		)
		(fp_line
			(start -0.67945 0.3048)
			(end -0.67945 -0.305054)
			(stroke
				(width 0.1)
				(type default)
			)
			(layer "F.Fab")
		)
		(fp_line
			(start -0.12065 0.3048)
			(end -0.67945 0.3048)
			(stroke
				(width 0.1)
				(type default)
			)
			(layer "F.Fab")
		)
		(fp_line
			(start 0.120396 0.3048)
			(end 0.120396 0.2794)
			(stroke
				(width 0.1)
				(type default)
			)
			(layer "F.Fab")
		)
		(fp_line
			(start 0.67945 0.3048)
			(end 0.120396 0.3048)
			(stroke
				(width 0.1)
				(type default)
			)
			(layer "F.Fab")
		)
		(fp_line
			(start -0.12065 0.2794)
			(end -0.12065 0.3048)
			(stroke
				(width 0.1)
				(type default)
			)
			(layer "F.Fab")
		)
		(fp_line
			(start 0.120396 0.2794)
			(end -0.12065 0.2794)
			(stroke
				(width 0.1)
				(type default)
			)
			(layer "F.Fab")
		)
		(fp_line
			(start -0.12065 -0.2794)
			(end 0.12065 -0.2794)
			(stroke
				(width 0.1)
				(type default)
			)
			(layer "F.Fab")
		)
		(fp_line
			(start 0.12065 -0.2794)
			(end 0.12065 -0.3048)
			(stroke
				(width 0.1)
				(type default)
			)
			(layer "F.Fab")
		)
		(fp_line
			(start 0.12065 -0.3048)
			(end 0.67945 -0.3048)
			(stroke
				(width 0.1)
				(type default)
			)
			(layer "F.Fab")
		)
		(fp_line
			(start 0.67945 -0.3048)
			(end 0.67945 0.3048)
			(stroke
				(width 0.1)
				(type default)
			)
			(layer "F.Fab")
		)
		(fp_line
			(start -0.67945 -0.305054)
			(end -0.12065 -0.305054)
			(stroke
				(width 0.1)
				(type default)
			)
			(layer "F.Fab")
		)
		(fp_line
			(start -0.12065 -0.305054)
			(end -0.12065 -0.2794)
			(stroke
				(width 0.1)
				(type default)
			)
			(layer "F.Fab")
		)
		(pad "1" smd circle
			(at -0.40005 0 270)
			(size 0 0)
			(layers "F.Cu" "F.Mask" "F.Paste")
			(net "GND")
		)
		(pad "2" smd circle
			(at 0.40005 0 270)
			(size 0 0)
			(layers "F.Cu" "F.Mask" "F.Paste")
			(net "PVCCIN_CPU0_VREF")
		)
	)
	(footprint ""
		(layer "F.Cu")
		(at 298.368974 -412.80588)
		(property "Reference" "U331"
			(at -0.517652 -2.589022 0)
			(unlocked yes)
			(layer "F.SilkS")
			(effects
				(font
					(size 0.7874 0.5842)
					(thickness 0.1524)
				)
			)
		)
		(property "Value" ""
			(at 0 0 0)
			(layer "F.Fab")
			(effects
				(font
					(size 1.27 1.27)
				)
			)
		)
		(duplicate_pad_numbers_are_jumpers no)
		(fp_line
			(start -1.500124 -1.500124)
			(end -1.004062 -1.500124)
			(stroke
				(width 0.1524)
				(type default)
			)
			(layer "F.SilkS")
		)
		(fp_line
			(start -1.500124 -1.004062)
			(end -1.500124 -1.500124)
			(stroke
				(width 0.1524)
				(type default)
			)
			(layer "F.SilkS")
		)
		(fp_line
			(start -1.500124 1.500124)
			(end -1.500124 1.004062)
			(stroke
				(width 0.1524)
				(type default)
			)
			(layer "F.SilkS")
		)
		(fp_line
			(start -1.004062 1.500124)
			(end -1.500124 1.500124)
			(stroke
				(width 0.1524)
				(type default)
			)
			(layer "F.SilkS")
		)
		(fp_line
			(start 1.004062 -1.500124)
			(end 1.500124 -1.500124)
			(stroke
				(width 0.1524)
				(type default)
			)
			(layer "F.SilkS")
		)
		(fp_line
			(start 1.500124 -1.500124)
			(end 1.500124 -1.004062)
			(stroke
				(width 0.1524)
				(type default)
			)
			(layer "F.SilkS")
		)
		(fp_line
			(start 1.500124 1.004062)
			(end 1.500124 1.500124)
			(stroke
				(width 0.1524)
				(type default)
			)
			(layer "F.SilkS")
		)
		(fp_line
			(start 1.500124 1.500124)
			(end 1.004062 1.500124)
			(stroke
				(width 0.1524)
				(type default)
			)
			(layer "F.SilkS")
		)
		(fp_poly
			(pts
				(xy -2.1844 -1.649984) (xy -2.902966 -0.931418) (xy -1.825244 -0.572262)
			)
			(stroke
				(width 0)
				(type default)
			)
			(fill yes)
			(layer "F.SilkS")
		)
		(fp_line
			(start -1.500124 -1.500124)
			(end 1.500124 -1.500124)
			(stroke
				(width 0.1)
				(type default)
			)
			(layer "F.Fab")
		)
		(fp_line
			(start -1.500124 1.500124)
			(end -1.500124 -1.500124)
			(stroke
				(width 0.1)
				(type default)
			)
			(layer "F.Fab")
		)
		(fp_line
			(start 1.500124 -1.500124)
			(end 1.500124 1.500124)
			(stroke
				(width 0.1)
				(type default)
			)
			(layer "F.Fab")
		)
		(fp_line
			(start 1.500124 1.500124)
			(end -1.500124 1.500124)
			(stroke
				(width 0.1)
				(type default)
			)
			(layer "F.Fab")
		)
		(fp_poly
			(pts
				(xy -2.847848 -1.258062) (xy -2.847848 -0.242062) (xy -1.831848 -0.750062)
			)
			(stroke
				(width 0)
				(type default)
			)
			(fill yes)
			(layer "F.Fab")
		)
		(pad "1" smd rect
			(at -1.400048 -0.750062 270)
			(size 0.2286 0.6096)
			(layers "F.Cu" "F.Mask" "F.Paste")
			(net "HSC_TYPE_ADC_A1")
		)
		(pad "2" smd rect
			(at -1.400048 -0.249936 270)
			(size 0.2286 0.6096)
			(layers "F.Cu" "F.Mask" "F.Paste")
			(net "HSC_TYPE_ADC_A0")
		)
		(pad "3" smd rect
			(at -1.400048 0.249936 270)
			(size 0.2286 0.6096)
			(layers "F.Cu" "F.Mask" "F.Paste")
			(net "TP_HSC_TYPE_ADC_ALERT")
		)
		(pad "4" smd rect
			(at -1.400048 0.750062 270)
			(size 0.2286 0.6096)
			(layers "F.Cu" "F.Mask" "F.Paste")
			(net "SMB_HSC_TYPE_ADC_SDA")
		)
		(pad "5" smd rect
			(at -0.750062 1.400048)
			(size 0.2286 0.6096)
			(layers "F.Cu" "F.Mask" "F.Paste")
			(net "SMB_HSC_TYPE_ADC_SCL")
		)
		(pad "6" smd rect
			(at -0.249936 1.400048)
			(size 0.2286 0.6096)
			(layers "F.Cu" "F.Mask" "F.Paste")
			(net "NC_HSC_TYPE_NC0")
		)
		(pad "7" smd rect
			(at 0.249936 1.400048)
			(size 0.2286 0.6096)
			(layers "F.Cu" "F.Mask" "F.Paste")
			(net "NC_HSC_TYPE_NC1")
		)
		(pad "8" smd rect
			(at 0.750062 1.400048)
			(size 0.2286 0.6096)
			(layers "F.Cu" "F.Mask" "F.Paste")
			(net "NC_HSC_TYPE_NC2")
		)
		(pad "9" smd rect
			(at 1.400048 0.750062 270)
			(size 0.2286 0.6096)
			(layers "F.Cu" "F.Mask" "F.Paste")
			(net "P3V3_AUX")
		)
		(pad "10" smd rect
			(at 1.400048 0.249936 270)
			(size 0.2286 0.6096)
			(layers "F.Cu" "F.Mask" "F.Paste")
			(net "GND")
		)
		(pad "11" smd rect
			(at 1.400048 -0.249936 270)
			(size 0.2286 0.6096)
			(layers "F.Cu" "F.Mask" "F.Paste")
			(net "HSC_TYPE_ADC")
		)
		(pad "12" smd rect
			(at 1.400048 -0.750062 270)
			(size 0.2286 0.6096)
			(layers "F.Cu" "F.Mask" "F.Paste")
			(net "NC_HSC_TYPE_VINM")
		)
		(pad "13" smd rect
			(at 0.750062 -1.400048)
			(size 0.2286 0.6096)
			(layers "F.Cu" "F.Mask" "F.Paste")
			(net "NC_HSC_TYPE_VINP")
		)
		(pad "14" smd rect
			(at 0.249936 -1.400048)
			(size 0.2286 0.6096)
			(layers "F.Cu" "F.Mask" "F.Paste")
			(net "NC_HSC_TYPE_NC3")
		)
		(pad "15" smd rect
			(at -0.249936 -1.400048)
			(size 0.2286 0.6096)
			(layers "F.Cu" "F.Mask" "F.Paste")
			(net "NC_HSC_TYPE_NC4")
		)
		(pad "16" smd rect
			(at -0.750062 -1.400048)
			(size 0.2286 0.6096)
			(layers "F.Cu" "F.Mask" "F.Paste")
			(net "NC_HSC_TYPE_NC5")
		)
		(pad "TH" smd rect
			(at 0 0)
			(size 1.7018 1.7018)
			(layers "F.Cu" "F.Mask" "F.Paste")
			(net "GND")
		)
	)
	(footprint ""
		(layer "F.Cu")
		(at 85.262466 -336.935572 -90)
		(property "Reference" "PC503_P1_6"
			(at 0 0 270)
			(layer "F.SilkS")
			(hide yes)
			(effects
				(font
					(size 1.27 1.27)
				)
			)
		)
		(property "Value" ""
			(at 0 0 270)
			(layer "F.Fab")
			(effects
				(font
					(size 1.27 1.27)
				)
			)
		)
		(duplicate_pad_numbers_are_jumpers no)
		(fp_line
			(start -0.7874 0.4064)
			(end -0.7874 -0.4064)
			(stroke
				(width 0.1524)
				(type default)
			)
			(layer "F.SilkS")
		)
		(fp_line
			(start 0.7874 0.4064)
			(end -0.7874 0.4064)
			(stroke
				(width 0.1524)
				(type default)
			)
			(layer "F.SilkS")
		)
		(fp_line
			(start -0.7874 -0.4064)
			(end 0.7874 -0.4064)
			(stroke
				(width 0.1524)
				(type default)
			)
			(layer "F.SilkS")
		)
		(fp_line
			(start 0.7874 -0.4064)
			(end 0.7874 0.4064)
			(stroke
				(width 0.1524)
				(type default)
			)
			(layer "F.SilkS")
		)
		(fp_line
			(start -0.67945 0.3048)
			(end -0.67945 -0.305054)
			(stroke
				(width 0.1)
				(type default)
			)
			(layer "F.Fab")
		)
		(fp_line
			(start -0.12065 0.3048)
			(end -0.67945 0.3048)
			(stroke
				(width 0.1)
				(type default)
			)
			(layer "F.Fab")
		)
		(fp_line
			(start 0.120396 0.3048)
			(end 0.120396 0.2794)
			(stroke
				(width 0.1)
				(type default)
			)
			(layer "F.Fab")
		)
		(fp_line
			(start 0.67945 0.3048)
			(end 0.120396 0.3048)
			(stroke
				(width 0.1)
				(type default)
			)
			(layer "F.Fab")
		)
		(fp_line
			(start -0.12065 0.2794)
			(end -0.12065 0.3048)
			(stroke
				(width 0.1)
				(type default)
			)
			(layer "F.Fab")
		)
		(fp_line
			(start 0.120396 0.2794)
			(end -0.12065 0.2794)
			(stroke
				(width 0.1)
				(type default)
			)
			(layer "F.Fab")
		)
		(fp_line
			(start -0.12065 -0.2794)
			(end 0.12065 -0.2794)
			(stroke
				(width 0.1)
				(type default)
			)
			(layer "F.Fab")
		)
		(fp_line
			(start 0.12065 -0.2794)
			(end 0.12065 -0.3048)
			(stroke
				(width 0.1)
				(type default)
			)
			(layer "F.Fab")
		)
		(fp_line
			(start 0.12065 -0.3048)
			(end 0.67945 -0.3048)
			(stroke
				(width 0.1)
				(type default)
			)
			(layer "F.Fab")
		)
		(fp_line
			(start 0.67945 -0.3048)
			(end 0.67945 0.3048)
			(stroke
				(width 0.1)
				(type default)
			)
			(layer "F.Fab")
		)
		(fp_line
			(start -0.67945 -0.305054)
			(end -0.12065 -0.305054)
			(stroke
				(width 0.1)
				(type default)
			)
			(layer "F.Fab")
		)
		(fp_line
			(start -0.12065 -0.305054)
			(end -0.12065 -0.2794)
			(stroke
				(width 0.1)
				(type default)
			)
			(layer "F.Fab")
		)
		(pad "1" smd circle
			(at -0.40005 0 270)
			(size 0 0)
			(layers "F.Cu" "F.Mask" "F.Paste")
			(net "PVCCIN_CPU1_PVCC")
		)
		(pad "2" smd circle
			(at 0.40005 0 270)
			(size 0 0)
			(layers "F.Cu" "F.Mask" "F.Paste")
			(net "GND")
		)
	)
	(footprint ""
		(layer "F.Cu")
		(at 293.399718 -362.843826 -90)
		(property "Reference" "PC1174_P0_4"
			(at 0 0 270)
			(layer "F.SilkS")
			(hide yes)
			(effects
				(font
					(size 1.27 1.27)
				)
			)
		)
		(property "Value" ""
			(at 0 0 270)
			(layer "F.Fab")
			(effects
				(font
					(size 1.27 1.27)
				)
			)
		)
		(duplicate_pad_numbers_are_jumpers no)
		(fp_line
			(start -0.7874 0.4064)
			(end -0.7874 -0.4064)
			(stroke
				(width 0.1524)
				(type default)
			)
			(layer "F.SilkS")
		)
		(fp_line
			(start 0.7874 0.4064)
			(end -0.7874 0.4064)
			(stroke
				(width 0.1524)
				(type default)
			)
			(layer "F.SilkS")
		)
		(fp_line
			(start -0.7874 -0.4064)
			(end 0.7874 -0.4064)
			(stroke
				(width 0.1524)
				(type default)
			)
			(layer "F.SilkS")
		)
		(fp_line
			(start 0.7874 -0.4064)
			(end 0.7874 0.4064)
			(stroke
				(width 0.1524)
				(type default)
			)
			(layer "F.SilkS")
		)
		(fp_line
			(start -0.67945 0.3048)
			(end -0.67945 -0.305054)
			(stroke
				(width 0.1)
				(type default)
			)
			(layer "F.Fab")
		)
		(fp_line
			(start -0.12065 0.3048)
			(end -0.67945 0.3048)
			(stroke
				(width 0.1)
				(type default)
			)
			(layer "F.Fab")
		)
		(fp_line
			(start 0.120396 0.3048)
			(end 0.120396 0.2794)
			(stroke
				(width 0.1)
				(type default)
			)
			(layer "F.Fab")
		)
		(fp_line
			(start 0.67945 0.3048)
			(end 0.120396 0.3048)
			(stroke
				(width 0.1)
				(type default)
			)
			(layer "F.Fab")
		)
		(fp_line
			(start -0.12065 0.2794)
			(end -0.12065 0.3048)
			(stroke
				(width 0.1)
				(type default)
			)
			(layer "F.Fab")
		)
		(fp_line
			(start 0.120396 0.2794)
			(end -0.12065 0.2794)
			(stroke
				(width 0.1)
				(type default)
			)
			(layer "F.Fab")
		)
		(fp_line
			(start -0.12065 -0.2794)
			(end 0.12065 -0.2794)
			(stroke
				(width 0.1)
				(type default)
			)
			(layer "F.Fab")
		)
		(fp_line
			(start 0.12065 -0.2794)
			(end 0.12065 -0.3048)
			(stroke
				(width 0.1)
				(type default)
			)
			(layer "F.Fab")
		)
		(fp_line
			(start 0.12065 -0.3048)
			(end 0.67945 -0.3048)
			(stroke
				(width 0.1)
				(type default)
			)
			(layer "F.Fab")
		)
		(fp_line
			(start 0.67945 -0.3048)
			(end 0.67945 0.3048)
			(stroke
				(width 0.1)
				(type default)
			)
			(layer "F.Fab")
		)
		(fp_line
			(start -0.67945 -0.305054)
			(end -0.12065 -0.305054)
			(stroke
				(width 0.1)
				(type default)
			)
			(layer "F.Fab")
		)
		(fp_line
			(start -0.12065 -0.305054)
			(end -0.12065 -0.2794)
			(stroke
				(width 0.1)
				(type default)
			)
			(layer "F.Fab")
		)
		(pad "1" smd circle
			(at -0.40005 0 270)
			(size 0 0)
			(layers "F.Cu" "F.Mask" "F.Paste")
			(net "SW_P12V_PVCCFA_EHV_FIVRA_CPU0_L")
		)
		(pad "2" smd circle
			(at 0.40005 0 270)
			(size 0 0)
			(layers "F.Cu" "F.Mask" "F.Paste")
			(net "GND")
		)
	)
	(footprint ""
		(layer "F.Cu")
		(at 260.731508 0.383794)
		(property "Reference" "J77"
			(at -4.164838 0.886206 90)
			(unlocked yes)
			(layer "F.SilkS")
			(effects
				(font
					(size 0.7874 0.5842)
					(thickness 0.1524)
				)
				(justify left)
			)
		)
		(property "Value" ""
			(at 0 0 0)
			(layer "F.Fab")
			(effects
				(font
					(size 1.27 1.27)
				)
			)
		)
		(duplicate_pad_numbers_are_jumpers no)
		(fp_line
			(start -1.2192 -2.1082)
			(end 1.2192 -2.1082)
			(stroke
				(width 0.1524)
				(type default)
			)
			(layer "F.SilkS")
		)
		(fp_line
			(start -1.2192 2.1082)
			(end -1.2192 -2.1082)
			(stroke
				(width 0.1524)
				(type default)
			)
			(layer "F.SilkS")
		)
		(fp_line
			(start 1.2192 -2.1082)
			(end 1.2192 2.1082)
			(stroke
				(width 0.1524)
				(type default)
			)
			(layer "F.SilkS")
		)
		(fp_line
			(start 1.2192 2.1082)
			(end -1.2192 2.1082)
			(stroke
				(width 0.1524)
				(type default)
			)
			(layer "F.SilkS")
		)
		(pad "" np_thru_hole circle
			(at -2.8829 -1.27 270)
			(size 1.0414 1.0414)
			(drill 1.0414)
			(layers "*.Cu" "*.Mask")
			(clearance 0.381)
			(thermal_gap 0.381)
		)
		(pad "" np_thru_hole circle
			(at -2.8829 1.27 270)
			(size 1.0414 1.0414)
			(drill 1.0414)
			(layers "*.Cu" "*.Mask")
			(clearance 0.381)
			(thermal_gap 0.381)
		)
		(pad "" np_thru_hole circle
			(at 3.4671 -1.27 270)
			(size 1.0414 1.0414)
			(drill 1.0414)
			(layers "*.Cu" "*.Mask")
			(clearance 0.381)
			(thermal_gap 0.381)
		)
		(pad "" np_thru_hole circle
			(at 3.4671 1.27 270)
			(size 1.0414 1.0414)
			(drill 1.0414)
			(layers "*.Cu" "*.Mask")
			(clearance 0.381)
			(thermal_gap 0.381)
		)
		(pad "1" smd rect
			(at 0.8255 -0.249936 270)
			(size 0.3048 0.508)
			(layers "F.Cu" "F.Mask" "F.Paste")
			(net "DELTA_L_85_10INCH_IN1_DP")
		)
		(pad "2" smd rect
			(at 0.8255 0.249936 270)
			(size 0.3048 0.508)
			(layers "F.Cu" "F.Mask" "F.Paste")
			(net "DELTA_L_85_10INCH_IN1_DN")
		)
		(pad "3" smd circle
			(at 0 0)
			(size 0 0)
			(layers "F.Cu" "F.Mask" "F.Paste")
			(net "DELTA_L_GND_1")
		)
		(zone
			(layer "F.Cu")
			(hatch none 0.5)
			(connect_pads
				(clearance 0)
			)
			(min_thickness 0.25)
			(keepout
				(tracks not_allowed)
				(vias allowed)
				(pads allowed)
				(copperpour not_allowed)
				(footprints allowed)
			)
			(placement
				(enabled no)
				(sheetname "")
			)
			(fill
				(thermal_gap 0.5)
				(thermal_bridge_width 0.5)
				(island_removal_mode 0)
			)
			(polygon
				(pts
					(xy 261.849108 -0.164846) (xy 261.849108 -0.069342) (xy 261.252208 -0.069342) (xy 261.252208 0.337058)
					(xy 261.849108 0.337058) (xy 261.849108 0.43053) (xy 261.252208 0.43053) (xy 261.252208 0.83693)
					(xy 261.849108 0.83693) (xy 261.849108 0.932434) (xy 261.150608 0.932434) (xy 261.150608 -0.164846)
				)
			)
		)
		(zone
			(layers "F.Cu" "B.Cu" "In1.Cu" "In2.Cu" "In3.Cu" "In4.Cu" "In5.Cu" "In6.Cu"
				"In7.Cu" "In8.Cu" "In9.Cu" "In10.Cu" "In11.Cu" "In12.Cu" "In13.Cu" "In14.Cu"
				"In15.Cu" "In16.Cu"
			)
			(hatch none 0.5)
			(connect_pads
				(clearance 0)
			)
			(min_thickness 0.25)
			(keepout
				(tracks not_allowed)
				(vias allowed)
				(pads allowed)
				(copperpour not_allowed)
				(footprints allowed)
			)
			(placement
				(enabled no)
				(sheetname "")
			)
			(fill
				(thermal_gap 0.5)
				(thermal_bridge_width 0.5)
				(island_removal_mode 0)
			)
			(polygon
				(pts
					(arc
						(start 258.775708 -0.886206)
						(mid 256.921508 -0.886206)
						(end 258.775708 -0.886206)
					)
				)
			)
		)
		(zone
			(layers "F.Cu" "B.Cu" "In1.Cu" "In2.Cu" "In3.Cu" "In4.Cu" "In5.Cu" "In6.Cu"
				"In7.Cu" "In8.Cu" "In9.Cu" "In10.Cu" "In11.Cu" "In12.Cu" "In13.Cu" "In14.Cu"
				"In15.Cu" "In16.Cu"
			)
			(hatch none 0.5)
			(connect_pads
				(clearance 0)
			)
			(min_thickness 0.25)
			(keepout
				(tracks not_allowed)
				(vias allowed)
				(pads allowed)
				(copperpour not_allowed)
				(footprints allowed)
			)
			(placement
				(enabled no)
				(sheetname "")
			)
			(fill
				(thermal_gap 0.5)
				(thermal_bridge_width 0.5)
				(island_removal_mode 0)
			)
			(polygon
				(pts
					(arc
						(start 258.775708 1.653794)
						(mid 256.921508 1.653794)
						(end 258.775708 1.653794)
					)
				)
			)
		)
		(zone
			(layers "F.Cu" "B.Cu" "In1.Cu" "In2.Cu" "In3.Cu" "In4.Cu" "In5.Cu" "In6.Cu"
				"In7.Cu" "In8.Cu" "In9.Cu" "In10.Cu" "In11.Cu" "In12.Cu" "In13.Cu" "In14.Cu"
				"In15.Cu" "In16.Cu"
			)
			(hatch none 0.5)
			(connect_pads
				(clearance 0)
			)
			(min_thickness 0.25)
			(keepout
				(tracks not_allowed)
				(vias allowed)
				(pads allowed)
				(copperpour not_allowed)
				(footprints allowed)
			)
			(placement
				(enabled no)
				(sheetname "")
			)
			(fill
				(thermal_gap 0.5)
				(thermal_bridge_width 0.5)
				(island_removal_mode 0)
			)
			(polygon
				(pts
					(arc
						(start 265.125708 -0.886206)
						(mid 263.271508 -0.886206)
						(end 265.125708 -0.886206)
					)
				)
			)
		)
		(zone
			(layers "F.Cu" "B.Cu" "In1.Cu" "In2.Cu" "In3.Cu" "In4.Cu" "In5.Cu" "In6.Cu"
				"In7.Cu" "In8.Cu" "In9.Cu" "In10.Cu" "In11.Cu" "In12.Cu" "In13.Cu" "In14.Cu"
				"In15.Cu" "In16.Cu"
			)
			(hatch none 0.5)
			(connect_pads
				(clearance 0)
			)
			(min_thickness 0.25)
			(keepout
				(tracks not_allowed)
				(vias allowed)
				(pads allowed)
				(copperpour not_allowed)
				(footprints allowed)
			)
			(placement
				(enabled no)
				(sheetname "")
			)
			(fill
				(thermal_gap 0.5)
				(thermal_bridge_width 0.5)
				(island_removal_mode 0)
			)
			(polygon
				(pts
					(arc
						(start 265.125708 1.653794)
						(mid 263.271508 1.653794)
						(end 265.125708 1.653794)
					)
				)
			)
		)
	)
	(footprint ""
		(layer "F.Cu")
		(at 118.781576 -338.3026 -90)
		(property "Reference" "PC1358"
			(at 0 0 270)
			(layer "F.SilkS")
			(hide yes)
			(effects
				(font
					(size 1.27 1.27)
				)
			)
		)
		(property "Value" ""
			(at 0 0 270)
			(layer "F.Fab")
			(effects
				(font
					(size 1.27 1.27)
				)
			)
		)
		(duplicate_pad_numbers_are_jumpers no)
		(fp_line
			(start -0.7874 0.4064)
			(end -0.7874 -0.4064)
			(stroke
				(width 0.1524)
				(type default)
			)
			(layer "F.SilkS")
		)
		(fp_line
			(start 0.7874 0.4064)
			(end -0.7874 0.4064)
			(stroke
				(width 0.1524)
				(type default)
			)
			(layer "F.SilkS")
		)
		(fp_line
			(start -0.7874 -0.4064)
			(end 0.7874 -0.4064)
			(stroke
				(width 0.1524)
				(type default)
			)
			(layer "F.SilkS")
		)
		(fp_line
			(start 0.7874 -0.4064)
			(end 0.7874 0.4064)
			(stroke
				(width 0.1524)
				(type default)
			)
			(layer "F.SilkS")
		)
		(fp_line
			(start -0.67945 0.3048)
			(end -0.67945 -0.305054)
			(stroke
				(width 0.1)
				(type default)
			)
			(layer "F.Fab")
		)
		(fp_line
			(start -0.12065 0.3048)
			(end -0.67945 0.3048)
			(stroke
				(width 0.1)
				(type default)
			)
			(layer "F.Fab")
		)
		(fp_line
			(start 0.120396 0.3048)
			(end 0.120396 0.2794)
			(stroke
				(width 0.1)
				(type default)
			)
			(layer "F.Fab")
		)
		(fp_line
			(start 0.67945 0.3048)
			(end 0.120396 0.3048)
			(stroke
				(width 0.1)
				(type default)
			)
			(layer "F.Fab")
		)
		(fp_line
			(start -0.12065 0.2794)
			(end -0.12065 0.3048)
			(stroke
				(width 0.1)
				(type default)
			)
			(layer "F.Fab")
		)
		(fp_line
			(start 0.120396 0.2794)
			(end -0.12065 0.2794)
			(stroke
				(width 0.1)
				(type default)
			)
			(layer "F.Fab")
		)
		(fp_line
			(start -0.12065 -0.2794)
			(end 0.12065 -0.2794)
			(stroke
				(width 0.1)
				(type default)
			)
			(layer "F.Fab")
		)
		(fp_line
			(start 0.12065 -0.2794)
			(end 0.12065 -0.3048)
			(stroke
				(width 0.1)
				(type default)
			)
			(layer "F.Fab")
		)
		(fp_line
			(start 0.12065 -0.3048)
			(end 0.67945 -0.3048)
			(stroke
				(width 0.1)
				(type default)
			)
			(layer "F.Fab")
		)
		(fp_line
			(start 0.67945 -0.3048)
			(end 0.67945 0.3048)
			(stroke
				(width 0.1)
				(type default)
			)
			(layer "F.Fab")
		)
		(fp_line
			(start -0.67945 -0.305054)
			(end -0.12065 -0.305054)
			(stroke
				(width 0.1)
				(type default)
			)
			(layer "F.Fab")
		)
		(fp_line
			(start -0.12065 -0.305054)
			(end -0.12065 -0.2794)
			(stroke
				(width 0.1)
				(type default)
			)
			(layer "F.Fab")
		)
		(pad "1" smd circle
			(at -0.40005 0 270)
			(size 0 0)
			(layers "F.Cu" "F.Mask" "F.Paste")
			(net "GND")
		)
		(pad "2" smd circle
			(at 0.40005 0 270)
			(size 0 0)
			(layers "F.Cu" "F.Mask" "F.Paste")
			(net "PVCCIN_CPU1_VREF")
		)
	)
	(footprint ""
		(layer "F.Cu")
		(at 197.19036 -124.170948)
		(property "Reference" "R1710"
			(at 0 0 0)
			(layer "F.SilkS")
			(hide yes)
			(effects
				(font
					(size 1.27 1.27)
				)
			)
		)
		(property "Value" ""
			(at 0 0 0)
			(layer "F.Fab")
			(effects
				(font
					(size 1.27 1.27)
				)
			)
		)
		(duplicate_pad_numbers_are_jumpers no)
		(fp_line
			(start -0.7874 -0.4064)
			(end 0.7874 -0.4064)
			(stroke
				(width 0.1524)
				(type default)
			)
			(layer "F.SilkS")
		)
		(fp_line
			(start -0.7874 0.4064)
			(end -0.7874 -0.4064)
			(stroke
				(width 0.1524)
				(type default)
			)
			(layer "F.SilkS")
		)
		(fp_line
			(start 0.7874 -0.4064)
			(end 0.7874 0.4064)
			(stroke
				(width 0.1524)
				(type default)
			)
			(layer "F.SilkS")
		)
		(fp_line
			(start 0.7874 0.4064)
			(end -0.7874 0.4064)
			(stroke
				(width 0.1524)
				(type default)
			)
			(layer "F.SilkS")
		)
		(fp_line
			(start -0.67945 -0.305054)
			(end -0.12065 -0.305054)
			(stroke
				(width 0.1)
				(type default)
			)
			(layer "F.Fab")
		)
		(fp_line
			(start -0.67945 0.3048)
			(end -0.67945 -0.305054)
			(stroke
				(width 0.1)
				(type default)
			)
			(layer "F.Fab")
		)
		(fp_line
			(start -0.12065 -0.305054)
			(end -0.12065 -0.2794)
			(stroke
				(width 0.1)
				(type default)
			)
			(layer "F.Fab")
		)
		(fp_line
			(start -0.12065 -0.2794)
			(end 0.12065 -0.2794)
			(stroke
				(width 0.1)
				(type default)
			)
			(layer "F.Fab")
		)
		(fp_line
			(start -0.12065 0.2794)
			(end -0.12065 0.3048)
			(stroke
				(width 0.1)
				(type default)
			)
			(layer "F.Fab")
		)
		(fp_line
			(start -0.12065 0.3048)
			(end -0.67945 0.3048)
			(stroke
				(width 0.1)
				(type default)
			)
			(layer "F.Fab")
		)
		(fp_line
			(start 0.120396 0.2794)
			(end -0.12065 0.2794)
			(stroke
				(width 0.1)
				(type default)
			)
			(layer "F.Fab")
		)
		(fp_line
			(start 0.120396 0.3048)
			(end 0.120396 0.2794)
			(stroke
				(width 0.1)
				(type default)
			)
			(layer "F.Fab")
		)
		(fp_line
			(start 0.12065 -0.3048)
			(end 0.67945 -0.3048)
			(stroke
				(width 0.1)
				(type default)
			)
			(layer "F.Fab")
		)
		(fp_line
			(start 0.12065 -0.2794)
			(end 0.12065 -0.3048)
			(stroke
				(width 0.1)
				(type default)
			)
			(layer "F.Fab")
		)
		(fp_line
			(start 0.67945 -0.3048)
			(end 0.67945 0.3048)
			(stroke
				(width 0.1)
				(type default)
			)
			(layer "F.Fab")
		)
		(fp_line
			(start 0.67945 0.3048)
			(end 0.120396 0.3048)
			(stroke
				(width 0.1)
				(type default)
			)
			(layer "F.Fab")
		)
		(pad "1" smd circle
			(at -0.40005 0)
			(size 0 0)
			(layers "F.Cu" "F.Mask" "F.Paste")
			(net "FM_PLD_REV_N")
		)
		(pad "2" smd circle
			(at 0.40005 0)
			(size 0 0)
			(layers "F.Cu" "F.Mask" "F.Paste")
			(net "FM_PLD_REV_R_N")
		)
	)
	(footprint ""
		(layer "F.Cu")
		(at 261.600188 -92.498926 90)
		(property "Reference" "R3638"
			(at 0 0 90)
			(layer "F.SilkS")
			(hide yes)
			(effects
				(font
					(size 1.27 1.27)
				)
			)
		)
		(property "Value" ""
			(at 0 0 90)
			(layer "F.Fab")
			(effects
				(font
					(size 1.27 1.27)
				)
			)
		)
		(duplicate_pad_numbers_are_jumpers no)
		(fp_line
			(start 0.7874 -0.4064)
			(end 0.7874 0.4064)
			(stroke
				(width 0.1524)
				(type default)
			)
			(layer "F.SilkS")
		)
		(fp_line
			(start -0.7874 -0.4064)
			(end 0.7874 -0.4064)
			(stroke
				(width 0.1524)
				(type default)
			)
			(layer "F.SilkS")
		)
		(fp_line
			(start 0.7874 0.4064)
			(end -0.7874 0.4064)
			(stroke
				(width 0.1524)
				(type default)
			)
			(layer "F.SilkS")
		)
		(fp_line
			(start -0.7874 0.4064)
			(end -0.7874 -0.4064)
			(stroke
				(width 0.1524)
				(type default)
			)
			(layer "F.SilkS")
		)
		(fp_line
			(start -0.12065 -0.305054)
			(end -0.12065 -0.2794)
			(stroke
				(width 0.1)
				(type default)
			)
			(layer "F.Fab")
		)
		(fp_line
			(start -0.67945 -0.305054)
			(end -0.12065 -0.305054)
			(stroke
				(width 0.1)
				(type default)
			)
			(layer "F.Fab")
		)
		(fp_line
			(start 0.67945 -0.3048)
			(end 0.67945 0.3048)
			(stroke
				(width 0.1)
				(type default)
			)
			(layer "F.Fab")
		)
		(fp_line
			(start 0.12065 -0.3048)
			(end 0.67945 -0.3048)
			(stroke
				(width 0.1)
				(type default)
			)
			(layer "F.Fab")
		)
		(fp_line
			(start 0.12065 -0.2794)
			(end 0.12065 -0.3048)
			(stroke
				(width 0.1)
				(type default)
			)
			(layer "F.Fab")
		)
		(fp_line
			(start -0.12065 -0.2794)
			(end 0.12065 -0.2794)
			(stroke
				(width 0.1)
				(type default)
			)
			(layer "F.Fab")
		)
		(fp_line
			(start 0.120396 0.2794)
			(end -0.12065 0.2794)
			(stroke
				(width 0.1)
				(type default)
			)
			(layer "F.Fab")
		)
		(fp_line
			(start -0.12065 0.2794)
			(end -0.12065 0.3048)
			(stroke
				(width 0.1)
				(type default)
			)
			(layer "F.Fab")
		)
		(fp_line
			(start 0.67945 0.3048)
			(end 0.120396 0.3048)
			(stroke
				(width 0.1)
				(type default)
			)
			(layer "F.Fab")
		)
		(fp_line
			(start 0.120396 0.3048)
			(end 0.120396 0.2794)
			(stroke
				(width 0.1)
				(type default)
			)
			(layer "F.Fab")
		)
		(fp_line
			(start -0.12065 0.3048)
			(end -0.67945 0.3048)
			(stroke
				(width 0.1)
				(type default)
			)
			(layer "F.Fab")
		)
		(fp_line
			(start -0.67945 0.3048)
			(end -0.67945 -0.305054)
			(stroke
				(width 0.1)
				(type default)
			)
			(layer "F.Fab")
		)
		(pad "1" smd circle
			(at -0.40005 0 90)
			(size 0 0)
			(layers "F.Cu" "F.Mask" "F.Paste")
			(net "P3V3_AUX")
		)
		(pad "2" smd circle
			(at 0.40005 0 90)
			(size 0 0)
			(layers "F.Cu" "F.Mask" "F.Paste")
			(net "CK440Q_OE_1")
		)
	)
	(footprint ""
		(layer "F.Cu")
		(at 435.185566 -40.104568 180)
		(property "Reference" "R1324"
			(at 0 0 180)
			(layer "F.SilkS")
			(hide yes)
			(effects
				(font
					(size 1.27 1.27)
				)
			)
		)
		(property "Value" ""
			(at 0 0 180)
			(layer "F.Fab")
			(effects
				(font
					(size 1.27 1.27)
				)
			)
		)
		(duplicate_pad_numbers_are_jumpers no)
		(fp_line
			(start 0.7874 0.4064)
			(end -0.7874 0.4064)
			(stroke
				(width 0.1524)
				(type default)
			)
			(layer "F.SilkS")
		)
		(fp_line
			(start 0.7874 -0.4064)
			(end 0.7874 0.4064)
			(stroke
				(width 0.1524)
				(type default)
			)
			(layer "F.SilkS")
		)
		(fp_line
			(start -0.7874 0.4064)
			(end -0.7874 -0.4064)
			(stroke
				(width 0.1524)
				(type default)
			)
			(layer "F.SilkS")
		)
		(fp_line
			(start -0.7874 -0.4064)
			(end 0.7874 -0.4064)
			(stroke
				(width 0.1524)
				(type default)
			)
			(layer "F.SilkS")
		)
		(fp_line
			(start 0.67945 0.3048)
			(end 0.120396 0.3048)
			(stroke
				(width 0.1)
				(type default)
			)
			(layer "F.Fab")
		)
		(fp_line
			(start 0.67945 -0.3048)
			(end 0.67945 0.3048)
			(stroke
				(width 0.1)
				(type default)
			)
			(layer "F.Fab")
		)
		(fp_line
			(start 0.12065 -0.2794)
			(end 0.12065 -0.3048)
			(stroke
				(width 0.1)
				(type default)
			)
			(layer "F.Fab")
		)
		(fp_line
			(start 0.12065 -0.3048)
			(end 0.67945 -0.3048)
			(stroke
				(width 0.1)
				(type default)
			)
			(layer "F.Fab")
		)
		(fp_line
			(start 0.120396 0.3048)
			(end 0.120396 0.2794)
			(stroke
				(width 0.1)
				(type default)
			)
			(layer "F.Fab")
		)
		(fp_line
			(start 0.120396 0.2794)
			(end -0.12065 0.2794)
			(stroke
				(width 0.1)
				(type default)
			)
			(layer "F.Fab")
		)
		(fp_line
			(start -0.12065 0.3048)
			(end -0.67945 0.3048)
			(stroke
				(width 0.1)
				(type default)
			)
			(layer "F.Fab")
		)
		(fp_line
			(start -0.12065 0.2794)
			(end -0.12065 0.3048)
			(stroke
				(width 0.1)
				(type default)
			)
			(layer "F.Fab")
		)
		(fp_line
			(start -0.12065 -0.2794)
			(end 0.12065 -0.2794)
			(stroke
				(width 0.1)
				(type default)
			)
			(layer "F.Fab")
		)
		(fp_line
			(start -0.12065 -0.305054)
			(end -0.12065 -0.2794)
			(stroke
				(width 0.1)
				(type default)
			)
			(layer "F.Fab")
		)
		(fp_line
			(start -0.67945 0.3048)
			(end -0.67945 -0.305054)
			(stroke
				(width 0.1)
				(type default)
			)
			(layer "F.Fab")
		)
		(fp_line
			(start -0.67945 -0.305054)
			(end -0.12065 -0.305054)
			(stroke
				(width 0.1)
				(type default)
			)
			(layer "F.Fab")
		)
		(pad "1" smd circle
			(at -0.40005 0 180)
			(size 0 0)
			(layers "F.Cu" "F.Mask" "F.Paste")
			(net "GND")
		)
		(pad "2" smd circle
			(at 0.40005 0 180)
			(size 0 0)
			(layers "F.Cu" "F.Mask" "F.Paste")
			(net "PD_BIOS_IMAGE_SWAP_N")
		)
	)
	(footprint ""
		(layer "F.Cu")
		(at 140.208 -370.423948 90)
		(property "Reference" "R2371"
			(at 0 0 90)
			(layer "F.SilkS")
			(hide yes)
			(effects
				(font
					(size 1.27 1.27)
				)
			)
		)
		(property "Value" ""
			(at 0 0 90)
			(layer "F.Fab")
			(effects
				(font
					(size 1.27 1.27)
				)
			)
		)
		(duplicate_pad_numbers_are_jumpers no)
		(fp_line
			(start 0.7874 -0.4064)
			(end 0.7874 0.4064)
			(stroke
				(width 0.1524)
				(type default)
			)
			(layer "F.SilkS")
		)
		(fp_line
			(start -0.7874 -0.4064)
			(end 0.7874 -0.4064)
			(stroke
				(width 0.1524)
				(type default)
			)
			(layer "F.SilkS")
		)
		(fp_line
			(start 0.7874 0.4064)
			(end -0.7874 0.4064)
			(stroke
				(width 0.1524)
				(type default)
			)
			(layer "F.SilkS")
		)
		(fp_line
			(start -0.7874 0.4064)
			(end -0.7874 -0.4064)
			(stroke
				(width 0.1524)
				(type default)
			)
			(layer "F.SilkS")
		)
		(fp_line
			(start -0.12065 -0.305054)
			(end -0.12065 -0.2794)
			(stroke
				(width 0.1)
				(type default)
			)
			(layer "F.Fab")
		)
		(fp_line
			(start -0.67945 -0.305054)
			(end -0.12065 -0.305054)
			(stroke
				(width 0.1)
				(type default)
			)
			(layer "F.Fab")
		)
		(fp_line
			(start 0.67945 -0.3048)
			(end 0.67945 0.3048)
			(stroke
				(width 0.1)
				(type default)
			)
			(layer "F.Fab")
		)
		(fp_line
			(start 0.12065 -0.3048)
			(end 0.67945 -0.3048)
			(stroke
				(width 0.1)
				(type default)
			)
			(layer "F.Fab")
		)
		(fp_line
			(start 0.12065 -0.2794)
			(end 0.12065 -0.3048)
			(stroke
				(width 0.1)
				(type default)
			)
			(layer "F.Fab")
		)
		(fp_line
			(start -0.12065 -0.2794)
			(end 0.12065 -0.2794)
			(stroke
				(width 0.1)
				(type default)
			)
			(layer "F.Fab")
		)
		(fp_line
			(start 0.120396 0.2794)
			(end -0.12065 0.2794)
			(stroke
				(width 0.1)
				(type default)
			)
			(layer "F.Fab")
		)
		(fp_line
			(start -0.12065 0.2794)
			(end -0.12065 0.3048)
			(stroke
				(width 0.1)
				(type default)
			)
			(layer "F.Fab")
		)
		(fp_line
			(start 0.67945 0.3048)
			(end 0.120396 0.3048)
			(stroke
				(width 0.1)
				(type default)
			)
			(layer "F.Fab")
		)
		(fp_line
			(start 0.120396 0.3048)
			(end 0.120396 0.2794)
			(stroke
				(width 0.1)
				(type default)
			)
			(layer "F.Fab")
		)
		(fp_line
			(start -0.12065 0.3048)
			(end -0.67945 0.3048)
			(stroke
				(width 0.1)
				(type default)
			)
			(layer "F.Fab")
		)
		(fp_line
			(start -0.67945 0.3048)
			(end -0.67945 -0.305054)
			(stroke
				(width 0.1)
				(type default)
			)
			(layer "F.Fab")
		)
		(pad "1" smd circle
			(at -0.40005 0 90)
			(size 0 0)
			(layers "F.Cu" "F.Mask" "F.Paste")
			(net "SMB_VR_3V3AUX_SCL_R3")
		)
		(pad "2" smd circle
			(at 0.40005 0 90)
			(size 0 0)
			(layers "F.Cu" "F.Mask" "F.Paste")
			(net "SMB_CLK_PVCCIN_CPU0")
		)
	)
	(footprint ""
		(layer "F.Cu")
		(at 446.727834 -179.862734)
		(property "Reference" "PC1279"
			(at 0 0 0)
			(layer "F.SilkS")
			(hide yes)
			(effects
				(font
					(size 1.27 1.27)
				)
			)
		)
		(property "Value" ""
			(at 0 0 0)
			(layer "F.Fab")
			(effects
				(font
					(size 1.27 1.27)
				)
			)
		)
		(duplicate_pad_numbers_are_jumpers no)
		(fp_line
			(start -1.524 -0.762)
			(end 1.524 -0.762)
			(stroke
				(width 0.1524)
				(type default)
			)
			(layer "F.SilkS")
		)
		(fp_line
			(start -1.524 0.762)
			(end -1.524 -0.762)
			(stroke
				(width 0.1524)
				(type default)
			)
			(layer "F.SilkS")
		)
		(fp_line
			(start 1.524 -0.762)
			(end 1.524 0.762)
			(stroke
				(width 0.1524)
				(type default)
			)
			(layer "F.SilkS")
		)
		(fp_line
			(start 1.524 0.762)
			(end -1.524 0.762)
			(stroke
				(width 0.1524)
				(type default)
			)
			(layer "F.SilkS")
		)
		(fp_line
			(start -1.1049 -0.724916)
			(end -1.1049 0.724916)
			(stroke
				(width 0.1)
				(type default)
			)
			(layer "F.Fab")
		)
		(fp_line
			(start -1.1049 0.724916)
			(end 1.1049 0.724916)
			(stroke
				(width 0.1)
				(type default)
			)
			(layer "F.Fab")
		)
		(fp_line
			(start 1.1049 -0.724916)
			(end -1.1049 -0.724916)
			(stroke
				(width 0.1)
				(type default)
			)
			(layer "F.Fab")
		)
		(fp_line
			(start 1.1049 0.724916)
			(end 1.1049 -0.724916)
			(stroke
				(width 0.1)
				(type default)
			)
			(layer "F.Fab")
		)
		(pad "1" smd rect
			(at -0.889 0 180)
			(size 1.016 1.27)
			(layers "F.Cu" "F.Mask" "F.Paste")
			(net "PVNN_MAIN_CPU0")
		)
		(pad "2" smd rect
			(at 0.889 0 180)
			(size 1.016 1.27)
			(layers "F.Cu" "F.Mask" "F.Paste")
			(net "GND")
		)
	)
	(footprint ""
		(layer "F.Cu")
		(at 153.21788 -112.867948 180)
		(property "Reference" "R3235"
			(at 0 0 180)
			(layer "F.SilkS")
			(hide yes)
			(effects
				(font
					(size 1.27 1.27)
				)
			)
		)
		(property "Value" ""
			(at 0 0 180)
			(layer "F.Fab")
			(effects
				(font
					(size 1.27 1.27)
				)
			)
		)
		(duplicate_pad_numbers_are_jumpers no)
		(fp_line
			(start 0.7874 0.4064)
			(end -0.7874 0.4064)
			(stroke
				(width 0.1524)
				(type default)
			)
			(layer "F.SilkS")
		)
		(fp_line
			(start 0.7874 -0.4064)
			(end 0.7874 0.4064)
			(stroke
				(width 0.1524)
				(type default)
			)
			(layer "F.SilkS")
		)
		(fp_line
			(start -0.7874 0.4064)
			(end -0.7874 -0.4064)
			(stroke
				(width 0.1524)
				(type default)
			)
			(layer "F.SilkS")
		)
		(fp_line
			(start -0.7874 -0.4064)
			(end 0.7874 -0.4064)
			(stroke
				(width 0.1524)
				(type default)
			)
			(layer "F.SilkS")
		)
		(fp_line
			(start 0.67945 0.3048)
			(end 0.120396 0.3048)
			(stroke
				(width 0.1)
				(type default)
			)
			(layer "F.Fab")
		)
		(fp_line
			(start 0.67945 -0.3048)
			(end 0.67945 0.3048)
			(stroke
				(width 0.1)
				(type default)
			)
			(layer "F.Fab")
		)
		(fp_line
			(start 0.12065 -0.2794)
			(end 0.12065 -0.3048)
			(stroke
				(width 0.1)
				(type default)
			)
			(layer "F.Fab")
		)
		(fp_line
			(start 0.12065 -0.3048)
			(end 0.67945 -0.3048)
			(stroke
				(width 0.1)
				(type default)
			)
			(layer "F.Fab")
		)
		(fp_line
			(start 0.120396 0.3048)
			(end 0.120396 0.2794)
			(stroke
				(width 0.1)
				(type default)
			)
			(layer "F.Fab")
		)
		(fp_line
			(start 0.120396 0.2794)
			(end -0.12065 0.2794)
			(stroke
				(width 0.1)
				(type default)
			)
			(layer "F.Fab")
		)
		(fp_line
			(start -0.12065 0.3048)
			(end -0.67945 0.3048)
			(stroke
				(width 0.1)
				(type default)
			)
			(layer "F.Fab")
		)
		(fp_line
			(start -0.12065 0.2794)
			(end -0.12065 0.3048)
			(stroke
				(width 0.1)
				(type default)
			)
			(layer "F.Fab")
		)
		(fp_line
			(start -0.12065 -0.2794)
			(end 0.12065 -0.2794)
			(stroke
				(width 0.1)
				(type default)
			)
			(layer "F.Fab")
		)
		(fp_line
			(start -0.12065 -0.305054)
			(end -0.12065 -0.2794)
			(stroke
				(width 0.1)
				(type default)
			)
			(layer "F.Fab")
		)
		(fp_line
			(start -0.67945 0.3048)
			(end -0.67945 -0.305054)
			(stroke
				(width 0.1)
				(type default)
			)
			(layer "F.Fab")
		)
		(fp_line
			(start -0.67945 -0.305054)
			(end -0.12065 -0.305054)
			(stroke
				(width 0.1)
				(type default)
			)
			(layer "F.Fab")
		)
		(pad "1" smd circle
			(at -0.40005 0 180)
			(size 0 0)
			(layers "F.Cu" "F.Mask" "F.Paste")
			(net "RST_HP_OCP_V3_2_R_N")
		)
		(pad "2" smd circle
			(at 0.40005 0 180)
			(size 0 0)
			(layers "F.Cu" "F.Mask" "F.Paste")
			(net "GND")
		)
	)
	(footprint ""
		(layer "F.Cu")
		(at 416.009582 -170.821858 -90)
		(property "Reference" "PU43_P0_1"
			(at -4.59486 -6.229858 0)
			(unlocked yes)
			(layer "F.SilkS")
			(effects
				(font
					(size 0.7874 0.5842)
					(thickness 0.1524)
				)
				(justify left)
			)
		)
		(property "Value" ""
			(at 0 0 270)
			(layer "F.Fab")
			(effects
				(font
					(size 1.27 1.27)
				)
			)
		)
		(duplicate_pad_numbers_are_jumpers no)
		(fp_line
			(start -2.500122 2.999994)
			(end -2.500122 2.339594)
			(stroke
				(width 0.1524)
				(type default)
			)
			(layer "F.SilkS")
		)
		(fp_line
			(start -2.2987 2.999994)
			(end -2.500122 2.999994)
			(stroke
				(width 0.1524)
				(type default)
			)
			(layer "F.SilkS")
		)
		(fp_line
			(start 2.500122 2.999994)
			(end 2.2987 2.999994)
			(stroke
				(width 0.1524)
				(type default)
			)
			(layer "F.SilkS")
		)
		(fp_line
			(start 2.500122 2.339594)
			(end 2.500122 2.999994)
			(stroke
				(width 0.1524)
				(type default)
			)
			(layer "F.SilkS")
		)
		(fp_line
			(start -2.500122 0.6604)
			(end -2.500122 0.229108)
			(stroke
				(width 0.1524)
				(type default)
			)
			(layer "F.SilkS")
		)
		(fp_line
			(start -2.500122 -2.529078)
			(end -2.500122 -2.999994)
			(stroke
				(width 0.1524)
				(type default)
			)
			(layer "F.SilkS")
		)
		(fp_line
			(start -2.500122 -2.999994)
			(end -2.24409 -2.999994)
			(stroke
				(width 0.1524)
				(type default)
			)
			(layer "F.SilkS")
		)
		(fp_line
			(start 2.31394 -2.999994)
			(end 2.500122 -2.999994)
			(stroke
				(width 0.1524)
				(type default)
			)
			(layer "F.SilkS")
		)
		(fp_line
			(start 2.500122 -2.999994)
			(end 2.500122 -2.44348)
			(stroke
				(width 0.1524)
				(type default)
			)
			(layer "F.SilkS")
		)
		(fp_poly
			(pts
				(xy -4.215892 -2.236978) (xy -5.231892 -1.728978) (xy -5.231892 -2.744978)
			)
			(stroke
				(width 0)
				(type default)
			)
			(fill yes)
			(layer "F.SilkS")
		)
		(fp_line
			(start -2.500122 2.999994)
			(end -2.500122 -2.999994)
			(stroke
				(width 0.1)
				(type default)
			)
			(layer "F.Fab")
		)
		(fp_line
			(start 2.500122 2.999994)
			(end -2.500122 2.999994)
			(stroke
				(width 0.1)
				(type default)
			)
			(layer "F.Fab")
		)
		(fp_line
			(start -2.500122 -2.999994)
			(end 2.500122 -2.999994)
			(stroke
				(width 0.1)
				(type default)
			)
			(layer "F.Fab")
		)
		(fp_line
			(start 2.500122 -2.999994)
			(end 2.500122 2.999994)
			(stroke
				(width 0.1)
				(type default)
			)
			(layer "F.Fab")
		)
		(fp_poly
			(pts
				(xy -4.218432 -2.783078) (xy -4.218432 -1.767078) (xy -3.202432 -2.275078)
			)
			(stroke
				(width 0)
				(type default)
			)
			(fill yes)
			(layer "F.Fab")
		)
		(pad "1" smd rect
			(at -2.400046 -2.275078)
			(size 0.2286 0.6096)
			(layers "F.Cu" "F.Mask" "F.Paste")
			(net "PVCCINFAON_CPU0_VOS1")
		)
		(pad "2" smd rect
			(at -2.400046 -1.82499)
			(size 0.2286 0.6096)
			(layers "F.Cu" "F.Mask" "F.Paste")
			(net "GND")
		)
		(pad "3" smd rect
			(at -2.400046 -1.374902)
			(size 0.2286 0.6096)
			(layers "F.Cu" "F.Mask" "F.Paste")
			(net "PVCCINFAON_CPU0_VDD1")
		)
		(pad "4" smd rect
			(at -2.400046 -0.925068)
			(size 0.2286 0.6096)
			(layers "F.Cu" "F.Mask" "F.Paste")
			(net "PVCCFA_EHV_CPU0_PVCC")
		)
		(pad "5" smd rect
			(at -2.400046 -0.47498)
			(size 0.2286 0.6096)
			(layers "F.Cu" "F.Mask" "F.Paste")
			(net "GND")
		)
		(pad "6" smd rect
			(at -2.400046 -0.024892)
			(size 0.2286 0.6096)
			(layers "F.Cu" "F.Mask" "F.Paste")
			(net "Net_1923")
		)
		(pad "7_9-20_24" smd circle
			(at 0 1.150112)
			(size 0 0)
			(layers "F.Cu" "F.Mask" "F.Paste")
			(net "GND")
		)
		(pad "10_19" smd rect
			(at 0 2.899918)
			(size 0.6096 4.318)
			(layers "F.Cu" "F.Mask" "F.Paste")
			(net "SW_PVCCINFAON_CPU0_SW1")
		)
		(pad "25_29" smd rect
			(at 1.549908 -1.279906 180)
			(size 2.0574 2.3114)
			(layers "F.Cu" "F.Mask" "F.Paste")
			(net "SW_P12V_PVCCINFAON_CPU0_FLT")
		)
		(pad "30" smd rect
			(at 2.05994 -2.899918 270)
			(size 0.2286 0.6096)
			(layers "F.Cu" "F.Mask" "F.Paste")
			(net "SW_P12V_PVCCINFAON_CPU0_FLT")
		)
		(pad "31" smd rect
			(at 1.610106 -2.899918 270)
			(size 0.2286 0.6096)
			(layers "F.Cu" "F.Mask" "F.Paste")
			(net "Net_1922")
		)
		(pad "32" smd rect
			(at 1.160018 -2.899918 270)
			(size 0.2286 0.6096)
			(layers "F.Cu" "F.Mask" "F.Paste")
			(net "SW_PVCCINFAON_CPU0_BOOTR1")
		)
		(pad "33" smd rect
			(at 0.70993 -2.899918 270)
			(size 0.2286 0.6096)
			(layers "F.Cu" "F.Mask" "F.Paste")
			(net "SW_PVCCINFAON_CPU0_BOOT1")
		)
		(pad "34" smd rect
			(at 0.260096 -2.899918 270)
			(size 0.2286 0.6096)
			(layers "F.Cu" "F.Mask" "F.Paste")
			(net "PVCCINFAON_CPU0_APWM1")
		)
		(pad "35" smd rect
			(at -0.189992 -2.899918 270)
			(size 0.2286 0.6096)
			(layers "F.Cu" "F.Mask" "F.Paste")
			(net "PVCCINFAON_CPU0_VDD1")
		)
		(pad "36" smd rect
			(at -0.64008 -2.899918 270)
			(size 0.2286 0.6096)
			(layers "F.Cu" "F.Mask" "F.Paste")
			(net "PVCCINFAON_CPU0_ATSEN")
		)
		(pad "37" smd rect
			(at -1.089914 -2.899918 270)
			(size 0.2286 0.6096)
			(layers "F.Cu" "F.Mask" "F.Paste")
			(net "PVCCINFAON_CPU0_LSET1")
		)
		(pad "38" smd rect
			(at -1.540002 -2.899918 270)
			(size 0.2286 0.6096)
			(layers "F.Cu" "F.Mask" "F.Paste")
			(net "PVCCINFAON_CPU0_ACSP1")
		)
		(pad "39" smd rect
			(at -1.99009 -2.899918 270)
			(size 0.2286 0.6096)
			(layers "F.Cu" "F.Mask" "F.Paste")
			(net "PVCCINFAON_CPU0_VREF")
		)
		(pad "40" smd rect
			(at -0.87503 -1.27508 270)
			(size 1.7526 1.9558)
			(layers "F.Cu" "F.Mask" "F.Paste")
			(net "GND")
		)
		(pad "41" smd rect
			(at -1.525016 0.249936 180)
			(size 0.3048 0.4572)
			(layers "F.Cu" "F.Mask" "F.Paste")
			(net "Net_1924")
		)
	)
	(footprint ""
		(layer "F.Cu")
		(at 139.2682 -104.116378 -90)
		(property "Reference" "R338"
			(at 0 0 270)
			(layer "F.SilkS")
			(hide yes)
			(effects
				(font
					(size 1.27 1.27)
				)
			)
		)
		(property "Value" ""
			(at 0 0 270)
			(layer "F.Fab")
			(effects
				(font
					(size 1.27 1.27)
				)
			)
		)
		(duplicate_pad_numbers_are_jumpers no)
		(fp_line
			(start -0.7874 0.4064)
			(end -0.7874 -0.4064)
			(stroke
				(width 0.1524)
				(type default)
			)
			(layer "F.SilkS")
		)
		(fp_line
			(start 0.7874 0.4064)
			(end -0.7874 0.4064)
			(stroke
				(width 0.1524)
				(type default)
			)
			(layer "F.SilkS")
		)
		(fp_line
			(start -0.7874 -0.4064)
			(end 0.7874 -0.4064)
			(stroke
				(width 0.1524)
				(type default)
			)
			(layer "F.SilkS")
		)
		(fp_line
			(start 0.7874 -0.4064)
			(end 0.7874 0.4064)
			(stroke
				(width 0.1524)
				(type default)
			)
			(layer "F.SilkS")
		)
		(fp_line
			(start -0.67945 0.3048)
			(end -0.67945 -0.305054)
			(stroke
				(width 0.1)
				(type default)
			)
			(layer "F.Fab")
		)
		(fp_line
			(start -0.12065 0.3048)
			(end -0.67945 0.3048)
			(stroke
				(width 0.1)
				(type default)
			)
			(layer "F.Fab")
		)
		(fp_line
			(start 0.120396 0.3048)
			(end 0.120396 0.2794)
			(stroke
				(width 0.1)
				(type default)
			)
			(layer "F.Fab")
		)
		(fp_line
			(start 0.67945 0.3048)
			(end 0.120396 0.3048)
			(stroke
				(width 0.1)
				(type default)
			)
			(layer "F.Fab")
		)
		(fp_line
			(start -0.12065 0.2794)
			(end -0.12065 0.3048)
			(stroke
				(width 0.1)
				(type default)
			)
			(layer "F.Fab")
		)
		(fp_line
			(start 0.120396 0.2794)
			(end -0.12065 0.2794)
			(stroke
				(width 0.1)
				(type default)
			)
			(layer "F.Fab")
		)
		(fp_line
			(start -0.12065 -0.2794)
			(end 0.12065 -0.2794)
			(stroke
				(width 0.1)
				(type default)
			)
			(layer "F.Fab")
		)
		(fp_line
			(start 0.12065 -0.2794)
			(end 0.12065 -0.3048)
			(stroke
				(width 0.1)
				(type default)
			)
			(layer "F.Fab")
		)
		(fp_line
			(start 0.12065 -0.3048)
			(end 0.67945 -0.3048)
			(stroke
				(width 0.1)
				(type default)
			)
			(layer "F.Fab")
		)
		(fp_line
			(start 0.67945 -0.3048)
			(end 0.67945 0.3048)
			(stroke
				(width 0.1)
				(type default)
			)
			(layer "F.Fab")
		)
		(fp_line
			(start -0.67945 -0.305054)
			(end -0.12065 -0.305054)
			(stroke
				(width 0.1)
				(type default)
			)
			(layer "F.Fab")
		)
		(fp_line
			(start -0.12065 -0.305054)
			(end -0.12065 -0.2794)
			(stroke
				(width 0.1)
				(type default)
			)
			(layer "F.Fab")
		)
		(pad "1" smd circle
			(at -0.40005 0 270)
			(size 0 0)
			(layers "F.Cu" "F.Mask" "F.Paste")
			(net "H_CPU_ERR0_LVC1_R_N")
		)
		(pad "2" smd circle
			(at 0.40005 0 270)
			(size 0 0)
			(layers "F.Cu" "F.Mask" "F.Paste")
			(net "H_CPU_ERR0_LVC1_N")
		)
	)
	(footprint ""
		(layer "F.Cu")
		(at 113.349532 -365.158274 90)
		(property "Reference" "PC1194"
			(at 0 0 90)
			(layer "F.SilkS")
			(hide yes)
			(effects
				(font
					(size 1.27 1.27)
				)
			)
		)
		(property "Value" ""
			(at 0 0 90)
			(layer "F.Fab")
			(effects
				(font
					(size 1.27 1.27)
				)
			)
		)
		(duplicate_pad_numbers_are_jumpers no)
		(fp_line
			(start 0.7874 -0.4064)
			(end 0.7874 0.4064)
			(stroke
				(width 0.1524)
				(type default)
			)
			(layer "F.SilkS")
		)
		(fp_line
			(start -0.7874 -0.4064)
			(end 0.7874 -0.4064)
			(stroke
				(width 0.1524)
				(type default)
			)
			(layer "F.SilkS")
		)
		(fp_line
			(start 0.7874 0.4064)
			(end -0.7874 0.4064)
			(stroke
				(width 0.1524)
				(type default)
			)
			(layer "F.SilkS")
		)
		(fp_line
			(start -0.7874 0.4064)
			(end -0.7874 -0.4064)
			(stroke
				(width 0.1524)
				(type default)
			)
			(layer "F.SilkS")
		)
		(fp_line
			(start -0.12065 -0.305054)
			(end -0.12065 -0.2794)
			(stroke
				(width 0.1)
				(type default)
			)
			(layer "F.Fab")
		)
		(fp_line
			(start -0.67945 -0.305054)
			(end -0.12065 -0.305054)
			(stroke
				(width 0.1)
				(type default)
			)
			(layer "F.Fab")
		)
		(fp_line
			(start 0.67945 -0.3048)
			(end 0.67945 0.3048)
			(stroke
				(width 0.1)
				(type default)
			)
			(layer "F.Fab")
		)
		(fp_line
			(start 0.12065 -0.3048)
			(end 0.67945 -0.3048)
			(stroke
				(width 0.1)
				(type default)
			)
			(layer "F.Fab")
		)
		(fp_line
			(start 0.12065 -0.2794)
			(end 0.12065 -0.3048)
			(stroke
				(width 0.1)
				(type default)
			)
			(layer "F.Fab")
		)
		(fp_line
			(start -0.12065 -0.2794)
			(end 0.12065 -0.2794)
			(stroke
				(width 0.1)
				(type default)
			)
			(layer "F.Fab")
		)
		(fp_line
			(start 0.120396 0.2794)
			(end -0.12065 0.2794)
			(stroke
				(width 0.1)
				(type default)
			)
			(layer "F.Fab")
		)
		(fp_line
			(start -0.12065 0.2794)
			(end -0.12065 0.3048)
			(stroke
				(width 0.1)
				(type default)
			)
			(layer "F.Fab")
		)
		(fp_line
			(start 0.67945 0.3048)
			(end 0.120396 0.3048)
			(stroke
				(width 0.1)
				(type default)
			)
			(layer "F.Fab")
		)
		(fp_line
			(start 0.120396 0.3048)
			(end 0.120396 0.2794)
			(stroke
				(width 0.1)
				(type default)
			)
			(layer "F.Fab")
		)
		(fp_line
			(start -0.12065 0.3048)
			(end -0.67945 0.3048)
			(stroke
				(width 0.1)
				(type default)
			)
			(layer "F.Fab")
		)
		(fp_line
			(start -0.67945 0.3048)
			(end -0.67945 -0.305054)
			(stroke
				(width 0.1)
				(type default)
			)
			(layer "F.Fab")
		)
		(pad "1" smd circle
			(at -0.40005 0 90)
			(size 0 0)
			(layers "F.Cu" "F.Mask" "F.Paste")
			(net "PVCCIN_CPU1_VREF")
		)
		(pad "2" smd circle
			(at 0.40005 0 90)
			(size 0 0)
			(layers "F.Cu" "F.Mask" "F.Paste")
			(net "GND")
		)
	)
	(footprint ""
		(layer "F.Cu")
		(at 327.281032 -13.746734)
		(property "Reference" "C535"
			(at 0 0 0)
			(layer "F.SilkS")
			(hide yes)
			(effects
				(font
					(size 1.27 1.27)
				)
			)
		)
		(property "Value" ""
			(at 0 0 0)
			(layer "F.Fab")
			(effects
				(font
					(size 1.27 1.27)
				)
			)
		)
		(duplicate_pad_numbers_are_jumpers no)
		(fp_line
			(start -1.524 -0.762)
			(end 1.524 -0.762)
			(stroke
				(width 0.1524)
				(type default)
			)
			(layer "F.SilkS")
		)
		(fp_line
			(start -1.524 0.762)
			(end -1.524 -0.762)
			(stroke
				(width 0.1524)
				(type default)
			)
			(layer "F.SilkS")
		)
		(fp_line
			(start 1.524 -0.762)
			(end 1.524 0.762)
			(stroke
				(width 0.1524)
				(type default)
			)
			(layer "F.SilkS")
		)
		(fp_line
			(start 1.524 0.762)
			(end -1.524 0.762)
			(stroke
				(width 0.1524)
				(type default)
			)
			(layer "F.SilkS")
		)
		(fp_line
			(start -1.1049 -0.724916)
			(end -1.1049 0.724916)
			(stroke
				(width 0.1)
				(type default)
			)
			(layer "F.Fab")
		)
		(fp_line
			(start -1.1049 0.724916)
			(end 1.1049 0.724916)
			(stroke
				(width 0.1)
				(type default)
			)
			(layer "F.Fab")
		)
		(fp_line
			(start 1.1049 -0.724916)
			(end -1.1049 -0.724916)
			(stroke
				(width 0.1)
				(type default)
			)
			(layer "F.Fab")
		)
		(fp_line
			(start 1.1049 0.724916)
			(end 1.1049 -0.724916)
			(stroke
				(width 0.1)
				(type default)
			)
			(layer "F.Fab")
		)
		(pad "1" smd rect
			(at -0.889 0 180)
			(size 1.016 1.27)
			(layers "F.Cu" "F.Mask" "F.Paste")
			(net "PGPPA_AUX")
		)
		(pad "2" smd rect
			(at 0.889 0 180)
			(size 1.016 1.27)
			(layers "F.Cu" "F.Mask" "F.Paste")
			(net "GND")
		)
	)
	(footprint ""
		(layer "F.Cu")
		(at 99.724464 -65.141094 -90)
		(property "Reference" "R3091"
			(at 0 0 270)
			(layer "F.SilkS")
			(hide yes)
			(effects
				(font
					(size 1.27 1.27)
				)
			)
		)
		(property "Value" ""
			(at 0 0 270)
			(layer "F.Fab")
			(effects
				(font
					(size 1.27 1.27)
				)
			)
		)
		(duplicate_pad_numbers_are_jumpers no)
		(fp_line
			(start -0.7874 0.4064)
			(end -0.7874 -0.4064)
			(stroke
				(width 0.1524)
				(type default)
			)
			(layer "F.SilkS")
		)
		(fp_line
			(start 0.7874 0.4064)
			(end -0.7874 0.4064)
			(stroke
				(width 0.1524)
				(type default)
			)
			(layer "F.SilkS")
		)
		(fp_line
			(start -0.7874 -0.4064)
			(end 0.7874 -0.4064)
			(stroke
				(width 0.1524)
				(type default)
			)
			(layer "F.SilkS")
		)
		(fp_line
			(start 0.7874 -0.4064)
			(end 0.7874 0.4064)
			(stroke
				(width 0.1524)
				(type default)
			)
			(layer "F.SilkS")
		)
		(fp_line
			(start -0.67945 0.3048)
			(end -0.67945 -0.305054)
			(stroke
				(width 0.1)
				(type default)
			)
			(layer "F.Fab")
		)
		(fp_line
			(start -0.12065 0.3048)
			(end -0.67945 0.3048)
			(stroke
				(width 0.1)
				(type default)
			)
			(layer "F.Fab")
		)
		(fp_line
			(start 0.120396 0.3048)
			(end 0.120396 0.2794)
			(stroke
				(width 0.1)
				(type default)
			)
			(layer "F.Fab")
		)
		(fp_line
			(start 0.67945 0.3048)
			(end 0.120396 0.3048)
			(stroke
				(width 0.1)
				(type default)
			)
			(layer "F.Fab")
		)
		(fp_line
			(start -0.12065 0.2794)
			(end -0.12065 0.3048)
			(stroke
				(width 0.1)
				(type default)
			)
			(layer "F.Fab")
		)
		(fp_line
			(start 0.120396 0.2794)
			(end -0.12065 0.2794)
			(stroke
				(width 0.1)
				(type default)
			)
			(layer "F.Fab")
		)
		(fp_line
			(start -0.12065 -0.2794)
			(end 0.12065 -0.2794)
			(stroke
				(width 0.1)
				(type default)
			)
			(layer "F.Fab")
		)
		(fp_line
			(start 0.12065 -0.2794)
			(end 0.12065 -0.3048)
			(stroke
				(width 0.1)
				(type default)
			)
			(layer "F.Fab")
		)
		(fp_line
			(start 0.12065 -0.3048)
			(end 0.67945 -0.3048)
			(stroke
				(width 0.1)
				(type default)
			)
			(layer "F.Fab")
		)
		(fp_line
			(start 0.67945 -0.3048)
			(end 0.67945 0.3048)
			(stroke
				(width 0.1)
				(type default)
			)
			(layer "F.Fab")
		)
		(fp_line
			(start -0.67945 -0.305054)
			(end -0.12065 -0.305054)
			(stroke
				(width 0.1)
				(type default)
			)
			(layer "F.Fab")
		)
		(fp_line
			(start -0.12065 -0.305054)
			(end -0.12065 -0.2794)
			(stroke
				(width 0.1)
				(type default)
			)
			(layer "F.Fab")
		)
		(pad "1" smd circle
			(at -0.40005 0 270)
			(size 0 0)
			(layers "F.Cu" "F.Mask" "F.Paste")
			(net "LED_PWRGD_PVCCIN_CPU0")
		)
		(pad "2" smd circle
			(at 0.40005 0 270)
			(size 0 0)
			(layers "F.Cu" "F.Mask" "F.Paste")
			(net "P3V3_AUX")
		)
	)
	(footprint ""
		(layer "F.Cu")
		(at 337.536282 -341.729822 90)
		(property "Reference" "PR1770"
			(at 0 0 90)
			(layer "F.SilkS")
			(hide yes)
			(effects
				(font
					(size 1.27 1.27)
				)
			)
		)
		(property "Value" ""
			(at 0 0 90)
			(layer "F.Fab")
			(effects
				(font
					(size 1.27 1.27)
				)
			)
		)
		(duplicate_pad_numbers_are_jumpers no)
		(fp_line
			(start 0.7874 -0.4064)
			(end 0.7874 0.4064)
			(stroke
				(width 0.1524)
				(type default)
			)
			(layer "F.SilkS")
		)
		(fp_line
			(start -0.7874 -0.4064)
			(end 0.7874 -0.4064)
			(stroke
				(width 0.1524)
				(type default)
			)
			(layer "F.SilkS")
		)
		(fp_line
			(start 0.7874 0.4064)
			(end -0.7874 0.4064)
			(stroke
				(width 0.1524)
				(type default)
			)
			(layer "F.SilkS")
		)
		(fp_line
			(start -0.7874 0.4064)
			(end -0.7874 -0.4064)
			(stroke
				(width 0.1524)
				(type default)
			)
			(layer "F.SilkS")
		)
		(fp_line
			(start -0.12065 -0.305054)
			(end -0.12065 -0.2794)
			(stroke
				(width 0.1)
				(type default)
			)
			(layer "F.Fab")
		)
		(fp_line
			(start -0.67945 -0.305054)
			(end -0.12065 -0.305054)
			(stroke
				(width 0.1)
				(type default)
			)
			(layer "F.Fab")
		)
		(fp_line
			(start 0.67945 -0.3048)
			(end 0.67945 0.3048)
			(stroke
				(width 0.1)
				(type default)
			)
			(layer "F.Fab")
		)
		(fp_line
			(start 0.12065 -0.3048)
			(end 0.67945 -0.3048)
			(stroke
				(width 0.1)
				(type default)
			)
			(layer "F.Fab")
		)
		(fp_line
			(start 0.12065 -0.2794)
			(end 0.12065 -0.3048)
			(stroke
				(width 0.1)
				(type default)
			)
			(layer "F.Fab")
		)
		(fp_line
			(start -0.12065 -0.2794)
			(end 0.12065 -0.2794)
			(stroke
				(width 0.1)
				(type default)
			)
			(layer "F.Fab")
		)
		(fp_line
			(start 0.120396 0.2794)
			(end -0.12065 0.2794)
			(stroke
				(width 0.1)
				(type default)
			)
			(layer "F.Fab")
		)
		(fp_line
			(start -0.12065 0.2794)
			(end -0.12065 0.3048)
			(stroke
				(width 0.1)
				(type default)
			)
			(layer "F.Fab")
		)
		(fp_line
			(start 0.67945 0.3048)
			(end 0.120396 0.3048)
			(stroke
				(width 0.1)
				(type default)
			)
			(layer "F.Fab")
		)
		(fp_line
			(start 0.120396 0.3048)
			(end 0.120396 0.2794)
			(stroke
				(width 0.1)
				(type default)
			)
			(layer "F.Fab")
		)
		(fp_line
			(start -0.12065 0.3048)
			(end -0.67945 0.3048)
			(stroke
				(width 0.1)
				(type default)
			)
			(layer "F.Fab")
		)
		(fp_line
			(start -0.67945 0.3048)
			(end -0.67945 -0.305054)
			(stroke
				(width 0.1)
				(type default)
			)
			(layer "F.Fab")
		)
		(pad "1" smd circle
			(at -0.40005 0 90)
			(size 0 0)
			(layers "F.Cu" "F.Mask" "F.Paste")
			(net "SW_PVCCIN_CPU0_BOOT6")
		)
		(pad "2" smd circle
			(at 0.40005 0 90)
			(size 0 0)
			(layers "F.Cu" "F.Mask" "F.Paste")
			(net "SW_PVCCIN_CPU0_BOOT6_R")
		)
	)
	(footprint ""
		(layer "F.Cu")
		(at 99.067366 -338.180172 -90)
		(property "Reference" "PC565"
			(at 0 0 270)
			(layer "F.SilkS")
			(hide yes)
			(effects
				(font
					(size 1.27 1.27)
				)
			)
		)
		(property "Value" ""
			(at 0 0 270)
			(layer "F.Fab")
			(effects
				(font
					(size 1.27 1.27)
				)
			)
		)
		(duplicate_pad_numbers_are_jumpers no)
		(fp_line
			(start -0.7874 0.4064)
			(end -0.7874 -0.4064)
			(stroke
				(width 0.1524)
				(type default)
			)
			(layer "F.SilkS")
		)
		(fp_line
			(start 0.7874 0.4064)
			(end -0.7874 0.4064)
			(stroke
				(width 0.1524)
				(type default)
			)
			(layer "F.SilkS")
		)
		(fp_line
			(start -0.7874 -0.4064)
			(end 0.7874 -0.4064)
			(stroke
				(width 0.1524)
				(type default)
			)
			(layer "F.SilkS")
		)
		(fp_line
			(start 0.7874 -0.4064)
			(end 0.7874 0.4064)
			(stroke
				(width 0.1524)
				(type default)
			)
			(layer "F.SilkS")
		)
		(fp_line
			(start -0.67945 0.3048)
			(end -0.67945 -0.305054)
			(stroke
				(width 0.1)
				(type default)
			)
			(layer "F.Fab")
		)
		(fp_line
			(start -0.12065 0.3048)
			(end -0.67945 0.3048)
			(stroke
				(width 0.1)
				(type default)
			)
			(layer "F.Fab")
		)
		(fp_line
			(start 0.120396 0.3048)
			(end 0.120396 0.2794)
			(stroke
				(width 0.1)
				(type default)
			)
			(layer "F.Fab")
		)
		(fp_line
			(start 0.67945 0.3048)
			(end 0.120396 0.3048)
			(stroke
				(width 0.1)
				(type default)
			)
			(layer "F.Fab")
		)
		(fp_line
			(start -0.12065 0.2794)
			(end -0.12065 0.3048)
			(stroke
				(width 0.1)
				(type default)
			)
			(layer "F.Fab")
		)
		(fp_line
			(start 0.120396 0.2794)
			(end -0.12065 0.2794)
			(stroke
				(width 0.1)
				(type default)
			)
			(layer "F.Fab")
		)
		(fp_line
			(start -0.12065 -0.2794)
			(end 0.12065 -0.2794)
			(stroke
				(width 0.1)
				(type default)
			)
			(layer "F.Fab")
		)
		(fp_line
			(start 0.12065 -0.2794)
			(end 0.12065 -0.3048)
			(stroke
				(width 0.1)
				(type default)
			)
			(layer "F.Fab")
		)
		(fp_line
			(start 0.12065 -0.3048)
			(end 0.67945 -0.3048)
			(stroke
				(width 0.1)
				(type default)
			)
			(layer "F.Fab")
		)
		(fp_line
			(start 0.67945 -0.3048)
			(end 0.67945 0.3048)
			(stroke
				(width 0.1)
				(type default)
			)
			(layer "F.Fab")
		)
		(fp_line
			(start -0.67945 -0.305054)
			(end -0.12065 -0.305054)
			(stroke
				(width 0.1)
				(type default)
			)
			(layer "F.Fab")
		)
		(fp_line
			(start -0.12065 -0.305054)
			(end -0.12065 -0.2794)
			(stroke
				(width 0.1)
				(type default)
			)
			(layer "F.Fab")
		)
		(pad "1" smd circle
			(at -0.40005 0 270)
			(size 0 0)
			(layers "F.Cu" "F.Mask" "F.Paste")
			(net "SW_PVCCIN_CPU1_BOOT1_R")
		)
		(pad "2" smd circle
			(at 0.40005 0 270)
			(size 0 0)
			(layers "F.Cu" "F.Mask" "F.Paste")
			(net "SW_PVCCIN_CPU1_BOOTR1")
		)
	)
	(footprint ""
		(layer "F.Cu")
		(at 367.762282 -58.533792)
		(property "Reference" "U17"
			(at -2.032 -3.27533 0)
			(unlocked yes)
			(layer "F.SilkS")
			(effects
				(font
					(size 0.7874 0.5842)
					(thickness 0.1524)
				)
				(justify left)
			)
		)
		(property "Value" ""
			(at 0 0 0)
			(layer "F.Fab")
			(effects
				(font
					(size 1.27 1.27)
				)
			)
		)
		(duplicate_pad_numbers_are_jumpers no)
		(fp_line
			(start -2.0066 -2.5527)
			(end -0.5715 -2.5527)
			(stroke
				(width 0.1524)
				(type default)
			)
			(layer "F.SilkS")
		)
		(fp_line
			(start -2.0066 2.5527)
			(end -2.0066 -2.5527)
			(stroke
				(width 0.1524)
				(type default)
			)
			(layer "F.SilkS")
		)
		(fp_line
			(start -0.5715 -2.5527)
			(end 0 -1.9812)
			(stroke
				(width 0.1524)
				(type default)
			)
			(layer "F.SilkS")
		)
		(fp_line
			(start 0 -1.9812)
			(end 0.5715 -2.5527)
			(stroke
				(width 0.1524)
				(type default)
			)
			(layer "F.SilkS")
		)
		(fp_line
			(start 0.5715 -2.5527)
			(end 2.0066 -2.5527)
			(stroke
				(width 0.1524)
				(type default)
			)
			(layer "F.SilkS")
		)
		(fp_line
			(start 2.0066 -2.5527)
			(end 2.0066 2.5527)
			(stroke
				(width 0.1524)
				(type default)
			)
			(layer "F.SilkS")
		)
		(fp_line
			(start 2.0066 2.5527)
			(end -2.0066 2.5527)
			(stroke
				(width 0.1524)
				(type default)
			)
			(layer "F.SilkS")
		)
		(fp_poly
			(pts
				(xy -4.36372 -2.233168) (xy -3.81 -1.905) (xy -4.36372 -1.608328)
			)
			(stroke
				(width 0)
				(type default)
			)
			(fill yes)
			(layer "F.SilkS")
		)
		(fp_line
			(start -2.249932 -2.549906)
			(end 2.249932 -2.549906)
			(stroke
				(width 0.1)
				(type default)
			)
			(layer "F.Fab")
		)
		(fp_line
			(start -2.249932 2.549906)
			(end -2.249932 -2.549906)
			(stroke
				(width 0.1)
				(type default)
			)
			(layer "F.Fab")
		)
		(fp_line
			(start 2.249932 -2.549906)
			(end 2.249932 2.549906)
			(stroke
				(width 0.1)
				(type default)
			)
			(layer "F.Fab")
		)
		(fp_line
			(start 2.249932 2.549906)
			(end -2.249932 2.549906)
			(stroke
				(width 0.1)
				(type default)
			)
			(layer "F.Fab")
		)
		(fp_poly
			(pts
				(xy -4.36372 -1.608328) (xy -4.36372 -2.233168) (xy -3.81 -1.905)
			)
			(stroke
				(width 0)
				(type default)
			)
			(fill yes)
			(layer "F.Fab")
		)
		(pad "1" smd rect
			(at -2.921 -1.949958 270)
			(size 0.3556 1.4986)
			(layers "F.Cu" "F.Mask" "F.Paste")
			(net "PWRGD_PVNN_MAIN_CPU0")
		)
		(pad "2" smd rect
			(at -2.921 -1.299972 270)
			(size 0.3556 1.4986)
			(layers "F.Cu" "F.Mask" "F.Paste")
			(net "JTAG_DBP_TMS")
		)
		(pad "3" smd rect
			(at -2.921 -0.649986 270)
			(size 0.3556 1.4986)
			(layers "F.Cu" "F.Mask" "F.Paste")
			(net "JTAG_DBP_CPU_QS_GTL_TMS")
		)
		(pad "4" smd rect
			(at -2.921 0 270)
			(size 0.3556 1.4986)
			(layers "F.Cu" "F.Mask" "F.Paste")
			(net "PWRGD_PVNN_MAIN_CPU0")
		)
		(pad "5" smd rect
			(at -2.921 0.649986 270)
			(size 0.3556 1.4986)
			(layers "F.Cu" "F.Mask" "F.Paste")
			(net "JTAG_DBP_TDI")
		)
		(pad "6" smd rect
			(at -2.921 1.299972 270)
			(size 0.3556 1.4986)
			(layers "F.Cu" "F.Mask" "F.Paste")
			(net "JTAG_QS_MUX_GTL_TDI")
		)
		(pad "7" smd rect
			(at -2.921 1.949958 270)
			(size 0.3556 1.4986)
			(layers "F.Cu" "F.Mask" "F.Paste")
			(net "GND")
		)
		(pad "8" smd rect
			(at 2.921 1.949958 270)
			(size 0.3556 1.4986)
			(layers "F.Cu" "F.Mask" "F.Paste")
			(net "TP_74CB_B8")
		)
		(pad "9" smd rect
			(at 2.921 1.299972 270)
			(size 0.3556 1.4986)
			(layers "F.Cu" "F.Mask" "F.Paste")
			(net "PD_74CB_A9")
		)
		(pad "10" smd rect
			(at 2.921 0.649986 270)
			(size 0.3556 1.4986)
			(layers "F.Cu" "F.Mask" "F.Paste")
			(net "PWRGD_PVNN_MAIN_CPU0")
		)
		(pad "11" smd rect
			(at 2.921 0 270)
			(size 0.3556 1.4986)
			(layers "F.Cu" "F.Mask" "F.Paste")
			(net "JTAG_MUX_QS_GTL_TDO")
		)
		(pad "12" smd rect
			(at 2.921 -0.649986 270)
			(size 0.3556 1.4986)
			(layers "F.Cu" "F.Mask" "F.Paste")
			(net "JTAG_DBP_TDO")
		)
		(pad "13" smd rect
			(at 2.921 -1.299972 270)
			(size 0.3556 1.4986)
			(layers "F.Cu" "F.Mask" "F.Paste")
			(net "PWRGD_PVNN_MAIN_CPU0")
		)
		(pad "14" smd rect
			(at 2.921 -1.949958 270)
			(size 0.3556 1.4986)
			(layers "F.Cu" "F.Mask" "F.Paste")
			(net "P3V3_AUX")
		)
	)
	(footprint ""
		(layer "F.Cu")
		(at 432.916838 -180.97627)
		(property "Reference" "PU81"
			(at 3.54838 7.799832 0)
			(unlocked yes)
			(layer "F.SilkS")
			(effects
				(font
					(size 0.7874 0.5842)
					(thickness 0.1524)
				)
				(justify left)
			)
		)
		(property "Value" ""
			(at 0 0 0)
			(layer "F.Fab")
			(effects
				(font
					(size 1.27 1.27)
				)
			)
		)
		(duplicate_pad_numbers_are_jumpers no)
		(fp_line
			(start -1.050036 -1.549908)
			(end -0.503936 -1.549908)
			(stroke
				(width 0.1524)
				(type default)
			)
			(layer "F.SilkS")
		)
		(fp_line
			(start -1.050036 -1.253998)
			(end -1.050036 -1.549908)
			(stroke
				(width 0.1524)
				(type default)
			)
			(layer "F.SilkS")
		)
		(fp_line
			(start -1.050036 1.549908)
			(end -1.050036 1.253998)
			(stroke
				(width 0.1524)
				(type default)
			)
			(layer "F.SilkS")
		)
		(fp_line
			(start -0.503936 1.549908)
			(end -1.050036 1.549908)
			(stroke
				(width 0.1524)
				(type default)
			)
			(layer "F.SilkS")
		)
		(fp_line
			(start 0.503936 -1.549908)
			(end 1.050036 -1.549908)
			(stroke
				(width 0.1524)
				(type default)
			)
			(layer "F.SilkS")
		)
		(fp_line
			(start 1.050036 -1.549908)
			(end 1.050036 -1.253998)
			(stroke
				(width 0.1524)
				(type default)
			)
			(layer "F.SilkS")
		)
		(fp_line
			(start 1.050036 1.253998)
			(end 1.050036 1.549908)
			(stroke
				(width 0.1524)
				(type default)
			)
			(layer "F.SilkS")
		)
		(fp_line
			(start 1.050036 1.549908)
			(end 0.503936 1.549908)
			(stroke
				(width 0.1524)
				(type default)
			)
			(layer "F.SilkS")
		)
		(fp_poly
			(pts
				(xy -1.285494 -1.491742) (xy -2.093722 -1.761236) (xy -1.554988 -2.29997)
			)
			(stroke
				(width 0)
				(type default)
			)
			(fill yes)
			(layer "F.SilkS")
		)
		(fp_line
			(start -1.050036 -1.549908)
			(end 1.050036 -1.549908)
			(stroke
				(width 0.1)
				(type default)
			)
			(layer "F.Fab")
		)
		(fp_line
			(start -1.050036 1.549908)
			(end -1.050036 -1.549908)
			(stroke
				(width 0.1)
				(type default)
			)
			(layer "F.Fab")
		)
		(fp_line
			(start 1.050036 -1.549908)
			(end 1.050036 1.549908)
			(stroke
				(width 0.1)
				(type default)
			)
			(layer "F.Fab")
		)
		(fp_line
			(start 1.050036 1.549908)
			(end -1.050036 1.549908)
			(stroke
				(width 0.1)
				(type default)
			)
			(layer "F.Fab")
		)
		(fp_poly
			(pts
				(xy -2.2352 -0.618998) (xy -2.2352 -1.380998) (xy -1.4732 -0.999998)
			)
			(stroke
				(width 0)
				(type default)
			)
			(fill yes)
			(layer "F.Fab")
		)
		(pad "1" smd circle
			(at -0.94996 -0.999998 270)
			(size 0 0)
			(layers "F.Cu" "F.Mask" "F.Paste")
			(net "GND")
		)
		(pad "2" smd rect
			(at -0.849884 -0.499872 90)
			(size 0.254 0.9144)
			(layers "F.Cu" "F.Mask" "F.Paste")
			(net "SW_PVNN_MAIN_CPU0_SW")
		)
		(pad "3" smd rect
			(at -0.649986 0 90)
			(size 0.254 1.3208)
			(layers "F.Cu" "F.Mask" "F.Paste")
			(net "SW_P12V_PVCCINFAON_CPU0_FLT")
		)
		(pad "4" smd rect
			(at -0.849884 0.499872 90)
			(size 0.254 0.9144)
			(layers "F.Cu" "F.Mask" "F.Paste")
			(net "PVNN_MAIN_CPU0_CS")
		)
		(pad "5" smd circle
			(at -0.94996 0.999998 270)
			(size 0 0)
			(layers "F.Cu" "F.Mask" "F.Paste")
			(net "FM_PVNN_MAIN_CPU0_EN")
		)
		(pad "6" smd circle
			(at -0.249936 1.450086)
			(size 0 0)
			(layers "F.Cu" "F.Mask" "F.Paste")
			(net "PVNN_MAIN_CPU0_FB")
		)
		(pad "7" smd circle
			(at 0.249936 1.450086)
			(size 0 0)
			(layers "F.Cu" "F.Mask" "F.Paste")
			(net "GND")
		)
		(pad "8" smd circle
			(at 0.94996 0.999998 90)
			(size 0 0)
			(layers "F.Cu" "F.Mask" "F.Paste")
			(net "PVNN_MAIN_CPU0_REF")
		)
		(pad "9" smd rect
			(at 0.849884 0.499872 90)
			(size 0.254 0.9144)
			(layers "F.Cu" "F.Mask" "F.Paste")
			(net "PWRGD_PVNN_MAIN_CPU0_R")
		)
		(pad "10" smd rect
			(at 0.849884 0 90)
			(size 0.254 0.9144)
			(layers "F.Cu" "F.Mask" "F.Paste")
			(net "SW_PVNN_MAIN_CPU0_BST")
		)
		(pad "11" smd rect
			(at 0.849884 -0.499872 90)
			(size 0.254 0.9144)
			(layers "F.Cu" "F.Mask" "F.Paste")
			(net "SW_PVNN_MAIN_CPU0_SW")
		)
		(pad "12" smd circle
			(at 0.94996 -0.999998 90)
			(size 0 0)
			(layers "F.Cu" "F.Mask" "F.Paste")
			(net "PVNN_MAIN_CPU0_MODE")
		)
		(pad "13" smd circle
			(at 0.249936 -1.450086 180)
			(size 0 0)
			(layers "F.Cu" "F.Mask" "F.Paste")
			(net "PVNN_MAIN_CPU0_VCC")
		)
		(pad "14" smd circle
			(at -0.249936 -1.450086 180)
			(size 0 0)
			(layers "F.Cu" "F.Mask" "F.Paste")
			(net "GND")
		)
	)
	(footprint ""
		(layer "F.Cu")
		(at 441.050172 -32.173418 90)
		(property "Reference" "PC2155"
			(at 0 0 90)
			(layer "F.SilkS")
			(hide yes)
			(effects
				(font
					(size 1.27 1.27)
				)
			)
		)
		(property "Value" ""
			(at 0 0 90)
			(layer "F.Fab")
			(effects
				(font
					(size 1.27 1.27)
				)
			)
		)
		(duplicate_pad_numbers_are_jumpers no)
		(fp_line
			(start 0.7874 -0.4064)
			(end 0.7874 0.4064)
			(stroke
				(width 0.1524)
				(type default)
			)
			(layer "F.SilkS")
		)
		(fp_line
			(start -0.7874 -0.4064)
			(end 0.7874 -0.4064)
			(stroke
				(width 0.1524)
				(type default)
			)
			(layer "F.SilkS")
		)
		(fp_line
			(start 0.7874 0.4064)
			(end -0.7874 0.4064)
			(stroke
				(width 0.1524)
				(type default)
			)
			(layer "F.SilkS")
		)
		(fp_line
			(start -0.7874 0.4064)
			(end -0.7874 -0.4064)
			(stroke
				(width 0.1524)
				(type default)
			)
			(layer "F.SilkS")
		)
		(fp_line
			(start -0.12065 -0.305054)
			(end -0.12065 -0.2794)
			(stroke
				(width 0.1)
				(type default)
			)
			(layer "F.Fab")
		)
		(fp_line
			(start -0.67945 -0.305054)
			(end -0.12065 -0.305054)
			(stroke
				(width 0.1)
				(type default)
			)
			(layer "F.Fab")
		)
		(fp_line
			(start 0.67945 -0.3048)
			(end 0.67945 0.3048)
			(stroke
				(width 0.1)
				(type default)
			)
			(layer "F.Fab")
		)
		(fp_line
			(start 0.12065 -0.3048)
			(end 0.67945 -0.3048)
			(stroke
				(width 0.1)
				(type default)
			)
			(layer "F.Fab")
		)
		(fp_line
			(start 0.12065 -0.2794)
			(end 0.12065 -0.3048)
			(stroke
				(width 0.1)
				(type default)
			)
			(layer "F.Fab")
		)
		(fp_line
			(start -0.12065 -0.2794)
			(end 0.12065 -0.2794)
			(stroke
				(width 0.1)
				(type default)
			)
			(layer "F.Fab")
		)
		(fp_line
			(start 0.120396 0.2794)
			(end -0.12065 0.2794)
			(stroke
				(width 0.1)
				(type default)
			)
			(layer "F.Fab")
		)
		(fp_line
			(start -0.12065 0.2794)
			(end -0.12065 0.3048)
			(stroke
				(width 0.1)
				(type default)
			)
			(layer "F.Fab")
		)
		(fp_line
			(start 0.67945 0.3048)
			(end 0.120396 0.3048)
			(stroke
				(width 0.1)
				(type default)
			)
			(layer "F.Fab")
		)
		(fp_line
			(start 0.120396 0.3048)
			(end 0.120396 0.2794)
			(stroke
				(width 0.1)
				(type default)
			)
			(layer "F.Fab")
		)
		(fp_line
			(start -0.12065 0.3048)
			(end -0.67945 0.3048)
			(stroke
				(width 0.1)
				(type default)
			)
			(layer "F.Fab")
		)
		(fp_line
			(start -0.67945 0.3048)
			(end -0.67945 -0.305054)
			(stroke
				(width 0.1)
				(type default)
			)
			(layer "F.Fab")
		)
		(pad "1" smd circle
			(at -0.40005 0 90)
			(size 0 0)
			(layers "F.Cu" "F.Mask" "F.Paste")
			(net "P12V_OCP_SS_1")
		)
		(pad "2" smd circle
			(at 0.40005 0 90)
			(size 0 0)
			(layers "F.Cu" "F.Mask" "F.Paste")
			(net "GND")
		)
	)
	(footprint ""
		(layer "F.Cu")
		(at 113.494312 -128.392682 180)
		(property "Reference" "R3526"
			(at 0 0 180)
			(layer "F.SilkS")
			(hide yes)
			(effects
				(font
					(size 1.27 1.27)
				)
			)
		)
		(property "Value" ""
			(at 0 0 180)
			(layer "F.Fab")
			(effects
				(font
					(size 1.27 1.27)
				)
			)
		)
		(duplicate_pad_numbers_are_jumpers no)
		(fp_line
			(start 0.7874 0.4064)
			(end -0.7874 0.4064)
			(stroke
				(width 0.1524)
				(type default)
			)
			(layer "F.SilkS")
		)
		(fp_line
			(start 0.7874 -0.4064)
			(end 0.7874 0.4064)
			(stroke
				(width 0.1524)
				(type default)
			)
			(layer "F.SilkS")
		)
		(fp_line
			(start -0.7874 0.4064)
			(end -0.7874 -0.4064)
			(stroke
				(width 0.1524)
				(type default)
			)
			(layer "F.SilkS")
		)
		(fp_line
			(start -0.7874 -0.4064)
			(end 0.7874 -0.4064)
			(stroke
				(width 0.1524)
				(type default)
			)
			(layer "F.SilkS")
		)
		(fp_line
			(start 0.67945 0.3048)
			(end 0.120396 0.3048)
			(stroke
				(width 0.1)
				(type default)
			)
			(layer "F.Fab")
		)
		(fp_line
			(start 0.67945 -0.3048)
			(end 0.67945 0.3048)
			(stroke
				(width 0.1)
				(type default)
			)
			(layer "F.Fab")
		)
		(fp_line
			(start 0.12065 -0.2794)
			(end 0.12065 -0.3048)
			(stroke
				(width 0.1)
				(type default)
			)
			(layer "F.Fab")
		)
		(fp_line
			(start 0.12065 -0.3048)
			(end 0.67945 -0.3048)
			(stroke
				(width 0.1)
				(type default)
			)
			(layer "F.Fab")
		)
		(fp_line
			(start 0.120396 0.3048)
			(end 0.120396 0.2794)
			(stroke
				(width 0.1)
				(type default)
			)
			(layer "F.Fab")
		)
		(fp_line
			(start 0.120396 0.2794)
			(end -0.12065 0.2794)
			(stroke
				(width 0.1)
				(type default)
			)
			(layer "F.Fab")
		)
		(fp_line
			(start -0.12065 0.3048)
			(end -0.67945 0.3048)
			(stroke
				(width 0.1)
				(type default)
			)
			(layer "F.Fab")
		)
		(fp_line
			(start -0.12065 0.2794)
			(end -0.12065 0.3048)
			(stroke
				(width 0.1)
				(type default)
			)
			(layer "F.Fab")
		)
		(fp_line
			(start -0.12065 -0.2794)
			(end 0.12065 -0.2794)
			(stroke
				(width 0.1)
				(type default)
			)
			(layer "F.Fab")
		)
		(fp_line
			(start -0.12065 -0.305054)
			(end -0.12065 -0.2794)
			(stroke
				(width 0.1)
				(type default)
			)
			(layer "F.Fab")
		)
		(fp_line
			(start -0.67945 0.3048)
			(end -0.67945 -0.305054)
			(stroke
				(width 0.1)
				(type default)
			)
			(layer "F.Fab")
		)
		(fp_line
			(start -0.67945 -0.305054)
			(end -0.12065 -0.305054)
			(stroke
				(width 0.1)
				(type default)
			)
			(layer "F.Fab")
		)
		(pad "1" smd circle
			(at -0.40005 0 180)
			(size 0 0)
			(layers "F.Cu" "F.Mask" "F.Paste")
			(net "SMB_PCIE0_3V3AUX_SCL_R5")
		)
		(pad "2" smd circle
			(at 0.40005 0 180)
			(size 0 0)
			(layers "F.Cu" "F.Mask" "F.Paste")
			(net "SMB_SENSOR_E1S_3V3AUX_SCL")
		)
	)
	(footprint ""
		(layer "F.Cu")
		(at 426.607986 -366.691164 90)
		(property "Reference" "PR1782"
			(at 0 0 90)
			(layer "F.SilkS")
			(hide yes)
			(effects
				(font
					(size 1.27 1.27)
				)
			)
		)
		(property "Value" ""
			(at 0 0 90)
			(layer "F.Fab")
			(effects
				(font
					(size 1.27 1.27)
				)
			)
		)
		(duplicate_pad_numbers_are_jumpers no)
		(fp_line
			(start 0.7874 -0.4064)
			(end 0.7874 0.4064)
			(stroke
				(width 0.1524)
				(type default)
			)
			(layer "F.SilkS")
		)
		(fp_line
			(start -0.7874 -0.4064)
			(end 0.7874 -0.4064)
			(stroke
				(width 0.1524)
				(type default)
			)
			(layer "F.SilkS")
		)
		(fp_line
			(start 0.7874 0.4064)
			(end -0.7874 0.4064)
			(stroke
				(width 0.1524)
				(type default)
			)
			(layer "F.SilkS")
		)
		(fp_line
			(start -0.7874 0.4064)
			(end -0.7874 -0.4064)
			(stroke
				(width 0.1524)
				(type default)
			)
			(layer "F.SilkS")
		)
		(fp_line
			(start -0.12065 -0.305054)
			(end -0.12065 -0.2794)
			(stroke
				(width 0.1)
				(type default)
			)
			(layer "F.Fab")
		)
		(fp_line
			(start -0.67945 -0.305054)
			(end -0.12065 -0.305054)
			(stroke
				(width 0.1)
				(type default)
			)
			(layer "F.Fab")
		)
		(fp_line
			(start 0.67945 -0.3048)
			(end 0.67945 0.3048)
			(stroke
				(width 0.1)
				(type default)
			)
			(layer "F.Fab")
		)
		(fp_line
			(start 0.12065 -0.3048)
			(end 0.67945 -0.3048)
			(stroke
				(width 0.1)
				(type default)
			)
			(layer "F.Fab")
		)
		(fp_line
			(start 0.12065 -0.2794)
			(end 0.12065 -0.3048)
			(stroke
				(width 0.1)
				(type default)
			)
			(layer "F.Fab")
		)
		(fp_line
			(start -0.12065 -0.2794)
			(end 0.12065 -0.2794)
			(stroke
				(width 0.1)
				(type default)
			)
			(layer "F.Fab")
		)
		(fp_line
			(start 0.120396 0.2794)
			(end -0.12065 0.2794)
			(stroke
				(width 0.1)
				(type default)
			)
			(layer "F.Fab")
		)
		(fp_line
			(start -0.12065 0.2794)
			(end -0.12065 0.3048)
			(stroke
				(width 0.1)
				(type default)
			)
			(layer "F.Fab")
		)
		(fp_line
			(start 0.67945 0.3048)
			(end 0.120396 0.3048)
			(stroke
				(width 0.1)
				(type default)
			)
			(layer "F.Fab")
		)
		(fp_line
			(start 0.120396 0.3048)
			(end 0.120396 0.2794)
			(stroke
				(width 0.1)
				(type default)
			)
			(layer "F.Fab")
		)
		(fp_line
			(start -0.12065 0.3048)
			(end -0.67945 0.3048)
			(stroke
				(width 0.1)
				(type default)
			)
			(layer "F.Fab")
		)
		(fp_line
			(start -0.67945 0.3048)
			(end -0.67945 -0.305054)
			(stroke
				(width 0.1)
				(type default)
			)
			(layer "F.Fab")
		)
		(pad "1" smd circle
			(at -0.40005 0 90)
			(size 0 0)
			(layers "F.Cu" "F.Mask" "F.Paste")
			(net "SW_PVCCFA_EHV_FIVRA_CPU0_BOOT3")
		)
		(pad "2" smd circle
			(at 0.40005 0 90)
			(size 0 0)
			(layers "F.Cu" "F.Mask" "F.Paste")
			(net "SW_PVCCFA_EHV_FIVRA_CPU0_BOOT3_")
		)
	)
	(footprint ""
		(layer "F.Cu")
		(at 391.36828 -121.15546)
		(property "Reference" "ME13"
			(at -9.652 -9.540748 0)
			(unlocked yes)
			(layer "F.SilkS")
			(effects
				(font
					(size 0.7874 0.5842)
					(thickness 0.1524)
				)
				(justify left)
			)
		)
		(property "Value" ""
			(at 0 0 0)
			(layer "F.Fab")
			(effects
				(font
					(size 1.27 1.27)
				)
			)
		)
		(duplicate_pad_numbers_are_jumpers no)
		(zone
			(layer "F.Cu")
			(hatch none 0.5)
			(connect_pads
				(clearance 0)
			)
			(min_thickness 0.25)
			(keepout
				(tracks allowed)
				(vias allowed)
				(pads allowed)
				(copperpour allowed)
				(footprints not_allowed)
			)
			(placement
				(enabled no)
				(sheetname "")
			)
			(fill
				(thermal_gap 0.5)
				(thermal_bridge_width 0.5)
				(island_removal_mode 0)
			)
			(polygon
				(pts
					(arc
						(start 401.36826 -121.15546)
						(mid 381.3683 -121.15546)
						(end 401.36826 -121.15546)
					)
				)
			)
		)
	)
	(footprint ""
		(layer "F.Cu")
		(at 249.52579 -53.424582 -90)
		(property "Reference" "PR3957"
			(at 0 0 270)
			(layer "F.SilkS")
			(hide yes)
			(effects
				(font
					(size 1.27 1.27)
				)
			)
		)
		(property "Value" ""
			(at 0 0 270)
			(layer "F.Fab")
			(effects
				(font
					(size 1.27 1.27)
				)
			)
		)
		(duplicate_pad_numbers_are_jumpers no)
		(fp_line
			(start -1.2954 0.5842)
			(end -1.2954 -0.5842)
			(stroke
				(width 0.1524)
				(type default)
			)
			(layer "F.SilkS")
		)
		(fp_line
			(start 1.2954 0.5842)
			(end -1.2954 0.5842)
			(stroke
				(width 0.1524)
				(type default)
			)
			(layer "F.SilkS")
		)
		(fp_line
			(start -1.2954 -0.5842)
			(end 1.2954 -0.5842)
			(stroke
				(width 0.1524)
				(type default)
			)
			(layer "F.SilkS")
		)
		(fp_line
			(start 1.2954 -0.5842)
			(end 1.2954 0.5842)
			(stroke
				(width 0.1524)
				(type default)
			)
			(layer "F.SilkS")
		)
		(fp_line
			(start -0.8636 0.4572)
			(end -0.8636 0.4318)
			(stroke
				(width 0.1)
				(type default)
			)
			(layer "F.Fab")
		)
		(fp_line
			(start 0.8636 0.4572)
			(end -0.8636 0.4572)
			(stroke
				(width 0.1)
				(type default)
			)
			(layer "F.Fab")
		)
		(fp_line
			(start -0.8636 0.4318)
			(end -0.8636 0.4064)
			(stroke
				(width 0.1)
				(type default)
			)
			(layer "F.Fab")
		)
		(fp_line
			(start -1.1938 0.4064)
			(end -1.1938 -0.406654)
			(stroke
				(width 0.1)
				(type default)
			)
			(layer "F.Fab")
		)
		(fp_line
			(start -0.8636 0.4064)
			(end -1.1938 0.4064)
			(stroke
				(width 0.1)
				(type default)
			)
			(layer "F.Fab")
		)
		(fp_line
			(start 0.8636 0.4064)
			(end 0.8636 0.4572)
			(stroke
				(width 0.1)
				(type default)
			)
			(layer "F.Fab")
		)
		(fp_line
			(start 1.1938 0.4064)
			(end 0.8636 0.4064)
			(stroke
				(width 0.1)
				(type default)
			)
			(layer "F.Fab")
		)
		(fp_line
			(start -1.1938 -0.406654)
			(end -0.8636 -0.406654)
			(stroke
				(width 0.1)
				(type default)
			)
			(layer "F.Fab")
		)
		(fp_line
			(start -0.8636 -0.406654)
			(end -0.8636 -0.4572)
			(stroke
				(width 0.1)
				(type default)
			)
			(layer "F.Fab")
		)
		(fp_line
			(start 0.8636 -0.406654)
			(end 1.1938 -0.406654)
			(stroke
				(width 0.1)
				(type default)
			)
			(layer "F.Fab")
		)
		(fp_line
			(start 1.1938 -0.406654)
			(end 1.1938 0.4064)
			(stroke
				(width 0.1)
				(type default)
			)
			(layer "F.Fab")
		)
		(fp_line
			(start -0.8636 -0.4572)
			(end 0.8636 -0.4572)
			(stroke
				(width 0.1)
				(type default)
			)
			(layer "F.Fab")
		)
		(fp_line
			(start 0.8636 -0.4572)
			(end 0.8636 -0.406654)
			(stroke
				(width 0.1)
				(type default)
			)
			(layer "F.Fab")
		)
		(pad "1" smd rect
			(at -0.7366 0 180)
			(size 0.7112 0.8128)
			(layers "F.Cu" "F.Mask" "F.Paste")
			(net "P12V_AUX")
		)
		(pad "2" smd rect
			(at 0.7366 0 180)
			(size 0.7112 0.8128)
			(layers "F.Cu" "F.Mask" "F.Paste")
			(net "P12V_E1S_AVIN_PD_0")
		)
	)
	(footprint ""
		(layer "F.Cu")
		(at 455.617834 -93.437964)
		(property "Reference" "R3231"
			(at 0 0 0)
			(layer "F.SilkS")
			(hide yes)
			(effects
				(font
					(size 1.27 1.27)
				)
			)
		)
		(property "Value" ""
			(at 0 0 0)
			(layer "F.Fab")
			(effects
				(font
					(size 1.27 1.27)
				)
			)
		)
		(duplicate_pad_numbers_are_jumpers no)
		(fp_line
			(start -0.7874 -0.4064)
			(end 0.7874 -0.4064)
			(stroke
				(width 0.1524)
				(type default)
			)
			(layer "F.SilkS")
		)
		(fp_line
			(start -0.7874 0.4064)
			(end -0.7874 -0.4064)
			(stroke
				(width 0.1524)
				(type default)
			)
			(layer "F.SilkS")
		)
		(fp_line
			(start 0.7874 -0.4064)
			(end 0.7874 0.4064)
			(stroke
				(width 0.1524)
				(type default)
			)
			(layer "F.SilkS")
		)
		(fp_line
			(start 0.7874 0.4064)
			(end -0.7874 0.4064)
			(stroke
				(width 0.1524)
				(type default)
			)
			(layer "F.SilkS")
		)
		(fp_line
			(start -0.67945 -0.305054)
			(end -0.12065 -0.305054)
			(stroke
				(width 0.1)
				(type default)
			)
			(layer "F.Fab")
		)
		(fp_line
			(start -0.67945 0.3048)
			(end -0.67945 -0.305054)
			(stroke
				(width 0.1)
				(type default)
			)
			(layer "F.Fab")
		)
		(fp_line
			(start -0.12065 -0.305054)
			(end -0.12065 -0.2794)
			(stroke
				(width 0.1)
				(type default)
			)
			(layer "F.Fab")
		)
		(fp_line
			(start -0.12065 -0.2794)
			(end 0.12065 -0.2794)
			(stroke
				(width 0.1)
				(type default)
			)
			(layer "F.Fab")
		)
		(fp_line
			(start -0.12065 0.2794)
			(end -0.12065 0.3048)
			(stroke
				(width 0.1)
				(type default)
			)
			(layer "F.Fab")
		)
		(fp_line
			(start -0.12065 0.3048)
			(end -0.67945 0.3048)
			(stroke
				(width 0.1)
				(type default)
			)
			(layer "F.Fab")
		)
		(fp_line
			(start 0.120396 0.2794)
			(end -0.12065 0.2794)
			(stroke
				(width 0.1)
				(type default)
			)
			(layer "F.Fab")
		)
		(fp_line
			(start 0.120396 0.3048)
			(end 0.120396 0.2794)
			(stroke
				(width 0.1)
				(type default)
			)
			(layer "F.Fab")
		)
		(fp_line
			(start 0.12065 -0.3048)
			(end 0.67945 -0.3048)
			(stroke
				(width 0.1)
				(type default)
			)
			(layer "F.Fab")
		)
		(fp_line
			(start 0.12065 -0.2794)
			(end 0.12065 -0.3048)
			(stroke
				(width 0.1)
				(type default)
			)
			(layer "F.Fab")
		)
		(fp_line
			(start 0.67945 -0.3048)
			(end 0.67945 0.3048)
			(stroke
				(width 0.1)
				(type default)
			)
			(layer "F.Fab")
		)
		(fp_line
			(start 0.67945 0.3048)
			(end 0.120396 0.3048)
			(stroke
				(width 0.1)
				(type default)
			)
			(layer "F.Fab")
		)
		(pad "1" smd circle
			(at -0.40005 0)
			(size 0 0)
			(layers "F.Cu" "F.Mask" "F.Paste")
			(net "OCP_SFF_AUX_PWR_EN")
		)
		(pad "2" smd circle
			(at 0.40005 0)
			(size 0 0)
			(layers "F.Cu" "F.Mask" "F.Paste")
			(net "OCP_SFF_AUX_PWR_EN_R4")
		)
	)
	(footprint ""
		(layer "F.Cu")
		(at 151.82977 -40.50792 180)
		(property "Reference" "R4463"
			(at 0 0 180)
			(layer "F.SilkS")
			(hide yes)
			(effects
				(font
					(size 1.27 1.27)
				)
			)
		)
		(property "Value" ""
			(at 0 0 180)
			(layer "F.Fab")
			(effects
				(font
					(size 1.27 1.27)
				)
			)
		)
		(duplicate_pad_numbers_are_jumpers no)
		(fp_line
			(start 0.7874 0.4064)
			(end -0.7874 0.4064)
			(stroke
				(width 0.1524)
				(type default)
			)
			(layer "F.SilkS")
		)
		(fp_line
			(start 0.7874 -0.4064)
			(end 0.7874 0.4064)
			(stroke
				(width 0.1524)
				(type default)
			)
			(layer "F.SilkS")
		)
		(fp_line
			(start -0.7874 0.4064)
			(end -0.7874 -0.4064)
			(stroke
				(width 0.1524)
				(type default)
			)
			(layer "F.SilkS")
		)
		(fp_line
			(start -0.7874 -0.4064)
			(end 0.7874 -0.4064)
			(stroke
				(width 0.1524)
				(type default)
			)
			(layer "F.SilkS")
		)
		(fp_line
			(start 0.67945 0.3048)
			(end 0.120396 0.3048)
			(stroke
				(width 0.1)
				(type default)
			)
			(layer "F.Fab")
		)
		(fp_line
			(start 0.67945 -0.3048)
			(end 0.67945 0.3048)
			(stroke
				(width 0.1)
				(type default)
			)
			(layer "F.Fab")
		)
		(fp_line
			(start 0.12065 -0.2794)
			(end 0.12065 -0.3048)
			(stroke
				(width 0.1)
				(type default)
			)
			(layer "F.Fab")
		)
		(fp_line
			(start 0.12065 -0.3048)
			(end 0.67945 -0.3048)
			(stroke
				(width 0.1)
				(type default)
			)
			(layer "F.Fab")
		)
		(fp_line
			(start 0.120396 0.3048)
			(end 0.120396 0.2794)
			(stroke
				(width 0.1)
				(type default)
			)
			(layer "F.Fab")
		)
		(fp_line
			(start 0.120396 0.2794)
			(end -0.12065 0.2794)
			(stroke
				(width 0.1)
				(type default)
			)
			(layer "F.Fab")
		)
		(fp_line
			(start -0.12065 0.3048)
			(end -0.67945 0.3048)
			(stroke
				(width 0.1)
				(type default)
			)
			(layer "F.Fab")
		)
		(fp_line
			(start -0.12065 0.2794)
			(end -0.12065 0.3048)
			(stroke
				(width 0.1)
				(type default)
			)
			(layer "F.Fab")
		)
		(fp_line
			(start -0.12065 -0.2794)
			(end 0.12065 -0.2794)
			(stroke
				(width 0.1)
				(type default)
			)
			(layer "F.Fab")
		)
		(fp_line
			(start -0.12065 -0.305054)
			(end -0.12065 -0.2794)
			(stroke
				(width 0.1)
				(type default)
			)
			(layer "F.Fab")
		)
		(fp_line
			(start -0.67945 0.3048)
			(end -0.67945 -0.305054)
			(stroke
				(width 0.1)
				(type default)
			)
			(layer "F.Fab")
		)
		(fp_line
			(start -0.67945 -0.305054)
			(end -0.12065 -0.305054)
			(stroke
				(width 0.1)
				(type default)
			)
			(layer "F.Fab")
		)
		(pad "1" smd circle
			(at -0.40005 0 180)
			(size 0 0)
			(layers "F.Cu" "F.Mask" "F.Paste")
			(net "USB_HUB_2_RREF")
		)
		(pad "2" smd circle
			(at 0.40005 0 180)
			(size 0 0)
			(layers "F.Cu" "F.Mask" "F.Paste")
			(net "GND")
		)
	)
	(footprint ""
		(layer "F.Cu")
		(at 144.61236 -92.634308 -90)
		(property "Reference" "R4051"
			(at 0 0 270)
			(layer "F.SilkS")
			(hide yes)
			(effects
				(font
					(size 1.27 1.27)
				)
			)
		)
		(property "Value" ""
			(at 0 0 270)
			(layer "F.Fab")
			(effects
				(font
					(size 1.27 1.27)
				)
			)
		)
		(duplicate_pad_numbers_are_jumpers no)
		(fp_line
			(start -0.7874 0.4064)
			(end -0.7874 -0.4064)
			(stroke
				(width 0.1524)
				(type default)
			)
			(layer "F.SilkS")
		)
		(fp_line
			(start 0.7874 0.4064)
			(end -0.7874 0.4064)
			(stroke
				(width 0.1524)
				(type default)
			)
			(layer "F.SilkS")
		)
		(fp_line
			(start -0.7874 -0.4064)
			(end 0.7874 -0.4064)
			(stroke
				(width 0.1524)
				(type default)
			)
			(layer "F.SilkS")
		)
		(fp_line
			(start 0.7874 -0.4064)
			(end 0.7874 0.4064)
			(stroke
				(width 0.1524)
				(type default)
			)
			(layer "F.SilkS")
		)
		(fp_line
			(start -0.67945 0.3048)
			(end -0.67945 -0.305054)
			(stroke
				(width 0.1)
				(type default)
			)
			(layer "F.Fab")
		)
		(fp_line
			(start -0.12065 0.3048)
			(end -0.67945 0.3048)
			(stroke
				(width 0.1)
				(type default)
			)
			(layer "F.Fab")
		)
		(fp_line
			(start 0.120396 0.3048)
			(end 0.120396 0.2794)
			(stroke
				(width 0.1)
				(type default)
			)
			(layer "F.Fab")
		)
		(fp_line
			(start 0.67945 0.3048)
			(end 0.120396 0.3048)
			(stroke
				(width 0.1)
				(type default)
			)
			(layer "F.Fab")
		)
		(fp_line
			(start -0.12065 0.2794)
			(end -0.12065 0.3048)
			(stroke
				(width 0.1)
				(type default)
			)
			(layer "F.Fab")
		)
		(fp_line
			(start 0.120396 0.2794)
			(end -0.12065 0.2794)
			(stroke
				(width 0.1)
				(type default)
			)
			(layer "F.Fab")
		)
		(fp_line
			(start -0.12065 -0.2794)
			(end 0.12065 -0.2794)
			(stroke
				(width 0.1)
				(type default)
			)
			(layer "F.Fab")
		)
		(fp_line
			(start 0.12065 -0.2794)
			(end 0.12065 -0.3048)
			(stroke
				(width 0.1)
				(type default)
			)
			(layer "F.Fab")
		)
		(fp_line
			(start 0.12065 -0.3048)
			(end 0.67945 -0.3048)
			(stroke
				(width 0.1)
				(type default)
			)
			(layer "F.Fab")
		)
		(fp_line
			(start 0.67945 -0.3048)
			(end 0.67945 0.3048)
			(stroke
				(width 0.1)
				(type default)
			)
			(layer "F.Fab")
		)
		(fp_line
			(start -0.67945 -0.305054)
			(end -0.12065 -0.305054)
			(stroke
				(width 0.1)
				(type default)
			)
			(layer "F.Fab")
		)
		(fp_line
			(start -0.12065 -0.305054)
			(end -0.12065 -0.2794)
			(stroke
				(width 0.1)
				(type default)
			)
			(layer "F.Fab")
		)
		(pad "1" smd circle
			(at -0.40005 0 270)
			(size 0 0)
			(layers "F.Cu" "F.Mask" "F.Paste")
			(net "H_CPU_ERR1_LVC2_R_N")
		)
		(pad "2" smd circle
			(at 0.40005 0 270)
			(size 0 0)
			(layers "F.Cu" "F.Mask" "F.Paste")
			(net "H_CPU_ERR1_LVC2_N")
		)
	)
	(footprint ""
		(layer "F.Cu")
		(at 259.710936 -38.738556 90)
		(property "Reference" "PD114"
			(at 4.87172 -1.177036 0)
			(unlocked yes)
			(layer "F.SilkS")
			(effects
				(font
					(size 0.7874 0.5842)
					(thickness 0.1524)
				)
				(justify left)
			)
		)
		(property "Value" ""
			(at 0 0 90)
			(layer "F.Fab")
			(effects
				(font
					(size 1.27 1.27)
				)
			)
		)
		(duplicate_pad_numbers_are_jumpers no)
		(fp_line
			(start 2.631186 -0.999998)
			(end -2.250186 -0.999998)
			(stroke
				(width 0.1524)
				(type default)
			)
			(layer "F.SilkS")
		)
		(fp_line
			(start -2.250186 -0.999998)
			(end -2.250186 0.999998)
			(stroke
				(width 0.1524)
				(type default)
			)
			(layer "F.SilkS")
		)
		(fp_line
			(start 0.381 -0.4318)
			(end 0.381 0.3302)
			(stroke
				(width 0.1524)
				(type default)
			)
			(layer "F.SilkS")
		)
		(fp_line
			(start -0.381 -0.4318)
			(end 0.381 -0.0508)
			(stroke
				(width 0.1524)
				(type default)
			)
			(layer "F.SilkS")
		)
		(fp_line
			(start 0.381 -0.0508)
			(end 0.635 -0.0508)
			(stroke
				(width 0.1524)
				(type default)
			)
			(layer "F.SilkS")
		)
		(fp_line
			(start 0.381 -0.0508)
			(end -0.381 0.3302)
			(stroke
				(width 0.1524)
				(type default)
			)
			(layer "F.SilkS")
		)
		(fp_line
			(start -0.381 -0.0508)
			(end -0.6604 -0.0508)
			(stroke
				(width 0.1524)
				(type default)
			)
			(layer "F.SilkS")
		)
		(fp_line
			(start -0.381 0.3302)
			(end -0.381 -0.4318)
			(stroke
				(width 0.1524)
				(type default)
			)
			(layer "F.SilkS")
		)
		(fp_line
			(start 2.631186 0.999998)
			(end 2.631186 -0.999998)
			(stroke
				(width 0.1524)
				(type default)
			)
			(layer "F.SilkS")
		)
		(fp_line
			(start -2.250186 0.999998)
			(end 2.631186 0.999998)
			(stroke
				(width 0.1524)
				(type default)
			)
			(layer "F.SilkS")
		)
		(fp_rect
			(start 2.1844 -0.9652)
			(end 2.6162 1.016)
			(stroke
				(width 0)
				(type default)
			)
			(fill yes)
			(layer "F.SilkS")
		)
		(fp_line
			(start 1.450086 -0.999998)
			(end -1.450086 -0.999998)
			(stroke
				(width 0.1)
				(type default)
			)
			(layer "F.Fab")
		)
		(fp_line
			(start -1.450086 -0.999998)
			(end -1.450086 0.999998)
			(stroke
				(width 0.1)
				(type default)
			)
			(layer "F.Fab")
		)
		(fp_line
			(start 1.450086 0.999998)
			(end 1.450086 -0.999998)
			(stroke
				(width 0.1)
				(type default)
			)
			(layer "F.Fab")
		)
		(fp_line
			(start -1.450086 0.999998)
			(end 1.450086 0.999998)
			(stroke
				(width 0.1)
				(type default)
			)
			(layer "F.Fab")
		)
		(fp_text user "-"
			(at 2.4384 -0.22225 90)
			(unlocked yes)
			(layer "F.SilkS")
			(effects
				(font
					(size 1.905 1.4224)
					(thickness 0.1524)
				)
				(justify left)
			)
		)
		(fp_text user "+"
			(at -3.83921 1.491234 90)
			(unlocked yes)
			(layer "F.SilkS")
			(effects
				(font
					(size 1.905 1.4224)
					(thickness 0.1524)
				)
				(justify left)
			)
		)
		(fp_text user "-"
			(at 2.4384 -0.22225 90)
			(unlocked yes)
			(layer "F.Fab")
			(effects
				(font
					(size 1.905 1.4224)
					(thickness 0.1524)
				)
				(justify left)
			)
		)
		(fp_text user "+"
			(at -3.4798 -0.22225 90)
			(unlocked yes)
			(layer "F.Fab")
			(effects
				(font
					(size 1.905 1.4224)
					(thickness 0.1524)
				)
				(justify left)
			)
		)
		(pad "A" smd rect
			(at -1.450086 0 90)
			(size 1.3208 1.4224)
			(layers "F.Cu" "F.Mask" "F.Paste")
			(net "GND")
		)
		(pad "C" smd rect
			(at 1.450086 0 90)
			(size 1.3208 1.4224)
			(layers "F.Cu" "F.Mask" "F.Paste")
			(net "P12V_AUX")
		)
	)
	(footprint ""
		(layer "F.Cu")
		(at 19.19859 -385.865624 90)
		(property "Reference" "R4659"
			(at 0 0 90)
			(layer "F.SilkS")
			(hide yes)
			(effects
				(font
					(size 1.27 1.27)
				)
			)
		)
		(property "Value" ""
			(at 0 0 90)
			(layer "F.Fab")
			(effects
				(font
					(size 1.27 1.27)
				)
			)
		)
		(duplicate_pad_numbers_are_jumpers no)
		(fp_line
			(start -0.7874 -0.4064)
			(end 0.7874 -0.4064)
			(stroke
				(width 0.1524)
				(type default)
			)
			(layer "F.SilkS")
		)
		(fp_line
			(start 0.7874 0.4064)
			(end -0.001524 0.4064)
			(stroke
				(width 0.1524)
				(type default)
			)
			(layer "F.SilkS")
		)
		(fp_line
			(start -0.7874 0.4064)
			(end -0.7874 -0.4064)
			(stroke
				(width 0.1524)
				(type default)
			)
			(layer "F.SilkS")
		)
		(fp_line
			(start -0.12065 -0.305054)
			(end -0.12065 -0.2794)
			(stroke
				(width 0.1)
				(type default)
			)
			(layer "F.Fab")
		)
		(fp_line
			(start -0.67945 -0.305054)
			(end -0.12065 -0.305054)
			(stroke
				(width 0.1)
				(type default)
			)
			(layer "F.Fab")
		)
		(fp_line
			(start 0.67945 -0.3048)
			(end 0.67945 0.3048)
			(stroke
				(width 0.1)
				(type default)
			)
			(layer "F.Fab")
		)
		(fp_line
			(start 0.12065 -0.3048)
			(end 0.67945 -0.3048)
			(stroke
				(width 0.1)
				(type default)
			)
			(layer "F.Fab")
		)
		(fp_line
			(start 0.12065 -0.2794)
			(end 0.12065 -0.3048)
			(stroke
				(width 0.1)
				(type default)
			)
			(layer "F.Fab")
		)
		(fp_line
			(start -0.12065 -0.2794)
			(end 0.12065 -0.2794)
			(stroke
				(width 0.1)
				(type default)
			)
			(layer "F.Fab")
		)
		(fp_line
			(start 0.120396 0.2794)
			(end -0.12065 0.2794)
			(stroke
				(width 0.1)
				(type default)
			)
			(layer "F.Fab")
		)
		(fp_line
			(start -0.12065 0.2794)
			(end -0.12065 0.3048)
			(stroke
				(width 0.1)
				(type default)
			)
			(layer "F.Fab")
		)
		(fp_line
			(start 0.67945 0.3048)
			(end 0.120396 0.3048)
			(stroke
				(width 0.1)
				(type default)
			)
			(layer "F.Fab")
		)
		(fp_line
			(start 0.120396 0.3048)
			(end 0.120396 0.2794)
			(stroke
				(width 0.1)
				(type default)
			)
			(layer "F.Fab")
		)
		(fp_line
			(start -0.12065 0.3048)
			(end -0.67945 0.3048)
			(stroke
				(width 0.1)
				(type default)
			)
			(layer "F.Fab")
		)
		(fp_line
			(start -0.67945 0.3048)
			(end -0.67945 -0.305054)
			(stroke
				(width 0.1)
				(type default)
			)
			(layer "F.Fab")
		)
		(pad "1" smd rect
			(at -0.40005 0 270)
			(size 0.4572 0.508)
			(layers "F.Cu" "F.Mask" "F.Paste")
			(net "P2E_MB_BMC_TX_C_DP<0>")
		)
		(pad "2" smd rect
			(at 0.40005 0 270)
			(size 0.4572 0.508)
			(layers "F.Cu" "F.Mask" "F.Paste")
			(net "P2E_MB_BMC_TX_C_R1_DP<0>")
		)
	)
	(footprint ""
		(layer "F.Cu")
		(at 307.14188 -50.878486 180)
		(property "Reference" "R1338"
			(at 0 0 180)
			(layer "F.SilkS")
			(hide yes)
			(effects
				(font
					(size 1.27 1.27)
				)
			)
		)
		(property "Value" ""
			(at 0 0 180)
			(layer "F.Fab")
			(effects
				(font
					(size 1.27 1.27)
				)
			)
		)
		(duplicate_pad_numbers_are_jumpers no)
		(fp_line
			(start 0.7874 0.4064)
			(end -0.7874 0.4064)
			(stroke
				(width 0.1524)
				(type default)
			)
			(layer "F.SilkS")
		)
		(fp_line
			(start 0.7874 -0.4064)
			(end 0.7874 0.4064)
			(stroke
				(width 0.1524)
				(type default)
			)
			(layer "F.SilkS")
		)
		(fp_line
			(start -0.7874 0.4064)
			(end -0.7874 -0.4064)
			(stroke
				(width 0.1524)
				(type default)
			)
			(layer "F.SilkS")
		)
		(fp_line
			(start -0.7874 -0.4064)
			(end 0.7874 -0.4064)
			(stroke
				(width 0.1524)
				(type default)
			)
			(layer "F.SilkS")
		)
		(fp_line
			(start 0.67945 0.3048)
			(end 0.120396 0.3048)
			(stroke
				(width 0.1)
				(type default)
			)
			(layer "F.Fab")
		)
		(fp_line
			(start 0.67945 -0.3048)
			(end 0.67945 0.3048)
			(stroke
				(width 0.1)
				(type default)
			)
			(layer "F.Fab")
		)
		(fp_line
			(start 0.12065 -0.2794)
			(end 0.12065 -0.3048)
			(stroke
				(width 0.1)
				(type default)
			)
			(layer "F.Fab")
		)
		(fp_line
			(start 0.12065 -0.3048)
			(end 0.67945 -0.3048)
			(stroke
				(width 0.1)
				(type default)
			)
			(layer "F.Fab")
		)
		(fp_line
			(start 0.120396 0.3048)
			(end 0.120396 0.2794)
			(stroke
				(width 0.1)
				(type default)
			)
			(layer "F.Fab")
		)
		(fp_line
			(start 0.120396 0.2794)
			(end -0.12065 0.2794)
			(stroke
				(width 0.1)
				(type default)
			)
			(layer "F.Fab")
		)
		(fp_line
			(start -0.12065 0.3048)
			(end -0.67945 0.3048)
			(stroke
				(width 0.1)
				(type default)
			)
			(layer "F.Fab")
		)
		(fp_line
			(start -0.12065 0.2794)
			(end -0.12065 0.3048)
			(stroke
				(width 0.1)
				(type default)
			)
			(layer "F.Fab")
		)
		(fp_line
			(start -0.12065 -0.2794)
			(end 0.12065 -0.2794)
			(stroke
				(width 0.1)
				(type default)
			)
			(layer "F.Fab")
		)
		(fp_line
			(start -0.12065 -0.305054)
			(end -0.12065 -0.2794)
			(stroke
				(width 0.1)
				(type default)
			)
			(layer "F.Fab")
		)
		(fp_line
			(start -0.67945 0.3048)
			(end -0.67945 -0.305054)
			(stroke
				(width 0.1)
				(type default)
			)
			(layer "F.Fab")
		)
		(fp_line
			(start -0.67945 -0.305054)
			(end -0.12065 -0.305054)
			(stroke
				(width 0.1)
				(type default)
			)
			(layer "F.Fab")
		)
		(pad "1" smd circle
			(at -0.40005 0 180)
			(size 0 0)
			(layers "F.Cu" "F.Mask" "F.Paste")
			(net "FM_PCH_BIOS_RCVR_MODE")
		)
		(pad "2" smd circle
			(at 0.40005 0 180)
			(size 0 0)
			(layers "F.Cu" "F.Mask" "F.Paste")
			(net "GND")
		)
	)
	(footprint ""
		(layer "F.Cu")
		(at 304.09896 -433.04587 90)
		(property "Reference" "R4140"
			(at 0 0 90)
			(layer "F.SilkS")
			(hide yes)
			(effects
				(font
					(size 1.27 1.27)
				)
			)
		)
		(property "Value" ""
			(at 0 0 90)
			(layer "F.Fab")
			(effects
				(font
					(size 1.27 1.27)
				)
			)
		)
		(duplicate_pad_numbers_are_jumpers no)
		(fp_line
			(start 0.7874 -0.4064)
			(end 0.7874 0.4064)
			(stroke
				(width 0.1524)
				(type default)
			)
			(layer "F.SilkS")
		)
		(fp_line
			(start -0.7874 -0.4064)
			(end 0.7874 -0.4064)
			(stroke
				(width 0.1524)
				(type default)
			)
			(layer "F.SilkS")
		)
		(fp_line
			(start 0.7874 0.4064)
			(end -0.7874 0.4064)
			(stroke
				(width 0.1524)
				(type default)
			)
			(layer "F.SilkS")
		)
		(fp_line
			(start -0.7874 0.4064)
			(end -0.7874 -0.4064)
			(stroke
				(width 0.1524)
				(type default)
			)
			(layer "F.SilkS")
		)
		(fp_line
			(start -0.12065 -0.305054)
			(end -0.12065 -0.2794)
			(stroke
				(width 0.1)
				(type default)
			)
			(layer "F.Fab")
		)
		(fp_line
			(start -0.67945 -0.305054)
			(end -0.12065 -0.305054)
			(stroke
				(width 0.1)
				(type default)
			)
			(layer "F.Fab")
		)
		(fp_line
			(start 0.67945 -0.3048)
			(end 0.67945 0.3048)
			(stroke
				(width 0.1)
				(type default)
			)
			(layer "F.Fab")
		)
		(fp_line
			(start 0.12065 -0.3048)
			(end 0.67945 -0.3048)
			(stroke
				(width 0.1)
				(type default)
			)
			(layer "F.Fab")
		)
		(fp_line
			(start 0.12065 -0.2794)
			(end 0.12065 -0.3048)
			(stroke
				(width 0.1)
				(type default)
			)
			(layer "F.Fab")
		)
		(fp_line
			(start -0.12065 -0.2794)
			(end 0.12065 -0.2794)
			(stroke
				(width 0.1)
				(type default)
			)
			(layer "F.Fab")
		)
		(fp_line
			(start 0.120396 0.2794)
			(end -0.12065 0.2794)
			(stroke
				(width 0.1)
				(type default)
			)
			(layer "F.Fab")
		)
		(fp_line
			(start -0.12065 0.2794)
			(end -0.12065 0.3048)
			(stroke
				(width 0.1)
				(type default)
			)
			(layer "F.Fab")
		)
		(fp_line
			(start 0.67945 0.3048)
			(end 0.120396 0.3048)
			(stroke
				(width 0.1)
				(type default)
			)
			(layer "F.Fab")
		)
		(fp_line
			(start 0.120396 0.3048)
			(end 0.120396 0.2794)
			(stroke
				(width 0.1)
				(type default)
			)
			(layer "F.Fab")
		)
		(fp_line
			(start -0.12065 0.3048)
			(end -0.67945 0.3048)
			(stroke
				(width 0.1)
				(type default)
			)
			(layer "F.Fab")
		)
		(fp_line
			(start -0.67945 0.3048)
			(end -0.67945 -0.305054)
			(stroke
				(width 0.1)
				(type default)
			)
			(layer "F.Fab")
		)
		(pad "1" smd circle
			(at -0.40005 0 90)
			(size 0 0)
			(layers "F.Cu" "F.Mask" "F.Paste")
			(net "P3V3_AUX")
		)
		(pad "2" smd circle
			(at 0.40005 0 90)
			(size 0 0)
			(layers "F.Cu" "F.Mask" "F.Paste")
			(net "GPU_3V3IO_RSVD3_FFU_ISO")
		)
	)
	(footprint ""
		(layer "F.Cu")
		(at 179.09032 -408.203908)
		(property "Reference" "R4531"
			(at 0 0 0)
			(layer "F.SilkS")
			(hide yes)
			(effects
				(font
					(size 1.27 1.27)
				)
			)
		)
		(property "Value" ""
			(at 0 0 0)
			(layer "F.Fab")
			(effects
				(font
					(size 1.27 1.27)
				)
			)
		)
		(duplicate_pad_numbers_are_jumpers no)
		(fp_line
			(start -0.7874 -0.4064)
			(end 0.7874 -0.4064)
			(stroke
				(width 0.1524)
				(type default)
			)
			(layer "F.SilkS")
		)
		(fp_line
			(start -0.7874 0.4064)
			(end -0.7874 -0.4064)
			(stroke
				(width 0.1524)
				(type default)
			)
			(layer "F.SilkS")
		)
		(fp_line
			(start 0.7874 -0.4064)
			(end 0.7874 0.4064)
			(stroke
				(width 0.1524)
				(type default)
			)
			(layer "F.SilkS")
		)
		(fp_line
			(start 0.7874 0.4064)
			(end -0.7874 0.4064)
			(stroke
				(width 0.1524)
				(type default)
			)
			(layer "F.SilkS")
		)
		(fp_line
			(start -0.67945 -0.305054)
			(end -0.12065 -0.305054)
			(stroke
				(width 0.1)
				(type default)
			)
			(layer "F.Fab")
		)
		(fp_line
			(start -0.67945 0.3048)
			(end -0.67945 -0.305054)
			(stroke
				(width 0.1)
				(type default)
			)
			(layer "F.Fab")
		)
		(fp_line
			(start -0.12065 -0.305054)
			(end -0.12065 -0.2794)
			(stroke
				(width 0.1)
				(type default)
			)
			(layer "F.Fab")
		)
		(fp_line
			(start -0.12065 -0.2794)
			(end 0.12065 -0.2794)
			(stroke
				(width 0.1)
				(type default)
			)
			(layer "F.Fab")
		)
		(fp_line
			(start -0.12065 0.2794)
			(end -0.12065 0.3048)
			(stroke
				(width 0.1)
				(type default)
			)
			(layer "F.Fab")
		)
		(fp_line
			(start -0.12065 0.3048)
			(end -0.67945 0.3048)
			(stroke
				(width 0.1)
				(type default)
			)
			(layer "F.Fab")
		)
		(fp_line
			(start 0.120396 0.2794)
			(end -0.12065 0.2794)
			(stroke
				(width 0.1)
				(type default)
			)
			(layer "F.Fab")
		)
		(fp_line
			(start 0.120396 0.3048)
			(end 0.120396 0.2794)
			(stroke
				(width 0.1)
				(type default)
			)
			(layer "F.Fab")
		)
		(fp_line
			(start 0.12065 -0.3048)
			(end 0.67945 -0.3048)
			(stroke
				(width 0.1)
				(type default)
			)
			(layer "F.Fab")
		)
		(fp_line
			(start 0.12065 -0.2794)
			(end 0.12065 -0.3048)
			(stroke
				(width 0.1)
				(type default)
			)
			(layer "F.Fab")
		)
		(fp_line
			(start 0.67945 -0.3048)
			(end 0.67945 0.3048)
			(stroke
				(width 0.1)
				(type default)
			)
			(layer "F.Fab")
		)
		(fp_line
			(start 0.67945 0.3048)
			(end 0.120396 0.3048)
			(stroke
				(width 0.1)
				(type default)
			)
			(layer "F.Fab")
		)
		(pad "1" smd circle
			(at -0.40005 0)
			(size 0 0)
			(layers "F.Cu" "F.Mask" "F.Paste")
			(net "SMB_SML1_PMBUS_HSC_SDA_R3")
		)
		(pad "2" smd circle
			(at 0.40005 0)
			(size 0 0)
			(layers "F.Cu" "F.Mask" "F.Paste")
			(net "SMB_SML1_PMBUS_HSC_SDA")
		)
	)
	(footprint ""
		(layer "F.Cu")
		(at 164.64788 -109.565948)
		(property "Reference" "R1606"
			(at 0 0 0)
			(layer "F.SilkS")
			(hide yes)
			(effects
				(font
					(size 1.27 1.27)
				)
			)
		)
		(property "Value" ""
			(at 0 0 0)
			(layer "F.Fab")
			(effects
				(font
					(size 1.27 1.27)
				)
			)
		)
		(duplicate_pad_numbers_are_jumpers no)
		(fp_line
			(start -0.7874 -0.4064)
			(end 0.7874 -0.4064)
			(stroke
				(width 0.1524)
				(type default)
			)
			(layer "F.SilkS")
		)
		(fp_line
			(start -0.7874 0.4064)
			(end -0.7874 -0.4064)
			(stroke
				(width 0.1524)
				(type default)
			)
			(layer "F.SilkS")
		)
		(fp_line
			(start 0.7874 -0.4064)
			(end 0.7874 0.4064)
			(stroke
				(width 0.1524)
				(type default)
			)
			(layer "F.SilkS")
		)
		(fp_line
			(start 0.7874 0.4064)
			(end -0.7874 0.4064)
			(stroke
				(width 0.1524)
				(type default)
			)
			(layer "F.SilkS")
		)
		(fp_line
			(start -0.67945 -0.305054)
			(end -0.12065 -0.305054)
			(stroke
				(width 0.1)
				(type default)
			)
			(layer "F.Fab")
		)
		(fp_line
			(start -0.67945 0.3048)
			(end -0.67945 -0.305054)
			(stroke
				(width 0.1)
				(type default)
			)
			(layer "F.Fab")
		)
		(fp_line
			(start -0.12065 -0.305054)
			(end -0.12065 -0.2794)
			(stroke
				(width 0.1)
				(type default)
			)
			(layer "F.Fab")
		)
		(fp_line
			(start -0.12065 -0.2794)
			(end 0.12065 -0.2794)
			(stroke
				(width 0.1)
				(type default)
			)
			(layer "F.Fab")
		)
		(fp_line
			(start -0.12065 0.2794)
			(end -0.12065 0.3048)
			(stroke
				(width 0.1)
				(type default)
			)
			(layer "F.Fab")
		)
		(fp_line
			(start -0.12065 0.3048)
			(end -0.67945 0.3048)
			(stroke
				(width 0.1)
				(type default)
			)
			(layer "F.Fab")
		)
		(fp_line
			(start 0.120396 0.2794)
			(end -0.12065 0.2794)
			(stroke
				(width 0.1)
				(type default)
			)
			(layer "F.Fab")
		)
		(fp_line
			(start 0.120396 0.3048)
			(end 0.120396 0.2794)
			(stroke
				(width 0.1)
				(type default)
			)
			(layer "F.Fab")
		)
		(fp_line
			(start 0.12065 -0.3048)
			(end 0.67945 -0.3048)
			(stroke
				(width 0.1)
				(type default)
			)
			(layer "F.Fab")
		)
		(fp_line
			(start 0.12065 -0.2794)
			(end 0.12065 -0.3048)
			(stroke
				(width 0.1)
				(type default)
			)
			(layer "F.Fab")
		)
		(fp_line
			(start 0.67945 -0.3048)
			(end 0.67945 0.3048)
			(stroke
				(width 0.1)
				(type default)
			)
			(layer "F.Fab")
		)
		(fp_line
			(start 0.67945 0.3048)
			(end 0.120396 0.3048)
			(stroke
				(width 0.1)
				(type default)
			)
			(layer "F.Fab")
		)
		(pad "1" smd circle
			(at -0.40005 0)
			(size 0 0)
			(layers "F.Cu" "F.Mask" "F.Paste")
			(net "FM_OCP_SFF_PWR_GOOD")
		)
		(pad "2" smd circle
			(at 0.40005 0)
			(size 0 0)
			(layers "F.Cu" "F.Mask" "F.Paste")
			(net "FM_OCP_SFF_PWR_GOOD_R")
		)
	)
	(footprint ""
		(layer "F.Cu")
		(at 431.989992 -386.171948 180)
		(property "Reference" "R2841"
			(at 0 0 180)
			(layer "F.SilkS")
			(hide yes)
			(effects
				(font
					(size 1.27 1.27)
				)
			)
		)
		(property "Value" ""
			(at 0 0 180)
			(layer "F.Fab")
			(effects
				(font
					(size 1.27 1.27)
				)
			)
		)
		(duplicate_pad_numbers_are_jumpers no)
		(fp_line
			(start 0.7874 0.4064)
			(end -0.7874 0.4064)
			(stroke
				(width 0.1524)
				(type default)
			)
			(layer "F.SilkS")
		)
		(fp_line
			(start 0.7874 -0.4064)
			(end 0.7874 0.4064)
			(stroke
				(width 0.1524)
				(type default)
			)
			(layer "F.SilkS")
		)
		(fp_line
			(start -0.7874 0.4064)
			(end -0.7874 -0.4064)
			(stroke
				(width 0.1524)
				(type default)
			)
			(layer "F.SilkS")
		)
		(fp_line
			(start -0.7874 -0.4064)
			(end 0.7874 -0.4064)
			(stroke
				(width 0.1524)
				(type default)
			)
			(layer "F.SilkS")
		)
		(fp_line
			(start 0.67945 0.3048)
			(end 0.120396 0.3048)
			(stroke
				(width 0.1)
				(type default)
			)
			(layer "F.Fab")
		)
		(fp_line
			(start 0.67945 -0.3048)
			(end 0.67945 0.3048)
			(stroke
				(width 0.1)
				(type default)
			)
			(layer "F.Fab")
		)
		(fp_line
			(start 0.12065 -0.2794)
			(end 0.12065 -0.3048)
			(stroke
				(width 0.1)
				(type default)
			)
			(layer "F.Fab")
		)
		(fp_line
			(start 0.12065 -0.3048)
			(end 0.67945 -0.3048)
			(stroke
				(width 0.1)
				(type default)
			)
			(layer "F.Fab")
		)
		(fp_line
			(start 0.120396 0.3048)
			(end 0.120396 0.2794)
			(stroke
				(width 0.1)
				(type default)
			)
			(layer "F.Fab")
		)
		(fp_line
			(start 0.120396 0.2794)
			(end -0.12065 0.2794)
			(stroke
				(width 0.1)
				(type default)
			)
			(layer "F.Fab")
		)
		(fp_line
			(start -0.12065 0.3048)
			(end -0.67945 0.3048)
			(stroke
				(width 0.1)
				(type default)
			)
			(layer "F.Fab")
		)
		(fp_line
			(start -0.12065 0.2794)
			(end -0.12065 0.3048)
			(stroke
				(width 0.1)
				(type default)
			)
			(layer "F.Fab")
		)
		(fp_line
			(start -0.12065 -0.2794)
			(end 0.12065 -0.2794)
			(stroke
				(width 0.1)
				(type default)
			)
			(layer "F.Fab")
		)
		(fp_line
			(start -0.12065 -0.305054)
			(end -0.12065 -0.2794)
			(stroke
				(width 0.1)
				(type default)
			)
			(layer "F.Fab")
		)
		(fp_line
			(start -0.67945 0.3048)
			(end -0.67945 -0.305054)
			(stroke
				(width 0.1)
				(type default)
			)
			(layer "F.Fab")
		)
		(fp_line
			(start -0.67945 -0.305054)
			(end -0.12065 -0.305054)
			(stroke
				(width 0.1)
				(type default)
			)
			(layer "F.Fab")
		)
		(pad "1" smd circle
			(at -0.40005 0 180)
			(size 0 0)
			(layers "F.Cu" "F.Mask" "F.Paste")
			(net "P3V3_AUX")
		)
		(pad "2" smd circle
			(at 0.40005 0 180)
			(size 0 0)
			(layers "F.Cu" "F.Mask" "F.Paste")
			(net "FM_SWB_PWRGD_N")
		)
	)
	(footprint ""
		(layer "F.Cu")
		(at 36.14928 -433.923948 180)
		(property "Reference" "R3226"
			(at 0 0 180)
			(layer "F.SilkS")
			(hide yes)
			(effects
				(font
					(size 1.27 1.27)
				)
			)
		)
		(property "Value" ""
			(at 0 0 180)
			(layer "F.Fab")
			(effects
				(font
					(size 1.27 1.27)
				)
			)
		)
		(duplicate_pad_numbers_are_jumpers no)
		(fp_line
			(start 0.7874 0.4064)
			(end -0.7874 0.4064)
			(stroke
				(width 0.1524)
				(type default)
			)
			(layer "F.SilkS")
		)
		(fp_line
			(start 0.7874 -0.4064)
			(end 0.7874 0.4064)
			(stroke
				(width 0.1524)
				(type default)
			)
			(layer "F.SilkS")
		)
		(fp_line
			(start -0.7874 0.4064)
			(end -0.7874 -0.4064)
			(stroke
				(width 0.1524)
				(type default)
			)
			(layer "F.SilkS")
		)
		(fp_line
			(start -0.7874 -0.4064)
			(end 0.7874 -0.4064)
			(stroke
				(width 0.1524)
				(type default)
			)
			(layer "F.SilkS")
		)
		(fp_line
			(start 0.67945 0.3048)
			(end 0.120396 0.3048)
			(stroke
				(width 0.1)
				(type default)
			)
			(layer "F.Fab")
		)
		(fp_line
			(start 0.67945 -0.3048)
			(end 0.67945 0.3048)
			(stroke
				(width 0.1)
				(type default)
			)
			(layer "F.Fab")
		)
		(fp_line
			(start 0.12065 -0.2794)
			(end 0.12065 -0.3048)
			(stroke
				(width 0.1)
				(type default)
			)
			(layer "F.Fab")
		)
		(fp_line
			(start 0.12065 -0.3048)
			(end 0.67945 -0.3048)
			(stroke
				(width 0.1)
				(type default)
			)
			(layer "F.Fab")
		)
		(fp_line
			(start 0.120396 0.3048)
			(end 0.120396 0.2794)
			(stroke
				(width 0.1)
				(type default)
			)
			(layer "F.Fab")
		)
		(fp_line
			(start 0.120396 0.2794)
			(end -0.12065 0.2794)
			(stroke
				(width 0.1)
				(type default)
			)
			(layer "F.Fab")
		)
		(fp_line
			(start -0.12065 0.3048)
			(end -0.67945 0.3048)
			(stroke
				(width 0.1)
				(type default)
			)
			(layer "F.Fab")
		)
		(fp_line
			(start -0.12065 0.2794)
			(end -0.12065 0.3048)
			(stroke
				(width 0.1)
				(type default)
			)
			(layer "F.Fab")
		)
		(fp_line
			(start -0.12065 -0.2794)
			(end 0.12065 -0.2794)
			(stroke
				(width 0.1)
				(type default)
			)
			(layer "F.Fab")
		)
		(fp_line
			(start -0.12065 -0.305054)
			(end -0.12065 -0.2794)
			(stroke
				(width 0.1)
				(type default)
			)
			(layer "F.Fab")
		)
		(fp_line
			(start -0.67945 0.3048)
			(end -0.67945 -0.305054)
			(stroke
				(width 0.1)
				(type default)
			)
			(layer "F.Fab")
		)
		(fp_line
			(start -0.67945 -0.305054)
			(end -0.12065 -0.305054)
			(stroke
				(width 0.1)
				(type default)
			)
			(layer "F.Fab")
		)
		(pad "1" smd circle
			(at -0.40005 0 180)
			(size 0 0)
			(layers "F.Cu" "F.Mask" "F.Paste")
			(net "SMB_1_BMC_GPU_SCL")
		)
		(pad "2" smd circle
			(at 0.40005 0 180)
			(size 0 0)
			(layers "F.Cu" "F.Mask" "F.Paste")
			(net "P3V3_AUX")
		)
	)
	(footprint ""
		(layer "F.Cu")
		(at 455.123804 -71.245984 -90)
		(property "Reference" "PC567"
			(at 0 0 270)
			(layer "F.SilkS")
			(hide yes)
			(effects
				(font
					(size 1.27 1.27)
				)
			)
		)
		(property "Value" ""
			(at 0 0 270)
			(layer "F.Fab")
			(effects
				(font
					(size 1.27 1.27)
				)
			)
		)
		(duplicate_pad_numbers_are_jumpers no)
		(fp_line
			(start -1.524 0.762)
			(end -1.524 -0.762)
			(stroke
				(width 0.1524)
				(type default)
			)
			(layer "F.SilkS")
		)
		(fp_line
			(start 1.524 0.762)
			(end -1.524 0.762)
			(stroke
				(width 0.1524)
				(type default)
			)
			(layer "F.SilkS")
		)
		(fp_line
			(start -1.524 -0.762)
			(end 1.524 -0.762)
			(stroke
				(width 0.1524)
				(type default)
			)
			(layer "F.SilkS")
		)
		(fp_line
			(start 1.524 -0.762)
			(end 1.524 0.762)
			(stroke
				(width 0.1524)
				(type default)
			)
			(layer "F.SilkS")
		)
		(fp_line
			(start -1.1049 0.724916)
			(end 1.1049 0.724916)
			(stroke
				(width 0.1)
				(type default)
			)
			(layer "F.Fab")
		)
		(fp_line
			(start 1.1049 0.724916)
			(end 1.1049 -0.724916)
			(stroke
				(width 0.1)
				(type default)
			)
			(layer "F.Fab")
		)
		(fp_line
			(start -1.1049 -0.724916)
			(end -1.1049 0.724916)
			(stroke
				(width 0.1)
				(type default)
			)
			(layer "F.Fab")
		)
		(fp_line
			(start 1.1049 -0.724916)
			(end -1.1049 -0.724916)
			(stroke
				(width 0.1)
				(type default)
			)
			(layer "F.Fab")
		)
		(pad "1" smd rect
			(at -0.889 0 90)
			(size 1.016 1.27)
			(layers "F.Cu" "F.Mask" "F.Paste")
			(net "SW_P3V3_AUX_FLT")
		)
		(pad "2" smd rect
			(at 0.889 0 90)
			(size 1.016 1.27)
			(layers "F.Cu" "F.Mask" "F.Paste")
			(net "GND")
		)
	)
	(footprint ""
		(layer "F.Cu")
		(at 36.930584 -106.523282)
		(property "Reference" "C2050"
			(at 0 0 0)
			(layer "F.SilkS")
			(hide yes)
			(effects
				(font
					(size 1.27 1.27)
				)
			)
		)
		(property "Value" ""
			(at 0 0 0)
			(layer "F.Fab")
			(effects
				(font
					(size 1.27 1.27)
				)
			)
		)
		(duplicate_pad_numbers_are_jumpers no)
		(fp_line
			(start -0.7874 -0.4064)
			(end 0.7874 -0.4064)
			(stroke
				(width 0.1524)
				(type default)
			)
			(layer "F.SilkS")
		)
		(fp_line
			(start -0.7874 0.4064)
			(end -0.7874 -0.4064)
			(stroke
				(width 0.1524)
				(type default)
			)
			(layer "F.SilkS")
		)
		(fp_line
			(start 0.7874 -0.4064)
			(end 0.7874 0.4064)
			(stroke
				(width 0.1524)
				(type default)
			)
			(layer "F.SilkS")
		)
		(fp_line
			(start 0.7874 0.4064)
			(end -0.7874 0.4064)
			(stroke
				(width 0.1524)
				(type default)
			)
			(layer "F.SilkS")
		)
		(fp_line
			(start -0.67945 -0.305054)
			(end -0.12065 -0.305054)
			(stroke
				(width 0.1)
				(type default)
			)
			(layer "F.Fab")
		)
		(fp_line
			(start -0.67945 0.3048)
			(end -0.67945 -0.305054)
			(stroke
				(width 0.1)
				(type default)
			)
			(layer "F.Fab")
		)
		(fp_line
			(start -0.12065 -0.305054)
			(end -0.12065 -0.2794)
			(stroke
				(width 0.1)
				(type default)
			)
			(layer "F.Fab")
		)
		(fp_line
			(start -0.12065 -0.2794)
			(end 0.12065 -0.2794)
			(stroke
				(width 0.1)
				(type default)
			)
			(layer "F.Fab")
		)
		(fp_line
			(start -0.12065 0.2794)
			(end -0.12065 0.3048)
			(stroke
				(width 0.1)
				(type default)
			)
			(layer "F.Fab")
		)
		(fp_line
			(start -0.12065 0.3048)
			(end -0.67945 0.3048)
			(stroke
				(width 0.1)
				(type default)
			)
			(layer "F.Fab")
		)
		(fp_line
			(start 0.120396 0.2794)
			(end -0.12065 0.2794)
			(stroke
				(width 0.1)
				(type default)
			)
			(layer "F.Fab")
		)
		(fp_line
			(start 0.120396 0.3048)
			(end 0.120396 0.2794)
			(stroke
				(width 0.1)
				(type default)
			)
			(layer "F.Fab")
		)
		(fp_line
			(start 0.12065 -0.3048)
			(end 0.67945 -0.3048)
			(stroke
				(width 0.1)
				(type default)
			)
			(layer "F.Fab")
		)
		(fp_line
			(start 0.12065 -0.2794)
			(end 0.12065 -0.3048)
			(stroke
				(width 0.1)
				(type default)
			)
			(layer "F.Fab")
		)
		(fp_line
			(start 0.67945 -0.3048)
			(end 0.67945 0.3048)
			(stroke
				(width 0.1)
				(type default)
			)
			(layer "F.Fab")
		)
		(fp_line
			(start 0.67945 0.3048)
			(end 0.120396 0.3048)
			(stroke
				(width 0.1)
				(type default)
			)
			(layer "F.Fab")
		)
		(pad "1" smd circle
			(at -0.40005 0)
			(size 0 0)
			(layers "F.Cu" "F.Mask" "F.Paste")
			(net "P3V3_PDB_AUX_ADC_TIC")
		)
		(pad "2" smd circle
			(at 0.40005 0)
			(size 0 0)
			(layers "F.Cu" "F.Mask" "F.Paste")
			(net "GND")
		)
	)
	(footprint ""
		(layer "F.Cu")
		(at 299.6946 -346.700348)
		(property "Reference" "PC619"
			(at 0 0 0)
			(layer "F.SilkS")
			(hide yes)
			(effects
				(font
					(size 1.27 1.27)
				)
			)
		)
		(property "Value" ""
			(at 0 0 0)
			(layer "F.Fab")
			(effects
				(font
					(size 1.27 1.27)
				)
			)
		)
		(duplicate_pad_numbers_are_jumpers no)
		(fp_line
			(start 2.750058 0.999998)
			(end -2.750058 0.999998)
			(stroke
				(width 0.1524)
				(type default)
			)
			(layer "F.SilkS")
		)
		(fp_circle
			(center 0 0.999998)
			(end 2.750058 0.999998)
			(stroke
				(width 0.1524)
				(type default)
			)
			(fill no)
			(layer "F.SilkS")
		)
		(fp_poly
			(pts
				(arc
					(start 2.750058 0.999998)
					(mid 0 3.750056)
					(end -2.750058 0.999998)
				)
			)
			(stroke
				(width 0)
				(type default)
			)
			(fill yes)
			(layer "F.SilkS")
		)
		(fp_circle
			(center 0 0.999998)
			(end 2.750058 0.999998)
			(stroke
				(width 0.1)
				(type default)
			)
			(fill no)
			(layer "F.Fab")
		)
		(pad "1" thru_hole rect
			(at 0 0)
			(size 1.5748 1.5748)
			(drill 1.0668)
			(layers "*.Cu" "*.Mask")
			(remove_unused_layers no)
			(net "PVCCFA_EHV_FIVRA_CPU0")
			(clearance 0)
			(padstack
				(mode front_inner_back)
				(layer "Inner"
					(shape circle)
					(size 1.5748 1.5748)
					(clearance 0)
				)
				(layer "B.Cu"
					(shape rect)
					(size 1.5748 1.5748)
					(clearance 0)
				)
			)
		)
		(pad "2" thru_hole circle
			(at 0 1.999996)
			(size 1.5748 1.5748)
			(drill 1.0668)
			(layers "*.Cu" "*.Mask")
			(remove_unused_layers no)
			(net "GND")
			(clearance 0)
		)
	)
	(footprint ""
		(layer "F.Cu")
		(at 70.358 -113.756948 180)
		(property "Reference" "R4269"
			(at 0 0 180)
			(layer "F.SilkS")
			(hide yes)
			(effects
				(font
					(size 1.27 1.27)
				)
			)
		)
		(property "Value" ""
			(at 0 0 180)
			(layer "F.Fab")
			(effects
				(font
					(size 1.27 1.27)
				)
			)
		)
		(duplicate_pad_numbers_are_jumpers no)
		(fp_line
			(start 0.7874 0.4064)
			(end -0.7874 0.4064)
			(stroke
				(width 0.1524)
				(type default)
			)
			(layer "F.SilkS")
		)
		(fp_line
			(start 0.7874 -0.4064)
			(end 0.7874 0.4064)
			(stroke
				(width 0.1524)
				(type default)
			)
			(layer "F.SilkS")
		)
		(fp_line
			(start -0.7874 0.4064)
			(end -0.7874 -0.4064)
			(stroke
				(width 0.1524)
				(type default)
			)
			(layer "F.SilkS")
		)
		(fp_line
			(start -0.7874 -0.4064)
			(end 0.7874 -0.4064)
			(stroke
				(width 0.1524)
				(type default)
			)
			(layer "F.SilkS")
		)
		(fp_line
			(start 0.67945 0.3048)
			(end 0.120396 0.3048)
			(stroke
				(width 0.1)
				(type default)
			)
			(layer "F.Fab")
		)
		(fp_line
			(start 0.67945 -0.3048)
			(end 0.67945 0.3048)
			(stroke
				(width 0.1)
				(type default)
			)
			(layer "F.Fab")
		)
		(fp_line
			(start 0.12065 -0.2794)
			(end 0.12065 -0.3048)
			(stroke
				(width 0.1)
				(type default)
			)
			(layer "F.Fab")
		)
		(fp_line
			(start 0.12065 -0.3048)
			(end 0.67945 -0.3048)
			(stroke
				(width 0.1)
				(type default)
			)
			(layer "F.Fab")
		)
		(fp_line
			(start 0.120396 0.3048)
			(end 0.120396 0.2794)
			(stroke
				(width 0.1)
				(type default)
			)
			(layer "F.Fab")
		)
		(fp_line
			(start 0.120396 0.2794)
			(end -0.12065 0.2794)
			(stroke
				(width 0.1)
				(type default)
			)
			(layer "F.Fab")
		)
		(fp_line
			(start -0.12065 0.3048)
			(end -0.67945 0.3048)
			(stroke
				(width 0.1)
				(type default)
			)
			(layer "F.Fab")
		)
		(fp_line
			(start -0.12065 0.2794)
			(end -0.12065 0.3048)
			(stroke
				(width 0.1)
				(type default)
			)
			(layer "F.Fab")
		)
		(fp_line
			(start -0.12065 -0.2794)
			(end 0.12065 -0.2794)
			(stroke
				(width 0.1)
				(type default)
			)
			(layer "F.Fab")
		)
		(fp_line
			(start -0.12065 -0.305054)
			(end -0.12065 -0.2794)
			(stroke
				(width 0.1)
				(type default)
			)
			(layer "F.Fab")
		)
		(fp_line
			(start -0.67945 0.3048)
			(end -0.67945 -0.305054)
			(stroke
				(width 0.1)
				(type default)
			)
			(layer "F.Fab")
		)
		(fp_line
			(start -0.67945 -0.305054)
			(end -0.12065 -0.305054)
			(stroke
				(width 0.1)
				(type default)
			)
			(layer "F.Fab")
		)
		(pad "1" smd circle
			(at -0.40005 0 180)
			(size 0 0)
			(layers "F.Cu" "F.Mask" "F.Paste")
			(net "P3V3_AUX")
		)
		(pad "2" smd circle
			(at 0.40005 0 180)
			(size 0 0)
			(layers "F.Cu" "F.Mask" "F.Paste")
			(net "SMB_VR_SENSOR_3V3AUX_SCL")
		)
	)
	(footprint ""
		(layer "F.Cu")
		(at 342.803734 -27.488388 -90)
		(property "Reference" "R635"
			(at 0 0 270)
			(layer "F.SilkS")
			(hide yes)
			(effects
				(font
					(size 1.27 1.27)
				)
			)
		)
		(property "Value" ""
			(at 0 0 270)
			(layer "F.Fab")
			(effects
				(font
					(size 1.27 1.27)
				)
			)
		)
		(duplicate_pad_numbers_are_jumpers no)
		(fp_line
			(start -0.7874 0.4064)
			(end -0.7874 -0.4064)
			(stroke
				(width 0.1524)
				(type default)
			)
			(layer "F.SilkS")
		)
		(fp_line
			(start 0.7874 0.4064)
			(end -0.7874 0.4064)
			(stroke
				(width 0.1524)
				(type default)
			)
			(layer "F.SilkS")
		)
		(fp_line
			(start -0.7874 -0.4064)
			(end 0.7874 -0.4064)
			(stroke
				(width 0.1524)
				(type default)
			)
			(layer "F.SilkS")
		)
		(fp_line
			(start 0.7874 -0.4064)
			(end 0.7874 0.4064)
			(stroke
				(width 0.1524)
				(type default)
			)
			(layer "F.SilkS")
		)
		(fp_line
			(start -0.67945 0.3048)
			(end -0.67945 -0.305054)
			(stroke
				(width 0.1)
				(type default)
			)
			(layer "F.Fab")
		)
		(fp_line
			(start -0.12065 0.3048)
			(end -0.67945 0.3048)
			(stroke
				(width 0.1)
				(type default)
			)
			(layer "F.Fab")
		)
		(fp_line
			(start 0.120396 0.3048)
			(end 0.120396 0.2794)
			(stroke
				(width 0.1)
				(type default)
			)
			(layer "F.Fab")
		)
		(fp_line
			(start 0.67945 0.3048)
			(end 0.120396 0.3048)
			(stroke
				(width 0.1)
				(type default)
			)
			(layer "F.Fab")
		)
		(fp_line
			(start -0.12065 0.2794)
			(end -0.12065 0.3048)
			(stroke
				(width 0.1)
				(type default)
			)
			(layer "F.Fab")
		)
		(fp_line
			(start 0.120396 0.2794)
			(end -0.12065 0.2794)
			(stroke
				(width 0.1)
				(type default)
			)
			(layer "F.Fab")
		)
		(fp_line
			(start -0.12065 -0.2794)
			(end 0.12065 -0.2794)
			(stroke
				(width 0.1)
				(type default)
			)
			(layer "F.Fab")
		)
		(fp_line
			(start 0.12065 -0.2794)
			(end 0.12065 -0.3048)
			(stroke
				(width 0.1)
				(type default)
			)
			(layer "F.Fab")
		)
		(fp_line
			(start 0.12065 -0.3048)
			(end 0.67945 -0.3048)
			(stroke
				(width 0.1)
				(type default)
			)
			(layer "F.Fab")
		)
		(fp_line
			(start 0.67945 -0.3048)
			(end 0.67945 0.3048)
			(stroke
				(width 0.1)
				(type default)
			)
			(layer "F.Fab")
		)
		(fp_line
			(start -0.67945 -0.305054)
			(end -0.12065 -0.305054)
			(stroke
				(width 0.1)
				(type default)
			)
			(layer "F.Fab")
		)
		(fp_line
			(start -0.12065 -0.305054)
			(end -0.12065 -0.2794)
			(stroke
				(width 0.1)
				(type default)
			)
			(layer "F.Fab")
		)
		(pad "1" smd circle
			(at -0.40005 0 270)
			(size 0 0)
			(layers "F.Cu" "F.Mask" "F.Paste")
			(net "PU_OC3_USB_N")
		)
		(pad "2" smd circle
			(at 0.40005 0 270)
			(size 0 0)
			(layers "F.Cu" "F.Mask" "F.Paste")
			(net "P3V3_AUX")
		)
	)
	(footprint ""
		(layer "F.Cu")
		(at 98.045016 -338.180172 90)
		(property "Reference" "PR1767"
			(at 0 0 90)
			(layer "F.SilkS")
			(hide yes)
			(effects
				(font
					(size 1.27 1.27)
				)
			)
		)
		(property "Value" ""
			(at 0 0 90)
			(layer "F.Fab")
			(effects
				(font
					(size 1.27 1.27)
				)
			)
		)
		(duplicate_pad_numbers_are_jumpers no)
		(fp_line
			(start 0.7874 -0.4064)
			(end 0.7874 0.4064)
			(stroke
				(width 0.1524)
				(type default)
			)
			(layer "F.SilkS")
		)
		(fp_line
			(start -0.7874 -0.4064)
			(end 0.7874 -0.4064)
			(stroke
				(width 0.1524)
				(type default)
			)
			(layer "F.SilkS")
		)
		(fp_line
			(start 0.7874 0.4064)
			(end -0.7874 0.4064)
			(stroke
				(width 0.1524)
				(type default)
			)
			(layer "F.SilkS")
		)
		(fp_line
			(start -0.7874 0.4064)
			(end -0.7874 -0.4064)
			(stroke
				(width 0.1524)
				(type default)
			)
			(layer "F.SilkS")
		)
		(fp_line
			(start -0.12065 -0.305054)
			(end -0.12065 -0.2794)
			(stroke
				(width 0.1)
				(type default)
			)
			(layer "F.Fab")
		)
		(fp_line
			(start -0.67945 -0.305054)
			(end -0.12065 -0.305054)
			(stroke
				(width 0.1)
				(type default)
			)
			(layer "F.Fab")
		)
		(fp_line
			(start 0.67945 -0.3048)
			(end 0.67945 0.3048)
			(stroke
				(width 0.1)
				(type default)
			)
			(layer "F.Fab")
		)
		(fp_line
			(start 0.12065 -0.3048)
			(end 0.67945 -0.3048)
			(stroke
				(width 0.1)
				(type default)
			)
			(layer "F.Fab")
		)
		(fp_line
			(start 0.12065 -0.2794)
			(end 0.12065 -0.3048)
			(stroke
				(width 0.1)
				(type default)
			)
			(layer "F.Fab")
		)
		(fp_line
			(start -0.12065 -0.2794)
			(end 0.12065 -0.2794)
			(stroke
				(width 0.1)
				(type default)
			)
			(layer "F.Fab")
		)
		(fp_line
			(start 0.120396 0.2794)
			(end -0.12065 0.2794)
			(stroke
				(width 0.1)
				(type default)
			)
			(layer "F.Fab")
		)
		(fp_line
			(start -0.12065 0.2794)
			(end -0.12065 0.3048)
			(stroke
				(width 0.1)
				(type default)
			)
			(layer "F.Fab")
		)
		(fp_line
			(start 0.67945 0.3048)
			(end 0.120396 0.3048)
			(stroke
				(width 0.1)
				(type default)
			)
			(layer "F.Fab")
		)
		(fp_line
			(start 0.120396 0.3048)
			(end 0.120396 0.2794)
			(stroke
				(width 0.1)
				(type default)
			)
			(layer "F.Fab")
		)
		(fp_line
			(start -0.12065 0.3048)
			(end -0.67945 0.3048)
			(stroke
				(width 0.1)
				(type default)
			)
			(layer "F.Fab")
		)
		(fp_line
			(start -0.67945 0.3048)
			(end -0.67945 -0.305054)
			(stroke
				(width 0.1)
				(type default)
			)
			(layer "F.Fab")
		)
		(pad "1" smd circle
			(at -0.40005 0 90)
			(size 0 0)
			(layers "F.Cu" "F.Mask" "F.Paste")
			(net "SW_PVCCIN_CPU1_BOOT1")
		)
		(pad "2" smd circle
			(at 0.40005 0 90)
			(size 0 0)
			(layers "F.Cu" "F.Mask" "F.Paste")
			(net "SW_PVCCIN_CPU1_BOOT1_R")
		)
	)
	(footprint ""
		(layer "F.Cu")
		(at 27.628596 -393.342876)
		(property "Reference" "R3270"
			(at 0 0 0)
			(layer "F.SilkS")
			(hide yes)
			(effects
				(font
					(size 1.27 1.27)
				)
			)
		)
		(property "Value" ""
			(at 0 0 0)
			(layer "F.Fab")
			(effects
				(font
					(size 1.27 1.27)
				)
			)
		)
		(duplicate_pad_numbers_are_jumpers no)
		(fp_line
			(start -0.7874 -0.4064)
			(end 0.7874 -0.4064)
			(stroke
				(width 0.1524)
				(type default)
			)
			(layer "F.SilkS")
		)
		(fp_line
			(start -0.7874 0.4064)
			(end -0.7874 -0.4064)
			(stroke
				(width 0.1524)
				(type default)
			)
			(layer "F.SilkS")
		)
		(fp_line
			(start 0.7874 -0.4064)
			(end 0.7874 0.4064)
			(stroke
				(width 0.1524)
				(type default)
			)
			(layer "F.SilkS")
		)
		(fp_line
			(start 0.7874 0.4064)
			(end -0.7874 0.4064)
			(stroke
				(width 0.1524)
				(type default)
			)
			(layer "F.SilkS")
		)
		(fp_line
			(start -0.67945 -0.305054)
			(end -0.12065 -0.305054)
			(stroke
				(width 0.1)
				(type default)
			)
			(layer "F.Fab")
		)
		(fp_line
			(start -0.67945 0.3048)
			(end -0.67945 -0.305054)
			(stroke
				(width 0.1)
				(type default)
			)
			(layer "F.Fab")
		)
		(fp_line
			(start -0.12065 -0.305054)
			(end -0.12065 -0.2794)
			(stroke
				(width 0.1)
				(type default)
			)
			(layer "F.Fab")
		)
		(fp_line
			(start -0.12065 -0.2794)
			(end 0.12065 -0.2794)
			(stroke
				(width 0.1)
				(type default)
			)
			(layer "F.Fab")
		)
		(fp_line
			(start -0.12065 0.2794)
			(end -0.12065 0.3048)
			(stroke
				(width 0.1)
				(type default)
			)
			(layer "F.Fab")
		)
		(fp_line
			(start -0.12065 0.3048)
			(end -0.67945 0.3048)
			(stroke
				(width 0.1)
				(type default)
			)
			(layer "F.Fab")
		)
		(fp_line
			(start 0.120396 0.2794)
			(end -0.12065 0.2794)
			(stroke
				(width 0.1)
				(type default)
			)
			(layer "F.Fab")
		)
		(fp_line
			(start 0.120396 0.3048)
			(end 0.120396 0.2794)
			(stroke
				(width 0.1)
				(type default)
			)
			(layer "F.Fab")
		)
		(fp_line
			(start 0.12065 -0.3048)
			(end 0.67945 -0.3048)
			(stroke
				(width 0.1)
				(type default)
			)
			(layer "F.Fab")
		)
		(fp_line
			(start 0.12065 -0.2794)
			(end 0.12065 -0.3048)
			(stroke
				(width 0.1)
				(type default)
			)
			(layer "F.Fab")
		)
		(fp_line
			(start 0.67945 -0.3048)
			(end 0.67945 0.3048)
			(stroke
				(width 0.1)
				(type default)
			)
			(layer "F.Fab")
		)
		(fp_line
			(start 0.67945 0.3048)
			(end 0.120396 0.3048)
			(stroke
				(width 0.1)
				(type default)
			)
			(layer "F.Fab")
		)
		(pad "1" smd circle
			(at -0.40005 0)
			(size 0 0)
			(layers "F.Cu" "F.Mask" "F.Paste")
			(net "FM_P2E_FGB")
		)
		(pad "2" smd circle
			(at 0.40005 0)
			(size 0 0)
			(layers "F.Cu" "F.Mask" "F.Paste")
			(net "GND")
		)
	)
	(footprint ""
		(layer "F.Cu")
		(at 75.424538 -19.220942)
		(property "Reference" "PC2146"
			(at 0 0 0)
			(layer "F.SilkS")
			(hide yes)
			(effects
				(font
					(size 1.27 1.27)
				)
			)
		)
		(property "Value" ""
			(at 0 0 0)
			(layer "F.Fab")
			(effects
				(font
					(size 1.27 1.27)
				)
			)
		)
		(duplicate_pad_numbers_are_jumpers no)
		(fp_line
			(start -0.7874 -0.4064)
			(end 0.7874 -0.4064)
			(stroke
				(width 0.1524)
				(type default)
			)
			(layer "F.SilkS")
		)
		(fp_line
			(start -0.7874 0.4064)
			(end -0.7874 -0.4064)
			(stroke
				(width 0.1524)
				(type default)
			)
			(layer "F.SilkS")
		)
		(fp_line
			(start 0.7874 -0.4064)
			(end 0.7874 0.4064)
			(stroke
				(width 0.1524)
				(type default)
			)
			(layer "F.SilkS")
		)
		(fp_line
			(start 0.7874 0.4064)
			(end -0.7874 0.4064)
			(stroke
				(width 0.1524)
				(type default)
			)
			(layer "F.SilkS")
		)
		(fp_line
			(start -0.67945 -0.305054)
			(end -0.12065 -0.305054)
			(stroke
				(width 0.1)
				(type default)
			)
			(layer "F.Fab")
		)
		(fp_line
			(start -0.67945 0.3048)
			(end -0.67945 -0.305054)
			(stroke
				(width 0.1)
				(type default)
			)
			(layer "F.Fab")
		)
		(fp_line
			(start -0.12065 -0.305054)
			(end -0.12065 -0.2794)
			(stroke
				(width 0.1)
				(type default)
			)
			(layer "F.Fab")
		)
		(fp_line
			(start -0.12065 -0.2794)
			(end 0.12065 -0.2794)
			(stroke
				(width 0.1)
				(type default)
			)
			(layer "F.Fab")
		)
		(fp_line
			(start -0.12065 0.2794)
			(end -0.12065 0.3048)
			(stroke
				(width 0.1)
				(type default)
			)
			(layer "F.Fab")
		)
		(fp_line
			(start -0.12065 0.3048)
			(end -0.67945 0.3048)
			(stroke
				(width 0.1)
				(type default)
			)
			(layer "F.Fab")
		)
		(fp_line
			(start 0.120396 0.2794)
			(end -0.12065 0.2794)
			(stroke
				(width 0.1)
				(type default)
			)
			(layer "F.Fab")
		)
		(fp_line
			(start 0.120396 0.3048)
			(end 0.120396 0.2794)
			(stroke
				(width 0.1)
				(type default)
			)
			(layer "F.Fab")
		)
		(fp_line
			(start 0.12065 -0.3048)
			(end 0.67945 -0.3048)
			(stroke
				(width 0.1)
				(type default)
			)
			(layer "F.Fab")
		)
		(fp_line
			(start 0.12065 -0.2794)
			(end 0.12065 -0.3048)
			(stroke
				(width 0.1)
				(type default)
			)
			(layer "F.Fab")
		)
		(fp_line
			(start 0.67945 -0.3048)
			(end 0.67945 0.3048)
			(stroke
				(width 0.1)
				(type default)
			)
			(layer "F.Fab")
		)
		(fp_line
			(start 0.67945 0.3048)
			(end 0.120396 0.3048)
			(stroke
				(width 0.1)
				(type default)
			)
			(layer "F.Fab")
		)
		(pad "1" smd circle
			(at -0.40005 0)
			(size 0 0)
			(layers "F.Cu" "F.Mask" "F.Paste")
			(net "GND")
		)
		(pad "2" smd circle
			(at 0.40005 0)
			(size 0 0)
			(layers "F.Cu" "F.Mask" "F.Paste")
			(net "P12V_OCP_REG_2")
		)
	)
	(footprint ""
		(layer "F.Cu")
		(at 24.580596 -388.008876 -90)
		(property "Reference" "C1863"
			(at 0 0 270)
			(layer "F.SilkS")
			(hide yes)
			(effects
				(font
					(size 1.27 1.27)
				)
			)
		)
		(property "Value" ""
			(at 0 0 270)
			(layer "F.Fab")
			(effects
				(font
					(size 1.27 1.27)
				)
			)
		)
		(duplicate_pad_numbers_are_jumpers no)
		(fp_line
			(start -0.7874 0.4064)
			(end -0.7874 -0.4064)
			(stroke
				(width 0.1524)
				(type default)
			)
			(layer "F.SilkS")
		)
		(fp_line
			(start 0.7874 0.4064)
			(end -0.7874 0.4064)
			(stroke
				(width 0.1524)
				(type default)
			)
			(layer "F.SilkS")
		)
		(fp_line
			(start -0.7874 -0.4064)
			(end 0.7874 -0.4064)
			(stroke
				(width 0.1524)
				(type default)
			)
			(layer "F.SilkS")
		)
		(fp_line
			(start 0.7874 -0.4064)
			(end 0.7874 0.4064)
			(stroke
				(width 0.1524)
				(type default)
			)
			(layer "F.SilkS")
		)
		(fp_line
			(start -0.67945 0.3048)
			(end -0.67945 -0.305054)
			(stroke
				(width 0.1)
				(type default)
			)
			(layer "F.Fab")
		)
		(fp_line
			(start -0.12065 0.3048)
			(end -0.67945 0.3048)
			(stroke
				(width 0.1)
				(type default)
			)
			(layer "F.Fab")
		)
		(fp_line
			(start 0.120396 0.3048)
			(end 0.120396 0.2794)
			(stroke
				(width 0.1)
				(type default)
			)
			(layer "F.Fab")
		)
		(fp_line
			(start 0.67945 0.3048)
			(end 0.120396 0.3048)
			(stroke
				(width 0.1)
				(type default)
			)
			(layer "F.Fab")
		)
		(fp_line
			(start -0.12065 0.2794)
			(end -0.12065 0.3048)
			(stroke
				(width 0.1)
				(type default)
			)
			(layer "F.Fab")
		)
		(fp_line
			(start 0.120396 0.2794)
			(end -0.12065 0.2794)
			(stroke
				(width 0.1)
				(type default)
			)
			(layer "F.Fab")
		)
		(fp_line
			(start -0.12065 -0.2794)
			(end 0.12065 -0.2794)
			(stroke
				(width 0.1)
				(type default)
			)
			(layer "F.Fab")
		)
		(fp_line
			(start 0.12065 -0.2794)
			(end 0.12065 -0.3048)
			(stroke
				(width 0.1)
				(type default)
			)
			(layer "F.Fab")
		)
		(fp_line
			(start 0.12065 -0.3048)
			(end 0.67945 -0.3048)
			(stroke
				(width 0.1)
				(type default)
			)
			(layer "F.Fab")
		)
		(fp_line
			(start 0.67945 -0.3048)
			(end 0.67945 0.3048)
			(stroke
				(width 0.1)
				(type default)
			)
			(layer "F.Fab")
		)
		(fp_line
			(start -0.67945 -0.305054)
			(end -0.12065 -0.305054)
			(stroke
				(width 0.1)
				(type default)
			)
			(layer "F.Fab")
		)
		(fp_line
			(start -0.12065 -0.305054)
			(end -0.12065 -0.2794)
			(stroke
				(width 0.1)
				(type default)
			)
			(layer "F.Fab")
		)
		(pad "1" smd circle
			(at -0.40005 0 270)
			(size 0 0)
			(layers "F.Cu" "F.Mask" "F.Paste")
			(net "P3V3_AUX")
		)
		(pad "2" smd circle
			(at 0.40005 0 270)
			(size 0 0)
			(layers "F.Cu" "F.Mask" "F.Paste")
			(net "GND")
		)
	)
	(footprint ""
		(layer "F.Cu")
		(at 85.260942 -339.738462 90)
		(property "Reference" "PC501"
			(at 0 0 90)
			(layer "F.SilkS")
			(hide yes)
			(effects
				(font
					(size 1.27 1.27)
				)
			)
		)
		(property "Value" ""
			(at 0 0 90)
			(layer "F.Fab")
			(effects
				(font
					(size 1.27 1.27)
				)
			)
		)
		(duplicate_pad_numbers_are_jumpers no)
		(fp_line
			(start 0.7874 -0.4064)
			(end 0.7874 0.4064)
			(stroke
				(width 0.1524)
				(type default)
			)
			(layer "F.SilkS")
		)
		(fp_line
			(start -0.7874 -0.4064)
			(end 0.7874 -0.4064)
			(stroke
				(width 0.1524)
				(type default)
			)
			(layer "F.SilkS")
		)
		(fp_line
			(start 0.7874 0.4064)
			(end -0.7874 0.4064)
			(stroke
				(width 0.1524)
				(type default)
			)
			(layer "F.SilkS")
		)
		(fp_line
			(start -0.7874 0.4064)
			(end -0.7874 -0.4064)
			(stroke
				(width 0.1524)
				(type default)
			)
			(layer "F.SilkS")
		)
		(fp_line
			(start -0.12065 -0.305054)
			(end -0.12065 -0.2794)
			(stroke
				(width 0.1)
				(type default)
			)
			(layer "F.Fab")
		)
		(fp_line
			(start -0.67945 -0.305054)
			(end -0.12065 -0.305054)
			(stroke
				(width 0.1)
				(type default)
			)
			(layer "F.Fab")
		)
		(fp_line
			(start 0.67945 -0.3048)
			(end 0.67945 0.3048)
			(stroke
				(width 0.1)
				(type default)
			)
			(layer "F.Fab")
		)
		(fp_line
			(start 0.12065 -0.3048)
			(end 0.67945 -0.3048)
			(stroke
				(width 0.1)
				(type default)
			)
			(layer "F.Fab")
		)
		(fp_line
			(start 0.12065 -0.2794)
			(end 0.12065 -0.3048)
			(stroke
				(width 0.1)
				(type default)
			)
			(layer "F.Fab")
		)
		(fp_line
			(start -0.12065 -0.2794)
			(end 0.12065 -0.2794)
			(stroke
				(width 0.1)
				(type default)
			)
			(layer "F.Fab")
		)
		(fp_line
			(start 0.120396 0.2794)
			(end -0.12065 0.2794)
			(stroke
				(width 0.1)
				(type default)
			)
			(layer "F.Fab")
		)
		(fp_line
			(start -0.12065 0.2794)
			(end -0.12065 0.3048)
			(stroke
				(width 0.1)
				(type default)
			)
			(layer "F.Fab")
		)
		(fp_line
			(start 0.67945 0.3048)
			(end 0.120396 0.3048)
			(stroke
				(width 0.1)
				(type default)
			)
			(layer "F.Fab")
		)
		(fp_line
			(start 0.120396 0.3048)
			(end 0.120396 0.2794)
			(stroke
				(width 0.1)
				(type default)
			)
			(layer "F.Fab")
		)
		(fp_line
			(start -0.12065 0.3048)
			(end -0.67945 0.3048)
			(stroke
				(width 0.1)
				(type default)
			)
			(layer "F.Fab")
		)
		(fp_line
			(start -0.67945 0.3048)
			(end -0.67945 -0.305054)
			(stroke
				(width 0.1)
				(type default)
			)
			(layer "F.Fab")
		)
		(pad "1" smd circle
			(at -0.40005 0 90)
			(size 0 0)
			(layers "F.Cu" "F.Mask" "F.Paste")
			(net "PVCCIN_CPU1_VDD6")
		)
		(pad "2" smd circle
			(at 0.40005 0 90)
			(size 0 0)
			(layers "F.Cu" "F.Mask" "F.Paste")
			(net "GND")
		)
	)
	(footprint ""
		(layer "F.Cu")
		(at 141.656054 -97.808542 -90)
		(property "Reference" "U306"
			(at -1.20523 -2.996692 0)
			(unlocked yes)
			(layer "F.SilkS")
			(effects
				(font
					(size 0.7874 0.5842)
					(thickness 0.1524)
				)
				(justify left)
			)
		)
		(property "Value" ""
			(at 0 0 270)
			(layer "F.Fab")
			(effects
				(font
					(size 1.27 1.27)
				)
			)
		)
		(duplicate_pad_numbers_are_jumpers no)
		(fp_line
			(start -2.0066 2.5527)
			(end -2.0066 -2.5527)
			(stroke
				(width 0.1524)
				(type default)
			)
			(layer "F.SilkS")
		)
		(fp_line
			(start 2.0066 2.5527)
			(end -2.0066 2.5527)
			(stroke
				(width 0.1524)
				(type default)
			)
			(layer "F.SilkS")
		)
		(fp_line
			(start 0 -1.9812)
			(end 0.5715 -2.5527)
			(stroke
				(width 0.1524)
				(type default)
			)
			(layer "F.SilkS")
		)
		(fp_line
			(start -2.0066 -2.5527)
			(end -0.5715 -2.5527)
			(stroke
				(width 0.1524)
				(type default)
			)
			(layer "F.SilkS")
		)
		(fp_line
			(start -0.5715 -2.5527)
			(end 0 -1.9812)
			(stroke
				(width 0.1524)
				(type default)
			)
			(layer "F.SilkS")
		)
		(fp_line
			(start 0.5715 -2.5527)
			(end 2.0066 -2.5527)
			(stroke
				(width 0.1524)
				(type default)
			)
			(layer "F.SilkS")
		)
		(fp_line
			(start 2.0066 -2.5527)
			(end 2.0066 2.5527)
			(stroke
				(width 0.1524)
				(type default)
			)
			(layer "F.SilkS")
		)
		(fp_poly
			(pts
				(xy -2.810764 -2.90576) (xy -3.138932 -2.35204) (xy -3.435604 -2.90576)
			)
			(stroke
				(width 0)
				(type default)
			)
			(fill yes)
			(layer "F.SilkS")
		)
		(fp_line
			(start -2.249932 2.549906)
			(end -2.249932 -2.549906)
			(stroke
				(width 0.1)
				(type default)
			)
			(layer "F.Fab")
		)
		(fp_line
			(start 2.249932 2.549906)
			(end -2.249932 2.549906)
			(stroke
				(width 0.1)
				(type default)
			)
			(layer "F.Fab")
		)
		(fp_line
			(start -2.249932 -2.549906)
			(end 2.249932 -2.549906)
			(stroke
				(width 0.1)
				(type default)
			)
			(layer "F.Fab")
		)
		(fp_line
			(start 2.249932 -2.549906)
			(end 2.249932 2.549906)
			(stroke
				(width 0.1)
				(type default)
			)
			(layer "F.Fab")
		)
		(fp_poly
			(pts
				(xy -4.36372 -1.608328) (xy -4.36372 -2.233168) (xy -3.81 -1.905)
			)
			(stroke
				(width 0)
				(type default)
			)
			(fill yes)
			(layer "F.Fab")
		)
		(pad "1" smd rect
			(at -2.921 -1.949958 180)
			(size 0.3556 1.4986)
			(layers "F.Cu" "F.Mask" "F.Paste")
			(net "PD_CPU1_ERRS_U306_DIR")
		)
		(pad "2" smd rect
			(at -2.921 -1.299972 180)
			(size 0.3556 1.4986)
			(layers "F.Cu" "F.Mask" "F.Paste")
			(net "PD_GTL2014_ERROR_B0")
		)
		(pad "3" smd rect
			(at -2.921 -0.649986 180)
			(size 0.3556 1.4986)
			(layers "F.Cu" "F.Mask" "F.Paste")
			(net "H_CPU_ERR2_LVC1_N")
		)
		(pad "4" smd rect
			(at -2.921 0 180)
			(size 0.3556 1.4986)
			(layers "F.Cu" "F.Mask" "F.Paste")
			(net "P0V62_CPU0_ERRS_U306_VREF")
		)
		(pad "5" smd rect
			(at -2.921 0.649986 180)
			(size 0.3556 1.4986)
			(layers "F.Cu" "F.Mask" "F.Paste")
			(net "H_CPU_ERR1_LVC1_N")
		)
		(pad "6" smd rect
			(at -2.921 1.299972 180)
			(size 0.3556 1.4986)
			(layers "F.Cu" "F.Mask" "F.Paste")
			(net "H_CPU_ERR0_LVC1_N")
		)
		(pad "7" smd rect
			(at -2.921 1.949958 180)
			(size 0.3556 1.4986)
			(layers "F.Cu" "F.Mask" "F.Paste")
			(net "GND")
		)
		(pad "8" smd rect
			(at 2.921 1.949958 180)
			(size 0.3556 1.4986)
			(layers "F.Cu" "F.Mask" "F.Paste")
			(net "GND")
		)
		(pad "9" smd rect
			(at 2.921 1.299972 180)
			(size 0.3556 1.4986)
			(layers "F.Cu" "F.Mask" "F.Paste")
			(net "H_CPU_ERR0_LVC2_R_N")
		)
		(pad "10" smd rect
			(at 2.921 0.649986 180)
			(size 0.3556 1.4986)
			(layers "F.Cu" "F.Mask" "F.Paste")
			(net "H_CPU_ERR1_LVC2_R_N")
		)
		(pad "11" smd rect
			(at 2.921 0 180)
			(size 0.3556 1.4986)
			(layers "F.Cu" "F.Mask" "F.Paste")
			(net "GND")
		)
		(pad "12" smd rect
			(at 2.921 -0.649986 180)
			(size 0.3556 1.4986)
			(layers "F.Cu" "F.Mask" "F.Paste")
			(net "H_CPU_ERR2_LVC2_R_N")
		)
		(pad "13" smd rect
			(at 2.921 -1.299972 180)
			(size 0.3556 1.4986)
			(layers "F.Cu" "F.Mask" "F.Paste")
			(net "NC_U306_A0")
		)
		(pad "14" smd rect
			(at 2.921 -1.949958 180)
			(size 0.3556 1.4986)
			(layers "F.Cu" "F.Mask" "F.Paste")
			(net "P3V3")
		)
	)
	(footprint ""
		(layer "F.Cu")
		(at 349.77705 -360.929174 -90)
		(property "Reference" "R2366"
			(at 0 0 270)
			(layer "F.SilkS")
			(hide yes)
			(effects
				(font
					(size 1.27 1.27)
				)
			)
		)
		(property "Value" ""
			(at 0 0 270)
			(layer "F.Fab")
			(effects
				(font
					(size 1.27 1.27)
				)
			)
		)
		(duplicate_pad_numbers_are_jumpers no)
		(fp_line
			(start -0.7874 0.4064)
			(end -0.7874 -0.4064)
			(stroke
				(width 0.1524)
				(type default)
			)
			(layer "F.SilkS")
		)
		(fp_line
			(start 0.7874 0.4064)
			(end -0.7874 0.4064)
			(stroke
				(width 0.1524)
				(type default)
			)
			(layer "F.SilkS")
		)
		(fp_line
			(start -0.7874 -0.4064)
			(end 0.7874 -0.4064)
			(stroke
				(width 0.1524)
				(type default)
			)
			(layer "F.SilkS")
		)
		(fp_line
			(start 0.7874 -0.4064)
			(end 0.7874 0.4064)
			(stroke
				(width 0.1524)
				(type default)
			)
			(layer "F.SilkS")
		)
		(fp_line
			(start -0.67945 0.3048)
			(end -0.67945 -0.305054)
			(stroke
				(width 0.1)
				(type default)
			)
			(layer "F.Fab")
		)
		(fp_line
			(start -0.12065 0.3048)
			(end -0.67945 0.3048)
			(stroke
				(width 0.1)
				(type default)
			)
			(layer "F.Fab")
		)
		(fp_line
			(start 0.120396 0.3048)
			(end 0.120396 0.2794)
			(stroke
				(width 0.1)
				(type default)
			)
			(layer "F.Fab")
		)
		(fp_line
			(start 0.67945 0.3048)
			(end 0.120396 0.3048)
			(stroke
				(width 0.1)
				(type default)
			)
			(layer "F.Fab")
		)
		(fp_line
			(start -0.12065 0.2794)
			(end -0.12065 0.3048)
			(stroke
				(width 0.1)
				(type default)
			)
			(layer "F.Fab")
		)
		(fp_line
			(start 0.120396 0.2794)
			(end -0.12065 0.2794)
			(stroke
				(width 0.1)
				(type default)
			)
			(layer "F.Fab")
		)
		(fp_line
			(start -0.12065 -0.2794)
			(end 0.12065 -0.2794)
			(stroke
				(width 0.1)
				(type default)
			)
			(layer "F.Fab")
		)
		(fp_line
			(start 0.12065 -0.2794)
			(end 0.12065 -0.3048)
			(stroke
				(width 0.1)
				(type default)
			)
			(layer "F.Fab")
		)
		(fp_line
			(start 0.12065 -0.3048)
			(end 0.67945 -0.3048)
			(stroke
				(width 0.1)
				(type default)
			)
			(layer "F.Fab")
		)
		(fp_line
			(start 0.67945 -0.3048)
			(end 0.67945 0.3048)
			(stroke
				(width 0.1)
				(type default)
			)
			(layer "F.Fab")
		)
		(fp_line
			(start -0.67945 -0.305054)
			(end -0.12065 -0.305054)
			(stroke
				(width 0.1)
				(type default)
			)
			(layer "F.Fab")
		)
		(fp_line
			(start -0.12065 -0.305054)
			(end -0.12065 -0.2794)
			(stroke
				(width 0.1)
				(type default)
			)
			(layer "F.Fab")
		)
		(pad "1" smd circle
			(at -0.40005 0 270)
			(size 0 0)
			(layers "F.Cu" "F.Mask" "F.Paste")
			(net "PWRGD_PVCCIN_CPU0")
		)
		(pad "2" smd circle
			(at 0.40005 0 270)
			(size 0 0)
			(layers "F.Cu" "F.Mask" "F.Paste")
			(net "PWRGD_PVCCIN_CPU0_R")
		)
	)
	(footprint ""
		(layer "F.Cu")
		(at 344.937588 -333.716122)
		(property "Reference" "PU13_P0_1"
			(at -2.66954 -6.20649 0)
			(unlocked yes)
			(layer "F.SilkS")
			(effects
				(font
					(size 0.7874 0.5842)
					(thickness 0.1524)
				)
				(justify left)
			)
		)
		(property "Value" ""
			(at 0 0 0)
			(layer "F.Fab")
			(effects
				(font
					(size 1.27 1.27)
				)
			)
		)
		(duplicate_pad_numbers_are_jumpers no)
		(fp_line
			(start -2.500122 -2.999994)
			(end -2.24409 -2.999994)
			(stroke
				(width 0.1524)
				(type default)
			)
			(layer "F.SilkS")
		)
		(fp_line
			(start -2.500122 -2.529078)
			(end -2.500122 -2.999994)
			(stroke
				(width 0.1524)
				(type default)
			)
			(layer "F.SilkS")
		)
		(fp_line
			(start -2.500122 0.6604)
			(end -2.500122 0.229108)
			(stroke
				(width 0.1524)
				(type default)
			)
			(layer "F.SilkS")
		)
		(fp_line
			(start -2.500122 2.999994)
			(end -2.500122 2.339594)
			(stroke
				(width 0.1524)
				(type default)
			)
			(layer "F.SilkS")
		)
		(fp_line
			(start -2.2987 2.999994)
			(end -2.500122 2.999994)
			(stroke
				(width 0.1524)
				(type default)
			)
			(layer "F.SilkS")
		)
		(fp_line
			(start 2.31394 -2.999994)
			(end 2.500122 -2.999994)
			(stroke
				(width 0.1524)
				(type default)
			)
			(layer "F.SilkS")
		)
		(fp_line
			(start 2.500122 -2.999994)
			(end 2.500122 -2.44348)
			(stroke
				(width 0.1524)
				(type default)
			)
			(layer "F.SilkS")
		)
		(fp_line
			(start 2.500122 2.339594)
			(end 2.500122 2.999994)
			(stroke
				(width 0.1524)
				(type default)
			)
			(layer "F.SilkS")
		)
		(fp_line
			(start 2.500122 2.999994)
			(end 2.2987 2.999994)
			(stroke
				(width 0.1524)
				(type default)
			)
			(layer "F.SilkS")
		)
		(fp_poly
			(pts
				(xy -2.218436 -3.60045) (xy -2.726436 -2.58445) (xy -3.234436 -3.60045)
			)
			(stroke
				(width 0)
				(type default)
			)
			(fill yes)
			(layer "F.SilkS")
		)
		(fp_line
			(start -2.500122 -2.999994)
			(end 2.500122 -2.999994)
			(stroke
				(width 0.1)
				(type default)
			)
			(layer "F.Fab")
		)
		(fp_line
			(start -2.500122 2.999994)
			(end -2.500122 -2.999994)
			(stroke
				(width 0.1)
				(type default)
			)
			(layer "F.Fab")
		)
		(fp_line
			(start 2.500122 -2.999994)
			(end 2.500122 2.999994)
			(stroke
				(width 0.1)
				(type default)
			)
			(layer "F.Fab")
		)
		(fp_line
			(start 2.500122 2.999994)
			(end -2.500122 2.999994)
			(stroke
				(width 0.1)
				(type default)
			)
			(layer "F.Fab")
		)
		(fp_poly
			(pts
				(xy -4.218432 -2.783078) (xy -4.218432 -1.767078) (xy -3.202432 -2.275078)
			)
			(stroke
				(width 0)
				(type default)
			)
			(fill yes)
			(layer "F.Fab")
		)
		(pad "1" smd rect
			(at -2.400046 -2.275078 90)
			(size 0.2286 0.6096)
			(layers "F.Cu" "F.Mask" "F.Paste")
			(net "PVCCIN_CPU0_VOS1")
		)
		(pad "2" smd rect
			(at -2.400046 -1.82499 90)
			(size 0.2286 0.6096)
			(layers "F.Cu" "F.Mask" "F.Paste")
			(net "GND")
		)
		(pad "3" smd rect
			(at -2.400046 -1.374902 90)
			(size 0.2286 0.6096)
			(layers "F.Cu" "F.Mask" "F.Paste")
			(net "PVCCIN_CPU0_VDD1")
		)
		(pad "4" smd rect
			(at -2.400046 -0.925068 90)
			(size 0.2286 0.6096)
			(layers "F.Cu" "F.Mask" "F.Paste")
			(net "PVCCIN_CPU0_PVCC")
		)
		(pad "5" smd rect
			(at -2.400046 -0.47498 90)
			(size 0.2286 0.6096)
			(layers "F.Cu" "F.Mask" "F.Paste")
			(net "GND")
		)
		(pad "6" smd rect
			(at -2.400046 -0.024892 90)
			(size 0.2286 0.6096)
			(layers "F.Cu" "F.Mask" "F.Paste")
			(net "Net_8544")
		)
		(pad "7_9-20_24" smd circle
			(at 0 1.150112 90)
			(size 0 0)
			(layers "F.Cu" "F.Mask" "F.Paste")
			(net "GND")
		)
		(pad "10_19" smd rect
			(at 0 2.899918 90)
			(size 0.6096 4.318)
			(layers "F.Cu" "F.Mask" "F.Paste")
			(net "SW_PVCCIN_CPU0_SW1")
		)
		(pad "25_29" smd rect
			(at 1.549908 -1.279906 270)
			(size 2.0574 2.3114)
			(layers "F.Cu" "F.Mask" "F.Paste")
			(net "SW_P12V_PVCCIN_CPU0_FLT")
		)
		(pad "30" smd rect
			(at 2.05994 -2.899918)
			(size 0.2286 0.6096)
			(layers "F.Cu" "F.Mask" "F.Paste")
			(net "SW_P12V_PVCCIN_CPU0_FLT")
		)
		(pad "31" smd rect
			(at 1.610106 -2.899918)
			(size 0.2286 0.6096)
			(layers "F.Cu" "F.Mask" "F.Paste")
			(net "Net_8545")
		)
		(pad "32" smd rect
			(at 1.160018 -2.899918)
			(size 0.2286 0.6096)
			(layers "F.Cu" "F.Mask" "F.Paste")
			(net "SW_PVCCIN_CPU0_BOOTR1")
		)
		(pad "33" smd rect
			(at 0.70993 -2.899918)
			(size 0.2286 0.6096)
			(layers "F.Cu" "F.Mask" "F.Paste")
			(net "SW_PVCCIN_CPU0_BOOT1")
		)
		(pad "34" smd rect
			(at 0.260096 -2.899918)
			(size 0.2286 0.6096)
			(layers "F.Cu" "F.Mask" "F.Paste")
			(net "PVCCIN_CPU0_PWM1")
		)
		(pad "35" smd rect
			(at -0.189992 -2.899918)
			(size 0.2286 0.6096)
			(layers "F.Cu" "F.Mask" "F.Paste")
			(net "PVCCIN_CPU0_VDD1")
		)
		(pad "36" smd rect
			(at -0.64008 -2.899918)
			(size 0.2286 0.6096)
			(layers "F.Cu" "F.Mask" "F.Paste")
			(net "PVCCIN_CPU0_ATSEN")
		)
		(pad "37" smd rect
			(at -1.089914 -2.899918)
			(size 0.2286 0.6096)
			(layers "F.Cu" "F.Mask" "F.Paste")
			(net "PVCCIN_CPU0_LSET1")
		)
		(pad "38" smd rect
			(at -1.540002 -2.899918)
			(size 0.2286 0.6096)
			(layers "F.Cu" "F.Mask" "F.Paste")
			(net "PVCCIN_CPU0_IMON1")
		)
		(pad "39" smd rect
			(at -1.99009 -2.899918)
			(size 0.2286 0.6096)
			(layers "F.Cu" "F.Mask" "F.Paste")
			(net "PVCCIN_CPU0_VREF")
		)
		(pad "40" smd rect
			(at -0.87503 -1.27508)
			(size 1.7526 1.9558)
			(layers "F.Cu" "F.Mask" "F.Paste")
			(net "GND")
		)
		(pad "41" smd rect
			(at -1.525016 0.249936 270)
			(size 0.3048 0.4572)
			(layers "F.Cu" "F.Mask" "F.Paste")
			(net "Net_8543")
		)
		(zone
			(layer "F.Cu")
			(hatch none 0.5)
			(connect_pads
				(clearance 0)
			)
			(min_thickness 0.25)
			(keepout
				(tracks not_allowed)
				(vias allowed)
				(pads allowed)
				(copperpour not_allowed)
				(footprints allowed)
			)
			(placement
				(enabled no)
				(sheetname "")
			)
			(fill
				(thermal_gap 0.5)
				(thermal_bridge_width 0.5)
				(island_removal_mode 0)
			)
			(polygon
				(pts
					(xy 342.437466 -330.716128) (xy 342.437466 -331.465428) (xy 347.43771 -331.465428) (xy 347.43771 -330.716128)
					(xy 347.147388 -330.716128) (xy 347.147388 -331.171804) (xy 342.727788 -331.171804) (xy 342.727788 -330.716128)
				)
			)
		)
		(zone
			(layer "F.Cu")
			(hatch none 0.5)
			(connect_pads
				(clearance 0)
			)
			(min_thickness 0.25)
			(keepout
				(tracks not_allowed)
				(vias allowed)
				(pads allowed)
				(copperpour not_allowed)
				(footprints allowed)
			)
			(placement
				(enabled no)
				(sheetname "")
			)
			(fill
				(thermal_gap 0.5)
				(thermal_bridge_width 0.5)
				(island_removal_mode 0)
			)
			(polygon
				(pts
					(xy 343.691972 -333.634588) (xy 343.986866 -333.634588) (xy 343.986866 -332.966822) (xy 342.437466 -332.966822)
					(xy 342.437466 -333.423514) (xy 343.133172 -333.423514) (xy 343.133172 -333.262986) (xy 343.691972 -333.262986)
				)
			)
		)
	)
	(footprint ""
		(layer "F.Cu")
		(at 68.212462 -40.437562)
		(property "Reference" "R3608"
			(at 0 0 0)
			(layer "F.SilkS")
			(hide yes)
			(effects
				(font
					(size 1.27 1.27)
				)
			)
		)
		(property "Value" ""
			(at 0 0 0)
			(layer "F.Fab")
			(effects
				(font
					(size 1.27 1.27)
				)
			)
		)
		(duplicate_pad_numbers_are_jumpers no)
		(fp_line
			(start -0.7874 -0.4064)
			(end 0.7874 -0.4064)
			(stroke
				(width 0.1524)
				(type default)
			)
			(layer "F.SilkS")
		)
		(fp_line
			(start -0.7874 0.4064)
			(end -0.7874 -0.4064)
			(stroke
				(width 0.1524)
				(type default)
			)
			(layer "F.SilkS")
		)
		(fp_line
			(start 0.7874 -0.4064)
			(end 0.7874 0.4064)
			(stroke
				(width 0.1524)
				(type default)
			)
			(layer "F.SilkS")
		)
		(fp_line
			(start 0.7874 0.4064)
			(end -0.7874 0.4064)
			(stroke
				(width 0.1524)
				(type default)
			)
			(layer "F.SilkS")
		)
		(fp_line
			(start -0.67945 -0.305054)
			(end -0.12065 -0.305054)
			(stroke
				(width 0.1)
				(type default)
			)
			(layer "F.Fab")
		)
		(fp_line
			(start -0.67945 0.3048)
			(end -0.67945 -0.305054)
			(stroke
				(width 0.1)
				(type default)
			)
			(layer "F.Fab")
		)
		(fp_line
			(start -0.12065 -0.305054)
			(end -0.12065 -0.2794)
			(stroke
				(width 0.1)
				(type default)
			)
			(layer "F.Fab")
		)
		(fp_line
			(start -0.12065 -0.2794)
			(end 0.12065 -0.2794)
			(stroke
				(width 0.1)
				(type default)
			)
			(layer "F.Fab")
		)
		(fp_line
			(start -0.12065 0.2794)
			(end -0.12065 0.3048)
			(stroke
				(width 0.1)
				(type default)
			)
			(layer "F.Fab")
		)
		(fp_line
			(start -0.12065 0.3048)
			(end -0.67945 0.3048)
			(stroke
				(width 0.1)
				(type default)
			)
			(layer "F.Fab")
		)
		(fp_line
			(start 0.120396 0.2794)
			(end -0.12065 0.2794)
			(stroke
				(width 0.1)
				(type default)
			)
			(layer "F.Fab")
		)
		(fp_line
			(start 0.120396 0.3048)
			(end 0.120396 0.2794)
			(stroke
				(width 0.1)
				(type default)
			)
			(layer "F.Fab")
		)
		(fp_line
			(start 0.12065 -0.3048)
			(end 0.67945 -0.3048)
			(stroke
				(width 0.1)
				(type default)
			)
			(layer "F.Fab")
		)
		(fp_line
			(start 0.12065 -0.2794)
			(end 0.12065 -0.3048)
			(stroke
				(width 0.1)
				(type default)
			)
			(layer "F.Fab")
		)
		(fp_line
			(start 0.67945 -0.3048)
			(end 0.67945 0.3048)
			(stroke
				(width 0.1)
				(type default)
			)
			(layer "F.Fab")
		)
		(fp_line
			(start 0.67945 0.3048)
			(end 0.120396 0.3048)
			(stroke
				(width 0.1)
				(type default)
			)
			(layer "F.Fab")
		)
		(pad "1" smd circle
			(at -0.40005 0)
			(size 0 0)
			(layers "F.Cu" "F.Mask" "F.Paste")
			(net "GND")
		)
		(pad "2" smd circle
			(at 0.40005 0)
			(size 0 0)
			(layers "F.Cu" "F.Mask" "F.Paste")
			(net "INA230_3_A1")
		)
	)
	(footprint ""
		(layer "F.Cu")
		(at 128.3843 -21.951188)
		(property "Reference" "R367"
			(at 0 0 0)
			(layer "F.SilkS")
			(hide yes)
			(effects
				(font
					(size 1.27 1.27)
				)
			)
		)
		(property "Value" ""
			(at 0 0 0)
			(layer "F.Fab")
			(effects
				(font
					(size 1.27 1.27)
				)
			)
		)
		(duplicate_pad_numbers_are_jumpers no)
		(fp_line
			(start -0.7874 -0.4064)
			(end 0.7874 -0.4064)
			(stroke
				(width 0.1524)
				(type default)
			)
			(layer "F.SilkS")
		)
		(fp_line
			(start -0.7874 0.4064)
			(end -0.7874 -0.4064)
			(stroke
				(width 0.1524)
				(type default)
			)
			(layer "F.SilkS")
		)
		(fp_line
			(start 0.7874 -0.4064)
			(end 0.7874 0.4064)
			(stroke
				(width 0.1524)
				(type default)
			)
			(layer "F.SilkS")
		)
		(fp_line
			(start 0.7874 0.4064)
			(end -0.7874 0.4064)
			(stroke
				(width 0.1524)
				(type default)
			)
			(layer "F.SilkS")
		)
		(fp_line
			(start -0.67945 -0.305054)
			(end -0.12065 -0.305054)
			(stroke
				(width 0.1)
				(type default)
			)
			(layer "F.Fab")
		)
		(fp_line
			(start -0.67945 0.3048)
			(end -0.67945 -0.305054)
			(stroke
				(width 0.1)
				(type default)
			)
			(layer "F.Fab")
		)
		(fp_line
			(start -0.12065 -0.305054)
			(end -0.12065 -0.2794)
			(stroke
				(width 0.1)
				(type default)
			)
			(layer "F.Fab")
		)
		(fp_line
			(start -0.12065 -0.2794)
			(end 0.12065 -0.2794)
			(stroke
				(width 0.1)
				(type default)
			)
			(layer "F.Fab")
		)
		(fp_line
			(start -0.12065 0.2794)
			(end -0.12065 0.3048)
			(stroke
				(width 0.1)
				(type default)
			)
			(layer "F.Fab")
		)
		(fp_line
			(start -0.12065 0.3048)
			(end -0.67945 0.3048)
			(stroke
				(width 0.1)
				(type default)
			)
			(layer "F.Fab")
		)
		(fp_line
			(start 0.120396 0.2794)
			(end -0.12065 0.2794)
			(stroke
				(width 0.1)
				(type default)
			)
			(layer "F.Fab")
		)
		(fp_line
			(start 0.120396 0.3048)
			(end 0.120396 0.2794)
			(stroke
				(width 0.1)
				(type default)
			)
			(layer "F.Fab")
		)
		(fp_line
			(start 0.12065 -0.3048)
			(end 0.67945 -0.3048)
			(stroke
				(width 0.1)
				(type default)
			)
			(layer "F.Fab")
		)
		(fp_line
			(start 0.12065 -0.2794)
			(end 0.12065 -0.3048)
			(stroke
				(width 0.1)
				(type default)
			)
			(layer "F.Fab")
		)
		(fp_line
			(start 0.67945 -0.3048)
			(end 0.67945 0.3048)
			(stroke
				(width 0.1)
				(type default)
			)
			(layer "F.Fab")
		)
		(fp_line
			(start 0.67945 0.3048)
			(end 0.120396 0.3048)
			(stroke
				(width 0.1)
				(type default)
			)
			(layer "F.Fab")
		)
		(pad "1" smd circle
			(at -0.40005 0)
			(size 0 0)
			(layers "F.Cu" "F.Mask" "F.Paste")
			(net "P3V3_AUX")
		)
		(pad "2" smd circle
			(at 0.40005 0)
			(size 0 0)
			(layers "F.Cu" "F.Mask" "F.Paste")
			(net "FM_PCH_SPKR")
		)
	)
	(footprint ""
		(layer "F.Cu")
		(at 320.190622 -55.235348)
		(property "Reference" "R401"
			(at 0 0 0)
			(layer "F.SilkS")
			(hide yes)
			(effects
				(font
					(size 1.27 1.27)
				)
			)
		)
		(property "Value" ""
			(at 0 0 0)
			(layer "F.Fab")
			(effects
				(font
					(size 1.27 1.27)
				)
			)
		)
		(duplicate_pad_numbers_are_jumpers no)
		(fp_line
			(start -0.7874 -0.4064)
			(end 0.7874 -0.4064)
			(stroke
				(width 0.1524)
				(type default)
			)
			(layer "F.SilkS")
		)
		(fp_line
			(start -0.7874 0.4064)
			(end -0.7874 -0.4064)
			(stroke
				(width 0.1524)
				(type default)
			)
			(layer "F.SilkS")
		)
		(fp_line
			(start 0.7874 -0.4064)
			(end 0.7874 0.4064)
			(stroke
				(width 0.1524)
				(type default)
			)
			(layer "F.SilkS")
		)
		(fp_line
			(start 0.7874 0.4064)
			(end -0.7874 0.4064)
			(stroke
				(width 0.1524)
				(type default)
			)
			(layer "F.SilkS")
		)
		(fp_line
			(start -0.67945 -0.305054)
			(end -0.12065 -0.305054)
			(stroke
				(width 0.1)
				(type default)
			)
			(layer "F.Fab")
		)
		(fp_line
			(start -0.67945 0.3048)
			(end -0.67945 -0.305054)
			(stroke
				(width 0.1)
				(type default)
			)
			(layer "F.Fab")
		)
		(fp_line
			(start -0.12065 -0.305054)
			(end -0.12065 -0.2794)
			(stroke
				(width 0.1)
				(type default)
			)
			(layer "F.Fab")
		)
		(fp_line
			(start -0.12065 -0.2794)
			(end 0.12065 -0.2794)
			(stroke
				(width 0.1)
				(type default)
			)
			(layer "F.Fab")
		)
		(fp_line
			(start -0.12065 0.2794)
			(end -0.12065 0.3048)
			(stroke
				(width 0.1)
				(type default)
			)
			(layer "F.Fab")
		)
		(fp_line
			(start -0.12065 0.3048)
			(end -0.67945 0.3048)
			(stroke
				(width 0.1)
				(type default)
			)
			(layer "F.Fab")
		)
		(fp_line
			(start 0.120396 0.2794)
			(end -0.12065 0.2794)
			(stroke
				(width 0.1)
				(type default)
			)
			(layer "F.Fab")
		)
		(fp_line
			(start 0.120396 0.3048)
			(end 0.120396 0.2794)
			(stroke
				(width 0.1)
				(type default)
			)
			(layer "F.Fab")
		)
		(fp_line
			(start 0.12065 -0.3048)
			(end 0.67945 -0.3048)
			(stroke
				(width 0.1)
				(type default)
			)
			(layer "F.Fab")
		)
		(fp_line
			(start 0.12065 -0.2794)
			(end 0.12065 -0.3048)
			(stroke
				(width 0.1)
				(type default)
			)
			(layer "F.Fab")
		)
		(fp_line
			(start 0.67945 -0.3048)
			(end 0.67945 0.3048)
			(stroke
				(width 0.1)
				(type default)
			)
			(layer "F.Fab")
		)
		(fp_line
			(start 0.67945 0.3048)
			(end 0.120396 0.3048)
			(stroke
				(width 0.1)
				(type default)
			)
			(layer "F.Fab")
		)
		(pad "1" smd circle
			(at -0.40005 0)
			(size 0 0)
			(layers "F.Cu" "F.Mask" "F.Paste")
			(net "P3V3_AUX")
		)
		(pad "2" smd circle
			(at 0.40005 0)
			(size 0 0)
			(layers "F.Cu" "F.Mask" "F.Paste")
			(net "IRQ_TPM_SPI_N")
		)
	)
	(footprint ""
		(layer "F.Cu")
		(at 121.521982 -324.445376)
		(property "Reference" "PL28"
			(at 7.738618 5.508498 0)
			(unlocked yes)
			(layer "F.SilkS")
			(effects
				(font
					(size 0.7874 0.5842)
					(thickness 0.1524)
				)
				(justify left)
			)
		)
		(property "Value" ""
			(at 0 0 0)
			(layer "F.Fab")
			(effects
				(font
					(size 1.27 1.27)
				)
			)
		)
		(duplicate_pad_numbers_are_jumpers no)
		(fp_line
			(start -3.750056 -5.500116)
			(end -2.393442 -5.500116)
			(stroke
				(width 0.1524)
				(type default)
			)
			(layer "F.SilkS")
		)
		(fp_line
			(start -3.750056 5.500116)
			(end -3.750056 -5.500116)
			(stroke
				(width 0.1524)
				(type default)
			)
			(layer "F.SilkS")
		)
		(fp_line
			(start -2.393442 5.500116)
			(end -3.750056 5.500116)
			(stroke
				(width 0.1524)
				(type default)
			)
			(layer "F.SilkS")
		)
		(fp_line
			(start 2.393442 5.500116)
			(end 3.750056 5.500116)
			(stroke
				(width 0.1524)
				(type default)
			)
			(layer "F.SilkS")
		)
		(fp_line
			(start 3.750056 -5.500116)
			(end 2.393442 -5.500116)
			(stroke
				(width 0.1524)
				(type default)
			)
			(layer "F.SilkS")
		)
		(fp_line
			(start 3.750056 5.500116)
			(end 3.750056 -5.500116)
			(stroke
				(width 0.1524)
				(type default)
			)
			(layer "F.SilkS")
		)
		(fp_poly
			(pts
				(xy -3.575304 -7.087362) (xy -3.216148 -6.00964) (xy -4.29387 -6.36905)
			)
			(stroke
				(width 0)
				(type default)
			)
			(fill yes)
			(layer "F.SilkS")
		)
		(fp_line
			(start -3.750056 -5.500116)
			(end -3.750056 5.500116)
			(stroke
				(width 0.1)
				(type default)
			)
			(layer "F.Fab")
		)
		(fp_line
			(start -3.750056 5.500116)
			(end 3.750056 5.500116)
			(stroke
				(width 0.1)
				(type default)
			)
			(layer "F.Fab")
		)
		(fp_line
			(start 3.750056 -5.500116)
			(end -3.750056 -5.500116)
			(stroke
				(width 0.1)
				(type default)
			)
			(layer "F.Fab")
		)
		(fp_line
			(start 3.750056 5.500116)
			(end 3.750056 -5.500116)
			(stroke
				(width 0.1)
				(type default)
			)
			(layer "F.Fab")
		)
		(fp_poly
			(pts
				(xy -4.9276 -4.757928) (xy -4.9276 -3.741928) (xy -3.9116 -4.249928)
			)
			(stroke
				(width 0)
				(type default)
			)
			(fill yes)
			(layer "F.Fab")
		)
		(pad "1" smd rect
			(at 0 -4.249928 270)
			(size 2.413 4.5212)
			(layers "F.Cu" "F.Mask" "F.Paste")
			(net "SW_PVCCIN_CPU1_SW4")
		)
		(pad "2" smd rect
			(at 0 -1.175004 270)
			(size 1.3716 4.5212)
			(layers "F.Cu" "F.Mask" "F.Paste")
			(net "IND_P1_CPL4")
		)
		(pad "3" smd rect
			(at 0 1.175004 270)
			(size 1.3716 4.5212)
			(layers "F.Cu" "F.Mask" "F.Paste")
			(net "IND_P1_CPL3")
		)
		(pad "4" smd rect
			(at 0 4.249928 270)
			(size 2.413 4.5212)
			(layers "F.Cu" "F.Mask" "F.Paste")
			(net "PVCCIN_CPU1")
		)
	)
	(footprint ""
		(layer "F.Cu")
		(at 216.065608 -408.887422)
		(property "Reference" "PR3988"
			(at 0 0 0)
			(layer "F.SilkS")
			(hide yes)
			(effects
				(font
					(size 1.27 1.27)
				)
			)
		)
		(property "Value" ""
			(at 0 0 0)
			(layer "F.Fab")
			(effects
				(font
					(size 1.27 1.27)
				)
			)
		)
		(duplicate_pad_numbers_are_jumpers no)
		(fp_line
			(start -0.7874 -0.4064)
			(end 0.7874 -0.4064)
			(stroke
				(width 0.1524)
				(type default)
			)
			(layer "F.SilkS")
		)
		(fp_line
			(start -0.7874 0.4064)
			(end -0.7874 -0.4064)
			(stroke
				(width 0.1524)
				(type default)
			)
			(layer "F.SilkS")
		)
		(fp_line
			(start 0.7874 -0.4064)
			(end 0.7874 0.4064)
			(stroke
				(width 0.1524)
				(type default)
			)
			(layer "F.SilkS")
		)
		(fp_line
			(start 0.7874 0.4064)
			(end -0.7874 0.4064)
			(stroke
				(width 0.1524)
				(type default)
			)
			(layer "F.SilkS")
		)
		(fp_line
			(start -0.67945 -0.305054)
			(end -0.12065 -0.305054)
			(stroke
				(width 0.1)
				(type default)
			)
			(layer "F.Fab")
		)
		(fp_line
			(start -0.67945 0.3048)
			(end -0.67945 -0.305054)
			(stroke
				(width 0.1)
				(type default)
			)
			(layer "F.Fab")
		)
		(fp_line
			(start -0.12065 -0.305054)
			(end -0.12065 -0.2794)
			(stroke
				(width 0.1)
				(type default)
			)
			(layer "F.Fab")
		)
		(fp_line
			(start -0.12065 -0.2794)
			(end 0.12065 -0.2794)
			(stroke
				(width 0.1)
				(type default)
			)
			(layer "F.Fab")
		)
		(fp_line
			(start -0.12065 0.2794)
			(end -0.12065 0.3048)
			(stroke
				(width 0.1)
				(type default)
			)
			(layer "F.Fab")
		)
		(fp_line
			(start -0.12065 0.3048)
			(end -0.67945 0.3048)
			(stroke
				(width 0.1)
				(type default)
			)
			(layer "F.Fab")
		)
		(fp_line
			(start 0.120396 0.2794)
			(end -0.12065 0.2794)
			(stroke
				(width 0.1)
				(type default)
			)
			(layer "F.Fab")
		)
		(fp_line
			(start 0.120396 0.3048)
			(end 0.120396 0.2794)
			(stroke
				(width 0.1)
				(type default)
			)
			(layer "F.Fab")
		)
		(fp_line
			(start 0.12065 -0.3048)
			(end 0.67945 -0.3048)
			(stroke
				(width 0.1)
				(type default)
			)
			(layer "F.Fab")
		)
		(fp_line
			(start 0.12065 -0.2794)
			(end 0.12065 -0.3048)
			(stroke
				(width 0.1)
				(type default)
			)
			(layer "F.Fab")
		)
		(fp_line
			(start 0.67945 -0.3048)
			(end 0.67945 0.3048)
			(stroke
				(width 0.1)
				(type default)
			)
			(layer "F.Fab")
		)
		(fp_line
			(start 0.67945 0.3048)
			(end 0.120396 0.3048)
			(stroke
				(width 0.1)
				(type default)
			)
			(layer "F.Fab")
		)
		(pad "1" smd circle
			(at -0.40005 0)
			(size 0 0)
			(layers "F.Cu" "F.Mask" "F.Paste")
			(net "HSC_SCREF")
		)
		(pad "2" smd circle
			(at 0.40005 0)
			(size 0 0)
			(layers "F.Cu" "F.Mask" "F.Paste")
			(net "HSC_SCREF_3")
		)
	)
	(footprint ""
		(layer "F.Cu")
		(at 388.025132 -38.265354 180)
		(property "Reference" "C580"
			(at 0 0 180)
			(layer "F.SilkS")
			(hide yes)
			(effects
				(font
					(size 1.27 1.27)
				)
			)
		)
		(property "Value" ""
			(at 0 0 180)
			(layer "F.Fab")
			(effects
				(font
					(size 1.27 1.27)
				)
			)
		)
		(duplicate_pad_numbers_are_jumpers no)
		(fp_line
			(start 0.7874 0.4064)
			(end -0.7874 0.4064)
			(stroke
				(width 0.1524)
				(type default)
			)
			(layer "F.SilkS")
		)
		(fp_line
			(start 0.7874 -0.4064)
			(end 0.7874 0.4064)
			(stroke
				(width 0.1524)
				(type default)
			)
			(layer "F.SilkS")
		)
		(fp_line
			(start -0.7874 0.4064)
			(end -0.7874 -0.4064)
			(stroke
				(width 0.1524)
				(type default)
			)
			(layer "F.SilkS")
		)
		(fp_line
			(start -0.7874 -0.4064)
			(end 0.7874 -0.4064)
			(stroke
				(width 0.1524)
				(type default)
			)
			(layer "F.SilkS")
		)
		(fp_line
			(start 0.67945 0.3048)
			(end 0.120396 0.3048)
			(stroke
				(width 0.1)
				(type default)
			)
			(layer "F.Fab")
		)
		(fp_line
			(start 0.67945 -0.3048)
			(end 0.67945 0.3048)
			(stroke
				(width 0.1)
				(type default)
			)
			(layer "F.Fab")
		)
		(fp_line
			(start 0.12065 -0.2794)
			(end 0.12065 -0.3048)
			(stroke
				(width 0.1)
				(type default)
			)
			(layer "F.Fab")
		)
		(fp_line
			(start 0.12065 -0.3048)
			(end 0.67945 -0.3048)
			(stroke
				(width 0.1)
				(type default)
			)
			(layer "F.Fab")
		)
		(fp_line
			(start 0.120396 0.3048)
			(end 0.120396 0.2794)
			(stroke
				(width 0.1)
				(type default)
			)
			(layer "F.Fab")
		)
		(fp_line
			(start 0.120396 0.2794)
			(end -0.12065 0.2794)
			(stroke
				(width 0.1)
				(type default)
			)
			(layer "F.Fab")
		)
		(fp_line
			(start -0.12065 0.3048)
			(end -0.67945 0.3048)
			(stroke
				(width 0.1)
				(type default)
			)
			(layer "F.Fab")
		)
		(fp_line
			(start -0.12065 0.2794)
			(end -0.12065 0.3048)
			(stroke
				(width 0.1)
				(type default)
			)
			(layer "F.Fab")
		)
		(fp_line
			(start -0.12065 -0.2794)
			(end 0.12065 -0.2794)
			(stroke
				(width 0.1)
				(type default)
			)
			(layer "F.Fab")
		)
		(fp_line
			(start -0.12065 -0.305054)
			(end -0.12065 -0.2794)
			(stroke
				(width 0.1)
				(type default)
			)
			(layer "F.Fab")
		)
		(fp_line
			(start -0.67945 0.3048)
			(end -0.67945 -0.305054)
			(stroke
				(width 0.1)
				(type default)
			)
			(layer "F.Fab")
		)
		(fp_line
			(start -0.67945 -0.305054)
			(end -0.12065 -0.305054)
			(stroke
				(width 0.1)
				(type default)
			)
			(layer "F.Fab")
		)
		(pad "1" smd circle
			(at -0.40005 0 180)
			(size 0 0)
			(layers "F.Cu" "F.Mask" "F.Paste")
			(net "P3V3_OCP_SFF")
		)
		(pad "2" smd circle
			(at 0.40005 0 180)
			(size 0 0)
			(layers "F.Cu" "F.Mask" "F.Paste")
			(net "GND")
		)
	)
	(footprint ""
		(layer "F.Cu")
		(at 366.48263 -260.364986 -90)
		(property "Reference" "C402"
			(at 0 0 270)
			(layer "F.SilkS")
			(hide yes)
			(effects
				(font
					(size 1.27 1.27)
				)
			)
		)
		(property "Value" ""
			(at 0 0 270)
			(layer "F.Fab")
			(effects
				(font
					(size 1.27 1.27)
				)
			)
		)
		(duplicate_pad_numbers_are_jumpers no)
		(fp_line
			(start -0.7874 0.4064)
			(end -0.7874 -0.4064)
			(stroke
				(width 0.1524)
				(type default)
			)
			(layer "F.SilkS")
		)
		(fp_line
			(start 0.7874 0.4064)
			(end -0.7874 0.4064)
			(stroke
				(width 0.1524)
				(type default)
			)
			(layer "F.SilkS")
		)
		(fp_line
			(start -0.7874 -0.4064)
			(end 0.7874 -0.4064)
			(stroke
				(width 0.1524)
				(type default)
			)
			(layer "F.SilkS")
		)
		(fp_line
			(start 0.7874 -0.4064)
			(end 0.7874 0.4064)
			(stroke
				(width 0.1524)
				(type default)
			)
			(layer "F.SilkS")
		)
		(fp_line
			(start -0.67945 0.3048)
			(end -0.67945 -0.305054)
			(stroke
				(width 0.1)
				(type default)
			)
			(layer "F.Fab")
		)
		(fp_line
			(start -0.12065 0.3048)
			(end -0.67945 0.3048)
			(stroke
				(width 0.1)
				(type default)
			)
			(layer "F.Fab")
		)
		(fp_line
			(start 0.120396 0.3048)
			(end 0.120396 0.2794)
			(stroke
				(width 0.1)
				(type default)
			)
			(layer "F.Fab")
		)
		(fp_line
			(start 0.67945 0.3048)
			(end 0.120396 0.3048)
			(stroke
				(width 0.1)
				(type default)
			)
			(layer "F.Fab")
		)
		(fp_line
			(start -0.12065 0.2794)
			(end -0.12065 0.3048)
			(stroke
				(width 0.1)
				(type default)
			)
			(layer "F.Fab")
		)
		(fp_line
			(start 0.120396 0.2794)
			(end -0.12065 0.2794)
			(stroke
				(width 0.1)
				(type default)
			)
			(layer "F.Fab")
		)
		(fp_line
			(start -0.12065 -0.2794)
			(end 0.12065 -0.2794)
			(stroke
				(width 0.1)
				(type default)
			)
			(layer "F.Fab")
		)
		(fp_line
			(start 0.12065 -0.2794)
			(end 0.12065 -0.3048)
			(stroke
				(width 0.1)
				(type default)
			)
			(layer "F.Fab")
		)
		(fp_line
			(start 0.12065 -0.3048)
			(end 0.67945 -0.3048)
			(stroke
				(width 0.1)
				(type default)
			)
			(layer "F.Fab")
		)
		(fp_line
			(start 0.67945 -0.3048)
			(end 0.67945 0.3048)
			(stroke
				(width 0.1)
				(type default)
			)
			(layer "F.Fab")
		)
		(fp_line
			(start -0.67945 -0.305054)
			(end -0.12065 -0.305054)
			(stroke
				(width 0.1)
				(type default)
			)
			(layer "F.Fab")
		)
		(fp_line
			(start -0.12065 -0.305054)
			(end -0.12065 -0.2794)
			(stroke
				(width 0.1)
				(type default)
			)
			(layer "F.Fab")
		)
		(pad "1" smd circle
			(at -0.40005 0 270)
			(size 0 0)
			(layers "F.Cu" "F.Mask" "F.Paste")
			(net "PVCCFA_EHV_FIVRA_CPU0")
		)
		(pad "2" smd circle
			(at 0.40005 0 270)
			(size 0 0)
			(layers "F.Cu" "F.Mask" "F.Paste")
			(net "GND")
		)
	)
	(footprint ""
		(layer "F.Cu")
		(at 312.443622 -39.868348 180)
		(property "Reference" "R1583"
			(at 0 0 180)
			(layer "F.SilkS")
			(hide yes)
			(effects
				(font
					(size 1.27 1.27)
				)
			)
		)
		(property "Value" ""
			(at 0 0 180)
			(layer "F.Fab")
			(effects
				(font
					(size 1.27 1.27)
				)
			)
		)
		(duplicate_pad_numbers_are_jumpers no)
		(fp_line
			(start 0.7874 0.4064)
			(end -0.7874 0.4064)
			(stroke
				(width 0.1524)
				(type default)
			)
			(layer "F.SilkS")
		)
		(fp_line
			(start 0.7874 -0.4064)
			(end 0.7874 0.4064)
			(stroke
				(width 0.1524)
				(type default)
			)
			(layer "F.SilkS")
		)
		(fp_line
			(start -0.7874 0.4064)
			(end -0.7874 -0.4064)
			(stroke
				(width 0.1524)
				(type default)
			)
			(layer "F.SilkS")
		)
		(fp_line
			(start -0.7874 -0.4064)
			(end 0.7874 -0.4064)
			(stroke
				(width 0.1524)
				(type default)
			)
			(layer "F.SilkS")
		)
		(fp_line
			(start 0.67945 0.3048)
			(end 0.120396 0.3048)
			(stroke
				(width 0.1)
				(type default)
			)
			(layer "F.Fab")
		)
		(fp_line
			(start 0.67945 -0.3048)
			(end 0.67945 0.3048)
			(stroke
				(width 0.1)
				(type default)
			)
			(layer "F.Fab")
		)
		(fp_line
			(start 0.12065 -0.2794)
			(end 0.12065 -0.3048)
			(stroke
				(width 0.1)
				(type default)
			)
			(layer "F.Fab")
		)
		(fp_line
			(start 0.12065 -0.3048)
			(end 0.67945 -0.3048)
			(stroke
				(width 0.1)
				(type default)
			)
			(layer "F.Fab")
		)
		(fp_line
			(start 0.120396 0.3048)
			(end 0.120396 0.2794)
			(stroke
				(width 0.1)
				(type default)
			)
			(layer "F.Fab")
		)
		(fp_line
			(start 0.120396 0.2794)
			(end -0.12065 0.2794)
			(stroke
				(width 0.1)
				(type default)
			)
			(layer "F.Fab")
		)
		(fp_line
			(start -0.12065 0.3048)
			(end -0.67945 0.3048)
			(stroke
				(width 0.1)
				(type default)
			)
			(layer "F.Fab")
		)
		(fp_line
			(start -0.12065 0.2794)
			(end -0.12065 0.3048)
			(stroke
				(width 0.1)
				(type default)
			)
			(layer "F.Fab")
		)
		(fp_line
			(start -0.12065 -0.2794)
			(end 0.12065 -0.2794)
			(stroke
				(width 0.1)
				(type default)
			)
			(layer "F.Fab")
		)
		(fp_line
			(start -0.12065 -0.305054)
			(end -0.12065 -0.2794)
			(stroke
				(width 0.1)
				(type default)
			)
			(layer "F.Fab")
		)
		(fp_line
			(start -0.67945 0.3048)
			(end -0.67945 -0.305054)
			(stroke
				(width 0.1)
				(type default)
			)
			(layer "F.Fab")
		)
		(fp_line
			(start -0.67945 -0.305054)
			(end -0.12065 -0.305054)
			(stroke
				(width 0.1)
				(type default)
			)
			(layer "F.Fab")
		)
		(pad "1" smd circle
			(at -0.40005 0 180)
			(size 0 0)
			(layers "F.Cu" "F.Mask" "F.Paste")
			(net "PU_PCH_PLD_3V3AUX_ALERT_N")
		)
		(pad "2" smd circle
			(at 0.40005 0 180)
			(size 0 0)
			(layers "F.Cu" "F.Mask" "F.Paste")
			(net "P3V3_AUX")
		)
	)
	(footprint ""
		(layer "F.Cu")
		(at 79.691738 -147.677632)
		(property "Reference" "U14"
			(at 3.05308 3.23469 0)
			(unlocked yes)
			(layer "F.SilkS")
			(effects
				(font
					(size 0.7874 0.5842)
					(thickness 0.1524)
				)
				(justify left)
			)
		)
		(property "Value" ""
			(at 0 0 0)
			(layer "F.Fab")
			(effects
				(font
					(size 1.27 1.27)
				)
			)
		)
		(duplicate_pad_numbers_are_jumpers no)
		(fp_line
			(start -1.7272 -2.489962)
			(end -0.779018 -2.489962)
			(stroke
				(width 0.1524)
				(type default)
			)
			(layer "F.SilkS")
		)
		(fp_line
			(start -1.7272 2.489962)
			(end -1.7272 -2.489962)
			(stroke
				(width 0.1524)
				(type default)
			)
			(layer "F.SilkS")
		)
		(fp_line
			(start -0.779018 -2.489962)
			(end 0 -1.710944)
			(stroke
				(width 0.1524)
				(type default)
			)
			(layer "F.SilkS")
		)
		(fp_line
			(start 0 -1.710944)
			(end 0.779018 -2.489962)
			(stroke
				(width 0.1524)
				(type default)
			)
			(layer "F.SilkS")
		)
		(fp_line
			(start 0.779018 -2.489962)
			(end 1.7272 -2.489962)
			(stroke
				(width 0.1524)
				(type default)
			)
			(layer "F.SilkS")
		)
		(fp_line
			(start 1.7272 -2.489962)
			(end 1.7272 2.489962)
			(stroke
				(width 0.1524)
				(type default)
			)
			(layer "F.SilkS")
		)
		(fp_line
			(start 1.7272 2.489962)
			(end -1.7272 2.489962)
			(stroke
				(width 0.1524)
				(type default)
			)
			(layer "F.SilkS")
		)
		(fp_poly
			(pts
				(xy -3.821176 -2.2225) (xy -4.837176 -1.7145) (xy -4.837176 -2.7305)
			)
			(stroke
				(width 0)
				(type default)
			)
			(fill yes)
			(layer "F.SilkS")
		)
		(fp_line
			(start -1.994916 -2.489962)
			(end 1.994916 -2.489962)
			(stroke
				(width 0.1)
				(type default)
			)
			(layer "F.Fab")
		)
		(fp_line
			(start -1.994916 2.489962)
			(end -1.994916 -2.489962)
			(stroke
				(width 0.1)
				(type default)
			)
			(layer "F.Fab")
		)
		(fp_line
			(start 1.994916 -2.489962)
			(end 1.994916 2.489962)
			(stroke
				(width 0.1)
				(type default)
			)
			(layer "F.Fab")
		)
		(fp_line
			(start 1.994916 2.489962)
			(end -1.994916 2.489962)
			(stroke
				(width 0.1)
				(type default)
			)
			(layer "F.Fab")
		)
		(fp_poly
			(pts
				(xy -4.837176 -2.7305) (xy -4.837176 -1.7145) (xy -3.821176 -2.2225)
			)
			(stroke
				(width 0)
				(type default)
			)
			(fill yes)
			(layer "F.Fab")
		)
		(pad "1" smd rect
			(at -2.6924 -2.2225 270)
			(size 0.4318 1.6764)
			(layers "F.Cu" "F.Mask" "F.Paste")
			(net "FM_SPD_REMOTE_EN")
		)
		(pad "2" smd rect
			(at -2.6924 -1.5875 270)
			(size 0.4318 1.6764)
			(layers "F.Cu" "F.Mask" "F.Paste")
			(net "I3C_SPD_DDRABCD_CPU1_R_SCL")
		)
		(pad "3" smd rect
			(at -2.6924 -0.9525 270)
			(size 0.4318 1.6764)
			(layers "F.Cu" "F.Mask" "F.Paste")
			(net "I3C_SPD_DDRABCD_CPU1_BMC_SCL")
		)
		(pad "4" smd rect
			(at -2.6924 -0.3175 270)
			(size 0.4318 1.6764)
			(layers "F.Cu" "F.Mask" "F.Paste")
			(net "I3C_SPD_DDRABCD_CPU1_LVC1_R_SCL")
		)
		(pad "5" smd rect
			(at -2.6924 0.3175 270)
			(size 0.4318 1.6764)
			(layers "F.Cu" "F.Mask" "F.Paste")
			(net "I3C_SPD_DDRABCD_CPU1_R_SDA")
		)
		(pad "6" smd rect
			(at -2.6924 0.9525 270)
			(size 0.4318 1.6764)
			(layers "F.Cu" "F.Mask" "F.Paste")
			(net "I3C_SPD_DDRABCD_CPU1_BMC_SDA")
		)
		(pad "7" smd rect
			(at -2.6924 1.5875 270)
			(size 0.4318 1.6764)
			(layers "F.Cu" "F.Mask" "F.Paste")
			(net "I3C_SPD_DDRABCD_CPU1_LVC1_R_SDA")
		)
		(pad "8" smd rect
			(at -2.6924 2.2225 270)
			(size 0.4318 1.6764)
			(layers "F.Cu" "F.Mask" "F.Paste")
			(net "GND")
		)
		(pad "9" smd rect
			(at 2.6924 2.2225 270)
			(size 0.4318 1.6764)
			(layers "F.Cu" "F.Mask" "F.Paste")
			(net "I3C_SPD_DDREFGH_CPU1_LVC1_R_SCL")
		)
		(pad "10" smd rect
			(at 2.6924 1.5875 270)
			(size 0.4318 1.6764)
			(layers "F.Cu" "F.Mask" "F.Paste")
			(net "I3C_SPD_DDREFGH_CPU1_BMC_SCL")
		)
		(pad "11" smd rect
			(at 2.6924 0.9525 270)
			(size 0.4318 1.6764)
			(layers "F.Cu" "F.Mask" "F.Paste")
			(net "I3C_SPD_DDREFGH_CPU1_R_SCL")
		)
		(pad "12" smd rect
			(at 2.6924 0.3175 270)
			(size 0.4318 1.6764)
			(layers "F.Cu" "F.Mask" "F.Paste")
			(net "I3C_SPD_DDREFGH_CPU1_LVC1_R_SDA")
		)
		(pad "13" smd rect
			(at 2.6924 -0.3175 270)
			(size 0.4318 1.6764)
			(layers "F.Cu" "F.Mask" "F.Paste")
			(net "I3C_SPD_DDREFGH_CPU1_BMC_SDA")
		)
		(pad "14" smd rect
			(at 2.6924 -0.9525 270)
			(size 0.4318 1.6764)
			(layers "F.Cu" "F.Mask" "F.Paste")
			(net "I3C_SPD_DDREFGH_CPU1_R_SDA")
		)
		(pad "15" smd rect
			(at 2.6924 -1.5875 270)
			(size 0.4318 1.6764)
			(layers "F.Cu" "F.Mask" "F.Paste")
			(net "PD_I3C_SPD_DDR_CPU1_OE_N")
		)
		(pad "16" smd rect
			(at 2.6924 -2.2225 270)
			(size 0.4318 1.6764)
			(layers "F.Cu" "F.Mask" "F.Paste")
			(net "P3V3_AUX")
		)
	)
	(footprint ""
		(layer "F.Cu")
		(at 351.6757 -65.354962)
		(property "Reference" "C144"
			(at 0 0 0)
			(layer "F.SilkS")
			(hide yes)
			(effects
				(font
					(size 1.27 1.27)
				)
			)
		)
		(property "Value" ""
			(at 0 0 0)
			(layer "F.Fab")
			(effects
				(font
					(size 1.27 1.27)
				)
			)
		)
		(duplicate_pad_numbers_are_jumpers no)
		(fp_line
			(start -0.299974 -0.150114)
			(end 0.299974 -0.150114)
			(stroke
				(width 0.1)
				(type default)
			)
			(layer "F.Fab")
		)
		(fp_line
			(start -0.299974 0.150114)
			(end -0.299974 -0.150114)
			(stroke
				(width 0.1)
				(type default)
			)
			(layer "F.Fab")
		)
		(fp_line
			(start 0.299974 -0.150114)
			(end 0.299974 0.150114)
			(stroke
				(width 0.1)
				(type default)
			)
			(layer "F.Fab")
		)
		(fp_line
			(start 0.299974 0.150114)
			(end -0.299974 0.150114)
			(stroke
				(width 0.1)
				(type default)
			)
			(layer "F.Fab")
		)
		(pad "1" smd rect
			(at -0.2667 0)
			(size 0.3048 0.381)
			(layers "F.Cu" "F.Mask" "F.Paste")
			(net "DMI_CPU0_PCH_TX_C_DP<5>")
		)
		(pad "2" smd rect
			(at 0.2667 0)
			(size 0.3048 0.381)
			(layers "F.Cu" "F.Mask" "F.Paste")
			(net "DMI_CPU0_PCH_TX_DP<5>")
		)
		(zone
			(layer "In1.Cu")
			(hatch none 0.5)
			(connect_pads
				(clearance 0)
			)
			(min_thickness 0.25)
			(keepout
				(tracks not_allowed)
				(vias allowed)
				(pads allowed)
				(copperpour not_allowed)
				(footprints allowed)
			)
			(placement
				(enabled no)
				(sheetname "")
			)
			(fill
				(thermal_gap 0.5)
				(thermal_bridge_width 0.5)
				(island_removal_mode 0)
			)
			(polygon
				(pts
					(arc
						(start 351.282 -65.113662)
						(mid 351.228118 -65.13598)
						(end 351.2058 -65.189862)
					)
					(arc
						(start 351.2058 -65.520062)
						(mid 351.228118 -65.573944)
						(end 351.282 -65.596262)
					)
					(arc
						(start 351.536 -65.596262)
						(mid 351.589882 -65.573944)
						(end 351.6122 -65.520062)
					)
					(arc
						(start 351.6122 -65.189862)
						(mid 351.589882 -65.13598)
						(end 351.536 -65.113662)
					)
				)
			)
		)
		(zone
			(layer "In1.Cu")
			(hatch none 0.5)
			(connect_pads
				(clearance 0)
			)
			(min_thickness 0.25)
			(keepout
				(tracks not_allowed)
				(vias allowed)
				(pads allowed)
				(copperpour not_allowed)
				(footprints allowed)
			)
			(placement
				(enabled no)
				(sheetname "")
			)
			(fill
				(thermal_gap 0.5)
				(thermal_bridge_width 0.5)
				(island_removal_mode 0)
			)
			(polygon
				(pts
					(arc
						(start 351.8154 -65.113662)
						(mid 351.761518 -65.13598)
						(end 351.7392 -65.189862)
					)
					(arc
						(start 351.7392 -65.520062)
						(mid 351.761518 -65.573944)
						(end 351.8154 -65.596262)
					)
					(arc
						(start 352.0694 -65.596262)
						(mid 352.123282 -65.573944)
						(end 352.1456 -65.520062)
					)
					(arc
						(start 352.1456 -65.189862)
						(mid 352.123282 -65.13598)
						(end 352.0694 -65.113662)
					)
				)
			)
		)
	)
	(footprint ""
		(layer "F.Cu")
		(at 249.916696 -43.556682 180)
		(property "Reference" "PR3961"
			(at 0 0 180)
			(layer "F.SilkS")
			(hide yes)
			(effects
				(font
					(size 1.27 1.27)
				)
			)
		)
		(property "Value" ""
			(at 0 0 180)
			(layer "F.Fab")
			(effects
				(font
					(size 1.27 1.27)
				)
			)
		)
		(duplicate_pad_numbers_are_jumpers no)
		(fp_line
			(start 0.7874 0.4064)
			(end -0.7874 0.4064)
			(stroke
				(width 0.1524)
				(type default)
			)
			(layer "F.SilkS")
		)
		(fp_line
			(start 0.7874 -0.4064)
			(end 0.7874 0.4064)
			(stroke
				(width 0.1524)
				(type default)
			)
			(layer "F.SilkS")
		)
		(fp_line
			(start -0.7874 0.4064)
			(end -0.7874 -0.4064)
			(stroke
				(width 0.1524)
				(type default)
			)
			(layer "F.SilkS")
		)
		(fp_line
			(start -0.7874 -0.4064)
			(end 0.7874 -0.4064)
			(stroke
				(width 0.1524)
				(type default)
			)
			(layer "F.SilkS")
		)
		(fp_line
			(start 0.67945 0.3048)
			(end 0.120396 0.3048)
			(stroke
				(width 0.1)
				(type default)
			)
			(layer "F.Fab")
		)
		(fp_line
			(start 0.67945 -0.3048)
			(end 0.67945 0.3048)
			(stroke
				(width 0.1)
				(type default)
			)
			(layer "F.Fab")
		)
		(fp_line
			(start 0.12065 -0.2794)
			(end 0.12065 -0.3048)
			(stroke
				(width 0.1)
				(type default)
			)
			(layer "F.Fab")
		)
		(fp_line
			(start 0.12065 -0.3048)
			(end 0.67945 -0.3048)
			(stroke
				(width 0.1)
				(type default)
			)
			(layer "F.Fab")
		)
		(fp_line
			(start 0.120396 0.3048)
			(end 0.120396 0.2794)
			(stroke
				(width 0.1)
				(type default)
			)
			(layer "F.Fab")
		)
		(fp_line
			(start 0.120396 0.2794)
			(end -0.12065 0.2794)
			(stroke
				(width 0.1)
				(type default)
			)
			(layer "F.Fab")
		)
		(fp_line
			(start -0.12065 0.3048)
			(end -0.67945 0.3048)
			(stroke
				(width 0.1)
				(type default)
			)
			(layer "F.Fab")
		)
		(fp_line
			(start -0.12065 0.2794)
			(end -0.12065 0.3048)
			(stroke
				(width 0.1)
				(type default)
			)
			(layer "F.Fab")
		)
		(fp_line
			(start -0.12065 -0.2794)
			(end 0.12065 -0.2794)
			(stroke
				(width 0.1)
				(type default)
			)
			(layer "F.Fab")
		)
		(fp_line
			(start -0.12065 -0.305054)
			(end -0.12065 -0.2794)
			(stroke
				(width 0.1)
				(type default)
			)
			(layer "F.Fab")
		)
		(fp_line
			(start -0.67945 0.3048)
			(end -0.67945 -0.305054)
			(stroke
				(width 0.1)
				(type default)
			)
			(layer "F.Fab")
		)
		(fp_line
			(start -0.67945 -0.305054)
			(end -0.12065 -0.305054)
			(stroke
				(width 0.1)
				(type default)
			)
			(layer "F.Fab")
		)
		(pad "1" smd circle
			(at -0.40005 0 180)
			(size 0 0)
			(layers "F.Cu" "F.Mask" "F.Paste")
			(net "P12V_E1S_UV_0")
		)
		(pad "2" smd circle
			(at 0.40005 0 180)
			(size 0 0)
			(layers "F.Cu" "F.Mask" "F.Paste")
			(net "P12V_E1S_OV_0")
		)
	)
	(footprint ""
		(layer "F.Cu")
		(at 317.396622 -53.787548)
		(property "Reference" "R371"
			(at 0 0 0)
			(layer "F.SilkS")
			(hide yes)
			(effects
				(font
					(size 1.27 1.27)
				)
			)
		)
		(property "Value" ""
			(at 0 0 0)
			(layer "F.Fab")
			(effects
				(font
					(size 1.27 1.27)
				)
			)
		)
		(duplicate_pad_numbers_are_jumpers no)
		(fp_line
			(start -0.7874 -0.4064)
			(end 0.7874 -0.4064)
			(stroke
				(width 0.1524)
				(type default)
			)
			(layer "F.SilkS")
		)
		(fp_line
			(start -0.7874 0.4064)
			(end -0.7874 -0.4064)
			(stroke
				(width 0.1524)
				(type default)
			)
			(layer "F.SilkS")
		)
		(fp_line
			(start 0.7874 -0.4064)
			(end 0.7874 0.4064)
			(stroke
				(width 0.1524)
				(type default)
			)
			(layer "F.SilkS")
		)
		(fp_line
			(start 0.7874 0.4064)
			(end -0.7874 0.4064)
			(stroke
				(width 0.1524)
				(type default)
			)
			(layer "F.SilkS")
		)
		(fp_line
			(start -0.67945 -0.305054)
			(end -0.12065 -0.305054)
			(stroke
				(width 0.1)
				(type default)
			)
			(layer "F.Fab")
		)
		(fp_line
			(start -0.67945 0.3048)
			(end -0.67945 -0.305054)
			(stroke
				(width 0.1)
				(type default)
			)
			(layer "F.Fab")
		)
		(fp_line
			(start -0.12065 -0.305054)
			(end -0.12065 -0.2794)
			(stroke
				(width 0.1)
				(type default)
			)
			(layer "F.Fab")
		)
		(fp_line
			(start -0.12065 -0.2794)
			(end 0.12065 -0.2794)
			(stroke
				(width 0.1)
				(type default)
			)
			(layer "F.Fab")
		)
		(fp_line
			(start -0.12065 0.2794)
			(end -0.12065 0.3048)
			(stroke
				(width 0.1)
				(type default)
			)
			(layer "F.Fab")
		)
		(fp_line
			(start -0.12065 0.3048)
			(end -0.67945 0.3048)
			(stroke
				(width 0.1)
				(type default)
			)
			(layer "F.Fab")
		)
		(fp_line
			(start 0.120396 0.2794)
			(end -0.12065 0.2794)
			(stroke
				(width 0.1)
				(type default)
			)
			(layer "F.Fab")
		)
		(fp_line
			(start 0.120396 0.3048)
			(end 0.120396 0.2794)
			(stroke
				(width 0.1)
				(type default)
			)
			(layer "F.Fab")
		)
		(fp_line
			(start 0.12065 -0.3048)
			(end 0.67945 -0.3048)
			(stroke
				(width 0.1)
				(type default)
			)
			(layer "F.Fab")
		)
		(fp_line
			(start 0.12065 -0.2794)
			(end 0.12065 -0.3048)
			(stroke
				(width 0.1)
				(type default)
			)
			(layer "F.Fab")
		)
		(fp_line
			(start 0.67945 -0.3048)
			(end 0.67945 0.3048)
			(stroke
				(width 0.1)
				(type default)
			)
			(layer "F.Fab")
		)
		(fp_line
			(start 0.67945 0.3048)
			(end 0.120396 0.3048)
			(stroke
				(width 0.1)
				(type default)
			)
			(layer "F.Fab")
		)
		(pad "1" smd circle
			(at -0.40005 0)
			(size 0 0)
			(layers "F.Cu" "F.Mask" "F.Paste")
			(net "P3V3_AUX")
		)
		(pad "2" smd circle
			(at 0.40005 0)
			(size 0 0)
			(layers "F.Cu" "F.Mask" "F.Paste")
			(net "FM_PCH_BOOT_BIOS_STRAP")
		)
	)
	(footprint ""
		(layer "F.Cu")
		(at 309.522622 -41.900348 180)
		(property "Reference" "R1449"
			(at 0 0 180)
			(layer "F.SilkS")
			(hide yes)
			(effects
				(font
					(size 1.27 1.27)
				)
			)
		)
		(property "Value" ""
			(at 0 0 180)
			(layer "F.Fab")
			(effects
				(font
					(size 1.27 1.27)
				)
			)
		)
		(duplicate_pad_numbers_are_jumpers no)
		(fp_line
			(start 0.7874 0.4064)
			(end -0.7874 0.4064)
			(stroke
				(width 0.1524)
				(type default)
			)
			(layer "F.SilkS")
		)
		(fp_line
			(start 0.7874 -0.4064)
			(end 0.7874 0.4064)
			(stroke
				(width 0.1524)
				(type default)
			)
			(layer "F.SilkS")
		)
		(fp_line
			(start -0.7874 0.4064)
			(end -0.7874 -0.4064)
			(stroke
				(width 0.1524)
				(type default)
			)
			(layer "F.SilkS")
		)
		(fp_line
			(start -0.7874 -0.4064)
			(end 0.7874 -0.4064)
			(stroke
				(width 0.1524)
				(type default)
			)
			(layer "F.SilkS")
		)
		(fp_line
			(start 0.67945 0.3048)
			(end 0.120396 0.3048)
			(stroke
				(width 0.1)
				(type default)
			)
			(layer "F.Fab")
		)
		(fp_line
			(start 0.67945 -0.3048)
			(end 0.67945 0.3048)
			(stroke
				(width 0.1)
				(type default)
			)
			(layer "F.Fab")
		)
		(fp_line
			(start 0.12065 -0.2794)
			(end 0.12065 -0.3048)
			(stroke
				(width 0.1)
				(type default)
			)
			(layer "F.Fab")
		)
		(fp_line
			(start 0.12065 -0.3048)
			(end 0.67945 -0.3048)
			(stroke
				(width 0.1)
				(type default)
			)
			(layer "F.Fab")
		)
		(fp_line
			(start 0.120396 0.3048)
			(end 0.120396 0.2794)
			(stroke
				(width 0.1)
				(type default)
			)
			(layer "F.Fab")
		)
		(fp_line
			(start 0.120396 0.2794)
			(end -0.12065 0.2794)
			(stroke
				(width 0.1)
				(type default)
			)
			(layer "F.Fab")
		)
		(fp_line
			(start -0.12065 0.3048)
			(end -0.67945 0.3048)
			(stroke
				(width 0.1)
				(type default)
			)
			(layer "F.Fab")
		)
		(fp_line
			(start -0.12065 0.2794)
			(end -0.12065 0.3048)
			(stroke
				(width 0.1)
				(type default)
			)
			(layer "F.Fab")
		)
		(fp_line
			(start -0.12065 -0.2794)
			(end 0.12065 -0.2794)
			(stroke
				(width 0.1)
				(type default)
			)
			(layer "F.Fab")
		)
		(fp_line
			(start -0.12065 -0.305054)
			(end -0.12065 -0.2794)
			(stroke
				(width 0.1)
				(type default)
			)
			(layer "F.Fab")
		)
		(fp_line
			(start -0.67945 0.3048)
			(end -0.67945 -0.305054)
			(stroke
				(width 0.1)
				(type default)
			)
			(layer "F.Fab")
		)
		(fp_line
			(start -0.67945 -0.305054)
			(end -0.12065 -0.305054)
			(stroke
				(width 0.1)
				(type default)
			)
			(layer "F.Fab")
		)
		(pad "1" smd circle
			(at -0.40005 0 180)
			(size 0 0)
			(layers "F.Cu" "F.Mask" "F.Paste")
			(net "P3V3_AUX")
		)
		(pad "2" smd circle
			(at 0.40005 0 180)
			(size 0 0)
			(layers "F.Cu" "F.Mask" "F.Paste")
			(net "FM_BIOS_POST_CMPLT_N")
		)
	)
	(footprint ""
		(layer "F.Cu")
		(at 384.99669 -408.517344 -90)
		(property "Reference" "C878"
			(at 0 0 270)
			(layer "F.SilkS")
			(hide yes)
			(effects
				(font
					(size 1.27 1.27)
				)
			)
		)
		(property "Value" ""
			(at 0 0 270)
			(layer "F.Fab")
			(effects
				(font
					(size 1.27 1.27)
				)
			)
		)
		(duplicate_pad_numbers_are_jumpers no)
		(fp_line
			(start -0.299974 0.150114)
			(end -0.299974 -0.150114)
			(stroke
				(width 0.1)
				(type default)
			)
			(layer "F.Fab")
		)
		(fp_line
			(start 0.299974 0.150114)
			(end -0.299974 0.150114)
			(stroke
				(width 0.1)
				(type default)
			)
			(layer "F.Fab")
		)
		(fp_line
			(start -0.299974 -0.150114)
			(end 0.299974 -0.150114)
			(stroke
				(width 0.1)
				(type default)
			)
			(layer "F.Fab")
		)
		(fp_line
			(start 0.299974 -0.150114)
			(end 0.299974 0.150114)
			(stroke
				(width 0.1)
				(type default)
			)
			(layer "F.Fab")
		)
		(pad "1" smd rect
			(at -0.2667 0 270)
			(size 0.3048 0.381)
			(layers "F.Cu" "F.Mask" "F.Paste")
			(net "P5E_CPU0_PE3_TX_C_DN<11>")
		)
		(pad "2" smd rect
			(at 0.2667 0 270)
			(size 0.3048 0.381)
			(layers "F.Cu" "F.Mask" "F.Paste")
			(net "P5E_CPU0_PE3_TX_DN<11>")
		)
	)
	(footprint ""
		(layer "F.Cu")
		(at 415.818828 -174.396654 180)
		(property "Reference" "PC2947"
			(at 0 0 180)
			(layer "F.SilkS")
			(hide yes)
			(effects
				(font
					(size 1.27 1.27)
				)
			)
		)
		(property "Value" ""
			(at 0 0 180)
			(layer "F.Fab")
			(effects
				(font
					(size 1.27 1.27)
				)
			)
		)
		(duplicate_pad_numbers_are_jumpers no)
		(fp_line
			(start 0.7874 0.4064)
			(end -0.7874 0.4064)
			(stroke
				(width 0.1524)
				(type default)
			)
			(layer "F.SilkS")
		)
		(fp_line
			(start 0.7874 -0.4064)
			(end 0.7874 0.4064)
			(stroke
				(width 0.1524)
				(type default)
			)
			(layer "F.SilkS")
		)
		(fp_line
			(start -0.7874 0.4064)
			(end -0.7874 -0.4064)
			(stroke
				(width 0.1524)
				(type default)
			)
			(layer "F.SilkS")
		)
		(fp_line
			(start -0.7874 -0.4064)
			(end 0.7874 -0.4064)
			(stroke
				(width 0.1524)
				(type default)
			)
			(layer "F.SilkS")
		)
		(fp_line
			(start 0.67945 0.3048)
			(end 0.120396 0.3048)
			(stroke
				(width 0.1)
				(type default)
			)
			(layer "F.Fab")
		)
		(fp_line
			(start 0.67945 -0.3048)
			(end 0.67945 0.3048)
			(stroke
				(width 0.1)
				(type default)
			)
			(layer "F.Fab")
		)
		(fp_line
			(start 0.12065 -0.2794)
			(end 0.12065 -0.3048)
			(stroke
				(width 0.1)
				(type default)
			)
			(layer "F.Fab")
		)
		(fp_line
			(start 0.12065 -0.3048)
			(end 0.67945 -0.3048)
			(stroke
				(width 0.1)
				(type default)
			)
			(layer "F.Fab")
		)
		(fp_line
			(start 0.120396 0.3048)
			(end 0.120396 0.2794)
			(stroke
				(width 0.1)
				(type default)
			)
			(layer "F.Fab")
		)
		(fp_line
			(start 0.120396 0.2794)
			(end -0.12065 0.2794)
			(stroke
				(width 0.1)
				(type default)
			)
			(layer "F.Fab")
		)
		(fp_line
			(start -0.12065 0.3048)
			(end -0.67945 0.3048)
			(stroke
				(width 0.1)
				(type default)
			)
			(layer "F.Fab")
		)
		(fp_line
			(start -0.12065 0.2794)
			(end -0.12065 0.3048)
			(stroke
				(width 0.1)
				(type default)
			)
			(layer "F.Fab")
		)
		(fp_line
			(start -0.12065 -0.2794)
			(end 0.12065 -0.2794)
			(stroke
				(width 0.1)
				(type default)
			)
			(layer "F.Fab")
		)
		(fp_line
			(start -0.12065 -0.305054)
			(end -0.12065 -0.2794)
			(stroke
				(width 0.1)
				(type default)
			)
			(layer "F.Fab")
		)
		(fp_line
			(start -0.67945 0.3048)
			(end -0.67945 -0.305054)
			(stroke
				(width 0.1)
				(type default)
			)
			(layer "F.Fab")
		)
		(fp_line
			(start -0.67945 -0.305054)
			(end -0.12065 -0.305054)
			(stroke
				(width 0.1)
				(type default)
			)
			(layer "F.Fab")
		)
		(pad "1" smd circle
			(at -0.40005 0 180)
			(size 0 0)
			(layers "F.Cu" "F.Mask" "F.Paste")
			(net "PVCCFA_EHV_CPU0_PVCC")
		)
		(pad "2" smd circle
			(at 0.40005 0 180)
			(size 0 0)
			(layers "F.Cu" "F.Mask" "F.Paste")
			(net "GND")
		)
	)
	(footprint ""
		(layer "F.Cu")
		(at 325.397368 -402.371052 -90)
		(property "Reference" "C1564"
			(at 0 0 270)
			(layer "F.SilkS")
			(hide yes)
			(effects
				(font
					(size 1.27 1.27)
				)
			)
		)
		(property "Value" ""
			(at 0 0 270)
			(layer "F.Fab")
			(effects
				(font
					(size 1.27 1.27)
				)
			)
		)
		(duplicate_pad_numbers_are_jumpers no)
		(fp_line
			(start -0.299974 0.150114)
			(end -0.299974 -0.150114)
			(stroke
				(width 0.1)
				(type default)
			)
			(layer "F.Fab")
		)
		(fp_line
			(start 0.299974 0.150114)
			(end -0.299974 0.150114)
			(stroke
				(width 0.1)
				(type default)
			)
			(layer "F.Fab")
		)
		(fp_line
			(start -0.299974 -0.150114)
			(end 0.299974 -0.150114)
			(stroke
				(width 0.1)
				(type default)
			)
			(layer "F.Fab")
		)
		(fp_line
			(start 0.299974 -0.150114)
			(end 0.299974 0.150114)
			(stroke
				(width 0.1)
				(type default)
			)
			(layer "F.Fab")
		)
		(pad "1" smd rect
			(at -0.2667 0 270)
			(size 0.3048 0.381)
			(layers "F.Cu" "F.Mask" "F.Paste")
			(net "P5E_CPU0_PE4_TX_C_DN<7>")
		)
		(pad "2" smd rect
			(at 0.2667 0 270)
			(size 0.3048 0.381)
			(layers "F.Cu" "F.Mask" "F.Paste")
			(net "P5E_CPU0_PE4_TX_DN<7>")
		)
	)
	(footprint ""
		(layer "F.Cu")
		(at 223.37141 -73.517506)
		(property "Reference" "PC2216"
			(at 0 0 0)
			(layer "F.SilkS")
			(hide yes)
			(effects
				(font
					(size 1.27 1.27)
				)
			)
		)
		(property "Value" ""
			(at 0 0 0)
			(layer "F.Fab")
			(effects
				(font
					(size 1.27 1.27)
				)
			)
		)
		(duplicate_pad_numbers_are_jumpers no)
		(fp_line
			(start -0.7874 -0.4064)
			(end 0.7874 -0.4064)
			(stroke
				(width 0.1524)
				(type default)
			)
			(layer "F.SilkS")
		)
		(fp_line
			(start -0.7874 0.4064)
			(end -0.7874 -0.4064)
			(stroke
				(width 0.1524)
				(type default)
			)
			(layer "F.SilkS")
		)
		(fp_line
			(start 0.7874 -0.4064)
			(end 0.7874 0.4064)
			(stroke
				(width 0.1524)
				(type default)
			)
			(layer "F.SilkS")
		)
		(fp_line
			(start 0.7874 0.4064)
			(end -0.7874 0.4064)
			(stroke
				(width 0.1524)
				(type default)
			)
			(layer "F.SilkS")
		)
		(fp_line
			(start -0.67945 -0.305054)
			(end -0.12065 -0.305054)
			(stroke
				(width 0.1)
				(type default)
			)
			(layer "F.Fab")
		)
		(fp_line
			(start -0.67945 0.3048)
			(end -0.67945 -0.305054)
			(stroke
				(width 0.1)
				(type default)
			)
			(layer "F.Fab")
		)
		(fp_line
			(start -0.12065 -0.305054)
			(end -0.12065 -0.2794)
			(stroke
				(width 0.1)
				(type default)
			)
			(layer "F.Fab")
		)
		(fp_line
			(start -0.12065 -0.2794)
			(end 0.12065 -0.2794)
			(stroke
				(width 0.1)
				(type default)
			)
			(layer "F.Fab")
		)
		(fp_line
			(start -0.12065 0.2794)
			(end -0.12065 0.3048)
			(stroke
				(width 0.1)
				(type default)
			)
			(layer "F.Fab")
		)
		(fp_line
			(start -0.12065 0.3048)
			(end -0.67945 0.3048)
			(stroke
				(width 0.1)
				(type default)
			)
			(layer "F.Fab")
		)
		(fp_line
			(start 0.120396 0.2794)
			(end -0.12065 0.2794)
			(stroke
				(width 0.1)
				(type default)
			)
			(layer "F.Fab")
		)
		(fp_line
			(start 0.120396 0.3048)
			(end 0.120396 0.2794)
			(stroke
				(width 0.1)
				(type default)
			)
			(layer "F.Fab")
		)
		(fp_line
			(start 0.12065 -0.3048)
			(end 0.67945 -0.3048)
			(stroke
				(width 0.1)
				(type default)
			)
			(layer "F.Fab")
		)
		(fp_line
			(start 0.12065 -0.2794)
			(end 0.12065 -0.3048)
			(stroke
				(width 0.1)
				(type default)
			)
			(layer "F.Fab")
		)
		(fp_line
			(start 0.67945 -0.3048)
			(end 0.67945 0.3048)
			(stroke
				(width 0.1)
				(type default)
			)
			(layer "F.Fab")
		)
		(fp_line
			(start 0.67945 0.3048)
			(end 0.120396 0.3048)
			(stroke
				(width 0.1)
				(type default)
			)
			(layer "F.Fab")
		)
		(pad "1" smd circle
			(at -0.40005 0)
			(size 0 0)
			(layers "F.Cu" "F.Mask" "F.Paste")
			(net "P3V3_E1S_GATE_0")
		)
		(pad "2" smd circle
			(at 0.40005 0)
			(size 0 0)
			(layers "F.Cu" "F.Mask" "F.Paste")
			(net "GND")
		)
	)
	(footprint ""
		(layer "F.Cu")
		(at 128.401572 -128.986026)
		(property "Reference" "R2704"
			(at 0 0 0)
			(layer "F.SilkS")
			(hide yes)
			(effects
				(font
					(size 1.27 1.27)
				)
			)
		)
		(property "Value" ""
			(at 0 0 0)
			(layer "F.Fab")
			(effects
				(font
					(size 1.27 1.27)
				)
			)
		)
		(duplicate_pad_numbers_are_jumpers no)
		(fp_line
			(start -0.7874 -0.4064)
			(end 0.7874 -0.4064)
			(stroke
				(width 0.1524)
				(type default)
			)
			(layer "F.SilkS")
		)
		(fp_line
			(start -0.7874 0.4064)
			(end -0.7874 -0.4064)
			(stroke
				(width 0.1524)
				(type default)
			)
			(layer "F.SilkS")
		)
		(fp_line
			(start 0.7874 -0.4064)
			(end 0.7874 0.4064)
			(stroke
				(width 0.1524)
				(type default)
			)
			(layer "F.SilkS")
		)
		(fp_line
			(start 0.7874 0.4064)
			(end -0.7874 0.4064)
			(stroke
				(width 0.1524)
				(type default)
			)
			(layer "F.SilkS")
		)
		(fp_line
			(start -0.67945 -0.305054)
			(end -0.12065 -0.305054)
			(stroke
				(width 0.1)
				(type default)
			)
			(layer "F.Fab")
		)
		(fp_line
			(start -0.67945 0.3048)
			(end -0.67945 -0.305054)
			(stroke
				(width 0.1)
				(type default)
			)
			(layer "F.Fab")
		)
		(fp_line
			(start -0.12065 -0.305054)
			(end -0.12065 -0.2794)
			(stroke
				(width 0.1)
				(type default)
			)
			(layer "F.Fab")
		)
		(fp_line
			(start -0.12065 -0.2794)
			(end 0.12065 -0.2794)
			(stroke
				(width 0.1)
				(type default)
			)
			(layer "F.Fab")
		)
		(fp_line
			(start -0.12065 0.2794)
			(end -0.12065 0.3048)
			(stroke
				(width 0.1)
				(type default)
			)
			(layer "F.Fab")
		)
		(fp_line
			(start -0.12065 0.3048)
			(end -0.67945 0.3048)
			(stroke
				(width 0.1)
				(type default)
			)
			(layer "F.Fab")
		)
		(fp_line
			(start 0.120396 0.2794)
			(end -0.12065 0.2794)
			(stroke
				(width 0.1)
				(type default)
			)
			(layer "F.Fab")
		)
		(fp_line
			(start 0.120396 0.3048)
			(end 0.120396 0.2794)
			(stroke
				(width 0.1)
				(type default)
			)
			(layer "F.Fab")
		)
		(fp_line
			(start 0.12065 -0.3048)
			(end 0.67945 -0.3048)
			(stroke
				(width 0.1)
				(type default)
			)
			(layer "F.Fab")
		)
		(fp_line
			(start 0.12065 -0.2794)
			(end 0.12065 -0.3048)
			(stroke
				(width 0.1)
				(type default)
			)
			(layer "F.Fab")
		)
		(fp_line
			(start 0.67945 -0.3048)
			(end 0.67945 0.3048)
			(stroke
				(width 0.1)
				(type default)
			)
			(layer "F.Fab")
		)
		(fp_line
			(start 0.67945 0.3048)
			(end 0.120396 0.3048)
			(stroke
				(width 0.1)
				(type default)
			)
			(layer "F.Fab")
		)
		(pad "1" smd circle
			(at -0.40005 0)
			(size 0 0)
			(layers "F.Cu" "F.Mask" "F.Paste")
			(net "SMB_BMC_SWB_SDA_R4")
		)
		(pad "2" smd circle
			(at 0.40005 0)
			(size 0 0)
			(layers "F.Cu" "F.Mask" "F.Paste")
			(net "SMB_BMC_SWB_SDA")
		)
	)
	(footprint ""
		(layer "F.Cu")
		(at 111.332772 -139.133326)
		(property "Reference" "R538"
			(at 0 0 0)
			(layer "F.SilkS")
			(hide yes)
			(effects
				(font
					(size 1.27 1.27)
				)
			)
		)
		(property "Value" ""
			(at 0 0 0)
			(layer "F.Fab")
			(effects
				(font
					(size 1.27 1.27)
				)
			)
		)
		(duplicate_pad_numbers_are_jumpers no)
		(fp_line
			(start -0.7874 -0.4064)
			(end 0.7874 -0.4064)
			(stroke
				(width 0.1524)
				(type default)
			)
			(layer "F.SilkS")
		)
		(fp_line
			(start -0.7874 0.4064)
			(end -0.7874 -0.4064)
			(stroke
				(width 0.1524)
				(type default)
			)
			(layer "F.SilkS")
		)
		(fp_line
			(start 0.7874 -0.4064)
			(end 0.7874 0.4064)
			(stroke
				(width 0.1524)
				(type default)
			)
			(layer "F.SilkS")
		)
		(fp_line
			(start 0.7874 0.4064)
			(end -0.7874 0.4064)
			(stroke
				(width 0.1524)
				(type default)
			)
			(layer "F.SilkS")
		)
		(fp_line
			(start -0.67945 -0.305054)
			(end -0.12065 -0.305054)
			(stroke
				(width 0.1)
				(type default)
			)
			(layer "F.Fab")
		)
		(fp_line
			(start -0.67945 0.3048)
			(end -0.67945 -0.305054)
			(stroke
				(width 0.1)
				(type default)
			)
			(layer "F.Fab")
		)
		(fp_line
			(start -0.12065 -0.305054)
			(end -0.12065 -0.2794)
			(stroke
				(width 0.1)
				(type default)
			)
			(layer "F.Fab")
		)
		(fp_line
			(start -0.12065 -0.2794)
			(end 0.12065 -0.2794)
			(stroke
				(width 0.1)
				(type default)
			)
			(layer "F.Fab")
		)
		(fp_line
			(start -0.12065 0.2794)
			(end -0.12065 0.3048)
			(stroke
				(width 0.1)
				(type default)
			)
			(layer "F.Fab")
		)
		(fp_line
			(start -0.12065 0.3048)
			(end -0.67945 0.3048)
			(stroke
				(width 0.1)
				(type default)
			)
			(layer "F.Fab")
		)
		(fp_line
			(start 0.120396 0.2794)
			(end -0.12065 0.2794)
			(stroke
				(width 0.1)
				(type default)
			)
			(layer "F.Fab")
		)
		(fp_line
			(start 0.120396 0.3048)
			(end 0.120396 0.2794)
			(stroke
				(width 0.1)
				(type default)
			)
			(layer "F.Fab")
		)
		(fp_line
			(start 0.12065 -0.3048)
			(end 0.67945 -0.3048)
			(stroke
				(width 0.1)
				(type default)
			)
			(layer "F.Fab")
		)
		(fp_line
			(start 0.12065 -0.2794)
			(end 0.12065 -0.3048)
			(stroke
				(width 0.1)
				(type default)
			)
			(layer "F.Fab")
		)
		(fp_line
			(start 0.67945 -0.3048)
			(end 0.67945 0.3048)
			(stroke
				(width 0.1)
				(type default)
			)
			(layer "F.Fab")
		)
		(fp_line
			(start 0.67945 0.3048)
			(end 0.120396 0.3048)
			(stroke
				(width 0.1)
				(type default)
			)
			(layer "F.Fab")
		)
		(pad "1" smd circle
			(at -0.40005 0)
			(size 0 0)
			(layers "F.Cu" "F.Mask" "F.Paste")
			(net "P3V3_AUX")
		)
		(pad "2" smd circle
			(at 0.40005 0)
			(size 0 0)
			(layers "F.Cu" "F.Mask" "F.Paste")
			(net "PCA9548_PCIE3_ADDR1")
		)
	)
	(footprint ""
		(layer "F.Cu")
		(at 39.827454 -111.606838)
		(property "Reference" "R3866"
			(at 0 0 0)
			(layer "F.SilkS")
			(hide yes)
			(effects
				(font
					(size 1.27 1.27)
				)
			)
		)
		(property "Value" ""
			(at 0 0 0)
			(layer "F.Fab")
			(effects
				(font
					(size 1.27 1.27)
				)
			)
		)
		(duplicate_pad_numbers_are_jumpers no)
		(fp_line
			(start -0.7874 -0.4064)
			(end 0.7874 -0.4064)
			(stroke
				(width 0.1524)
				(type default)
			)
			(layer "F.SilkS")
		)
		(fp_line
			(start -0.7874 0.4064)
			(end -0.7874 -0.4064)
			(stroke
				(width 0.1524)
				(type default)
			)
			(layer "F.SilkS")
		)
		(fp_line
			(start 0.7874 -0.4064)
			(end 0.7874 0.4064)
			(stroke
				(width 0.1524)
				(type default)
			)
			(layer "F.SilkS")
		)
		(fp_line
			(start 0.7874 0.4064)
			(end -0.7874 0.4064)
			(stroke
				(width 0.1524)
				(type default)
			)
			(layer "F.SilkS")
		)
		(fp_line
			(start -0.67945 -0.305054)
			(end -0.12065 -0.305054)
			(stroke
				(width 0.1)
				(type default)
			)
			(layer "F.Fab")
		)
		(fp_line
			(start -0.67945 0.3048)
			(end -0.67945 -0.305054)
			(stroke
				(width 0.1)
				(type default)
			)
			(layer "F.Fab")
		)
		(fp_line
			(start -0.12065 -0.305054)
			(end -0.12065 -0.2794)
			(stroke
				(width 0.1)
				(type default)
			)
			(layer "F.Fab")
		)
		(fp_line
			(start -0.12065 -0.2794)
			(end 0.12065 -0.2794)
			(stroke
				(width 0.1)
				(type default)
			)
			(layer "F.Fab")
		)
		(fp_line
			(start -0.12065 0.2794)
			(end -0.12065 0.3048)
			(stroke
				(width 0.1)
				(type default)
			)
			(layer "F.Fab")
		)
		(fp_line
			(start -0.12065 0.3048)
			(end -0.67945 0.3048)
			(stroke
				(width 0.1)
				(type default)
			)
			(layer "F.Fab")
		)
		(fp_line
			(start 0.120396 0.2794)
			(end -0.12065 0.2794)
			(stroke
				(width 0.1)
				(type default)
			)
			(layer "F.Fab")
		)
		(fp_line
			(start 0.120396 0.3048)
			(end 0.120396 0.2794)
			(stroke
				(width 0.1)
				(type default)
			)
			(layer "F.Fab")
		)
		(fp_line
			(start 0.12065 -0.3048)
			(end 0.67945 -0.3048)
			(stroke
				(width 0.1)
				(type default)
			)
			(layer "F.Fab")
		)
		(fp_line
			(start 0.12065 -0.2794)
			(end 0.12065 -0.3048)
			(stroke
				(width 0.1)
				(type default)
			)
			(layer "F.Fab")
		)
		(fp_line
			(start 0.67945 -0.3048)
			(end 0.67945 0.3048)
			(stroke
				(width 0.1)
				(type default)
			)
			(layer "F.Fab")
		)
		(fp_line
			(start 0.67945 0.3048)
			(end 0.120396 0.3048)
			(stroke
				(width 0.1)
				(type default)
			)
			(layer "F.Fab")
		)
		(pad "1" smd rect
			(at -0.40005 0 180)
			(size 0.4572 0.508)
			(layers "F.Cu" "F.Mask" "F.Paste")
			(net "P12V_OCP_SFF_ISENSE_MPS_TIC")
		)
		(pad "2" smd rect
			(at 0.40005 0 180)
			(size 0.4572 0.508)
			(layers "F.Cu" "F.Mask" "F.Paste")
			(net "P12V_OCP_SFF_ISENSE_TIC")
		)
	)
	(footprint ""
		(layer "F.Cu")
		(at 115.052094 -338.17814 -90)
		(property "Reference" "PC532"
			(at 0 0 270)
			(layer "F.SilkS")
			(hide yes)
			(effects
				(font
					(size 1.27 1.27)
				)
			)
		)
		(property "Value" ""
			(at 0 0 270)
			(layer "F.Fab")
			(effects
				(font
					(size 1.27 1.27)
				)
			)
		)
		(duplicate_pad_numbers_are_jumpers no)
		(fp_line
			(start -0.7874 0.4064)
			(end -0.7874 -0.4064)
			(stroke
				(width 0.1524)
				(type default)
			)
			(layer "F.SilkS")
		)
		(fp_line
			(start 0.7874 0.4064)
			(end -0.7874 0.4064)
			(stroke
				(width 0.1524)
				(type default)
			)
			(layer "F.SilkS")
		)
		(fp_line
			(start -0.7874 -0.4064)
			(end 0.7874 -0.4064)
			(stroke
				(width 0.1524)
				(type default)
			)
			(layer "F.SilkS")
		)
		(fp_line
			(start 0.7874 -0.4064)
			(end 0.7874 0.4064)
			(stroke
				(width 0.1524)
				(type default)
			)
			(layer "F.SilkS")
		)
		(fp_line
			(start -0.67945 0.3048)
			(end -0.67945 -0.305054)
			(stroke
				(width 0.1)
				(type default)
			)
			(layer "F.Fab")
		)
		(fp_line
			(start -0.12065 0.3048)
			(end -0.67945 0.3048)
			(stroke
				(width 0.1)
				(type default)
			)
			(layer "F.Fab")
		)
		(fp_line
			(start 0.120396 0.3048)
			(end 0.120396 0.2794)
			(stroke
				(width 0.1)
				(type default)
			)
			(layer "F.Fab")
		)
		(fp_line
			(start 0.67945 0.3048)
			(end 0.120396 0.3048)
			(stroke
				(width 0.1)
				(type default)
			)
			(layer "F.Fab")
		)
		(fp_line
			(start -0.12065 0.2794)
			(end -0.12065 0.3048)
			(stroke
				(width 0.1)
				(type default)
			)
			(layer "F.Fab")
		)
		(fp_line
			(start 0.120396 0.2794)
			(end -0.12065 0.2794)
			(stroke
				(width 0.1)
				(type default)
			)
			(layer "F.Fab")
		)
		(fp_line
			(start -0.12065 -0.2794)
			(end 0.12065 -0.2794)
			(stroke
				(width 0.1)
				(type default)
			)
			(layer "F.Fab")
		)
		(fp_line
			(start 0.12065 -0.2794)
			(end 0.12065 -0.3048)
			(stroke
				(width 0.1)
				(type default)
			)
			(layer "F.Fab")
		)
		(fp_line
			(start 0.12065 -0.3048)
			(end 0.67945 -0.3048)
			(stroke
				(width 0.1)
				(type default)
			)
			(layer "F.Fab")
		)
		(fp_line
			(start 0.67945 -0.3048)
			(end 0.67945 0.3048)
			(stroke
				(width 0.1)
				(type default)
			)
			(layer "F.Fab")
		)
		(fp_line
			(start -0.67945 -0.305054)
			(end -0.12065 -0.305054)
			(stroke
				(width 0.1)
				(type default)
			)
			(layer "F.Fab")
		)
		(fp_line
			(start -0.12065 -0.305054)
			(end -0.12065 -0.2794)
			(stroke
				(width 0.1)
				(type default)
			)
			(layer "F.Fab")
		)
		(pad "1" smd circle
			(at -0.40005 0 270)
			(size 0 0)
			(layers "F.Cu" "F.Mask" "F.Paste")
			(net "SW_PVCCIN_CPU1_BOOT3_R")
		)
		(pad "2" smd circle
			(at 0.40005 0 270)
			(size 0 0)
			(layers "F.Cu" "F.Mask" "F.Paste")
			(net "SW_PVCCIN_CPU1_BOOTR3")
		)
	)
	(footprint ""
		(layer "F.Cu")
		(at 31.53918 -122.380502 90)
		(property "Reference" "R1662"
			(at 0 0 90)
			(layer "F.SilkS")
			(hide yes)
			(effects
				(font
					(size 1.27 1.27)
				)
			)
		)
		(property "Value" ""
			(at 0 0 90)
			(layer "F.Fab")
			(effects
				(font
					(size 1.27 1.27)
				)
			)
		)
		(duplicate_pad_numbers_are_jumpers no)
		(fp_line
			(start 0.7874 -0.4064)
			(end 0.7874 0.4064)
			(stroke
				(width 0.1524)
				(type default)
			)
			(layer "F.SilkS")
		)
		(fp_line
			(start -0.7874 -0.4064)
			(end 0.7874 -0.4064)
			(stroke
				(width 0.1524)
				(type default)
			)
			(layer "F.SilkS")
		)
		(fp_line
			(start 0.7874 0.4064)
			(end -0.7874 0.4064)
			(stroke
				(width 0.1524)
				(type default)
			)
			(layer "F.SilkS")
		)
		(fp_line
			(start -0.7874 0.4064)
			(end -0.7874 -0.4064)
			(stroke
				(width 0.1524)
				(type default)
			)
			(layer "F.SilkS")
		)
		(fp_line
			(start -0.12065 -0.305054)
			(end -0.12065 -0.2794)
			(stroke
				(width 0.1)
				(type default)
			)
			(layer "F.Fab")
		)
		(fp_line
			(start -0.67945 -0.305054)
			(end -0.12065 -0.305054)
			(stroke
				(width 0.1)
				(type default)
			)
			(layer "F.Fab")
		)
		(fp_line
			(start 0.67945 -0.3048)
			(end 0.67945 0.3048)
			(stroke
				(width 0.1)
				(type default)
			)
			(layer "F.Fab")
		)
		(fp_line
			(start 0.12065 -0.3048)
			(end 0.67945 -0.3048)
			(stroke
				(width 0.1)
				(type default)
			)
			(layer "F.Fab")
		)
		(fp_line
			(start 0.12065 -0.2794)
			(end 0.12065 -0.3048)
			(stroke
				(width 0.1)
				(type default)
			)
			(layer "F.Fab")
		)
		(fp_line
			(start -0.12065 -0.2794)
			(end 0.12065 -0.2794)
			(stroke
				(width 0.1)
				(type default)
			)
			(layer "F.Fab")
		)
		(fp_line
			(start 0.120396 0.2794)
			(end -0.12065 0.2794)
			(stroke
				(width 0.1)
				(type default)
			)
			(layer "F.Fab")
		)
		(fp_line
			(start -0.12065 0.2794)
			(end -0.12065 0.3048)
			(stroke
				(width 0.1)
				(type default)
			)
			(layer "F.Fab")
		)
		(fp_line
			(start 0.67945 0.3048)
			(end 0.120396 0.3048)
			(stroke
				(width 0.1)
				(type default)
			)
			(layer "F.Fab")
		)
		(fp_line
			(start 0.120396 0.3048)
			(end 0.120396 0.2794)
			(stroke
				(width 0.1)
				(type default)
			)
			(layer "F.Fab")
		)
		(fp_line
			(start -0.12065 0.3048)
			(end -0.67945 0.3048)
			(stroke
				(width 0.1)
				(type default)
			)
			(layer "F.Fab")
		)
		(fp_line
			(start -0.67945 0.3048)
			(end -0.67945 -0.305054)
			(stroke
				(width 0.1)
				(type default)
			)
			(layer "F.Fab")
		)
		(pad "1" smd circle
			(at -0.40005 0 90)
			(size 0 0)
			(layers "F.Cu" "F.Mask" "F.Paste")
			(net "SMB_VR_3V3AUX_SDA")
		)
		(pad "2" smd circle
			(at 0.40005 0 90)
			(size 0 0)
			(layers "F.Cu" "F.Mask" "F.Paste")
			(net "SMB_VR_3V3AUX_SDA_R")
		)
	)
	(footprint ""
		(layer "F.Cu")
		(at 60.127388 -32.287972 180)
		(property "Reference" "R3868"
			(at 0 0 180)
			(layer "F.SilkS")
			(hide yes)
			(effects
				(font
					(size 1.27 1.27)
				)
			)
		)
		(property "Value" ""
			(at 0 0 180)
			(layer "F.Fab")
			(effects
				(font
					(size 1.27 1.27)
				)
			)
		)
		(duplicate_pad_numbers_are_jumpers no)
		(fp_line
			(start 0.7874 0.4064)
			(end -0.7874 0.4064)
			(stroke
				(width 0.1524)
				(type default)
			)
			(layer "F.SilkS")
		)
		(fp_line
			(start 0.7874 -0.4064)
			(end 0.7874 0.4064)
			(stroke
				(width 0.1524)
				(type default)
			)
			(layer "F.SilkS")
		)
		(fp_line
			(start -0.7874 0.4064)
			(end -0.7874 -0.4064)
			(stroke
				(width 0.1524)
				(type default)
			)
			(layer "F.SilkS")
		)
		(fp_line
			(start -0.7874 -0.4064)
			(end 0.7874 -0.4064)
			(stroke
				(width 0.1524)
				(type default)
			)
			(layer "F.SilkS")
		)
		(fp_line
			(start 0.67945 0.3048)
			(end 0.120396 0.3048)
			(stroke
				(width 0.1)
				(type default)
			)
			(layer "F.Fab")
		)
		(fp_line
			(start 0.67945 -0.3048)
			(end 0.67945 0.3048)
			(stroke
				(width 0.1)
				(type default)
			)
			(layer "F.Fab")
		)
		(fp_line
			(start 0.12065 -0.2794)
			(end 0.12065 -0.3048)
			(stroke
				(width 0.1)
				(type default)
			)
			(layer "F.Fab")
		)
		(fp_line
			(start 0.12065 -0.3048)
			(end 0.67945 -0.3048)
			(stroke
				(width 0.1)
				(type default)
			)
			(layer "F.Fab")
		)
		(fp_line
			(start 0.120396 0.3048)
			(end 0.120396 0.2794)
			(stroke
				(width 0.1)
				(type default)
			)
			(layer "F.Fab")
		)
		(fp_line
			(start 0.120396 0.2794)
			(end -0.12065 0.2794)
			(stroke
				(width 0.1)
				(type default)
			)
			(layer "F.Fab")
		)
		(fp_line
			(start -0.12065 0.3048)
			(end -0.67945 0.3048)
			(stroke
				(width 0.1)
				(type default)
			)
			(layer "F.Fab")
		)
		(fp_line
			(start -0.12065 0.2794)
			(end -0.12065 0.3048)
			(stroke
				(width 0.1)
				(type default)
			)
			(layer "F.Fab")
		)
		(fp_line
			(start -0.12065 -0.2794)
			(end 0.12065 -0.2794)
			(stroke
				(width 0.1)
				(type default)
			)
			(layer "F.Fab")
		)
		(fp_line
			(start -0.12065 -0.305054)
			(end -0.12065 -0.2794)
			(stroke
				(width 0.1)
				(type default)
			)
			(layer "F.Fab")
		)
		(fp_line
			(start -0.67945 0.3048)
			(end -0.67945 -0.305054)
			(stroke
				(width 0.1)
				(type default)
			)
			(layer "F.Fab")
		)
		(fp_line
			(start -0.67945 -0.305054)
			(end -0.12065 -0.305054)
			(stroke
				(width 0.1)
				(type default)
			)
			(layer "F.Fab")
		)
		(pad "1" smd rect
			(at -0.40005 0)
			(size 0.4572 0.508)
			(layers "F.Cu" "F.Mask" "F.Paste")
			(net "P12V_OCP_SENSE_2")
		)
		(pad "2" smd rect
			(at 0.40005 0)
			(size 0.4572 0.508)
			(layers "F.Cu" "F.Mask" "F.Paste")
			(net "P12V_OCP_V3_2_ISENSE_MAM_TIC")
		)
	)
	(footprint ""
		(layer "F.Cu")
		(at 155.690824 -51.531012)
		(property "Reference" "C2013"
			(at 0 0 0)
			(layer "F.SilkS")
			(hide yes)
			(effects
				(font
					(size 1.27 1.27)
				)
			)
		)
		(property "Value" ""
			(at 0 0 0)
			(layer "F.Fab")
			(effects
				(font
					(size 1.27 1.27)
				)
			)
		)
		(duplicate_pad_numbers_are_jumpers no)
		(fp_line
			(start -0.7874 -0.4064)
			(end 0.7874 -0.4064)
			(stroke
				(width 0.1524)
				(type default)
			)
			(layer "F.SilkS")
		)
		(fp_line
			(start -0.7874 0.4064)
			(end -0.7874 -0.4064)
			(stroke
				(width 0.1524)
				(type default)
			)
			(layer "F.SilkS")
		)
		(fp_line
			(start 0.7874 -0.4064)
			(end 0.7874 0.4064)
			(stroke
				(width 0.1524)
				(type default)
			)
			(layer "F.SilkS")
		)
		(fp_line
			(start 0.7874 0.4064)
			(end -0.7874 0.4064)
			(stroke
				(width 0.1524)
				(type default)
			)
			(layer "F.SilkS")
		)
		(fp_line
			(start -0.67945 -0.305054)
			(end -0.12065 -0.305054)
			(stroke
				(width 0.1)
				(type default)
			)
			(layer "F.Fab")
		)
		(fp_line
			(start -0.67945 0.3048)
			(end -0.67945 -0.305054)
			(stroke
				(width 0.1)
				(type default)
			)
			(layer "F.Fab")
		)
		(fp_line
			(start -0.12065 -0.305054)
			(end -0.12065 -0.2794)
			(stroke
				(width 0.1)
				(type default)
			)
			(layer "F.Fab")
		)
		(fp_line
			(start -0.12065 -0.2794)
			(end 0.12065 -0.2794)
			(stroke
				(width 0.1)
				(type default)
			)
			(layer "F.Fab")
		)
		(fp_line
			(start -0.12065 0.2794)
			(end -0.12065 0.3048)
			(stroke
				(width 0.1)
				(type default)
			)
			(layer "F.Fab")
		)
		(fp_line
			(start -0.12065 0.3048)
			(end -0.67945 0.3048)
			(stroke
				(width 0.1)
				(type default)
			)
			(layer "F.Fab")
		)
		(fp_line
			(start 0.120396 0.2794)
			(end -0.12065 0.2794)
			(stroke
				(width 0.1)
				(type default)
			)
			(layer "F.Fab")
		)
		(fp_line
			(start 0.120396 0.3048)
			(end 0.120396 0.2794)
			(stroke
				(width 0.1)
				(type default)
			)
			(layer "F.Fab")
		)
		(fp_line
			(start 0.12065 -0.3048)
			(end 0.67945 -0.3048)
			(stroke
				(width 0.1)
				(type default)
			)
			(layer "F.Fab")
		)
		(fp_line
			(start 0.12065 -0.2794)
			(end 0.12065 -0.3048)
			(stroke
				(width 0.1)
				(type default)
			)
			(layer "F.Fab")
		)
		(fp_line
			(start 0.67945 -0.3048)
			(end 0.67945 0.3048)
			(stroke
				(width 0.1)
				(type default)
			)
			(layer "F.Fab")
		)
		(fp_line
			(start 0.67945 0.3048)
			(end 0.120396 0.3048)
			(stroke
				(width 0.1)
				(type default)
			)
			(layer "F.Fab")
		)
		(pad "1" smd circle
			(at -0.40005 0)
			(size 0 0)
			(layers "F.Cu" "F.Mask" "F.Paste")
			(net "P3V3_AUX")
		)
		(pad "2" smd circle
			(at 0.40005 0)
			(size 0 0)
			(layers "F.Cu" "F.Mask" "F.Paste")
			(net "GND")
		)
	)
	(footprint ""
		(layer "F.Cu")
		(at 24.804878 -17.623536 90)
		(property "Reference" "C813"
			(at 0 0 90)
			(layer "F.SilkS")
			(hide yes)
			(effects
				(font
					(size 1.27 1.27)
				)
			)
		)
		(property "Value" ""
			(at 0 0 90)
			(layer "F.Fab")
			(effects
				(font
					(size 1.27 1.27)
				)
			)
		)
		(duplicate_pad_numbers_are_jumpers no)
		(fp_line
			(start 0.299974 -0.150114)
			(end 0.299974 0.150114)
			(stroke
				(width 0.1)
				(type default)
			)
			(layer "F.Fab")
		)
		(fp_line
			(start -0.299974 -0.150114)
			(end 0.299974 -0.150114)
			(stroke
				(width 0.1)
				(type default)
			)
			(layer "F.Fab")
		)
		(fp_line
			(start 0.299974 0.150114)
			(end -0.299974 0.150114)
			(stroke
				(width 0.1)
				(type default)
			)
			(layer "F.Fab")
		)
		(fp_line
			(start -0.299974 0.150114)
			(end -0.299974 -0.150114)
			(stroke
				(width 0.1)
				(type default)
			)
			(layer "F.Fab")
		)
		(pad "1" smd rect
			(at -0.2667 0 90)
			(size 0.3048 0.381)
			(layers "F.Cu" "F.Mask" "F.Paste")
			(net "P5E_CPU1_PE1_TX_C_DP<12>")
		)
		(pad "2" smd rect
			(at 0.2667 0 90)
			(size 0.3048 0.381)
			(layers "F.Cu" "F.Mask" "F.Paste")
			(net "P5E_CPU1_PE1_TX_DP<12>")
		)
	)
	(footprint ""
		(layer "F.Cu")
		(at 79.75473 -59.372246 90)
		(property "Reference" "PR3812"
			(at 0 0 90)
			(layer "F.SilkS")
			(hide yes)
			(effects
				(font
					(size 1.27 1.27)
				)
			)
		)
		(property "Value" ""
			(at 0 0 90)
			(layer "F.Fab")
			(effects
				(font
					(size 1.27 1.27)
				)
			)
		)
		(duplicate_pad_numbers_are_jumpers no)
		(fp_line
			(start 0.7874 -0.4064)
			(end 0.7874 0.4064)
			(stroke
				(width 0.1524)
				(type default)
			)
			(layer "F.SilkS")
		)
		(fp_line
			(start -0.7874 -0.4064)
			(end 0.7874 -0.4064)
			(stroke
				(width 0.1524)
				(type default)
			)
			(layer "F.SilkS")
		)
		(fp_line
			(start 0.7874 0.4064)
			(end -0.7874 0.4064)
			(stroke
				(width 0.1524)
				(type default)
			)
			(layer "F.SilkS")
		)
		(fp_line
			(start -0.7874 0.4064)
			(end -0.7874 -0.4064)
			(stroke
				(width 0.1524)
				(type default)
			)
			(layer "F.SilkS")
		)
		(fp_line
			(start -0.12065 -0.305054)
			(end -0.12065 -0.2794)
			(stroke
				(width 0.1)
				(type default)
			)
			(layer "F.Fab")
		)
		(fp_line
			(start -0.67945 -0.305054)
			(end -0.12065 -0.305054)
			(stroke
				(width 0.1)
				(type default)
			)
			(layer "F.Fab")
		)
		(fp_line
			(start 0.67945 -0.3048)
			(end 0.67945 0.3048)
			(stroke
				(width 0.1)
				(type default)
			)
			(layer "F.Fab")
		)
		(fp_line
			(start 0.12065 -0.3048)
			(end 0.67945 -0.3048)
			(stroke
				(width 0.1)
				(type default)
			)
			(layer "F.Fab")
		)
		(fp_line
			(start 0.12065 -0.2794)
			(end 0.12065 -0.3048)
			(stroke
				(width 0.1)
				(type default)
			)
			(layer "F.Fab")
		)
		(fp_line
			(start -0.12065 -0.2794)
			(end 0.12065 -0.2794)
			(stroke
				(width 0.1)
				(type default)
			)
			(layer "F.Fab")
		)
		(fp_line
			(start 0.120396 0.2794)
			(end -0.12065 0.2794)
			(stroke
				(width 0.1)
				(type default)
			)
			(layer "F.Fab")
		)
		(fp_line
			(start -0.12065 0.2794)
			(end -0.12065 0.3048)
			(stroke
				(width 0.1)
				(type default)
			)
			(layer "F.Fab")
		)
		(fp_line
			(start 0.67945 0.3048)
			(end 0.120396 0.3048)
			(stroke
				(width 0.1)
				(type default)
			)
			(layer "F.Fab")
		)
		(fp_line
			(start 0.120396 0.3048)
			(end 0.120396 0.2794)
			(stroke
				(width 0.1)
				(type default)
			)
			(layer "F.Fab")
		)
		(fp_line
			(start -0.12065 0.3048)
			(end -0.67945 0.3048)
			(stroke
				(width 0.1)
				(type default)
			)
			(layer "F.Fab")
		)
		(fp_line
			(start -0.67945 0.3048)
			(end -0.67945 -0.305054)
			(stroke
				(width 0.1)
				(type default)
			)
			(layer "F.Fab")
		)
		(pad "1" smd circle
			(at -0.40005 0 90)
			(size 0 0)
			(layers "F.Cu" "F.Mask" "F.Paste")
			(net "P3V3_OCP_OV_2")
		)
		(pad "2" smd circle
			(at 0.40005 0 90)
			(size 0 0)
			(layers "F.Cu" "F.Mask" "F.Paste")
			(net "GND")
		)
	)
	(footprint ""
		(layer "F.Cu")
		(at 315.110622 -50.155348)
		(property "Reference" "R3040"
			(at 0 0 0)
			(layer "F.SilkS")
			(hide yes)
			(effects
				(font
					(size 1.27 1.27)
				)
			)
		)
		(property "Value" ""
			(at 0 0 0)
			(layer "F.Fab")
			(effects
				(font
					(size 1.27 1.27)
				)
			)
		)
		(duplicate_pad_numbers_are_jumpers no)
		(fp_line
			(start -0.7874 -0.4064)
			(end 0.7874 -0.4064)
			(stroke
				(width 0.1524)
				(type default)
			)
			(layer "F.SilkS")
		)
		(fp_line
			(start -0.7874 0.4064)
			(end -0.7874 -0.4064)
			(stroke
				(width 0.1524)
				(type default)
			)
			(layer "F.SilkS")
		)
		(fp_line
			(start 0.7874 -0.4064)
			(end 0.7874 0.4064)
			(stroke
				(width 0.1524)
				(type default)
			)
			(layer "F.SilkS")
		)
		(fp_line
			(start 0.7874 0.4064)
			(end -0.7874 0.4064)
			(stroke
				(width 0.1524)
				(type default)
			)
			(layer "F.SilkS")
		)
		(fp_line
			(start -0.67945 -0.305054)
			(end -0.12065 -0.305054)
			(stroke
				(width 0.1)
				(type default)
			)
			(layer "F.Fab")
		)
		(fp_line
			(start -0.67945 0.3048)
			(end -0.67945 -0.305054)
			(stroke
				(width 0.1)
				(type default)
			)
			(layer "F.Fab")
		)
		(fp_line
			(start -0.12065 -0.305054)
			(end -0.12065 -0.2794)
			(stroke
				(width 0.1)
				(type default)
			)
			(layer "F.Fab")
		)
		(fp_line
			(start -0.12065 -0.2794)
			(end 0.12065 -0.2794)
			(stroke
				(width 0.1)
				(type default)
			)
			(layer "F.Fab")
		)
		(fp_line
			(start -0.12065 0.2794)
			(end -0.12065 0.3048)
			(stroke
				(width 0.1)
				(type default)
			)
			(layer "F.Fab")
		)
		(fp_line
			(start -0.12065 0.3048)
			(end -0.67945 0.3048)
			(stroke
				(width 0.1)
				(type default)
			)
			(layer "F.Fab")
		)
		(fp_line
			(start 0.120396 0.2794)
			(end -0.12065 0.2794)
			(stroke
				(width 0.1)
				(type default)
			)
			(layer "F.Fab")
		)
		(fp_line
			(start 0.120396 0.3048)
			(end 0.120396 0.2794)
			(stroke
				(width 0.1)
				(type default)
			)
			(layer "F.Fab")
		)
		(fp_line
			(start 0.12065 -0.3048)
			(end 0.67945 -0.3048)
			(stroke
				(width 0.1)
				(type default)
			)
			(layer "F.Fab")
		)
		(fp_line
			(start 0.12065 -0.2794)
			(end 0.12065 -0.3048)
			(stroke
				(width 0.1)
				(type default)
			)
			(layer "F.Fab")
		)
		(fp_line
			(start 0.67945 -0.3048)
			(end 0.67945 0.3048)
			(stroke
				(width 0.1)
				(type default)
			)
			(layer "F.Fab")
		)
		(fp_line
			(start 0.67945 0.3048)
			(end 0.120396 0.3048)
			(stroke
				(width 0.1)
				(type default)
			)
			(layer "F.Fab")
		)
		(pad "1" smd circle
			(at -0.40005 0)
			(size 0 0)
			(layers "F.Cu" "F.Mask" "F.Paste")
			(net "P3V3_AUX")
		)
		(pad "2" smd circle
			(at 0.40005 0)
			(size 0 0)
			(layers "F.Cu" "F.Mask" "F.Paste")
			(net "IRQ_PCH_SCI_WHEA_N")
		)
	)
	(footprint ""
		(layer "F.Cu")
		(at 427.452028 -172.453808)
		(property "Reference" "PC207"
			(at 0 0 0)
			(layer "F.SilkS")
			(hide yes)
			(effects
				(font
					(size 1.27 1.27)
				)
			)
		)
		(property "Value" ""
			(at 0 0 0)
			(layer "F.Fab")
			(effects
				(font
					(size 1.27 1.27)
				)
			)
		)
		(duplicate_pad_numbers_are_jumpers no)
		(fp_line
			(start -3.400044 1.249934)
			(end 3.400044 1.249934)
			(stroke
				(width 0.1524)
				(type default)
			)
			(layer "F.SilkS")
		)
		(fp_circle
			(center 0 1.249934)
			(end 3.400044 1.249934)
			(stroke
				(width 0.1524)
				(type default)
			)
			(fill no)
			(layer "F.SilkS")
		)
		(fp_poly
			(pts
				(arc
					(start -3.400044 1.249934)
					(mid 0 4.649978)
					(end 3.400044 1.249934)
				)
			)
			(stroke
				(width 0)
				(type default)
			)
			(fill yes)
			(layer "F.SilkS")
		)
		(fp_circle
			(center 0 1.249934)
			(end 3.400044 1.249934)
			(stroke
				(width 0.1)
				(type default)
			)
			(fill no)
			(layer "F.Fab")
		)
		(pad "1" thru_hole rect
			(at 0 0)
			(size 1.524 1.524)
			(drill 1.016)
			(layers "*.Cu" "*.Mask")
			(remove_unused_layers no)
			(net "SW_P12V_PVCCINFAON_CPU0_FLT")
			(clearance 0)
			(padstack
				(mode front_inner_back)
				(layer "Inner"
					(shape circle)
					(size 1.524 1.524)
					(clearance 0)
				)
				(layer "B.Cu"
					(shape rect)
					(size 1.524 1.524)
					(clearance 0)
				)
			)
		)
		(pad "2" thru_hole circle
			(at 0 2.500122)
			(size 1.524 1.524)
			(drill 1.016)
			(layers "*.Cu" "*.Mask")
			(remove_unused_layers no)
			(net "GND")
			(clearance 0)
		)
	)
	(footprint ""
		(layer "F.Cu")
		(at 420.682166 -138.333988)
		(property "Reference" "R2392"
			(at 0 0 0)
			(layer "F.SilkS")
			(hide yes)
			(effects
				(font
					(size 1.27 1.27)
				)
			)
		)
		(property "Value" ""
			(at 0 0 0)
			(layer "F.Fab")
			(effects
				(font
					(size 1.27 1.27)
				)
			)
		)
		(duplicate_pad_numbers_are_jumpers no)
		(fp_line
			(start -0.7874 -0.4064)
			(end 0.7874 -0.4064)
			(stroke
				(width 0.1524)
				(type default)
			)
			(layer "F.SilkS")
		)
		(fp_line
			(start -0.7874 0.4064)
			(end -0.7874 -0.4064)
			(stroke
				(width 0.1524)
				(type default)
			)
			(layer "F.SilkS")
		)
		(fp_line
			(start 0.7874 -0.4064)
			(end 0.7874 0.4064)
			(stroke
				(width 0.1524)
				(type default)
			)
			(layer "F.SilkS")
		)
		(fp_line
			(start 0.7874 0.4064)
			(end -0.7874 0.4064)
			(stroke
				(width 0.1524)
				(type default)
			)
			(layer "F.SilkS")
		)
		(fp_line
			(start -0.67945 -0.305054)
			(end -0.12065 -0.305054)
			(stroke
				(width 0.1)
				(type default)
			)
			(layer "F.Fab")
		)
		(fp_line
			(start -0.67945 0.3048)
			(end -0.67945 -0.305054)
			(stroke
				(width 0.1)
				(type default)
			)
			(layer "F.Fab")
		)
		(fp_line
			(start -0.12065 -0.305054)
			(end -0.12065 -0.2794)
			(stroke
				(width 0.1)
				(type default)
			)
			(layer "F.Fab")
		)
		(fp_line
			(start -0.12065 -0.2794)
			(end 0.12065 -0.2794)
			(stroke
				(width 0.1)
				(type default)
			)
			(layer "F.Fab")
		)
		(fp_line
			(start -0.12065 0.2794)
			(end -0.12065 0.3048)
			(stroke
				(width 0.1)
				(type default)
			)
			(layer "F.Fab")
		)
		(fp_line
			(start -0.12065 0.3048)
			(end -0.67945 0.3048)
			(stroke
				(width 0.1)
				(type default)
			)
			(layer "F.Fab")
		)
		(fp_line
			(start 0.120396 0.2794)
			(end -0.12065 0.2794)
			(stroke
				(width 0.1)
				(type default)
			)
			(layer "F.Fab")
		)
		(fp_line
			(start 0.120396 0.3048)
			(end 0.120396 0.2794)
			(stroke
				(width 0.1)
				(type default)
			)
			(layer "F.Fab")
		)
		(fp_line
			(start 0.12065 -0.3048)
			(end 0.67945 -0.3048)
			(stroke
				(width 0.1)
				(type default)
			)
			(layer "F.Fab")
		)
		(fp_line
			(start 0.12065 -0.2794)
			(end 0.12065 -0.3048)
			(stroke
				(width 0.1)
				(type default)
			)
			(layer "F.Fab")
		)
		(fp_line
			(start 0.67945 -0.3048)
			(end 0.67945 0.3048)
			(stroke
				(width 0.1)
				(type default)
			)
			(layer "F.Fab")
		)
		(fp_line
			(start 0.67945 0.3048)
			(end 0.120396 0.3048)
			(stroke
				(width 0.1)
				(type default)
			)
			(layer "F.Fab")
		)
		(pad "1" smd circle
			(at -0.40005 0)
			(size 0 0)
			(layers "F.Cu" "F.Mask" "F.Paste")
			(net "P3V3_AUX")
		)
		(pad "2" smd circle
			(at 0.40005 0)
			(size 0 0)
			(layers "F.Cu" "F.Mask" "F.Paste")
			(net "PVCCINFAON_CPU0_VR_FAULT")
		)
	)
	(footprint ""
		(layer "F.Cu")
		(at 55.090314 -161.539174)
		(property "Reference" "PC2951"
			(at 0 0 0)
			(layer "F.SilkS")
			(hide yes)
			(effects
				(font
					(size 1.27 1.27)
				)
			)
		)
		(property "Value" ""
			(at 0 0 0)
			(layer "F.Fab")
			(effects
				(font
					(size 1.27 1.27)
				)
			)
		)
		(duplicate_pad_numbers_are_jumpers no)
		(fp_line
			(start -0.7874 -0.4064)
			(end 0.7874 -0.4064)
			(stroke
				(width 0.1524)
				(type default)
			)
			(layer "F.SilkS")
		)
		(fp_line
			(start -0.7874 0.4064)
			(end -0.7874 -0.4064)
			(stroke
				(width 0.1524)
				(type default)
			)
			(layer "F.SilkS")
		)
		(fp_line
			(start 0.7874 -0.4064)
			(end 0.7874 0.4064)
			(stroke
				(width 0.1524)
				(type default)
			)
			(layer "F.SilkS")
		)
		(fp_line
			(start 0.7874 0.4064)
			(end -0.7874 0.4064)
			(stroke
				(width 0.1524)
				(type default)
			)
			(layer "F.SilkS")
		)
		(fp_line
			(start -0.67945 -0.305054)
			(end -0.12065 -0.305054)
			(stroke
				(width 0.1)
				(type default)
			)
			(layer "F.Fab")
		)
		(fp_line
			(start -0.67945 0.3048)
			(end -0.67945 -0.305054)
			(stroke
				(width 0.1)
				(type default)
			)
			(layer "F.Fab")
		)
		(fp_line
			(start -0.12065 -0.305054)
			(end -0.12065 -0.2794)
			(stroke
				(width 0.1)
				(type default)
			)
			(layer "F.Fab")
		)
		(fp_line
			(start -0.12065 -0.2794)
			(end 0.12065 -0.2794)
			(stroke
				(width 0.1)
				(type default)
			)
			(layer "F.Fab")
		)
		(fp_line
			(start -0.12065 0.2794)
			(end -0.12065 0.3048)
			(stroke
				(width 0.1)
				(type default)
			)
			(layer "F.Fab")
		)
		(fp_line
			(start -0.12065 0.3048)
			(end -0.67945 0.3048)
			(stroke
				(width 0.1)
				(type default)
			)
			(layer "F.Fab")
		)
		(fp_line
			(start 0.120396 0.2794)
			(end -0.12065 0.2794)
			(stroke
				(width 0.1)
				(type default)
			)
			(layer "F.Fab")
		)
		(fp_line
			(start 0.120396 0.3048)
			(end 0.120396 0.2794)
			(stroke
				(width 0.1)
				(type default)
			)
			(layer "F.Fab")
		)
		(fp_line
			(start 0.12065 -0.3048)
			(end 0.67945 -0.3048)
			(stroke
				(width 0.1)
				(type default)
			)
			(layer "F.Fab")
		)
		(fp_line
			(start 0.12065 -0.2794)
			(end 0.12065 -0.3048)
			(stroke
				(width 0.1)
				(type default)
			)
			(layer "F.Fab")
		)
		(fp_line
			(start 0.67945 -0.3048)
			(end 0.67945 0.3048)
			(stroke
				(width 0.1)
				(type default)
			)
			(layer "F.Fab")
		)
		(fp_line
			(start 0.67945 0.3048)
			(end 0.120396 0.3048)
			(stroke
				(width 0.1)
				(type default)
			)
			(layer "F.Fab")
		)
		(pad "1" smd circle
			(at -0.40005 0)
			(size 0 0)
			(layers "F.Cu" "F.Mask" "F.Paste")
			(net "PVCCFA_EHV_CPU1_PVCC")
		)
		(pad "2" smd circle
			(at 0.40005 0)
			(size 0 0)
			(layers "F.Cu" "F.Mask" "F.Paste")
			(net "GND")
		)
	)
	(footprint ""
		(layer "F.Cu")
		(at 116.561616 -256.6543 -90)
		(property "Reference" "C289"
			(at 0 0 270)
			(layer "F.SilkS")
			(hide yes)
			(effects
				(font
					(size 1.27 1.27)
				)
			)
		)
		(property "Value" ""
			(at 0 0 270)
			(layer "F.Fab")
			(effects
				(font
					(size 1.27 1.27)
				)
			)
		)
		(duplicate_pad_numbers_are_jumpers no)
		(fp_line
			(start -0.7874 0.4064)
			(end -0.7874 -0.4064)
			(stroke
				(width 0.1524)
				(type default)
			)
			(layer "F.SilkS")
		)
		(fp_line
			(start 0.7874 0.4064)
			(end -0.7874 0.4064)
			(stroke
				(width 0.1524)
				(type default)
			)
			(layer "F.SilkS")
		)
		(fp_line
			(start -0.7874 -0.4064)
			(end 0.7874 -0.4064)
			(stroke
				(width 0.1524)
				(type default)
			)
			(layer "F.SilkS")
		)
		(fp_line
			(start 0.7874 -0.4064)
			(end 0.7874 0.4064)
			(stroke
				(width 0.1524)
				(type default)
			)
			(layer "F.SilkS")
		)
		(fp_line
			(start -0.67945 0.3048)
			(end -0.67945 -0.305054)
			(stroke
				(width 0.1)
				(type default)
			)
			(layer "F.Fab")
		)
		(fp_line
			(start -0.12065 0.3048)
			(end -0.67945 0.3048)
			(stroke
				(width 0.1)
				(type default)
			)
			(layer "F.Fab")
		)
		(fp_line
			(start 0.120396 0.3048)
			(end 0.120396 0.2794)
			(stroke
				(width 0.1)
				(type default)
			)
			(layer "F.Fab")
		)
		(fp_line
			(start 0.67945 0.3048)
			(end 0.120396 0.3048)
			(stroke
				(width 0.1)
				(type default)
			)
			(layer "F.Fab")
		)
		(fp_line
			(start -0.12065 0.2794)
			(end -0.12065 0.3048)
			(stroke
				(width 0.1)
				(type default)
			)
			(layer "F.Fab")
		)
		(fp_line
			(start 0.120396 0.2794)
			(end -0.12065 0.2794)
			(stroke
				(width 0.1)
				(type default)
			)
			(layer "F.Fab")
		)
		(fp_line
			(start -0.12065 -0.2794)
			(end 0.12065 -0.2794)
			(stroke
				(width 0.1)
				(type default)
			)
			(layer "F.Fab")
		)
		(fp_line
			(start 0.12065 -0.2794)
			(end 0.12065 -0.3048)
			(stroke
				(width 0.1)
				(type default)
			)
			(layer "F.Fab")
		)
		(fp_line
			(start 0.12065 -0.3048)
			(end 0.67945 -0.3048)
			(stroke
				(width 0.1)
				(type default)
			)
			(layer "F.Fab")
		)
		(fp_line
			(start 0.67945 -0.3048)
			(end 0.67945 0.3048)
			(stroke
				(width 0.1)
				(type default)
			)
			(layer "F.Fab")
		)
		(fp_line
			(start -0.67945 -0.305054)
			(end -0.12065 -0.305054)
			(stroke
				(width 0.1)
				(type default)
			)
			(layer "F.Fab")
		)
		(fp_line
			(start -0.12065 -0.305054)
			(end -0.12065 -0.2794)
			(stroke
				(width 0.1)
				(type default)
			)
			(layer "F.Fab")
		)
		(pad "1" smd circle
			(at -0.40005 0 270)
			(size 0 0)
			(layers "F.Cu" "F.Mask" "F.Paste")
			(net "PVCCIN_CPU1")
		)
		(pad "2" smd circle
			(at 0.40005 0 270)
			(size 0 0)
			(layers "F.Cu" "F.Mask" "F.Paste")
			(net "GND")
		)
	)
	(footprint ""
		(layer "F.Cu")
		(at 175.4124 -94.338648 90)
		(property "Reference" "R4583"
			(at 0 0 90)
			(layer "F.SilkS")
			(hide yes)
			(effects
				(font
					(size 1.27 1.27)
				)
			)
		)
		(property "Value" ""
			(at 0 0 90)
			(layer "F.Fab")
			(effects
				(font
					(size 1.27 1.27)
				)
			)
		)
		(duplicate_pad_numbers_are_jumpers no)
		(fp_line
			(start 0.7874 -0.4064)
			(end 0.7874 0.4064)
			(stroke
				(width 0.1524)
				(type default)
			)
			(layer "F.SilkS")
		)
		(fp_line
			(start -0.7874 -0.4064)
			(end 0.7874 -0.4064)
			(stroke
				(width 0.1524)
				(type default)
			)
			(layer "F.SilkS")
		)
		(fp_line
			(start 0.7874 0.4064)
			(end -0.7874 0.4064)
			(stroke
				(width 0.1524)
				(type default)
			)
			(layer "F.SilkS")
		)
		(fp_line
			(start -0.7874 0.4064)
			(end -0.7874 -0.4064)
			(stroke
				(width 0.1524)
				(type default)
			)
			(layer "F.SilkS")
		)
		(fp_line
			(start -0.12065 -0.305054)
			(end -0.12065 -0.2794)
			(stroke
				(width 0.1)
				(type default)
			)
			(layer "F.Fab")
		)
		(fp_line
			(start -0.67945 -0.305054)
			(end -0.12065 -0.305054)
			(stroke
				(width 0.1)
				(type default)
			)
			(layer "F.Fab")
		)
		(fp_line
			(start 0.67945 -0.3048)
			(end 0.67945 0.3048)
			(stroke
				(width 0.1)
				(type default)
			)
			(layer "F.Fab")
		)
		(fp_line
			(start 0.12065 -0.3048)
			(end 0.67945 -0.3048)
			(stroke
				(width 0.1)
				(type default)
			)
			(layer "F.Fab")
		)
		(fp_line
			(start 0.12065 -0.2794)
			(end 0.12065 -0.3048)
			(stroke
				(width 0.1)
				(type default)
			)
			(layer "F.Fab")
		)
		(fp_line
			(start -0.12065 -0.2794)
			(end 0.12065 -0.2794)
			(stroke
				(width 0.1)
				(type default)
			)
			(layer "F.Fab")
		)
		(fp_line
			(start 0.120396 0.2794)
			(end -0.12065 0.2794)
			(stroke
				(width 0.1)
				(type default)
			)
			(layer "F.Fab")
		)
		(fp_line
			(start -0.12065 0.2794)
			(end -0.12065 0.3048)
			(stroke
				(width 0.1)
				(type default)
			)
			(layer "F.Fab")
		)
		(fp_line
			(start 0.67945 0.3048)
			(end 0.120396 0.3048)
			(stroke
				(width 0.1)
				(type default)
			)
			(layer "F.Fab")
		)
		(fp_line
			(start 0.120396 0.3048)
			(end 0.120396 0.2794)
			(stroke
				(width 0.1)
				(type default)
			)
			(layer "F.Fab")
		)
		(fp_line
			(start -0.12065 0.3048)
			(end -0.67945 0.3048)
			(stroke
				(width 0.1)
				(type default)
			)
			(layer "F.Fab")
		)
		(fp_line
			(start -0.67945 0.3048)
			(end -0.67945 -0.305054)
			(stroke
				(width 0.1)
				(type default)
			)
			(layer "F.Fab")
		)
		(pad "1" smd rect
			(at -0.40005 0 270)
			(size 0.4572 0.508)
			(layers "F.Cu" "F.Mask" "F.Paste")
			(net "FM_BOARD_BMC_SKU_ID1")
		)
		(pad "2" smd rect
			(at 0.40005 0 270)
			(size 0.4572 0.508)
			(layers "F.Cu" "F.Mask" "F.Paste")
			(net "GND")
		)
	)
	(footprint ""
		(layer "F.Cu")
		(at 40.627554 -110.587282 180)
		(property "Reference" "R3862"
			(at 0 0 180)
			(layer "F.SilkS")
			(hide yes)
			(effects
				(font
					(size 1.27 1.27)
				)
			)
		)
		(property "Value" ""
			(at 0 0 180)
			(layer "F.Fab")
			(effects
				(font
					(size 1.27 1.27)
				)
			)
		)
		(duplicate_pad_numbers_are_jumpers no)
		(fp_line
			(start 0.7874 0.4064)
			(end -0.7874 0.4064)
			(stroke
				(width 0.1524)
				(type default)
			)
			(layer "F.SilkS")
		)
		(fp_line
			(start 0.7874 -0.4064)
			(end 0.7874 0.4064)
			(stroke
				(width 0.1524)
				(type default)
			)
			(layer "F.SilkS")
		)
		(fp_line
			(start -0.7874 0.4064)
			(end -0.7874 -0.4064)
			(stroke
				(width 0.1524)
				(type default)
			)
			(layer "F.SilkS")
		)
		(fp_line
			(start -0.7874 -0.4064)
			(end 0.7874 -0.4064)
			(stroke
				(width 0.1524)
				(type default)
			)
			(layer "F.SilkS")
		)
		(fp_line
			(start 0.67945 0.3048)
			(end 0.120396 0.3048)
			(stroke
				(width 0.1)
				(type default)
			)
			(layer "F.Fab")
		)
		(fp_line
			(start 0.67945 -0.3048)
			(end 0.67945 0.3048)
			(stroke
				(width 0.1)
				(type default)
			)
			(layer "F.Fab")
		)
		(fp_line
			(start 0.12065 -0.2794)
			(end 0.12065 -0.3048)
			(stroke
				(width 0.1)
				(type default)
			)
			(layer "F.Fab")
		)
		(fp_line
			(start 0.12065 -0.3048)
			(end 0.67945 -0.3048)
			(stroke
				(width 0.1)
				(type default)
			)
			(layer "F.Fab")
		)
		(fp_line
			(start 0.120396 0.3048)
			(end 0.120396 0.2794)
			(stroke
				(width 0.1)
				(type default)
			)
			(layer "F.Fab")
		)
		(fp_line
			(start 0.120396 0.2794)
			(end -0.12065 0.2794)
			(stroke
				(width 0.1)
				(type default)
			)
			(layer "F.Fab")
		)
		(fp_line
			(start -0.12065 0.3048)
			(end -0.67945 0.3048)
			(stroke
				(width 0.1)
				(type default)
			)
			(layer "F.Fab")
		)
		(fp_line
			(start -0.12065 0.2794)
			(end -0.12065 0.3048)
			(stroke
				(width 0.1)
				(type default)
			)
			(layer "F.Fab")
		)
		(fp_line
			(start -0.12065 -0.2794)
			(end 0.12065 -0.2794)
			(stroke
				(width 0.1)
				(type default)
			)
			(layer "F.Fab")
		)
		(fp_line
			(start -0.12065 -0.305054)
			(end -0.12065 -0.2794)
			(stroke
				(width 0.1)
				(type default)
			)
			(layer "F.Fab")
		)
		(fp_line
			(start -0.67945 0.3048)
			(end -0.67945 -0.305054)
			(stroke
				(width 0.1)
				(type default)
			)
			(layer "F.Fab")
		)
		(fp_line
			(start -0.67945 -0.305054)
			(end -0.12065 -0.305054)
			(stroke
				(width 0.1)
				(type default)
			)
			(layer "F.Fab")
		)
		(pad "1" smd rect
			(at -0.40005 0)
			(size 0.4572 0.508)
			(layers "F.Cu" "F.Mask" "F.Paste")
			(net "P12V_OCP_V3_2_ISENSE_MPS_TIC")
		)
		(pad "2" smd rect
			(at 0.40005 0)
			(size 0.4572 0.508)
			(layers "F.Cu" "F.Mask" "F.Paste")
			(net "P12V_OCP_V3_2_ISENSE_TIC")
		)
	)
	(footprint ""
		(layer "F.Cu")
		(at 200.6346 -122.748548)
		(property "Reference" "R4608"
			(at 0 0 0)
			(layer "F.SilkS")
			(hide yes)
			(effects
				(font
					(size 1.27 1.27)
				)
			)
		)
		(property "Value" ""
			(at 0 0 0)
			(layer "F.Fab")
			(effects
				(font
					(size 1.27 1.27)
				)
			)
		)
		(duplicate_pad_numbers_are_jumpers no)
		(fp_line
			(start -0.7874 -0.4064)
			(end 0.7874 -0.4064)
			(stroke
				(width 0.1524)
				(type default)
			)
			(layer "F.SilkS")
		)
		(fp_line
			(start -0.7874 0.4064)
			(end -0.7874 -0.4064)
			(stroke
				(width 0.1524)
				(type default)
			)
			(layer "F.SilkS")
		)
		(fp_line
			(start 0.7874 -0.4064)
			(end 0.7874 0.4064)
			(stroke
				(width 0.1524)
				(type default)
			)
			(layer "F.SilkS")
		)
		(fp_line
			(start 0.7874 0.4064)
			(end -0.7874 0.4064)
			(stroke
				(width 0.1524)
				(type default)
			)
			(layer "F.SilkS")
		)
		(fp_line
			(start -0.67945 -0.305054)
			(end -0.12065 -0.305054)
			(stroke
				(width 0.1)
				(type default)
			)
			(layer "F.Fab")
		)
		(fp_line
			(start -0.67945 0.3048)
			(end -0.67945 -0.305054)
			(stroke
				(width 0.1)
				(type default)
			)
			(layer "F.Fab")
		)
		(fp_line
			(start -0.12065 -0.305054)
			(end -0.12065 -0.2794)
			(stroke
				(width 0.1)
				(type default)
			)
			(layer "F.Fab")
		)
		(fp_line
			(start -0.12065 -0.2794)
			(end 0.12065 -0.2794)
			(stroke
				(width 0.1)
				(type default)
			)
			(layer "F.Fab")
		)
		(fp_line
			(start -0.12065 0.2794)
			(end -0.12065 0.3048)
			(stroke
				(width 0.1)
				(type default)
			)
			(layer "F.Fab")
		)
		(fp_line
			(start -0.12065 0.3048)
			(end -0.67945 0.3048)
			(stroke
				(width 0.1)
				(type default)
			)
			(layer "F.Fab")
		)
		(fp_line
			(start 0.120396 0.2794)
			(end -0.12065 0.2794)
			(stroke
				(width 0.1)
				(type default)
			)
			(layer "F.Fab")
		)
		(fp_line
			(start 0.120396 0.3048)
			(end 0.120396 0.2794)
			(stroke
				(width 0.1)
				(type default)
			)
			(layer "F.Fab")
		)
		(fp_line
			(start 0.12065 -0.3048)
			(end 0.67945 -0.3048)
			(stroke
				(width 0.1)
				(type default)
			)
			(layer "F.Fab")
		)
		(fp_line
			(start 0.12065 -0.2794)
			(end 0.12065 -0.3048)
			(stroke
				(width 0.1)
				(type default)
			)
			(layer "F.Fab")
		)
		(fp_line
			(start 0.67945 -0.3048)
			(end 0.67945 0.3048)
			(stroke
				(width 0.1)
				(type default)
			)
			(layer "F.Fab")
		)
		(fp_line
			(start 0.67945 0.3048)
			(end 0.120396 0.3048)
			(stroke
				(width 0.1)
				(type default)
			)
			(layer "F.Fab")
		)
		(pad "1" smd circle
			(at -0.40005 0)
			(size 0 0)
			(layers "F.Cu" "F.Mask" "F.Paste")
			(net "GPU_FPGA_RST_N")
		)
		(pad "2" smd circle
			(at 0.40005 0)
			(size 0 0)
			(layers "F.Cu" "F.Mask" "F.Paste")
			(net "GPU_FPGA_RST_R_N")
		)
	)
	(footprint ""
		(layer "F.Cu")
		(at 63.194438 -29.398722 180)
		(property "Reference" "PR3851"
			(at 0 0 180)
			(layer "F.SilkS")
			(hide yes)
			(effects
				(font
					(size 1.27 1.27)
				)
			)
		)
		(property "Value" ""
			(at 0 0 180)
			(layer "F.Fab")
			(effects
				(font
					(size 1.27 1.27)
				)
			)
		)
		(duplicate_pad_numbers_are_jumpers no)
		(fp_line
			(start 0.7874 0.4064)
			(end -0.7874 0.4064)
			(stroke
				(width 0.1524)
				(type default)
			)
			(layer "F.SilkS")
		)
		(fp_line
			(start 0.7874 -0.4064)
			(end 0.7874 0.4064)
			(stroke
				(width 0.1524)
				(type default)
			)
			(layer "F.SilkS")
		)
		(fp_line
			(start -0.7874 0.4064)
			(end -0.7874 -0.4064)
			(stroke
				(width 0.1524)
				(type default)
			)
			(layer "F.SilkS")
		)
		(fp_line
			(start -0.7874 -0.4064)
			(end 0.7874 -0.4064)
			(stroke
				(width 0.1524)
				(type default)
			)
			(layer "F.SilkS")
		)
		(fp_line
			(start 0.67945 0.3048)
			(end 0.120396 0.3048)
			(stroke
				(width 0.1)
				(type default)
			)
			(layer "F.Fab")
		)
		(fp_line
			(start 0.67945 -0.3048)
			(end 0.67945 0.3048)
			(stroke
				(width 0.1)
				(type default)
			)
			(layer "F.Fab")
		)
		(fp_line
			(start 0.12065 -0.2794)
			(end 0.12065 -0.3048)
			(stroke
				(width 0.1)
				(type default)
			)
			(layer "F.Fab")
		)
		(fp_line
			(start 0.12065 -0.3048)
			(end 0.67945 -0.3048)
			(stroke
				(width 0.1)
				(type default)
			)
			(layer "F.Fab")
		)
		(fp_line
			(start 0.120396 0.3048)
			(end 0.120396 0.2794)
			(stroke
				(width 0.1)
				(type default)
			)
			(layer "F.Fab")
		)
		(fp_line
			(start 0.120396 0.2794)
			(end -0.12065 0.2794)
			(stroke
				(width 0.1)
				(type default)
			)
			(layer "F.Fab")
		)
		(fp_line
			(start -0.12065 0.3048)
			(end -0.67945 0.3048)
			(stroke
				(width 0.1)
				(type default)
			)
			(layer "F.Fab")
		)
		(fp_line
			(start -0.12065 0.2794)
			(end -0.12065 0.3048)
			(stroke
				(width 0.1)
				(type default)
			)
			(layer "F.Fab")
		)
		(fp_line
			(start -0.12065 -0.2794)
			(end 0.12065 -0.2794)
			(stroke
				(width 0.1)
				(type default)
			)
			(layer "F.Fab")
		)
		(fp_line
			(start -0.12065 -0.305054)
			(end -0.12065 -0.2794)
			(stroke
				(width 0.1)
				(type default)
			)
			(layer "F.Fab")
		)
		(fp_line
			(start -0.67945 0.3048)
			(end -0.67945 -0.305054)
			(stroke
				(width 0.1)
				(type default)
			)
			(layer "F.Fab")
		)
		(fp_line
			(start -0.67945 -0.305054)
			(end -0.12065 -0.305054)
			(stroke
				(width 0.1)
				(type default)
			)
			(layer "F.Fab")
		)
		(pad "1" smd circle
			(at -0.40005 0 180)
			(size 0 0)
			(layers "F.Cu" "F.Mask" "F.Paste")
			(net "P12V_OCP_FLTB_2")
		)
		(pad "2" smd circle
			(at 0.40005 0 180)
			(size 0 0)
			(layers "F.Cu" "F.Mask" "F.Paste")
			(net "P3V3_AUX")
		)
	)
	(footprint ""
		(layer "F.Cu")
		(at 357.735632 -397.519398)
		(property "Reference" "R2668"
			(at 0 0 0)
			(layer "F.SilkS")
			(hide yes)
			(effects
				(font
					(size 1.27 1.27)
				)
			)
		)
		(property "Value" ""
			(at 0 0 0)
			(layer "F.Fab")
			(effects
				(font
					(size 1.27 1.27)
				)
			)
		)
		(duplicate_pad_numbers_are_jumpers no)
		(fp_line
			(start -0.7874 -0.4064)
			(end 0.7874 -0.4064)
			(stroke
				(width 0.1524)
				(type default)
			)
			(layer "F.SilkS")
		)
		(fp_line
			(start -0.7874 0.4064)
			(end -0.7874 -0.4064)
			(stroke
				(width 0.1524)
				(type default)
			)
			(layer "F.SilkS")
		)
		(fp_line
			(start 0.7874 -0.4064)
			(end 0.7874 0.4064)
			(stroke
				(width 0.1524)
				(type default)
			)
			(layer "F.SilkS")
		)
		(fp_line
			(start 0.7874 0.4064)
			(end -0.7874 0.4064)
			(stroke
				(width 0.1524)
				(type default)
			)
			(layer "F.SilkS")
		)
		(fp_line
			(start -0.67945 -0.305054)
			(end -0.12065 -0.305054)
			(stroke
				(width 0.1)
				(type default)
			)
			(layer "F.Fab")
		)
		(fp_line
			(start -0.67945 0.3048)
			(end -0.67945 -0.305054)
			(stroke
				(width 0.1)
				(type default)
			)
			(layer "F.Fab")
		)
		(fp_line
			(start -0.12065 -0.305054)
			(end -0.12065 -0.2794)
			(stroke
				(width 0.1)
				(type default)
			)
			(layer "F.Fab")
		)
		(fp_line
			(start -0.12065 -0.2794)
			(end 0.12065 -0.2794)
			(stroke
				(width 0.1)
				(type default)
			)
			(layer "F.Fab")
		)
		(fp_line
			(start -0.12065 0.2794)
			(end -0.12065 0.3048)
			(stroke
				(width 0.1)
				(type default)
			)
			(layer "F.Fab")
		)
		(fp_line
			(start -0.12065 0.3048)
			(end -0.67945 0.3048)
			(stroke
				(width 0.1)
				(type default)
			)
			(layer "F.Fab")
		)
		(fp_line
			(start 0.120396 0.2794)
			(end -0.12065 0.2794)
			(stroke
				(width 0.1)
				(type default)
			)
			(layer "F.Fab")
		)
		(fp_line
			(start 0.120396 0.3048)
			(end 0.120396 0.2794)
			(stroke
				(width 0.1)
				(type default)
			)
			(layer "F.Fab")
		)
		(fp_line
			(start 0.12065 -0.3048)
			(end 0.67945 -0.3048)
			(stroke
				(width 0.1)
				(type default)
			)
			(layer "F.Fab")
		)
		(fp_line
			(start 0.12065 -0.2794)
			(end 0.12065 -0.3048)
			(stroke
				(width 0.1)
				(type default)
			)
			(layer "F.Fab")
		)
		(fp_line
			(start 0.67945 -0.3048)
			(end 0.67945 0.3048)
			(stroke
				(width 0.1)
				(type default)
			)
			(layer "F.Fab")
		)
		(fp_line
			(start 0.67945 0.3048)
			(end 0.120396 0.3048)
			(stroke
				(width 0.1)
				(type default)
			)
			(layer "F.Fab")
		)
		(pad "1" smd circle
			(at -0.40005 0)
			(size 0 0)
			(layers "F.Cu" "F.Mask" "F.Paste")
			(net "P3V3_AUX")
		)
		(pad "2" smd circle
			(at 0.40005 0)
			(size 0 0)
			(layers "F.Cu" "F.Mask" "F.Paste")
			(net "I3C_BMC_SWB_BUF_R_SDA")
		)
	)
	(footprint ""
		(layer "F.Cu")
		(at 369.228878 -394.647166 180)
		(property "Reference" "R4165"
			(at 0 0 180)
			(layer "F.SilkS")
			(hide yes)
			(effects
				(font
					(size 1.27 1.27)
				)
			)
		)
		(property "Value" ""
			(at 0 0 180)
			(layer "F.Fab")
			(effects
				(font
					(size 1.27 1.27)
				)
			)
		)
		(duplicate_pad_numbers_are_jumpers no)
		(fp_line
			(start 0.7874 0.4064)
			(end -0.7874 0.4064)
			(stroke
				(width 0.1524)
				(type default)
			)
			(layer "F.SilkS")
		)
		(fp_line
			(start 0.7874 -0.4064)
			(end 0.7874 0.4064)
			(stroke
				(width 0.1524)
				(type default)
			)
			(layer "F.SilkS")
		)
		(fp_line
			(start -0.7874 0.4064)
			(end -0.7874 -0.4064)
			(stroke
				(width 0.1524)
				(type default)
			)
			(layer "F.SilkS")
		)
		(fp_line
			(start -0.7874 -0.4064)
			(end 0.7874 -0.4064)
			(stroke
				(width 0.1524)
				(type default)
			)
			(layer "F.SilkS")
		)
		(fp_line
			(start 0.67945 0.3048)
			(end 0.120396 0.3048)
			(stroke
				(width 0.1)
				(type default)
			)
			(layer "F.Fab")
		)
		(fp_line
			(start 0.67945 -0.3048)
			(end 0.67945 0.3048)
			(stroke
				(width 0.1)
				(type default)
			)
			(layer "F.Fab")
		)
		(fp_line
			(start 0.12065 -0.2794)
			(end 0.12065 -0.3048)
			(stroke
				(width 0.1)
				(type default)
			)
			(layer "F.Fab")
		)
		(fp_line
			(start 0.12065 -0.3048)
			(end 0.67945 -0.3048)
			(stroke
				(width 0.1)
				(type default)
			)
			(layer "F.Fab")
		)
		(fp_line
			(start 0.120396 0.3048)
			(end 0.120396 0.2794)
			(stroke
				(width 0.1)
				(type default)
			)
			(layer "F.Fab")
		)
		(fp_line
			(start 0.120396 0.2794)
			(end -0.12065 0.2794)
			(stroke
				(width 0.1)
				(type default)
			)
			(layer "F.Fab")
		)
		(fp_line
			(start -0.12065 0.3048)
			(end -0.67945 0.3048)
			(stroke
				(width 0.1)
				(type default)
			)
			(layer "F.Fab")
		)
		(fp_line
			(start -0.12065 0.2794)
			(end -0.12065 0.3048)
			(stroke
				(width 0.1)
				(type default)
			)
			(layer "F.Fab")
		)
		(fp_line
			(start -0.12065 -0.2794)
			(end 0.12065 -0.2794)
			(stroke
				(width 0.1)
				(type default)
			)
			(layer "F.Fab")
		)
		(fp_line
			(start -0.12065 -0.305054)
			(end -0.12065 -0.2794)
			(stroke
				(width 0.1)
				(type default)
			)
			(layer "F.Fab")
		)
		(fp_line
			(start -0.67945 0.3048)
			(end -0.67945 -0.305054)
			(stroke
				(width 0.1)
				(type default)
			)
			(layer "F.Fab")
		)
		(fp_line
			(start -0.67945 -0.305054)
			(end -0.12065 -0.305054)
			(stroke
				(width 0.1)
				(type default)
			)
			(layer "F.Fab")
		)
		(pad "1" smd circle
			(at -0.40005 0 180)
			(size 0 0)
			(layers "F.Cu" "F.Mask" "F.Paste")
			(net "P3V3_AUX")
		)
		(pad "2" smd circle
			(at 0.40005 0 180)
			(size 0 0)
			(layers "F.Cu" "F.Mask" "F.Paste")
			(net "GPU_3V3IO_RSVD4_N")
		)
	)
	(footprint ""
		(layer "F.Cu")
		(at 385.734052 -68.126356 180)
		(property "Reference" "R776"
			(at 0 0 180)
			(layer "F.SilkS")
			(hide yes)
			(effects
				(font
					(size 1.27 1.27)
				)
			)
		)
		(property "Value" ""
			(at 0 0 180)
			(layer "F.Fab")
			(effects
				(font
					(size 1.27 1.27)
				)
			)
		)
		(duplicate_pad_numbers_are_jumpers no)
		(fp_line
			(start 0.7874 0.4064)
			(end -0.7874 0.4064)
			(stroke
				(width 0.1524)
				(type default)
			)
			(layer "F.SilkS")
		)
		(fp_line
			(start 0.7874 -0.4064)
			(end 0.7874 0.4064)
			(stroke
				(width 0.1524)
				(type default)
			)
			(layer "F.SilkS")
		)
		(fp_line
			(start -0.7874 0.4064)
			(end -0.7874 -0.4064)
			(stroke
				(width 0.1524)
				(type default)
			)
			(layer "F.SilkS")
		)
		(fp_line
			(start -0.7874 -0.4064)
			(end 0.7874 -0.4064)
			(stroke
				(width 0.1524)
				(type default)
			)
			(layer "F.SilkS")
		)
		(fp_line
			(start 0.67945 0.3048)
			(end 0.120396 0.3048)
			(stroke
				(width 0.1)
				(type default)
			)
			(layer "F.Fab")
		)
		(fp_line
			(start 0.67945 -0.3048)
			(end 0.67945 0.3048)
			(stroke
				(width 0.1)
				(type default)
			)
			(layer "F.Fab")
		)
		(fp_line
			(start 0.12065 -0.2794)
			(end 0.12065 -0.3048)
			(stroke
				(width 0.1)
				(type default)
			)
			(layer "F.Fab")
		)
		(fp_line
			(start 0.12065 -0.3048)
			(end 0.67945 -0.3048)
			(stroke
				(width 0.1)
				(type default)
			)
			(layer "F.Fab")
		)
		(fp_line
			(start 0.120396 0.3048)
			(end 0.120396 0.2794)
			(stroke
				(width 0.1)
				(type default)
			)
			(layer "F.Fab")
		)
		(fp_line
			(start 0.120396 0.2794)
			(end -0.12065 0.2794)
			(stroke
				(width 0.1)
				(type default)
			)
			(layer "F.Fab")
		)
		(fp_line
			(start -0.12065 0.3048)
			(end -0.67945 0.3048)
			(stroke
				(width 0.1)
				(type default)
			)
			(layer "F.Fab")
		)
		(fp_line
			(start -0.12065 0.2794)
			(end -0.12065 0.3048)
			(stroke
				(width 0.1)
				(type default)
			)
			(layer "F.Fab")
		)
		(fp_line
			(start -0.12065 -0.2794)
			(end 0.12065 -0.2794)
			(stroke
				(width 0.1)
				(type default)
			)
			(layer "F.Fab")
		)
		(fp_line
			(start -0.12065 -0.305054)
			(end -0.12065 -0.2794)
			(stroke
				(width 0.1)
				(type default)
			)
			(layer "F.Fab")
		)
		(fp_line
			(start -0.67945 0.3048)
			(end -0.67945 -0.305054)
			(stroke
				(width 0.1)
				(type default)
			)
			(layer "F.Fab")
		)
		(fp_line
			(start -0.67945 -0.305054)
			(end -0.12065 -0.305054)
			(stroke
				(width 0.1)
				(type default)
			)
			(layer "F.Fab")
		)
		(pad "1" smd circle
			(at -0.40005 0 180)
			(size 0 0)
			(layers "F.Cu" "F.Mask" "F.Paste")
			(net "JTAG_DBP_TDO_R")
		)
		(pad "2" smd circle
			(at 0.40005 0 180)
			(size 0 0)
			(layers "F.Cu" "F.Mask" "F.Paste")
			(net "JTAG_DBP_TDO")
		)
	)
	(footprint ""
		(layer "F.Cu")
		(at 44.169584 -107.031282)
		(property "Reference" "R1785"
			(at 0 0 0)
			(layer "F.SilkS")
			(hide yes)
			(effects
				(font
					(size 1.27 1.27)
				)
			)
		)
		(property "Value" ""
			(at 0 0 0)
			(layer "F.Fab")
			(effects
				(font
					(size 1.27 1.27)
				)
			)
		)
		(duplicate_pad_numbers_are_jumpers no)
		(fp_line
			(start -0.7874 -0.4064)
			(end 0.7874 -0.4064)
			(stroke
				(width 0.1524)
				(type default)
			)
			(layer "F.SilkS")
		)
		(fp_line
			(start -0.7874 0.4064)
			(end -0.7874 -0.4064)
			(stroke
				(width 0.1524)
				(type default)
			)
			(layer "F.SilkS")
		)
		(fp_line
			(start 0.7874 -0.4064)
			(end 0.7874 0.4064)
			(stroke
				(width 0.1524)
				(type default)
			)
			(layer "F.SilkS")
		)
		(fp_line
			(start 0.7874 0.4064)
			(end -0.7874 0.4064)
			(stroke
				(width 0.1524)
				(type default)
			)
			(layer "F.SilkS")
		)
		(fp_line
			(start -0.67945 -0.305054)
			(end -0.12065 -0.305054)
			(stroke
				(width 0.1)
				(type default)
			)
			(layer "F.Fab")
		)
		(fp_line
			(start -0.67945 0.3048)
			(end -0.67945 -0.305054)
			(stroke
				(width 0.1)
				(type default)
			)
			(layer "F.Fab")
		)
		(fp_line
			(start -0.12065 -0.305054)
			(end -0.12065 -0.2794)
			(stroke
				(width 0.1)
				(type default)
			)
			(layer "F.Fab")
		)
		(fp_line
			(start -0.12065 -0.2794)
			(end 0.12065 -0.2794)
			(stroke
				(width 0.1)
				(type default)
			)
			(layer "F.Fab")
		)
		(fp_line
			(start -0.12065 0.2794)
			(end -0.12065 0.3048)
			(stroke
				(width 0.1)
				(type default)
			)
			(layer "F.Fab")
		)
		(fp_line
			(start -0.12065 0.3048)
			(end -0.67945 0.3048)
			(stroke
				(width 0.1)
				(type default)
			)
			(layer "F.Fab")
		)
		(fp_line
			(start 0.120396 0.2794)
			(end -0.12065 0.2794)
			(stroke
				(width 0.1)
				(type default)
			)
			(layer "F.Fab")
		)
		(fp_line
			(start 0.120396 0.3048)
			(end 0.120396 0.2794)
			(stroke
				(width 0.1)
				(type default)
			)
			(layer "F.Fab")
		)
		(fp_line
			(start 0.12065 -0.3048)
			(end 0.67945 -0.3048)
			(stroke
				(width 0.1)
				(type default)
			)
			(layer "F.Fab")
		)
		(fp_line
			(start 0.12065 -0.2794)
			(end 0.12065 -0.3048)
			(stroke
				(width 0.1)
				(type default)
			)
			(layer "F.Fab")
		)
		(fp_line
			(start 0.67945 -0.3048)
			(end 0.67945 0.3048)
			(stroke
				(width 0.1)
				(type default)
			)
			(layer "F.Fab")
		)
		(fp_line
			(start 0.67945 0.3048)
			(end 0.120396 0.3048)
			(stroke
				(width 0.1)
				(type default)
			)
			(layer "F.Fab")
		)
		(pad "1" smd circle
			(at -0.40005 0)
			(size 0 0)
			(layers "F.Cu" "F.Mask" "F.Paste")
			(net "P3V3_AUX_ADC")
		)
		(pad "2" smd circle
			(at 0.40005 0)
			(size 0 0)
			(layers "F.Cu" "F.Mask" "F.Paste")
			(net "GND")
		)
	)
	(footprint ""
		(layer "F.Cu")
		(at 447.687192 -21.236178 180)
		(property "Reference" "PR5484"
			(at 0 0 180)
			(layer "F.SilkS")
			(hide yes)
			(effects
				(font
					(size 1.27 1.27)
				)
			)
		)
		(property "Value" ""
			(at 0 0 180)
			(layer "F.Fab")
			(effects
				(font
					(size 1.27 1.27)
				)
			)
		)
		(duplicate_pad_numbers_are_jumpers no)
		(fp_line
			(start 0.7874 0.4064)
			(end -0.7874 0.4064)
			(stroke
				(width 0.1524)
				(type default)
			)
			(layer "F.SilkS")
		)
		(fp_line
			(start 0.7874 -0.4064)
			(end 0.7874 0.4064)
			(stroke
				(width 0.1524)
				(type default)
			)
			(layer "F.SilkS")
		)
		(fp_line
			(start -0.7874 0.4064)
			(end -0.7874 -0.4064)
			(stroke
				(width 0.1524)
				(type default)
			)
			(layer "F.SilkS")
		)
		(fp_line
			(start -0.7874 -0.4064)
			(end 0.7874 -0.4064)
			(stroke
				(width 0.1524)
				(type default)
			)
			(layer "F.SilkS")
		)
		(fp_line
			(start 0.67945 0.3048)
			(end 0.120396 0.3048)
			(stroke
				(width 0.1)
				(type default)
			)
			(layer "F.Fab")
		)
		(fp_line
			(start 0.67945 -0.3048)
			(end 0.67945 0.3048)
			(stroke
				(width 0.1)
				(type default)
			)
			(layer "F.Fab")
		)
		(fp_line
			(start 0.12065 -0.2794)
			(end 0.12065 -0.3048)
			(stroke
				(width 0.1)
				(type default)
			)
			(layer "F.Fab")
		)
		(fp_line
			(start 0.12065 -0.3048)
			(end 0.67945 -0.3048)
			(stroke
				(width 0.1)
				(type default)
			)
			(layer "F.Fab")
		)
		(fp_line
			(start 0.120396 0.3048)
			(end 0.120396 0.2794)
			(stroke
				(width 0.1)
				(type default)
			)
			(layer "F.Fab")
		)
		(fp_line
			(start 0.120396 0.2794)
			(end -0.12065 0.2794)
			(stroke
				(width 0.1)
				(type default)
			)
			(layer "F.Fab")
		)
		(fp_line
			(start -0.12065 0.3048)
			(end -0.67945 0.3048)
			(stroke
				(width 0.1)
				(type default)
			)
			(layer "F.Fab")
		)
		(fp_line
			(start -0.12065 0.2794)
			(end -0.12065 0.3048)
			(stroke
				(width 0.1)
				(type default)
			)
			(layer "F.Fab")
		)
		(fp_line
			(start -0.12065 -0.2794)
			(end 0.12065 -0.2794)
			(stroke
				(width 0.1)
				(type default)
			)
			(layer "F.Fab")
		)
		(fp_line
			(start -0.12065 -0.305054)
			(end -0.12065 -0.2794)
			(stroke
				(width 0.1)
				(type default)
			)
			(layer "F.Fab")
		)
		(fp_line
			(start -0.67945 0.3048)
			(end -0.67945 -0.305054)
			(stroke
				(width 0.1)
				(type default)
			)
			(layer "F.Fab")
		)
		(fp_line
			(start -0.67945 -0.305054)
			(end -0.12065 -0.305054)
			(stroke
				(width 0.1)
				(type default)
			)
			(layer "F.Fab")
		)
		(pad "1" smd circle
			(at -0.40005 0 180)
			(size 0 0)
			(layers "F.Cu" "F.Mask" "F.Paste")
			(net "P12V_OCP_CB_1")
		)
		(pad "2" smd circle
			(at 0.40005 0 180)
			(size 0 0)
			(layers "F.Cu" "F.Mask" "F.Paste")
			(net "GND")
		)
	)
	(footprint ""
		(layer "F.Cu")
		(at 366.48263 -244.03177 90)
		(property "Reference" "C1017"
			(at 0 0 90)
			(layer "F.SilkS")
			(hide yes)
			(effects
				(font
					(size 1.27 1.27)
				)
			)
		)
		(property "Value" ""
			(at 0 0 90)
			(layer "F.Fab")
			(effects
				(font
					(size 1.27 1.27)
				)
			)
		)
		(duplicate_pad_numbers_are_jumpers no)
		(fp_line
			(start 0.7874 -0.4064)
			(end 0.7874 0.4064)
			(stroke
				(width 0.1524)
				(type default)
			)
			(layer "F.SilkS")
		)
		(fp_line
			(start -0.7874 -0.4064)
			(end 0.7874 -0.4064)
			(stroke
				(width 0.1524)
				(type default)
			)
			(layer "F.SilkS")
		)
		(fp_line
			(start 0.7874 0.4064)
			(end -0.7874 0.4064)
			(stroke
				(width 0.1524)
				(type default)
			)
			(layer "F.SilkS")
		)
		(fp_line
			(start -0.7874 0.4064)
			(end -0.7874 -0.4064)
			(stroke
				(width 0.1524)
				(type default)
			)
			(layer "F.SilkS")
		)
		(fp_line
			(start -0.12065 -0.305054)
			(end -0.12065 -0.2794)
			(stroke
				(width 0.1)
				(type default)
			)
			(layer "F.Fab")
		)
		(fp_line
			(start -0.67945 -0.305054)
			(end -0.12065 -0.305054)
			(stroke
				(width 0.1)
				(type default)
			)
			(layer "F.Fab")
		)
		(fp_line
			(start 0.67945 -0.3048)
			(end 0.67945 0.3048)
			(stroke
				(width 0.1)
				(type default)
			)
			(layer "F.Fab")
		)
		(fp_line
			(start 0.12065 -0.3048)
			(end 0.67945 -0.3048)
			(stroke
				(width 0.1)
				(type default)
			)
			(layer "F.Fab")
		)
		(fp_line
			(start 0.12065 -0.2794)
			(end 0.12065 -0.3048)
			(stroke
				(width 0.1)
				(type default)
			)
			(layer "F.Fab")
		)
		(fp_line
			(start -0.12065 -0.2794)
			(end 0.12065 -0.2794)
			(stroke
				(width 0.1)
				(type default)
			)
			(layer "F.Fab")
		)
		(fp_line
			(start 0.120396 0.2794)
			(end -0.12065 0.2794)
			(stroke
				(width 0.1)
				(type default)
			)
			(layer "F.Fab")
		)
		(fp_line
			(start -0.12065 0.2794)
			(end -0.12065 0.3048)
			(stroke
				(width 0.1)
				(type default)
			)
			(layer "F.Fab")
		)
		(fp_line
			(start 0.67945 0.3048)
			(end 0.120396 0.3048)
			(stroke
				(width 0.1)
				(type default)
			)
			(layer "F.Fab")
		)
		(fp_line
			(start 0.120396 0.3048)
			(end 0.120396 0.2794)
			(stroke
				(width 0.1)
				(type default)
			)
			(layer "F.Fab")
		)
		(fp_line
			(start -0.12065 0.3048)
			(end -0.67945 0.3048)
			(stroke
				(width 0.1)
				(type default)
			)
			(layer "F.Fab")
		)
		(fp_line
			(start -0.67945 0.3048)
			(end -0.67945 -0.305054)
			(stroke
				(width 0.1)
				(type default)
			)
			(layer "F.Fab")
		)
		(pad "1" smd circle
			(at -0.40005 0 90)
			(size 0 0)
			(layers "F.Cu" "F.Mask" "F.Paste")
			(net "PVCCIN_CPU0")
		)
		(pad "2" smd circle
			(at 0.40005 0 90)
			(size 0 0)
			(layers "F.Cu" "F.Mask" "F.Paste")
			(net "GND")
		)
	)
	(footprint ""
		(layer "F.Cu")
		(at 158.33471 -81.90865 -90)
		(property "Reference" "R3225"
			(at 0 0 270)
			(layer "F.SilkS")
			(hide yes)
			(effects
				(font
					(size 1.27 1.27)
				)
			)
		)
		(property "Value" ""
			(at 0 0 270)
			(layer "F.Fab")
			(effects
				(font
					(size 1.27 1.27)
				)
			)
		)
		(duplicate_pad_numbers_are_jumpers no)
		(fp_line
			(start -0.7874 0.4064)
			(end -0.7874 -0.4064)
			(stroke
				(width 0.1524)
				(type default)
			)
			(layer "F.SilkS")
		)
		(fp_line
			(start 0.7874 0.4064)
			(end -0.7874 0.4064)
			(stroke
				(width 0.1524)
				(type default)
			)
			(layer "F.SilkS")
		)
		(fp_line
			(start -0.7874 -0.4064)
			(end 0.7874 -0.4064)
			(stroke
				(width 0.1524)
				(type default)
			)
			(layer "F.SilkS")
		)
		(fp_line
			(start 0.7874 -0.4064)
			(end 0.7874 0.4064)
			(stroke
				(width 0.1524)
				(type default)
			)
			(layer "F.SilkS")
		)
		(fp_line
			(start -0.67945 0.3048)
			(end -0.67945 -0.305054)
			(stroke
				(width 0.1)
				(type default)
			)
			(layer "F.Fab")
		)
		(fp_line
			(start -0.12065 0.3048)
			(end -0.67945 0.3048)
			(stroke
				(width 0.1)
				(type default)
			)
			(layer "F.Fab")
		)
		(fp_line
			(start 0.120396 0.3048)
			(end 0.120396 0.2794)
			(stroke
				(width 0.1)
				(type default)
			)
			(layer "F.Fab")
		)
		(fp_line
			(start 0.67945 0.3048)
			(end 0.120396 0.3048)
			(stroke
				(width 0.1)
				(type default)
			)
			(layer "F.Fab")
		)
		(fp_line
			(start -0.12065 0.2794)
			(end -0.12065 0.3048)
			(stroke
				(width 0.1)
				(type default)
			)
			(layer "F.Fab")
		)
		(fp_line
			(start 0.120396 0.2794)
			(end -0.12065 0.2794)
			(stroke
				(width 0.1)
				(type default)
			)
			(layer "F.Fab")
		)
		(fp_line
			(start -0.12065 -0.2794)
			(end 0.12065 -0.2794)
			(stroke
				(width 0.1)
				(type default)
			)
			(layer "F.Fab")
		)
		(fp_line
			(start 0.12065 -0.2794)
			(end 0.12065 -0.3048)
			(stroke
				(width 0.1)
				(type default)
			)
			(layer "F.Fab")
		)
		(fp_line
			(start 0.12065 -0.3048)
			(end 0.67945 -0.3048)
			(stroke
				(width 0.1)
				(type default)
			)
			(layer "F.Fab")
		)
		(fp_line
			(start 0.67945 -0.3048)
			(end 0.67945 0.3048)
			(stroke
				(width 0.1)
				(type default)
			)
			(layer "F.Fab")
		)
		(fp_line
			(start -0.67945 -0.305054)
			(end -0.12065 -0.305054)
			(stroke
				(width 0.1)
				(type default)
			)
			(layer "F.Fab")
		)
		(fp_line
			(start -0.12065 -0.305054)
			(end -0.12065 -0.2794)
			(stroke
				(width 0.1)
				(type default)
			)
			(layer "F.Fab")
		)
		(pad "1" smd circle
			(at -0.40005 0 270)
			(size 0 0)
			(layers "F.Cu" "F.Mask" "F.Paste")
			(net "SMB_S3M_CPU1_PIROM_3V3AUX_SDA")
		)
		(pad "2" smd circle
			(at 0.40005 0 270)
			(size 0 0)
			(layers "F.Cu" "F.Mask" "F.Paste")
			(net "P3V3_AUX")
		)
	)
	(footprint ""
		(layer "F.Cu")
		(at 94.201996 -338.298282 -90)
		(property "Reference" "PC1339"
			(at 0 0 270)
			(layer "F.SilkS")
			(hide yes)
			(effects
				(font
					(size 1.27 1.27)
				)
			)
		)
		(property "Value" ""
			(at 0 0 270)
			(layer "F.Fab")
			(effects
				(font
					(size 1.27 1.27)
				)
			)
		)
		(duplicate_pad_numbers_are_jumpers no)
		(fp_line
			(start -0.7874 0.4064)
			(end -0.7874 -0.4064)
			(stroke
				(width 0.1524)
				(type default)
			)
			(layer "F.SilkS")
		)
		(fp_line
			(start 0.7874 0.4064)
			(end -0.7874 0.4064)
			(stroke
				(width 0.1524)
				(type default)
			)
			(layer "F.SilkS")
		)
		(fp_line
			(start -0.7874 -0.4064)
			(end 0.7874 -0.4064)
			(stroke
				(width 0.1524)
				(type default)
			)
			(layer "F.SilkS")
		)
		(fp_line
			(start 0.7874 -0.4064)
			(end 0.7874 0.4064)
			(stroke
				(width 0.1524)
				(type default)
			)
			(layer "F.SilkS")
		)
		(fp_line
			(start -0.67945 0.3048)
			(end -0.67945 -0.305054)
			(stroke
				(width 0.1)
				(type default)
			)
			(layer "F.Fab")
		)
		(fp_line
			(start -0.12065 0.3048)
			(end -0.67945 0.3048)
			(stroke
				(width 0.1)
				(type default)
			)
			(layer "F.Fab")
		)
		(fp_line
			(start 0.120396 0.3048)
			(end 0.120396 0.2794)
			(stroke
				(width 0.1)
				(type default)
			)
			(layer "F.Fab")
		)
		(fp_line
			(start 0.67945 0.3048)
			(end 0.120396 0.3048)
			(stroke
				(width 0.1)
				(type default)
			)
			(layer "F.Fab")
		)
		(fp_line
			(start -0.12065 0.2794)
			(end -0.12065 0.3048)
			(stroke
				(width 0.1)
				(type default)
			)
			(layer "F.Fab")
		)
		(fp_line
			(start 0.120396 0.2794)
			(end -0.12065 0.2794)
			(stroke
				(width 0.1)
				(type default)
			)
			(layer "F.Fab")
		)
		(fp_line
			(start -0.12065 -0.2794)
			(end 0.12065 -0.2794)
			(stroke
				(width 0.1)
				(type default)
			)
			(layer "F.Fab")
		)
		(fp_line
			(start 0.12065 -0.2794)
			(end 0.12065 -0.3048)
			(stroke
				(width 0.1)
				(type default)
			)
			(layer "F.Fab")
		)
		(fp_line
			(start 0.12065 -0.3048)
			(end 0.67945 -0.3048)
			(stroke
				(width 0.1)
				(type default)
			)
			(layer "F.Fab")
		)
		(fp_line
			(start 0.67945 -0.3048)
			(end 0.67945 0.3048)
			(stroke
				(width 0.1)
				(type default)
			)
			(layer "F.Fab")
		)
		(fp_line
			(start -0.67945 -0.305054)
			(end -0.12065 -0.305054)
			(stroke
				(width 0.1)
				(type default)
			)
			(layer "F.Fab")
		)
		(fp_line
			(start -0.12065 -0.305054)
			(end -0.12065 -0.2794)
			(stroke
				(width 0.1)
				(type default)
			)
			(layer "F.Fab")
		)
		(pad "1" smd circle
			(at -0.40005 0 270)
			(size 0 0)
			(layers "F.Cu" "F.Mask" "F.Paste")
			(net "GND")
		)
		(pad "2" smd circle
			(at 0.40005 0 270)
			(size 0 0)
			(layers "F.Cu" "F.Mask" "F.Paste")
			(net "PVCCIN_CPU1_VREF")
		)
	)
	(footprint ""
		(layer "F.Cu")
		(at 209.74558 -127.528828)
		(property "Reference" "R1695"
			(at 0 0 0)
			(layer "F.SilkS")
			(hide yes)
			(effects
				(font
					(size 1.27 1.27)
				)
			)
		)
		(property "Value" ""
			(at 0 0 0)
			(layer "F.Fab")
			(effects
				(font
					(size 1.27 1.27)
				)
			)
		)
		(duplicate_pad_numbers_are_jumpers no)
		(fp_line
			(start -0.7874 -0.4064)
			(end 0.7874 -0.4064)
			(stroke
				(width 0.1524)
				(type default)
			)
			(layer "F.SilkS")
		)
		(fp_line
			(start -0.7874 0.4064)
			(end -0.7874 -0.4064)
			(stroke
				(width 0.1524)
				(type default)
			)
			(layer "F.SilkS")
		)
		(fp_line
			(start 0.7874 -0.4064)
			(end 0.7874 0.4064)
			(stroke
				(width 0.1524)
				(type default)
			)
			(layer "F.SilkS")
		)
		(fp_line
			(start 0.7874 0.4064)
			(end -0.7874 0.4064)
			(stroke
				(width 0.1524)
				(type default)
			)
			(layer "F.SilkS")
		)
		(fp_line
			(start -0.67945 -0.305054)
			(end -0.12065 -0.305054)
			(stroke
				(width 0.1)
				(type default)
			)
			(layer "F.Fab")
		)
		(fp_line
			(start -0.67945 0.3048)
			(end -0.67945 -0.305054)
			(stroke
				(width 0.1)
				(type default)
			)
			(layer "F.Fab")
		)
		(fp_line
			(start -0.12065 -0.305054)
			(end -0.12065 -0.2794)
			(stroke
				(width 0.1)
				(type default)
			)
			(layer "F.Fab")
		)
		(fp_line
			(start -0.12065 -0.2794)
			(end 0.12065 -0.2794)
			(stroke
				(width 0.1)
				(type default)
			)
			(layer "F.Fab")
		)
		(fp_line
			(start -0.12065 0.2794)
			(end -0.12065 0.3048)
			(stroke
				(width 0.1)
				(type default)
			)
			(layer "F.Fab")
		)
		(fp_line
			(start -0.12065 0.3048)
			(end -0.67945 0.3048)
			(stroke
				(width 0.1)
				(type default)
			)
			(layer "F.Fab")
		)
		(fp_line
			(start 0.120396 0.2794)
			(end -0.12065 0.2794)
			(stroke
				(width 0.1)
				(type default)
			)
			(layer "F.Fab")
		)
		(fp_line
			(start 0.120396 0.3048)
			(end 0.120396 0.2794)
			(stroke
				(width 0.1)
				(type default)
			)
			(layer "F.Fab")
		)
		(fp_line
			(start 0.12065 -0.3048)
			(end 0.67945 -0.3048)
			(stroke
				(width 0.1)
				(type default)
			)
			(layer "F.Fab")
		)
		(fp_line
			(start 0.12065 -0.2794)
			(end 0.12065 -0.3048)
			(stroke
				(width 0.1)
				(type default)
			)
			(layer "F.Fab")
		)
		(fp_line
			(start 0.67945 -0.3048)
			(end 0.67945 0.3048)
			(stroke
				(width 0.1)
				(type default)
			)
			(layer "F.Fab")
		)
		(fp_line
			(start 0.67945 0.3048)
			(end 0.120396 0.3048)
			(stroke
				(width 0.1)
				(type default)
			)
			(layer "F.Fab")
		)
		(pad "1" smd circle
			(at -0.40005 0)
			(size 0 0)
			(layers "F.Cu" "F.Mask" "F.Paste")
			(net "PWRGD_DSW_PWROK")
		)
		(pad "2" smd circle
			(at 0.40005 0)
			(size 0 0)
			(layers "F.Cu" "F.Mask" "F.Paste")
			(net "RST_RSMRST_PCH_N")
		)
	)
	(footprint ""
		(layer "F.Cu")
		(at 220.363034 -75.02779 -90)
		(property "Reference" "PR3967"
			(at 0 0 270)
			(layer "F.SilkS")
			(hide yes)
			(effects
				(font
					(size 1.27 1.27)
				)
			)
		)
		(property "Value" ""
			(at 0 0 270)
			(layer "F.Fab")
			(effects
				(font
					(size 1.27 1.27)
				)
			)
		)
		(duplicate_pad_numbers_are_jumpers no)
		(fp_line
			(start -0.7874 0.4064)
			(end -0.7874 -0.4064)
			(stroke
				(width 0.1524)
				(type default)
			)
			(layer "F.SilkS")
		)
		(fp_line
			(start 0.7874 0.4064)
			(end -0.7874 0.4064)
			(stroke
				(width 0.1524)
				(type default)
			)
			(layer "F.SilkS")
		)
		(fp_line
			(start -0.7874 -0.4064)
			(end 0.7874 -0.4064)
			(stroke
				(width 0.1524)
				(type default)
			)
			(layer "F.SilkS")
		)
		(fp_line
			(start 0.7874 -0.4064)
			(end 0.7874 0.4064)
			(stroke
				(width 0.1524)
				(type default)
			)
			(layer "F.SilkS")
		)
		(fp_line
			(start -0.67945 0.3048)
			(end -0.67945 -0.305054)
			(stroke
				(width 0.1)
				(type default)
			)
			(layer "F.Fab")
		)
		(fp_line
			(start -0.12065 0.3048)
			(end -0.67945 0.3048)
			(stroke
				(width 0.1)
				(type default)
			)
			(layer "F.Fab")
		)
		(fp_line
			(start 0.120396 0.3048)
			(end 0.120396 0.2794)
			(stroke
				(width 0.1)
				(type default)
			)
			(layer "F.Fab")
		)
		(fp_line
			(start 0.67945 0.3048)
			(end 0.120396 0.3048)
			(stroke
				(width 0.1)
				(type default)
			)
			(layer "F.Fab")
		)
		(fp_line
			(start -0.12065 0.2794)
			(end -0.12065 0.3048)
			(stroke
				(width 0.1)
				(type default)
			)
			(layer "F.Fab")
		)
		(fp_line
			(start 0.120396 0.2794)
			(end -0.12065 0.2794)
			(stroke
				(width 0.1)
				(type default)
			)
			(layer "F.Fab")
		)
		(fp_line
			(start -0.12065 -0.2794)
			(end 0.12065 -0.2794)
			(stroke
				(width 0.1)
				(type default)
			)
			(layer "F.Fab")
		)
		(fp_line
			(start 0.12065 -0.2794)
			(end 0.12065 -0.3048)
			(stroke
				(width 0.1)
				(type default)
			)
			(layer "F.Fab")
		)
		(fp_line
			(start 0.12065 -0.3048)
			(end 0.67945 -0.3048)
			(stroke
				(width 0.1)
				(type default)
			)
			(layer "F.Fab")
		)
		(fp_line
			(start 0.67945 -0.3048)
			(end 0.67945 0.3048)
			(stroke
				(width 0.1)
				(type default)
			)
			(layer "F.Fab")
		)
		(fp_line
			(start -0.67945 -0.305054)
			(end -0.12065 -0.305054)
			(stroke
				(width 0.1)
				(type default)
			)
			(layer "F.Fab")
		)
		(fp_line
			(start -0.12065 -0.305054)
			(end -0.12065 -0.2794)
			(stroke
				(width 0.1)
				(type default)
			)
			(layer "F.Fab")
		)
		(pad "1" smd circle
			(at -0.40005 0 270)
			(size 0 0)
			(layers "F.Cu" "F.Mask" "F.Paste")
			(net "P3V3_AUX")
		)
		(pad "2" smd circle
			(at 0.40005 0 270)
			(size 0 0)
			(layers "F.Cu" "F.Mask" "F.Paste")
			(net "P3V3_E1S_VCC_0")
		)
	)
	(footprint ""
		(layer "F.Cu")
		(at 437.242966 -125.696726 180)
		(property "Reference" "R2401"
			(at 0 0 180)
			(layer "F.SilkS")
			(hide yes)
			(effects
				(font
					(size 1.27 1.27)
				)
			)
		)
		(property "Value" ""
			(at 0 0 180)
			(layer "F.Fab")
			(effects
				(font
					(size 1.27 1.27)
				)
			)
		)
		(duplicate_pad_numbers_are_jumpers no)
		(fp_line
			(start 0.7874 0.4064)
			(end -0.7874 0.4064)
			(stroke
				(width 0.1524)
				(type default)
			)
			(layer "F.SilkS")
		)
		(fp_line
			(start 0.7874 -0.4064)
			(end 0.7874 0.4064)
			(stroke
				(width 0.1524)
				(type default)
			)
			(layer "F.SilkS")
		)
		(fp_line
			(start -0.7874 0.4064)
			(end -0.7874 -0.4064)
			(stroke
				(width 0.1524)
				(type default)
			)
			(layer "F.SilkS")
		)
		(fp_line
			(start -0.7874 -0.4064)
			(end 0.7874 -0.4064)
			(stroke
				(width 0.1524)
				(type default)
			)
			(layer "F.SilkS")
		)
		(fp_line
			(start 0.67945 0.3048)
			(end 0.120396 0.3048)
			(stroke
				(width 0.1)
				(type default)
			)
			(layer "F.Fab")
		)
		(fp_line
			(start 0.67945 -0.3048)
			(end 0.67945 0.3048)
			(stroke
				(width 0.1)
				(type default)
			)
			(layer "F.Fab")
		)
		(fp_line
			(start 0.12065 -0.2794)
			(end 0.12065 -0.3048)
			(stroke
				(width 0.1)
				(type default)
			)
			(layer "F.Fab")
		)
		(fp_line
			(start 0.12065 -0.3048)
			(end 0.67945 -0.3048)
			(stroke
				(width 0.1)
				(type default)
			)
			(layer "F.Fab")
		)
		(fp_line
			(start 0.120396 0.3048)
			(end 0.120396 0.2794)
			(stroke
				(width 0.1)
				(type default)
			)
			(layer "F.Fab")
		)
		(fp_line
			(start 0.120396 0.2794)
			(end -0.12065 0.2794)
			(stroke
				(width 0.1)
				(type default)
			)
			(layer "F.Fab")
		)
		(fp_line
			(start -0.12065 0.3048)
			(end -0.67945 0.3048)
			(stroke
				(width 0.1)
				(type default)
			)
			(layer "F.Fab")
		)
		(fp_line
			(start -0.12065 0.2794)
			(end -0.12065 0.3048)
			(stroke
				(width 0.1)
				(type default)
			)
			(layer "F.Fab")
		)
		(fp_line
			(start -0.12065 -0.2794)
			(end 0.12065 -0.2794)
			(stroke
				(width 0.1)
				(type default)
			)
			(layer "F.Fab")
		)
		(fp_line
			(start -0.12065 -0.305054)
			(end -0.12065 -0.2794)
			(stroke
				(width 0.1)
				(type default)
			)
			(layer "F.Fab")
		)
		(fp_line
			(start -0.67945 0.3048)
			(end -0.67945 -0.305054)
			(stroke
				(width 0.1)
				(type default)
			)
			(layer "F.Fab")
		)
		(fp_line
			(start -0.67945 -0.305054)
			(end -0.12065 -0.305054)
			(stroke
				(width 0.1)
				(type default)
			)
			(layer "F.Fab")
		)
		(pad "1" smd circle
			(at -0.40005 0 180)
			(size 0 0)
			(layers "F.Cu" "F.Mask" "F.Paste")
			(net "SVID_ALERT1_CPU0_R_N")
		)
		(pad "2" smd circle
			(at 0.40005 0 180)
			(size 0 0)
			(layers "F.Cu" "F.Mask" "F.Paste")
			(net "SVID_ALERT_PVCCD_HV_CPU0_R")
		)
	)
	(footprint ""
		(layer "F.Cu")
		(at 24.684482 -396.887192 -90)
		(property "Reference" "R4664"
			(at 0 0 270)
			(layer "F.SilkS")
			(hide yes)
			(effects
				(font
					(size 1.27 1.27)
				)
			)
		)
		(property "Value" ""
			(at 0 0 270)
			(layer "F.Fab")
			(effects
				(font
					(size 1.27 1.27)
				)
			)
		)
		(duplicate_pad_numbers_are_jumpers no)
		(fp_line
			(start -0.7874 0.4064)
			(end -0.7874 -0.4064)
			(stroke
				(width 0.1524)
				(type default)
			)
			(layer "F.SilkS")
		)
		(fp_line
			(start 0.7874 0.4064)
			(end -0.7874 0.4064)
			(stroke
				(width 0.1524)
				(type default)
			)
			(layer "F.SilkS")
		)
		(fp_line
			(start 0.017272 -0.4064)
			(end 0.7874 -0.4064)
			(stroke
				(width 0.1524)
				(type default)
			)
			(layer "F.SilkS")
		)
		(fp_line
			(start -0.67945 0.3048)
			(end -0.67945 -0.305054)
			(stroke
				(width 0.1)
				(type default)
			)
			(layer "F.Fab")
		)
		(fp_line
			(start -0.12065 0.3048)
			(end -0.67945 0.3048)
			(stroke
				(width 0.1)
				(type default)
			)
			(layer "F.Fab")
		)
		(fp_line
			(start 0.120396 0.3048)
			(end 0.120396 0.2794)
			(stroke
				(width 0.1)
				(type default)
			)
			(layer "F.Fab")
		)
		(fp_line
			(start 0.67945 0.3048)
			(end 0.120396 0.3048)
			(stroke
				(width 0.1)
				(type default)
			)
			(layer "F.Fab")
		)
		(fp_line
			(start -0.12065 0.2794)
			(end -0.12065 0.3048)
			(stroke
				(width 0.1)
				(type default)
			)
			(layer "F.Fab")
		)
		(fp_line
			(start 0.120396 0.2794)
			(end -0.12065 0.2794)
			(stroke
				(width 0.1)
				(type default)
			)
			(layer "F.Fab")
		)
		(fp_line
			(start -0.12065 -0.2794)
			(end 0.12065 -0.2794)
			(stroke
				(width 0.1)
				(type default)
			)
			(layer "F.Fab")
		)
		(fp_line
			(start 0.12065 -0.2794)
			(end 0.12065 -0.3048)
			(stroke
				(width 0.1)
				(type default)
			)
			(layer "F.Fab")
		)
		(fp_line
			(start 0.12065 -0.3048)
			(end 0.67945 -0.3048)
			(stroke
				(width 0.1)
				(type default)
			)
			(layer "F.Fab")
		)
		(fp_line
			(start 0.67945 -0.3048)
			(end 0.67945 0.3048)
			(stroke
				(width 0.1)
				(type default)
			)
			(layer "F.Fab")
		)
		(fp_line
			(start -0.67945 -0.305054)
			(end -0.12065 -0.305054)
			(stroke
				(width 0.1)
				(type default)
			)
			(layer "F.Fab")
		)
		(fp_line
			(start -0.12065 -0.305054)
			(end -0.12065 -0.2794)
			(stroke
				(width 0.1)
				(type default)
			)
			(layer "F.Fab")
		)
		(pad "1" smd rect
			(at -0.40005 0 90)
			(size 0.4572 0.508)
			(layers "F.Cu" "F.Mask" "F.Paste")
			(net "P2E_MB_BMC_RX_DN<0>")
		)
		(pad "2" smd rect
			(at 0.40005 0 90)
			(size 0.4572 0.508)
			(layers "F.Cu" "F.Mask" "F.Paste")
			(net "P2E_MB_BMC_RX_R1_DN<0>")
		)
	)
	(footprint ""
		(layer "F.Cu")
		(at 210.086956 -30.276292 90)
		(property "Reference" "R3622"
			(at 0 0 90)
			(layer "F.SilkS")
			(hide yes)
			(effects
				(font
					(size 1.27 1.27)
				)
			)
		)
		(property "Value" ""
			(at 0 0 90)
			(layer "F.Fab")
			(effects
				(font
					(size 1.27 1.27)
				)
			)
		)
		(duplicate_pad_numbers_are_jumpers no)
		(fp_line
			(start 0.7874 -0.4064)
			(end 0.7874 0.4064)
			(stroke
				(width 0.1524)
				(type default)
			)
			(layer "F.SilkS")
		)
		(fp_line
			(start -0.7874 -0.4064)
			(end 0.7874 -0.4064)
			(stroke
				(width 0.1524)
				(type default)
			)
			(layer "F.SilkS")
		)
		(fp_line
			(start 0.7874 0.4064)
			(end -0.7874 0.4064)
			(stroke
				(width 0.1524)
				(type default)
			)
			(layer "F.SilkS")
		)
		(fp_line
			(start -0.7874 0.4064)
			(end -0.7874 -0.4064)
			(stroke
				(width 0.1524)
				(type default)
			)
			(layer "F.SilkS")
		)
		(fp_line
			(start -0.12065 -0.305054)
			(end -0.12065 -0.2794)
			(stroke
				(width 0.1)
				(type default)
			)
			(layer "F.Fab")
		)
		(fp_line
			(start -0.67945 -0.305054)
			(end -0.12065 -0.305054)
			(stroke
				(width 0.1)
				(type default)
			)
			(layer "F.Fab")
		)
		(fp_line
			(start 0.67945 -0.3048)
			(end 0.67945 0.3048)
			(stroke
				(width 0.1)
				(type default)
			)
			(layer "F.Fab")
		)
		(fp_line
			(start 0.12065 -0.3048)
			(end 0.67945 -0.3048)
			(stroke
				(width 0.1)
				(type default)
			)
			(layer "F.Fab")
		)
		(fp_line
			(start 0.12065 -0.2794)
			(end 0.12065 -0.3048)
			(stroke
				(width 0.1)
				(type default)
			)
			(layer "F.Fab")
		)
		(fp_line
			(start -0.12065 -0.2794)
			(end 0.12065 -0.2794)
			(stroke
				(width 0.1)
				(type default)
			)
			(layer "F.Fab")
		)
		(fp_line
			(start 0.120396 0.2794)
			(end -0.12065 0.2794)
			(stroke
				(width 0.1)
				(type default)
			)
			(layer "F.Fab")
		)
		(fp_line
			(start -0.12065 0.2794)
			(end -0.12065 0.3048)
			(stroke
				(width 0.1)
				(type default)
			)
			(layer "F.Fab")
		)
		(fp_line
			(start 0.67945 0.3048)
			(end 0.120396 0.3048)
			(stroke
				(width 0.1)
				(type default)
			)
			(layer "F.Fab")
		)
		(fp_line
			(start 0.120396 0.3048)
			(end 0.120396 0.2794)
			(stroke
				(width 0.1)
				(type default)
			)
			(layer "F.Fab")
		)
		(fp_line
			(start -0.12065 0.3048)
			(end -0.67945 0.3048)
			(stroke
				(width 0.1)
				(type default)
			)
			(layer "F.Fab")
		)
		(fp_line
			(start -0.67945 0.3048)
			(end -0.67945 -0.305054)
			(stroke
				(width 0.1)
				(type default)
			)
			(layer "F.Fab")
		)
		(pad "1" smd circle
			(at -0.40005 0 90)
			(size 0 0)
			(layers "F.Cu" "F.Mask" "F.Paste")
			(net "P3V3_AUX")
		)
		(pad "2" smd circle
			(at 0.40005 0 90)
			(size 0 0)
			(layers "F.Cu" "F.Mask" "F.Paste")
			(net "INA230_5_A0")
		)
	)
	(footprint ""
		(layer "F.Cu")
		(at 246.784622 -90.651584 180)
		(property "Reference" "C2037"
			(at 0 0 180)
			(layer "F.SilkS")
			(hide yes)
			(effects
				(font
					(size 1.27 1.27)
				)
			)
		)
		(property "Value" ""
			(at 0 0 180)
			(layer "F.Fab")
			(effects
				(font
					(size 1.27 1.27)
				)
			)
		)
		(duplicate_pad_numbers_are_jumpers no)
		(fp_line
			(start 0.7874 0.4064)
			(end -0.7874 0.4064)
			(stroke
				(width 0.1524)
				(type default)
			)
			(layer "F.SilkS")
		)
		(fp_line
			(start 0.7874 -0.4064)
			(end 0.7874 0.4064)
			(stroke
				(width 0.1524)
				(type default)
			)
			(layer "F.SilkS")
		)
		(fp_line
			(start -0.7874 0.4064)
			(end -0.7874 -0.4064)
			(stroke
				(width 0.1524)
				(type default)
			)
			(layer "F.SilkS")
		)
		(fp_line
			(start -0.7874 -0.4064)
			(end 0.7874 -0.4064)
			(stroke
				(width 0.1524)
				(type default)
			)
			(layer "F.SilkS")
		)
		(fp_line
			(start 0.67945 0.3048)
			(end 0.120396 0.3048)
			(stroke
				(width 0.1)
				(type default)
			)
			(layer "F.Fab")
		)
		(fp_line
			(start 0.67945 -0.3048)
			(end 0.67945 0.3048)
			(stroke
				(width 0.1)
				(type default)
			)
			(layer "F.Fab")
		)
		(fp_line
			(start 0.12065 -0.2794)
			(end 0.12065 -0.3048)
			(stroke
				(width 0.1)
				(type default)
			)
			(layer "F.Fab")
		)
		(fp_line
			(start 0.12065 -0.3048)
			(end 0.67945 -0.3048)
			(stroke
				(width 0.1)
				(type default)
			)
			(layer "F.Fab")
		)
		(fp_line
			(start 0.120396 0.3048)
			(end 0.120396 0.2794)
			(stroke
				(width 0.1)
				(type default)
			)
			(layer "F.Fab")
		)
		(fp_line
			(start 0.120396 0.2794)
			(end -0.12065 0.2794)
			(stroke
				(width 0.1)
				(type default)
			)
			(layer "F.Fab")
		)
		(fp_line
			(start -0.12065 0.3048)
			(end -0.67945 0.3048)
			(stroke
				(width 0.1)
				(type default)
			)
			(layer "F.Fab")
		)
		(fp_line
			(start -0.12065 0.2794)
			(end -0.12065 0.3048)
			(stroke
				(width 0.1)
				(type default)
			)
			(layer "F.Fab")
		)
		(fp_line
			(start -0.12065 -0.2794)
			(end 0.12065 -0.2794)
			(stroke
				(width 0.1)
				(type default)
			)
			(layer "F.Fab")
		)
		(fp_line
			(start -0.12065 -0.305054)
			(end -0.12065 -0.2794)
			(stroke
				(width 0.1)
				(type default)
			)
			(layer "F.Fab")
		)
		(fp_line
			(start -0.67945 0.3048)
			(end -0.67945 -0.305054)
			(stroke
				(width 0.1)
				(type default)
			)
			(layer "F.Fab")
		)
		(fp_line
			(start -0.67945 -0.305054)
			(end -0.12065 -0.305054)
			(stroke
				(width 0.1)
				(type default)
			)
			(layer "F.Fab")
		)
		(pad "1" smd circle
			(at -0.40005 0 180)
			(size 0 0)
			(layers "F.Cu" "F.Mask" "F.Paste")
			(net "XTAL_CLK_GEN1_25M_X2")
		)
		(pad "2" smd circle
			(at 0.40005 0 180)
			(size 0 0)
			(layers "F.Cu" "F.Mask" "F.Paste")
			(net "GND")
		)
	)
	(footprint ""
		(layer "F.Cu")
		(at 104.361234 -247.715278 90)
		(property "Reference" "C425"
			(at 0 0 90)
			(layer "F.SilkS")
			(hide yes)
			(effects
				(font
					(size 1.27 1.27)
				)
			)
		)
		(property "Value" ""
			(at 0 0 90)
			(layer "F.Fab")
			(effects
				(font
					(size 1.27 1.27)
				)
			)
		)
		(duplicate_pad_numbers_are_jumpers no)
		(fp_line
			(start 0.7874 -0.4064)
			(end 0.7874 0.4064)
			(stroke
				(width 0.1524)
				(type default)
			)
			(layer "F.SilkS")
		)
		(fp_line
			(start -0.7874 -0.4064)
			(end 0.7874 -0.4064)
			(stroke
				(width 0.1524)
				(type default)
			)
			(layer "F.SilkS")
		)
		(fp_line
			(start 0.7874 0.4064)
			(end -0.7874 0.4064)
			(stroke
				(width 0.1524)
				(type default)
			)
			(layer "F.SilkS")
		)
		(fp_line
			(start -0.7874 0.4064)
			(end -0.7874 -0.4064)
			(stroke
				(width 0.1524)
				(type default)
			)
			(layer "F.SilkS")
		)
		(fp_line
			(start -0.12065 -0.305054)
			(end -0.12065 -0.2794)
			(stroke
				(width 0.1)
				(type default)
			)
			(layer "F.Fab")
		)
		(fp_line
			(start -0.67945 -0.305054)
			(end -0.12065 -0.305054)
			(stroke
				(width 0.1)
				(type default)
			)
			(layer "F.Fab")
		)
		(fp_line
			(start 0.67945 -0.3048)
			(end 0.67945 0.3048)
			(stroke
				(width 0.1)
				(type default)
			)
			(layer "F.Fab")
		)
		(fp_line
			(start 0.12065 -0.3048)
			(end 0.67945 -0.3048)
			(stroke
				(width 0.1)
				(type default)
			)
			(layer "F.Fab")
		)
		(fp_line
			(start 0.12065 -0.2794)
			(end 0.12065 -0.3048)
			(stroke
				(width 0.1)
				(type default)
			)
			(layer "F.Fab")
		)
		(fp_line
			(start -0.12065 -0.2794)
			(end 0.12065 -0.2794)
			(stroke
				(width 0.1)
				(type default)
			)
			(layer "F.Fab")
		)
		(fp_line
			(start 0.120396 0.2794)
			(end -0.12065 0.2794)
			(stroke
				(width 0.1)
				(type default)
			)
			(layer "F.Fab")
		)
		(fp_line
			(start -0.12065 0.2794)
			(end -0.12065 0.3048)
			(stroke
				(width 0.1)
				(type default)
			)
			(layer "F.Fab")
		)
		(fp_line
			(start 0.67945 0.3048)
			(end 0.120396 0.3048)
			(stroke
				(width 0.1)
				(type default)
			)
			(layer "F.Fab")
		)
		(fp_line
			(start 0.120396 0.3048)
			(end 0.120396 0.2794)
			(stroke
				(width 0.1)
				(type default)
			)
			(layer "F.Fab")
		)
		(fp_line
			(start -0.12065 0.3048)
			(end -0.67945 0.3048)
			(stroke
				(width 0.1)
				(type default)
			)
			(layer "F.Fab")
		)
		(fp_line
			(start -0.67945 0.3048)
			(end -0.67945 -0.305054)
			(stroke
				(width 0.1)
				(type default)
			)
			(layer "F.Fab")
		)
		(pad "1" smd circle
			(at -0.40005 0 90)
			(size 0 0)
			(layers "F.Cu" "F.Mask" "F.Paste")
			(net "PVCCD_HV_CPU1")
		)
		(pad "2" smd circle
			(at 0.40005 0 90)
			(size 0 0)
			(layers "F.Cu" "F.Mask" "F.Paste")
			(net "GND")
		)
	)
	(footprint ""
		(layer "F.Cu")
		(at 179.749958 -435.600094)
		(property "Reference" "H89"
			(at -5.998718 -4.288536 0)
			(unlocked yes)
			(layer "F.SilkS")
			(effects
				(font
					(size 0.7874 0.5842)
					(thickness 0.1524)
				)
				(justify left)
			)
		)
		(property "Value" ""
			(at 0 0 0)
			(layer "F.Fab")
			(effects
				(font
					(size 1.27 1.27)
				)
			)
		)
		(duplicate_pad_numbers_are_jumpers no)
		(pad "1" thru_hole circle
			(at 0 0)
			(size 10.0076 10.0076)
			(drill 5.6134)
			(layers "*.Cu" "*.Mask")
			(remove_unused_layers no)
			(net "GND")
			(clearance -1.9431)
		)
	)
	(footprint ""
		(layer "F.Cu")
		(at 122.555 -55.971948)
		(property "Reference" "U327"
			(at 1.27 -3.52933 0)
			(unlocked yes)
			(layer "F.SilkS")
			(effects
				(font
					(size 0.7874 0.5842)
					(thickness 0.1524)
				)
				(justify left)
			)
		)
		(property "Value" ""
			(at 0 0 0)
			(layer "F.Fab")
			(effects
				(font
					(size 1.27 1.27)
				)
			)
		)
		(duplicate_pad_numbers_are_jumpers no)
		(fp_line
			(start -2.0066 -2.5527)
			(end -0.5715 -2.5527)
			(stroke
				(width 0.1524)
				(type default)
			)
			(layer "F.SilkS")
		)
		(fp_line
			(start -2.0066 2.5527)
			(end -2.0066 -2.5527)
			(stroke
				(width 0.1524)
				(type default)
			)
			(layer "F.SilkS")
		)
		(fp_line
			(start -0.5715 -2.5527)
			(end 0 -1.9812)
			(stroke
				(width 0.1524)
				(type default)
			)
			(layer "F.SilkS")
		)
		(fp_line
			(start 0 -1.9812)
			(end 0.5715 -2.5527)
			(stroke
				(width 0.1524)
				(type default)
			)
			(layer "F.SilkS")
		)
		(fp_line
			(start 0.5715 -2.5527)
			(end 2.0066 -2.5527)
			(stroke
				(width 0.1524)
				(type default)
			)
			(layer "F.SilkS")
		)
		(fp_line
			(start 2.0066 -2.5527)
			(end 2.0066 2.5527)
			(stroke
				(width 0.1524)
				(type default)
			)
			(layer "F.SilkS")
		)
		(fp_line
			(start 2.0066 2.5527)
			(end -2.0066 2.5527)
			(stroke
				(width 0.1524)
				(type default)
			)
			(layer "F.SilkS")
		)
		(fp_poly
			(pts
				(xy -4.36372 -1.608328) (xy -4.36372 -2.233168) (xy -3.81 -1.905)
			)
			(stroke
				(width 0)
				(type default)
			)
			(fill yes)
			(layer "F.SilkS")
		)
		(fp_line
			(start -2.249932 -2.549906)
			(end 2.249932 -2.549906)
			(stroke
				(width 0.1)
				(type default)
			)
			(layer "F.Fab")
		)
		(fp_line
			(start -2.249932 2.549906)
			(end -2.249932 -2.549906)
			(stroke
				(width 0.1)
				(type default)
			)
			(layer "F.Fab")
		)
		(fp_line
			(start 2.249932 -2.549906)
			(end 2.249932 2.549906)
			(stroke
				(width 0.1)
				(type default)
			)
			(layer "F.Fab")
		)
		(fp_line
			(start 2.249932 2.549906)
			(end -2.249932 2.549906)
			(stroke
				(width 0.1)
				(type default)
			)
			(layer "F.Fab")
		)
		(fp_poly
			(pts
				(xy -4.36372 -1.608328) (xy -4.36372 -2.233168) (xy -3.81 -1.905)
			)
			(stroke
				(width 0)
				(type default)
			)
			(fill yes)
			(layer "F.Fab")
		)
		(pad "1" smd rect
			(at -2.921 -1.949958 270)
			(size 0.3556 1.4986)
			(layers "F.Cu" "F.Mask" "F.Paste")
			(net "JTAG_BMC_SW_R_OE")
		)
		(pad "2" smd rect
			(at -2.921 -1.299972 270)
			(size 0.3556 1.4986)
			(layers "F.Cu" "F.Mask" "F.Paste")
			(net "JTAG_BMC_TCK_R")
		)
		(pad "3" smd rect
			(at -2.921 -0.649986 270)
			(size 0.3556 1.4986)
			(layers "F.Cu" "F.Mask" "F.Paste")
			(net "JTAG_BMC_SW_TCK_R")
		)
		(pad "4" smd rect
			(at -2.921 0 270)
			(size 0.3556 1.4986)
			(layers "F.Cu" "F.Mask" "F.Paste")
			(net "JTAG_BMC_SW_R_OE")
		)
		(pad "5" smd rect
			(at -2.921 0.649986 270)
			(size 0.3556 1.4986)
			(layers "F.Cu" "F.Mask" "F.Paste")
			(net "JTAG_BMC_TMS_R")
		)
		(pad "6" smd rect
			(at -2.921 1.299972 270)
			(size 0.3556 1.4986)
			(layers "F.Cu" "F.Mask" "F.Paste")
			(net "JTAG_BMC_SW_TMS_R")
		)
		(pad "7" smd rect
			(at -2.921 1.949958 270)
			(size 0.3556 1.4986)
			(layers "F.Cu" "F.Mask" "F.Paste")
			(net "GND")
		)
		(pad "8" smd rect
			(at 2.921 1.949958 270)
			(size 0.3556 1.4986)
			(layers "F.Cu" "F.Mask" "F.Paste")
			(net "JTAG_BMC_SW_TDI_R")
		)
		(pad "9" smd rect
			(at 2.921 1.299972 270)
			(size 0.3556 1.4986)
			(layers "F.Cu" "F.Mask" "F.Paste")
			(net "JTAG_BMC_TDI_R")
		)
		(pad "10" smd rect
			(at 2.921 0.649986 270)
			(size 0.3556 1.4986)
			(layers "F.Cu" "F.Mask" "F.Paste")
			(net "JTAG_BMC_SW_R_OE")
		)
		(pad "11" smd rect
			(at 2.921 0 270)
			(size 0.3556 1.4986)
			(layers "F.Cu" "F.Mask" "F.Paste")
			(net "JTAG_BMC_SW_TDO_R")
		)
		(pad "12" smd rect
			(at 2.921 -0.649986 270)
			(size 0.3556 1.4986)
			(layers "F.Cu" "F.Mask" "F.Paste")
			(net "JTAG_BMC_TDO_R")
		)
		(pad "13" smd rect
			(at 2.921 -1.299972 270)
			(size 0.3556 1.4986)
			(layers "F.Cu" "F.Mask" "F.Paste")
			(net "JTAG_BMC_SW_R_OE")
		)
		(pad "14" smd rect
			(at 2.921 -1.949958 270)
			(size 0.3556 1.4986)
			(layers "F.Cu" "F.Mask" "F.Paste")
			(net "P3V3_AUX")
		)
	)
	(footprint ""
		(layer "F.Cu")
		(at 236.649768 -192.499996)
		(property "Reference" "H94"
			(at -4.87172 -5.123688 0)
			(unlocked yes)
			(layer "F.SilkS")
			(effects
				(font
					(size 0.7874 0.5842)
					(thickness 0.1524)
				)
				(justify left)
			)
		)
		(property "Value" ""
			(at 0 0 0)
			(layer "F.Fab")
			(effects
				(font
					(size 1.27 1.27)
				)
			)
		)
		(duplicate_pad_numbers_are_jumpers no)
		(pad "1" thru_hole circle
			(at 0 0)
			(size 10.0076 10.0076)
			(drill 5.6134)
			(layers "*.Cu" "*.Mask")
			(remove_unused_layers no)
			(net "GND")
			(clearance -1.9431)
		)
	)
	(footprint ""
		(layer "F.Cu")
		(at 223.716088 -223.09709 -90)
		(property "Reference" "C568"
			(at 0 0 270)
			(layer "F.SilkS")
			(hide yes)
			(effects
				(font
					(size 1.27 1.27)
				)
			)
		)
		(property "Value" ""
			(at 0 0 270)
			(layer "F.Fab")
			(effects
				(font
					(size 1.27 1.27)
				)
			)
		)
		(duplicate_pad_numbers_are_jumpers no)
		(fp_line
			(start -0.7874 0.4064)
			(end -0.7874 -0.4064)
			(stroke
				(width 0.1524)
				(type default)
			)
			(layer "F.SilkS")
		)
		(fp_line
			(start 0.7874 0.4064)
			(end -0.7874 0.4064)
			(stroke
				(width 0.1524)
				(type default)
			)
			(layer "F.SilkS")
		)
		(fp_line
			(start -0.7874 -0.4064)
			(end 0.7874 -0.4064)
			(stroke
				(width 0.1524)
				(type default)
			)
			(layer "F.SilkS")
		)
		(fp_line
			(start 0.7874 -0.4064)
			(end 0.7874 0.4064)
			(stroke
				(width 0.1524)
				(type default)
			)
			(layer "F.SilkS")
		)
		(fp_line
			(start -0.67945 0.3048)
			(end -0.67945 -0.305054)
			(stroke
				(width 0.1)
				(type default)
			)
			(layer "F.Fab")
		)
		(fp_line
			(start -0.12065 0.3048)
			(end -0.67945 0.3048)
			(stroke
				(width 0.1)
				(type default)
			)
			(layer "F.Fab")
		)
		(fp_line
			(start 0.120396 0.3048)
			(end 0.120396 0.2794)
			(stroke
				(width 0.1)
				(type default)
			)
			(layer "F.Fab")
		)
		(fp_line
			(start 0.67945 0.3048)
			(end 0.120396 0.3048)
			(stroke
				(width 0.1)
				(type default)
			)
			(layer "F.Fab")
		)
		(fp_line
			(start -0.12065 0.2794)
			(end -0.12065 0.3048)
			(stroke
				(width 0.1)
				(type default)
			)
			(layer "F.Fab")
		)
		(fp_line
			(start 0.120396 0.2794)
			(end -0.12065 0.2794)
			(stroke
				(width 0.1)
				(type default)
			)
			(layer "F.Fab")
		)
		(fp_line
			(start -0.12065 -0.2794)
			(end 0.12065 -0.2794)
			(stroke
				(width 0.1)
				(type default)
			)
			(layer "F.Fab")
		)
		(fp_line
			(start 0.12065 -0.2794)
			(end 0.12065 -0.3048)
			(stroke
				(width 0.1)
				(type default)
			)
			(layer "F.Fab")
		)
		(fp_line
			(start 0.12065 -0.3048)
			(end 0.67945 -0.3048)
			(stroke
				(width 0.1)
				(type default)
			)
			(layer "F.Fab")
		)
		(fp_line
			(start 0.67945 -0.3048)
			(end 0.67945 0.3048)
			(stroke
				(width 0.1)
				(type default)
			)
			(layer "F.Fab")
		)
		(fp_line
			(start -0.67945 -0.305054)
			(end -0.12065 -0.305054)
			(stroke
				(width 0.1)
				(type default)
			)
			(layer "F.Fab")
		)
		(fp_line
			(start -0.12065 -0.305054)
			(end -0.12065 -0.2794)
			(stroke
				(width 0.1)
				(type default)
			)
			(layer "F.Fab")
		)
		(pad "1" smd circle
			(at -0.40005 0 270)
			(size 0 0)
			(layers "F.Cu" "F.Mask" "F.Paste")
			(net "PVNN_TERM_CPU1")
		)
		(pad "2" smd circle
			(at 0.40005 0 270)
			(size 0 0)
			(layers "F.Cu" "F.Mask" "F.Paste")
			(net "GND")
		)
	)
	(footprint ""
		(layer "F.Cu")
		(at 366.4458 -15.255748 180)
		(property "Reference" "C2345"
			(at 0 0 180)
			(layer "F.SilkS")
			(hide yes)
			(effects
				(font
					(size 1.27 1.27)
				)
			)
		)
		(property "Value" ""
			(at 0 0 180)
			(layer "F.Fab")
			(effects
				(font
					(size 1.27 1.27)
				)
			)
		)
		(duplicate_pad_numbers_are_jumpers no)
		(fp_line
			(start 0.7874 0.4064)
			(end -0.7874 0.4064)
			(stroke
				(width 0.1524)
				(type default)
			)
			(layer "F.SilkS")
		)
		(fp_line
			(start 0.7874 -0.4064)
			(end 0.7874 0.4064)
			(stroke
				(width 0.1524)
				(type default)
			)
			(layer "F.SilkS")
		)
		(fp_line
			(start -0.7874 0.4064)
			(end -0.7874 -0.4064)
			(stroke
				(width 0.1524)
				(type default)
			)
			(layer "F.SilkS")
		)
		(fp_line
			(start -0.7874 -0.4064)
			(end 0.7874 -0.4064)
			(stroke
				(width 0.1524)
				(type default)
			)
			(layer "F.SilkS")
		)
		(fp_line
			(start 0.67945 0.3048)
			(end 0.120396 0.3048)
			(stroke
				(width 0.1)
				(type default)
			)
			(layer "F.Fab")
		)
		(fp_line
			(start 0.67945 -0.3048)
			(end 0.67945 0.3048)
			(stroke
				(width 0.1)
				(type default)
			)
			(layer "F.Fab")
		)
		(fp_line
			(start 0.12065 -0.2794)
			(end 0.12065 -0.3048)
			(stroke
				(width 0.1)
				(type default)
			)
			(layer "F.Fab")
		)
		(fp_line
			(start 0.12065 -0.3048)
			(end 0.67945 -0.3048)
			(stroke
				(width 0.1)
				(type default)
			)
			(layer "F.Fab")
		)
		(fp_line
			(start 0.120396 0.3048)
			(end 0.120396 0.2794)
			(stroke
				(width 0.1)
				(type default)
			)
			(layer "F.Fab")
		)
		(fp_line
			(start 0.120396 0.2794)
			(end -0.12065 0.2794)
			(stroke
				(width 0.1)
				(type default)
			)
			(layer "F.Fab")
		)
		(fp_line
			(start -0.12065 0.3048)
			(end -0.67945 0.3048)
			(stroke
				(width 0.1)
				(type default)
			)
			(layer "F.Fab")
		)
		(fp_line
			(start -0.12065 0.2794)
			(end -0.12065 0.3048)
			(stroke
				(width 0.1)
				(type default)
			)
			(layer "F.Fab")
		)
		(fp_line
			(start -0.12065 -0.2794)
			(end 0.12065 -0.2794)
			(stroke
				(width 0.1)
				(type default)
			)
			(layer "F.Fab")
		)
		(fp_line
			(start -0.12065 -0.305054)
			(end -0.12065 -0.2794)
			(stroke
				(width 0.1)
				(type default)
			)
			(layer "F.Fab")
		)
		(fp_line
			(start -0.67945 0.3048)
			(end -0.67945 -0.305054)
			(stroke
				(width 0.1)
				(type default)
			)
			(layer "F.Fab")
		)
		(fp_line
			(start -0.67945 -0.305054)
			(end -0.12065 -0.305054)
			(stroke
				(width 0.1)
				(type default)
			)
			(layer "F.Fab")
		)
		(pad "1" smd circle
			(at -0.40005 0 180)
			(size 0 0)
			(layers "F.Cu" "F.Mask" "F.Paste")
			(net "P3V3_AUX")
		)
		(pad "2" smd circle
			(at 0.40005 0 180)
			(size 0 0)
			(layers "F.Cu" "F.Mask" "F.Paste")
			(net "GND")
		)
	)
	(footprint ""
		(layer "F.Cu")
		(at 181.712616 -353.554284)
		(property "Reference" "PU77_P1_3"
			(at 3.717544 -10.170414 0)
			(unlocked yes)
			(layer "F.SilkS")
			(effects
				(font
					(size 0.7874 0.5842)
					(thickness 0.1524)
				)
				(justify left)
			)
		)
		(property "Value" ""
			(at 0 0 0)
			(layer "F.Fab")
			(effects
				(font
					(size 1.27 1.27)
				)
			)
		)
		(duplicate_pad_numbers_are_jumpers no)
		(fp_line
			(start -2.500122 -2.999994)
			(end -2.24409 -2.999994)
			(stroke
				(width 0.1524)
				(type default)
			)
			(layer "F.SilkS")
		)
		(fp_line
			(start -2.500122 -2.529078)
			(end -2.500122 -2.999994)
			(stroke
				(width 0.1524)
				(type default)
			)
			(layer "F.SilkS")
		)
		(fp_line
			(start -2.500122 0.6604)
			(end -2.500122 0.229108)
			(stroke
				(width 0.1524)
				(type default)
			)
			(layer "F.SilkS")
		)
		(fp_line
			(start -2.500122 2.999994)
			(end -2.500122 2.339594)
			(stroke
				(width 0.1524)
				(type default)
			)
			(layer "F.SilkS")
		)
		(fp_line
			(start -2.2987 2.999994)
			(end -2.500122 2.999994)
			(stroke
				(width 0.1524)
				(type default)
			)
			(layer "F.SilkS")
		)
		(fp_line
			(start 2.31394 -2.999994)
			(end 2.500122 -2.999994)
			(stroke
				(width 0.1524)
				(type default)
			)
			(layer "F.SilkS")
		)
		(fp_line
			(start 2.500122 -2.999994)
			(end 2.500122 -2.44348)
			(stroke
				(width 0.1524)
				(type default)
			)
			(layer "F.SilkS")
		)
		(fp_line
			(start 2.500122 2.339594)
			(end 2.500122 2.999994)
			(stroke
				(width 0.1524)
				(type default)
			)
			(layer "F.SilkS")
		)
		(fp_line
			(start 2.500122 2.999994)
			(end 2.2987 2.999994)
			(stroke
				(width 0.1524)
				(type default)
			)
			(layer "F.SilkS")
		)
		(fp_poly
			(pts
				(xy -5.358892 -2.826258) (xy -4.342892 -2.318258) (xy -5.358892 -1.810258)
			)
			(stroke
				(width 0)
				(type default)
			)
			(fill yes)
			(layer "F.SilkS")
		)
		(fp_line
			(start -2.500122 -2.999994)
			(end 2.500122 -2.999994)
			(stroke
				(width 0.1)
				(type default)
			)
			(layer "F.Fab")
		)
		(fp_line
			(start -2.500122 2.999994)
			(end -2.500122 -2.999994)
			(stroke
				(width 0.1)
				(type default)
			)
			(layer "F.Fab")
		)
		(fp_line
			(start 2.500122 -2.999994)
			(end 2.500122 2.999994)
			(stroke
				(width 0.1)
				(type default)
			)
			(layer "F.Fab")
		)
		(fp_line
			(start 2.500122 2.999994)
			(end -2.500122 2.999994)
			(stroke
				(width 0.1)
				(type default)
			)
			(layer "F.Fab")
		)
		(fp_poly
			(pts
				(xy -4.218432 -2.783078) (xy -4.218432 -1.767078) (xy -3.202432 -2.275078)
			)
			(stroke
				(width 0)
				(type default)
			)
			(fill yes)
			(layer "F.Fab")
		)
		(pad "1" smd rect
			(at -2.400046 -2.275078 90)
			(size 0.2286 0.6096)
			(layers "F.Cu" "F.Mask" "F.Paste")
			(net "PVCCFA_EHV_FIVRA_CPU1_VOS3")
		)
		(pad "2" smd rect
			(at -2.400046 -1.82499 90)
			(size 0.2286 0.6096)
			(layers "F.Cu" "F.Mask" "F.Paste")
			(net "GND")
		)
		(pad "3" smd rect
			(at -2.400046 -1.374902 90)
			(size 0.2286 0.6096)
			(layers "F.Cu" "F.Mask" "F.Paste")
			(net "PVCCFA_EHV_FIVRA_CPU1_VDD3")
		)
		(pad "4" smd rect
			(at -2.400046 -0.925068 90)
			(size 0.2286 0.6096)
			(layers "F.Cu" "F.Mask" "F.Paste")
			(net "PVCCFA_EHV_FIVRA_CPU1_PVCC1")
		)
		(pad "5" smd rect
			(at -2.400046 -0.47498 90)
			(size 0.2286 0.6096)
			(layers "F.Cu" "F.Mask" "F.Paste")
			(net "GND")
		)
		(pad "6" smd rect
			(at -2.400046 -0.024892 90)
			(size 0.2286 0.6096)
			(layers "F.Cu" "F.Mask" "F.Paste")
			(net "Net_8499")
		)
		(pad "7_9-20_24" smd circle
			(at 0 1.150112 90)
			(size 0 0)
			(layers "F.Cu" "F.Mask" "F.Paste")
			(net "GND")
		)
		(pad "10_19" smd rect
			(at 0 2.899918 90)
			(size 0.6096 4.318)
			(layers "F.Cu" "F.Mask" "F.Paste")
			(net "SW_PVCCFA_EHV_FIVRA_CPU1_SW3")
		)
		(pad "25_29" smd rect
			(at 1.549908 -1.279906 270)
			(size 2.0574 2.3114)
			(layers "F.Cu" "F.Mask" "F.Paste")
			(net "SW_P12V_PVCCFA_EHV_FIVRA_CPU1_R")
		)
		(pad "30" smd rect
			(at 2.05994 -2.899918)
			(size 0.2286 0.6096)
			(layers "F.Cu" "F.Mask" "F.Paste")
			(net "SW_P12V_PVCCFA_EHV_FIVRA_CPU1_R")
		)
		(pad "31" smd rect
			(at 1.610106 -2.899918)
			(size 0.2286 0.6096)
			(layers "F.Cu" "F.Mask" "F.Paste")
			(net "Net_8500")
		)
		(pad "32" smd rect
			(at 1.160018 -2.899918)
			(size 0.2286 0.6096)
			(layers "F.Cu" "F.Mask" "F.Paste")
			(net "SW_PVCCFA_EHV_FIVRA_CPU1_BOOTR3")
		)
		(pad "33" smd rect
			(at 0.70993 -2.899918)
			(size 0.2286 0.6096)
			(layers "F.Cu" "F.Mask" "F.Paste")
			(net "SW_PVCCFA_EHV_FIVRA_CPU1_BOOT3")
		)
		(pad "34" smd rect
			(at 0.260096 -2.899918)
			(size 0.2286 0.6096)
			(layers "F.Cu" "F.Mask" "F.Paste")
			(net "PVCCFA_EHV_FIVRA_CPU1_PWM3")
		)
		(pad "35" smd rect
			(at -0.189992 -2.899918)
			(size 0.2286 0.6096)
			(layers "F.Cu" "F.Mask" "F.Paste")
			(net "PVCCFA_EHV_FIVRA_CPU1_VDD3")
		)
		(pad "36" smd rect
			(at -0.64008 -2.899918)
			(size 0.2286 0.6096)
			(layers "F.Cu" "F.Mask" "F.Paste")
			(net "PVCCFA_EHV_FIVRA_CPU1_BTSEN")
		)
		(pad "37" smd rect
			(at -1.089914 -2.899918)
			(size 0.2286 0.6096)
			(layers "F.Cu" "F.Mask" "F.Paste")
			(net "PVCCFA_EHV_FIVRA_CPU1_LSET3")
		)
		(pad "38" smd rect
			(at -1.540002 -2.899918)
			(size 0.2286 0.6096)
			(layers "F.Cu" "F.Mask" "F.Paste")
			(net "PVCCFA_EHV_FIVRA_CPU1_IMON3")
		)
		(pad "39" smd rect
			(at -1.99009 -2.899918)
			(size 0.2286 0.6096)
			(layers "F.Cu" "F.Mask" "F.Paste")
			(net "PVCCIN_CPU1_VREF")
		)
		(pad "40" smd rect
			(at -0.87503 -1.27508)
			(size 1.7526 1.9558)
			(layers "F.Cu" "F.Mask" "F.Paste")
			(net "GND")
		)
		(pad "41" smd rect
			(at -1.525016 0.249936 270)
			(size 0.3048 0.4572)
			(layers "F.Cu" "F.Mask" "F.Paste")
			(net "Net_8498")
		)
		(zone
			(layer "F.Cu")
			(hatch none 0.5)
			(connect_pads
				(clearance 0)
			)
			(min_thickness 0.25)
			(keepout
				(tracks not_allowed)
				(vias allowed)
				(pads allowed)
				(copperpour not_allowed)
				(footprints allowed)
			)
			(placement
				(enabled no)
				(sheetname "")
			)
			(fill
				(thermal_gap 0.5)
				(thermal_bridge_width 0.5)
				(island_removal_mode 0)
			)
			(polygon
				(pts
					(xy 179.212494 -350.55429) (xy 179.212494 -351.285048) (xy 184.212738 -351.285048) (xy 184.212738 -350.55429)
					(xy 183.922416 -350.55429) (xy 183.922416 -351.009966) (xy 179.502816 -351.009966) (xy 179.502816 -350.55429)
				)
			)
		)
		(zone
			(layer "F.Cu")
			(hatch none 0.5)
			(connect_pads
				(clearance 0)
			)
			(min_thickness 0.25)
			(keepout
				(tracks not_allowed)
				(vias allowed)
				(pads allowed)
				(copperpour not_allowed)
				(footprints allowed)
			)
			(placement
				(enabled no)
				(sheetname "")
			)
			(fill
				(thermal_gap 0.5)
				(thermal_bridge_width 0.5)
				(island_removal_mode 0)
			)
			(polygon
				(pts
					(xy 179.9336 -353.800664) (xy 180.70068 -353.800664) (xy 180.70068 -353.482148) (xy 180.761894 -353.482148)
					(xy 180.761894 -352.861118) (xy 180.70576 -352.804984) (xy 179.212494 -352.804984) (xy 179.212494 -353.261676)
					(xy 179.9082 -353.261676) (xy 179.9082 -353.101148) (xy 180.467 -353.101148) (xy 180.467 -353.507548)
					(xy 179.9082 -353.507548) (xy 179.9082 -353.287076) (xy 179.212494 -353.287076) (xy 179.212494 -353.414076)
					(xy 179.66817 -353.414076) (xy 179.66817 -353.784408) (xy 179.9336 -353.784408)
				)
			)
		)
	)
	(footprint ""
		(layer "F.Cu")
		(at 308.4068 -26.3652)
		(property "Reference" "U342"
			(at 5.0927 -1.85801 0)
			(unlocked yes)
			(layer "F.SilkS")
			(effects
				(font
					(size 0.7874 0.5842)
					(thickness 0.1524)
				)
			)
		)
		(property "Value" ""
			(at 0 0 0)
			(layer "F.Fab")
			(effects
				(font
					(size 1.27 1.27)
				)
			)
		)
		(duplicate_pad_numbers_are_jumpers no)
		(fp_line
			(start -2.032 -1.549908)
			(end -0.508 -1.549908)
			(stroke
				(width 0.1524)
				(type default)
			)
			(layer "F.SilkS")
		)
		(fp_line
			(start -2.032 1.549908)
			(end -2.032 -1.549908)
			(stroke
				(width 0.1524)
				(type default)
			)
			(layer "F.SilkS")
		)
		(fp_line
			(start -0.508 -1.549908)
			(end 0 -0.762)
			(stroke
				(width 0.1524)
				(type default)
			)
			(layer "F.SilkS")
		)
		(fp_line
			(start 0 -0.762)
			(end 0.508 -1.549908)
			(stroke
				(width 0.1524)
				(type default)
			)
			(layer "F.SilkS")
		)
		(fp_line
			(start 0.508 -1.549908)
			(end 2.032 -1.549908)
			(stroke
				(width 0.1524)
				(type default)
			)
			(layer "F.SilkS")
		)
		(fp_line
			(start 2.032 -1.549908)
			(end 2.032 1.549908)
			(stroke
				(width 0.1524)
				(type default)
			)
			(layer "F.SilkS")
		)
		(fp_line
			(start 2.032 1.549908)
			(end -2.032 1.549908)
			(stroke
				(width 0.1524)
				(type default)
			)
			(layer "F.SilkS")
		)
		(fp_poly
			(pts
				(xy -3.2004 -1.45796) (xy -3.2004 -0.44196) (xy -2.1844 -0.94996)
			)
			(stroke
				(width 0)
				(type default)
			)
			(fill yes)
			(layer "F.SilkS")
		)
		(fp_line
			(start -0.849884 -1.549908)
			(end 0.849884 -1.549908)
			(stroke
				(width 0.1)
				(type default)
			)
			(layer "F.Fab")
		)
		(fp_line
			(start -0.849884 1.549908)
			(end -0.849884 -1.549908)
			(stroke
				(width 0.1)
				(type default)
			)
			(layer "F.Fab")
		)
		(fp_line
			(start 0.849884 -1.549908)
			(end 0.849884 1.549908)
			(stroke
				(width 0.1)
				(type default)
			)
			(layer "F.Fab")
		)
		(fp_line
			(start 0.849884 1.549908)
			(end -0.849884 1.549908)
			(stroke
				(width 0.1)
				(type default)
			)
			(layer "F.Fab")
		)
		(fp_poly
			(pts
				(xy -3.2004 -1.45796) (xy -3.2004 -0.44196) (xy -2.1844 -0.94996)
			)
			(stroke
				(width 0)
				(type default)
			)
			(fill yes)
			(layer "F.Fab")
		)
		(pad "1" smd rect
			(at -1.35001 -0.94996 270)
			(size 0.6096 1.0668)
			(layers "F.Cu" "F.Mask" "F.Paste")
			(net "DSW_PWROK_P2V5_COMP")
		)
		(pad "2" smd rect
			(at -1.35001 0 270)
			(size 0.6096 1.0668)
			(layers "F.Cu" "F.Mask" "F.Paste")
			(net "GND")
		)
		(pad "3" smd rect
			(at -1.35001 0.94996 270)
			(size 0.6096 1.0668)
			(layers "F.Cu" "F.Mask" "F.Paste")
			(net "PWRGD_DSW_PWROK_TRIGGER")
		)
		(pad "4" smd rect
			(at 1.35001 0.94996 270)
			(size 0.6096 1.0668)
			(layers "F.Cu" "F.Mask" "F.Paste")
			(net "PWRGD_DSW_PWROK_R5")
		)
		(pad "5" smd rect
			(at 1.35001 -0.94996 270)
			(size 0.6096 1.0668)
			(layers "F.Cu" "F.Mask" "F.Paste")
			(net "P12V_AUX")
		)
	)
	(footprint ""
		(layer "F.Cu")
		(at 209.931 -114.0968 180)
		(property "Reference" "R4773"
			(at 0 0 180)
			(layer "F.SilkS")
			(hide yes)
			(effects
				(font
					(size 1.27 1.27)
				)
			)
		)
		(property "Value" ""
			(at 0 0 180)
			(layer "F.Fab")
			(effects
				(font
					(size 1.27 1.27)
				)
			)
		)
		(duplicate_pad_numbers_are_jumpers no)
		(fp_line
			(start 0.7874 0.4064)
			(end -0.7874 0.4064)
			(stroke
				(width 0.1524)
				(type default)
			)
			(layer "F.SilkS")
		)
		(fp_line
			(start 0.7874 -0.4064)
			(end 0.7874 0.4064)
			(stroke
				(width 0.1524)
				(type default)
			)
			(layer "F.SilkS")
		)
		(fp_line
			(start -0.7874 0.4064)
			(end -0.7874 -0.4064)
			(stroke
				(width 0.1524)
				(type default)
			)
			(layer "F.SilkS")
		)
		(fp_line
			(start -0.7874 -0.4064)
			(end 0.7874 -0.4064)
			(stroke
				(width 0.1524)
				(type default)
			)
			(layer "F.SilkS")
		)
		(fp_line
			(start 0.67945 0.3048)
			(end 0.120396 0.3048)
			(stroke
				(width 0.1)
				(type default)
			)
			(layer "F.Fab")
		)
		(fp_line
			(start 0.67945 -0.3048)
			(end 0.67945 0.3048)
			(stroke
				(width 0.1)
				(type default)
			)
			(layer "F.Fab")
		)
		(fp_line
			(start 0.12065 -0.2794)
			(end 0.12065 -0.3048)
			(stroke
				(width 0.1)
				(type default)
			)
			(layer "F.Fab")
		)
		(fp_line
			(start 0.12065 -0.3048)
			(end 0.67945 -0.3048)
			(stroke
				(width 0.1)
				(type default)
			)
			(layer "F.Fab")
		)
		(fp_line
			(start 0.120396 0.3048)
			(end 0.120396 0.2794)
			(stroke
				(width 0.1)
				(type default)
			)
			(layer "F.Fab")
		)
		(fp_line
			(start 0.120396 0.2794)
			(end -0.12065 0.2794)
			(stroke
				(width 0.1)
				(type default)
			)
			(layer "F.Fab")
		)
		(fp_line
			(start -0.12065 0.3048)
			(end -0.67945 0.3048)
			(stroke
				(width 0.1)
				(type default)
			)
			(layer "F.Fab")
		)
		(fp_line
			(start -0.12065 0.2794)
			(end -0.12065 0.3048)
			(stroke
				(width 0.1)
				(type default)
			)
			(layer "F.Fab")
		)
		(fp_line
			(start -0.12065 -0.2794)
			(end 0.12065 -0.2794)
			(stroke
				(width 0.1)
				(type default)
			)
			(layer "F.Fab")
		)
		(fp_line
			(start -0.12065 -0.305054)
			(end -0.12065 -0.2794)
			(stroke
				(width 0.1)
				(type default)
			)
			(layer "F.Fab")
		)
		(fp_line
			(start -0.67945 0.3048)
			(end -0.67945 -0.305054)
			(stroke
				(width 0.1)
				(type default)
			)
			(layer "F.Fab")
		)
		(fp_line
			(start -0.67945 -0.305054)
			(end -0.12065 -0.305054)
			(stroke
				(width 0.1)
				(type default)
			)
			(layer "F.Fab")
		)
		(pad "1" smd circle
			(at -0.40005 0 180)
			(size 0 0)
			(layers "F.Cu" "F.Mask" "F.Paste")
			(net "P3V3_AUX")
		)
		(pad "2" smd circle
			(at 0.40005 0 180)
			(size 0 0)
			(layers "F.Cu" "F.Mask" "F.Paste")
			(net "UV_P2V5_COMP")
		)
	)
	(footprint ""
		(layer "F.Cu")
		(at 136.62406 -27.447748)
		(property "Reference" "R4282"
			(at 0 0 0)
			(layer "F.SilkS")
			(hide yes)
			(effects
				(font
					(size 1.27 1.27)
				)
			)
		)
		(property "Value" ""
			(at 0 0 0)
			(layer "F.Fab")
			(effects
				(font
					(size 1.27 1.27)
				)
			)
		)
		(duplicate_pad_numbers_are_jumpers no)
		(fp_line
			(start -0.7874 -0.4064)
			(end 0.7874 -0.4064)
			(stroke
				(width 0.1524)
				(type default)
			)
			(layer "F.SilkS")
		)
		(fp_line
			(start -0.7874 0.4064)
			(end -0.7874 -0.4064)
			(stroke
				(width 0.1524)
				(type default)
			)
			(layer "F.SilkS")
		)
		(fp_line
			(start 0.7874 -0.4064)
			(end 0.7874 0.4064)
			(stroke
				(width 0.1524)
				(type default)
			)
			(layer "F.SilkS")
		)
		(fp_line
			(start 0.7874 0.4064)
			(end -0.7874 0.4064)
			(stroke
				(width 0.1524)
				(type default)
			)
			(layer "F.SilkS")
		)
		(fp_line
			(start -0.67945 -0.305054)
			(end -0.12065 -0.305054)
			(stroke
				(width 0.1)
				(type default)
			)
			(layer "F.Fab")
		)
		(fp_line
			(start -0.67945 0.3048)
			(end -0.67945 -0.305054)
			(stroke
				(width 0.1)
				(type default)
			)
			(layer "F.Fab")
		)
		(fp_line
			(start -0.12065 -0.305054)
			(end -0.12065 -0.2794)
			(stroke
				(width 0.1)
				(type default)
			)
			(layer "F.Fab")
		)
		(fp_line
			(start -0.12065 -0.2794)
			(end 0.12065 -0.2794)
			(stroke
				(width 0.1)
				(type default)
			)
			(layer "F.Fab")
		)
		(fp_line
			(start -0.12065 0.2794)
			(end -0.12065 0.3048)
			(stroke
				(width 0.1)
				(type default)
			)
			(layer "F.Fab")
		)
		(fp_line
			(start -0.12065 0.3048)
			(end -0.67945 0.3048)
			(stroke
				(width 0.1)
				(type default)
			)
			(layer "F.Fab")
		)
		(fp_line
			(start 0.120396 0.2794)
			(end -0.12065 0.2794)
			(stroke
				(width 0.1)
				(type default)
			)
			(layer "F.Fab")
		)
		(fp_line
			(start 0.120396 0.3048)
			(end 0.120396 0.2794)
			(stroke
				(width 0.1)
				(type default)
			)
			(layer "F.Fab")
		)
		(fp_line
			(start 0.12065 -0.3048)
			(end 0.67945 -0.3048)
			(stroke
				(width 0.1)
				(type default)
			)
			(layer "F.Fab")
		)
		(fp_line
			(start 0.12065 -0.2794)
			(end 0.12065 -0.3048)
			(stroke
				(width 0.1)
				(type default)
			)
			(layer "F.Fab")
		)
		(fp_line
			(start 0.67945 -0.3048)
			(end 0.67945 0.3048)
			(stroke
				(width 0.1)
				(type default)
			)
			(layer "F.Fab")
		)
		(fp_line
			(start 0.67945 0.3048)
			(end 0.120396 0.3048)
			(stroke
				(width 0.1)
				(type default)
			)
			(layer "F.Fab")
		)
		(pad "1" smd circle
			(at -0.40005 0)
			(size 0 0)
			(layers "F.Cu" "F.Mask" "F.Paste")
			(net "FM_USB3_1_EQB")
		)
		(pad "2" smd circle
			(at 0.40005 0)
			(size 0 0)
			(layers "F.Cu" "F.Mask" "F.Paste")
			(net "GND")
		)
	)
	(footprint ""
		(layer "F.Cu")
		(at 140.208 -368.645948 -90)
		(property "Reference" "R1713"
			(at 0 0 270)
			(layer "F.SilkS")
			(hide yes)
			(effects
				(font
					(size 1.27 1.27)
				)
			)
		)
		(property "Value" ""
			(at 0 0 270)
			(layer "F.Fab")
			(effects
				(font
					(size 1.27 1.27)
				)
			)
		)
		(duplicate_pad_numbers_are_jumpers no)
		(fp_line
			(start -0.7874 0.4064)
			(end -0.7874 -0.4064)
			(stroke
				(width 0.1524)
				(type default)
			)
			(layer "F.SilkS")
		)
		(fp_line
			(start 0.7874 0.4064)
			(end -0.7874 0.4064)
			(stroke
				(width 0.1524)
				(type default)
			)
			(layer "F.SilkS")
		)
		(fp_line
			(start -0.7874 -0.4064)
			(end 0.7874 -0.4064)
			(stroke
				(width 0.1524)
				(type default)
			)
			(layer "F.SilkS")
		)
		(fp_line
			(start 0.7874 -0.4064)
			(end 0.7874 0.4064)
			(stroke
				(width 0.1524)
				(type default)
			)
			(layer "F.SilkS")
		)
		(fp_line
			(start -0.67945 0.3048)
			(end -0.67945 -0.305054)
			(stroke
				(width 0.1)
				(type default)
			)
			(layer "F.Fab")
		)
		(fp_line
			(start -0.12065 0.3048)
			(end -0.67945 0.3048)
			(stroke
				(width 0.1)
				(type default)
			)
			(layer "F.Fab")
		)
		(fp_line
			(start 0.120396 0.3048)
			(end 0.120396 0.2794)
			(stroke
				(width 0.1)
				(type default)
			)
			(layer "F.Fab")
		)
		(fp_line
			(start 0.67945 0.3048)
			(end 0.120396 0.3048)
			(stroke
				(width 0.1)
				(type default)
			)
			(layer "F.Fab")
		)
		(fp_line
			(start -0.12065 0.2794)
			(end -0.12065 0.3048)
			(stroke
				(width 0.1)
				(type default)
			)
			(layer "F.Fab")
		)
		(fp_line
			(start 0.120396 0.2794)
			(end -0.12065 0.2794)
			(stroke
				(width 0.1)
				(type default)
			)
			(layer "F.Fab")
		)
		(fp_line
			(start -0.12065 -0.2794)
			(end 0.12065 -0.2794)
			(stroke
				(width 0.1)
				(type default)
			)
			(layer "F.Fab")
		)
		(fp_line
			(start 0.12065 -0.2794)
			(end 0.12065 -0.3048)
			(stroke
				(width 0.1)
				(type default)
			)
			(layer "F.Fab")
		)
		(fp_line
			(start 0.12065 -0.3048)
			(end 0.67945 -0.3048)
			(stroke
				(width 0.1)
				(type default)
			)
			(layer "F.Fab")
		)
		(fp_line
			(start 0.67945 -0.3048)
			(end 0.67945 0.3048)
			(stroke
				(width 0.1)
				(type default)
			)
			(layer "F.Fab")
		)
		(fp_line
			(start -0.67945 -0.305054)
			(end -0.12065 -0.305054)
			(stroke
				(width 0.1)
				(type default)
			)
			(layer "F.Fab")
		)
		(fp_line
			(start -0.12065 -0.305054)
			(end -0.12065 -0.2794)
			(stroke
				(width 0.1)
				(type default)
			)
			(layer "F.Fab")
		)
		(pad "1" smd circle
			(at -0.40005 0 270)
			(size 0 0)
			(layers "F.Cu" "F.Mask" "F.Paste")
			(net "SMB_VR_3V3AUX_SCL_R3")
		)
		(pad "2" smd circle
			(at 0.40005 0 270)
			(size 0 0)
			(layers "F.Cu" "F.Mask" "F.Paste")
			(net "P3V3_AUX")
		)
	)
	(footprint ""
		(layer "F.Cu")
		(at 164.64788 -113.756948)
		(property "Reference" "R3485"
			(at 0 0 0)
			(layer "F.SilkS")
			(hide yes)
			(effects
				(font
					(size 1.27 1.27)
				)
			)
		)
		(property "Value" ""
			(at 0 0 0)
			(layer "F.Fab")
			(effects
				(font
					(size 1.27 1.27)
				)
			)
		)
		(duplicate_pad_numbers_are_jumpers no)
		(fp_line
			(start -0.7874 -0.4064)
			(end 0.7874 -0.4064)
			(stroke
				(width 0.1524)
				(type default)
			)
			(layer "F.SilkS")
		)
		(fp_line
			(start -0.7874 0.4064)
			(end -0.7874 -0.4064)
			(stroke
				(width 0.1524)
				(type default)
			)
			(layer "F.SilkS")
		)
		(fp_line
			(start 0.7874 -0.4064)
			(end 0.7874 0.4064)
			(stroke
				(width 0.1524)
				(type default)
			)
			(layer "F.SilkS")
		)
		(fp_line
			(start 0.7874 0.4064)
			(end -0.7874 0.4064)
			(stroke
				(width 0.1524)
				(type default)
			)
			(layer "F.SilkS")
		)
		(fp_line
			(start -0.67945 -0.305054)
			(end -0.12065 -0.305054)
			(stroke
				(width 0.1)
				(type default)
			)
			(layer "F.Fab")
		)
		(fp_line
			(start -0.67945 0.3048)
			(end -0.67945 -0.305054)
			(stroke
				(width 0.1)
				(type default)
			)
			(layer "F.Fab")
		)
		(fp_line
			(start -0.12065 -0.305054)
			(end -0.12065 -0.2794)
			(stroke
				(width 0.1)
				(type default)
			)
			(layer "F.Fab")
		)
		(fp_line
			(start -0.12065 -0.2794)
			(end 0.12065 -0.2794)
			(stroke
				(width 0.1)
				(type default)
			)
			(layer "F.Fab")
		)
		(fp_line
			(start -0.12065 0.2794)
			(end -0.12065 0.3048)
			(stroke
				(width 0.1)
				(type default)
			)
			(layer "F.Fab")
		)
		(fp_line
			(start -0.12065 0.3048)
			(end -0.67945 0.3048)
			(stroke
				(width 0.1)
				(type default)
			)
			(layer "F.Fab")
		)
		(fp_line
			(start 0.120396 0.2794)
			(end -0.12065 0.2794)
			(stroke
				(width 0.1)
				(type default)
			)
			(layer "F.Fab")
		)
		(fp_line
			(start 0.120396 0.3048)
			(end 0.120396 0.2794)
			(stroke
				(width 0.1)
				(type default)
			)
			(layer "F.Fab")
		)
		(fp_line
			(start 0.12065 -0.3048)
			(end 0.67945 -0.3048)
			(stroke
				(width 0.1)
				(type default)
			)
			(layer "F.Fab")
		)
		(fp_line
			(start 0.12065 -0.2794)
			(end 0.12065 -0.3048)
			(stroke
				(width 0.1)
				(type default)
			)
			(layer "F.Fab")
		)
		(fp_line
			(start 0.67945 -0.3048)
			(end 0.67945 0.3048)
			(stroke
				(width 0.1)
				(type default)
			)
			(layer "F.Fab")
		)
		(fp_line
			(start 0.67945 0.3048)
			(end 0.120396 0.3048)
			(stroke
				(width 0.1)
				(type default)
			)
			(layer "F.Fab")
		)
		(pad "1" smd circle
			(at -0.40005 0)
			(size 0 0)
			(layers "F.Cu" "F.Mask" "F.Paste")
			(net "GPU_WP_HW_CTRL_N")
		)
		(pad "2" smd circle
			(at 0.40005 0)
			(size 0 0)
			(layers "F.Cu" "F.Mask" "F.Paste")
			(net "GPU_WP_HW_CTRL_R_N")
		)
	)
	(footprint ""
		(layer "F.Cu")
		(at 156.085794 -408.517344 -90)
		(property "Reference" "C1539"
			(at 0 0 270)
			(layer "F.SilkS")
			(hide yes)
			(effects
				(font
					(size 1.27 1.27)
				)
			)
		)
		(property "Value" ""
			(at 0 0 270)
			(layer "F.Fab")
			(effects
				(font
					(size 1.27 1.27)
				)
			)
		)
		(duplicate_pad_numbers_are_jumpers no)
		(fp_line
			(start -0.299974 0.150114)
			(end -0.299974 -0.150114)
			(stroke
				(width 0.1)
				(type default)
			)
			(layer "F.Fab")
		)
		(fp_line
			(start 0.299974 0.150114)
			(end -0.299974 0.150114)
			(stroke
				(width 0.1)
				(type default)
			)
			(layer "F.Fab")
		)
		(fp_line
			(start -0.299974 -0.150114)
			(end 0.299974 -0.150114)
			(stroke
				(width 0.1)
				(type default)
			)
			(layer "F.Fab")
		)
		(fp_line
			(start 0.299974 -0.150114)
			(end 0.299974 0.150114)
			(stroke
				(width 0.1)
				(type default)
			)
			(layer "F.Fab")
		)
		(pad "1" smd rect
			(at -0.2667 0 270)
			(size 0.3048 0.381)
			(layers "F.Cu" "F.Mask" "F.Paste")
			(net "P5E_CPU1_PE3_TX_C_DP<4>")
		)
		(pad "2" smd rect
			(at 0.2667 0 270)
			(size 0.3048 0.381)
			(layers "F.Cu" "F.Mask" "F.Paste")
			(net "P5E_CPU1_PE3_TX_DP<4>")
		)
	)
	(footprint ""
		(layer "F.Cu")
		(at 113.318798 -333.716122)
		(property "Reference" "PU28_P1_3"
			(at -1.810258 -6.183376 0)
			(unlocked yes)
			(layer "F.SilkS")
			(effects
				(font
					(size 0.7874 0.5842)
					(thickness 0.1524)
				)
				(justify left)
			)
		)
		(property "Value" ""
			(at 0 0 0)
			(layer "F.Fab")
			(effects
				(font
					(size 1.27 1.27)
				)
			)
		)
		(duplicate_pad_numbers_are_jumpers no)
		(fp_line
			(start -2.500122 -2.999994)
			(end -2.24409 -2.999994)
			(stroke
				(width 0.1524)
				(type default)
			)
			(layer "F.SilkS")
		)
		(fp_line
			(start -2.500122 -2.529078)
			(end -2.500122 -2.999994)
			(stroke
				(width 0.1524)
				(type default)
			)
			(layer "F.SilkS")
		)
		(fp_line
			(start -2.500122 0.6604)
			(end -2.500122 0.229108)
			(stroke
				(width 0.1524)
				(type default)
			)
			(layer "F.SilkS")
		)
		(fp_line
			(start -2.500122 2.999994)
			(end -2.500122 2.339594)
			(stroke
				(width 0.1524)
				(type default)
			)
			(layer "F.SilkS")
		)
		(fp_line
			(start -2.2987 2.999994)
			(end -2.500122 2.999994)
			(stroke
				(width 0.1524)
				(type default)
			)
			(layer "F.SilkS")
		)
		(fp_line
			(start 2.31394 -2.999994)
			(end 2.500122 -2.999994)
			(stroke
				(width 0.1524)
				(type default)
			)
			(layer "F.SilkS")
		)
		(fp_line
			(start 2.500122 -2.999994)
			(end 2.500122 -2.44348)
			(stroke
				(width 0.1524)
				(type default)
			)
			(layer "F.SilkS")
		)
		(fp_line
			(start 2.500122 2.339594)
			(end 2.500122 2.999994)
			(stroke
				(width 0.1524)
				(type default)
			)
			(layer "F.SilkS")
		)
		(fp_line
			(start 2.500122 2.999994)
			(end 2.2987 2.999994)
			(stroke
				(width 0.1524)
				(type default)
			)
			(layer "F.SilkS")
		)
		(fp_poly
			(pts
				(xy -2.148586 -3.63728) (xy -2.656586 -2.62128) (xy -3.164586 -3.63728)
			)
			(stroke
				(width 0)
				(type default)
			)
			(fill yes)
			(layer "F.SilkS")
		)
		(fp_line
			(start -2.500122 -2.999994)
			(end 2.500122 -2.999994)
			(stroke
				(width 0.1)
				(type default)
			)
			(layer "F.Fab")
		)
		(fp_line
			(start -2.500122 2.999994)
			(end -2.500122 -2.999994)
			(stroke
				(width 0.1)
				(type default)
			)
			(layer "F.Fab")
		)
		(fp_line
			(start 2.500122 -2.999994)
			(end 2.500122 2.999994)
			(stroke
				(width 0.1)
				(type default)
			)
			(layer "F.Fab")
		)
		(fp_line
			(start 2.500122 2.999994)
			(end -2.500122 2.999994)
			(stroke
				(width 0.1)
				(type default)
			)
			(layer "F.Fab")
		)
		(fp_poly
			(pts
				(xy -4.218432 -2.783078) (xy -4.218432 -1.767078) (xy -3.202432 -2.275078)
			)
			(stroke
				(width 0)
				(type default)
			)
			(fill yes)
			(layer "F.Fab")
		)
		(pad "1" smd rect
			(at -2.400046 -2.275078 90)
			(size 0.2286 0.6096)
			(layers "F.Cu" "F.Mask" "F.Paste")
			(net "PVCCIN_CPU1_VOS3")
		)
		(pad "2" smd rect
			(at -2.400046 -1.82499 90)
			(size 0.2286 0.6096)
			(layers "F.Cu" "F.Mask" "F.Paste")
			(net "GND")
		)
		(pad "3" smd rect
			(at -2.400046 -1.374902 90)
			(size 0.2286 0.6096)
			(layers "F.Cu" "F.Mask" "F.Paste")
			(net "PVCCIN_CPU1_VDD3")
		)
		(pad "4" smd rect
			(at -2.400046 -0.925068 90)
			(size 0.2286 0.6096)
			(layers "F.Cu" "F.Mask" "F.Paste")
			(net "PVCCIN_CPU1_PVCC")
		)
		(pad "5" smd rect
			(at -2.400046 -0.47498 90)
			(size 0.2286 0.6096)
			(layers "F.Cu" "F.Mask" "F.Paste")
			(net "GND")
		)
		(pad "6" smd rect
			(at -2.400046 -0.024892 90)
			(size 0.2286 0.6096)
			(layers "F.Cu" "F.Mask" "F.Paste")
			(net "Net_8526")
		)
		(pad "7_9-20_24" smd circle
			(at 0 1.150112 90)
			(size 0 0)
			(layers "F.Cu" "F.Mask" "F.Paste")
			(net "GND")
		)
		(pad "10_19" smd rect
			(at 0 2.899918 90)
			(size 0.6096 4.318)
			(layers "F.Cu" "F.Mask" "F.Paste")
			(net "SW_PVCCIN_CPU1_SW3")
		)
		(pad "25_29" smd rect
			(at 1.549908 -1.279906 270)
			(size 2.0574 2.3114)
			(layers "F.Cu" "F.Mask" "F.Paste")
			(net "SW_P12V_PVCCIN_CPU1_FLT")
		)
		(pad "30" smd rect
			(at 2.05994 -2.899918)
			(size 0.2286 0.6096)
			(layers "F.Cu" "F.Mask" "F.Paste")
			(net "SW_P12V_PVCCIN_CPU1_FLT")
		)
		(pad "31" smd rect
			(at 1.610106 -2.899918)
			(size 0.2286 0.6096)
			(layers "F.Cu" "F.Mask" "F.Paste")
			(net "Net_8527")
		)
		(pad "32" smd rect
			(at 1.160018 -2.899918)
			(size 0.2286 0.6096)
			(layers "F.Cu" "F.Mask" "F.Paste")
			(net "SW_PVCCIN_CPU1_BOOTR3")
		)
		(pad "33" smd rect
			(at 0.70993 -2.899918)
			(size 0.2286 0.6096)
			(layers "F.Cu" "F.Mask" "F.Paste")
			(net "SW_PVCCIN_CPU1_BOOT3")
		)
		(pad "34" smd rect
			(at 0.260096 -2.899918)
			(size 0.2286 0.6096)
			(layers "F.Cu" "F.Mask" "F.Paste")
			(net "PVCCIN_CPU1_PWM3")
		)
		(pad "35" smd rect
			(at -0.189992 -2.899918)
			(size 0.2286 0.6096)
			(layers "F.Cu" "F.Mask" "F.Paste")
			(net "PVCCIN_CPU1_VDD3")
		)
		(pad "36" smd rect
			(at -0.64008 -2.899918)
			(size 0.2286 0.6096)
			(layers "F.Cu" "F.Mask" "F.Paste")
			(net "PVCCIN_CPU1_ATSEN")
		)
		(pad "37" smd rect
			(at -1.089914 -2.899918)
			(size 0.2286 0.6096)
			(layers "F.Cu" "F.Mask" "F.Paste")
			(net "PVCCIN_CPU1_LSET3")
		)
		(pad "38" smd rect
			(at -1.540002 -2.899918)
			(size 0.2286 0.6096)
			(layers "F.Cu" "F.Mask" "F.Paste")
			(net "PVCCIN_CPU1_IMON3")
		)
		(pad "39" smd rect
			(at -1.99009 -2.899918)
			(size 0.2286 0.6096)
			(layers "F.Cu" "F.Mask" "F.Paste")
			(net "PVCCIN_CPU1_VREF")
		)
		(pad "40" smd rect
			(at -0.87503 -1.27508)
			(size 1.7526 1.9558)
			(layers "F.Cu" "F.Mask" "F.Paste")
			(net "GND")
		)
		(pad "41" smd rect
			(at -1.525016 0.249936 270)
			(size 0.3048 0.4572)
			(layers "F.Cu" "F.Mask" "F.Paste")
			(net "Net_8525")
		)
		(zone
			(layer "F.Cu")
			(hatch none 0.5)
			(connect_pads
				(clearance 0)
			)
			(min_thickness 0.25)
			(keepout
				(tracks not_allowed)
				(vias allowed)
				(pads allowed)
				(copperpour not_allowed)
				(footprints allowed)
			)
			(placement
				(enabled no)
				(sheetname "")
			)
			(fill
				(thermal_gap 0.5)
				(thermal_bridge_width 0.5)
				(island_removal_mode 0)
			)
			(polygon
				(pts
					(xy 110.818676 -330.716128) (xy 110.818676 -331.465428) (xy 115.81892 -331.465428) (xy 115.81892 -330.716128)
					(xy 115.528598 -330.716128) (xy 115.528598 -331.171804) (xy 111.108998 -331.171804) (xy 111.108998 -330.716128)
				)
			)
		)
		(zone
			(layer "F.Cu")
			(hatch none 0.5)
			(connect_pads
				(clearance 0)
			)
			(min_thickness 0.25)
			(keepout
				(tracks not_allowed)
				(vias allowed)
				(pads allowed)
				(copperpour not_allowed)
				(footprints allowed)
			)
			(placement
				(enabled no)
				(sheetname "")
			)
			(fill
				(thermal_gap 0.5)
				(thermal_bridge_width 0.5)
				(island_removal_mode 0)
			)
			(polygon
				(pts
					(xy 111.274352 -334.040988) (xy 111.516668 -334.040988) (xy 111.516668 -333.962502) (xy 112.3061 -333.962502)
					(xy 112.3061 -333.644748) (xy 112.368076 -333.644748) (xy 112.368076 -332.966822) (xy 110.818676 -332.966822)
					(xy 110.818676 -333.423514) (xy 111.514382 -333.423514) (xy 111.514382 -333.262986) (xy 112.073182 -333.262986)
					(xy 112.073182 -333.669386) (xy 111.514382 -333.669386) (xy 111.514382 -333.448914) (xy 110.818676 -333.448914)
					(xy 110.818676 -333.575914) (xy 111.274352 -333.575914)
				)
			)
		)
	)
	(footprint ""
		(layer "F.Cu")
		(at 356.54488 -294.01008)
		(property "Reference" "C217"
			(at 0 0 0)
			(layer "F.SilkS")
			(hide yes)
			(effects
				(font
					(size 1.27 1.27)
				)
			)
		)
		(property "Value" ""
			(at 0 0 0)
			(layer "F.Fab")
			(effects
				(font
					(size 1.27 1.27)
				)
			)
		)
		(duplicate_pad_numbers_are_jumpers no)
		(fp_line
			(start -1.524 -0.762)
			(end 1.524 -0.762)
			(stroke
				(width 0.1524)
				(type default)
			)
			(layer "F.SilkS")
		)
		(fp_line
			(start -1.524 0.762)
			(end -1.524 -0.762)
			(stroke
				(width 0.1524)
				(type default)
			)
			(layer "F.SilkS")
		)
		(fp_line
			(start 1.524 -0.762)
			(end 1.524 0.762)
			(stroke
				(width 0.1524)
				(type default)
			)
			(layer "F.SilkS")
		)
		(fp_line
			(start 1.524 0.762)
			(end -1.524 0.762)
			(stroke
				(width 0.1524)
				(type default)
			)
			(layer "F.SilkS")
		)
		(fp_line
			(start -1.1049 -0.724916)
			(end -1.1049 0.724916)
			(stroke
				(width 0.1)
				(type default)
			)
			(layer "F.Fab")
		)
		(fp_line
			(start -1.1049 0.724916)
			(end 1.1049 0.724916)
			(stroke
				(width 0.1)
				(type default)
			)
			(layer "F.Fab")
		)
		(fp_line
			(start 1.1049 -0.724916)
			(end -1.1049 -0.724916)
			(stroke
				(width 0.1)
				(type default)
			)
			(layer "F.Fab")
		)
		(fp_line
			(start 1.1049 0.724916)
			(end 1.1049 -0.724916)
			(stroke
				(width 0.1)
				(type default)
			)
			(layer "F.Fab")
		)
		(pad "1" smd rect
			(at -0.889 0 180)
			(size 1.016 1.27)
			(layers "F.Cu" "F.Mask" "F.Paste")
			(net "PVCCIN_CPU0")
		)
		(pad "2" smd rect
			(at 0.889 0 180)
			(size 1.016 1.27)
			(layers "F.Cu" "F.Mask" "F.Paste")
			(net "GND")
		)
	)
	(footprint ""
		(layer "F.Cu")
		(at 76.881736 -142.587218 -90)
		(property "Reference" "R675"
			(at 0 0 270)
			(layer "F.SilkS")
			(hide yes)
			(effects
				(font
					(size 1.27 1.27)
				)
			)
		)
		(property "Value" ""
			(at 0 0 270)
			(layer "F.Fab")
			(effects
				(font
					(size 1.27 1.27)
				)
			)
		)
		(duplicate_pad_numbers_are_jumpers no)
		(fp_line
			(start -0.7874 0.4064)
			(end -0.7874 -0.4064)
			(stroke
				(width 0.1524)
				(type default)
			)
			(layer "F.SilkS")
		)
		(fp_line
			(start 0.7874 0.4064)
			(end -0.7874 0.4064)
			(stroke
				(width 0.1524)
				(type default)
			)
			(layer "F.SilkS")
		)
		(fp_line
			(start -0.7874 -0.4064)
			(end 0.7874 -0.4064)
			(stroke
				(width 0.1524)
				(type default)
			)
			(layer "F.SilkS")
		)
		(fp_line
			(start 0.7874 -0.4064)
			(end 0.7874 0.4064)
			(stroke
				(width 0.1524)
				(type default)
			)
			(layer "F.SilkS")
		)
		(fp_line
			(start -0.67945 0.3048)
			(end -0.67945 -0.305054)
			(stroke
				(width 0.1)
				(type default)
			)
			(layer "F.Fab")
		)
		(fp_line
			(start -0.12065 0.3048)
			(end -0.67945 0.3048)
			(stroke
				(width 0.1)
				(type default)
			)
			(layer "F.Fab")
		)
		(fp_line
			(start 0.120396 0.3048)
			(end 0.120396 0.2794)
			(stroke
				(width 0.1)
				(type default)
			)
			(layer "F.Fab")
		)
		(fp_line
			(start 0.67945 0.3048)
			(end 0.120396 0.3048)
			(stroke
				(width 0.1)
				(type default)
			)
			(layer "F.Fab")
		)
		(fp_line
			(start -0.12065 0.2794)
			(end -0.12065 0.3048)
			(stroke
				(width 0.1)
				(type default)
			)
			(layer "F.Fab")
		)
		(fp_line
			(start 0.120396 0.2794)
			(end -0.12065 0.2794)
			(stroke
				(width 0.1)
				(type default)
			)
			(layer "F.Fab")
		)
		(fp_line
			(start -0.12065 -0.2794)
			(end 0.12065 -0.2794)
			(stroke
				(width 0.1)
				(type default)
			)
			(layer "F.Fab")
		)
		(fp_line
			(start 0.12065 -0.2794)
			(end 0.12065 -0.3048)
			(stroke
				(width 0.1)
				(type default)
			)
			(layer "F.Fab")
		)
		(fp_line
			(start 0.12065 -0.3048)
			(end 0.67945 -0.3048)
			(stroke
				(width 0.1)
				(type default)
			)
			(layer "F.Fab")
		)
		(fp_line
			(start 0.67945 -0.3048)
			(end 0.67945 0.3048)
			(stroke
				(width 0.1)
				(type default)
			)
			(layer "F.Fab")
		)
		(fp_line
			(start -0.67945 -0.305054)
			(end -0.12065 -0.305054)
			(stroke
				(width 0.1)
				(type default)
			)
			(layer "F.Fab")
		)
		(fp_line
			(start -0.12065 -0.305054)
			(end -0.12065 -0.2794)
			(stroke
				(width 0.1)
				(type default)
			)
			(layer "F.Fab")
		)
		(pad "1" smd circle
			(at -0.40005 0 270)
			(size 0 0)
			(layers "F.Cu" "F.Mask" "F.Paste")
			(net "I3C_SPD_DDRABCD_CPU1_LVC1_R_SDA")
		)
		(pad "2" smd circle
			(at 0.40005 0 270)
			(size 0 0)
			(layers "F.Cu" "F.Mask" "F.Paste")
			(net "I3C_SPD_DDRABCD_CPU1_LVC1_SDA")
		)
	)
	(footprint ""
		(layer "F.Cu")
		(at 348.961964 -66.074544)
		(property "Reference" "C145"
			(at 0 0 0)
			(layer "F.SilkS")
			(hide yes)
			(effects
				(font
					(size 1.27 1.27)
				)
			)
		)
		(property "Value" ""
			(at 0 0 0)
			(layer "F.Fab")
			(effects
				(font
					(size 1.27 1.27)
				)
			)
		)
		(duplicate_pad_numbers_are_jumpers no)
		(fp_line
			(start -0.299974 -0.150114)
			(end 0.299974 -0.150114)
			(stroke
				(width 0.1)
				(type default)
			)
			(layer "F.Fab")
		)
		(fp_line
			(start -0.299974 0.150114)
			(end -0.299974 -0.150114)
			(stroke
				(width 0.1)
				(type default)
			)
			(layer "F.Fab")
		)
		(fp_line
			(start 0.299974 -0.150114)
			(end 0.299974 0.150114)
			(stroke
				(width 0.1)
				(type default)
			)
			(layer "F.Fab")
		)
		(fp_line
			(start 0.299974 0.150114)
			(end -0.299974 0.150114)
			(stroke
				(width 0.1)
				(type default)
			)
			(layer "F.Fab")
		)
		(pad "1" smd rect
			(at -0.2667 0)
			(size 0.3048 0.381)
			(layers "F.Cu" "F.Mask" "F.Paste")
			(net "DMI_CPU0_PCH_TX_C_DN<4>")
		)
		(pad "2" smd rect
			(at 0.2667 0)
			(size 0.3048 0.381)
			(layers "F.Cu" "F.Mask" "F.Paste")
			(net "DMI_CPU0_PCH_TX_DN<4>")
		)
		(zone
			(layer "In1.Cu")
			(hatch none 0.5)
			(connect_pads
				(clearance 0)
			)
			(min_thickness 0.25)
			(keepout
				(tracks not_allowed)
				(vias allowed)
				(pads allowed)
				(copperpour not_allowed)
				(footprints allowed)
			)
			(placement
				(enabled no)
				(sheetname "")
			)
			(fill
				(thermal_gap 0.5)
				(thermal_bridge_width 0.5)
				(island_removal_mode 0)
			)
			(polygon
				(pts
					(arc
						(start 348.568264 -65.833244)
						(mid 348.514382 -65.855562)
						(end 348.492064 -65.909444)
					)
					(arc
						(start 348.492064 -66.239644)
						(mid 348.514382 -66.293526)
						(end 348.568264 -66.315844)
					)
					(arc
						(start 348.822264 -66.315844)
						(mid 348.876146 -66.293526)
						(end 348.898464 -66.239644)
					)
					(arc
						(start 348.898464 -65.909444)
						(mid 348.876146 -65.855562)
						(end 348.822264 -65.833244)
					)
				)
			)
		)
		(zone
			(layer "In1.Cu")
			(hatch none 0.5)
			(connect_pads
				(clearance 0)
			)
			(min_thickness 0.25)
			(keepout
				(tracks not_allowed)
				(vias allowed)
				(pads allowed)
				(copperpour not_allowed)
				(footprints allowed)
			)
			(placement
				(enabled no)
				(sheetname "")
			)
			(fill
				(thermal_gap 0.5)
				(thermal_bridge_width 0.5)
				(island_removal_mode 0)
			)
			(polygon
				(pts
					(arc
						(start 349.101664 -65.833244)
						(mid 349.047782 -65.855562)
						(end 349.025464 -65.909444)
					)
					(arc
						(start 349.025464 -66.239644)
						(mid 349.047782 -66.293526)
						(end 349.101664 -66.315844)
					)
					(arc
						(start 349.355664 -66.315844)
						(mid 349.409546 -66.293526)
						(end 349.431864 -66.239644)
					)
					(arc
						(start 349.431864 -65.909444)
						(mid 349.409546 -65.855562)
						(end 349.355664 -65.833244)
					)
				)
			)
		)
	)
	(footprint ""
		(layer "F.Cu")
		(at 119.508016 -252.956568 -90)
		(property "Reference" "C238"
			(at 0 0 270)
			(layer "F.SilkS")
			(hide yes)
			(effects
				(font
					(size 1.27 1.27)
				)
			)
		)
		(property "Value" ""
			(at 0 0 270)
			(layer "F.Fab")
			(effects
				(font
					(size 1.27 1.27)
				)
			)
		)
		(duplicate_pad_numbers_are_jumpers no)
		(fp_line
			(start -0.7874 0.4064)
			(end -0.7874 -0.4064)
			(stroke
				(width 0.1524)
				(type default)
			)
			(layer "F.SilkS")
		)
		(fp_line
			(start 0.7874 0.4064)
			(end -0.7874 0.4064)
			(stroke
				(width 0.1524)
				(type default)
			)
			(layer "F.SilkS")
		)
		(fp_line
			(start -0.7874 -0.4064)
			(end 0.7874 -0.4064)
			(stroke
				(width 0.1524)
				(type default)
			)
			(layer "F.SilkS")
		)
		(fp_line
			(start 0.7874 -0.4064)
			(end 0.7874 0.4064)
			(stroke
				(width 0.1524)
				(type default)
			)
			(layer "F.SilkS")
		)
		(fp_line
			(start -0.67945 0.3048)
			(end -0.67945 -0.305054)
			(stroke
				(width 0.1)
				(type default)
			)
			(layer "F.Fab")
		)
		(fp_line
			(start -0.12065 0.3048)
			(end -0.67945 0.3048)
			(stroke
				(width 0.1)
				(type default)
			)
			(layer "F.Fab")
		)
		(fp_line
			(start 0.120396 0.3048)
			(end 0.120396 0.2794)
			(stroke
				(width 0.1)
				(type default)
			)
			(layer "F.Fab")
		)
		(fp_line
			(start 0.67945 0.3048)
			(end 0.120396 0.3048)
			(stroke
				(width 0.1)
				(type default)
			)
			(layer "F.Fab")
		)
		(fp_line
			(start -0.12065 0.2794)
			(end -0.12065 0.3048)
			(stroke
				(width 0.1)
				(type default)
			)
			(layer "F.Fab")
		)
		(fp_line
			(start 0.120396 0.2794)
			(end -0.12065 0.2794)
			(stroke
				(width 0.1)
				(type default)
			)
			(layer "F.Fab")
		)
		(fp_line
			(start -0.12065 -0.2794)
			(end 0.12065 -0.2794)
			(stroke
				(width 0.1)
				(type default)
			)
			(layer "F.Fab")
		)
		(fp_line
			(start 0.12065 -0.2794)
			(end 0.12065 -0.3048)
			(stroke
				(width 0.1)
				(type default)
			)
			(layer "F.Fab")
		)
		(fp_line
			(start 0.12065 -0.3048)
			(end 0.67945 -0.3048)
			(stroke
				(width 0.1)
				(type default)
			)
			(layer "F.Fab")
		)
		(fp_line
			(start 0.67945 -0.3048)
			(end 0.67945 0.3048)
			(stroke
				(width 0.1)
				(type default)
			)
			(layer "F.Fab")
		)
		(fp_line
			(start -0.67945 -0.305054)
			(end -0.12065 -0.305054)
			(stroke
				(width 0.1)
				(type default)
			)
			(layer "F.Fab")
		)
		(fp_line
			(start -0.12065 -0.305054)
			(end -0.12065 -0.2794)
			(stroke
				(width 0.1)
				(type default)
			)
			(layer "F.Fab")
		)
		(pad "1" smd circle
			(at -0.40005 0 270)
			(size 0 0)
			(layers "F.Cu" "F.Mask" "F.Paste")
			(net "PVCCIN_CPU1")
		)
		(pad "2" smd circle
			(at 0.40005 0 270)
			(size 0 0)
			(layers "F.Cu" "F.Mask" "F.Paste")
			(net "GND")
		)
	)
	(footprint ""
		(layer "F.Cu")
		(at 63.270638 -402.371052 -90)
		(property "Reference" "C720"
			(at 0 0 270)
			(layer "F.SilkS")
			(hide yes)
			(effects
				(font
					(size 1.27 1.27)
				)
			)
		)
		(property "Value" ""
			(at 0 0 270)
			(layer "F.Fab")
			(effects
				(font
					(size 1.27 1.27)
				)
			)
		)
		(duplicate_pad_numbers_are_jumpers no)
		(fp_line
			(start -0.299974 0.150114)
			(end -0.299974 -0.150114)
			(stroke
				(width 0.1)
				(type default)
			)
			(layer "F.Fab")
		)
		(fp_line
			(start 0.299974 0.150114)
			(end -0.299974 0.150114)
			(stroke
				(width 0.1)
				(type default)
			)
			(layer "F.Fab")
		)
		(fp_line
			(start -0.299974 -0.150114)
			(end 0.299974 -0.150114)
			(stroke
				(width 0.1)
				(type default)
			)
			(layer "F.Fab")
		)
		(fp_line
			(start 0.299974 -0.150114)
			(end 0.299974 0.150114)
			(stroke
				(width 0.1)
				(type default)
			)
			(layer "F.Fab")
		)
		(pad "1" smd rect
			(at -0.2667 0 270)
			(size 0.3048 0.381)
			(layers "F.Cu" "F.Mask" "F.Paste")
			(net "P5E_CPU1_PE0_TX_C_DN<10>")
		)
		(pad "2" smd rect
			(at 0.2667 0 270)
			(size 0.3048 0.381)
			(layers "F.Cu" "F.Mask" "F.Paste")
			(net "P5E_CPU1_PE0_TX_DN<10>")
		)
	)
	(footprint ""
		(layer "F.Cu")
		(at 292.79088 -46.954948 90)
		(property "Reference" "R4063"
			(at 0 0 90)
			(layer "F.SilkS")
			(hide yes)
			(effects
				(font
					(size 1.27 1.27)
				)
			)
		)
		(property "Value" ""
			(at 0 0 90)
			(layer "F.Fab")
			(effects
				(font
					(size 1.27 1.27)
				)
			)
		)
		(duplicate_pad_numbers_are_jumpers no)
		(fp_line
			(start 0.7874 -0.4064)
			(end 0.7874 0.4064)
			(stroke
				(width 0.1524)
				(type default)
			)
			(layer "F.SilkS")
		)
		(fp_line
			(start -0.7874 -0.4064)
			(end 0.7874 -0.4064)
			(stroke
				(width 0.1524)
				(type default)
			)
			(layer "F.SilkS")
		)
		(fp_line
			(start 0.7874 0.4064)
			(end -0.7874 0.4064)
			(stroke
				(width 0.1524)
				(type default)
			)
			(layer "F.SilkS")
		)
		(fp_line
			(start -0.7874 0.4064)
			(end -0.7874 -0.4064)
			(stroke
				(width 0.1524)
				(type default)
			)
			(layer "F.SilkS")
		)
		(fp_line
			(start -0.12065 -0.305054)
			(end -0.12065 -0.2794)
			(stroke
				(width 0.1)
				(type default)
			)
			(layer "F.Fab")
		)
		(fp_line
			(start -0.67945 -0.305054)
			(end -0.12065 -0.305054)
			(stroke
				(width 0.1)
				(type default)
			)
			(layer "F.Fab")
		)
		(fp_line
			(start 0.67945 -0.3048)
			(end 0.67945 0.3048)
			(stroke
				(width 0.1)
				(type default)
			)
			(layer "F.Fab")
		)
		(fp_line
			(start 0.12065 -0.3048)
			(end 0.67945 -0.3048)
			(stroke
				(width 0.1)
				(type default)
			)
			(layer "F.Fab")
		)
		(fp_line
			(start 0.12065 -0.2794)
			(end 0.12065 -0.3048)
			(stroke
				(width 0.1)
				(type default)
			)
			(layer "F.Fab")
		)
		(fp_line
			(start -0.12065 -0.2794)
			(end 0.12065 -0.2794)
			(stroke
				(width 0.1)
				(type default)
			)
			(layer "F.Fab")
		)
		(fp_line
			(start 0.120396 0.2794)
			(end -0.12065 0.2794)
			(stroke
				(width 0.1)
				(type default)
			)
			(layer "F.Fab")
		)
		(fp_line
			(start -0.12065 0.2794)
			(end -0.12065 0.3048)
			(stroke
				(width 0.1)
				(type default)
			)
			(layer "F.Fab")
		)
		(fp_line
			(start 0.67945 0.3048)
			(end 0.120396 0.3048)
			(stroke
				(width 0.1)
				(type default)
			)
			(layer "F.Fab")
		)
		(fp_line
			(start 0.120396 0.3048)
			(end 0.120396 0.2794)
			(stroke
				(width 0.1)
				(type default)
			)
			(layer "F.Fab")
		)
		(fp_line
			(start -0.12065 0.3048)
			(end -0.67945 0.3048)
			(stroke
				(width 0.1)
				(type default)
			)
			(layer "F.Fab")
		)
		(fp_line
			(start -0.67945 0.3048)
			(end -0.67945 -0.305054)
			(stroke
				(width 0.1)
				(type default)
			)
			(layer "F.Fab")
		)
		(pad "1" smd circle
			(at -0.40005 0 90)
			(size 0 0)
			(layers "F.Cu" "F.Mask" "F.Paste")
			(net "E1S_0_EN")
		)
		(pad "2" smd circle
			(at 0.40005 0 90)
			(size 0 0)
			(layers "F.Cu" "F.Mask" "F.Paste")
			(net "P3V3_E1S_EN_1_R")
		)
	)
	(footprint ""
		(layer "F.Cu")
		(at 116.159534 -38.065456)
		(property "Reference" "R3322"
			(at 0 0 0)
			(layer "F.SilkS")
			(hide yes)
			(effects
				(font
					(size 1.27 1.27)
				)
			)
		)
		(property "Value" ""
			(at 0 0 0)
			(layer "F.Fab")
			(effects
				(font
					(size 1.27 1.27)
				)
			)
		)
		(duplicate_pad_numbers_are_jumpers no)
		(fp_line
			(start -0.7874 -0.4064)
			(end 0.7874 -0.4064)
			(stroke
				(width 0.1524)
				(type default)
			)
			(layer "F.SilkS")
		)
		(fp_line
			(start -0.7874 0.4064)
			(end -0.7874 -0.4064)
			(stroke
				(width 0.1524)
				(type default)
			)
			(layer "F.SilkS")
		)
		(fp_line
			(start 0.7874 -0.4064)
			(end 0.7874 0.4064)
			(stroke
				(width 0.1524)
				(type default)
			)
			(layer "F.SilkS")
		)
		(fp_line
			(start 0.7874 0.4064)
			(end -0.7874 0.4064)
			(stroke
				(width 0.1524)
				(type default)
			)
			(layer "F.SilkS")
		)
		(fp_line
			(start -0.67945 -0.305054)
			(end -0.12065 -0.305054)
			(stroke
				(width 0.1)
				(type default)
			)
			(layer "F.Fab")
		)
		(fp_line
			(start -0.67945 0.3048)
			(end -0.67945 -0.305054)
			(stroke
				(width 0.1)
				(type default)
			)
			(layer "F.Fab")
		)
		(fp_line
			(start -0.12065 -0.305054)
			(end -0.12065 -0.2794)
			(stroke
				(width 0.1)
				(type default)
			)
			(layer "F.Fab")
		)
		(fp_line
			(start -0.12065 -0.2794)
			(end 0.12065 -0.2794)
			(stroke
				(width 0.1)
				(type default)
			)
			(layer "F.Fab")
		)
		(fp_line
			(start -0.12065 0.2794)
			(end -0.12065 0.3048)
			(stroke
				(width 0.1)
				(type default)
			)
			(layer "F.Fab")
		)
		(fp_line
			(start -0.12065 0.3048)
			(end -0.67945 0.3048)
			(stroke
				(width 0.1)
				(type default)
			)
			(layer "F.Fab")
		)
		(fp_line
			(start 0.120396 0.2794)
			(end -0.12065 0.2794)
			(stroke
				(width 0.1)
				(type default)
			)
			(layer "F.Fab")
		)
		(fp_line
			(start 0.120396 0.3048)
			(end 0.120396 0.2794)
			(stroke
				(width 0.1)
				(type default)
			)
			(layer "F.Fab")
		)
		(fp_line
			(start 0.12065 -0.3048)
			(end 0.67945 -0.3048)
			(stroke
				(width 0.1)
				(type default)
			)
			(layer "F.Fab")
		)
		(fp_line
			(start 0.12065 -0.2794)
			(end 0.12065 -0.3048)
			(stroke
				(width 0.1)
				(type default)
			)
			(layer "F.Fab")
		)
		(fp_line
			(start 0.67945 -0.3048)
			(end 0.67945 0.3048)
			(stroke
				(width 0.1)
				(type default)
			)
			(layer "F.Fab")
		)
		(fp_line
			(start 0.67945 0.3048)
			(end 0.120396 0.3048)
			(stroke
				(width 0.1)
				(type default)
			)
			(layer "F.Fab")
		)
		(pad "1" smd circle
			(at -0.40005 0)
			(size 0 0)
			(layers "F.Cu" "F.Mask" "F.Paste")
			(net "P3V3_AUX")
		)
		(pad "2" smd circle
			(at 0.40005 0)
			(size 0 0)
			(layers "F.Cu" "F.Mask" "F.Paste")
			(net "CLK_GEN2_GPU_FPGA_OE_R2_N")
		)
	)
	(footprint ""
		(layer "F.Cu")
		(at 422.478962 -139.797028)
		(property "Reference" "PC216"
			(at 0 0 0)
			(layer "F.SilkS")
			(hide yes)
			(effects
				(font
					(size 1.27 1.27)
				)
			)
		)
		(property "Value" ""
			(at 0 0 0)
			(layer "F.Fab")
			(effects
				(font
					(size 1.27 1.27)
				)
			)
		)
		(duplicate_pad_numbers_are_jumpers no)
		(fp_line
			(start -0.7874 -0.4064)
			(end 0.7874 -0.4064)
			(stroke
				(width 0.1524)
				(type default)
			)
			(layer "F.SilkS")
		)
		(fp_line
			(start -0.7874 0.4064)
			(end -0.7874 -0.4064)
			(stroke
				(width 0.1524)
				(type default)
			)
			(layer "F.SilkS")
		)
		(fp_line
			(start 0.7874 -0.4064)
			(end 0.7874 0.4064)
			(stroke
				(width 0.1524)
				(type default)
			)
			(layer "F.SilkS")
		)
		(fp_line
			(start 0.7874 0.4064)
			(end -0.7874 0.4064)
			(stroke
				(width 0.1524)
				(type default)
			)
			(layer "F.SilkS")
		)
		(fp_line
			(start -0.67945 -0.305054)
			(end -0.12065 -0.305054)
			(stroke
				(width 0.1)
				(type default)
			)
			(layer "F.Fab")
		)
		(fp_line
			(start -0.67945 0.3048)
			(end -0.67945 -0.305054)
			(stroke
				(width 0.1)
				(type default)
			)
			(layer "F.Fab")
		)
		(fp_line
			(start -0.12065 -0.305054)
			(end -0.12065 -0.2794)
			(stroke
				(width 0.1)
				(type default)
			)
			(layer "F.Fab")
		)
		(fp_line
			(start -0.12065 -0.2794)
			(end 0.12065 -0.2794)
			(stroke
				(width 0.1)
				(type default)
			)
			(layer "F.Fab")
		)
		(fp_line
			(start -0.12065 0.2794)
			(end -0.12065 0.3048)
			(stroke
				(width 0.1)
				(type default)
			)
			(layer "F.Fab")
		)
		(fp_line
			(start -0.12065 0.3048)
			(end -0.67945 0.3048)
			(stroke
				(width 0.1)
				(type default)
			)
			(layer "F.Fab")
		)
		(fp_line
			(start 0.120396 0.2794)
			(end -0.12065 0.2794)
			(stroke
				(width 0.1)
				(type default)
			)
			(layer "F.Fab")
		)
		(fp_line
			(start 0.120396 0.3048)
			(end 0.120396 0.2794)
			(stroke
				(width 0.1)
				(type default)
			)
			(layer "F.Fab")
		)
		(fp_line
			(start 0.12065 -0.3048)
			(end 0.67945 -0.3048)
			(stroke
				(width 0.1)
				(type default)
			)
			(layer "F.Fab")
		)
		(fp_line
			(start 0.12065 -0.2794)
			(end 0.12065 -0.3048)
			(stroke
				(width 0.1)
				(type default)
			)
			(layer "F.Fab")
		)
		(fp_line
			(start 0.67945 -0.3048)
			(end 0.67945 0.3048)
			(stroke
				(width 0.1)
				(type default)
			)
			(layer "F.Fab")
		)
		(fp_line
			(start 0.67945 0.3048)
			(end 0.120396 0.3048)
			(stroke
				(width 0.1)
				(type default)
			)
			(layer "F.Fab")
		)
		(pad "1" smd circle
			(at -0.40005 0)
			(size 0 0)
			(layers "F.Cu" "F.Mask" "F.Paste")
			(net "SH_PVCCFA_EHV_CPU0_R")
		)
		(pad "2" smd circle
			(at 0.40005 0)
			(size 0 0)
			(layers "F.Cu" "F.Mask" "F.Paste")
			(net "VSENSE_PVCCFA_EHV_CPU0_DN")
		)
	)
	(footprint ""
		(layer "F.Cu")
		(at 281.758898 -424.54576 -90)
		(property "Reference" "R4669"
			(at 0 0 270)
			(layer "F.SilkS")
			(hide yes)
			(effects
				(font
					(size 1.27 1.27)
				)
			)
		)
		(property "Value" ""
			(at 0 0 270)
			(layer "F.Fab")
			(effects
				(font
					(size 1.27 1.27)
				)
			)
		)
		(duplicate_pad_numbers_are_jumpers no)
		(fp_line
			(start -0.7874 0.4064)
			(end -0.7874 -0.4064)
			(stroke
				(width 0.1524)
				(type default)
			)
			(layer "F.SilkS")
		)
		(fp_line
			(start 0.7874 0.4064)
			(end -0.7874 0.4064)
			(stroke
				(width 0.1524)
				(type default)
			)
			(layer "F.SilkS")
		)
		(fp_line
			(start -0.7874 -0.4064)
			(end 0.7874 -0.4064)
			(stroke
				(width 0.1524)
				(type default)
			)
			(layer "F.SilkS")
		)
		(fp_line
			(start 0.7874 -0.4064)
			(end 0.7874 0.4064)
			(stroke
				(width 0.1524)
				(type default)
			)
			(layer "F.SilkS")
		)
		(fp_line
			(start -0.67945 0.3048)
			(end -0.67945 -0.305054)
			(stroke
				(width 0.1)
				(type default)
			)
			(layer "F.Fab")
		)
		(fp_line
			(start -0.12065 0.3048)
			(end -0.67945 0.3048)
			(stroke
				(width 0.1)
				(type default)
			)
			(layer "F.Fab")
		)
		(fp_line
			(start 0.120396 0.3048)
			(end 0.120396 0.2794)
			(stroke
				(width 0.1)
				(type default)
			)
			(layer "F.Fab")
		)
		(fp_line
			(start 0.67945 0.3048)
			(end 0.120396 0.3048)
			(stroke
				(width 0.1)
				(type default)
			)
			(layer "F.Fab")
		)
		(fp_line
			(start -0.12065 0.2794)
			(end -0.12065 0.3048)
			(stroke
				(width 0.1)
				(type default)
			)
			(layer "F.Fab")
		)
		(fp_line
			(start 0.120396 0.2794)
			(end -0.12065 0.2794)
			(stroke
				(width 0.1)
				(type default)
			)
			(layer "F.Fab")
		)
		(fp_line
			(start -0.12065 -0.2794)
			(end 0.12065 -0.2794)
			(stroke
				(width 0.1)
				(type default)
			)
			(layer "F.Fab")
		)
		(fp_line
			(start 0.12065 -0.2794)
			(end 0.12065 -0.3048)
			(stroke
				(width 0.1)
				(type default)
			)
			(layer "F.Fab")
		)
		(fp_line
			(start 0.12065 -0.3048)
			(end 0.67945 -0.3048)
			(stroke
				(width 0.1)
				(type default)
			)
			(layer "F.Fab")
		)
		(fp_line
			(start 0.67945 -0.3048)
			(end 0.67945 0.3048)
			(stroke
				(width 0.1)
				(type default)
			)
			(layer "F.Fab")
		)
		(fp_line
			(start -0.67945 -0.305054)
			(end -0.12065 -0.305054)
			(stroke
				(width 0.1)
				(type default)
			)
			(layer "F.Fab")
		)
		(fp_line
			(start -0.12065 -0.305054)
			(end -0.12065 -0.2794)
			(stroke
				(width 0.1)
				(type default)
			)
			(layer "F.Fab")
		)
		(pad "1" smd circle
			(at -0.40005 0 270)
			(size 0 0)
			(layers "F.Cu" "F.Mask" "F.Paste")
			(net "HSC_CSOUT")
		)
		(pad "2" smd circle
			(at 0.40005 0 270)
			(size 0 0)
			(layers "F.Cu" "F.Mask" "F.Paste")
			(net "A_HSC_HIGH")
		)
	)
	(footprint ""
		(layer "F.Cu")
		(at 373.65813 -408.517344 -90)
		(property "Reference" "C871"
			(at 0 0 270)
			(layer "F.SilkS")
			(hide yes)
			(effects
				(font
					(size 1.27 1.27)
				)
			)
		)
		(property "Value" ""
			(at 0 0 270)
			(layer "F.Fab")
			(effects
				(font
					(size 1.27 1.27)
				)
			)
		)
		(duplicate_pad_numbers_are_jumpers no)
		(fp_line
			(start -0.299974 0.150114)
			(end -0.299974 -0.150114)
			(stroke
				(width 0.1)
				(type default)
			)
			(layer "F.Fab")
		)
		(fp_line
			(start 0.299974 0.150114)
			(end -0.299974 0.150114)
			(stroke
				(width 0.1)
				(type default)
			)
			(layer "F.Fab")
		)
		(fp_line
			(start -0.299974 -0.150114)
			(end 0.299974 -0.150114)
			(stroke
				(width 0.1)
				(type default)
			)
			(layer "F.Fab")
		)
		(fp_line
			(start 0.299974 -0.150114)
			(end 0.299974 0.150114)
			(stroke
				(width 0.1)
				(type default)
			)
			(layer "F.Fab")
		)
		(pad "1" smd rect
			(at -0.2667 0 270)
			(size 0.3048 0.381)
			(layers "F.Cu" "F.Mask" "F.Paste")
			(net "P5E_CPU0_PE3_TX_C_DP<15>")
		)
		(pad "2" smd rect
			(at 0.2667 0 270)
			(size 0.3048 0.381)
			(layers "F.Cu" "F.Mask" "F.Paste")
			(net "P5E_CPU0_PE3_TX_DP<15>")
		)
	)
	(footprint ""
		(layer "F.Cu")
		(at 123.994926 -119.810784 -90)
		(property "Reference" "R4037"
			(at 0 0 270)
			(layer "F.SilkS")
			(hide yes)
			(effects
				(font
					(size 1.27 1.27)
				)
			)
		)
		(property "Value" ""
			(at 0 0 270)
			(layer "F.Fab")
			(effects
				(font
					(size 1.27 1.27)
				)
			)
		)
		(duplicate_pad_numbers_are_jumpers no)
		(fp_line
			(start -0.7874 0.4064)
			(end -0.7874 -0.4064)
			(stroke
				(width 0.1524)
				(type default)
			)
			(layer "F.SilkS")
		)
		(fp_line
			(start 0.7874 0.4064)
			(end -0.7874 0.4064)
			(stroke
				(width 0.1524)
				(type default)
			)
			(layer "F.SilkS")
		)
		(fp_line
			(start -0.7874 -0.4064)
			(end 0.7874 -0.4064)
			(stroke
				(width 0.1524)
				(type default)
			)
			(layer "F.SilkS")
		)
		(fp_line
			(start 0.7874 -0.4064)
			(end 0.7874 0.4064)
			(stroke
				(width 0.1524)
				(type default)
			)
			(layer "F.SilkS")
		)
		(fp_line
			(start -0.67945 0.3048)
			(end -0.67945 -0.305054)
			(stroke
				(width 0.1)
				(type default)
			)
			(layer "F.Fab")
		)
		(fp_line
			(start -0.12065 0.3048)
			(end -0.67945 0.3048)
			(stroke
				(width 0.1)
				(type default)
			)
			(layer "F.Fab")
		)
		(fp_line
			(start 0.120396 0.3048)
			(end 0.120396 0.2794)
			(stroke
				(width 0.1)
				(type default)
			)
			(layer "F.Fab")
		)
		(fp_line
			(start 0.67945 0.3048)
			(end 0.120396 0.3048)
			(stroke
				(width 0.1)
				(type default)
			)
			(layer "F.Fab")
		)
		(fp_line
			(start -0.12065 0.2794)
			(end -0.12065 0.3048)
			(stroke
				(width 0.1)
				(type default)
			)
			(layer "F.Fab")
		)
		(fp_line
			(start 0.120396 0.2794)
			(end -0.12065 0.2794)
			(stroke
				(width 0.1)
				(type default)
			)
			(layer "F.Fab")
		)
		(fp_line
			(start -0.12065 -0.2794)
			(end 0.12065 -0.2794)
			(stroke
				(width 0.1)
				(type default)
			)
			(layer "F.Fab")
		)
		(fp_line
			(start 0.12065 -0.2794)
			(end 0.12065 -0.3048)
			(stroke
				(width 0.1)
				(type default)
			)
			(layer "F.Fab")
		)
		(fp_line
			(start 0.12065 -0.3048)
			(end 0.67945 -0.3048)
			(stroke
				(width 0.1)
				(type default)
			)
			(layer "F.Fab")
		)
		(fp_line
			(start 0.67945 -0.3048)
			(end 0.67945 0.3048)
			(stroke
				(width 0.1)
				(type default)
			)
			(layer "F.Fab")
		)
		(fp_line
			(start -0.67945 -0.305054)
			(end -0.12065 -0.305054)
			(stroke
				(width 0.1)
				(type default)
			)
			(layer "F.Fab")
		)
		(fp_line
			(start -0.12065 -0.305054)
			(end -0.12065 -0.2794)
			(stroke
				(width 0.1)
				(type default)
			)
			(layer "F.Fab")
		)
		(pad "1" smd circle
			(at -0.40005 0 270)
			(size 0 0)
			(layers "F.Cu" "F.Mask" "F.Paste")
			(net "P3V3_AUX")
		)
		(pad "2" smd circle
			(at 0.40005 0 270)
			(size 0 0)
			(layers "F.Cu" "F.Mask" "F.Paste")
			(net "P0V62_CPU1_RST_DDR_VREF")
		)
	)
	(footprint ""
		(layer "F.Cu")
		(at 362.89488 -294.01008)
		(property "Reference" "C101"
			(at 0 0 0)
			(layer "F.SilkS")
			(hide yes)
			(effects
				(font
					(size 1.27 1.27)
				)
			)
		)
		(property "Value" ""
			(at 0 0 0)
			(layer "F.Fab")
			(effects
				(font
					(size 1.27 1.27)
				)
			)
		)
		(duplicate_pad_numbers_are_jumpers no)
		(fp_line
			(start -1.524 -0.762)
			(end 1.524 -0.762)
			(stroke
				(width 0.1524)
				(type default)
			)
			(layer "F.SilkS")
		)
		(fp_line
			(start -1.524 0.762)
			(end -1.524 -0.762)
			(stroke
				(width 0.1524)
				(type default)
			)
			(layer "F.SilkS")
		)
		(fp_line
			(start 1.524 -0.762)
			(end 1.524 0.762)
			(stroke
				(width 0.1524)
				(type default)
			)
			(layer "F.SilkS")
		)
		(fp_line
			(start 1.524 0.762)
			(end -1.524 0.762)
			(stroke
				(width 0.1524)
				(type default)
			)
			(layer "F.SilkS")
		)
		(fp_line
			(start -1.1049 -0.724916)
			(end -1.1049 0.724916)
			(stroke
				(width 0.1)
				(type default)
			)
			(layer "F.Fab")
		)
		(fp_line
			(start -1.1049 0.724916)
			(end 1.1049 0.724916)
			(stroke
				(width 0.1)
				(type default)
			)
			(layer "F.Fab")
		)
		(fp_line
			(start 1.1049 -0.724916)
			(end -1.1049 -0.724916)
			(stroke
				(width 0.1)
				(type default)
			)
			(layer "F.Fab")
		)
		(fp_line
			(start 1.1049 0.724916)
			(end 1.1049 -0.724916)
			(stroke
				(width 0.1)
				(type default)
			)
			(layer "F.Fab")
		)
		(pad "1" smd rect
			(at -0.889 0 180)
			(size 1.016 1.27)
			(layers "F.Cu" "F.Mask" "F.Paste")
			(net "PVCCIN_CPU0")
		)
		(pad "2" smd rect
			(at 0.889 0 180)
			(size 1.016 1.27)
			(layers "F.Cu" "F.Mask" "F.Paste")
			(net "GND")
		)
	)
	(footprint ""
		(layer "F.Cu")
		(at 244.128798 -50.126646 90)
		(property "Reference" "C1278"
			(at 0 0 90)
			(layer "F.SilkS")
			(hide yes)
			(effects
				(font
					(size 1.27 1.27)
				)
			)
		)
		(property "Value" ""
			(at 0 0 90)
			(layer "F.Fab")
			(effects
				(font
					(size 1.27 1.27)
				)
			)
		)
		(duplicate_pad_numbers_are_jumpers no)
		(fp_line
			(start 0.7874 -0.4064)
			(end 0.7874 0.4064)
			(stroke
				(width 0.1524)
				(type default)
			)
			(layer "F.SilkS")
		)
		(fp_line
			(start -0.7874 -0.4064)
			(end 0.7874 -0.4064)
			(stroke
				(width 0.1524)
				(type default)
			)
			(layer "F.SilkS")
		)
		(fp_line
			(start 0.7874 0.4064)
			(end -0.7874 0.4064)
			(stroke
				(width 0.1524)
				(type default)
			)
			(layer "F.SilkS")
		)
		(fp_line
			(start -0.7874 0.4064)
			(end -0.7874 -0.4064)
			(stroke
				(width 0.1524)
				(type default)
			)
			(layer "F.SilkS")
		)
		(fp_line
			(start -0.12065 -0.305054)
			(end -0.12065 -0.2794)
			(stroke
				(width 0.1)
				(type default)
			)
			(layer "F.Fab")
		)
		(fp_line
			(start -0.67945 -0.305054)
			(end -0.12065 -0.305054)
			(stroke
				(width 0.1)
				(type default)
			)
			(layer "F.Fab")
		)
		(fp_line
			(start 0.67945 -0.3048)
			(end 0.67945 0.3048)
			(stroke
				(width 0.1)
				(type default)
			)
			(layer "F.Fab")
		)
		(fp_line
			(start 0.12065 -0.3048)
			(end 0.67945 -0.3048)
			(stroke
				(width 0.1)
				(type default)
			)
			(layer "F.Fab")
		)
		(fp_line
			(start 0.12065 -0.2794)
			(end 0.12065 -0.3048)
			(stroke
				(width 0.1)
				(type default)
			)
			(layer "F.Fab")
		)
		(fp_line
			(start -0.12065 -0.2794)
			(end 0.12065 -0.2794)
			(stroke
				(width 0.1)
				(type default)
			)
			(layer "F.Fab")
		)
		(fp_line
			(start 0.120396 0.2794)
			(end -0.12065 0.2794)
			(stroke
				(width 0.1)
				(type default)
			)
			(layer "F.Fab")
		)
		(fp_line
			(start -0.12065 0.2794)
			(end -0.12065 0.3048)
			(stroke
				(width 0.1)
				(type default)
			)
			(layer "F.Fab")
		)
		(fp_line
			(start 0.67945 0.3048)
			(end 0.120396 0.3048)
			(stroke
				(width 0.1)
				(type default)
			)
			(layer "F.Fab")
		)
		(fp_line
			(start 0.120396 0.3048)
			(end 0.120396 0.2794)
			(stroke
				(width 0.1)
				(type default)
			)
			(layer "F.Fab")
		)
		(fp_line
			(start -0.12065 0.3048)
			(end -0.67945 0.3048)
			(stroke
				(width 0.1)
				(type default)
			)
			(layer "F.Fab")
		)
		(fp_line
			(start -0.67945 0.3048)
			(end -0.67945 -0.305054)
			(stroke
				(width 0.1)
				(type default)
			)
			(layer "F.Fab")
		)
		(pad "1" smd circle
			(at -0.40005 0 90)
			(size 0 0)
			(layers "F.Cu" "F.Mask" "F.Paste")
			(net "P12V_E1S_0")
		)
		(pad "2" smd circle
			(at 0.40005 0 90)
			(size 0 0)
			(layers "F.Cu" "F.Mask" "F.Paste")
			(net "GND")
		)
	)
	(footprint ""
		(layer "F.Cu")
		(at 250.77039 -53.424582 90)
		(property "Reference" "PC2205"
			(at 0 0 90)
			(layer "F.SilkS")
			(hide yes)
			(effects
				(font
					(size 1.27 1.27)
				)
			)
		)
		(property "Value" ""
			(at 0 0 90)
			(layer "F.Fab")
			(effects
				(font
					(size 1.27 1.27)
				)
			)
		)
		(duplicate_pad_numbers_are_jumpers no)
		(fp_line
			(start 1.2954 -0.5842)
			(end 1.2954 0.5842)
			(stroke
				(width 0.1524)
				(type default)
			)
			(layer "F.SilkS")
		)
		(fp_line
			(start 0 -0.5842)
			(end 0 0.5842)
			(stroke
				(width 0.1524)
				(type default)
			)
			(layer "F.SilkS")
		)
		(fp_line
			(start -1.2954 -0.5842)
			(end 1.2954 -0.5842)
			(stroke
				(width 0.1524)
				(type default)
			)
			(layer "F.SilkS")
		)
		(fp_line
			(start 1.2954 0.5842)
			(end -1.2954 0.5842)
			(stroke
				(width 0.1524)
				(type default)
			)
			(layer "F.SilkS")
		)
		(fp_line
			(start -1.2954 0.5842)
			(end -1.2954 -0.5842)
			(stroke
				(width 0.1524)
				(type default)
			)
			(layer "F.SilkS")
		)
		(fp_line
			(start 0.8636 -0.4572)
			(end 0.8636 -0.4064)
			(stroke
				(width 0.1)
				(type default)
			)
			(layer "F.Fab")
		)
		(fp_line
			(start -0.8636 -0.4572)
			(end 0.8636 -0.4572)
			(stroke
				(width 0.1)
				(type default)
			)
			(layer "F.Fab")
		)
		(fp_line
			(start 1.1938 -0.4064)
			(end 1.1938 0.4064)
			(stroke
				(width 0.1)
				(type default)
			)
			(layer "F.Fab")
		)
		(fp_line
			(start 0.8636 -0.4064)
			(end 1.1938 -0.4064)
			(stroke
				(width 0.1)
				(type default)
			)
			(layer "F.Fab")
		)
		(fp_line
			(start -0.8636 -0.4064)
			(end -0.8636 -0.4572)
			(stroke
				(width 0.1)
				(type default)
			)
			(layer "F.Fab")
		)
		(fp_line
			(start -1.1938 -0.4064)
			(end -0.8636 -0.4064)
			(stroke
				(width 0.1)
				(type default)
			)
			(layer "F.Fab")
		)
		(fp_line
			(start 1.1938 0.4064)
			(end 0.8636 0.4064)
			(stroke
				(width 0.1)
				(type default)
			)
			(layer "F.Fab")
		)
		(fp_line
			(start 0.8636 0.4064)
			(end 0.8636 0.4572)
			(stroke
				(width 0.1)
				(type default)
			)
			(layer "F.Fab")
		)
		(fp_line
			(start -0.8636 0.4064)
			(end -1.1938 0.4064)
			(stroke
				(width 0.1)
				(type default)
			)
			(layer "F.Fab")
		)
		(fp_line
			(start -1.1938 0.4064)
			(end -1.1938 -0.4064)
			(stroke
				(width 0.1)
				(type default)
			)
			(layer "F.Fab")
		)
		(fp_line
			(start 0.8636 0.4572)
			(end -0.8636 0.4572)
			(stroke
				(width 0.1)
				(type default)
			)
			(layer "F.Fab")
		)
		(fp_line
			(start -0.8636 0.4572)
			(end -0.8636 0.4064)
			(stroke
				(width 0.1)
				(type default)
			)
			(layer "F.Fab")
		)
		(pad "1" smd rect
			(at -0.7366 0)
			(size 0.7112 0.8128)
			(layers "F.Cu" "F.Mask" "F.Paste")
			(net "P12V_E1S_AVIN_PD_0")
		)
		(pad "2" smd rect
			(at 0.7366 0)
			(size 0.7112 0.8128)
			(layers "F.Cu" "F.Mask" "F.Paste")
			(net "GND")
		)
	)
	(footprint ""
		(layer "F.Cu")
		(at 409.50261 -408.517344 -90)
		(property "Reference" "C894"
			(at 0 0 270)
			(layer "F.SilkS")
			(hide yes)
			(effects
				(font
					(size 1.27 1.27)
				)
			)
		)
		(property "Value" ""
			(at 0 0 270)
			(layer "F.Fab")
			(effects
				(font
					(size 1.27 1.27)
				)
			)
		)
		(duplicate_pad_numbers_are_jumpers no)
		(fp_line
			(start -0.299974 0.150114)
			(end -0.299974 -0.150114)
			(stroke
				(width 0.1)
				(type default)
			)
			(layer "F.Fab")
		)
		(fp_line
			(start 0.299974 0.150114)
			(end -0.299974 0.150114)
			(stroke
				(width 0.1)
				(type default)
			)
			(layer "F.Fab")
		)
		(fp_line
			(start -0.299974 -0.150114)
			(end 0.299974 -0.150114)
			(stroke
				(width 0.1)
				(type default)
			)
			(layer "F.Fab")
		)
		(fp_line
			(start 0.299974 -0.150114)
			(end 0.299974 0.150114)
			(stroke
				(width 0.1)
				(type default)
			)
			(layer "F.Fab")
		)
		(pad "1" smd rect
			(at -0.2667 0 270)
			(size 0.3048 0.381)
			(layers "F.Cu" "F.Mask" "F.Paste")
			(net "P5E_CPU0_PE3_TX_C_DN<3>")
		)
		(pad "2" smd rect
			(at 0.2667 0 270)
			(size 0.3048 0.381)
			(layers "F.Cu" "F.Mask" "F.Paste")
			(net "P5E_CPU0_PE3_TX_DN<3>")
		)
	)
	(footprint ""
		(layer "F.Cu")
		(at 81.73847 -143.046704)
		(property "Reference" "R667"
			(at 0 0 0)
			(layer "F.SilkS")
			(hide yes)
			(effects
				(font
					(size 1.27 1.27)
				)
			)
		)
		(property "Value" ""
			(at 0 0 0)
			(layer "F.Fab")
			(effects
				(font
					(size 1.27 1.27)
				)
			)
		)
		(duplicate_pad_numbers_are_jumpers no)
		(fp_line
			(start -0.7874 -0.4064)
			(end 0.7874 -0.4064)
			(stroke
				(width 0.1524)
				(type default)
			)
			(layer "F.SilkS")
		)
		(fp_line
			(start -0.7874 0.4064)
			(end -0.7874 -0.4064)
			(stroke
				(width 0.1524)
				(type default)
			)
			(layer "F.SilkS")
		)
		(fp_line
			(start 0.7874 -0.4064)
			(end 0.7874 0.4064)
			(stroke
				(width 0.1524)
				(type default)
			)
			(layer "F.SilkS")
		)
		(fp_line
			(start 0.7874 0.4064)
			(end -0.7874 0.4064)
			(stroke
				(width 0.1524)
				(type default)
			)
			(layer "F.SilkS")
		)
		(fp_line
			(start -0.67945 -0.305054)
			(end -0.12065 -0.305054)
			(stroke
				(width 0.1)
				(type default)
			)
			(layer "F.Fab")
		)
		(fp_line
			(start -0.67945 0.3048)
			(end -0.67945 -0.305054)
			(stroke
				(width 0.1)
				(type default)
			)
			(layer "F.Fab")
		)
		(fp_line
			(start -0.12065 -0.305054)
			(end -0.12065 -0.2794)
			(stroke
				(width 0.1)
				(type default)
			)
			(layer "F.Fab")
		)
		(fp_line
			(start -0.12065 -0.2794)
			(end 0.12065 -0.2794)
			(stroke
				(width 0.1)
				(type default)
			)
			(layer "F.Fab")
		)
		(fp_line
			(start -0.12065 0.2794)
			(end -0.12065 0.3048)
			(stroke
				(width 0.1)
				(type default)
			)
			(layer "F.Fab")
		)
		(fp_line
			(start -0.12065 0.3048)
			(end -0.67945 0.3048)
			(stroke
				(width 0.1)
				(type default)
			)
			(layer "F.Fab")
		)
		(fp_line
			(start 0.120396 0.2794)
			(end -0.12065 0.2794)
			(stroke
				(width 0.1)
				(type default)
			)
			(layer "F.Fab")
		)
		(fp_line
			(start 0.120396 0.3048)
			(end 0.120396 0.2794)
			(stroke
				(width 0.1)
				(type default)
			)
			(layer "F.Fab")
		)
		(fp_line
			(start 0.12065 -0.3048)
			(end 0.67945 -0.3048)
			(stroke
				(width 0.1)
				(type default)
			)
			(layer "F.Fab")
		)
		(fp_line
			(start 0.12065 -0.2794)
			(end 0.12065 -0.3048)
			(stroke
				(width 0.1)
				(type default)
			)
			(layer "F.Fab")
		)
		(fp_line
			(start 0.67945 -0.3048)
			(end 0.67945 0.3048)
			(stroke
				(width 0.1)
				(type default)
			)
			(layer "F.Fab")
		)
		(fp_line
			(start 0.67945 0.3048)
			(end 0.120396 0.3048)
			(stroke
				(width 0.1)
				(type default)
			)
			(layer "F.Fab")
		)
		(pad "1" smd circle
			(at -0.40005 0)
			(size 0 0)
			(layers "F.Cu" "F.Mask" "F.Paste")
			(net "I3C_SPD_DDREFGH_CPU1_R_SCL")
		)
		(pad "2" smd circle
			(at 0.40005 0)
			(size 0 0)
			(layers "F.Cu" "F.Mask" "F.Paste")
			(net "I3C_SPD_DDREFGH_CPU1_LVC1_R_SCL")
		)
	)
	(footprint ""
		(layer "F.Cu")
		(at 125.48108 -106.238548 -90)
		(property "Reference" "R4049"
			(at 0 0 270)
			(layer "F.SilkS")
			(hide yes)
			(effects
				(font
					(size 1.27 1.27)
				)
			)
		)
		(property "Value" ""
			(at 0 0 270)
			(layer "F.Fab")
			(effects
				(font
					(size 1.27 1.27)
				)
			)
		)
		(duplicate_pad_numbers_are_jumpers no)
		(fp_line
			(start -0.7874 0.4064)
			(end -0.7874 -0.4064)
			(stroke
				(width 0.1524)
				(type default)
			)
			(layer "F.SilkS")
		)
		(fp_line
			(start 0.7874 0.4064)
			(end -0.7874 0.4064)
			(stroke
				(width 0.1524)
				(type default)
			)
			(layer "F.SilkS")
		)
		(fp_line
			(start -0.7874 -0.4064)
			(end 0.7874 -0.4064)
			(stroke
				(width 0.1524)
				(type default)
			)
			(layer "F.SilkS")
		)
		(fp_line
			(start 0.7874 -0.4064)
			(end 0.7874 0.4064)
			(stroke
				(width 0.1524)
				(type default)
			)
			(layer "F.SilkS")
		)
		(fp_line
			(start -0.67945 0.3048)
			(end -0.67945 -0.305054)
			(stroke
				(width 0.1)
				(type default)
			)
			(layer "F.Fab")
		)
		(fp_line
			(start -0.12065 0.3048)
			(end -0.67945 0.3048)
			(stroke
				(width 0.1)
				(type default)
			)
			(layer "F.Fab")
		)
		(fp_line
			(start 0.120396 0.3048)
			(end 0.120396 0.2794)
			(stroke
				(width 0.1)
				(type default)
			)
			(layer "F.Fab")
		)
		(fp_line
			(start 0.67945 0.3048)
			(end 0.120396 0.3048)
			(stroke
				(width 0.1)
				(type default)
			)
			(layer "F.Fab")
		)
		(fp_line
			(start -0.12065 0.2794)
			(end -0.12065 0.3048)
			(stroke
				(width 0.1)
				(type default)
			)
			(layer "F.Fab")
		)
		(fp_line
			(start 0.120396 0.2794)
			(end -0.12065 0.2794)
			(stroke
				(width 0.1)
				(type default)
			)
			(layer "F.Fab")
		)
		(fp_line
			(start -0.12065 -0.2794)
			(end 0.12065 -0.2794)
			(stroke
				(width 0.1)
				(type default)
			)
			(layer "F.Fab")
		)
		(fp_line
			(start 0.12065 -0.2794)
			(end 0.12065 -0.3048)
			(stroke
				(width 0.1)
				(type default)
			)
			(layer "F.Fab")
		)
		(fp_line
			(start 0.12065 -0.3048)
			(end 0.67945 -0.3048)
			(stroke
				(width 0.1)
				(type default)
			)
			(layer "F.Fab")
		)
		(fp_line
			(start 0.67945 -0.3048)
			(end 0.67945 0.3048)
			(stroke
				(width 0.1)
				(type default)
			)
			(layer "F.Fab")
		)
		(fp_line
			(start -0.67945 -0.305054)
			(end -0.12065 -0.305054)
			(stroke
				(width 0.1)
				(type default)
			)
			(layer "F.Fab")
		)
		(fp_line
			(start -0.12065 -0.305054)
			(end -0.12065 -0.2794)
			(stroke
				(width 0.1)
				(type default)
			)
			(layer "F.Fab")
		)
		(pad "1" smd circle
			(at -0.40005 0 270)
			(size 0 0)
			(layers "F.Cu" "F.Mask" "F.Paste")
			(net "RST_CPU1_DRAM_GH_PLD_LVT3_R_N")
		)
		(pad "2" smd circle
			(at 0.40005 0 270)
			(size 0 0)
			(layers "F.Cu" "F.Mask" "F.Paste")
			(net "RST_CPU1_DRAM_GH_PLD_LVT3_N")
		)
	)
	(footprint ""
		(layer "F.Cu")
		(at 169.27195 -358.135936 -90)
		(property "Reference" "PC1367"
			(at 0 0 270)
			(layer "F.SilkS")
			(hide yes)
			(effects
				(font
					(size 1.27 1.27)
				)
			)
		)
		(property "Value" ""
			(at 0 0 270)
			(layer "F.Fab")
			(effects
				(font
					(size 1.27 1.27)
				)
			)
		)
		(duplicate_pad_numbers_are_jumpers no)
		(fp_line
			(start -0.7874 0.4064)
			(end -0.7874 -0.4064)
			(stroke
				(width 0.1524)
				(type default)
			)
			(layer "F.SilkS")
		)
		(fp_line
			(start 0.7874 0.4064)
			(end -0.7874 0.4064)
			(stroke
				(width 0.1524)
				(type default)
			)
			(layer "F.SilkS")
		)
		(fp_line
			(start -0.7874 -0.4064)
			(end 0.7874 -0.4064)
			(stroke
				(width 0.1524)
				(type default)
			)
			(layer "F.SilkS")
		)
		(fp_line
			(start 0.7874 -0.4064)
			(end 0.7874 0.4064)
			(stroke
				(width 0.1524)
				(type default)
			)
			(layer "F.SilkS")
		)
		(fp_line
			(start -0.67945 0.3048)
			(end -0.67945 -0.305054)
			(stroke
				(width 0.1)
				(type default)
			)
			(layer "F.Fab")
		)
		(fp_line
			(start -0.12065 0.3048)
			(end -0.67945 0.3048)
			(stroke
				(width 0.1)
				(type default)
			)
			(layer "F.Fab")
		)
		(fp_line
			(start 0.120396 0.3048)
			(end 0.120396 0.2794)
			(stroke
				(width 0.1)
				(type default)
			)
			(layer "F.Fab")
		)
		(fp_line
			(start 0.67945 0.3048)
			(end 0.120396 0.3048)
			(stroke
				(width 0.1)
				(type default)
			)
			(layer "F.Fab")
		)
		(fp_line
			(start -0.12065 0.2794)
			(end -0.12065 0.3048)
			(stroke
				(width 0.1)
				(type default)
			)
			(layer "F.Fab")
		)
		(fp_line
			(start 0.120396 0.2794)
			(end -0.12065 0.2794)
			(stroke
				(width 0.1)
				(type default)
			)
			(layer "F.Fab")
		)
		(fp_line
			(start -0.12065 -0.2794)
			(end 0.12065 -0.2794)
			(stroke
				(width 0.1)
				(type default)
			)
			(layer "F.Fab")
		)
		(fp_line
			(start 0.12065 -0.2794)
			(end 0.12065 -0.3048)
			(stroke
				(width 0.1)
				(type default)
			)
			(layer "F.Fab")
		)
		(fp_line
			(start 0.12065 -0.3048)
			(end 0.67945 -0.3048)
			(stroke
				(width 0.1)
				(type default)
			)
			(layer "F.Fab")
		)
		(fp_line
			(start 0.67945 -0.3048)
			(end 0.67945 0.3048)
			(stroke
				(width 0.1)
				(type default)
			)
			(layer "F.Fab")
		)
		(fp_line
			(start -0.67945 -0.305054)
			(end -0.12065 -0.305054)
			(stroke
				(width 0.1)
				(type default)
			)
			(layer "F.Fab")
		)
		(fp_line
			(start -0.12065 -0.305054)
			(end -0.12065 -0.2794)
			(stroke
				(width 0.1)
				(type default)
			)
			(layer "F.Fab")
		)
		(pad "1" smd circle
			(at -0.40005 0 270)
			(size 0 0)
			(layers "F.Cu" "F.Mask" "F.Paste")
			(net "GND")
		)
		(pad "2" smd circle
			(at 0.40005 0 270)
			(size 0 0)
			(layers "F.Cu" "F.Mask" "F.Paste")
			(net "PVCCIN_CPU1_VREF")
		)
	)
	(footprint ""
		(layer "F.Cu")
		(at 407.694384 -16.088614 90)
		(property "Reference" "C850"
			(at 0 0 90)
			(layer "F.SilkS")
			(hide yes)
			(effects
				(font
					(size 1.27 1.27)
				)
			)
		)
		(property "Value" ""
			(at 0 0 90)
			(layer "F.Fab")
			(effects
				(font
					(size 1.27 1.27)
				)
			)
		)
		(duplicate_pad_numbers_are_jumpers no)
		(fp_line
			(start 0.299974 -0.150114)
			(end 0.299974 0.150114)
			(stroke
				(width 0.1)
				(type default)
			)
			(layer "F.Fab")
		)
		(fp_line
			(start -0.299974 -0.150114)
			(end 0.299974 -0.150114)
			(stroke
				(width 0.1)
				(type default)
			)
			(layer "F.Fab")
		)
		(fp_line
			(start 0.299974 0.150114)
			(end -0.299974 0.150114)
			(stroke
				(width 0.1)
				(type default)
			)
			(layer "F.Fab")
		)
		(fp_line
			(start -0.299974 0.150114)
			(end -0.299974 -0.150114)
			(stroke
				(width 0.1)
				(type default)
			)
			(layer "F.Fab")
		)
		(pad "1" smd rect
			(at -0.2667 0 90)
			(size 0.3048 0.381)
			(layers "F.Cu" "F.Mask" "F.Paste")
			(net "P5E_CPU0_PE1_TX_C_DN<9>")
		)
		(pad "2" smd rect
			(at 0.2667 0 90)
			(size 0.3048 0.381)
			(layers "F.Cu" "F.Mask" "F.Paste")
			(net "P5E_CPU0_PE1_TX_DN<9>")
		)
	)
	(footprint ""
		(layer "F.Cu")
		(at 336.777076 -337.126326)
		(property "Reference" "PU8_P0_6"
			(at -1.222756 -6.773672 0)
			(unlocked yes)
			(layer "F.SilkS")
			(effects
				(font
					(size 0.7874 0.5842)
					(thickness 0.1524)
				)
				(justify left)
			)
		)
		(property "Value" ""
			(at 0 0 0)
			(layer "F.Fab")
			(effects
				(font
					(size 1.27 1.27)
				)
			)
		)
		(duplicate_pad_numbers_are_jumpers no)
		(fp_line
			(start -2.500122 -2.999994)
			(end -2.24409 -2.999994)
			(stroke
				(width 0.1524)
				(type default)
			)
			(layer "F.SilkS")
		)
		(fp_line
			(start -2.500122 -2.529078)
			(end -2.500122 -2.999994)
			(stroke
				(width 0.1524)
				(type default)
			)
			(layer "F.SilkS")
		)
		(fp_line
			(start -2.500122 0.6604)
			(end -2.500122 0.229108)
			(stroke
				(width 0.1524)
				(type default)
			)
			(layer "F.SilkS")
		)
		(fp_line
			(start -2.500122 2.999994)
			(end -2.500122 2.339594)
			(stroke
				(width 0.1524)
				(type default)
			)
			(layer "F.SilkS")
		)
		(fp_line
			(start -2.2987 2.999994)
			(end -2.500122 2.999994)
			(stroke
				(width 0.1524)
				(type default)
			)
			(layer "F.SilkS")
		)
		(fp_line
			(start 2.31394 -2.999994)
			(end 2.500122 -2.999994)
			(stroke
				(width 0.1524)
				(type default)
			)
			(layer "F.SilkS")
		)
		(fp_line
			(start 2.500122 -2.999994)
			(end 2.500122 -2.44348)
			(stroke
				(width 0.1524)
				(type default)
			)
			(layer "F.SilkS")
		)
		(fp_line
			(start 2.500122 2.339594)
			(end 2.500122 2.999994)
			(stroke
				(width 0.1524)
				(type default)
			)
			(layer "F.SilkS")
		)
		(fp_line
			(start 2.500122 2.999994)
			(end 2.2987 2.999994)
			(stroke
				(width 0.1524)
				(type default)
			)
			(layer "F.SilkS")
		)
		(fp_poly
			(pts
				(xy -2.21742 -3.606038) (xy -2.72542 -2.590038) (xy -3.23342 -3.606038)
			)
			(stroke
				(width 0)
				(type default)
			)
			(fill yes)
			(layer "F.SilkS")
		)
		(fp_line
			(start -2.500122 -2.999994)
			(end 2.500122 -2.999994)
			(stroke
				(width 0.1)
				(type default)
			)
			(layer "F.Fab")
		)
		(fp_line
			(start -2.500122 2.999994)
			(end -2.500122 -2.999994)
			(stroke
				(width 0.1)
				(type default)
			)
			(layer "F.Fab")
		)
		(fp_line
			(start 2.500122 -2.999994)
			(end 2.500122 2.999994)
			(stroke
				(width 0.1)
				(type default)
			)
			(layer "F.Fab")
		)
		(fp_line
			(start 2.500122 2.999994)
			(end -2.500122 2.999994)
			(stroke
				(width 0.1)
				(type default)
			)
			(layer "F.Fab")
		)
		(fp_poly
			(pts
				(xy -4.218432 -2.783078) (xy -4.218432 -1.767078) (xy -3.202432 -2.275078)
			)
			(stroke
				(width 0)
				(type default)
			)
			(fill yes)
			(layer "F.Fab")
		)
		(pad "1" smd rect
			(at -2.400046 -2.275078 90)
			(size 0.2286 0.6096)
			(layers "F.Cu" "F.Mask" "F.Paste")
			(net "PVCCIN_CPU0_VOS6")
		)
		(pad "2" smd rect
			(at -2.400046 -1.82499 90)
			(size 0.2286 0.6096)
			(layers "F.Cu" "F.Mask" "F.Paste")
			(net "GND")
		)
		(pad "3" smd rect
			(at -2.400046 -1.374902 90)
			(size 0.2286 0.6096)
			(layers "F.Cu" "F.Mask" "F.Paste")
			(net "PVCCIN_CPU0_VDD6")
		)
		(pad "4" smd rect
			(at -2.400046 -0.925068 90)
			(size 0.2286 0.6096)
			(layers "F.Cu" "F.Mask" "F.Paste")
			(net "PVCCIN_CPU0_PVCC")
		)
		(pad "5" smd rect
			(at -2.400046 -0.47498 90)
			(size 0.2286 0.6096)
			(layers "F.Cu" "F.Mask" "F.Paste")
			(net "GND")
		)
		(pad "6" smd rect
			(at -2.400046 -0.024892 90)
			(size 0.2286 0.6096)
			(layers "F.Cu" "F.Mask" "F.Paste")
			(net "Net_8559")
		)
		(pad "7_9-20_24" smd circle
			(at 0 1.150112 90)
			(size 0 0)
			(layers "F.Cu" "F.Mask" "F.Paste")
			(net "GND")
		)
		(pad "10_19" smd rect
			(at 0 2.899918 90)
			(size 0.6096 4.318)
			(layers "F.Cu" "F.Mask" "F.Paste")
			(net "SW_PVCCIN_CPU0_SW6")
		)
		(pad "25_29" smd rect
			(at 1.549908 -1.279906 270)
			(size 2.0574 2.3114)
			(layers "F.Cu" "F.Mask" "F.Paste")
			(net "SW_P12V_PVCCIN_CPU0_FLT")
		)
		(pad "30" smd rect
			(at 2.05994 -2.899918)
			(size 0.2286 0.6096)
			(layers "F.Cu" "F.Mask" "F.Paste")
			(net "SW_P12V_PVCCIN_CPU0_FLT")
		)
		(pad "31" smd rect
			(at 1.610106 -2.899918)
			(size 0.2286 0.6096)
			(layers "F.Cu" "F.Mask" "F.Paste")
			(net "Net_8560")
		)
		(pad "32" smd rect
			(at 1.160018 -2.899918)
			(size 0.2286 0.6096)
			(layers "F.Cu" "F.Mask" "F.Paste")
			(net "SW_PVCCIN_CPU0_BOOTR6")
		)
		(pad "33" smd rect
			(at 0.70993 -2.899918)
			(size 0.2286 0.6096)
			(layers "F.Cu" "F.Mask" "F.Paste")
			(net "SW_PVCCIN_CPU0_BOOT6")
		)
		(pad "34" smd rect
			(at 0.260096 -2.899918)
			(size 0.2286 0.6096)
			(layers "F.Cu" "F.Mask" "F.Paste")
			(net "PVCCIN_CPU0_PWM6")
		)
		(pad "35" smd rect
			(at -0.189992 -2.899918)
			(size 0.2286 0.6096)
			(layers "F.Cu" "F.Mask" "F.Paste")
			(net "PVCCIN_CPU0_VDD6")
		)
		(pad "36" smd rect
			(at -0.64008 -2.899918)
			(size 0.2286 0.6096)
			(layers "F.Cu" "F.Mask" "F.Paste")
			(net "PVCCIN_CPU0_ATSEN")
		)
		(pad "37" smd rect
			(at -1.089914 -2.899918)
			(size 0.2286 0.6096)
			(layers "F.Cu" "F.Mask" "F.Paste")
			(net "PVCCIN_CPU0_LSET6")
		)
		(pad "38" smd rect
			(at -1.540002 -2.899918)
			(size 0.2286 0.6096)
			(layers "F.Cu" "F.Mask" "F.Paste")
			(net "PVCCIN_CPU0_IMON6")
		)
		(pad "39" smd rect
			(at -1.99009 -2.899918)
			(size 0.2286 0.6096)
			(layers "F.Cu" "F.Mask" "F.Paste")
			(net "PVCCIN_CPU0_VREF")
		)
		(pad "40" smd rect
			(at -0.87503 -1.27508)
			(size 1.7526 1.9558)
			(layers "F.Cu" "F.Mask" "F.Paste")
			(net "GND")
		)
		(pad "41" smd rect
			(at -1.525016 0.249936 270)
			(size 0.3048 0.4572)
			(layers "F.Cu" "F.Mask" "F.Paste")
			(net "Net_8558")
		)
		(zone
			(layer "F.Cu")
			(hatch none 0.5)
			(connect_pads
				(clearance 0)
			)
			(min_thickness 0.25)
			(keepout
				(tracks not_allowed)
				(vias allowed)
				(pads allowed)
				(copperpour not_allowed)
				(footprints allowed)
			)
			(placement
				(enabled no)
				(sheetname "")
			)
			(fill
				(thermal_gap 0.5)
				(thermal_bridge_width 0.5)
				(island_removal_mode 0)
			)
			(polygon
				(pts
					(xy 334.974946 -338.816442) (xy 334.974946 -337.764628) (xy 334.73263 -337.764628) (xy 334.73263 -338.844128)
					(xy 334.94726 -338.844128)
				)
			)
		)
		(zone
			(layer "F.Cu")
			(hatch none 0.5)
			(connect_pads
				(clearance 0)
			)
			(min_thickness 0.25)
			(keepout
				(tracks not_allowed)
				(vias allowed)
				(pads allowed)
				(copperpour not_allowed)
				(footprints allowed)
			)
			(placement
				(enabled no)
				(sheetname "")
			)
			(fill
				(thermal_gap 0.5)
				(thermal_bridge_width 0.5)
				(island_removal_mode 0)
			)
			(polygon
				(pts
					(xy 334.276954 -334.126332) (xy 334.276954 -334.875632) (xy 339.277198 -334.875632) (xy 339.277198 -334.126332)
					(xy 338.986876 -334.126332) (xy 338.986876 -334.582008) (xy 334.567276 -334.582008) (xy 334.567276 -334.126332)
				)
			)
		)
	)
	(footprint ""
		(layer "F.Cu")
		(at 51.10988 -170.576748 -90)
		(property "Reference" "PR1799"
			(at 0 0 270)
			(layer "F.SilkS")
			(hide yes)
			(effects
				(font
					(size 1.27 1.27)
				)
			)
		)
		(property "Value" ""
			(at 0 0 270)
			(layer "F.Fab")
			(effects
				(font
					(size 1.27 1.27)
				)
			)
		)
		(duplicate_pad_numbers_are_jumpers no)
		(fp_line
			(start -0.7874 0.4064)
			(end -0.7874 -0.4064)
			(stroke
				(width 0.1524)
				(type default)
			)
			(layer "F.SilkS")
		)
		(fp_line
			(start 0.7874 0.4064)
			(end -0.7874 0.4064)
			(stroke
				(width 0.1524)
				(type default)
			)
			(layer "F.SilkS")
		)
		(fp_line
			(start -0.7874 -0.4064)
			(end 0.7874 -0.4064)
			(stroke
				(width 0.1524)
				(type default)
			)
			(layer "F.SilkS")
		)
		(fp_line
			(start 0.7874 -0.4064)
			(end 0.7874 0.4064)
			(stroke
				(width 0.1524)
				(type default)
			)
			(layer "F.SilkS")
		)
		(fp_line
			(start -0.67945 0.3048)
			(end -0.67945 -0.305054)
			(stroke
				(width 0.1)
				(type default)
			)
			(layer "F.Fab")
		)
		(fp_line
			(start -0.12065 0.3048)
			(end -0.67945 0.3048)
			(stroke
				(width 0.1)
				(type default)
			)
			(layer "F.Fab")
		)
		(fp_line
			(start 0.120396 0.3048)
			(end 0.120396 0.2794)
			(stroke
				(width 0.1)
				(type default)
			)
			(layer "F.Fab")
		)
		(fp_line
			(start 0.67945 0.3048)
			(end 0.120396 0.3048)
			(stroke
				(width 0.1)
				(type default)
			)
			(layer "F.Fab")
		)
		(fp_line
			(start -0.12065 0.2794)
			(end -0.12065 0.3048)
			(stroke
				(width 0.1)
				(type default)
			)
			(layer "F.Fab")
		)
		(fp_line
			(start 0.120396 0.2794)
			(end -0.12065 0.2794)
			(stroke
				(width 0.1)
				(type default)
			)
			(layer "F.Fab")
		)
		(fp_line
			(start -0.12065 -0.2794)
			(end 0.12065 -0.2794)
			(stroke
				(width 0.1)
				(type default)
			)
			(layer "F.Fab")
		)
		(fp_line
			(start 0.12065 -0.2794)
			(end 0.12065 -0.3048)
			(stroke
				(width 0.1)
				(type default)
			)
			(layer "F.Fab")
		)
		(fp_line
			(start 0.12065 -0.3048)
			(end 0.67945 -0.3048)
			(stroke
				(width 0.1)
				(type default)
			)
			(layer "F.Fab")
		)
		(fp_line
			(start 0.67945 -0.3048)
			(end 0.67945 0.3048)
			(stroke
				(width 0.1)
				(type default)
			)
			(layer "F.Fab")
		)
		(fp_line
			(start -0.67945 -0.305054)
			(end -0.12065 -0.305054)
			(stroke
				(width 0.1)
				(type default)
			)
			(layer "F.Fab")
		)
		(fp_line
			(start -0.12065 -0.305054)
			(end -0.12065 -0.2794)
			(stroke
				(width 0.1)
				(type default)
			)
			(layer "F.Fab")
		)
		(pad "1" smd circle
			(at -0.40005 0 270)
			(size 0 0)
			(layers "F.Cu" "F.Mask" "F.Paste")
			(net "PVCCFA_EHV_CPU1_NC1")
		)
		(pad "2" smd circle
			(at 0.40005 0 270)
			(size 0 0)
			(layers "F.Cu" "F.Mask" "F.Paste")
			(net "PVCCFA_EHV_CPU1_VDD1")
		)
	)
	(footprint ""
		(layer "F.Cu")
		(at 448.980052 -18.063464 -90)
		(property "Reference" "PR3787"
			(at 0 0 270)
			(layer "F.SilkS")
			(hide yes)
			(effects
				(font
					(size 1.27 1.27)
				)
			)
		)
		(property "Value" ""
			(at 0 0 270)
			(layer "F.Fab")
			(effects
				(font
					(size 1.27 1.27)
				)
			)
		)
		(duplicate_pad_numbers_are_jumpers no)
		(fp_line
			(start -0.7874 0.4064)
			(end -0.7874 -0.4064)
			(stroke
				(width 0.1524)
				(type default)
			)
			(layer "F.SilkS")
		)
		(fp_line
			(start 0.7874 0.4064)
			(end -0.7874 0.4064)
			(stroke
				(width 0.1524)
				(type default)
			)
			(layer "F.SilkS")
		)
		(fp_line
			(start -0.7874 -0.4064)
			(end 0.7874 -0.4064)
			(stroke
				(width 0.1524)
				(type default)
			)
			(layer "F.SilkS")
		)
		(fp_line
			(start 0.7874 -0.4064)
			(end 0.7874 0.4064)
			(stroke
				(width 0.1524)
				(type default)
			)
			(layer "F.SilkS")
		)
		(fp_line
			(start -0.67945 0.3048)
			(end -0.67945 -0.305054)
			(stroke
				(width 0.1)
				(type default)
			)
			(layer "F.Fab")
		)
		(fp_line
			(start -0.12065 0.3048)
			(end -0.67945 0.3048)
			(stroke
				(width 0.1)
				(type default)
			)
			(layer "F.Fab")
		)
		(fp_line
			(start 0.120396 0.3048)
			(end 0.120396 0.2794)
			(stroke
				(width 0.1)
				(type default)
			)
			(layer "F.Fab")
		)
		(fp_line
			(start 0.67945 0.3048)
			(end 0.120396 0.3048)
			(stroke
				(width 0.1)
				(type default)
			)
			(layer "F.Fab")
		)
		(fp_line
			(start -0.12065 0.2794)
			(end -0.12065 0.3048)
			(stroke
				(width 0.1)
				(type default)
			)
			(layer "F.Fab")
		)
		(fp_line
			(start 0.120396 0.2794)
			(end -0.12065 0.2794)
			(stroke
				(width 0.1)
				(type default)
			)
			(layer "F.Fab")
		)
		(fp_line
			(start -0.12065 -0.2794)
			(end 0.12065 -0.2794)
			(stroke
				(width 0.1)
				(type default)
			)
			(layer "F.Fab")
		)
		(fp_line
			(start 0.12065 -0.2794)
			(end 0.12065 -0.3048)
			(stroke
				(width 0.1)
				(type default)
			)
			(layer "F.Fab")
		)
		(fp_line
			(start 0.12065 -0.3048)
			(end 0.67945 -0.3048)
			(stroke
				(width 0.1)
				(type default)
			)
			(layer "F.Fab")
		)
		(fp_line
			(start 0.67945 -0.3048)
			(end 0.67945 0.3048)
			(stroke
				(width 0.1)
				(type default)
			)
			(layer "F.Fab")
		)
		(fp_line
			(start -0.67945 -0.305054)
			(end -0.12065 -0.305054)
			(stroke
				(width 0.1)
				(type default)
			)
			(layer "F.Fab")
		)
		(fp_line
			(start -0.12065 -0.305054)
			(end -0.12065 -0.2794)
			(stroke
				(width 0.1)
				(type default)
			)
			(layer "F.Fab")
		)
		(pad "1" smd circle
			(at -0.40005 0 270)
			(size 0 0)
			(layers "F.Cu" "F.Mask" "F.Paste")
			(net "P12V_OCP_UV_1")
		)
		(pad "2" smd circle
			(at 0.40005 0 270)
			(size 0 0)
			(layers "F.Cu" "F.Mask" "F.Paste")
			(net "P12V_OCP_OV_1")
		)
	)
	(footprint ""
		(layer "F.Cu")
		(at 22.809454 -108.793026 180)
		(property "Reference" "R3689"
			(at 0 0 180)
			(layer "F.SilkS")
			(hide yes)
			(effects
				(font
					(size 1.27 1.27)
				)
			)
		)
		(property "Value" ""
			(at 0 0 180)
			(layer "F.Fab")
			(effects
				(font
					(size 1.27 1.27)
				)
			)
		)
		(duplicate_pad_numbers_are_jumpers no)
		(fp_line
			(start 0.7874 0.4064)
			(end -0.7874 0.4064)
			(stroke
				(width 0.1524)
				(type default)
			)
			(layer "F.SilkS")
		)
		(fp_line
			(start 0.7874 -0.4064)
			(end 0.7874 0.4064)
			(stroke
				(width 0.1524)
				(type default)
			)
			(layer "F.SilkS")
		)
		(fp_line
			(start -0.7874 0.4064)
			(end -0.7874 -0.4064)
			(stroke
				(width 0.1524)
				(type default)
			)
			(layer "F.SilkS")
		)
		(fp_line
			(start -0.7874 -0.4064)
			(end 0.7874 -0.4064)
			(stroke
				(width 0.1524)
				(type default)
			)
			(layer "F.SilkS")
		)
		(fp_line
			(start 0.67945 0.3048)
			(end 0.120396 0.3048)
			(stroke
				(width 0.1)
				(type default)
			)
			(layer "F.Fab")
		)
		(fp_line
			(start 0.67945 -0.3048)
			(end 0.67945 0.3048)
			(stroke
				(width 0.1)
				(type default)
			)
			(layer "F.Fab")
		)
		(fp_line
			(start 0.12065 -0.2794)
			(end 0.12065 -0.3048)
			(stroke
				(width 0.1)
				(type default)
			)
			(layer "F.Fab")
		)
		(fp_line
			(start 0.12065 -0.3048)
			(end 0.67945 -0.3048)
			(stroke
				(width 0.1)
				(type default)
			)
			(layer "F.Fab")
		)
		(fp_line
			(start 0.120396 0.3048)
			(end 0.120396 0.2794)
			(stroke
				(width 0.1)
				(type default)
			)
			(layer "F.Fab")
		)
		(fp_line
			(start 0.120396 0.2794)
			(end -0.12065 0.2794)
			(stroke
				(width 0.1)
				(type default)
			)
			(layer "F.Fab")
		)
		(fp_line
			(start -0.12065 0.3048)
			(end -0.67945 0.3048)
			(stroke
				(width 0.1)
				(type default)
			)
			(layer "F.Fab")
		)
		(fp_line
			(start -0.12065 0.2794)
			(end -0.12065 0.3048)
			(stroke
				(width 0.1)
				(type default)
			)
			(layer "F.Fab")
		)
		(fp_line
			(start -0.12065 -0.2794)
			(end 0.12065 -0.2794)
			(stroke
				(width 0.1)
				(type default)
			)
			(layer "F.Fab")
		)
		(fp_line
			(start -0.12065 -0.305054)
			(end -0.12065 -0.2794)
			(stroke
				(width 0.1)
				(type default)
			)
			(layer "F.Fab")
		)
		(fp_line
			(start -0.67945 0.3048)
			(end -0.67945 -0.305054)
			(stroke
				(width 0.1)
				(type default)
			)
			(layer "F.Fab")
		)
		(fp_line
			(start -0.67945 -0.305054)
			(end -0.12065 -0.305054)
			(stroke
				(width 0.1)
				(type default)
			)
			(layer "F.Fab")
		)
		(pad "1" smd circle
			(at -0.40005 0 180)
			(size 0 0)
			(layers "F.Cu" "F.Mask" "F.Paste")
			(net "P3V3_ADC128_VCC")
		)
		(pad "2" smd circle
			(at 0.40005 0 180)
			(size 0 0)
			(layers "F.Cu" "F.Mask" "F.Paste")
			(net "ADC128_VREF")
		)
	)
	(footprint ""
		(layer "F.Cu")
		(at 51.593496 -105.34777)
		(property "Reference" "R3729"
			(at 0 0 0)
			(layer "F.SilkS")
			(hide yes)
			(effects
				(font
					(size 1.27 1.27)
				)
			)
		)
		(property "Value" ""
			(at 0 0 0)
			(layer "F.Fab")
			(effects
				(font
					(size 1.27 1.27)
				)
			)
		)
		(duplicate_pad_numbers_are_jumpers no)
		(fp_line
			(start -0.7874 -0.4064)
			(end 0.7874 -0.4064)
			(stroke
				(width 0.1524)
				(type default)
			)
			(layer "F.SilkS")
		)
		(fp_line
			(start -0.7874 0.4064)
			(end -0.7874 -0.4064)
			(stroke
				(width 0.1524)
				(type default)
			)
			(layer "F.SilkS")
		)
		(fp_line
			(start 0.7874 -0.4064)
			(end 0.7874 0.4064)
			(stroke
				(width 0.1524)
				(type default)
			)
			(layer "F.SilkS")
		)
		(fp_line
			(start 0.7874 0.4064)
			(end -0.7874 0.4064)
			(stroke
				(width 0.1524)
				(type default)
			)
			(layer "F.SilkS")
		)
		(fp_line
			(start -0.67945 -0.305054)
			(end -0.12065 -0.305054)
			(stroke
				(width 0.1)
				(type default)
			)
			(layer "F.Fab")
		)
		(fp_line
			(start -0.67945 0.3048)
			(end -0.67945 -0.305054)
			(stroke
				(width 0.1)
				(type default)
			)
			(layer "F.Fab")
		)
		(fp_line
			(start -0.12065 -0.305054)
			(end -0.12065 -0.2794)
			(stroke
				(width 0.1)
				(type default)
			)
			(layer "F.Fab")
		)
		(fp_line
			(start -0.12065 -0.2794)
			(end 0.12065 -0.2794)
			(stroke
				(width 0.1)
				(type default)
			)
			(layer "F.Fab")
		)
		(fp_line
			(start -0.12065 0.2794)
			(end -0.12065 0.3048)
			(stroke
				(width 0.1)
				(type default)
			)
			(layer "F.Fab")
		)
		(fp_line
			(start -0.12065 0.3048)
			(end -0.67945 0.3048)
			(stroke
				(width 0.1)
				(type default)
			)
			(layer "F.Fab")
		)
		(fp_line
			(start 0.120396 0.2794)
			(end -0.12065 0.2794)
			(stroke
				(width 0.1)
				(type default)
			)
			(layer "F.Fab")
		)
		(fp_line
			(start 0.120396 0.3048)
			(end 0.120396 0.2794)
			(stroke
				(width 0.1)
				(type default)
			)
			(layer "F.Fab")
		)
		(fp_line
			(start 0.12065 -0.3048)
			(end 0.67945 -0.3048)
			(stroke
				(width 0.1)
				(type default)
			)
			(layer "F.Fab")
		)
		(fp_line
			(start 0.12065 -0.2794)
			(end 0.12065 -0.3048)
			(stroke
				(width 0.1)
				(type default)
			)
			(layer "F.Fab")
		)
		(fp_line
			(start 0.67945 -0.3048)
			(end 0.67945 0.3048)
			(stroke
				(width 0.1)
				(type default)
			)
			(layer "F.Fab")
		)
		(fp_line
			(start 0.67945 0.3048)
			(end 0.120396 0.3048)
			(stroke
				(width 0.1)
				(type default)
			)
			(layer "F.Fab")
		)
		(pad "1" smd circle
			(at -0.40005 0)
			(size 0 0)
			(layers "F.Cu" "F.Mask" "F.Paste")
			(net "P3V3_AUX")
		)
		(pad "2" smd circle
			(at 0.40005 0)
			(size 0 0)
			(layers "F.Cu" "F.Mask" "F.Paste")
			(net "SMB_LM75_2_3V3AUX_SCL")
		)
	)
	(footprint ""
		(layer "F.Cu")
		(at 193.90868 -358.206548)
		(property "Reference" "R628"
			(at 0 0 0)
			(layer "F.SilkS")
			(hide yes)
			(effects
				(font
					(size 1.27 1.27)
				)
			)
		)
		(property "Value" ""
			(at 0 0 0)
			(layer "F.Fab")
			(effects
				(font
					(size 1.27 1.27)
				)
			)
		)
		(duplicate_pad_numbers_are_jumpers no)
		(fp_line
			(start -0.7874 -0.4064)
			(end 0.7874 -0.4064)
			(stroke
				(width 0.1524)
				(type default)
			)
			(layer "F.SilkS")
		)
		(fp_line
			(start -0.7874 0.4064)
			(end -0.7874 -0.4064)
			(stroke
				(width 0.1524)
				(type default)
			)
			(layer "F.SilkS")
		)
		(fp_line
			(start 0.7874 -0.4064)
			(end 0.7874 0.4064)
			(stroke
				(width 0.1524)
				(type default)
			)
			(layer "F.SilkS")
		)
		(fp_line
			(start 0.7874 0.4064)
			(end -0.7874 0.4064)
			(stroke
				(width 0.1524)
				(type default)
			)
			(layer "F.SilkS")
		)
		(fp_line
			(start -0.67945 -0.305054)
			(end -0.12065 -0.305054)
			(stroke
				(width 0.1)
				(type default)
			)
			(layer "F.Fab")
		)
		(fp_line
			(start -0.67945 0.3048)
			(end -0.67945 -0.305054)
			(stroke
				(width 0.1)
				(type default)
			)
			(layer "F.Fab")
		)
		(fp_line
			(start -0.12065 -0.305054)
			(end -0.12065 -0.2794)
			(stroke
				(width 0.1)
				(type default)
			)
			(layer "F.Fab")
		)
		(fp_line
			(start -0.12065 -0.2794)
			(end 0.12065 -0.2794)
			(stroke
				(width 0.1)
				(type default)
			)
			(layer "F.Fab")
		)
		(fp_line
			(start -0.12065 0.2794)
			(end -0.12065 0.3048)
			(stroke
				(width 0.1)
				(type default)
			)
			(layer "F.Fab")
		)
		(fp_line
			(start -0.12065 0.3048)
			(end -0.67945 0.3048)
			(stroke
				(width 0.1)
				(type default)
			)
			(layer "F.Fab")
		)
		(fp_line
			(start 0.120396 0.2794)
			(end -0.12065 0.2794)
			(stroke
				(width 0.1)
				(type default)
			)
			(layer "F.Fab")
		)
		(fp_line
			(start 0.120396 0.3048)
			(end 0.120396 0.2794)
			(stroke
				(width 0.1)
				(type default)
			)
			(layer "F.Fab")
		)
		(fp_line
			(start 0.12065 -0.3048)
			(end 0.67945 -0.3048)
			(stroke
				(width 0.1)
				(type default)
			)
			(layer "F.Fab")
		)
		(fp_line
			(start 0.12065 -0.2794)
			(end 0.12065 -0.3048)
			(stroke
				(width 0.1)
				(type default)
			)
			(layer "F.Fab")
		)
		(fp_line
			(start 0.67945 -0.3048)
			(end 0.67945 0.3048)
			(stroke
				(width 0.1)
				(type default)
			)
			(layer "F.Fab")
		)
		(fp_line
			(start 0.67945 0.3048)
			(end 0.120396 0.3048)
			(stroke
				(width 0.1)
				(type default)
			)
			(layer "F.Fab")
		)
		(pad "1" smd circle
			(at -0.40005 0)
			(size 0 0)
			(layers "F.Cu" "F.Mask" "F.Paste")
			(net "PD_PIROM_CPU1_ADDR1")
		)
		(pad "2" smd circle
			(at 0.40005 0)
			(size 0 0)
			(layers "F.Cu" "F.Mask" "F.Paste")
			(net "GND")
		)
	)
	(footprint ""
		(layer "F.Cu")
		(at 377.579636 -337.126326)
		(property "Reference" "PU9_P0_5"
			(at -3.567176 -7.230872 0)
			(unlocked yes)
			(layer "F.SilkS")
			(effects
				(font
					(size 0.7874 0.5842)
					(thickness 0.1524)
				)
				(justify left)
			)
		)
		(property "Value" ""
			(at 0 0 0)
			(layer "F.Fab")
			(effects
				(font
					(size 1.27 1.27)
				)
			)
		)
		(duplicate_pad_numbers_are_jumpers no)
		(fp_line
			(start -2.500122 -2.999994)
			(end -2.24409 -2.999994)
			(stroke
				(width 0.1524)
				(type default)
			)
			(layer "F.SilkS")
		)
		(fp_line
			(start -2.500122 -2.529078)
			(end -2.500122 -2.999994)
			(stroke
				(width 0.1524)
				(type default)
			)
			(layer "F.SilkS")
		)
		(fp_line
			(start -2.500122 0.6604)
			(end -2.500122 0.229108)
			(stroke
				(width 0.1524)
				(type default)
			)
			(layer "F.SilkS")
		)
		(fp_line
			(start -2.500122 2.999994)
			(end -2.500122 2.339594)
			(stroke
				(width 0.1524)
				(type default)
			)
			(layer "F.SilkS")
		)
		(fp_line
			(start -2.2987 2.999994)
			(end -2.500122 2.999994)
			(stroke
				(width 0.1524)
				(type default)
			)
			(layer "F.SilkS")
		)
		(fp_line
			(start 2.31394 -2.999994)
			(end 2.500122 -2.999994)
			(stroke
				(width 0.1524)
				(type default)
			)
			(layer "F.SilkS")
		)
		(fp_line
			(start 2.500122 -2.999994)
			(end 2.500122 -2.44348)
			(stroke
				(width 0.1524)
				(type default)
			)
			(layer "F.SilkS")
		)
		(fp_line
			(start 2.500122 2.339594)
			(end 2.500122 2.999994)
			(stroke
				(width 0.1524)
				(type default)
			)
			(layer "F.SilkS")
		)
		(fp_line
			(start 2.500122 2.999994)
			(end 2.2987 2.999994)
			(stroke
				(width 0.1524)
				(type default)
			)
			(layer "F.SilkS")
		)
		(fp_poly
			(pts
				(xy -2.21234 -3.631438) (xy -2.72034 -2.615438) (xy -3.22834 -3.631438)
			)
			(stroke
				(width 0)
				(type default)
			)
			(fill yes)
			(layer "F.SilkS")
		)
		(fp_line
			(start -2.500122 -2.999994)
			(end 2.500122 -2.999994)
			(stroke
				(width 0.1)
				(type default)
			)
			(layer "F.Fab")
		)
		(fp_line
			(start -2.500122 2.999994)
			(end -2.500122 -2.999994)
			(stroke
				(width 0.1)
				(type default)
			)
			(layer "F.Fab")
		)
		(fp_line
			(start 2.500122 -2.999994)
			(end 2.500122 2.999994)
			(stroke
				(width 0.1)
				(type default)
			)
			(layer "F.Fab")
		)
		(fp_line
			(start 2.500122 2.999994)
			(end -2.500122 2.999994)
			(stroke
				(width 0.1)
				(type default)
			)
			(layer "F.Fab")
		)
		(fp_poly
			(pts
				(xy -4.218432 -2.783078) (xy -4.218432 -1.767078) (xy -3.202432 -2.275078)
			)
			(stroke
				(width 0)
				(type default)
			)
			(fill yes)
			(layer "F.Fab")
		)
		(pad "1" smd rect
			(at -2.400046 -2.275078 90)
			(size 0.2286 0.6096)
			(layers "F.Cu" "F.Mask" "F.Paste")
			(net "PVCCIN_CPU0_VOS5")
		)
		(pad "2" smd rect
			(at -2.400046 -1.82499 90)
			(size 0.2286 0.6096)
			(layers "F.Cu" "F.Mask" "F.Paste")
			(net "GND")
		)
		(pad "3" smd rect
			(at -2.400046 -1.374902 90)
			(size 0.2286 0.6096)
			(layers "F.Cu" "F.Mask" "F.Paste")
			(net "PVCCIN_CPU0_VDD5")
		)
		(pad "4" smd rect
			(at -2.400046 -0.925068 90)
			(size 0.2286 0.6096)
			(layers "F.Cu" "F.Mask" "F.Paste")
			(net "PVCCIN_CPU0_PVCC")
		)
		(pad "5" smd rect
			(at -2.400046 -0.47498 90)
			(size 0.2286 0.6096)
			(layers "F.Cu" "F.Mask" "F.Paste")
			(net "GND")
		)
		(pad "6" smd rect
			(at -2.400046 -0.024892 90)
			(size 0.2286 0.6096)
			(layers "F.Cu" "F.Mask" "F.Paste")
			(net "Net_8556")
		)
		(pad "7_9-20_24" smd circle
			(at 0 1.150112 90)
			(size 0 0)
			(layers "F.Cu" "F.Mask" "F.Paste")
			(net "GND")
		)
		(pad "10_19" smd rect
			(at 0 2.899918 90)
			(size 0.6096 4.318)
			(layers "F.Cu" "F.Mask" "F.Paste")
			(net "SW_PVCCIN_CPU0_SW5")
		)
		(pad "25_29" smd rect
			(at 1.549908 -1.279906 270)
			(size 2.0574 2.3114)
			(layers "F.Cu" "F.Mask" "F.Paste")
			(net "SW_P12V_PVCCIN_CPU0_FLT")
		)
		(pad "30" smd rect
			(at 2.05994 -2.899918)
			(size 0.2286 0.6096)
			(layers "F.Cu" "F.Mask" "F.Paste")
			(net "SW_P12V_PVCCIN_CPU0_FLT")
		)
		(pad "31" smd rect
			(at 1.610106 -2.899918)
			(size 0.2286 0.6096)
			(layers "F.Cu" "F.Mask" "F.Paste")
			(net "Net_8557")
		)
		(pad "32" smd rect
			(at 1.160018 -2.899918)
			(size 0.2286 0.6096)
			(layers "F.Cu" "F.Mask" "F.Paste")
			(net "SW_PVCCIN_CPU0_BOOTR5")
		)
		(pad "33" smd rect
			(at 0.70993 -2.899918)
			(size 0.2286 0.6096)
			(layers "F.Cu" "F.Mask" "F.Paste")
			(net "SW_PVCCIN_CPU0_BOOT5")
		)
		(pad "34" smd rect
			(at 0.260096 -2.899918)
			(size 0.2286 0.6096)
			(layers "F.Cu" "F.Mask" "F.Paste")
			(net "PVCCIN_CPU0_PWM5")
		)
		(pad "35" smd rect
			(at -0.189992 -2.899918)
			(size 0.2286 0.6096)
			(layers "F.Cu" "F.Mask" "F.Paste")
			(net "PVCCIN_CPU0_VDD5")
		)
		(pad "36" smd rect
			(at -0.64008 -2.899918)
			(size 0.2286 0.6096)
			(layers "F.Cu" "F.Mask" "F.Paste")
			(net "PVCCIN_CPU0_ATSEN")
		)
		(pad "37" smd rect
			(at -1.089914 -2.899918)
			(size 0.2286 0.6096)
			(layers "F.Cu" "F.Mask" "F.Paste")
			(net "PVCCIN_CPU0_LSET5")
		)
		(pad "38" smd rect
			(at -1.540002 -2.899918)
			(size 0.2286 0.6096)
			(layers "F.Cu" "F.Mask" "F.Paste")
			(net "PVCCIN_CPU0_IMON5")
		)
		(pad "39" smd rect
			(at -1.99009 -2.899918)
			(size 0.2286 0.6096)
			(layers "F.Cu" "F.Mask" "F.Paste")
			(net "PVCCIN_CPU0_VREF")
		)
		(pad "40" smd rect
			(at -0.87503 -1.27508)
			(size 1.7526 1.9558)
			(layers "F.Cu" "F.Mask" "F.Paste")
			(net "GND")
		)
		(pad "41" smd rect
			(at -1.525016 0.249936 270)
			(size 0.3048 0.4572)
			(layers "F.Cu" "F.Mask" "F.Paste")
			(net "Net_8555")
		)
		(zone
			(layer "F.Cu")
			(hatch none 0.5)
			(connect_pads
				(clearance 0)
			)
			(min_thickness 0.25)
			(keepout
				(tracks not_allowed)
				(vias allowed)
				(pads allowed)
				(copperpour not_allowed)
				(footprints allowed)
			)
			(placement
				(enabled no)
				(sheetname "")
			)
			(fill
				(thermal_gap 0.5)
				(thermal_bridge_width 0.5)
				(island_removal_mode 0)
			)
			(polygon
				(pts
					(xy 375.079514 -334.126332) (xy 375.079514 -334.875632) (xy 380.079758 -334.875632) (xy 380.079758 -334.126332)
					(xy 379.789436 -334.126332) (xy 379.789436 -334.582008) (xy 375.369836 -334.582008) (xy 375.369836 -334.126332)
				)
			)
		)
		(zone
			(layer "F.Cu")
			(hatch none 0.5)
			(connect_pads
				(clearance 0)
			)
			(min_thickness 0.25)
			(keepout
				(tracks not_allowed)
				(vias allowed)
				(pads allowed)
				(copperpour not_allowed)
				(footprints allowed)
			)
			(placement
				(enabled no)
				(sheetname "")
			)
			(fill
				(thermal_gap 0.5)
				(thermal_bridge_width 0.5)
				(island_removal_mode 0)
			)
			(polygon
				(pts
					(xy 375.53519 -337.429348) (xy 375.777506 -337.429348) (xy 375.777506 -337.372706) (xy 376.46356 -337.372706)
					(xy 376.46356 -337.058508) (xy 376.628914 -337.058508) (xy 376.628914 -336.377026) (xy 375.079514 -336.377026)
					(xy 375.079514 -336.833718) (xy 375.77522 -336.833718) (xy 375.77522 -336.67319) (xy 376.33402 -336.67319)
					(xy 376.33402 -337.07959) (xy 375.77522 -337.07959) (xy 375.77522 -336.859118) (xy 375.079514 -336.859118)
					(xy 375.079514 -336.986118) (xy 375.53519 -336.986118)
				)
			)
		)
	)
	(footprint ""
		(layer "F.Cu")
		(at 106.70921 -412.671768 180)
		(property "Reference" "R3355"
			(at 0 0 180)
			(layer "F.SilkS")
			(hide yes)
			(effects
				(font
					(size 1.27 1.27)
				)
			)
		)
		(property "Value" ""
			(at 0 0 180)
			(layer "F.Fab")
			(effects
				(font
					(size 1.27 1.27)
				)
			)
		)
		(duplicate_pad_numbers_are_jumpers no)
		(fp_line
			(start 0.7874 -0.4064)
			(end 0.7874 -0.00762)
			(stroke
				(width 0.1524)
				(type default)
			)
			(layer "F.SilkS")
		)
		(fp_line
			(start 0.43307 0.4064)
			(end -0.49149 0.4064)
			(stroke
				(width 0.1524)
				(type default)
			)
			(layer "F.SilkS")
		)
		(fp_line
			(start -0.7874 0.05842)
			(end -0.7874 -0.4064)
			(stroke
				(width 0.1524)
				(type default)
			)
			(layer "F.SilkS")
		)
		(fp_line
			(start -0.7874 -0.4064)
			(end 0.7874 -0.4064)
			(stroke
				(width 0.1524)
				(type default)
			)
			(layer "F.SilkS")
		)
		(fp_line
			(start 0.67945 0.3048)
			(end 0.120396 0.3048)
			(stroke
				(width 0.1)
				(type default)
			)
			(layer "F.Fab")
		)
		(fp_line
			(start 0.67945 -0.3048)
			(end 0.67945 0.3048)
			(stroke
				(width 0.1)
				(type default)
			)
			(layer "F.Fab")
		)
		(fp_line
			(start 0.12065 -0.2794)
			(end 0.12065 -0.3048)
			(stroke
				(width 0.1)
				(type default)
			)
			(layer "F.Fab")
		)
		(fp_line
			(start 0.12065 -0.3048)
			(end 0.67945 -0.3048)
			(stroke
				(width 0.1)
				(type default)
			)
			(layer "F.Fab")
		)
		(fp_line
			(start 0.120396 0.3048)
			(end 0.120396 0.2794)
			(stroke
				(width 0.1)
				(type default)
			)
			(layer "F.Fab")
		)
		(fp_line
			(start 0.120396 0.2794)
			(end -0.12065 0.2794)
			(stroke
				(width 0.1)
				(type default)
			)
			(layer "F.Fab")
		)
		(fp_line
			(start -0.12065 0.3048)
			(end -0.67945 0.3048)
			(stroke
				(width 0.1)
				(type default)
			)
			(layer "F.Fab")
		)
		(fp_line
			(start -0.12065 0.2794)
			(end -0.12065 0.3048)
			(stroke
				(width 0.1)
				(type default)
			)
			(layer "F.Fab")
		)
		(fp_line
			(start -0.12065 -0.2794)
			(end 0.12065 -0.2794)
			(stroke
				(width 0.1)
				(type default)
			)
			(layer "F.Fab")
		)
		(fp_line
			(start -0.12065 -0.305054)
			(end -0.12065 -0.2794)
			(stroke
				(width 0.1)
				(type default)
			)
			(layer "F.Fab")
		)
		(fp_line
			(start -0.67945 0.3048)
			(end -0.67945 -0.305054)
			(stroke
				(width 0.1)
				(type default)
			)
			(layer "F.Fab")
		)
		(fp_line
			(start -0.67945 -0.305054)
			(end -0.12065 -0.305054)
			(stroke
				(width 0.1)
				(type default)
			)
			(layer "F.Fab")
		)
		(pad "1" smd circle
			(at -0.40005 0 180)
			(size 0 0)
			(layers "F.Cu" "F.Mask" "F.Paste")
			(net "CLK_100M_GPU_2_R_DN")
		)
		(pad "2" smd circle
			(at 0.40005 0 180)
			(size 0 0)
			(layers "F.Cu" "F.Mask" "F.Paste")
			(net "CLK_100M_GPU_2_DN")
		)
	)
	(footprint ""
		(layer "F.Cu")
		(at 176.080928 -418.806122)
		(property "Reference" "R3433"
			(at 0 0 0)
			(layer "F.SilkS")
			(hide yes)
			(effects
				(font
					(size 1.27 1.27)
				)
			)
		)
		(property "Value" ""
			(at 0 0 0)
			(layer "F.Fab")
			(effects
				(font
					(size 1.27 1.27)
				)
			)
		)
		(duplicate_pad_numbers_are_jumpers no)
		(fp_line
			(start -0.7874 -0.4064)
			(end 0.7874 -0.4064)
			(stroke
				(width 0.1524)
				(type default)
			)
			(layer "F.SilkS")
		)
		(fp_line
			(start -0.7874 0.4064)
			(end -0.7874 -0.4064)
			(stroke
				(width 0.1524)
				(type default)
			)
			(layer "F.SilkS")
		)
		(fp_line
			(start 0.7874 -0.4064)
			(end 0.7874 0.4064)
			(stroke
				(width 0.1524)
				(type default)
			)
			(layer "F.SilkS")
		)
		(fp_line
			(start 0.7874 0.4064)
			(end -0.7874 0.4064)
			(stroke
				(width 0.1524)
				(type default)
			)
			(layer "F.SilkS")
		)
		(fp_line
			(start -0.67945 -0.305054)
			(end -0.12065 -0.305054)
			(stroke
				(width 0.1)
				(type default)
			)
			(layer "F.Fab")
		)
		(fp_line
			(start -0.67945 0.3048)
			(end -0.67945 -0.305054)
			(stroke
				(width 0.1)
				(type default)
			)
			(layer "F.Fab")
		)
		(fp_line
			(start -0.12065 -0.305054)
			(end -0.12065 -0.2794)
			(stroke
				(width 0.1)
				(type default)
			)
			(layer "F.Fab")
		)
		(fp_line
			(start -0.12065 -0.2794)
			(end 0.12065 -0.2794)
			(stroke
				(width 0.1)
				(type default)
			)
			(layer "F.Fab")
		)
		(fp_line
			(start -0.12065 0.2794)
			(end -0.12065 0.3048)
			(stroke
				(width 0.1)
				(type default)
			)
			(layer "F.Fab")
		)
		(fp_line
			(start -0.12065 0.3048)
			(end -0.67945 0.3048)
			(stroke
				(width 0.1)
				(type default)
			)
			(layer "F.Fab")
		)
		(fp_line
			(start 0.120396 0.2794)
			(end -0.12065 0.2794)
			(stroke
				(width 0.1)
				(type default)
			)
			(layer "F.Fab")
		)
		(fp_line
			(start 0.120396 0.3048)
			(end 0.120396 0.2794)
			(stroke
				(width 0.1)
				(type default)
			)
			(layer "F.Fab")
		)
		(fp_line
			(start 0.12065 -0.3048)
			(end 0.67945 -0.3048)
			(stroke
				(width 0.1)
				(type default)
			)
			(layer "F.Fab")
		)
		(fp_line
			(start 0.12065 -0.2794)
			(end 0.12065 -0.3048)
			(stroke
				(width 0.1)
				(type default)
			)
			(layer "F.Fab")
		)
		(fp_line
			(start 0.67945 -0.3048)
			(end 0.67945 0.3048)
			(stroke
				(width 0.1)
				(type default)
			)
			(layer "F.Fab")
		)
		(fp_line
			(start 0.67945 0.3048)
			(end 0.120396 0.3048)
			(stroke
				(width 0.1)
				(type default)
			)
			(layer "F.Fab")
		)
		(pad "1" smd circle
			(at -0.40005 0)
			(size 0 0)
			(layers "F.Cu" "F.Mask" "F.Paste")
			(net "P3V3_AUX")
		)
		(pad "2" smd circle
			(at 0.40005 0)
			(size 0 0)
			(layers "F.Cu" "F.Mask" "F.Paste")
			(net "GPU_BASE_HMC_READY_N")
		)
	)
	(footprint ""
		(layer "F.Cu")
		(at 80.925162 -25.358598 180)
		(property "Reference" "PR4522"
			(at 0 0 180)
			(layer "F.SilkS")
			(hide yes)
			(effects
				(font
					(size 1.27 1.27)
				)
			)
		)
		(property "Value" ""
			(at 0 0 180)
			(layer "F.Fab")
			(effects
				(font
					(size 1.27 1.27)
				)
			)
		)
		(duplicate_pad_numbers_are_jumpers no)
		(fp_line
			(start 0.7874 0.4064)
			(end -0.7874 0.4064)
			(stroke
				(width 0.1524)
				(type default)
			)
			(layer "F.SilkS")
		)
		(fp_line
			(start 0.7874 -0.4064)
			(end 0.7874 0.4064)
			(stroke
				(width 0.1524)
				(type default)
			)
			(layer "F.SilkS")
		)
		(fp_line
			(start -0.7874 0.4064)
			(end -0.7874 -0.4064)
			(stroke
				(width 0.1524)
				(type default)
			)
			(layer "F.SilkS")
		)
		(fp_line
			(start -0.7874 -0.4064)
			(end 0.7874 -0.4064)
			(stroke
				(width 0.1524)
				(type default)
			)
			(layer "F.SilkS")
		)
		(fp_line
			(start 0.67945 0.3048)
			(end 0.120396 0.3048)
			(stroke
				(width 0.1)
				(type default)
			)
			(layer "F.Fab")
		)
		(fp_line
			(start 0.67945 -0.3048)
			(end 0.67945 0.3048)
			(stroke
				(width 0.1)
				(type default)
			)
			(layer "F.Fab")
		)
		(fp_line
			(start 0.12065 -0.2794)
			(end 0.12065 -0.3048)
			(stroke
				(width 0.1)
				(type default)
			)
			(layer "F.Fab")
		)
		(fp_line
			(start 0.12065 -0.3048)
			(end 0.67945 -0.3048)
			(stroke
				(width 0.1)
				(type default)
			)
			(layer "F.Fab")
		)
		(fp_line
			(start 0.120396 0.3048)
			(end 0.120396 0.2794)
			(stroke
				(width 0.1)
				(type default)
			)
			(layer "F.Fab")
		)
		(fp_line
			(start 0.120396 0.2794)
			(end -0.12065 0.2794)
			(stroke
				(width 0.1)
				(type default)
			)
			(layer "F.Fab")
		)
		(fp_line
			(start -0.12065 0.3048)
			(end -0.67945 0.3048)
			(stroke
				(width 0.1)
				(type default)
			)
			(layer "F.Fab")
		)
		(fp_line
			(start -0.12065 0.2794)
			(end -0.12065 0.3048)
			(stroke
				(width 0.1)
				(type default)
			)
			(layer "F.Fab")
		)
		(fp_line
			(start -0.12065 -0.2794)
			(end 0.12065 -0.2794)
			(stroke
				(width 0.1)
				(type default)
			)
			(layer "F.Fab")
		)
		(fp_line
			(start -0.12065 -0.305054)
			(end -0.12065 -0.2794)
			(stroke
				(width 0.1)
				(type default)
			)
			(layer "F.Fab")
		)
		(fp_line
			(start -0.67945 0.3048)
			(end -0.67945 -0.305054)
			(stroke
				(width 0.1)
				(type default)
			)
			(layer "F.Fab")
		)
		(fp_line
			(start -0.67945 -0.305054)
			(end -0.12065 -0.305054)
			(stroke
				(width 0.1)
				(type default)
			)
			(layer "F.Fab")
		)
		(pad "1" smd circle
			(at -0.40005 0 180)
			(size 0 0)
			(layers "F.Cu" "F.Mask" "F.Paste")
			(net "P12V_OCP_V3_2")
		)
		(pad "2" smd circle
			(at 0.40005 0 180)
			(size 0 0)
			(layers "F.Cu" "F.Mask" "F.Paste")
			(net "P12V_OCP_GATE_2")
		)
	)
	(footprint ""
		(layer "F.Cu")
		(at 124.538994 -408.517344 -90)
		(property "Reference" "C1518"
			(at 0 0 270)
			(layer "F.SilkS")
			(hide yes)
			(effects
				(font
					(size 1.27 1.27)
				)
			)
		)
		(property "Value" ""
			(at 0 0 270)
			(layer "F.Fab")
			(effects
				(font
					(size 1.27 1.27)
				)
			)
		)
		(duplicate_pad_numbers_are_jumpers no)
		(fp_line
			(start -0.299974 0.150114)
			(end -0.299974 -0.150114)
			(stroke
				(width 0.1)
				(type default)
			)
			(layer "F.Fab")
		)
		(fp_line
			(start 0.299974 0.150114)
			(end -0.299974 0.150114)
			(stroke
				(width 0.1)
				(type default)
			)
			(layer "F.Fab")
		)
		(fp_line
			(start -0.299974 -0.150114)
			(end 0.299974 -0.150114)
			(stroke
				(width 0.1)
				(type default)
			)
			(layer "F.Fab")
		)
		(fp_line
			(start 0.299974 -0.150114)
			(end 0.299974 0.150114)
			(stroke
				(width 0.1)
				(type default)
			)
			(layer "F.Fab")
		)
		(pad "1" smd rect
			(at -0.2667 0 270)
			(size 0.3048 0.381)
			(layers "F.Cu" "F.Mask" "F.Paste")
			(net "P5E_CPU1_PE3_TX_C_DN<14>")
		)
		(pad "2" smd rect
			(at 0.2667 0 270)
			(size 0.3048 0.381)
			(layers "F.Cu" "F.Mask" "F.Paste")
			(net "P5E_CPU1_PE3_TX_DN<14>")
		)
	)
	(footprint ""
		(layer "F.Cu")
		(at 36.789106 -178.52009)
		(property "Reference" "PC1287"
			(at 0 0 0)
			(layer "F.SilkS")
			(hide yes)
			(effects
				(font
					(size 1.27 1.27)
				)
			)
		)
		(property "Value" ""
			(at 0 0 0)
			(layer "F.Fab")
			(effects
				(font
					(size 1.27 1.27)
				)
			)
		)
		(duplicate_pad_numbers_are_jumpers no)
		(fp_line
			(start -1.524 -0.762)
			(end 1.524 -0.762)
			(stroke
				(width 0.1524)
				(type default)
			)
			(layer "F.SilkS")
		)
		(fp_line
			(start -1.524 0.762)
			(end -1.524 -0.762)
			(stroke
				(width 0.1524)
				(type default)
			)
			(layer "F.SilkS")
		)
		(fp_line
			(start 1.524 -0.762)
			(end 1.524 0.762)
			(stroke
				(width 0.1524)
				(type default)
			)
			(layer "F.SilkS")
		)
		(fp_line
			(start 1.524 0.762)
			(end -1.524 0.762)
			(stroke
				(width 0.1524)
				(type default)
			)
			(layer "F.SilkS")
		)
		(fp_line
			(start -1.1049 -0.724916)
			(end -1.1049 0.724916)
			(stroke
				(width 0.1)
				(type default)
			)
			(layer "F.Fab")
		)
		(fp_line
			(start -1.1049 0.724916)
			(end 1.1049 0.724916)
			(stroke
				(width 0.1)
				(type default)
			)
			(layer "F.Fab")
		)
		(fp_line
			(start 1.1049 -0.724916)
			(end -1.1049 -0.724916)
			(stroke
				(width 0.1)
				(type default)
			)
			(layer "F.Fab")
		)
		(fp_line
			(start 1.1049 0.724916)
			(end 1.1049 -0.724916)
			(stroke
				(width 0.1)
				(type default)
			)
			(layer "F.Fab")
		)
		(pad "1" smd rect
			(at -0.889 0 180)
			(size 1.016 1.27)
			(layers "F.Cu" "F.Mask" "F.Paste")
			(net "PVNN_MAIN_CPU1")
		)
		(pad "2" smd rect
			(at 0.889 0 180)
			(size 1.016 1.27)
			(layers "F.Cu" "F.Mask" "F.Paste")
			(net "GND")
		)
	)
	(footprint ""
		(layer "F.Cu")
		(at 365.46663 -245.634002 -90)
		(property "Reference" "C1001"
			(at 0 0 270)
			(layer "F.SilkS")
			(hide yes)
			(effects
				(font
					(size 1.27 1.27)
				)
			)
		)
		(property "Value" ""
			(at 0 0 270)
			(layer "F.Fab")
			(effects
				(font
					(size 1.27 1.27)
				)
			)
		)
		(duplicate_pad_numbers_are_jumpers no)
		(fp_line
			(start -0.7874 0.4064)
			(end -0.7874 -0.4064)
			(stroke
				(width 0.1524)
				(type default)
			)
			(layer "F.SilkS")
		)
		(fp_line
			(start 0.7874 0.4064)
			(end -0.7874 0.4064)
			(stroke
				(width 0.1524)
				(type default)
			)
			(layer "F.SilkS")
		)
		(fp_line
			(start -0.7874 -0.4064)
			(end 0.7874 -0.4064)
			(stroke
				(width 0.1524)
				(type default)
			)
			(layer "F.SilkS")
		)
		(fp_line
			(start 0.7874 -0.4064)
			(end 0.7874 0.4064)
			(stroke
				(width 0.1524)
				(type default)
			)
			(layer "F.SilkS")
		)
		(fp_line
			(start -0.67945 0.3048)
			(end -0.67945 -0.305054)
			(stroke
				(width 0.1)
				(type default)
			)
			(layer "F.Fab")
		)
		(fp_line
			(start -0.12065 0.3048)
			(end -0.67945 0.3048)
			(stroke
				(width 0.1)
				(type default)
			)
			(layer "F.Fab")
		)
		(fp_line
			(start 0.120396 0.3048)
			(end 0.120396 0.2794)
			(stroke
				(width 0.1)
				(type default)
			)
			(layer "F.Fab")
		)
		(fp_line
			(start 0.67945 0.3048)
			(end 0.120396 0.3048)
			(stroke
				(width 0.1)
				(type default)
			)
			(layer "F.Fab")
		)
		(fp_line
			(start -0.12065 0.2794)
			(end -0.12065 0.3048)
			(stroke
				(width 0.1)
				(type default)
			)
			(layer "F.Fab")
		)
		(fp_line
			(start 0.120396 0.2794)
			(end -0.12065 0.2794)
			(stroke
				(width 0.1)
				(type default)
			)
			(layer "F.Fab")
		)
		(fp_line
			(start -0.12065 -0.2794)
			(end 0.12065 -0.2794)
			(stroke
				(width 0.1)
				(type default)
			)
			(layer "F.Fab")
		)
		(fp_line
			(start 0.12065 -0.2794)
			(end 0.12065 -0.3048)
			(stroke
				(width 0.1)
				(type default)
			)
			(layer "F.Fab")
		)
		(fp_line
			(start 0.12065 -0.3048)
			(end 0.67945 -0.3048)
			(stroke
				(width 0.1)
				(type default)
			)
			(layer "F.Fab")
		)
		(fp_line
			(start 0.67945 -0.3048)
			(end 0.67945 0.3048)
			(stroke
				(width 0.1)
				(type default)
			)
			(layer "F.Fab")
		)
		(fp_line
			(start -0.67945 -0.305054)
			(end -0.12065 -0.305054)
			(stroke
				(width 0.1)
				(type default)
			)
			(layer "F.Fab")
		)
		(fp_line
			(start -0.12065 -0.305054)
			(end -0.12065 -0.2794)
			(stroke
				(width 0.1)
				(type default)
			)
			(layer "F.Fab")
		)
		(pad "1" smd circle
			(at -0.40005 0 270)
			(size 0 0)
			(layers "F.Cu" "F.Mask" "F.Paste")
			(net "PVCCIN_CPU0")
		)
		(pad "2" smd circle
			(at 0.40005 0 270)
			(size 0 0)
			(layers "F.Cu" "F.Mask" "F.Paste")
			(net "GND")
		)
	)
	(footprint ""
		(layer "F.Cu")
		(at 164.64788 -116.296948)
		(property "Reference" "R1551"
			(at 0 0 0)
			(layer "F.SilkS")
			(hide yes)
			(effects
				(font
					(size 1.27 1.27)
				)
			)
		)
		(property "Value" ""
			(at 0 0 0)
			(layer "F.Fab")
			(effects
				(font
					(size 1.27 1.27)
				)
			)
		)
		(duplicate_pad_numbers_are_jumpers no)
		(fp_line
			(start -0.7874 -0.4064)
			(end 0.7874 -0.4064)
			(stroke
				(width 0.1524)
				(type default)
			)
			(layer "F.SilkS")
		)
		(fp_line
			(start -0.7874 0.4064)
			(end -0.7874 -0.4064)
			(stroke
				(width 0.1524)
				(type default)
			)
			(layer "F.SilkS")
		)
		(fp_line
			(start 0.7874 -0.4064)
			(end 0.7874 0.4064)
			(stroke
				(width 0.1524)
				(type default)
			)
			(layer "F.SilkS")
		)
		(fp_line
			(start 0.7874 0.4064)
			(end -0.7874 0.4064)
			(stroke
				(width 0.1524)
				(type default)
			)
			(layer "F.SilkS")
		)
		(fp_line
			(start -0.67945 -0.305054)
			(end -0.12065 -0.305054)
			(stroke
				(width 0.1)
				(type default)
			)
			(layer "F.Fab")
		)
		(fp_line
			(start -0.67945 0.3048)
			(end -0.67945 -0.305054)
			(stroke
				(width 0.1)
				(type default)
			)
			(layer "F.Fab")
		)
		(fp_line
			(start -0.12065 -0.305054)
			(end -0.12065 -0.2794)
			(stroke
				(width 0.1)
				(type default)
			)
			(layer "F.Fab")
		)
		(fp_line
			(start -0.12065 -0.2794)
			(end 0.12065 -0.2794)
			(stroke
				(width 0.1)
				(type default)
			)
			(layer "F.Fab")
		)
		(fp_line
			(start -0.12065 0.2794)
			(end -0.12065 0.3048)
			(stroke
				(width 0.1)
				(type default)
			)
			(layer "F.Fab")
		)
		(fp_line
			(start -0.12065 0.3048)
			(end -0.67945 0.3048)
			(stroke
				(width 0.1)
				(type default)
			)
			(layer "F.Fab")
		)
		(fp_line
			(start 0.120396 0.2794)
			(end -0.12065 0.2794)
			(stroke
				(width 0.1)
				(type default)
			)
			(layer "F.Fab")
		)
		(fp_line
			(start 0.120396 0.3048)
			(end 0.120396 0.2794)
			(stroke
				(width 0.1)
				(type default)
			)
			(layer "F.Fab")
		)
		(fp_line
			(start 0.12065 -0.3048)
			(end 0.67945 -0.3048)
			(stroke
				(width 0.1)
				(type default)
			)
			(layer "F.Fab")
		)
		(fp_line
			(start 0.12065 -0.2794)
			(end 0.12065 -0.3048)
			(stroke
				(width 0.1)
				(type default)
			)
			(layer "F.Fab")
		)
		(fp_line
			(start 0.67945 -0.3048)
			(end 0.67945 0.3048)
			(stroke
				(width 0.1)
				(type default)
			)
			(layer "F.Fab")
		)
		(fp_line
			(start 0.67945 0.3048)
			(end 0.120396 0.3048)
			(stroke
				(width 0.1)
				(type default)
			)
			(layer "F.Fab")
		)
		(pad "1" smd circle
			(at -0.40005 0)
			(size 0 0)
			(layers "F.Cu" "F.Mask" "F.Paste")
			(net "P3V3_AUX")
		)
		(pad "2" smd circle
			(at 0.40005 0)
			(size 0 0)
			(layers "F.Cu" "F.Mask" "F.Paste")
			(net "SMB_1_PLD_3V3AUX_SDA_R1")
		)
	)
	(footprint ""
		(layer "F.Cu")
		(at 247.627394 -88.343486 -90)
		(property "Reference" "Y2"
			(at -0.708406 -3.345688 0)
			(unlocked yes)
			(layer "F.SilkS")
			(effects
				(font
					(size 0.7874 0.5842)
					(thickness 0.1524)
				)
				(justify left)
			)
		)
		(property "Value" ""
			(at 0 0 270)
			(layer "F.Fab")
			(effects
				(font
					(size 1.27 1.27)
				)
			)
		)
		(duplicate_pad_numbers_are_jumpers no)
		(fp_line
			(start -1.538732 1.937004)
			(end -1.538732 -1.937004)
			(stroke
				(width 0.1524)
				(type default)
			)
			(layer "F.SilkS")
		)
		(fp_line
			(start 1.538732 1.937004)
			(end -1.538732 1.937004)
			(stroke
				(width 0.1524)
				(type default)
			)
			(layer "F.SilkS")
		)
		(fp_line
			(start -1.538732 -1.937004)
			(end 1.538732 -1.937004)
			(stroke
				(width 0.1524)
				(type default)
			)
			(layer "F.SilkS")
		)
		(fp_line
			(start 1.538732 -1.937004)
			(end 1.538732 1.937004)
			(stroke
				(width 0.1524)
				(type default)
			)
			(layer "F.SilkS")
		)
		(fp_poly
			(pts
				(xy -1.168908 -3.171952) (xy -0.302514 -3.171952) (xy -0.735838 -2.305558)
			)
			(stroke
				(width 0)
				(type default)
			)
			(fill yes)
			(layer "F.SilkS")
		)
		(fp_line
			(start -1.299972 1.649984)
			(end -1.299972 -1.649984)
			(stroke
				(width 0.1)
				(type default)
			)
			(layer "F.Fab")
		)
		(fp_line
			(start 1.299972 1.649984)
			(end -1.299972 1.649984)
			(stroke
				(width 0.1)
				(type default)
			)
			(layer "F.Fab")
		)
		(fp_line
			(start -1.299972 -1.649984)
			(end 1.299972 -1.649984)
			(stroke
				(width 0.1)
				(type default)
			)
			(layer "F.Fab")
		)
		(fp_line
			(start 1.299972 -1.649984)
			(end 1.299972 1.649984)
			(stroke
				(width 0.1)
				(type default)
			)
			(layer "F.Fab")
		)
		(fp_poly
			(pts
				(xy -2.5908 -0.626872) (xy -2.5908 -1.493266) (xy -1.724406 -1.059942)
			)
			(stroke
				(width 0)
				(type default)
			)
			(fill yes)
			(layer "F.Fab")
		)
		(pad "1" smd rect
			(at -0.8001 -1.059942 270)
			(size 1.2192 1.4986)
			(layers "F.Cu" "F.Mask" "F.Paste")
			(net "XTAL_CLK_GEN1_25M_X1_R")
		)
		(pad "2" smd rect
			(at -0.8001 1.059942 270)
			(size 1.2192 1.4986)
			(layers "F.Cu" "F.Mask" "F.Paste")
			(net "GND")
		)
		(pad "3" smd rect
			(at 0.8001 1.059942 270)
			(size 1.2192 1.4986)
			(layers "F.Cu" "F.Mask" "F.Paste")
			(net "XTAL_CLK_GEN1_25M_X2")
		)
		(pad "4" smd rect
			(at 0.8001 -1.059942 270)
			(size 1.2192 1.4986)
			(layers "F.Cu" "F.Mask" "F.Paste")
			(net "GND")
		)
	)
	(footprint ""
		(layer "F.Cu")
		(at 33.065974 -163.475162)
		(property "Reference" "PR705"
			(at 0 0 0)
			(layer "F.SilkS")
			(hide yes)
			(effects
				(font
					(size 1.27 1.27)
				)
			)
		)
		(property "Value" ""
			(at 0 0 0)
			(layer "F.Fab")
			(effects
				(font
					(size 1.27 1.27)
				)
			)
		)
		(duplicate_pad_numbers_are_jumpers no)
		(fp_line
			(start -0.7874 -0.4064)
			(end 0.7874 -0.4064)
			(stroke
				(width 0.1524)
				(type default)
			)
			(layer "F.SilkS")
		)
		(fp_line
			(start -0.7874 0.4064)
			(end -0.7874 -0.4064)
			(stroke
				(width 0.1524)
				(type default)
			)
			(layer "F.SilkS")
		)
		(fp_line
			(start 0.7874 -0.4064)
			(end 0.7874 0.4064)
			(stroke
				(width 0.1524)
				(type default)
			)
			(layer "F.SilkS")
		)
		(fp_line
			(start 0.7874 0.4064)
			(end -0.7874 0.4064)
			(stroke
				(width 0.1524)
				(type default)
			)
			(layer "F.SilkS")
		)
		(fp_line
			(start -0.67945 -0.305054)
			(end -0.12065 -0.305054)
			(stroke
				(width 0.1)
				(type default)
			)
			(layer "F.Fab")
		)
		(fp_line
			(start -0.67945 0.3048)
			(end -0.67945 -0.305054)
			(stroke
				(width 0.1)
				(type default)
			)
			(layer "F.Fab")
		)
		(fp_line
			(start -0.12065 -0.305054)
			(end -0.12065 -0.2794)
			(stroke
				(width 0.1)
				(type default)
			)
			(layer "F.Fab")
		)
		(fp_line
			(start -0.12065 -0.2794)
			(end 0.12065 -0.2794)
			(stroke
				(width 0.1)
				(type default)
			)
			(layer "F.Fab")
		)
		(fp_line
			(start -0.12065 0.2794)
			(end -0.12065 0.3048)
			(stroke
				(width 0.1)
				(type default)
			)
			(layer "F.Fab")
		)
		(fp_line
			(start -0.12065 0.3048)
			(end -0.67945 0.3048)
			(stroke
				(width 0.1)
				(type default)
			)
			(layer "F.Fab")
		)
		(fp_line
			(start 0.120396 0.2794)
			(end -0.12065 0.2794)
			(stroke
				(width 0.1)
				(type default)
			)
			(layer "F.Fab")
		)
		(fp_line
			(start 0.120396 0.3048)
			(end 0.120396 0.2794)
			(stroke
				(width 0.1)
				(type default)
			)
			(layer "F.Fab")
		)
		(fp_line
			(start 0.12065 -0.3048)
			(end 0.67945 -0.3048)
			(stroke
				(width 0.1)
				(type default)
			)
			(layer "F.Fab")
		)
		(fp_line
			(start 0.12065 -0.2794)
			(end 0.12065 -0.3048)
			(stroke
				(width 0.1)
				(type default)
			)
			(layer "F.Fab")
		)
		(fp_line
			(start 0.67945 -0.3048)
			(end 0.67945 0.3048)
			(stroke
				(width 0.1)
				(type default)
			)
			(layer "F.Fab")
		)
		(fp_line
			(start 0.67945 0.3048)
			(end 0.120396 0.3048)
			(stroke
				(width 0.1)
				(type default)
			)
			(layer "F.Fab")
		)
		(pad "1" smd circle
			(at -0.40005 0)
			(size 0 0)
			(layers "F.Cu" "F.Mask" "F.Paste")
			(net "PVCCD_HV_CPU1_ATSEN")
		)
		(pad "2" smd circle
			(at 0.40005 0)
			(size 0 0)
			(layers "F.Cu" "F.Mask" "F.Paste")
			(net "GND")
		)
	)
	(footprint ""
		(layer "F.Cu")
		(at 173.216062 -31.34868 180)
		(property "Reference" "R4709"
			(at 0 0 180)
			(layer "F.SilkS")
			(hide yes)
			(effects
				(font
					(size 1.27 1.27)
				)
			)
		)
		(property "Value" ""
			(at 0 0 180)
			(layer "F.Fab")
			(effects
				(font
					(size 1.27 1.27)
				)
			)
		)
		(duplicate_pad_numbers_are_jumpers no)
		(fp_line
			(start 0.7874 0.4064)
			(end -0.7874 0.4064)
			(stroke
				(width 0.1524)
				(type default)
			)
			(layer "F.SilkS")
		)
		(fp_line
			(start 0.7874 -0.4064)
			(end 0.7874 0.4064)
			(stroke
				(width 0.1524)
				(type default)
			)
			(layer "F.SilkS")
		)
		(fp_line
			(start -0.7874 0.4064)
			(end -0.7874 -0.4064)
			(stroke
				(width 0.1524)
				(type default)
			)
			(layer "F.SilkS")
		)
		(fp_line
			(start -0.7874 -0.4064)
			(end 0.7874 -0.4064)
			(stroke
				(width 0.1524)
				(type default)
			)
			(layer "F.SilkS")
		)
		(fp_line
			(start 0.67945 0.3048)
			(end 0.120396 0.3048)
			(stroke
				(width 0.1)
				(type default)
			)
			(layer "F.Fab")
		)
		(fp_line
			(start 0.67945 -0.3048)
			(end 0.67945 0.3048)
			(stroke
				(width 0.1)
				(type default)
			)
			(layer "F.Fab")
		)
		(fp_line
			(start 0.12065 -0.2794)
			(end 0.12065 -0.3048)
			(stroke
				(width 0.1)
				(type default)
			)
			(layer "F.Fab")
		)
		(fp_line
			(start 0.12065 -0.3048)
			(end 0.67945 -0.3048)
			(stroke
				(width 0.1)
				(type default)
			)
			(layer "F.Fab")
		)
		(fp_line
			(start 0.120396 0.3048)
			(end 0.120396 0.2794)
			(stroke
				(width 0.1)
				(type default)
			)
			(layer "F.Fab")
		)
		(fp_line
			(start 0.120396 0.2794)
			(end -0.12065 0.2794)
			(stroke
				(width 0.1)
				(type default)
			)
			(layer "F.Fab")
		)
		(fp_line
			(start -0.12065 0.3048)
			(end -0.67945 0.3048)
			(stroke
				(width 0.1)
				(type default)
			)
			(layer "F.Fab")
		)
		(fp_line
			(start -0.12065 0.2794)
			(end -0.12065 0.3048)
			(stroke
				(width 0.1)
				(type default)
			)
			(layer "F.Fab")
		)
		(fp_line
			(start -0.12065 -0.2794)
			(end 0.12065 -0.2794)
			(stroke
				(width 0.1)
				(type default)
			)
			(layer "F.Fab")
		)
		(fp_line
			(start -0.12065 -0.305054)
			(end -0.12065 -0.2794)
			(stroke
				(width 0.1)
				(type default)
			)
			(layer "F.Fab")
		)
		(fp_line
			(start -0.67945 0.3048)
			(end -0.67945 -0.305054)
			(stroke
				(width 0.1)
				(type default)
			)
			(layer "F.Fab")
		)
		(fp_line
			(start -0.67945 -0.305054)
			(end -0.12065 -0.305054)
			(stroke
				(width 0.1)
				(type default)
			)
			(layer "F.Fab")
		)
		(pad "1" smd circle
			(at -0.40005 0 180)
			(size 0 0)
			(layers "F.Cu" "F.Mask" "F.Paste")
			(net "P12V_SCM_FLTB_N")
		)
		(pad "2" smd circle
			(at 0.40005 0 180)
			(size 0 0)
			(layers "F.Cu" "F.Mask" "F.Paste")
			(net "P12V_SCM_FAULT_R_N")
		)
	)
	(footprint ""
		(layer "F.Cu")
		(at 192.052448 -403.144482)
		(property "Reference" "R2588"
			(at 0 0 0)
			(layer "F.SilkS")
			(hide yes)
			(effects
				(font
					(size 1.27 1.27)
				)
			)
		)
		(property "Value" ""
			(at 0 0 0)
			(layer "F.Fab")
			(effects
				(font
					(size 1.27 1.27)
				)
			)
		)
		(duplicate_pad_numbers_are_jumpers no)
		(fp_line
			(start -0.7874 -0.4064)
			(end 0.7874 -0.4064)
			(stroke
				(width 0.1524)
				(type default)
			)
			(layer "F.SilkS")
		)
		(fp_line
			(start -0.7874 0.4064)
			(end -0.7874 -0.4064)
			(stroke
				(width 0.1524)
				(type default)
			)
			(layer "F.SilkS")
		)
		(fp_line
			(start 0.7874 -0.4064)
			(end 0.7874 0.4064)
			(stroke
				(width 0.1524)
				(type default)
			)
			(layer "F.SilkS")
		)
		(fp_line
			(start 0.7874 0.4064)
			(end -0.7874 0.4064)
			(stroke
				(width 0.1524)
				(type default)
			)
			(layer "F.SilkS")
		)
		(fp_line
			(start -0.67945 -0.305054)
			(end -0.12065 -0.305054)
			(stroke
				(width 0.1)
				(type default)
			)
			(layer "F.Fab")
		)
		(fp_line
			(start -0.67945 0.3048)
			(end -0.67945 -0.305054)
			(stroke
				(width 0.1)
				(type default)
			)
			(layer "F.Fab")
		)
		(fp_line
			(start -0.12065 -0.305054)
			(end -0.12065 -0.2794)
			(stroke
				(width 0.1)
				(type default)
			)
			(layer "F.Fab")
		)
		(fp_line
			(start -0.12065 -0.2794)
			(end 0.12065 -0.2794)
			(stroke
				(width 0.1)
				(type default)
			)
			(layer "F.Fab")
		)
		(fp_line
			(start -0.12065 0.2794)
			(end -0.12065 0.3048)
			(stroke
				(width 0.1)
				(type default)
			)
			(layer "F.Fab")
		)
		(fp_line
			(start -0.12065 0.3048)
			(end -0.67945 0.3048)
			(stroke
				(width 0.1)
				(type default)
			)
			(layer "F.Fab")
		)
		(fp_line
			(start 0.120396 0.2794)
			(end -0.12065 0.2794)
			(stroke
				(width 0.1)
				(type default)
			)
			(layer "F.Fab")
		)
		(fp_line
			(start 0.120396 0.3048)
			(end 0.120396 0.2794)
			(stroke
				(width 0.1)
				(type default)
			)
			(layer "F.Fab")
		)
		(fp_line
			(start 0.12065 -0.3048)
			(end 0.67945 -0.3048)
			(stroke
				(width 0.1)
				(type default)
			)
			(layer "F.Fab")
		)
		(fp_line
			(start 0.12065 -0.2794)
			(end 0.12065 -0.3048)
			(stroke
				(width 0.1)
				(type default)
			)
			(layer "F.Fab")
		)
		(fp_line
			(start 0.67945 -0.3048)
			(end 0.67945 0.3048)
			(stroke
				(width 0.1)
				(type default)
			)
			(layer "F.Fab")
		)
		(fp_line
			(start 0.67945 0.3048)
			(end 0.120396 0.3048)
			(stroke
				(width 0.1)
				(type default)
			)
			(layer "F.Fab")
		)
		(pad "1" smd circle
			(at -0.40005 0)
			(size 0 0)
			(layers "F.Cu" "F.Mask" "F.Paste")
			(net "HSC_FAULT")
		)
		(pad "2" smd circle
			(at 0.40005 0)
			(size 0 0)
			(layers "F.Cu" "F.Mask" "F.Paste")
			(net "IRQ_HSC_FAULT_N")
		)
	)
	(footprint ""
		(layer "F.Cu")
		(at 386.461 -31.968948 180)
		(property "Reference" "U322"
			(at 5.588 -0.15367 0)
			(unlocked yes)
			(layer "F.SilkS")
			(effects
				(font
					(size 0.7874 0.5842)
					(thickness 0.1524)
				)
				(justify left)
			)
		)
		(property "Value" ""
			(at 0 0 180)
			(layer "F.Fab")
			(effects
				(font
					(size 1.27 1.27)
				)
			)
		)
		(duplicate_pad_numbers_are_jumpers no)
		(fp_line
			(start 1.733296 1.549908)
			(end 1.733296 -1.549908)
			(stroke
				(width 0.1524)
				(type default)
			)
			(layer "F.SilkS")
		)
		(fp_line
			(start 1.733296 -1.549908)
			(end 0.660908 -1.549908)
			(stroke
				(width 0.1524)
				(type default)
			)
			(layer "F.SilkS")
		)
		(fp_line
			(start 0.660908 -1.549908)
			(end 0 -0.889)
			(stroke
				(width 0.1524)
				(type default)
			)
			(layer "F.SilkS")
		)
		(fp_line
			(start 0 -0.889)
			(end -0.660908 -1.549908)
			(stroke
				(width 0.1524)
				(type default)
			)
			(layer "F.SilkS")
		)
		(fp_line
			(start -0.660908 -1.549908)
			(end -1.733296 -1.549908)
			(stroke
				(width 0.1524)
				(type default)
			)
			(layer "F.SilkS")
		)
		(fp_line
			(start -1.733296 1.549908)
			(end 1.733296 1.549908)
			(stroke
				(width 0.1524)
				(type default)
			)
			(layer "F.SilkS")
		)
		(fp_line
			(start -1.733296 -1.549908)
			(end -1.733296 1.549908)
			(stroke
				(width 0.1524)
				(type default)
			)
			(layer "F.SilkS")
		)
		(fp_poly
			(pts
				(xy -2.4384 -1.20396) (xy -2.4384 -0.69596) (xy -1.9304 -0.94996)
			)
			(stroke
				(width 0)
				(type default)
			)
			(fill yes)
			(layer "F.SilkS")
		)
		(fp_line
			(start 0.849884 1.549908)
			(end 0.849884 -1.549908)
			(stroke
				(width 0.1)
				(type default)
			)
			(layer "F.Fab")
		)
		(fp_line
			(start 0.849884 -1.549908)
			(end -0.849884 -1.549908)
			(stroke
				(width 0.1)
				(type default)
			)
			(layer "F.Fab")
		)
		(fp_line
			(start -0.849884 1.549908)
			(end 0.849884 1.549908)
			(stroke
				(width 0.1)
				(type default)
			)
			(layer "F.Fab")
		)
		(fp_line
			(start -0.849884 -1.549908)
			(end -0.849884 1.549908)
			(stroke
				(width 0.1)
				(type default)
			)
			(layer "F.Fab")
		)
		(fp_poly
			(pts
				(xy -2.4384 -1.20396) (xy -2.4384 -0.69596) (xy -1.9304 -0.94996)
			)
			(stroke
				(width 0)
				(type default)
			)
			(fill yes)
			(layer "F.Fab")
		)
		(pad "1" smd rect
			(at -1.199896 -0.94996 90)
			(size 0.5588 0.8128)
			(layers "F.Cu" "F.Mask" "F.Paste")
			(net "HP_OCP_V3_1_RST_R")
		)
		(pad "2" smd rect
			(at -1.199896 0 90)
			(size 0.5588 0.8128)
			(layers "F.Cu" "F.Mask" "F.Paste")
			(net "HP_LVC3_OCP_V3_1_P12V_PWRGD")
		)
		(pad "3" smd rect
			(at -1.199896 0.94996 90)
			(size 0.5588 0.8128)
			(layers "F.Cu" "F.Mask" "F.Paste")
			(net "GND")
		)
		(pad "4" smd rect
			(at 1.199896 0.94996 90)
			(size 0.5588 0.8128)
			(layers "F.Cu" "F.Mask" "F.Paste")
			(net "HP_LVC3_OCP_V3_1_PWRGD")
		)
		(pad "5" smd rect
			(at 1.199896 -0.94996 90)
			(size 0.5588 0.8128)
			(layers "F.Cu" "F.Mask" "F.Paste")
			(net "P3V3_AUX")
		)
	)
	(footprint ""
		(layer "F.Cu")
		(at 320.190622 -59.299348)
		(property "Reference" "R1220"
			(at 0 0 0)
			(layer "F.SilkS")
			(hide yes)
			(effects
				(font
					(size 1.27 1.27)
				)
			)
		)
		(property "Value" ""
			(at 0 0 0)
			(layer "F.Fab")
			(effects
				(font
					(size 1.27 1.27)
				)
			)
		)
		(duplicate_pad_numbers_are_jumpers no)
		(fp_line
			(start -0.7874 -0.4064)
			(end 0.7874 -0.4064)
			(stroke
				(width 0.1524)
				(type default)
			)
			(layer "F.SilkS")
		)
		(fp_line
			(start -0.7874 0.4064)
			(end -0.7874 -0.4064)
			(stroke
				(width 0.1524)
				(type default)
			)
			(layer "F.SilkS")
		)
		(fp_line
			(start 0.7874 -0.4064)
			(end 0.7874 0.4064)
			(stroke
				(width 0.1524)
				(type default)
			)
			(layer "F.SilkS")
		)
		(fp_line
			(start 0.7874 0.4064)
			(end -0.7874 0.4064)
			(stroke
				(width 0.1524)
				(type default)
			)
			(layer "F.SilkS")
		)
		(fp_line
			(start -0.67945 -0.305054)
			(end -0.12065 -0.305054)
			(stroke
				(width 0.1)
				(type default)
			)
			(layer "F.Fab")
		)
		(fp_line
			(start -0.67945 0.3048)
			(end -0.67945 -0.305054)
			(stroke
				(width 0.1)
				(type default)
			)
			(layer "F.Fab")
		)
		(fp_line
			(start -0.12065 -0.305054)
			(end -0.12065 -0.2794)
			(stroke
				(width 0.1)
				(type default)
			)
			(layer "F.Fab")
		)
		(fp_line
			(start -0.12065 -0.2794)
			(end 0.12065 -0.2794)
			(stroke
				(width 0.1)
				(type default)
			)
			(layer "F.Fab")
		)
		(fp_line
			(start -0.12065 0.2794)
			(end -0.12065 0.3048)
			(stroke
				(width 0.1)
				(type default)
			)
			(layer "F.Fab")
		)
		(fp_line
			(start -0.12065 0.3048)
			(end -0.67945 0.3048)
			(stroke
				(width 0.1)
				(type default)
			)
			(layer "F.Fab")
		)
		(fp_line
			(start 0.120396 0.2794)
			(end -0.12065 0.2794)
			(stroke
				(width 0.1)
				(type default)
			)
			(layer "F.Fab")
		)
		(fp_line
			(start 0.120396 0.3048)
			(end 0.120396 0.2794)
			(stroke
				(width 0.1)
				(type default)
			)
			(layer "F.Fab")
		)
		(fp_line
			(start 0.12065 -0.3048)
			(end 0.67945 -0.3048)
			(stroke
				(width 0.1)
				(type default)
			)
			(layer "F.Fab")
		)
		(fp_line
			(start 0.12065 -0.2794)
			(end 0.12065 -0.3048)
			(stroke
				(width 0.1)
				(type default)
			)
			(layer "F.Fab")
		)
		(fp_line
			(start 0.67945 -0.3048)
			(end 0.67945 0.3048)
			(stroke
				(width 0.1)
				(type default)
			)
			(layer "F.Fab")
		)
		(fp_line
			(start 0.67945 0.3048)
			(end 0.120396 0.3048)
			(stroke
				(width 0.1)
				(type default)
			)
			(layer "F.Fab")
		)
		(pad "1" smd circle
			(at -0.40005 0)
			(size 0 0)
			(layers "F.Cu" "F.Mask" "F.Paste")
			(net "P3V3_AUX")
		)
		(pad "2" smd circle
			(at 0.40005 0)
			(size 0 0)
			(layers "F.Cu" "F.Mask" "F.Paste")
			(net "FM_PCH_MCRO_LDO")
		)
	)
	(footprint ""
		(layer "F.Cu")
		(at 333.23784 -13.718032 -90)
		(property "Reference" "C1647"
			(at 0 0 270)
			(layer "F.SilkS")
			(hide yes)
			(effects
				(font
					(size 1.27 1.27)
				)
			)
		)
		(property "Value" ""
			(at 0 0 270)
			(layer "F.Fab")
			(effects
				(font
					(size 1.27 1.27)
				)
			)
		)
		(duplicate_pad_numbers_are_jumpers no)
		(fp_line
			(start -0.7874 0.4064)
			(end -0.7874 -0.4064)
			(stroke
				(width 0.1524)
				(type default)
			)
			(layer "F.SilkS")
		)
		(fp_line
			(start 0.7874 0.4064)
			(end -0.7874 0.4064)
			(stroke
				(width 0.1524)
				(type default)
			)
			(layer "F.SilkS")
		)
		(fp_line
			(start -0.7874 -0.4064)
			(end 0.7874 -0.4064)
			(stroke
				(width 0.1524)
				(type default)
			)
			(layer "F.SilkS")
		)
		(fp_line
			(start 0.7874 -0.4064)
			(end 0.7874 0.4064)
			(stroke
				(width 0.1524)
				(type default)
			)
			(layer "F.SilkS")
		)
		(fp_line
			(start -0.67945 0.3048)
			(end -0.67945 -0.305054)
			(stroke
				(width 0.1)
				(type default)
			)
			(layer "F.Fab")
		)
		(fp_line
			(start -0.12065 0.3048)
			(end -0.67945 0.3048)
			(stroke
				(width 0.1)
				(type default)
			)
			(layer "F.Fab")
		)
		(fp_line
			(start 0.120396 0.3048)
			(end 0.120396 0.2794)
			(stroke
				(width 0.1)
				(type default)
			)
			(layer "F.Fab")
		)
		(fp_line
			(start 0.67945 0.3048)
			(end 0.120396 0.3048)
			(stroke
				(width 0.1)
				(type default)
			)
			(layer "F.Fab")
		)
		(fp_line
			(start -0.12065 0.2794)
			(end -0.12065 0.3048)
			(stroke
				(width 0.1)
				(type default)
			)
			(layer "F.Fab")
		)
		(fp_line
			(start 0.120396 0.2794)
			(end -0.12065 0.2794)
			(stroke
				(width 0.1)
				(type default)
			)
			(layer "F.Fab")
		)
		(fp_line
			(start -0.12065 -0.2794)
			(end 0.12065 -0.2794)
			(stroke
				(width 0.1)
				(type default)
			)
			(layer "F.Fab")
		)
		(fp_line
			(start 0.12065 -0.2794)
			(end 0.12065 -0.3048)
			(stroke
				(width 0.1)
				(type default)
			)
			(layer "F.Fab")
		)
		(fp_line
			(start 0.12065 -0.3048)
			(end 0.67945 -0.3048)
			(stroke
				(width 0.1)
				(type default)
			)
			(layer "F.Fab")
		)
		(fp_line
			(start 0.67945 -0.3048)
			(end 0.67945 0.3048)
			(stroke
				(width 0.1)
				(type default)
			)
			(layer "F.Fab")
		)
		(fp_line
			(start -0.67945 -0.305054)
			(end -0.12065 -0.305054)
			(stroke
				(width 0.1)
				(type default)
			)
			(layer "F.Fab")
		)
		(fp_line
			(start -0.12065 -0.305054)
			(end -0.12065 -0.2794)
			(stroke
				(width 0.1)
				(type default)
			)
			(layer "F.Fab")
		)
		(pad "1" smd circle
			(at -0.40005 0 270)
			(size 0 0)
			(layers "F.Cu" "F.Mask" "F.Paste")
			(net "P3V3_AUX")
		)
		(pad "2" smd circle
			(at 0.40005 0 270)
			(size 0 0)
			(layers "F.Cu" "F.Mask" "F.Paste")
			(net "GND")
		)
	)
	(footprint ""
		(layer "F.Cu")
		(at 331.917802 -20.77085)
		(property "Reference" "R4118"
			(at 0 0 0)
			(layer "F.SilkS")
			(hide yes)
			(effects
				(font
					(size 1.27 1.27)
				)
			)
		)
		(property "Value" ""
			(at 0 0 0)
			(layer "F.Fab")
			(effects
				(font
					(size 1.27 1.27)
				)
			)
		)
		(duplicate_pad_numbers_are_jumpers no)
		(fp_line
			(start -0.7874 -0.4064)
			(end 0.7874 -0.4064)
			(stroke
				(width 0.1524)
				(type default)
			)
			(layer "F.SilkS")
		)
		(fp_line
			(start -0.7874 0.4064)
			(end -0.7874 -0.4064)
			(stroke
				(width 0.1524)
				(type default)
			)
			(layer "F.SilkS")
		)
		(fp_line
			(start 0.7874 -0.4064)
			(end 0.7874 0.4064)
			(stroke
				(width 0.1524)
				(type default)
			)
			(layer "F.SilkS")
		)
		(fp_line
			(start 0.7874 0.4064)
			(end -0.7874 0.4064)
			(stroke
				(width 0.1524)
				(type default)
			)
			(layer "F.SilkS")
		)
		(fp_line
			(start -0.67945 -0.305054)
			(end -0.12065 -0.305054)
			(stroke
				(width 0.1)
				(type default)
			)
			(layer "F.Fab")
		)
		(fp_line
			(start -0.67945 0.3048)
			(end -0.67945 -0.305054)
			(stroke
				(width 0.1)
				(type default)
			)
			(layer "F.Fab")
		)
		(fp_line
			(start -0.12065 -0.305054)
			(end -0.12065 -0.2794)
			(stroke
				(width 0.1)
				(type default)
			)
			(layer "F.Fab")
		)
		(fp_line
			(start -0.12065 -0.2794)
			(end 0.12065 -0.2794)
			(stroke
				(width 0.1)
				(type default)
			)
			(layer "F.Fab")
		)
		(fp_line
			(start -0.12065 0.2794)
			(end -0.12065 0.3048)
			(stroke
				(width 0.1)
				(type default)
			)
			(layer "F.Fab")
		)
		(fp_line
			(start -0.12065 0.3048)
			(end -0.67945 0.3048)
			(stroke
				(width 0.1)
				(type default)
			)
			(layer "F.Fab")
		)
		(fp_line
			(start 0.120396 0.2794)
			(end -0.12065 0.2794)
			(stroke
				(width 0.1)
				(type default)
			)
			(layer "F.Fab")
		)
		(fp_line
			(start 0.120396 0.3048)
			(end 0.120396 0.2794)
			(stroke
				(width 0.1)
				(type default)
			)
			(layer "F.Fab")
		)
		(fp_line
			(start 0.12065 -0.3048)
			(end 0.67945 -0.3048)
			(stroke
				(width 0.1)
				(type default)
			)
			(layer "F.Fab")
		)
		(fp_line
			(start 0.12065 -0.2794)
			(end 0.12065 -0.3048)
			(stroke
				(width 0.1)
				(type default)
			)
			(layer "F.Fab")
		)
		(fp_line
			(start 0.67945 -0.3048)
			(end 0.67945 0.3048)
			(stroke
				(width 0.1)
				(type default)
			)
			(layer "F.Fab")
		)
		(fp_line
			(start 0.67945 0.3048)
			(end 0.120396 0.3048)
			(stroke
				(width 0.1)
				(type default)
			)
			(layer "F.Fab")
		)
		(pad "1" smd circle
			(at -0.40005 0)
			(size 0 0)
			(layers "F.Cu" "F.Mask" "F.Paste")
			(net "IRQ_LPC_SERIRQ_ESPI_CS1_N")
		)
		(pad "2" smd circle
			(at 0.40005 0)
			(size 0 0)
			(layers "F.Cu" "F.Mask" "F.Paste")
			(net "IRQ_LPC_SERIRQ_ESPI_CS1_R_N")
		)
	)
	(footprint ""
		(layer "F.Cu")
		(at 228.649784 -44.500038)
		(property "Reference" "H77"
			(at -1.143 -3.266948 0)
			(unlocked yes)
			(layer "B.SilkS")
			(effects
				(font
					(size 0.7874 0.5842)
					(thickness 0.1524)
				)
				(justify left mirror)
			)
		)
		(property "Value" ""
			(at 0 0 0)
			(layer "F.Fab")
			(effects
				(font
					(size 1.27 1.27)
				)
			)
		)
		(duplicate_pad_numbers_are_jumpers no)
		(pad "1" thru_hole rect
			(at 0 0)
			(size 4.2164 5.0038)
			(drill 2.0066
				(offset 0.099822 0)
			)
			(layers "*.Cu" "*.Mask")
			(remove_unused_layers no)
			(net "GND")
			(clearance -0.8509)
			(padstack
				(mode front_inner_back)
				(layer "Inner"
					(shape circle)
					(size 4.0132 4.0132)
					(clearance -0.7493)
				)
				(layer "B.Cu"
					(shape circle)
					(size 4.0132 4.0132)
					(clearance -0.7493)
				)
			)
		)
	)
	(footprint ""
		(layer "F.Cu")
		(at 106.3244 -251.375672 90)
		(property "Reference" "C287"
			(at 0 0 90)
			(layer "F.SilkS")
			(hide yes)
			(effects
				(font
					(size 1.27 1.27)
				)
			)
		)
		(property "Value" ""
			(at 0 0 90)
			(layer "F.Fab")
			(effects
				(font
					(size 1.27 1.27)
				)
			)
		)
		(duplicate_pad_numbers_are_jumpers no)
		(fp_line
			(start 0.7874 -0.4064)
			(end 0.7874 0.4064)
			(stroke
				(width 0.1524)
				(type default)
			)
			(layer "F.SilkS")
		)
		(fp_line
			(start -0.7874 -0.4064)
			(end 0.7874 -0.4064)
			(stroke
				(width 0.1524)
				(type default)
			)
			(layer "F.SilkS")
		)
		(fp_line
			(start 0.7874 0.4064)
			(end -0.7874 0.4064)
			(stroke
				(width 0.1524)
				(type default)
			)
			(layer "F.SilkS")
		)
		(fp_line
			(start -0.7874 0.4064)
			(end -0.7874 -0.4064)
			(stroke
				(width 0.1524)
				(type default)
			)
			(layer "F.SilkS")
		)
		(fp_line
			(start -0.12065 -0.305054)
			(end -0.12065 -0.2794)
			(stroke
				(width 0.1)
				(type default)
			)
			(layer "F.Fab")
		)
		(fp_line
			(start -0.67945 -0.305054)
			(end -0.12065 -0.305054)
			(stroke
				(width 0.1)
				(type default)
			)
			(layer "F.Fab")
		)
		(fp_line
			(start 0.67945 -0.3048)
			(end 0.67945 0.3048)
			(stroke
				(width 0.1)
				(type default)
			)
			(layer "F.Fab")
		)
		(fp_line
			(start 0.12065 -0.3048)
			(end 0.67945 -0.3048)
			(stroke
				(width 0.1)
				(type default)
			)
			(layer "F.Fab")
		)
		(fp_line
			(start 0.12065 -0.2794)
			(end 0.12065 -0.3048)
			(stroke
				(width 0.1)
				(type default)
			)
			(layer "F.Fab")
		)
		(fp_line
			(start -0.12065 -0.2794)
			(end 0.12065 -0.2794)
			(stroke
				(width 0.1)
				(type default)
			)
			(layer "F.Fab")
		)
		(fp_line
			(start 0.120396 0.2794)
			(end -0.12065 0.2794)
			(stroke
				(width 0.1)
				(type default)
			)
			(layer "F.Fab")
		)
		(fp_line
			(start -0.12065 0.2794)
			(end -0.12065 0.3048)
			(stroke
				(width 0.1)
				(type default)
			)
			(layer "F.Fab")
		)
		(fp_line
			(start 0.67945 0.3048)
			(end 0.120396 0.3048)
			(stroke
				(width 0.1)
				(type default)
			)
			(layer "F.Fab")
		)
		(fp_line
			(start 0.120396 0.3048)
			(end 0.120396 0.2794)
			(stroke
				(width 0.1)
				(type default)
			)
			(layer "F.Fab")
		)
		(fp_line
			(start -0.12065 0.3048)
			(end -0.67945 0.3048)
			(stroke
				(width 0.1)
				(type default)
			)
			(layer "F.Fab")
		)
		(fp_line
			(start -0.67945 0.3048)
			(end -0.67945 -0.305054)
			(stroke
				(width 0.1)
				(type default)
			)
			(layer "F.Fab")
		)
		(pad "1" smd circle
			(at -0.40005 0 90)
			(size 0 0)
			(layers "F.Cu" "F.Mask" "F.Paste")
			(net "PVCCIN_CPU1")
		)
		(pad "2" smd circle
			(at 0.40005 0 90)
			(size 0 0)
			(layers "F.Cu" "F.Mask" "F.Paste")
			(net "GND")
		)
	)
	(footprint ""
		(layer "F.Cu")
		(at 139.855194 -408.517344 -90)
		(property "Reference" "C1528"
			(at 0 0 270)
			(layer "F.SilkS")
			(hide yes)
			(effects
				(font
					(size 1.27 1.27)
				)
			)
		)
		(property "Value" ""
			(at 0 0 270)
			(layer "F.Fab")
			(effects
				(font
					(size 1.27 1.27)
				)
			)
		)
		(duplicate_pad_numbers_are_jumpers no)
		(fp_line
			(start -0.299974 0.150114)
			(end -0.299974 -0.150114)
			(stroke
				(width 0.1)
				(type default)
			)
			(layer "F.Fab")
		)
		(fp_line
			(start 0.299974 0.150114)
			(end -0.299974 0.150114)
			(stroke
				(width 0.1)
				(type default)
			)
			(layer "F.Fab")
		)
		(fp_line
			(start -0.299974 -0.150114)
			(end 0.299974 -0.150114)
			(stroke
				(width 0.1)
				(type default)
			)
			(layer "F.Fab")
		)
		(fp_line
			(start 0.299974 -0.150114)
			(end 0.299974 0.150114)
			(stroke
				(width 0.1)
				(type default)
			)
			(layer "F.Fab")
		)
		(pad "1" smd rect
			(at -0.2667 0 270)
			(size 0.3048 0.381)
			(layers "F.Cu" "F.Mask" "F.Paste")
			(net "P5E_CPU1_PE3_TX_C_DN<9>")
		)
		(pad "2" smd rect
			(at 0.2667 0 270)
			(size 0.3048 0.381)
			(layers "F.Cu" "F.Mask" "F.Paste")
			(net "P5E_CPU1_PE3_TX_DN<9>")
		)
	)
	(footprint ""
		(layer "F.Cu")
		(at 463.343498 -43.221148 180)
		(property "Reference" "R4070"
			(at 0 0 180)
			(layer "F.SilkS")
			(hide yes)
			(effects
				(font
					(size 1.27 1.27)
				)
			)
		)
		(property "Value" ""
			(at 0 0 180)
			(layer "F.Fab")
			(effects
				(font
					(size 1.27 1.27)
				)
			)
		)
		(duplicate_pad_numbers_are_jumpers no)
		(fp_line
			(start 0.7874 0.4064)
			(end -0.7874 0.4064)
			(stroke
				(width 0.1524)
				(type default)
			)
			(layer "F.SilkS")
		)
		(fp_line
			(start 0.7874 -0.4064)
			(end 0.7874 0.4064)
			(stroke
				(width 0.1524)
				(type default)
			)
			(layer "F.SilkS")
		)
		(fp_line
			(start -0.7874 0.4064)
			(end -0.7874 -0.4064)
			(stroke
				(width 0.1524)
				(type default)
			)
			(layer "F.SilkS")
		)
		(fp_line
			(start -0.7874 -0.4064)
			(end 0.7874 -0.4064)
			(stroke
				(width 0.1524)
				(type default)
			)
			(layer "F.SilkS")
		)
		(fp_line
			(start 0.67945 0.3048)
			(end 0.120396 0.3048)
			(stroke
				(width 0.1)
				(type default)
			)
			(layer "F.Fab")
		)
		(fp_line
			(start 0.67945 -0.3048)
			(end 0.67945 0.3048)
			(stroke
				(width 0.1)
				(type default)
			)
			(layer "F.Fab")
		)
		(fp_line
			(start 0.12065 -0.2794)
			(end 0.12065 -0.3048)
			(stroke
				(width 0.1)
				(type default)
			)
			(layer "F.Fab")
		)
		(fp_line
			(start 0.12065 -0.3048)
			(end 0.67945 -0.3048)
			(stroke
				(width 0.1)
				(type default)
			)
			(layer "F.Fab")
		)
		(fp_line
			(start 0.120396 0.3048)
			(end 0.120396 0.2794)
			(stroke
				(width 0.1)
				(type default)
			)
			(layer "F.Fab")
		)
		(fp_line
			(start 0.120396 0.2794)
			(end -0.12065 0.2794)
			(stroke
				(width 0.1)
				(type default)
			)
			(layer "F.Fab")
		)
		(fp_line
			(start -0.12065 0.3048)
			(end -0.67945 0.3048)
			(stroke
				(width 0.1)
				(type default)
			)
			(layer "F.Fab")
		)
		(fp_line
			(start -0.12065 0.2794)
			(end -0.12065 0.3048)
			(stroke
				(width 0.1)
				(type default)
			)
			(layer "F.Fab")
		)
		(fp_line
			(start -0.12065 -0.2794)
			(end 0.12065 -0.2794)
			(stroke
				(width 0.1)
				(type default)
			)
			(layer "F.Fab")
		)
		(fp_line
			(start -0.12065 -0.305054)
			(end -0.12065 -0.2794)
			(stroke
				(width 0.1)
				(type default)
			)
			(layer "F.Fab")
		)
		(fp_line
			(start -0.67945 0.3048)
			(end -0.67945 -0.305054)
			(stroke
				(width 0.1)
				(type default)
			)
			(layer "F.Fab")
		)
		(fp_line
			(start -0.67945 -0.305054)
			(end -0.12065 -0.305054)
			(stroke
				(width 0.1)
				(type default)
			)
			(layer "F.Fab")
		)
		(pad "1" smd circle
			(at -0.40005 0 180)
			(size 0 0)
			(layers "F.Cu" "F.Mask" "F.Paste")
			(net "P12V_AUX")
		)
		(pad "2" smd circle
			(at 0.40005 0 180)
			(size 0 0)
			(layers "F.Cu" "F.Mask" "F.Paste")
			(net "P3V3_OCP_1_EN_G")
		)
	)
	(footprint ""
		(layer "F.Cu")
		(at 69.02196 -57.094628)
		(property "Reference" "PU207"
			(at -5.23748 1.086612 0)
			(unlocked yes)
			(layer "F.SilkS")
			(effects
				(font
					(size 0.7874 0.5842)
					(thickness 0.1524)
				)
			)
		)
		(property "Value" ""
			(at 0 0 0)
			(layer "F.Fab")
			(effects
				(font
					(size 1.27 1.27)
				)
			)
		)
		(duplicate_pad_numbers_are_jumpers no)
		(fp_line
			(start -1.239774 -1.495298)
			(end 1.239774 -1.495298)
			(stroke
				(width 0.1524)
				(type default)
			)
			(layer "F.SilkS")
		)
		(fp_line
			(start -1.239774 1.495298)
			(end -1.239774 -1.495298)
			(stroke
				(width 0.1524)
				(type default)
			)
			(layer "F.SilkS")
		)
		(fp_line
			(start 1.239774 -1.495298)
			(end 1.239774 1.495298)
			(stroke
				(width 0.1524)
				(type default)
			)
			(layer "F.SilkS")
		)
		(fp_line
			(start 1.239774 1.495298)
			(end -1.239774 1.495298)
			(stroke
				(width 0.1524)
				(type default)
			)
			(layer "F.SilkS")
		)
		(fp_poly
			(pts
				(xy -2.525014 -1.62814) (xy -1.509014 -1.12014) (xy -2.525014 -0.61214)
			)
			(stroke
				(width 0)
				(type default)
			)
			(fill yes)
			(layer "F.SilkS")
		)
		(fp_line
			(start -0.8001 -1.050036)
			(end 0.8001 -1.050036)
			(stroke
				(width 0.1)
				(type default)
			)
			(layer "F.Fab")
		)
		(fp_line
			(start -0.8001 1.050036)
			(end -0.8001 -1.050036)
			(stroke
				(width 0.1)
				(type default)
			)
			(layer "F.Fab")
		)
		(fp_line
			(start 0.8001 -1.050036)
			(end 0.8001 1.050036)
			(stroke
				(width 0.1)
				(type default)
			)
			(layer "F.Fab")
		)
		(fp_line
			(start 0.8001 1.050036)
			(end -0.8001 1.050036)
			(stroke
				(width 0.1)
				(type default)
			)
			(layer "F.Fab")
		)
		(fp_poly
			(pts
				(xy -2.458974 -0.508) (xy -2.458974 0.508) (xy -1.442974 0)
			)
			(stroke
				(width 0)
				(type default)
			)
			(fill yes)
			(layer "F.Fab")
		)
		(pad "1_2" smd circle
			(at -0.374904 0 90)
			(size 0 0)
			(layers "F.Cu" "F.Mask" "F.Paste")
			(net "P3V3_AUX")
		)
		(pad "3" smd rect
			(at -0.499872 0.999998)
			(size 0.254 0.7112)
			(layers "F.Cu" "F.Mask" "F.Paste")
			(net "GND")
		)
		(pad "4" smd rect
			(at 0 0.999998)
			(size 0.254 0.7112)
			(layers "F.Cu" "F.Mask" "F.Paste")
			(net "P3V3_OCP_ILIMIT_2")
		)
		(pad "5" smd rect
			(at 0.499872 0.999998)
			(size 0.254 0.7112)
			(layers "F.Cu" "F.Mask" "F.Paste")
			(net "P3V3_OCP_MODE_2")
		)
		(pad "6_7" smd circle
			(at 0.374904 0 270)
			(size 0 0)
			(layers "F.Cu" "F.Mask" "F.Paste")
			(net "P3V3_OCP_V3_2_R")
		)
		(pad "8" smd rect
			(at 0.499872 -0.999998)
			(size 0.254 0.7112)
			(layers "F.Cu" "F.Mask" "F.Paste")
			(net "P3V3_OCP_GATE_PU207_2")
		)
		(pad "9" smd rect
			(at 0 -0.999998)
			(size 0.254 0.7112)
			(layers "F.Cu" "F.Mask" "F.Paste")
			(net "P3V3_OCP_EN_2")
		)
		(pad "10" smd rect
			(at -0.499872 -0.999998)
			(size 0.254 0.7112)
			(layers "F.Cu" "F.Mask" "F.Paste")
			(net "P3V3_OCP_DVDT_2")
		)
	)
	(footprint ""
		(layer "F.Cu")
		(at 77.784198 -408.517344 -90)
		(property "Reference" "C691"
			(at 0 0 270)
			(layer "F.SilkS")
			(hide yes)
			(effects
				(font
					(size 1.27 1.27)
				)
			)
		)
		(property "Value" ""
			(at 0 0 270)
			(layer "F.Fab")
			(effects
				(font
					(size 1.27 1.27)
				)
			)
		)
		(duplicate_pad_numbers_are_jumpers no)
		(fp_line
			(start -0.299974 0.150114)
			(end -0.299974 -0.150114)
			(stroke
				(width 0.1)
				(type default)
			)
			(layer "F.Fab")
		)
		(fp_line
			(start 0.299974 0.150114)
			(end -0.299974 0.150114)
			(stroke
				(width 0.1)
				(type default)
			)
			(layer "F.Fab")
		)
		(fp_line
			(start -0.299974 -0.150114)
			(end 0.299974 -0.150114)
			(stroke
				(width 0.1)
				(type default)
			)
			(layer "F.Fab")
		)
		(fp_line
			(start 0.299974 -0.150114)
			(end 0.299974 0.150114)
			(stroke
				(width 0.1)
				(type default)
			)
			(layer "F.Fab")
		)
		(pad "1" smd rect
			(at -0.2667 0 270)
			(size 0.3048 0.381)
			(layers "F.Cu" "F.Mask" "F.Paste")
			(net "P5E_CPU1_PE4_TX_C_DP<9>")
		)
		(pad "2" smd rect
			(at 0.2667 0 270)
			(size 0.3048 0.381)
			(layers "F.Cu" "F.Mask" "F.Paste")
			(net "P5E_CPU1_PE4_TX_DP<9>")
		)
	)
	(footprint ""
		(layer "F.Cu")
		(at 432.636676 -94.938342)
		(property "Reference" "R3603"
			(at 0 0 0)
			(layer "F.SilkS")
			(hide yes)
			(effects
				(font
					(size 1.27 1.27)
				)
			)
		)
		(property "Value" ""
			(at 0 0 0)
			(layer "F.Fab")
			(effects
				(font
					(size 1.27 1.27)
				)
			)
		)
		(duplicate_pad_numbers_are_jumpers no)
		(fp_line
			(start -0.7874 -0.4064)
			(end 0.7874 -0.4064)
			(stroke
				(width 0.1524)
				(type default)
			)
			(layer "F.SilkS")
		)
		(fp_line
			(start -0.7874 0.4064)
			(end -0.7874 -0.4064)
			(stroke
				(width 0.1524)
				(type default)
			)
			(layer "F.SilkS")
		)
		(fp_line
			(start 0.7874 -0.4064)
			(end 0.7874 0.4064)
			(stroke
				(width 0.1524)
				(type default)
			)
			(layer "F.SilkS")
		)
		(fp_line
			(start 0.7874 0.4064)
			(end -0.7874 0.4064)
			(stroke
				(width 0.1524)
				(type default)
			)
			(layer "F.SilkS")
		)
		(fp_line
			(start -0.67945 -0.305054)
			(end -0.12065 -0.305054)
			(stroke
				(width 0.1)
				(type default)
			)
			(layer "F.Fab")
		)
		(fp_line
			(start -0.67945 0.3048)
			(end -0.67945 -0.305054)
			(stroke
				(width 0.1)
				(type default)
			)
			(layer "F.Fab")
		)
		(fp_line
			(start -0.12065 -0.305054)
			(end -0.12065 -0.2794)
			(stroke
				(width 0.1)
				(type default)
			)
			(layer "F.Fab")
		)
		(fp_line
			(start -0.12065 -0.2794)
			(end 0.12065 -0.2794)
			(stroke
				(width 0.1)
				(type default)
			)
			(layer "F.Fab")
		)
		(fp_line
			(start -0.12065 0.2794)
			(end -0.12065 0.3048)
			(stroke
				(width 0.1)
				(type default)
			)
			(layer "F.Fab")
		)
		(fp_line
			(start -0.12065 0.3048)
			(end -0.67945 0.3048)
			(stroke
				(width 0.1)
				(type default)
			)
			(layer "F.Fab")
		)
		(fp_line
			(start 0.120396 0.2794)
			(end -0.12065 0.2794)
			(stroke
				(width 0.1)
				(type default)
			)
			(layer "F.Fab")
		)
		(fp_line
			(start 0.120396 0.3048)
			(end 0.120396 0.2794)
			(stroke
				(width 0.1)
				(type default)
			)
			(layer "F.Fab")
		)
		(fp_line
			(start 0.12065 -0.3048)
			(end 0.67945 -0.3048)
			(stroke
				(width 0.1)
				(type default)
			)
			(layer "F.Fab")
		)
		(fp_line
			(start 0.12065 -0.2794)
			(end 0.12065 -0.3048)
			(stroke
				(width 0.1)
				(type default)
			)
			(layer "F.Fab")
		)
		(fp_line
			(start 0.67945 -0.3048)
			(end 0.67945 0.3048)
			(stroke
				(width 0.1)
				(type default)
			)
			(layer "F.Fab")
		)
		(fp_line
			(start 0.67945 0.3048)
			(end 0.120396 0.3048)
			(stroke
				(width 0.1)
				(type default)
			)
			(layer "F.Fab")
		)
		(pad "1" smd circle
			(at -0.40005 0)
			(size 0 0)
			(layers "F.Cu" "F.Mask" "F.Paste")
			(net "P3V3_OCP_SFF")
		)
		(pad "2" smd circle
			(at 0.40005 0)
			(size 0 0)
			(layers "F.Cu" "F.Mask" "F.Paste")
			(net "VSENSE_P3V3_INA230_1_INN")
		)
	)
	(footprint ""
		(layer "F.Cu")
		(at 24.069802 -407.890218 180)
		(property "Reference" "R3428"
			(at 0 0 180)
			(layer "F.SilkS")
			(hide yes)
			(effects
				(font
					(size 1.27 1.27)
				)
			)
		)
		(property "Value" ""
			(at 0 0 180)
			(layer "F.Fab")
			(effects
				(font
					(size 1.27 1.27)
				)
			)
		)
		(duplicate_pad_numbers_are_jumpers no)
		(fp_line
			(start 0.7874 0.4064)
			(end -0.7874 0.4064)
			(stroke
				(width 0.1524)
				(type default)
			)
			(layer "F.SilkS")
		)
		(fp_line
			(start 0.7874 -0.4064)
			(end 0.7874 0.4064)
			(stroke
				(width 0.1524)
				(type default)
			)
			(layer "F.SilkS")
		)
		(fp_line
			(start -0.7874 0.4064)
			(end -0.7874 -0.4064)
			(stroke
				(width 0.1524)
				(type default)
			)
			(layer "F.SilkS")
		)
		(fp_line
			(start -0.7874 -0.4064)
			(end 0.7874 -0.4064)
			(stroke
				(width 0.1524)
				(type default)
			)
			(layer "F.SilkS")
		)
		(fp_line
			(start 0.67945 0.3048)
			(end 0.120396 0.3048)
			(stroke
				(width 0.1)
				(type default)
			)
			(layer "F.Fab")
		)
		(fp_line
			(start 0.67945 -0.3048)
			(end 0.67945 0.3048)
			(stroke
				(width 0.1)
				(type default)
			)
			(layer "F.Fab")
		)
		(fp_line
			(start 0.12065 -0.2794)
			(end 0.12065 -0.3048)
			(stroke
				(width 0.1)
				(type default)
			)
			(layer "F.Fab")
		)
		(fp_line
			(start 0.12065 -0.3048)
			(end 0.67945 -0.3048)
			(stroke
				(width 0.1)
				(type default)
			)
			(layer "F.Fab")
		)
		(fp_line
			(start 0.120396 0.3048)
			(end 0.120396 0.2794)
			(stroke
				(width 0.1)
				(type default)
			)
			(layer "F.Fab")
		)
		(fp_line
			(start 0.120396 0.2794)
			(end -0.12065 0.2794)
			(stroke
				(width 0.1)
				(type default)
			)
			(layer "F.Fab")
		)
		(fp_line
			(start -0.12065 0.3048)
			(end -0.67945 0.3048)
			(stroke
				(width 0.1)
				(type default)
			)
			(layer "F.Fab")
		)
		(fp_line
			(start -0.12065 0.2794)
			(end -0.12065 0.3048)
			(stroke
				(width 0.1)
				(type default)
			)
			(layer "F.Fab")
		)
		(fp_line
			(start -0.12065 -0.2794)
			(end 0.12065 -0.2794)
			(stroke
				(width 0.1)
				(type default)
			)
			(layer "F.Fab")
		)
		(fp_line
			(start -0.12065 -0.305054)
			(end -0.12065 -0.2794)
			(stroke
				(width 0.1)
				(type default)
			)
			(layer "F.Fab")
		)
		(fp_line
			(start -0.67945 0.3048)
			(end -0.67945 -0.305054)
			(stroke
				(width 0.1)
				(type default)
			)
			(layer "F.Fab")
		)
		(fp_line
			(start -0.67945 -0.305054)
			(end -0.12065 -0.305054)
			(stroke
				(width 0.1)
				(type default)
			)
			(layer "F.Fab")
		)
		(pad "1" smd circle
			(at -0.40005 0 180)
			(size 0 0)
			(layers "F.Cu" "F.Mask" "F.Paste")
			(net "GPU_FPGA_THERM_OVERT_N")
		)
		(pad "2" smd circle
			(at 0.40005 0 180)
			(size 0 0)
			(layers "F.Cu" "F.Mask" "F.Paste")
			(net "GND")
		)
	)
	(footprint ""
		(layer "F.Cu")
		(at 39.643558 -100.49129)
		(property "Reference" "U193"
			(at -1.797558 3.525012 0)
			(unlocked yes)
			(layer "F.SilkS")
			(effects
				(font
					(size 0.7874 0.5842)
					(thickness 0.1524)
				)
				(justify left)
			)
		)
		(property "Value" ""
			(at 0 0 0)
			(layer "F.Fab")
			(effects
				(font
					(size 1.27 1.27)
				)
			)
		)
		(duplicate_pad_numbers_are_jumpers no)
		(fp_line
			(start -1.715516 -2.489962)
			(end -1.715516 2.489962)
			(stroke
				(width 0.1524)
				(type default)
			)
			(layer "F.SilkS")
		)
		(fp_line
			(start -1.715516 2.489962)
			(end 1.715516 2.489962)
			(stroke
				(width 0.1524)
				(type default)
			)
			(layer "F.SilkS")
		)
		(fp_line
			(start -1.092962 -2.489962)
			(end -1.715516 -2.489962)
			(stroke
				(width 0.1524)
				(type default)
			)
			(layer "F.SilkS")
		)
		(fp_line
			(start 0 -1.397)
			(end -1.092962 -2.489962)
			(stroke
				(width 0.1524)
				(type default)
			)
			(layer "F.SilkS")
		)
		(fp_line
			(start 1.092962 -2.489962)
			(end 0 -1.397)
			(stroke
				(width 0.1524)
				(type default)
			)
			(layer "F.SilkS")
		)
		(fp_line
			(start 1.715516 -2.489962)
			(end 1.092962 -2.489962)
			(stroke
				(width 0.1524)
				(type default)
			)
			(layer "F.SilkS")
		)
		(fp_line
			(start 1.715516 2.489962)
			(end 1.715516 -2.489962)
			(stroke
				(width 0.1524)
				(type default)
			)
			(layer "F.SilkS")
		)
		(fp_poly
			(pts
				(xy -2.187956 -3.79984) (xy -2.695956 -2.78384) (xy -3.203956 -3.79984)
			)
			(stroke
				(width 0)
				(type default)
			)
			(fill yes)
			(layer "F.SilkS")
		)
		(fp_line
			(start -1.994916 -2.489962)
			(end -1.994916 2.489962)
			(stroke
				(width 0.1)
				(type default)
			)
			(layer "F.Fab")
		)
		(fp_line
			(start -1.994916 2.489962)
			(end 1.994916 2.489962)
			(stroke
				(width 0.1)
				(type default)
			)
			(layer "F.Fab")
		)
		(fp_line
			(start 1.994916 -2.489962)
			(end -1.994916 -2.489962)
			(stroke
				(width 0.1)
				(type default)
			)
			(layer "F.Fab")
		)
		(fp_line
			(start 1.994916 2.489962)
			(end 1.994916 -2.489962)
			(stroke
				(width 0.1)
				(type default)
			)
			(layer "F.Fab")
		)
		(fp_poly
			(pts
				(xy -4.699 -2.7305) (xy -4.699 -1.7145) (xy -3.683 -2.2225)
			)
			(stroke
				(width 0)
				(type default)
			)
			(fill yes)
			(layer "F.Fab")
		)
		(pad "1" smd rect
			(at -2.655062 -2.2225 90)
			(size 0.381 1.6002)
			(layers "F.Cu" "F.Mask" "F.Paste")
			(net "MAX11617_VREF_R")
		)
		(pad "2" smd rect
			(at -2.655062 -1.5875 90)
			(size 0.381 1.6002)
			(layers "F.Cu" "F.Mask" "F.Paste")
			(net "GND")
		)
		(pad "3" smd rect
			(at -2.655062 -0.9525 90)
			(size 0.381 1.6002)
			(layers "F.Cu" "F.Mask" "F.Paste")
			(net "GND")
		)
		(pad "4" smd rect
			(at -2.655062 -0.3175 90)
			(size 0.381 1.6002)
			(layers "F.Cu" "F.Mask" "F.Paste")
			(net "GND")
		)
		(pad "5" smd rect
			(at -2.655062 0.3175 90)
			(size 0.381 1.6002)
			(layers "F.Cu" "F.Mask" "F.Paste")
			(net "P12V_AUX_ADC_MAM")
		)
		(pad "6" smd rect
			(at -2.655062 0.9525 90)
			(size 0.381 1.6002)
			(layers "F.Cu" "F.Mask" "F.Paste")
			(net "P12V_OCP_SFF_ISENSE_MAM")
		)
		(pad "7" smd rect
			(at -2.655062 1.5875 90)
			(size 0.381 1.6002)
			(layers "F.Cu" "F.Mask" "F.Paste")
			(net "P12V_OCP_V3_2_ISENSE_MAM")
		)
		(pad "8" smd rect
			(at -2.655062 2.2225 90)
			(size 0.381 1.6002)
			(layers "F.Cu" "F.Mask" "F.Paste")
			(net "P5V_ADC_MAM")
		)
		(pad "9" smd rect
			(at 2.655062 2.2225 90)
			(size 0.381 1.6002)
			(layers "F.Cu" "F.Mask" "F.Paste")
			(net "P3V3_ADC_MAM")
		)
		(pad "10" smd rect
			(at 2.655062 1.5875 90)
			(size 0.381 1.6002)
			(layers "F.Cu" "F.Mask" "F.Paste")
			(net "P3V3_AUX_ADC_MAM")
		)
		(pad "11" smd rect
			(at 2.655062 0.9525 90)
			(size 0.381 1.6002)
			(layers "F.Cu" "F.Mask" "F.Paste")
			(net "P3V3_PDB_AUX_ADC_MAM")
		)
		(pad "12" smd rect
			(at 2.655062 0.3175 90)
			(size 0.381 1.6002)
			(layers "F.Cu" "F.Mask" "F.Paste")
			(net "P12V_E1S_0_ISENSE_MAM")
		)
		(pad "13" smd rect
			(at 2.655062 -0.3175 90)
			(size 0.381 1.6002)
			(layers "F.Cu" "F.Mask" "F.Paste")
			(net "SMB_SEN_MAM_3V3AUX_SCL")
		)
		(pad "14" smd rect
			(at 2.655062 -0.9525 90)
			(size 0.381 1.6002)
			(layers "F.Cu" "F.Mask" "F.Paste")
			(net "SMB_SEN_MAM_3V3AUX_SDA")
		)
		(pad "15" smd rect
			(at 2.655062 -1.5875 90)
			(size 0.381 1.6002)
			(layers "F.Cu" "F.Mask" "F.Paste")
			(net "GND")
		)
		(pad "16" smd rect
			(at 2.655062 -2.2225 90)
			(size 0.381 1.6002)
			(layers "F.Cu" "F.Mask" "F.Paste")
			(net "P3V3_MAX11617_VDD")
		)
	)
	(footprint ""
		(layer "F.Cu")
		(at 383.514854 -73.15962)
		(property "Reference" "PC1642"
			(at 0 0 0)
			(layer "F.SilkS")
			(hide yes)
			(effects
				(font
					(size 1.27 1.27)
				)
			)
		)
		(property "Value" ""
			(at 0 0 0)
			(layer "F.Fab")
			(effects
				(font
					(size 1.27 1.27)
				)
			)
		)
		(duplicate_pad_numbers_are_jumpers no)
		(fp_line
			(start -0.7874 -0.4064)
			(end 0.7874 -0.4064)
			(stroke
				(width 0.1524)
				(type default)
			)
			(layer "F.SilkS")
		)
		(fp_line
			(start -0.7874 0.4064)
			(end -0.7874 -0.4064)
			(stroke
				(width 0.1524)
				(type default)
			)
			(layer "F.SilkS")
		)
		(fp_line
			(start 0.7874 -0.4064)
			(end 0.7874 0.4064)
			(stroke
				(width 0.1524)
				(type default)
			)
			(layer "F.SilkS")
		)
		(fp_line
			(start 0.7874 0.4064)
			(end -0.7874 0.4064)
			(stroke
				(width 0.1524)
				(type default)
			)
			(layer "F.SilkS")
		)
		(fp_line
			(start -0.67945 -0.305054)
			(end -0.12065 -0.305054)
			(stroke
				(width 0.1)
				(type default)
			)
			(layer "F.Fab")
		)
		(fp_line
			(start -0.67945 0.3048)
			(end -0.67945 -0.305054)
			(stroke
				(width 0.1)
				(type default)
			)
			(layer "F.Fab")
		)
		(fp_line
			(start -0.12065 -0.305054)
			(end -0.12065 -0.2794)
			(stroke
				(width 0.1)
				(type default)
			)
			(layer "F.Fab")
		)
		(fp_line
			(start -0.12065 -0.2794)
			(end 0.12065 -0.2794)
			(stroke
				(width 0.1)
				(type default)
			)
			(layer "F.Fab")
		)
		(fp_line
			(start -0.12065 0.2794)
			(end -0.12065 0.3048)
			(stroke
				(width 0.1)
				(type default)
			)
			(layer "F.Fab")
		)
		(fp_line
			(start -0.12065 0.3048)
			(end -0.67945 0.3048)
			(stroke
				(width 0.1)
				(type default)
			)
			(layer "F.Fab")
		)
		(fp_line
			(start 0.120396 0.2794)
			(end -0.12065 0.2794)
			(stroke
				(width 0.1)
				(type default)
			)
			(layer "F.Fab")
		)
		(fp_line
			(start 0.120396 0.3048)
			(end 0.120396 0.2794)
			(stroke
				(width 0.1)
				(type default)
			)
			(layer "F.Fab")
		)
		(fp_line
			(start 0.12065 -0.3048)
			(end 0.67945 -0.3048)
			(stroke
				(width 0.1)
				(type default)
			)
			(layer "F.Fab")
		)
		(fp_line
			(start 0.12065 -0.2794)
			(end 0.12065 -0.3048)
			(stroke
				(width 0.1)
				(type default)
			)
			(layer "F.Fab")
		)
		(fp_line
			(start 0.67945 -0.3048)
			(end 0.67945 0.3048)
			(stroke
				(width 0.1)
				(type default)
			)
			(layer "F.Fab")
		)
		(fp_line
			(start 0.67945 0.3048)
			(end 0.120396 0.3048)
			(stroke
				(width 0.1)
				(type default)
			)
			(layer "F.Fab")
		)
		(pad "1" smd circle
			(at -0.40005 0)
			(size 0 0)
			(layers "F.Cu" "F.Mask" "F.Paste")
			(net "P1V8_PCH_AUX_VCC")
		)
		(pad "2" smd circle
			(at 0.40005 0)
			(size 0 0)
			(layers "F.Cu" "F.Mask" "F.Paste")
			(net "GND")
		)
	)
	(footprint ""
		(layer "F.Cu")
		(at 126.396242 -352.812858)
		(property "Reference" "PC1260"
			(at 0 0 0)
			(layer "F.SilkS")
			(hide yes)
			(effects
				(font
					(size 1.27 1.27)
				)
			)
		)
		(property "Value" ""
			(at 0 0 0)
			(layer "F.Fab")
			(effects
				(font
					(size 1.27 1.27)
				)
			)
		)
		(duplicate_pad_numbers_are_jumpers no)
		(fp_line
			(start -1.524 -0.762)
			(end 1.524 -0.762)
			(stroke
				(width 0.1524)
				(type default)
			)
			(layer "F.SilkS")
		)
		(fp_line
			(start -1.524 0.762)
			(end -1.524 -0.762)
			(stroke
				(width 0.1524)
				(type default)
			)
			(layer "F.SilkS")
		)
		(fp_line
			(start 1.524 -0.762)
			(end 1.524 0.762)
			(stroke
				(width 0.1524)
				(type default)
			)
			(layer "F.SilkS")
		)
		(fp_line
			(start 1.524 0.762)
			(end -1.524 0.762)
			(stroke
				(width 0.1524)
				(type default)
			)
			(layer "F.SilkS")
		)
		(fp_line
			(start -1.1049 -0.724916)
			(end -1.1049 0.724916)
			(stroke
				(width 0.1)
				(type default)
			)
			(layer "F.Fab")
		)
		(fp_line
			(start -1.1049 0.724916)
			(end 1.1049 0.724916)
			(stroke
				(width 0.1)
				(type default)
			)
			(layer "F.Fab")
		)
		(fp_line
			(start 1.1049 -0.724916)
			(end -1.1049 -0.724916)
			(stroke
				(width 0.1)
				(type default)
			)
			(layer "F.Fab")
		)
		(fp_line
			(start 1.1049 0.724916)
			(end 1.1049 -0.724916)
			(stroke
				(width 0.1)
				(type default)
			)
			(layer "F.Fab")
		)
		(pad "1" smd rect
			(at -0.889 0 180)
			(size 1.016 1.27)
			(layers "F.Cu" "F.Mask" "F.Paste")
			(net "SW_P12V_PVCCIN_CPU1_FLT")
		)
		(pad "2" smd rect
			(at 0.889 0 180)
			(size 1.016 1.27)
			(layers "F.Cu" "F.Mask" "F.Paste")
			(net "GND")
		)
	)
	(footprint ""
		(layer "F.Cu")
		(at 59.8678 -36.083748 180)
		(property "Reference" "R4065"
			(at 0 0 180)
			(layer "F.SilkS")
			(hide yes)
			(effects
				(font
					(size 1.27 1.27)
				)
			)
		)
		(property "Value" ""
			(at 0 0 180)
			(layer "F.Fab")
			(effects
				(font
					(size 1.27 1.27)
				)
			)
		)
		(duplicate_pad_numbers_are_jumpers no)
		(fp_line
			(start 0.7874 0.4064)
			(end -0.7874 0.4064)
			(stroke
				(width 0.1524)
				(type default)
			)
			(layer "F.SilkS")
		)
		(fp_line
			(start 0.7874 -0.4064)
			(end 0.7874 0.4064)
			(stroke
				(width 0.1524)
				(type default)
			)
			(layer "F.SilkS")
		)
		(fp_line
			(start -0.7874 0.4064)
			(end -0.7874 -0.4064)
			(stroke
				(width 0.1524)
				(type default)
			)
			(layer "F.SilkS")
		)
		(fp_line
			(start -0.7874 -0.4064)
			(end 0.7874 -0.4064)
			(stroke
				(width 0.1524)
				(type default)
			)
			(layer "F.SilkS")
		)
		(fp_line
			(start 0.67945 0.3048)
			(end 0.120396 0.3048)
			(stroke
				(width 0.1)
				(type default)
			)
			(layer "F.Fab")
		)
		(fp_line
			(start 0.67945 -0.3048)
			(end 0.67945 0.3048)
			(stroke
				(width 0.1)
				(type default)
			)
			(layer "F.Fab")
		)
		(fp_line
			(start 0.12065 -0.2794)
			(end 0.12065 -0.3048)
			(stroke
				(width 0.1)
				(type default)
			)
			(layer "F.Fab")
		)
		(fp_line
			(start 0.12065 -0.3048)
			(end 0.67945 -0.3048)
			(stroke
				(width 0.1)
				(type default)
			)
			(layer "F.Fab")
		)
		(fp_line
			(start 0.120396 0.3048)
			(end 0.120396 0.2794)
			(stroke
				(width 0.1)
				(type default)
			)
			(layer "F.Fab")
		)
		(fp_line
			(start 0.120396 0.2794)
			(end -0.12065 0.2794)
			(stroke
				(width 0.1)
				(type default)
			)
			(layer "F.Fab")
		)
		(fp_line
			(start -0.12065 0.3048)
			(end -0.67945 0.3048)
			(stroke
				(width 0.1)
				(type default)
			)
			(layer "F.Fab")
		)
		(fp_line
			(start -0.12065 0.2794)
			(end -0.12065 0.3048)
			(stroke
				(width 0.1)
				(type default)
			)
			(layer "F.Fab")
		)
		(fp_line
			(start -0.12065 -0.2794)
			(end 0.12065 -0.2794)
			(stroke
				(width 0.1)
				(type default)
			)
			(layer "F.Fab")
		)
		(fp_line
			(start -0.12065 -0.305054)
			(end -0.12065 -0.2794)
			(stroke
				(width 0.1)
				(type default)
			)
			(layer "F.Fab")
		)
		(fp_line
			(start -0.67945 0.3048)
			(end -0.67945 -0.305054)
			(stroke
				(width 0.1)
				(type default)
			)
			(layer "F.Fab")
		)
		(fp_line
			(start -0.67945 -0.305054)
			(end -0.12065 -0.305054)
			(stroke
				(width 0.1)
				(type default)
			)
			(layer "F.Fab")
		)
		(pad "1" smd circle
			(at -0.40005 0 180)
			(size 0 0)
			(layers "F.Cu" "F.Mask" "F.Paste")
			(net "P12V_AUX")
		)
		(pad "2" smd circle
			(at 0.40005 0 180)
			(size 0 0)
			(layers "F.Cu" "F.Mask" "F.Paste")
			(net "P12V_OCP_2_EN_G")
		)
	)
	(footprint ""
		(layer "F.Cu")
		(at 369.7224 -74.3458 90)
		(property "Reference" "R4706"
			(at 0 0 90)
			(layer "F.SilkS")
			(hide yes)
			(effects
				(font
					(size 1.27 1.27)
				)
			)
		)
		(property "Value" ""
			(at 0 0 90)
			(layer "F.Fab")
			(effects
				(font
					(size 1.27 1.27)
				)
			)
		)
		(duplicate_pad_numbers_are_jumpers no)
		(fp_line
			(start 0.7874 -0.4064)
			(end 0.7874 0.4064)
			(stroke
				(width 0.1524)
				(type default)
			)
			(layer "F.SilkS")
		)
		(fp_line
			(start -0.7874 -0.4064)
			(end 0.7874 -0.4064)
			(stroke
				(width 0.1524)
				(type default)
			)
			(layer "F.SilkS")
		)
		(fp_line
			(start 0.7874 0.4064)
			(end -0.7874 0.4064)
			(stroke
				(width 0.1524)
				(type default)
			)
			(layer "F.SilkS")
		)
		(fp_line
			(start -0.7874 0.4064)
			(end -0.7874 -0.4064)
			(stroke
				(width 0.1524)
				(type default)
			)
			(layer "F.SilkS")
		)
		(fp_line
			(start -0.12065 -0.305054)
			(end -0.12065 -0.2794)
			(stroke
				(width 0.1)
				(type default)
			)
			(layer "F.Fab")
		)
		(fp_line
			(start -0.67945 -0.305054)
			(end -0.12065 -0.305054)
			(stroke
				(width 0.1)
				(type default)
			)
			(layer "F.Fab")
		)
		(fp_line
			(start 0.67945 -0.3048)
			(end 0.67945 0.3048)
			(stroke
				(width 0.1)
				(type default)
			)
			(layer "F.Fab")
		)
		(fp_line
			(start 0.12065 -0.3048)
			(end 0.67945 -0.3048)
			(stroke
				(width 0.1)
				(type default)
			)
			(layer "F.Fab")
		)
		(fp_line
			(start 0.12065 -0.2794)
			(end 0.12065 -0.3048)
			(stroke
				(width 0.1)
				(type default)
			)
			(layer "F.Fab")
		)
		(fp_line
			(start -0.12065 -0.2794)
			(end 0.12065 -0.2794)
			(stroke
				(width 0.1)
				(type default)
			)
			(layer "F.Fab")
		)
		(fp_line
			(start 0.120396 0.2794)
			(end -0.12065 0.2794)
			(stroke
				(width 0.1)
				(type default)
			)
			(layer "F.Fab")
		)
		(fp_line
			(start -0.12065 0.2794)
			(end -0.12065 0.3048)
			(stroke
				(width 0.1)
				(type default)
			)
			(layer "F.Fab")
		)
		(fp_line
			(start 0.67945 0.3048)
			(end 0.120396 0.3048)
			(stroke
				(width 0.1)
				(type default)
			)
			(layer "F.Fab")
		)
		(fp_line
			(start 0.120396 0.3048)
			(end 0.120396 0.2794)
			(stroke
				(width 0.1)
				(type default)
			)
			(layer "F.Fab")
		)
		(fp_line
			(start -0.12065 0.3048)
			(end -0.67945 0.3048)
			(stroke
				(width 0.1)
				(type default)
			)
			(layer "F.Fab")
		)
		(fp_line
			(start -0.67945 0.3048)
			(end -0.67945 -0.305054)
			(stroke
				(width 0.1)
				(type default)
			)
			(layer "F.Fab")
		)
		(pad "1" smd circle
			(at -0.40005 0 90)
			(size 0 0)
			(layers "F.Cu" "F.Mask" "F.Paste")
			(net "LED_P12V_AUX_R3")
		)
		(pad "2" smd circle
			(at 0.40005 0 90)
			(size 0 0)
			(layers "F.Cu" "F.Mask" "F.Paste")
			(net "P12V_AUX")
		)
	)
	(footprint ""
		(layer "F.Cu")
		(at 479.8695 -468.177372)
		(property "Reference" "JP16_23"
			(at -1.6764 -1.07823 0)
			(unlocked yes)
			(layer "F.SilkS")
			(effects
				(font
					(size 0.7874 0.5842)
					(thickness 0.1524)
				)
				(justify left)
			)
		)
		(property "Value" ""
			(at 0 0 0)
			(layer "F.Fab")
			(effects
				(font
					(size 1.27 1.27)
				)
			)
		)
		(duplicate_pad_numbers_are_jumpers no)
		(pad "1" smd circle
			(at 0 0)
			(size 0.762 0.762)
			(layers "F.Cu" "F.Mask" "F.Paste")
			(net "Net_8623")
		)
	)
	(footprint ""
		(layer "F.Cu")
		(at 191.065404 -32.110426 180)
		(property "Reference" "PD115"
			(at 9.013444 0.703072 0)
			(unlocked yes)
			(layer "F.SilkS")
			(effects
				(font
					(size 0.7874 0.5842)
					(thickness 0.1524)
				)
				(justify left)
			)
		)
		(property "Value" ""
			(at 0 0 180)
			(layer "F.Fab")
			(effects
				(font
					(size 1.27 1.27)
				)
			)
		)
		(duplicate_pad_numbers_are_jumpers no)
		(fp_line
			(start 2.631186 0.999998)
			(end 2.631186 -0.999998)
			(stroke
				(width 0.1524)
				(type default)
			)
			(layer "F.SilkS")
		)
		(fp_line
			(start 2.631186 -0.999998)
			(end -2.250186 -0.999998)
			(stroke
				(width 0.1524)
				(type default)
			)
			(layer "F.SilkS")
		)
		(fp_line
			(start 0.381 -0.0508)
			(end 0.635 -0.0508)
			(stroke
				(width 0.1524)
				(type default)
			)
			(layer "F.SilkS")
		)
		(fp_line
			(start 0.381 -0.0508)
			(end -0.381 0.3302)
			(stroke
				(width 0.1524)
				(type default)
			)
			(layer "F.SilkS")
		)
		(fp_line
			(start 0.381 -0.4318)
			(end 0.381 0.3302)
			(stroke
				(width 0.1524)
				(type default)
			)
			(layer "F.SilkS")
		)
		(fp_line
			(start -0.381 0.3302)
			(end -0.381 -0.4318)
			(stroke
				(width 0.1524)
				(type default)
			)
			(layer "F.SilkS")
		)
		(fp_line
			(start -0.381 -0.0508)
			(end -0.6604 -0.0508)
			(stroke
				(width 0.1524)
				(type default)
			)
			(layer "F.SilkS")
		)
		(fp_line
			(start -0.381 -0.4318)
			(end 0.381 -0.0508)
			(stroke
				(width 0.1524)
				(type default)
			)
			(layer "F.SilkS")
		)
		(fp_line
			(start -2.250186 0.999998)
			(end 2.631186 0.999998)
			(stroke
				(width 0.1524)
				(type default)
			)
			(layer "F.SilkS")
		)
		(fp_line
			(start -2.250186 -0.999998)
			(end -2.250186 0.999998)
			(stroke
				(width 0.1524)
				(type default)
			)
			(layer "F.SilkS")
		)
		(fp_rect
			(start 2.6162 -0.9652)
			(end 2.1844 1.016)
			(stroke
				(width 0)
				(type default)
			)
			(fill yes)
			(layer "F.SilkS")
		)
		(fp_line
			(start 1.450086 0.999998)
			(end 1.450086 -0.999998)
			(stroke
				(width 0.1)
				(type default)
			)
			(layer "F.Fab")
		)
		(fp_line
			(start 1.450086 -0.999998)
			(end -1.450086 -0.999998)
			(stroke
				(width 0.1)
				(type default)
			)
			(layer "F.Fab")
		)
		(fp_line
			(start -1.450086 0.999998)
			(end 1.450086 0.999998)
			(stroke
				(width 0.1)
				(type default)
			)
			(layer "F.Fab")
		)
		(fp_line
			(start -1.450086 -0.999998)
			(end -1.450086 0.999998)
			(stroke
				(width 0.1)
				(type default)
			)
			(layer "F.Fab")
		)
		(fp_text user "-"
			(at 2.4384 -0.22225 180)
			(unlocked yes)
			(layer "F.SilkS")
			(effects
				(font
					(size 1.905 1.4224)
					(thickness 0.1524)
				)
				(justify left)
			)
		)
		(fp_text user "+"
			(at -4.021836 -0.429768 180)
			(unlocked yes)
			(layer "F.SilkS")
			(effects
				(font
					(size 1.905 1.4224)
					(thickness 0.1524)
				)
				(justify left)
			)
		)
		(fp_text user "-"
			(at 2.4384 -0.22225 180)
			(unlocked yes)
			(layer "F.Fab")
			(effects
				(font
					(size 1.905 1.4224)
					(thickness 0.1524)
				)
				(justify left)
			)
		)
		(fp_text user "+"
			(at -3.4798 -0.22225 180)
			(unlocked yes)
			(layer "F.Fab")
			(effects
				(font
					(size 1.905 1.4224)
					(thickness 0.1524)
				)
				(justify left)
			)
		)
		(pad "A" smd rect
			(at -1.450086 0 180)
			(size 1.3208 1.4224)
			(layers "F.Cu" "F.Mask" "F.Paste")
			(net "GND")
		)
		(pad "C" smd rect
			(at 1.450086 0 180)
			(size 1.3208 1.4224)
			(layers "F.Cu" "F.Mask" "F.Paste")
			(net "P12V_AUX")
		)
	)
	(footprint ""
		(layer "F.Cu")
		(at 193.3829 -126.405386)
		(property "Reference" "R4520"
			(at 0 0 0)
			(layer "F.SilkS")
			(hide yes)
			(effects
				(font
					(size 1.27 1.27)
				)
			)
		)
		(property "Value" ""
			(at 0 0 0)
			(layer "F.Fab")
			(effects
				(font
					(size 1.27 1.27)
				)
			)
		)
		(duplicate_pad_numbers_are_jumpers no)
		(fp_line
			(start -0.7874 -0.4064)
			(end 0.7874 -0.4064)
			(stroke
				(width 0.1524)
				(type default)
			)
			(layer "F.SilkS")
		)
		(fp_line
			(start -0.7874 0.4064)
			(end -0.7874 -0.4064)
			(stroke
				(width 0.1524)
				(type default)
			)
			(layer "F.SilkS")
		)
		(fp_line
			(start 0.7874 -0.4064)
			(end 0.7874 0.4064)
			(stroke
				(width 0.1524)
				(type default)
			)
			(layer "F.SilkS")
		)
		(fp_line
			(start 0.7874 0.4064)
			(end -0.7874 0.4064)
			(stroke
				(width 0.1524)
				(type default)
			)
			(layer "F.SilkS")
		)
		(fp_line
			(start -0.67945 -0.305054)
			(end -0.12065 -0.305054)
			(stroke
				(width 0.1)
				(type default)
			)
			(layer "F.Fab")
		)
		(fp_line
			(start -0.67945 0.3048)
			(end -0.67945 -0.305054)
			(stroke
				(width 0.1)
				(type default)
			)
			(layer "F.Fab")
		)
		(fp_line
			(start -0.12065 -0.305054)
			(end -0.12065 -0.2794)
			(stroke
				(width 0.1)
				(type default)
			)
			(layer "F.Fab")
		)
		(fp_line
			(start -0.12065 -0.2794)
			(end 0.12065 -0.2794)
			(stroke
				(width 0.1)
				(type default)
			)
			(layer "F.Fab")
		)
		(fp_line
			(start -0.12065 0.2794)
			(end -0.12065 0.3048)
			(stroke
				(width 0.1)
				(type default)
			)
			(layer "F.Fab")
		)
		(fp_line
			(start -0.12065 0.3048)
			(end -0.67945 0.3048)
			(stroke
				(width 0.1)
				(type default)
			)
			(layer "F.Fab")
		)
		(fp_line
			(start 0.120396 0.2794)
			(end -0.12065 0.2794)
			(stroke
				(width 0.1)
				(type default)
			)
			(layer "F.Fab")
		)
		(fp_line
			(start 0.120396 0.3048)
			(end 0.120396 0.2794)
			(stroke
				(width 0.1)
				(type default)
			)
			(layer "F.Fab")
		)
		(fp_line
			(start 0.12065 -0.3048)
			(end 0.67945 -0.3048)
			(stroke
				(width 0.1)
				(type default)
			)
			(layer "F.Fab")
		)
		(fp_line
			(start 0.12065 -0.2794)
			(end 0.12065 -0.3048)
			(stroke
				(width 0.1)
				(type default)
			)
			(layer "F.Fab")
		)
		(fp_line
			(start 0.67945 -0.3048)
			(end 0.67945 0.3048)
			(stroke
				(width 0.1)
				(type default)
			)
			(layer "F.Fab")
		)
		(fp_line
			(start 0.67945 0.3048)
			(end 0.120396 0.3048)
			(stroke
				(width 0.1)
				(type default)
			)
			(layer "F.Fab")
		)
		(pad "1" smd circle
			(at -0.40005 0)
			(size 0 0)
			(layers "F.Cu" "F.Mask" "F.Paste")
			(net "P3V3")
		)
		(pad "2" smd circle
			(at 0.40005 0)
			(size 0 0)
			(layers "F.Cu" "F.Mask" "F.Paste")
			(net "CLK_SWB_BUF2_OE_N")
		)
	)
	(footprint ""
		(layer "F.Cu")
		(at 424.98772 -51.22418 180)
		(property "Reference" "C2360"
			(at 0 0 180)
			(layer "F.SilkS")
			(hide yes)
			(effects
				(font
					(size 1.27 1.27)
				)
			)
		)
		(property "Value" ""
			(at 0 0 180)
			(layer "F.Fab")
			(effects
				(font
					(size 1.27 1.27)
				)
			)
		)
		(duplicate_pad_numbers_are_jumpers no)
		(fp_line
			(start 0.7874 0.4064)
			(end -0.7874 0.4064)
			(stroke
				(width 0.1524)
				(type default)
			)
			(layer "F.SilkS")
		)
		(fp_line
			(start 0.7874 -0.4064)
			(end 0.7874 0.4064)
			(stroke
				(width 0.1524)
				(type default)
			)
			(layer "F.SilkS")
		)
		(fp_line
			(start -0.7874 0.4064)
			(end -0.7874 -0.4064)
			(stroke
				(width 0.1524)
				(type default)
			)
			(layer "F.SilkS")
		)
		(fp_line
			(start -0.7874 -0.4064)
			(end 0.7874 -0.4064)
			(stroke
				(width 0.1524)
				(type default)
			)
			(layer "F.SilkS")
		)
		(fp_line
			(start 0.6858 0.3048)
			(end 0.1016 0.3048)
			(stroke
				(width 0.1)
				(type default)
			)
			(layer "F.Fab")
		)
		(fp_line
			(start 0.6858 -0.3048)
			(end 0.6858 0.3048)
			(stroke
				(width 0.1)
				(type default)
			)
			(layer "F.Fab")
		)
		(fp_line
			(start 0.1016 0.3048)
			(end 0.1016 0.2794)
			(stroke
				(width 0.1)
				(type default)
			)
			(layer "F.Fab")
		)
		(fp_line
			(start 0.1016 0.2794)
			(end -0.1016 0.2794)
			(stroke
				(width 0.1)
				(type default)
			)
			(layer "F.Fab")
		)
		(fp_line
			(start 0.1016 -0.2794)
			(end 0.1016 -0.3048)
			(stroke
				(width 0.1)
				(type default)
			)
			(layer "F.Fab")
		)
		(fp_line
			(start 0.1016 -0.3048)
			(end 0.6858 -0.3048)
			(stroke
				(width 0.1)
				(type default)
			)
			(layer "F.Fab")
		)
		(fp_line
			(start -0.1016 0.3048)
			(end -0.6858 0.3048)
			(stroke
				(width 0.1)
				(type default)
			)
			(layer "F.Fab")
		)
		(fp_line
			(start -0.1016 0.2794)
			(end -0.1016 0.3048)
			(stroke
				(width 0.1)
				(type default)
			)
			(layer "F.Fab")
		)
		(fp_line
			(start -0.1016 -0.2794)
			(end 0.1016 -0.2794)
			(stroke
				(width 0.1)
				(type default)
			)
			(layer "F.Fab")
		)
		(fp_line
			(start -0.1016 -0.3048)
			(end -0.1016 -0.2794)
			(stroke
				(width 0.1)
				(type default)
			)
			(layer "F.Fab")
		)
		(fp_line
			(start -0.6858 0.3048)
			(end -0.6858 -0.3048)
			(stroke
				(width 0.1)
				(type default)
			)
			(layer "F.Fab")
		)
		(fp_line
			(start -0.6858 -0.3048)
			(end -0.1016 -0.3048)
			(stroke
				(width 0.1)
				(type default)
			)
			(layer "F.Fab")
		)
		(pad "1" smd rect
			(at -0.40005 0)
			(size 0.4572 0.508)
			(layers "F.Cu" "F.Mask" "F.Paste")
			(net "P3V3")
		)
		(pad "2" smd rect
			(at 0.40005 0)
			(size 0.4572 0.508)
			(layers "F.Cu" "F.Mask" "F.Paste")
			(net "GND")
		)
	)
	(footprint ""
		(layer "F.Cu")
		(at 85.576156 -92.888308)
		(property "Reference" "Q80"
			(at -4.63804 -0.635508 0)
			(unlocked yes)
			(layer "F.SilkS")
			(effects
				(font
					(size 0.7874 0.5842)
					(thickness 0.1524)
				)
				(justify left)
			)
		)
		(property "Value" ""
			(at 0 0 0)
			(layer "F.Fab")
			(effects
				(font
					(size 1.27 1.27)
				)
			)
		)
		(duplicate_pad_numbers_are_jumpers no)
		(fp_line
			(start -1.332738 -1.100074)
			(end -0.4826 -1.100074)
			(stroke
				(width 0.1524)
				(type default)
			)
			(layer "F.SilkS")
		)
		(fp_line
			(start -1.332738 1.100074)
			(end -1.332738 -1.100074)
			(stroke
				(width 0.1524)
				(type default)
			)
			(layer "F.SilkS")
		)
		(fp_line
			(start -0.4826 -1.100074)
			(end 0 -0.541274)
			(stroke
				(width 0.1524)
				(type default)
			)
			(layer "F.SilkS")
		)
		(fp_line
			(start 0 -0.541274)
			(end 0.4826 -1.100074)
			(stroke
				(width 0.1524)
				(type default)
			)
			(layer "F.SilkS")
		)
		(fp_line
			(start 0.4826 -1.100074)
			(end 1.332738 -1.100074)
			(stroke
				(width 0.1524)
				(type default)
			)
			(layer "F.SilkS")
		)
		(fp_line
			(start 1.332738 -1.100074)
			(end 1.332738 1.100074)
			(stroke
				(width 0.1524)
				(type default)
			)
			(layer "F.SilkS")
		)
		(fp_line
			(start 1.332738 1.100074)
			(end -1.332738 1.100074)
			(stroke
				(width 0.1524)
				(type default)
			)
			(layer "F.SilkS")
		)
		(fp_poly
			(pts
				(xy -2.2352 -1.001014) (xy -1.533144 -0.649986) (xy -2.2352 -0.298958)
			)
			(stroke
				(width 0)
				(type default)
			)
			(fill yes)
			(layer "F.SilkS")
		)
		(fp_line
			(start -0.674878 -1.100074)
			(end 0.674878 -1.100074)
			(stroke
				(width 0.1)
				(type default)
			)
			(layer "F.Fab")
		)
		(fp_line
			(start -0.674878 1.100074)
			(end -0.674878 -1.100074)
			(stroke
				(width 0.1)
				(type default)
			)
			(layer "F.Fab")
		)
		(fp_line
			(start 0.674878 -1.100074)
			(end 0.674878 1.100074)
			(stroke
				(width 0.1)
				(type default)
			)
			(layer "F.Fab")
		)
		(fp_line
			(start 0.674878 1.100074)
			(end -0.674878 1.100074)
			(stroke
				(width 0.1)
				(type default)
			)
			(layer "F.Fab")
		)
		(fp_poly
			(pts
				(xy -2.2352 -0.298958) (xy -2.2352 -1.001014) (xy -1.533144 -0.649986)
			)
			(stroke
				(width 0)
				(type default)
			)
			(fill yes)
			(layer "F.Fab")
		)
		(pad "1" smd rect
			(at -0.94996 -0.649986 90)
			(size 0.4318 0.508)
			(layers "F.Cu" "F.Mask" "F.Paste")
			(net "GND")
		)
		(pad "2" smd rect
			(at -0.94996 0 90)
			(size 0.4318 0.508)
			(layers "F.Cu" "F.Mask" "F.Paste")
			(net "PWRGD_PVCCFA_EHV_CPU0")
		)
		(pad "3" smd rect
			(at -0.94996 0.649986 90)
			(size 0.4318 0.508)
			(layers "F.Cu" "F.Mask" "F.Paste")
			(net "LED_PWRGD_PVCCFA_EHV_FIVRA_CP_1")
		)
		(pad "4" smd rect
			(at 0.94996 0.649986 90)
			(size 0.4318 0.508)
			(layers "F.Cu" "F.Mask" "F.Paste")
			(net "GND")
		)
		(pad "5" smd rect
			(at 0.94996 0 90)
			(size 0.4318 0.508)
			(layers "F.Cu" "F.Mask" "F.Paste")
			(net "PWRGD_PVCCFA_EHV_FIVRA_CPU0")
		)
		(pad "6" smd rect
			(at 0.94996 -0.649986 90)
			(size 0.4318 0.508)
			(layers "F.Cu" "F.Mask" "F.Paste")
			(net "LED_PWRGD_PVCCFA_EHV_CPU0_D")
		)
	)
	(footprint ""
		(layer "F.Cu")
		(at 421.0558 -17.612614 90)
		(property "Reference" "C860"
			(at 0 0 90)
			(layer "F.SilkS")
			(hide yes)
			(effects
				(font
					(size 1.27 1.27)
				)
			)
		)
		(property "Value" ""
			(at 0 0 90)
			(layer "F.Fab")
			(effects
				(font
					(size 1.27 1.27)
				)
			)
		)
		(duplicate_pad_numbers_are_jumpers no)
		(fp_line
			(start 0.299974 -0.150114)
			(end 0.299974 0.150114)
			(stroke
				(width 0.1)
				(type default)
			)
			(layer "F.Fab")
		)
		(fp_line
			(start -0.299974 -0.150114)
			(end 0.299974 -0.150114)
			(stroke
				(width 0.1)
				(type default)
			)
			(layer "F.Fab")
		)
		(fp_line
			(start 0.299974 0.150114)
			(end -0.299974 0.150114)
			(stroke
				(width 0.1)
				(type default)
			)
			(layer "F.Fab")
		)
		(fp_line
			(start -0.299974 0.150114)
			(end -0.299974 -0.150114)
			(stroke
				(width 0.1)
				(type default)
			)
			(layer "F.Fab")
		)
		(pad "1" smd rect
			(at -0.2667 0 90)
			(size 0.3048 0.381)
			(layers "F.Cu" "F.Mask" "F.Paste")
			(net "P5E_CPU0_PE1_TX_C_DN<4>")
		)
		(pad "2" smd rect
			(at 0.2667 0 90)
			(size 0.3048 0.381)
			(layers "F.Cu" "F.Mask" "F.Paste")
			(net "P5E_CPU0_PE1_TX_DN<4>")
		)
	)
	(footprint ""
		(layer "F.Cu")
		(at 429.267112 -143.1671 -90)
		(property "Reference" "PJ45"
			(at -1.386078 -1.278128 0)
			(unlocked yes)
			(layer "F.SilkS")
			(effects
				(font
					(size 0.7874 0.5842)
					(thickness 0.1524)
				)
				(justify left)
			)
		)
		(property "Value" ""
			(at 0 0 270)
			(layer "F.Fab")
			(effects
				(font
					(size 1.27 1.27)
				)
			)
		)
		(duplicate_pad_numbers_are_jumpers no)
		(pad "1" smd circle
			(at -0.7493 0)
			(size 0 0)
			(layers "F.Cu" "F.Mask" "F.Paste")
			(net "VSENSE_PVCCINFAON_CPU0_DP")
		)
		(pad "2" smd rect
			(at 0.7493 0 180)
			(size 0.7112 0.8128)
			(layers "F.Cu" "F.Mask" "F.Paste")
			(net "SH_PVCCINFAON_CPU0")
		)
		(zone
			(layer "F.Cu")
			(hatch none 0.5)
			(connect_pads
				(clearance 0)
			)
			(min_thickness 0.25)
			(keepout
				(tracks allowed)
				(vias not_allowed)
				(pads allowed)
				(copperpour not_allowed)
				(footprints allowed)
			)
			(placement
				(enabled no)
				(sheetname "")
			)
			(fill
				(thermal_gap 0.5)
				(thermal_bridge_width 0.5)
				(island_removal_mode 0)
			)
			(polygon
				(pts
					(xy 428.855886 -141.9606) (xy 429.673512 -141.9606) (xy 429.673512 -144.3482) (xy 428.855886 -144.3482)
				)
			)
		)
	)
	(footprint ""
		(layer "F.Cu")
		(at 50.437542 -158.211266)
		(property "Reference" "PC446"
			(at 0 0 0)
			(layer "F.SilkS")
			(hide yes)
			(effects
				(font
					(size 1.27 1.27)
				)
			)
		)
		(property "Value" ""
			(at 0 0 0)
			(layer "F.Fab")
			(effects
				(font
					(size 1.27 1.27)
				)
			)
		)
		(duplicate_pad_numbers_are_jumpers no)
		(fp_line
			(start -0.7874 -0.4064)
			(end 0.7874 -0.4064)
			(stroke
				(width 0.1524)
				(type default)
			)
			(layer "F.SilkS")
		)
		(fp_line
			(start -0.7874 0.4064)
			(end -0.7874 -0.4064)
			(stroke
				(width 0.1524)
				(type default)
			)
			(layer "F.SilkS")
		)
		(fp_line
			(start 0.7874 -0.4064)
			(end 0.7874 0.4064)
			(stroke
				(width 0.1524)
				(type default)
			)
			(layer "F.SilkS")
		)
		(fp_line
			(start 0.7874 0.4064)
			(end -0.7874 0.4064)
			(stroke
				(width 0.1524)
				(type default)
			)
			(layer "F.SilkS")
		)
		(fp_line
			(start -0.67945 -0.305054)
			(end -0.12065 -0.305054)
			(stroke
				(width 0.1)
				(type default)
			)
			(layer "F.Fab")
		)
		(fp_line
			(start -0.67945 0.3048)
			(end -0.67945 -0.305054)
			(stroke
				(width 0.1)
				(type default)
			)
			(layer "F.Fab")
		)
		(fp_line
			(start -0.12065 -0.305054)
			(end -0.12065 -0.2794)
			(stroke
				(width 0.1)
				(type default)
			)
			(layer "F.Fab")
		)
		(fp_line
			(start -0.12065 -0.2794)
			(end 0.12065 -0.2794)
			(stroke
				(width 0.1)
				(type default)
			)
			(layer "F.Fab")
		)
		(fp_line
			(start -0.12065 0.2794)
			(end -0.12065 0.3048)
			(stroke
				(width 0.1)
				(type default)
			)
			(layer "F.Fab")
		)
		(fp_line
			(start -0.12065 0.3048)
			(end -0.67945 0.3048)
			(stroke
				(width 0.1)
				(type default)
			)
			(layer "F.Fab")
		)
		(fp_line
			(start 0.120396 0.2794)
			(end -0.12065 0.2794)
			(stroke
				(width 0.1)
				(type default)
			)
			(layer "F.Fab")
		)
		(fp_line
			(start 0.120396 0.3048)
			(end 0.120396 0.2794)
			(stroke
				(width 0.1)
				(type default)
			)
			(layer "F.Fab")
		)
		(fp_line
			(start 0.12065 -0.3048)
			(end 0.67945 -0.3048)
			(stroke
				(width 0.1)
				(type default)
			)
			(layer "F.Fab")
		)
		(fp_line
			(start 0.12065 -0.2794)
			(end 0.12065 -0.3048)
			(stroke
				(width 0.1)
				(type default)
			)
			(layer "F.Fab")
		)
		(fp_line
			(start 0.67945 -0.3048)
			(end 0.67945 0.3048)
			(stroke
				(width 0.1)
				(type default)
			)
			(layer "F.Fab")
		)
		(fp_line
			(start 0.67945 0.3048)
			(end 0.120396 0.3048)
			(stroke
				(width 0.1)
				(type default)
			)
			(layer "F.Fab")
		)
		(pad "1" smd circle
			(at -0.40005 0)
			(size 0 0)
			(layers "F.Cu" "F.Mask" "F.Paste")
			(net "SW_PVCCINFAON_CPU1_BOOT1_R")
		)
		(pad "2" smd circle
			(at 0.40005 0)
			(size 0 0)
			(layers "F.Cu" "F.Mask" "F.Paste")
			(net "SW_PVCCINFAON_CPU1_BOOTR1")
		)
	)
	(footprint ""
		(layer "F.Cu")
		(at 174.879 -411.9626)
		(property "Reference" "JP4003"
			(at 2.060448 3.252724 90)
			(unlocked yes)
			(layer "F.SilkS")
			(effects
				(font
					(size 0.7874 0.5842)
					(thickness 0.1524)
				)
				(justify left)
			)
		)
		(property "Value" ""
			(at 0 0 0)
			(layer "F.Fab")
			(effects
				(font
					(size 1.27 1.27)
				)
			)
		)
		(duplicate_pad_numbers_are_jumpers no)
		(fp_line
			(start -1.249934 -1.320038)
			(end 1.249934 -1.320038)
			(stroke
				(width 0.1524)
				(type default)
			)
			(layer "F.SilkS")
		)
		(fp_line
			(start -1.249934 6.400038)
			(end -1.249934 -1.320038)
			(stroke
				(width 0.1524)
				(type default)
			)
			(layer "F.SilkS")
		)
		(fp_line
			(start 1.249934 -1.320038)
			(end 1.249934 6.400038)
			(stroke
				(width 0.1524)
				(type default)
			)
			(layer "F.SilkS")
		)
		(fp_line
			(start 1.249934 6.400038)
			(end -1.249934 6.400038)
			(stroke
				(width 0.1524)
				(type default)
			)
			(layer "F.SilkS")
		)
		(fp_poly
			(pts
				(xy -1.452372 0) (xy -2.5654 0.556514) (xy -2.5654 -0.556514)
			)
			(stroke
				(width 0)
				(type default)
			)
			(fill yes)
			(layer "F.SilkS")
		)
		(fp_line
			(start -1.249934 -1.320038)
			(end 1.249934 -1.320038)
			(stroke
				(width 0.1)
				(type default)
			)
			(layer "F.Fab")
		)
		(fp_line
			(start -1.249934 6.400038)
			(end -1.249934 -1.320038)
			(stroke
				(width 0.1)
				(type default)
			)
			(layer "F.Fab")
		)
		(fp_line
			(start 1.249934 -1.320038)
			(end 1.249934 6.400038)
			(stroke
				(width 0.1)
				(type default)
			)
			(layer "F.Fab")
		)
		(fp_line
			(start 1.249934 6.400038)
			(end -1.249934 6.400038)
			(stroke
				(width 0.1)
				(type default)
			)
			(layer "F.Fab")
		)
		(fp_poly
			(pts
				(xy -2.5654 -0.556514) (xy -1.452372 0) (xy -2.5654 0.556514)
			)
			(stroke
				(width 0)
				(type default)
			)
			(fill yes)
			(layer "F.Fab")
		)
		(fp_text user "3"
			(at -1.909572 5.30225 180)
			(unlocked yes)
			(layer "F.SilkS")
			(effects
				(font
					(size 0.7874 0.5842)
					(thickness 0.1524)
				)
			)
		)
		(fp_text user "3"
			(at -1.502156 5.17271 180)
			(unlocked yes)
			(layer "B.SilkS")
			(effects
				(font
					(size 0.7874 0.5842)
					(thickness 0.1524)
				)
				(justify mirror)
			)
		)
		(fp_text user "1"
			(at -1.425956 -0.14351 180)
			(unlocked yes)
			(layer "B.SilkS")
			(effects
				(font
					(size 0.7874 0.5842)
					(thickness 0.1524)
				)
				(justify mirror)
			)
		)
		(fp_text user "3"
			(at -1.1557 5.18287 0)
			(unlocked yes)
			(layer "B.Fab")
			(effects
				(font
					(size 0.7874 0.5842)
					(thickness 0.1524)
				)
				(justify mirror)
			)
		)
		(fp_text user "1"
			(at -1.143 0.02667 0)
			(unlocked yes)
			(layer "B.Fab")
			(effects
				(font
					(size 0.7874 0.5842)
					(thickness 0.1524)
				)
				(justify mirror)
			)
		)
		(fp_text user "3"
			(at -1.778 5.13207 0)
			(unlocked yes)
			(layer "F.Fab")
			(effects
				(font
					(size 0.7874 0.5842)
					(thickness 0.1524)
				)
			)
		)
		(pad "1" thru_hole rect
			(at 0 0)
			(size 1.5494 1.5494)
			(drill 1.0414)
			(layers "*.Cu" "*.Mask")
			(remove_unused_layers no)
			(net "Net_1915")
			(clearance 0)
			(padstack
				(mode front_inner_back)
				(layer "Inner"
					(shape circle)
					(size 1.5494 1.5494)
					(clearance 0)
				)
				(layer "B.Cu"
					(shape rect)
					(size 1.5494 1.5494)
					(clearance 0)
				)
			)
		)
		(pad "2" thru_hole circle
			(at 0 2.54)
			(size 1.5494 1.5494)
			(drill 1.0414)
			(layers "*.Cu" "*.Mask")
			(remove_unused_layers no)
			(net "PDB_PRSNT_N")
			(clearance 0)
		)
		(pad "3" thru_hole circle
			(at 0 5.08)
			(size 1.5494 1.5494)
			(drill 1.0414)
			(layers "*.Cu" "*.Mask")
			(remove_unused_layers no)
			(net "GND")
			(clearance 0)
		)
	)
	(footprint ""
		(layer "F.Cu")
		(at 303.48809 -428.85106)
		(property "Reference" "R4577"
			(at 0 0 0)
			(layer "F.SilkS")
			(hide yes)
			(effects
				(font
					(size 1.27 1.27)
				)
			)
		)
		(property "Value" ""
			(at 0 0 0)
			(layer "F.Fab")
			(effects
				(font
					(size 1.27 1.27)
				)
			)
		)
		(duplicate_pad_numbers_are_jumpers no)
		(fp_line
			(start -0.7874 -0.4064)
			(end 0.7874 -0.4064)
			(stroke
				(width 0.1524)
				(type default)
			)
			(layer "F.SilkS")
		)
		(fp_line
			(start -0.7874 0.4064)
			(end -0.7874 -0.4064)
			(stroke
				(width 0.1524)
				(type default)
			)
			(layer "F.SilkS")
		)
		(fp_line
			(start 0.7874 -0.4064)
			(end 0.7874 0.4064)
			(stroke
				(width 0.1524)
				(type default)
			)
			(layer "F.SilkS")
		)
		(fp_line
			(start 0.7874 0.4064)
			(end -0.7874 0.4064)
			(stroke
				(width 0.1524)
				(type default)
			)
			(layer "F.SilkS")
		)
		(fp_line
			(start -0.67945 -0.305054)
			(end -0.12065 -0.305054)
			(stroke
				(width 0.1)
				(type default)
			)
			(layer "F.Fab")
		)
		(fp_line
			(start -0.67945 0.3048)
			(end -0.67945 -0.305054)
			(stroke
				(width 0.1)
				(type default)
			)
			(layer "F.Fab")
		)
		(fp_line
			(start -0.12065 -0.305054)
			(end -0.12065 -0.2794)
			(stroke
				(width 0.1)
				(type default)
			)
			(layer "F.Fab")
		)
		(fp_line
			(start -0.12065 -0.2794)
			(end 0.12065 -0.2794)
			(stroke
				(width 0.1)
				(type default)
			)
			(layer "F.Fab")
		)
		(fp_line
			(start -0.12065 0.2794)
			(end -0.12065 0.3048)
			(stroke
				(width 0.1)
				(type default)
			)
			(layer "F.Fab")
		)
		(fp_line
			(start -0.12065 0.3048)
			(end -0.67945 0.3048)
			(stroke
				(width 0.1)
				(type default)
			)
			(layer "F.Fab")
		)
		(fp_line
			(start 0.120396 0.2794)
			(end -0.12065 0.2794)
			(stroke
				(width 0.1)
				(type default)
			)
			(layer "F.Fab")
		)
		(fp_line
			(start 0.120396 0.3048)
			(end 0.120396 0.2794)
			(stroke
				(width 0.1)
				(type default)
			)
			(layer "F.Fab")
		)
		(fp_line
			(start 0.12065 -0.3048)
			(end 0.67945 -0.3048)
			(stroke
				(width 0.1)
				(type default)
			)
			(layer "F.Fab")
		)
		(fp_line
			(start 0.12065 -0.2794)
			(end 0.12065 -0.3048)
			(stroke
				(width 0.1)
				(type default)
			)
			(layer "F.Fab")
		)
		(fp_line
			(start 0.67945 -0.3048)
			(end 0.67945 0.3048)
			(stroke
				(width 0.1)
				(type default)
			)
			(layer "F.Fab")
		)
		(fp_line
			(start 0.67945 0.3048)
			(end 0.120396 0.3048)
			(stroke
				(width 0.1)
				(type default)
			)
			(layer "F.Fab")
		)
		(pad "1" smd circle
			(at -0.40005 0)
			(size 0 0)
			(layers "F.Cu" "F.Mask" "F.Paste")
			(net "GPU_3V3IO_RSVD3_FFU")
		)
		(pad "2" smd circle
			(at 0.40005 0)
			(size 0 0)
			(layers "F.Cu" "F.Mask" "F.Paste")
			(net "GPU_3V3IO_RSVD3_FFU_ISO")
		)
	)
	(footprint ""
		(layer "F.Cu")
		(at 238.187738 -119.183658 -90)
		(property "Reference" "R3197"
			(at 0 0 270)
			(layer "F.SilkS")
			(hide yes)
			(effects
				(font
					(size 1.27 1.27)
				)
			)
		)
		(property "Value" ""
			(at 0 0 270)
			(layer "F.Fab")
			(effects
				(font
					(size 1.27 1.27)
				)
			)
		)
		(duplicate_pad_numbers_are_jumpers no)
		(fp_line
			(start 0.438658 0.4064)
			(end -0.287782 0.4064)
			(stroke
				(width 0.1524)
				(type default)
			)
			(layer "F.SilkS")
		)
		(fp_line
			(start -0.7874 0.121158)
			(end -0.7874 -0.4064)
			(stroke
				(width 0.1524)
				(type default)
			)
			(layer "F.SilkS")
		)
		(fp_line
			(start -0.7874 -0.4064)
			(end 0.7874 -0.4064)
			(stroke
				(width 0.1524)
				(type default)
			)
			(layer "F.SilkS")
		)
		(fp_line
			(start 0.7874 -0.4064)
			(end 0.7874 0.055118)
			(stroke
				(width 0.1524)
				(type default)
			)
			(layer "F.SilkS")
		)
		(fp_line
			(start -0.67945 0.3048)
			(end -0.67945 -0.305054)
			(stroke
				(width 0.1)
				(type default)
			)
			(layer "F.Fab")
		)
		(fp_line
			(start -0.12065 0.3048)
			(end -0.67945 0.3048)
			(stroke
				(width 0.1)
				(type default)
			)
			(layer "F.Fab")
		)
		(fp_line
			(start 0.120396 0.3048)
			(end 0.120396 0.2794)
			(stroke
				(width 0.1)
				(type default)
			)
			(layer "F.Fab")
		)
		(fp_line
			(start 0.67945 0.3048)
			(end 0.120396 0.3048)
			(stroke
				(width 0.1)
				(type default)
			)
			(layer "F.Fab")
		)
		(fp_line
			(start -0.12065 0.2794)
			(end -0.12065 0.3048)
			(stroke
				(width 0.1)
				(type default)
			)
			(layer "F.Fab")
		)
		(fp_line
			(start 0.120396 0.2794)
			(end -0.12065 0.2794)
			(stroke
				(width 0.1)
				(type default)
			)
			(layer "F.Fab")
		)
		(fp_line
			(start -0.12065 -0.2794)
			(end 0.12065 -0.2794)
			(stroke
				(width 0.1)
				(type default)
			)
			(layer "F.Fab")
		)
		(fp_line
			(start 0.12065 -0.2794)
			(end 0.12065 -0.3048)
			(stroke
				(width 0.1)
				(type default)
			)
			(layer "F.Fab")
		)
		(fp_line
			(start 0.12065 -0.3048)
			(end 0.67945 -0.3048)
			(stroke
				(width 0.1)
				(type default)
			)
			(layer "F.Fab")
		)
		(fp_line
			(start 0.67945 -0.3048)
			(end 0.67945 0.3048)
			(stroke
				(width 0.1)
				(type default)
			)
			(layer "F.Fab")
		)
		(fp_line
			(start -0.67945 -0.305054)
			(end -0.12065 -0.305054)
			(stroke
				(width 0.1)
				(type default)
			)
			(layer "F.Fab")
		)
		(fp_line
			(start -0.12065 -0.305054)
			(end -0.12065 -0.2794)
			(stroke
				(width 0.1)
				(type default)
			)
			(layer "F.Fab")
		)
		(pad "1" smd circle
			(at -0.40005 0 270)
			(size 0 0)
			(layers "F.Cu" "F.Mask" "F.Paste")
			(net "CLK_100M_OCP_V3_2_B_R_DN")
		)
		(pad "2" smd circle
			(at 0.40005 0 270)
			(size 0 0)
			(layers "F.Cu" "F.Mask" "F.Paste")
			(net "CLK_100M_OCP_V3_2_B_DN")
		)
	)
	(footprint ""
		(layer "F.Cu")
		(at 150.68296 -22.73808 90)
		(property "Reference" "R4720"
			(at 0 0 90)
			(layer "F.SilkS")
			(hide yes)
			(effects
				(font
					(size 1.27 1.27)
				)
			)
		)
		(property "Value" ""
			(at 0 0 90)
			(layer "F.Fab")
			(effects
				(font
					(size 1.27 1.27)
				)
			)
		)
		(duplicate_pad_numbers_are_jumpers no)
		(fp_line
			(start 0.7874 -0.4064)
			(end 0.7874 0.4064)
			(stroke
				(width 0.1524)
				(type default)
			)
			(layer "F.SilkS")
		)
		(fp_line
			(start -0.7874 -0.4064)
			(end 0.7874 -0.4064)
			(stroke
				(width 0.1524)
				(type default)
			)
			(layer "F.SilkS")
		)
		(fp_line
			(start 0.7874 0.4064)
			(end -0.7874 0.4064)
			(stroke
				(width 0.1524)
				(type default)
			)
			(layer "F.SilkS")
		)
		(fp_line
			(start -0.7874 0.4064)
			(end -0.7874 -0.4064)
			(stroke
				(width 0.1524)
				(type default)
			)
			(layer "F.SilkS")
		)
		(fp_line
			(start -0.12065 -0.305054)
			(end -0.12065 -0.2794)
			(stroke
				(width 0.1)
				(type default)
			)
			(layer "F.Fab")
		)
		(fp_line
			(start -0.67945 -0.305054)
			(end -0.12065 -0.305054)
			(stroke
				(width 0.1)
				(type default)
			)
			(layer "F.Fab")
		)
		(fp_line
			(start 0.67945 -0.3048)
			(end 0.67945 0.3048)
			(stroke
				(width 0.1)
				(type default)
			)
			(layer "F.Fab")
		)
		(fp_line
			(start 0.12065 -0.3048)
			(end 0.67945 -0.3048)
			(stroke
				(width 0.1)
				(type default)
			)
			(layer "F.Fab")
		)
		(fp_line
			(start 0.12065 -0.2794)
			(end 0.12065 -0.3048)
			(stroke
				(width 0.1)
				(type default)
			)
			(layer "F.Fab")
		)
		(fp_line
			(start -0.12065 -0.2794)
			(end 0.12065 -0.2794)
			(stroke
				(width 0.1)
				(type default)
			)
			(layer "F.Fab")
		)
		(fp_line
			(start 0.120396 0.2794)
			(end -0.12065 0.2794)
			(stroke
				(width 0.1)
				(type default)
			)
			(layer "F.Fab")
		)
		(fp_line
			(start -0.12065 0.2794)
			(end -0.12065 0.3048)
			(stroke
				(width 0.1)
				(type default)
			)
			(layer "F.Fab")
		)
		(fp_line
			(start 0.67945 0.3048)
			(end 0.120396 0.3048)
			(stroke
				(width 0.1)
				(type default)
			)
			(layer "F.Fab")
		)
		(fp_line
			(start 0.120396 0.3048)
			(end 0.120396 0.2794)
			(stroke
				(width 0.1)
				(type default)
			)
			(layer "F.Fab")
		)
		(fp_line
			(start -0.12065 0.3048)
			(end -0.67945 0.3048)
			(stroke
				(width 0.1)
				(type default)
			)
			(layer "F.Fab")
		)
		(fp_line
			(start -0.67945 0.3048)
			(end -0.67945 -0.305054)
			(stroke
				(width 0.1)
				(type default)
			)
			(layer "F.Fab")
		)
		(pad "1" smd circle
			(at -0.40005 0 90)
			(size 0 0)
			(layers "F.Cu" "F.Mask" "F.Paste")
			(net "FM_AC_PWR_BTN_N")
		)
		(pad "2" smd circle
			(at 0.40005 0 90)
			(size 0 0)
			(layers "F.Cu" "F.Mask" "F.Paste")
			(net "FM_AC_PWR_BTN_R_N")
		)
	)
	(footprint ""
		(layer "F.Cu")
		(at 182.14594 2.921)
		(property "Reference" "J79"
			(at -4.31927 1.016 90)
			(unlocked yes)
			(layer "F.SilkS")
			(effects
				(font
					(size 0.7874 0.5842)
					(thickness 0.1524)
				)
				(justify left)
			)
		)
		(property "Value" ""
			(at 0 0 0)
			(layer "F.Fab")
			(effects
				(font
					(size 1.27 1.27)
				)
			)
		)
		(duplicate_pad_numbers_are_jumpers no)
		(fp_line
			(start -1.2192 -2.1082)
			(end 1.2192 -2.1082)
			(stroke
				(width 0.1524)
				(type default)
			)
			(layer "F.SilkS")
		)
		(fp_line
			(start -1.2192 2.1082)
			(end -1.2192 -2.1082)
			(stroke
				(width 0.1524)
				(type default)
			)
			(layer "F.SilkS")
		)
		(fp_line
			(start 1.2192 -2.1082)
			(end 1.2192 2.1082)
			(stroke
				(width 0.1524)
				(type default)
			)
			(layer "F.SilkS")
		)
		(fp_line
			(start 1.2192 2.1082)
			(end -1.2192 2.1082)
			(stroke
				(width 0.1524)
				(type default)
			)
			(layer "F.SilkS")
		)
		(pad "" np_thru_hole circle
			(at -2.8829 -1.27 270)
			(size 1.0414 1.0414)
			(drill 1.0414)
			(layers "*.Cu" "*.Mask")
			(clearance 0.381)
			(thermal_gap 0.381)
		)
		(pad "" np_thru_hole circle
			(at -2.8829 1.27 270)
			(size 1.0414 1.0414)
			(drill 1.0414)
			(layers "*.Cu" "*.Mask")
			(clearance 0.381)
			(thermal_gap 0.381)
		)
		(pad "" np_thru_hole circle
			(at 3.4671 -1.27 270)
			(size 1.0414 1.0414)
			(drill 1.0414)
			(layers "*.Cu" "*.Mask")
			(clearance 0.381)
			(thermal_gap 0.381)
		)
		(pad "" np_thru_hole circle
			(at 3.4671 1.27 270)
			(size 1.0414 1.0414)
			(drill 1.0414)
			(layers "*.Cu" "*.Mask")
			(clearance 0.381)
			(thermal_gap 0.381)
		)
		(pad "1" smd rect
			(at 0.8255 -0.249936 270)
			(size 0.3048 0.508)
			(layers "F.Cu" "F.Mask" "F.Paste")
			(net "DELTA_L_85_10INCH_IN3_DP")
		)
		(pad "2" smd rect
			(at 0.8255 0.249936 270)
			(size 0.3048 0.508)
			(layers "F.Cu" "F.Mask" "F.Paste")
			(net "DELTA_L_85_10INCH_IN3_DN")
		)
		(pad "3" smd circle
			(at 0 0)
			(size 0 0)
			(layers "F.Cu" "F.Mask" "F.Paste")
			(net "DELTA_L_GND_1")
		)
		(zone
			(layer "F.Cu")
			(hatch none 0.5)
			(connect_pads
				(clearance 0)
			)
			(min_thickness 0.25)
			(keepout
				(tracks not_allowed)
				(vias allowed)
				(pads allowed)
				(copperpour not_allowed)
				(footprints allowed)
			)
			(placement
				(enabled no)
				(sheetname "")
			)
			(fill
				(thermal_gap 0.5)
				(thermal_bridge_width 0.5)
				(island_removal_mode 0)
			)
			(polygon
				(pts
					(xy 183.26354 2.37236) (xy 183.26354 2.467864) (xy 182.66664 2.467864) (xy 182.66664 2.874264)
					(xy 183.26354 2.874264) (xy 183.26354 2.967736) (xy 182.66664 2.967736) (xy 182.66664 3.374136)
					(xy 183.26354 3.374136) (xy 183.26354 3.46964) (xy 182.56504 3.46964) (xy 182.56504 2.37236)
				)
			)
		)
		(zone
			(layers "F.Cu" "B.Cu" "In1.Cu" "In2.Cu" "In3.Cu" "In4.Cu" "In5.Cu" "In6.Cu"
				"In7.Cu" "In8.Cu" "In9.Cu" "In10.Cu" "In11.Cu" "In12.Cu" "In13.Cu" "In14.Cu"
				"In15.Cu" "In16.Cu"
			)
			(hatch none 0.5)
			(connect_pads
				(clearance 0)
			)
			(min_thickness 0.25)
			(keepout
				(tracks not_allowed)
				(vias allowed)
				(pads allowed)
				(copperpour not_allowed)
				(footprints allowed)
			)
			(placement
				(enabled no)
				(sheetname "")
			)
			(fill
				(thermal_gap 0.5)
				(thermal_bridge_width 0.5)
				(island_removal_mode 0)
			)
			(polygon
				(pts
					(arc
						(start 180.19014 1.651)
						(mid 178.33594 1.651)
						(end 180.19014 1.651)
					)
				)
			)
		)
		(zone
			(layers "F.Cu" "B.Cu" "In1.Cu" "In2.Cu" "In3.Cu" "In4.Cu" "In5.Cu" "In6.Cu"
				"In7.Cu" "In8.Cu" "In9.Cu" "In10.Cu" "In11.Cu" "In12.Cu" "In13.Cu" "In14.Cu"
				"In15.Cu" "In16.Cu"
			)
			(hatch none 0.5)
			(connect_pads
				(clearance 0)
			)
			(min_thickness 0.25)
			(keepout
				(tracks not_allowed)
				(vias allowed)
				(pads allowed)
				(copperpour not_allowed)
				(footprints allowed)
			)
			(placement
				(enabled no)
				(sheetname "")
			)
			(fill
				(thermal_gap 0.5)
				(thermal_bridge_width 0.5)
				(island_removal_mode 0)
			)
			(polygon
				(pts
					(arc
						(start 180.19014 4.191)
						(mid 178.33594 4.191)
						(end 180.19014 4.191)
					)
				)
			)
		)
		(zone
			(layers "F.Cu" "B.Cu" "In1.Cu" "In2.Cu" "In3.Cu" "In4.Cu" "In5.Cu" "In6.Cu"
				"In7.Cu" "In8.Cu" "In9.Cu" "In10.Cu" "In11.Cu" "In12.Cu" "In13.Cu" "In14.Cu"
				"In15.Cu" "In16.Cu"
			)
			(hatch none 0.5)
			(connect_pads
				(clearance 0)
			)
			(min_thickness 0.25)
			(keepout
				(tracks not_allowed)
				(vias allowed)
				(pads allowed)
				(copperpour not_allowed)
				(footprints allowed)
			)
			(placement
				(enabled no)
				(sheetname "")
			)
			(fill
				(thermal_gap 0.5)
				(thermal_bridge_width 0.5)
				(island_removal_mode 0)
			)
			(polygon
				(pts
					(arc
						(start 186.54014 1.651)
						(mid 184.68594 1.651)
						(end 186.54014 1.651)
					)
				)
			)
		)
		(zone
			(layers "F.Cu" "B.Cu" "In1.Cu" "In2.Cu" "In3.Cu" "In4.Cu" "In5.Cu" "In6.Cu"
				"In7.Cu" "In8.Cu" "In9.Cu" "In10.Cu" "In11.Cu" "In12.Cu" "In13.Cu" "In14.Cu"
				"In15.Cu" "In16.Cu"
			)
			(hatch none 0.5)
			(connect_pads
				(clearance 0)
			)
			(min_thickness 0.25)
			(keepout
				(tracks not_allowed)
				(vias allowed)
				(pads allowed)
				(copperpour not_allowed)
				(footprints allowed)
			)
			(placement
				(enabled no)
				(sheetname "")
			)
			(fill
				(thermal_gap 0.5)
				(thermal_bridge_width 0.5)
				(island_removal_mode 0)
			)
			(polygon
				(pts
					(arc
						(start 186.54014 4.191)
						(mid 184.68594 4.191)
						(end 186.54014 4.191)
					)
				)
			)
		)
	)
	(footprint ""
		(layer "F.Cu")
		(at 248.740676 -90.65514)
		(property "Reference" "C2036"
			(at 0 0 0)
			(layer "F.SilkS")
			(hide yes)
			(effects
				(font
					(size 1.27 1.27)
				)
			)
		)
		(property "Value" ""
			(at 0 0 0)
			(layer "F.Fab")
			(effects
				(font
					(size 1.27 1.27)
				)
			)
		)
		(duplicate_pad_numbers_are_jumpers no)
		(fp_line
			(start -0.7874 -0.4064)
			(end 0.7874 -0.4064)
			(stroke
				(width 0.1524)
				(type default)
			)
			(layer "F.SilkS")
		)
		(fp_line
			(start -0.7874 0.4064)
			(end -0.7874 -0.4064)
			(stroke
				(width 0.1524)
				(type default)
			)
			(layer "F.SilkS")
		)
		(fp_line
			(start 0.7874 -0.4064)
			(end 0.7874 0.4064)
			(stroke
				(width 0.1524)
				(type default)
			)
			(layer "F.SilkS")
		)
		(fp_line
			(start 0.7874 0.4064)
			(end -0.7874 0.4064)
			(stroke
				(width 0.1524)
				(type default)
			)
			(layer "F.SilkS")
		)
		(fp_line
			(start -0.67945 -0.305054)
			(end -0.12065 -0.305054)
			(stroke
				(width 0.1)
				(type default)
			)
			(layer "F.Fab")
		)
		(fp_line
			(start -0.67945 0.3048)
			(end -0.67945 -0.305054)
			(stroke
				(width 0.1)
				(type default)
			)
			(layer "F.Fab")
		)
		(fp_line
			(start -0.12065 -0.305054)
			(end -0.12065 -0.2794)
			(stroke
				(width 0.1)
				(type default)
			)
			(layer "F.Fab")
		)
		(fp_line
			(start -0.12065 -0.2794)
			(end 0.12065 -0.2794)
			(stroke
				(width 0.1)
				(type default)
			)
			(layer "F.Fab")
		)
		(fp_line
			(start -0.12065 0.2794)
			(end -0.12065 0.3048)
			(stroke
				(width 0.1)
				(type default)
			)
			(layer "F.Fab")
		)
		(fp_line
			(start -0.12065 0.3048)
			(end -0.67945 0.3048)
			(stroke
				(width 0.1)
				(type default)
			)
			(layer "F.Fab")
		)
		(fp_line
			(start 0.120396 0.2794)
			(end -0.12065 0.2794)
			(stroke
				(width 0.1)
				(type default)
			)
			(layer "F.Fab")
		)
		(fp_line
			(start 0.120396 0.3048)
			(end 0.120396 0.2794)
			(stroke
				(width 0.1)
				(type default)
			)
			(layer "F.Fab")
		)
		(fp_line
			(start 0.12065 -0.3048)
			(end 0.67945 -0.3048)
			(stroke
				(width 0.1)
				(type default)
			)
			(layer "F.Fab")
		)
		(fp_line
			(start 0.12065 -0.2794)
			(end 0.12065 -0.3048)
			(stroke
				(width 0.1)
				(type default)
			)
			(layer "F.Fab")
		)
		(fp_line
			(start 0.67945 -0.3048)
			(end 0.67945 0.3048)
			(stroke
				(width 0.1)
				(type default)
			)
			(layer "F.Fab")
		)
		(fp_line
			(start 0.67945 0.3048)
			(end 0.120396 0.3048)
			(stroke
				(width 0.1)
				(type default)
			)
			(layer "F.Fab")
		)
		(pad "1" smd circle
			(at -0.40005 0)
			(size 0 0)
			(layers "F.Cu" "F.Mask" "F.Paste")
			(net "XTAL_CLK_GEN1_25M_X1_R")
		)
		(pad "2" smd circle
			(at 0.40005 0)
			(size 0 0)
			(layers "F.Cu" "F.Mask" "F.Paste")
			(net "GND")
		)
	)
	(footprint ""
		(layer "F.Cu")
		(at 176.391062 -32.935672 90)
		(property "Reference" "PC2232"
			(at 0 0 90)
			(layer "F.SilkS")
			(hide yes)
			(effects
				(font
					(size 1.27 1.27)
				)
			)
		)
		(property "Value" ""
			(at 0 0 90)
			(layer "F.Fab")
			(effects
				(font
					(size 1.27 1.27)
				)
			)
		)
		(duplicate_pad_numbers_are_jumpers no)
		(fp_line
			(start 0.7874 -0.4064)
			(end 0.7874 0.4064)
			(stroke
				(width 0.1524)
				(type default)
			)
			(layer "F.SilkS")
		)
		(fp_line
			(start -0.7874 -0.4064)
			(end 0.7874 -0.4064)
			(stroke
				(width 0.1524)
				(type default)
			)
			(layer "F.SilkS")
		)
		(fp_line
			(start 0.7874 0.4064)
			(end -0.7874 0.4064)
			(stroke
				(width 0.1524)
				(type default)
			)
			(layer "F.SilkS")
		)
		(fp_line
			(start -0.7874 0.4064)
			(end -0.7874 -0.4064)
			(stroke
				(width 0.1524)
				(type default)
			)
			(layer "F.SilkS")
		)
		(fp_line
			(start -0.12065 -0.305054)
			(end -0.12065 -0.2794)
			(stroke
				(width 0.1)
				(type default)
			)
			(layer "F.Fab")
		)
		(fp_line
			(start -0.67945 -0.305054)
			(end -0.12065 -0.305054)
			(stroke
				(width 0.1)
				(type default)
			)
			(layer "F.Fab")
		)
		(fp_line
			(start 0.67945 -0.3048)
			(end 0.67945 0.3048)
			(stroke
				(width 0.1)
				(type default)
			)
			(layer "F.Fab")
		)
		(fp_line
			(start 0.12065 -0.3048)
			(end 0.67945 -0.3048)
			(stroke
				(width 0.1)
				(type default)
			)
			(layer "F.Fab")
		)
		(fp_line
			(start 0.12065 -0.2794)
			(end 0.12065 -0.3048)
			(stroke
				(width 0.1)
				(type default)
			)
			(layer "F.Fab")
		)
		(fp_line
			(start -0.12065 -0.2794)
			(end 0.12065 -0.2794)
			(stroke
				(width 0.1)
				(type default)
			)
			(layer "F.Fab")
		)
		(fp_line
			(start 0.120396 0.2794)
			(end -0.12065 0.2794)
			(stroke
				(width 0.1)
				(type default)
			)
			(layer "F.Fab")
		)
		(fp_line
			(start -0.12065 0.2794)
			(end -0.12065 0.3048)
			(stroke
				(width 0.1)
				(type default)
			)
			(layer "F.Fab")
		)
		(fp_line
			(start 0.67945 0.3048)
			(end 0.120396 0.3048)
			(stroke
				(width 0.1)
				(type default)
			)
			(layer "F.Fab")
		)
		(fp_line
			(start 0.120396 0.3048)
			(end 0.120396 0.2794)
			(stroke
				(width 0.1)
				(type default)
			)
			(layer "F.Fab")
		)
		(fp_line
			(start -0.12065 0.3048)
			(end -0.67945 0.3048)
			(stroke
				(width 0.1)
				(type default)
			)
			(layer "F.Fab")
		)
		(fp_line
			(start -0.67945 0.3048)
			(end -0.67945 -0.305054)
			(stroke
				(width 0.1)
				(type default)
			)
			(layer "F.Fab")
		)
		(pad "1" smd circle
			(at -0.40005 0 90)
			(size 0 0)
			(layers "F.Cu" "F.Mask" "F.Paste")
			(net "P12V_SCM_SS")
		)
		(pad "2" smd circle
			(at 0.40005 0 90)
			(size 0 0)
			(layers "F.Cu" "F.Mask" "F.Paste")
			(net "GND")
		)
	)
	(footprint ""
		(layer "F.Cu")
		(at 304.1396 -421.49395 90)
		(property "Reference" "R4128"
			(at 0 0 90)
			(layer "F.SilkS")
			(hide yes)
			(effects
				(font
					(size 1.27 1.27)
				)
			)
		)
		(property "Value" ""
			(at 0 0 90)
			(layer "F.Fab")
			(effects
				(font
					(size 1.27 1.27)
				)
			)
		)
		(duplicate_pad_numbers_are_jumpers no)
		(fp_line
			(start 0.7874 -0.4064)
			(end 0.7874 0.4064)
			(stroke
				(width 0.1524)
				(type default)
			)
			(layer "F.SilkS")
		)
		(fp_line
			(start -0.7874 -0.4064)
			(end 0.7874 -0.4064)
			(stroke
				(width 0.1524)
				(type default)
			)
			(layer "F.SilkS")
		)
		(fp_line
			(start 0.7874 0.4064)
			(end -0.7874 0.4064)
			(stroke
				(width 0.1524)
				(type default)
			)
			(layer "F.SilkS")
		)
		(fp_line
			(start -0.7874 0.4064)
			(end -0.7874 -0.4064)
			(stroke
				(width 0.1524)
				(type default)
			)
			(layer "F.SilkS")
		)
		(fp_line
			(start -0.12065 -0.305054)
			(end -0.12065 -0.2794)
			(stroke
				(width 0.1)
				(type default)
			)
			(layer "F.Fab")
		)
		(fp_line
			(start -0.67945 -0.305054)
			(end -0.12065 -0.305054)
			(stroke
				(width 0.1)
				(type default)
			)
			(layer "F.Fab")
		)
		(fp_line
			(start 0.67945 -0.3048)
			(end 0.67945 0.3048)
			(stroke
				(width 0.1)
				(type default)
			)
			(layer "F.Fab")
		)
		(fp_line
			(start 0.12065 -0.3048)
			(end 0.67945 -0.3048)
			(stroke
				(width 0.1)
				(type default)
			)
			(layer "F.Fab")
		)
		(fp_line
			(start 0.12065 -0.2794)
			(end 0.12065 -0.3048)
			(stroke
				(width 0.1)
				(type default)
			)
			(layer "F.Fab")
		)
		(fp_line
			(start -0.12065 -0.2794)
			(end 0.12065 -0.2794)
			(stroke
				(width 0.1)
				(type default)
			)
			(layer "F.Fab")
		)
		(fp_line
			(start 0.120396 0.2794)
			(end -0.12065 0.2794)
			(stroke
				(width 0.1)
				(type default)
			)
			(layer "F.Fab")
		)
		(fp_line
			(start -0.12065 0.2794)
			(end -0.12065 0.3048)
			(stroke
				(width 0.1)
				(type default)
			)
			(layer "F.Fab")
		)
		(fp_line
			(start 0.67945 0.3048)
			(end 0.120396 0.3048)
			(stroke
				(width 0.1)
				(type default)
			)
			(layer "F.Fab")
		)
		(fp_line
			(start 0.120396 0.3048)
			(end 0.120396 0.2794)
			(stroke
				(width 0.1)
				(type default)
			)
			(layer "F.Fab")
		)
		(fp_line
			(start -0.12065 0.3048)
			(end -0.67945 0.3048)
			(stroke
				(width 0.1)
				(type default)
			)
			(layer "F.Fab")
		)
		(fp_line
			(start -0.67945 0.3048)
			(end -0.67945 -0.305054)
			(stroke
				(width 0.1)
				(type default)
			)
			(layer "F.Fab")
		)
		(pad "1" smd circle
			(at -0.40005 0 90)
			(size 0 0)
			(layers "F.Cu" "F.Mask" "F.Paste")
			(net "P3V3_AUX")
		)
		(pad "2" smd circle
			(at 0.40005 0 90)
			(size 0 0)
			(layers "F.Cu" "F.Mask" "F.Paste")
			(net "GPU_3V3IO_RSVD0_FFU_ISO")
		)
	)
	(footprint ""
		(layer "F.Cu")
		(at 418.6936 -51.87442 90)
		(property "Reference" "R4677"
			(at 0 0 90)
			(layer "F.SilkS")
			(hide yes)
			(effects
				(font
					(size 1.27 1.27)
				)
			)
		)
		(property "Value" ""
			(at 0 0 90)
			(layer "F.Fab")
			(effects
				(font
					(size 1.27 1.27)
				)
			)
		)
		(duplicate_pad_numbers_are_jumpers no)
		(fp_line
			(start 0.7874 -0.4064)
			(end 0.7874 0.4064)
			(stroke
				(width 0.1524)
				(type default)
			)
			(layer "F.SilkS")
		)
		(fp_line
			(start -0.7874 -0.4064)
			(end 0.7874 -0.4064)
			(stroke
				(width 0.1524)
				(type default)
			)
			(layer "F.SilkS")
		)
		(fp_line
			(start 0.7874 0.4064)
			(end -0.7874 0.4064)
			(stroke
				(width 0.1524)
				(type default)
			)
			(layer "F.SilkS")
		)
		(fp_line
			(start -0.7874 0.4064)
			(end -0.7874 -0.4064)
			(stroke
				(width 0.1524)
				(type default)
			)
			(layer "F.SilkS")
		)
		(fp_line
			(start -0.12065 -0.305054)
			(end -0.12065 -0.2794)
			(stroke
				(width 0.1)
				(type default)
			)
			(layer "F.Fab")
		)
		(fp_line
			(start -0.67945 -0.305054)
			(end -0.12065 -0.305054)
			(stroke
				(width 0.1)
				(type default)
			)
			(layer "F.Fab")
		)
		(fp_line
			(start 0.67945 -0.3048)
			(end 0.67945 0.3048)
			(stroke
				(width 0.1)
				(type default)
			)
			(layer "F.Fab")
		)
		(fp_line
			(start 0.12065 -0.3048)
			(end 0.67945 -0.3048)
			(stroke
				(width 0.1)
				(type default)
			)
			(layer "F.Fab")
		)
		(fp_line
			(start 0.12065 -0.2794)
			(end 0.12065 -0.3048)
			(stroke
				(width 0.1)
				(type default)
			)
			(layer "F.Fab")
		)
		(fp_line
			(start -0.12065 -0.2794)
			(end 0.12065 -0.2794)
			(stroke
				(width 0.1)
				(type default)
			)
			(layer "F.Fab")
		)
		(fp_line
			(start 0.120396 0.2794)
			(end -0.12065 0.2794)
			(stroke
				(width 0.1)
				(type default)
			)
			(layer "F.Fab")
		)
		(fp_line
			(start -0.12065 0.2794)
			(end -0.12065 0.3048)
			(stroke
				(width 0.1)
				(type default)
			)
			(layer "F.Fab")
		)
		(fp_line
			(start 0.67945 0.3048)
			(end 0.120396 0.3048)
			(stroke
				(width 0.1)
				(type default)
			)
			(layer "F.Fab")
		)
		(fp_line
			(start 0.120396 0.3048)
			(end 0.120396 0.2794)
			(stroke
				(width 0.1)
				(type default)
			)
			(layer "F.Fab")
		)
		(fp_line
			(start -0.12065 0.3048)
			(end -0.67945 0.3048)
			(stroke
				(width 0.1)
				(type default)
			)
			(layer "F.Fab")
		)
		(fp_line
			(start -0.67945 0.3048)
			(end -0.67945 -0.305054)
			(stroke
				(width 0.1)
				(type default)
			)
			(layer "F.Fab")
		)
		(pad "1" smd circle
			(at -0.40005 0 90)
			(size 0 0)
			(layers "F.Cu" "F.Mask" "F.Paste")
			(net "PWRGD_P3V3_R1")
		)
		(pad "2" smd circle
			(at 0.40005 0 90)
			(size 0 0)
			(layers "F.Cu" "F.Mask" "F.Paste")
			(net "PWRGD_P3V3")
		)
	)
	(footprint ""
		(layer "F.Cu")
		(at 198.8312 -128.793748 -90)
		(property "Reference" "R4612"
			(at 0 0 270)
			(layer "F.SilkS")
			(hide yes)
			(effects
				(font
					(size 1.27 1.27)
				)
			)
		)
		(property "Value" ""
			(at 0 0 270)
			(layer "F.Fab")
			(effects
				(font
					(size 1.27 1.27)
				)
			)
		)
		(duplicate_pad_numbers_are_jumpers no)
		(fp_line
			(start -0.7874 0.4064)
			(end -0.7874 -0.4064)
			(stroke
				(width 0.1524)
				(type default)
			)
			(layer "F.SilkS")
		)
		(fp_line
			(start 0.7874 0.4064)
			(end -0.7874 0.4064)
			(stroke
				(width 0.1524)
				(type default)
			)
			(layer "F.SilkS")
		)
		(fp_line
			(start -0.7874 -0.4064)
			(end 0.7874 -0.4064)
			(stroke
				(width 0.1524)
				(type default)
			)
			(layer "F.SilkS")
		)
		(fp_line
			(start 0.7874 -0.4064)
			(end 0.7874 0.4064)
			(stroke
				(width 0.1524)
				(type default)
			)
			(layer "F.SilkS")
		)
		(fp_line
			(start -0.67945 0.3048)
			(end -0.67945 -0.305054)
			(stroke
				(width 0.1)
				(type default)
			)
			(layer "F.Fab")
		)
		(fp_line
			(start -0.12065 0.3048)
			(end -0.67945 0.3048)
			(stroke
				(width 0.1)
				(type default)
			)
			(layer "F.Fab")
		)
		(fp_line
			(start 0.120396 0.3048)
			(end 0.120396 0.2794)
			(stroke
				(width 0.1)
				(type default)
			)
			(layer "F.Fab")
		)
		(fp_line
			(start 0.67945 0.3048)
			(end 0.120396 0.3048)
			(stroke
				(width 0.1)
				(type default)
			)
			(layer "F.Fab")
		)
		(fp_line
			(start -0.12065 0.2794)
			(end -0.12065 0.3048)
			(stroke
				(width 0.1)
				(type default)
			)
			(layer "F.Fab")
		)
		(fp_line
			(start 0.120396 0.2794)
			(end -0.12065 0.2794)
			(stroke
				(width 0.1)
				(type default)
			)
			(layer "F.Fab")
		)
		(fp_line
			(start -0.12065 -0.2794)
			(end 0.12065 -0.2794)
			(stroke
				(width 0.1)
				(type default)
			)
			(layer "F.Fab")
		)
		(fp_line
			(start 0.12065 -0.2794)
			(end 0.12065 -0.3048)
			(stroke
				(width 0.1)
				(type default)
			)
			(layer "F.Fab")
		)
		(fp_line
			(start 0.12065 -0.3048)
			(end 0.67945 -0.3048)
			(stroke
				(width 0.1)
				(type default)
			)
			(layer "F.Fab")
		)
		(fp_line
			(start 0.67945 -0.3048)
			(end 0.67945 0.3048)
			(stroke
				(width 0.1)
				(type default)
			)
			(layer "F.Fab")
		)
		(fp_line
			(start -0.67945 -0.305054)
			(end -0.12065 -0.305054)
			(stroke
				(width 0.1)
				(type default)
			)
			(layer "F.Fab")
		)
		(fp_line
			(start -0.12065 -0.305054)
			(end -0.12065 -0.2794)
			(stroke
				(width 0.1)
				(type default)
			)
			(layer "F.Fab")
		)
		(pad "1" smd circle
			(at -0.40005 0 270)
			(size 0 0)
			(layers "F.Cu" "F.Mask" "F.Paste")
			(net "FM_PCH_SPKR")
		)
		(pad "2" smd circle
			(at 0.40005 0 270)
			(size 0 0)
			(layers "F.Cu" "F.Mask" "F.Paste")
			(net "FM_PCH_SPKR_R")
		)
	)
	(footprint ""
		(layer "F.Cu")
		(at 192.688972 -22.694392)
		(property "Reference" "PR4012"
			(at 0 0 0)
			(layer "F.SilkS")
			(hide yes)
			(effects
				(font
					(size 1.27 1.27)
				)
			)
		)
		(property "Value" ""
			(at 0 0 0)
			(layer "F.Fab")
			(effects
				(font
					(size 1.27 1.27)
				)
			)
		)
		(duplicate_pad_numbers_are_jumpers no)
		(fp_line
			(start -0.7874 -0.4064)
			(end 0.7874 -0.4064)
			(stroke
				(width 0.1524)
				(type default)
			)
			(layer "F.SilkS")
		)
		(fp_line
			(start -0.7874 0.4064)
			(end -0.7874 -0.4064)
			(stroke
				(width 0.1524)
				(type default)
			)
			(layer "F.SilkS")
		)
		(fp_line
			(start 0.7874 -0.4064)
			(end 0.7874 0.4064)
			(stroke
				(width 0.1524)
				(type default)
			)
			(layer "F.SilkS")
		)
		(fp_line
			(start 0.7874 0.4064)
			(end -0.7874 0.4064)
			(stroke
				(width 0.1524)
				(type default)
			)
			(layer "F.SilkS")
		)
		(fp_line
			(start -0.67945 -0.305054)
			(end -0.12065 -0.305054)
			(stroke
				(width 0.1)
				(type default)
			)
			(layer "F.Fab")
		)
		(fp_line
			(start -0.67945 0.3048)
			(end -0.67945 -0.305054)
			(stroke
				(width 0.1)
				(type default)
			)
			(layer "F.Fab")
		)
		(fp_line
			(start -0.12065 -0.305054)
			(end -0.12065 -0.2794)
			(stroke
				(width 0.1)
				(type default)
			)
			(layer "F.Fab")
		)
		(fp_line
			(start -0.12065 -0.2794)
			(end 0.12065 -0.2794)
			(stroke
				(width 0.1)
				(type default)
			)
			(layer "F.Fab")
		)
		(fp_line
			(start -0.12065 0.2794)
			(end -0.12065 0.3048)
			(stroke
				(width 0.1)
				(type default)
			)
			(layer "F.Fab")
		)
		(fp_line
			(start -0.12065 0.3048)
			(end -0.67945 0.3048)
			(stroke
				(width 0.1)
				(type default)
			)
			(layer "F.Fab")
		)
		(fp_line
			(start 0.120396 0.2794)
			(end -0.12065 0.2794)
			(stroke
				(width 0.1)
				(type default)
			)
			(layer "F.Fab")
		)
		(fp_line
			(start 0.120396 0.3048)
			(end 0.120396 0.2794)
			(stroke
				(width 0.1)
				(type default)
			)
			(layer "F.Fab")
		)
		(fp_line
			(start 0.12065 -0.3048)
			(end 0.67945 -0.3048)
			(stroke
				(width 0.1)
				(type default)
			)
			(layer "F.Fab")
		)
		(fp_line
			(start 0.12065 -0.2794)
			(end 0.12065 -0.3048)
			(stroke
				(width 0.1)
				(type default)
			)
			(layer "F.Fab")
		)
		(fp_line
			(start 0.67945 -0.3048)
			(end 0.67945 0.3048)
			(stroke
				(width 0.1)
				(type default)
			)
			(layer "F.Fab")
		)
		(fp_line
			(start 0.67945 0.3048)
			(end 0.120396 0.3048)
			(stroke
				(width 0.1)
				(type default)
			)
			(layer "F.Fab")
		)
		(pad "1" smd circle
			(at -0.40005 0)
			(size 0 0)
			(layers "F.Cu" "F.Mask" "F.Paste")
			(net "P12V_SCM_PWRGD")
		)
		(pad "2" smd circle
			(at 0.40005 0)
			(size 0 0)
			(layers "F.Cu" "F.Mask" "F.Paste")
			(net "HP_LVC3_SCM_HSC_PWRGD")
		)
	)
	(footprint ""
		(layer "F.Cu")
		(at 289.116008 -412.34614)
		(property "Reference" "Q145"
			(at -1.438148 1.759204 0)
			(unlocked yes)
			(layer "F.SilkS")
			(effects
				(font
					(size 0.7874 0.5842)
					(thickness 0.1524)
				)
				(justify left)
			)
		)
		(property "Value" ""
			(at 0 0 0)
			(layer "F.Fab")
			(effects
				(font
					(size 1.27 1.27)
				)
			)
		)
		(duplicate_pad_numbers_are_jumpers no)
		(fp_line
			(start -1.332738 -1.100074)
			(end -0.4826 -1.100074)
			(stroke
				(width 0.1524)
				(type default)
			)
			(layer "F.SilkS")
		)
		(fp_line
			(start -1.332738 1.100074)
			(end -1.332738 -1.100074)
			(stroke
				(width 0.1524)
				(type default)
			)
			(layer "F.SilkS")
		)
		(fp_line
			(start -0.4826 -1.100074)
			(end 0 -0.541274)
			(stroke
				(width 0.1524)
				(type default)
			)
			(layer "F.SilkS")
		)
		(fp_line
			(start 0 -0.541274)
			(end 0.4826 -1.100074)
			(stroke
				(width 0.1524)
				(type default)
			)
			(layer "F.SilkS")
		)
		(fp_line
			(start 0.4826 -1.100074)
			(end 1.332738 -1.100074)
			(stroke
				(width 0.1524)
				(type default)
			)
			(layer "F.SilkS")
		)
		(fp_line
			(start 1.332738 -1.100074)
			(end 1.332738 1.100074)
			(stroke
				(width 0.1524)
				(type default)
			)
			(layer "F.SilkS")
		)
		(fp_line
			(start 1.332738 1.100074)
			(end -1.332738 1.100074)
			(stroke
				(width 0.1524)
				(type default)
			)
			(layer "F.SilkS")
		)
		(fp_poly
			(pts
				(xy -1.756156 -1.726946) (xy -1.507998 -0.982218) (xy -2.252726 -1.230376)
			)
			(stroke
				(width 0)
				(type default)
			)
			(fill yes)
			(layer "F.SilkS")
		)
		(fp_line
			(start -0.674878 -1.100074)
			(end 0.674878 -1.100074)
			(stroke
				(width 0.1)
				(type default)
			)
			(layer "F.Fab")
		)
		(fp_line
			(start -0.674878 1.100074)
			(end -0.674878 -1.100074)
			(stroke
				(width 0.1)
				(type default)
			)
			(layer "F.Fab")
		)
		(fp_line
			(start 0.674878 -1.100074)
			(end 0.674878 1.100074)
			(stroke
				(width 0.1)
				(type default)
			)
			(layer "F.Fab")
		)
		(fp_line
			(start 0.674878 1.100074)
			(end -0.674878 1.100074)
			(stroke
				(width 0.1)
				(type default)
			)
			(layer "F.Fab")
		)
		(fp_poly
			(pts
				(xy -2.2352 -0.298958) (xy -2.2352 -1.001014) (xy -1.533144 -0.649986)
			)
			(stroke
				(width 0)
				(type default)
			)
			(fill yes)
			(layer "F.Fab")
		)
		(pad "1" smd rect
			(at -0.94996 -0.649986 90)
			(size 0.4318 0.508)
			(layers "F.Cu" "F.Mask" "F.Paste")
			(net "GND")
		)
		(pad "2" smd rect
			(at -0.94996 0 90)
			(size 0.4318 0.508)
			(layers "F.Cu" "F.Mask" "F.Paste")
			(net "HPDB_HSC_PWRGD")
		)
		(pad "3" smd rect
			(at -0.94996 0.649986 90)
			(size 0.4318 0.508)
			(layers "F.Cu" "F.Mask" "F.Paste")
			(net "HPDB_HSC_PWRGD_ISO")
		)
		(pad "4" smd rect
			(at 0.94996 0.649986 90)
			(size 0.4318 0.508)
			(layers "F.Cu" "F.Mask" "F.Paste")
			(net "GND")
		)
		(pad "5" smd rect
			(at 0.94996 0 90)
			(size 0.4318 0.508)
			(layers "F.Cu" "F.Mask" "F.Paste")
			(net "HPDB_HSC_PWRGD_N")
		)
		(pad "6" smd rect
			(at 0.94996 -0.649986 90)
			(size 0.4318 0.508)
			(layers "F.Cu" "F.Mask" "F.Paste")
			(net "HPDB_HSC_PWRGD_N")
		)
	)
	(footprint ""
		(layer "F.Cu")
		(at 420.66972 -132.21716 180)
		(property "Reference" "PC2362"
			(at 0 0 180)
			(layer "F.SilkS")
			(hide yes)
			(effects
				(font
					(size 1.27 1.27)
				)
			)
		)
		(property "Value" ""
			(at 0 0 180)
			(layer "F.Fab")
			(effects
				(font
					(size 1.27 1.27)
				)
			)
		)
		(duplicate_pad_numbers_are_jumpers no)
		(fp_line
			(start 0.7874 0.4064)
			(end -0.7874 0.4064)
			(stroke
				(width 0.1524)
				(type default)
			)
			(layer "F.SilkS")
		)
		(fp_line
			(start 0.7874 -0.4064)
			(end 0.7874 0.4064)
			(stroke
				(width 0.1524)
				(type default)
			)
			(layer "F.SilkS")
		)
		(fp_line
			(start -0.7874 0.4064)
			(end -0.7874 -0.4064)
			(stroke
				(width 0.1524)
				(type default)
			)
			(layer "F.SilkS")
		)
		(fp_line
			(start -0.7874 -0.4064)
			(end 0.7874 -0.4064)
			(stroke
				(width 0.1524)
				(type default)
			)
			(layer "F.SilkS")
		)
		(fp_line
			(start 0.67945 0.3048)
			(end 0.120396 0.3048)
			(stroke
				(width 0.1)
				(type default)
			)
			(layer "F.Fab")
		)
		(fp_line
			(start 0.67945 -0.3048)
			(end 0.67945 0.3048)
			(stroke
				(width 0.1)
				(type default)
			)
			(layer "F.Fab")
		)
		(fp_line
			(start 0.12065 -0.2794)
			(end 0.12065 -0.3048)
			(stroke
				(width 0.1)
				(type default)
			)
			(layer "F.Fab")
		)
		(fp_line
			(start 0.12065 -0.3048)
			(end 0.67945 -0.3048)
			(stroke
				(width 0.1)
				(type default)
			)
			(layer "F.Fab")
		)
		(fp_line
			(start 0.120396 0.3048)
			(end 0.120396 0.2794)
			(stroke
				(width 0.1)
				(type default)
			)
			(layer "F.Fab")
		)
		(fp_line
			(start 0.120396 0.2794)
			(end -0.12065 0.2794)
			(stroke
				(width 0.1)
				(type default)
			)
			(layer "F.Fab")
		)
		(fp_line
			(start -0.12065 0.3048)
			(end -0.67945 0.3048)
			(stroke
				(width 0.1)
				(type default)
			)
			(layer "F.Fab")
		)
		(fp_line
			(start -0.12065 0.2794)
			(end -0.12065 0.3048)
			(stroke
				(width 0.1)
				(type default)
			)
			(layer "F.Fab")
		)
		(fp_line
			(start -0.12065 -0.2794)
			(end 0.12065 -0.2794)
			(stroke
				(width 0.1)
				(type default)
			)
			(layer "F.Fab")
		)
		(fp_line
			(start -0.12065 -0.305054)
			(end -0.12065 -0.2794)
			(stroke
				(width 0.1)
				(type default)
			)
			(layer "F.Fab")
		)
		(fp_line
			(start -0.67945 0.3048)
			(end -0.67945 -0.305054)
			(stroke
				(width 0.1)
				(type default)
			)
			(layer "F.Fab")
		)
		(fp_line
			(start -0.67945 -0.305054)
			(end -0.12065 -0.305054)
			(stroke
				(width 0.1)
				(type default)
			)
			(layer "F.Fab")
		)
		(pad "1" smd circle
			(at -0.40005 0 180)
			(size 0 0)
			(layers "F.Cu" "F.Mask" "F.Paste")
			(net "PVCCINFAON_CPU0_VCC")
		)
		(pad "2" smd circle
			(at 0.40005 0 180)
			(size 0 0)
			(layers "F.Cu" "F.Mask" "F.Paste")
			(net "GND")
		)
	)
	(footprint ""
		(layer "F.Cu")
		(at 420.453312 -366.658144)
		(property "Reference" "PC720_P0_1"
			(at 0 0 0)
			(layer "F.SilkS")
			(hide yes)
			(effects
				(font
					(size 1.27 1.27)
				)
			)
		)
		(property "Value" ""
			(at 0 0 0)
			(layer "F.Fab")
			(effects
				(font
					(size 1.27 1.27)
				)
			)
		)
		(duplicate_pad_numbers_are_jumpers no)
		(fp_line
			(start -1.524 -0.762)
			(end 1.524 -0.762)
			(stroke
				(width 0.1524)
				(type default)
			)
			(layer "F.SilkS")
		)
		(fp_line
			(start -1.524 0.762)
			(end -1.524 -0.762)
			(stroke
				(width 0.1524)
				(type default)
			)
			(layer "F.SilkS")
		)
		(fp_line
			(start 1.524 -0.762)
			(end 1.524 0.762)
			(stroke
				(width 0.1524)
				(type default)
			)
			(layer "F.SilkS")
		)
		(fp_line
			(start 1.524 0.762)
			(end -1.524 0.762)
			(stroke
				(width 0.1524)
				(type default)
			)
			(layer "F.SilkS")
		)
		(fp_line
			(start -1.1049 -0.724916)
			(end -1.1049 0.724916)
			(stroke
				(width 0.1)
				(type default)
			)
			(layer "F.Fab")
		)
		(fp_line
			(start -1.1049 0.724916)
			(end 1.1049 0.724916)
			(stroke
				(width 0.1)
				(type default)
			)
			(layer "F.Fab")
		)
		(fp_line
			(start 1.1049 -0.724916)
			(end -1.1049 -0.724916)
			(stroke
				(width 0.1)
				(type default)
			)
			(layer "F.Fab")
		)
		(fp_line
			(start 1.1049 0.724916)
			(end 1.1049 -0.724916)
			(stroke
				(width 0.1)
				(type default)
			)
			(layer "F.Fab")
		)
		(pad "1" smd rect
			(at -0.889 0 180)
			(size 1.016 1.27)
			(layers "F.Cu" "F.Mask" "F.Paste")
			(net "SW_P12V_PVCCFA_EHV_FIVRA_CPU0_R")
		)
		(pad "2" smd rect
			(at 0.889 0 180)
			(size 1.016 1.27)
			(layers "F.Cu" "F.Mask" "F.Paste")
			(net "GND")
		)
	)
	(footprint ""
		(layer "F.Cu")
		(at 148.13788 -56.225948)
		(property "Reference" "R1702"
			(at 0 0 0)
			(layer "F.SilkS")
			(hide yes)
			(effects
				(font
					(size 1.27 1.27)
				)
			)
		)
		(property "Value" ""
			(at 0 0 0)
			(layer "F.Fab")
			(effects
				(font
					(size 1.27 1.27)
				)
			)
		)
		(duplicate_pad_numbers_are_jumpers no)
		(fp_line
			(start -0.7874 -0.4064)
			(end 0.7874 -0.4064)
			(stroke
				(width 0.1524)
				(type default)
			)
			(layer "F.SilkS")
		)
		(fp_line
			(start -0.7874 0.4064)
			(end -0.7874 -0.4064)
			(stroke
				(width 0.1524)
				(type default)
			)
			(layer "F.SilkS")
		)
		(fp_line
			(start 0.7874 -0.4064)
			(end 0.7874 0.4064)
			(stroke
				(width 0.1524)
				(type default)
			)
			(layer "F.SilkS")
		)
		(fp_line
			(start 0.7874 0.4064)
			(end -0.7874 0.4064)
			(stroke
				(width 0.1524)
				(type default)
			)
			(layer "F.SilkS")
		)
		(fp_line
			(start -0.67945 -0.305054)
			(end -0.12065 -0.305054)
			(stroke
				(width 0.1)
				(type default)
			)
			(layer "F.Fab")
		)
		(fp_line
			(start -0.67945 0.3048)
			(end -0.67945 -0.305054)
			(stroke
				(width 0.1)
				(type default)
			)
			(layer "F.Fab")
		)
		(fp_line
			(start -0.12065 -0.305054)
			(end -0.12065 -0.2794)
			(stroke
				(width 0.1)
				(type default)
			)
			(layer "F.Fab")
		)
		(fp_line
			(start -0.12065 -0.2794)
			(end 0.12065 -0.2794)
			(stroke
				(width 0.1)
				(type default)
			)
			(layer "F.Fab")
		)
		(fp_line
			(start -0.12065 0.2794)
			(end -0.12065 0.3048)
			(stroke
				(width 0.1)
				(type default)
			)
			(layer "F.Fab")
		)
		(fp_line
			(start -0.12065 0.3048)
			(end -0.67945 0.3048)
			(stroke
				(width 0.1)
				(type default)
			)
			(layer "F.Fab")
		)
		(fp_line
			(start 0.120396 0.2794)
			(end -0.12065 0.2794)
			(stroke
				(width 0.1)
				(type default)
			)
			(layer "F.Fab")
		)
		(fp_line
			(start 0.120396 0.3048)
			(end 0.120396 0.2794)
			(stroke
				(width 0.1)
				(type default)
			)
			(layer "F.Fab")
		)
		(fp_line
			(start 0.12065 -0.3048)
			(end 0.67945 -0.3048)
			(stroke
				(width 0.1)
				(type default)
			)
			(layer "F.Fab")
		)
		(fp_line
			(start 0.12065 -0.2794)
			(end 0.12065 -0.3048)
			(stroke
				(width 0.1)
				(type default)
			)
			(layer "F.Fab")
		)
		(fp_line
			(start 0.67945 -0.3048)
			(end 0.67945 0.3048)
			(stroke
				(width 0.1)
				(type default)
			)
			(layer "F.Fab")
		)
		(fp_line
			(start 0.67945 0.3048)
			(end 0.120396 0.3048)
			(stroke
				(width 0.1)
				(type default)
			)
			(layer "F.Fab")
		)
		(pad "1" smd circle
			(at -0.40005 0)
			(size 0 0)
			(layers "F.Cu" "F.Mask" "F.Paste")
			(net "P1V8_PCH_AUX")
		)
		(pad "2" smd circle
			(at 0.40005 0)
			(size 0 0)
			(layers "F.Cu" "F.Mask" "F.Paste")
			(net "SMB_M2_P0_1V8AUX_SDA_R")
		)
	)
	(footprint ""
		(layer "F.Cu")
		(at 385.716272 -65.688464)
		(property "Reference" "R762"
			(at 0 0 0)
			(layer "F.SilkS")
			(hide yes)
			(effects
				(font
					(size 1.27 1.27)
				)
			)
		)
		(property "Value" ""
			(at 0 0 0)
			(layer "F.Fab")
			(effects
				(font
					(size 1.27 1.27)
				)
			)
		)
		(duplicate_pad_numbers_are_jumpers no)
		(fp_line
			(start -0.7874 -0.4064)
			(end 0.7874 -0.4064)
			(stroke
				(width 0.1524)
				(type default)
			)
			(layer "F.SilkS")
		)
		(fp_line
			(start -0.7874 0.4064)
			(end -0.7874 -0.4064)
			(stroke
				(width 0.1524)
				(type default)
			)
			(layer "F.SilkS")
		)
		(fp_line
			(start 0.7874 -0.4064)
			(end 0.7874 0.4064)
			(stroke
				(width 0.1524)
				(type default)
			)
			(layer "F.SilkS")
		)
		(fp_line
			(start 0.7874 0.4064)
			(end -0.7874 0.4064)
			(stroke
				(width 0.1524)
				(type default)
			)
			(layer "F.SilkS")
		)
		(fp_line
			(start -0.67945 -0.305054)
			(end -0.12065 -0.305054)
			(stroke
				(width 0.1)
				(type default)
			)
			(layer "F.Fab")
		)
		(fp_line
			(start -0.67945 0.3048)
			(end -0.67945 -0.305054)
			(stroke
				(width 0.1)
				(type default)
			)
			(layer "F.Fab")
		)
		(fp_line
			(start -0.12065 -0.305054)
			(end -0.12065 -0.2794)
			(stroke
				(width 0.1)
				(type default)
			)
			(layer "F.Fab")
		)
		(fp_line
			(start -0.12065 -0.2794)
			(end 0.12065 -0.2794)
			(stroke
				(width 0.1)
				(type default)
			)
			(layer "F.Fab")
		)
		(fp_line
			(start -0.12065 0.2794)
			(end -0.12065 0.3048)
			(stroke
				(width 0.1)
				(type default)
			)
			(layer "F.Fab")
		)
		(fp_line
			(start -0.12065 0.3048)
			(end -0.67945 0.3048)
			(stroke
				(width 0.1)
				(type default)
			)
			(layer "F.Fab")
		)
		(fp_line
			(start 0.120396 0.2794)
			(end -0.12065 0.2794)
			(stroke
				(width 0.1)
				(type default)
			)
			(layer "F.Fab")
		)
		(fp_line
			(start 0.120396 0.3048)
			(end 0.120396 0.2794)
			(stroke
				(width 0.1)
				(type default)
			)
			(layer "F.Fab")
		)
		(fp_line
			(start 0.12065 -0.3048)
			(end 0.67945 -0.3048)
			(stroke
				(width 0.1)
				(type default)
			)
			(layer "F.Fab")
		)
		(fp_line
			(start 0.12065 -0.2794)
			(end 0.12065 -0.3048)
			(stroke
				(width 0.1)
				(type default)
			)
			(layer "F.Fab")
		)
		(fp_line
			(start 0.67945 -0.3048)
			(end 0.67945 0.3048)
			(stroke
				(width 0.1)
				(type default)
			)
			(layer "F.Fab")
		)
		(fp_line
			(start 0.67945 0.3048)
			(end 0.120396 0.3048)
			(stroke
				(width 0.1)
				(type default)
			)
			(layer "F.Fab")
		)
		(pad "1" smd circle
			(at -0.40005 0)
			(size 0 0)
			(layers "F.Cu" "F.Mask" "F.Paste")
			(net "JTAG_DBP_CPU_GTL_TCK")
		)
		(pad "2" smd circle
			(at 0.40005 0)
			(size 0 0)
			(layers "F.Cu" "F.Mask" "F.Paste")
			(net "JTAG_DBP_CPU_GTL_TCK_R")
		)
	)
	(footprint ""
		(layer "F.Cu")
		(at 81.915 -353.52482)
		(property "Reference" "H47"
			(at -3.58394 -5.029708 0)
			(unlocked yes)
			(layer "F.SilkS")
			(effects
				(font
					(size 0.7874 0.5842)
					(thickness 0.1524)
				)
				(justify left)
			)
		)
		(property "Value" ""
			(at 0 0 0)
			(layer "F.Fab")
			(effects
				(font
					(size 1.27 1.27)
				)
			)
		)
		(duplicate_pad_numbers_are_jumpers no)
		(pad "1" thru_hole circle
			(at 0 0)
			(size 8.001 8.001)
			(drill 3.2004)
			(layers "*.Cu" "*.Mask")
			(remove_unused_layers no)
			(net "GND")
			(clearance -2.1463)
			(padstack
				(mode front_inner_back)
				(layer "Inner"
					(shape circle)
					(size 5.0038 5.0038)
					(clearance -0.6477)
				)
				(layer "B.Cu"
					(shape circle)
					(size 8.001 8.001)
					(clearance -2.1463)
				)
			)
		)
	)
	(footprint ""
		(layer "F.Cu")
		(at 107.287314 -260.36524 -90)
		(property "Reference" "C433"
			(at 0 0 270)
			(layer "F.SilkS")
			(hide yes)
			(effects
				(font
					(size 1.27 1.27)
				)
			)
		)
		(property "Value" ""
			(at 0 0 270)
			(layer "F.Fab")
			(effects
				(font
					(size 1.27 1.27)
				)
			)
		)
		(duplicate_pad_numbers_are_jumpers no)
		(fp_line
			(start -0.7874 0.4064)
			(end -0.7874 -0.4064)
			(stroke
				(width 0.1524)
				(type default)
			)
			(layer "F.SilkS")
		)
		(fp_line
			(start 0.7874 0.4064)
			(end -0.7874 0.4064)
			(stroke
				(width 0.1524)
				(type default)
			)
			(layer "F.SilkS")
		)
		(fp_line
			(start -0.7874 -0.4064)
			(end 0.7874 -0.4064)
			(stroke
				(width 0.1524)
				(type default)
			)
			(layer "F.SilkS")
		)
		(fp_line
			(start 0.7874 -0.4064)
			(end 0.7874 0.4064)
			(stroke
				(width 0.1524)
				(type default)
			)
			(layer "F.SilkS")
		)
		(fp_line
			(start -0.67945 0.3048)
			(end -0.67945 -0.305054)
			(stroke
				(width 0.1)
				(type default)
			)
			(layer "F.Fab")
		)
		(fp_line
			(start -0.12065 0.3048)
			(end -0.67945 0.3048)
			(stroke
				(width 0.1)
				(type default)
			)
			(layer "F.Fab")
		)
		(fp_line
			(start 0.120396 0.3048)
			(end 0.120396 0.2794)
			(stroke
				(width 0.1)
				(type default)
			)
			(layer "F.Fab")
		)
		(fp_line
			(start 0.67945 0.3048)
			(end 0.120396 0.3048)
			(stroke
				(width 0.1)
				(type default)
			)
			(layer "F.Fab")
		)
		(fp_line
			(start -0.12065 0.2794)
			(end -0.12065 0.3048)
			(stroke
				(width 0.1)
				(type default)
			)
			(layer "F.Fab")
		)
		(fp_line
			(start 0.120396 0.2794)
			(end -0.12065 0.2794)
			(stroke
				(width 0.1)
				(type default)
			)
			(layer "F.Fab")
		)
		(fp_line
			(start -0.12065 -0.2794)
			(end 0.12065 -0.2794)
			(stroke
				(width 0.1)
				(type default)
			)
			(layer "F.Fab")
		)
		(fp_line
			(start 0.12065 -0.2794)
			(end 0.12065 -0.3048)
			(stroke
				(width 0.1)
				(type default)
			)
			(layer "F.Fab")
		)
		(fp_line
			(start 0.12065 -0.3048)
			(end 0.67945 -0.3048)
			(stroke
				(width 0.1)
				(type default)
			)
			(layer "F.Fab")
		)
		(fp_line
			(start 0.67945 -0.3048)
			(end 0.67945 0.3048)
			(stroke
				(width 0.1)
				(type default)
			)
			(layer "F.Fab")
		)
		(fp_line
			(start -0.67945 -0.305054)
			(end -0.12065 -0.305054)
			(stroke
				(width 0.1)
				(type default)
			)
			(layer "F.Fab")
		)
		(fp_line
			(start -0.12065 -0.305054)
			(end -0.12065 -0.2794)
			(stroke
				(width 0.1)
				(type default)
			)
			(layer "F.Fab")
		)
		(pad "1" smd circle
			(at -0.40005 0 270)
			(size 0 0)
			(layers "F.Cu" "F.Mask" "F.Paste")
			(net "PVCCFA_EHV_FIVRA_CPU1")
		)
		(pad "2" smd circle
			(at 0.40005 0 270)
			(size 0 0)
			(layers "F.Cu" "F.Mask" "F.Paste")
			(net "GND")
		)
	)
	(footprint ""
		(layer "F.Cu")
		(at 191.295782 -28.267152)
		(property "Reference" "PC2237"
			(at 0 0 0)
			(layer "F.SilkS")
			(hide yes)
			(effects
				(font
					(size 1.27 1.27)
				)
			)
		)
		(property "Value" ""
			(at 0 0 0)
			(layer "F.Fab")
			(effects
				(font
					(size 1.27 1.27)
				)
			)
		)
		(duplicate_pad_numbers_are_jumpers no)
		(fp_line
			(start -0.7874 -0.4064)
			(end 0.7874 -0.4064)
			(stroke
				(width 0.1524)
				(type default)
			)
			(layer "F.SilkS")
		)
		(fp_line
			(start -0.7874 0.4064)
			(end -0.7874 -0.4064)
			(stroke
				(width 0.1524)
				(type default)
			)
			(layer "F.SilkS")
		)
		(fp_line
			(start 0.7874 -0.4064)
			(end 0.7874 0.4064)
			(stroke
				(width 0.1524)
				(type default)
			)
			(layer "F.SilkS")
		)
		(fp_line
			(start 0.7874 0.4064)
			(end -0.7874 0.4064)
			(stroke
				(width 0.1524)
				(type default)
			)
			(layer "F.SilkS")
		)
		(fp_line
			(start -0.67945 -0.305054)
			(end -0.12065 -0.305054)
			(stroke
				(width 0.1)
				(type default)
			)
			(layer "F.Fab")
		)
		(fp_line
			(start -0.67945 0.3048)
			(end -0.67945 -0.305054)
			(stroke
				(width 0.1)
				(type default)
			)
			(layer "F.Fab")
		)
		(fp_line
			(start -0.12065 -0.305054)
			(end -0.12065 -0.2794)
			(stroke
				(width 0.1)
				(type default)
			)
			(layer "F.Fab")
		)
		(fp_line
			(start -0.12065 -0.2794)
			(end 0.12065 -0.2794)
			(stroke
				(width 0.1)
				(type default)
			)
			(layer "F.Fab")
		)
		(fp_line
			(start -0.12065 0.2794)
			(end -0.12065 0.3048)
			(stroke
				(width 0.1)
				(type default)
			)
			(layer "F.Fab")
		)
		(fp_line
			(start -0.12065 0.3048)
			(end -0.67945 0.3048)
			(stroke
				(width 0.1)
				(type default)
			)
			(layer "F.Fab")
		)
		(fp_line
			(start 0.120396 0.2794)
			(end -0.12065 0.2794)
			(stroke
				(width 0.1)
				(type default)
			)
			(layer "F.Fab")
		)
		(fp_line
			(start 0.120396 0.3048)
			(end 0.120396 0.2794)
			(stroke
				(width 0.1)
				(type default)
			)
			(layer "F.Fab")
		)
		(fp_line
			(start 0.12065 -0.3048)
			(end 0.67945 -0.3048)
			(stroke
				(width 0.1)
				(type default)
			)
			(layer "F.Fab")
		)
		(fp_line
			(start 0.12065 -0.2794)
			(end 0.12065 -0.3048)
			(stroke
				(width 0.1)
				(type default)
			)
			(layer "F.Fab")
		)
		(fp_line
			(start 0.67945 -0.3048)
			(end 0.67945 0.3048)
			(stroke
				(width 0.1)
				(type default)
			)
			(layer "F.Fab")
		)
		(fp_line
			(start 0.67945 0.3048)
			(end 0.120396 0.3048)
			(stroke
				(width 0.1)
				(type default)
			)
			(layer "F.Fab")
		)
		(pad "1" smd circle
			(at -0.40005 0)
			(size 0 0)
			(layers "F.Cu" "F.Mask" "F.Paste")
			(net "P12V_SCM_GATE")
		)
		(pad "2" smd circle
			(at 0.40005 0)
			(size 0 0)
			(layers "F.Cu" "F.Mask" "F.Paste")
			(net "GND")
		)
	)
	(footprint ""
		(layer "F.Cu")
		(at 57.75833 -17.623536 90)
		(property "Reference" "C836"
			(at 0 0 90)
			(layer "F.SilkS")
			(hide yes)
			(effects
				(font
					(size 1.27 1.27)
				)
			)
		)
		(property "Value" ""
			(at 0 0 90)
			(layer "F.Fab")
			(effects
				(font
					(size 1.27 1.27)
				)
			)
		)
		(duplicate_pad_numbers_are_jumpers no)
		(fp_line
			(start 0.299974 -0.150114)
			(end 0.299974 0.150114)
			(stroke
				(width 0.1)
				(type default)
			)
			(layer "F.Fab")
		)
		(fp_line
			(start -0.299974 -0.150114)
			(end 0.299974 -0.150114)
			(stroke
				(width 0.1)
				(type default)
			)
			(layer "F.Fab")
		)
		(fp_line
			(start 0.299974 0.150114)
			(end -0.299974 0.150114)
			(stroke
				(width 0.1)
				(type default)
			)
			(layer "F.Fab")
		)
		(fp_line
			(start -0.299974 0.150114)
			(end -0.299974 -0.150114)
			(stroke
				(width 0.1)
				(type default)
			)
			(layer "F.Fab")
		)
		(pad "1" smd rect
			(at -0.2667 0 90)
			(size 0.3048 0.381)
			(layers "F.Cu" "F.Mask" "F.Paste")
			(net "P5E_CPU1_PE1_TX_C_DN<0>")
		)
		(pad "2" smd rect
			(at 0.2667 0 90)
			(size 0.3048 0.381)
			(layers "F.Cu" "F.Mask" "F.Paste")
			(net "P5E_CPU1_PE1_TX_DN<0>")
		)
	)
	(footprint ""
		(layer "F.Cu")
		(at 334.7212 -66.462148 180)
		(property "Reference" "C103"
			(at 0 0 180)
			(layer "F.SilkS")
			(hide yes)
			(effects
				(font
					(size 1.27 1.27)
				)
			)
		)
		(property "Value" ""
			(at 0 0 180)
			(layer "F.Fab")
			(effects
				(font
					(size 1.27 1.27)
				)
			)
		)
		(duplicate_pad_numbers_are_jumpers no)
		(fp_line
			(start 0.7874 0.4064)
			(end -0.7874 0.4064)
			(stroke
				(width 0.1524)
				(type default)
			)
			(layer "F.SilkS")
		)
		(fp_line
			(start 0.7874 -0.4064)
			(end 0.7874 0.4064)
			(stroke
				(width 0.1524)
				(type default)
			)
			(layer "F.SilkS")
		)
		(fp_line
			(start -0.7874 0.4064)
			(end -0.7874 -0.4064)
			(stroke
				(width 0.1524)
				(type default)
			)
			(layer "F.SilkS")
		)
		(fp_line
			(start -0.7874 -0.4064)
			(end 0.7874 -0.4064)
			(stroke
				(width 0.1524)
				(type default)
			)
			(layer "F.SilkS")
		)
		(fp_line
			(start 0.67945 0.3048)
			(end 0.120396 0.3048)
			(stroke
				(width 0.1)
				(type default)
			)
			(layer "F.Fab")
		)
		(fp_line
			(start 0.67945 -0.3048)
			(end 0.67945 0.3048)
			(stroke
				(width 0.1)
				(type default)
			)
			(layer "F.Fab")
		)
		(fp_line
			(start 0.12065 -0.2794)
			(end 0.12065 -0.3048)
			(stroke
				(width 0.1)
				(type default)
			)
			(layer "F.Fab")
		)
		(fp_line
			(start 0.12065 -0.3048)
			(end 0.67945 -0.3048)
			(stroke
				(width 0.1)
				(type default)
			)
			(layer "F.Fab")
		)
		(fp_line
			(start 0.120396 0.3048)
			(end 0.120396 0.2794)
			(stroke
				(width 0.1)
				(type default)
			)
			(layer "F.Fab")
		)
		(fp_line
			(start 0.120396 0.2794)
			(end -0.12065 0.2794)
			(stroke
				(width 0.1)
				(type default)
			)
			(layer "F.Fab")
		)
		(fp_line
			(start -0.12065 0.3048)
			(end -0.67945 0.3048)
			(stroke
				(width 0.1)
				(type default)
			)
			(layer "F.Fab")
		)
		(fp_line
			(start -0.12065 0.2794)
			(end -0.12065 0.3048)
			(stroke
				(width 0.1)
				(type default)
			)
			(layer "F.Fab")
		)
		(fp_line
			(start -0.12065 -0.2794)
			(end 0.12065 -0.2794)
			(stroke
				(width 0.1)
				(type default)
			)
			(layer "F.Fab")
		)
		(fp_line
			(start -0.12065 -0.305054)
			(end -0.12065 -0.2794)
			(stroke
				(width 0.1)
				(type default)
			)
			(layer "F.Fab")
		)
		(fp_line
			(start -0.67945 0.3048)
			(end -0.67945 -0.305054)
			(stroke
				(width 0.1)
				(type default)
			)
			(layer "F.Fab")
		)
		(fp_line
			(start -0.67945 -0.305054)
			(end -0.12065 -0.305054)
			(stroke
				(width 0.1)
				(type default)
			)
			(layer "F.Fab")
		)
		(pad "1" smd circle
			(at -0.40005 0 180)
			(size 0 0)
			(layers "F.Cu" "F.Mask" "F.Paste")
			(net "XTAL_PCH_25M_IN_R")
		)
		(pad "2" smd circle
			(at 0.40005 0 180)
			(size 0 0)
			(layers "F.Cu" "F.Mask" "F.Paste")
			(net "GND")
		)
	)
	(footprint ""
		(layer "F.Cu")
		(at 75.546458 -21.839682 180)
		(property "Reference" "PR3823"
			(at 0 0 180)
			(layer "F.SilkS")
			(hide yes)
			(effects
				(font
					(size 1.27 1.27)
				)
			)
		)
		(property "Value" ""
			(at 0 0 180)
			(layer "F.Fab")
			(effects
				(font
					(size 1.27 1.27)
				)
			)
		)
		(duplicate_pad_numbers_are_jumpers no)
		(fp_line
			(start 0.7874 0.4064)
			(end -0.7874 0.4064)
			(stroke
				(width 0.1524)
				(type default)
			)
			(layer "F.SilkS")
		)
		(fp_line
			(start 0.7874 -0.4064)
			(end 0.7874 0.4064)
			(stroke
				(width 0.1524)
				(type default)
			)
			(layer "F.SilkS")
		)
		(fp_line
			(start -0.7874 0.4064)
			(end -0.7874 -0.4064)
			(stroke
				(width 0.1524)
				(type default)
			)
			(layer "F.SilkS")
		)
		(fp_line
			(start -0.7874 -0.4064)
			(end 0.7874 -0.4064)
			(stroke
				(width 0.1524)
				(type default)
			)
			(layer "F.SilkS")
		)
		(fp_line
			(start 0.67945 0.3048)
			(end 0.120396 0.3048)
			(stroke
				(width 0.1)
				(type default)
			)
			(layer "F.Fab")
		)
		(fp_line
			(start 0.67945 -0.3048)
			(end 0.67945 0.3048)
			(stroke
				(width 0.1)
				(type default)
			)
			(layer "F.Fab")
		)
		(fp_line
			(start 0.12065 -0.2794)
			(end 0.12065 -0.3048)
			(stroke
				(width 0.1)
				(type default)
			)
			(layer "F.Fab")
		)
		(fp_line
			(start 0.12065 -0.3048)
			(end 0.67945 -0.3048)
			(stroke
				(width 0.1)
				(type default)
			)
			(layer "F.Fab")
		)
		(fp_line
			(start 0.120396 0.3048)
			(end 0.120396 0.2794)
			(stroke
				(width 0.1)
				(type default)
			)
			(layer "F.Fab")
		)
		(fp_line
			(start 0.120396 0.2794)
			(end -0.12065 0.2794)
			(stroke
				(width 0.1)
				(type default)
			)
			(layer "F.Fab")
		)
		(fp_line
			(start -0.12065 0.3048)
			(end -0.67945 0.3048)
			(stroke
				(width 0.1)
				(type default)
			)
			(layer "F.Fab")
		)
		(fp_line
			(start -0.12065 0.2794)
			(end -0.12065 0.3048)
			(stroke
				(width 0.1)
				(type default)
			)
			(layer "F.Fab")
		)
		(fp_line
			(start -0.12065 -0.2794)
			(end 0.12065 -0.2794)
			(stroke
				(width 0.1)
				(type default)
			)
			(layer "F.Fab")
		)
		(fp_line
			(start -0.12065 -0.305054)
			(end -0.12065 -0.2794)
			(stroke
				(width 0.1)
				(type default)
			)
			(layer "F.Fab")
		)
		(fp_line
			(start -0.67945 0.3048)
			(end -0.67945 -0.305054)
			(stroke
				(width 0.1)
				(type default)
			)
			(layer "F.Fab")
		)
		(fp_line
			(start -0.67945 -0.305054)
			(end -0.12065 -0.305054)
			(stroke
				(width 0.1)
				(type default)
			)
			(layer "F.Fab")
		)
		(pad "1" smd circle
			(at -0.40005 0 180)
			(size 0 0)
			(layers "F.Cu" "F.Mask" "F.Paste")
			(net "P12V_OCP_SENSE_2")
		)
		(pad "2" smd circle
			(at 0.40005 0 180)
			(size 0 0)
			(layers "F.Cu" "F.Mask" "F.Paste")
			(net "GND")
		)
	)
	(footprint ""
		(layer "F.Cu")
		(at 400.31289 -408.517344 -90)
		(property "Reference" "C888"
			(at 0 0 270)
			(layer "F.SilkS")
			(hide yes)
			(effects
				(font
					(size 1.27 1.27)
				)
			)
		)
		(property "Value" ""
			(at 0 0 270)
			(layer "F.Fab")
			(effects
				(font
					(size 1.27 1.27)
				)
			)
		)
		(duplicate_pad_numbers_are_jumpers no)
		(fp_line
			(start -0.299974 0.150114)
			(end -0.299974 -0.150114)
			(stroke
				(width 0.1)
				(type default)
			)
			(layer "F.Fab")
		)
		(fp_line
			(start 0.299974 0.150114)
			(end -0.299974 0.150114)
			(stroke
				(width 0.1)
				(type default)
			)
			(layer "F.Fab")
		)
		(fp_line
			(start -0.299974 -0.150114)
			(end 0.299974 -0.150114)
			(stroke
				(width 0.1)
				(type default)
			)
			(layer "F.Fab")
		)
		(fp_line
			(start 0.299974 -0.150114)
			(end 0.299974 0.150114)
			(stroke
				(width 0.1)
				(type default)
			)
			(layer "F.Fab")
		)
		(pad "1" smd rect
			(at -0.2667 0 270)
			(size 0.3048 0.381)
			(layers "F.Cu" "F.Mask" "F.Paste")
			(net "P5E_CPU0_PE3_TX_C_DN<6>")
		)
		(pad "2" smd rect
			(at 0.2667 0 270)
			(size 0.3048 0.381)
			(layers "F.Cu" "F.Mask" "F.Paste")
			(net "P5E_CPU0_PE3_TX_DN<6>")
		)
	)
	(footprint ""
		(layer "F.Cu")
		(at 104.104186 -40.935148)
		(property "Reference" "C1821"
			(at 0 0 0)
			(layer "F.SilkS")
			(hide yes)
			(effects
				(font
					(size 1.27 1.27)
				)
			)
		)
		(property "Value" ""
			(at 0 0 0)
			(layer "F.Fab")
			(effects
				(font
					(size 1.27 1.27)
				)
			)
		)
		(duplicate_pad_numbers_are_jumpers no)
		(fp_line
			(start -0.7874 -0.4064)
			(end 0.7874 -0.4064)
			(stroke
				(width 0.1524)
				(type default)
			)
			(layer "F.SilkS")
		)
		(fp_line
			(start -0.7874 0.4064)
			(end -0.7874 -0.4064)
			(stroke
				(width 0.1524)
				(type default)
			)
			(layer "F.SilkS")
		)
		(fp_line
			(start 0.7874 -0.4064)
			(end 0.7874 0.4064)
			(stroke
				(width 0.1524)
				(type default)
			)
			(layer "F.SilkS")
		)
		(fp_line
			(start 0.7874 0.4064)
			(end -0.7874 0.4064)
			(stroke
				(width 0.1524)
				(type default)
			)
			(layer "F.SilkS")
		)
		(fp_line
			(start -0.67945 -0.305054)
			(end -0.12065 -0.305054)
			(stroke
				(width 0.1)
				(type default)
			)
			(layer "F.Fab")
		)
		(fp_line
			(start -0.67945 0.3048)
			(end -0.67945 -0.305054)
			(stroke
				(width 0.1)
				(type default)
			)
			(layer "F.Fab")
		)
		(fp_line
			(start -0.12065 -0.305054)
			(end -0.12065 -0.2794)
			(stroke
				(width 0.1)
				(type default)
			)
			(layer "F.Fab")
		)
		(fp_line
			(start -0.12065 -0.2794)
			(end 0.12065 -0.2794)
			(stroke
				(width 0.1)
				(type default)
			)
			(layer "F.Fab")
		)
		(fp_line
			(start -0.12065 0.2794)
			(end -0.12065 0.3048)
			(stroke
				(width 0.1)
				(type default)
			)
			(layer "F.Fab")
		)
		(fp_line
			(start -0.12065 0.3048)
			(end -0.67945 0.3048)
			(stroke
				(width 0.1)
				(type default)
			)
			(layer "F.Fab")
		)
		(fp_line
			(start 0.120396 0.2794)
			(end -0.12065 0.2794)
			(stroke
				(width 0.1)
				(type default)
			)
			(layer "F.Fab")
		)
		(fp_line
			(start 0.120396 0.3048)
			(end 0.120396 0.2794)
			(stroke
				(width 0.1)
				(type default)
			)
			(layer "F.Fab")
		)
		(fp_line
			(start 0.12065 -0.3048)
			(end 0.67945 -0.3048)
			(stroke
				(width 0.1)
				(type default)
			)
			(layer "F.Fab")
		)
		(fp_line
			(start 0.12065 -0.2794)
			(end 0.12065 -0.3048)
			(stroke
				(width 0.1)
				(type default)
			)
			(layer "F.Fab")
		)
		(fp_line
			(start 0.67945 -0.3048)
			(end 0.67945 0.3048)
			(stroke
				(width 0.1)
				(type default)
			)
			(layer "F.Fab")
		)
		(fp_line
			(start 0.67945 0.3048)
			(end 0.120396 0.3048)
			(stroke
				(width 0.1)
				(type default)
			)
			(layer "F.Fab")
		)
		(pad "1" smd circle
			(at -0.40005 0)
			(size 0 0)
			(layers "F.Cu" "F.Mask" "F.Paste")
			(net "P3V3_AUX")
		)
		(pad "2" smd circle
			(at 0.40005 0)
			(size 0 0)
			(layers "F.Cu" "F.Mask" "F.Paste")
			(net "GND")
		)
	)
	(footprint ""
		(layer "F.Cu")
		(at 224.21215 -48.78197 180)
		(property "Reference" "R2426"
			(at 0 0 180)
			(layer "F.SilkS")
			(hide yes)
			(effects
				(font
					(size 1.27 1.27)
				)
			)
		)
		(property "Value" ""
			(at 0 0 180)
			(layer "F.Fab")
			(effects
				(font
					(size 1.27 1.27)
				)
			)
		)
		(duplicate_pad_numbers_are_jumpers no)
		(fp_line
			(start 0.7874 0.4064)
			(end -0.7874 0.4064)
			(stroke
				(width 0.1524)
				(type default)
			)
			(layer "F.SilkS")
		)
		(fp_line
			(start 0.7874 -0.4064)
			(end 0.7874 0.4064)
			(stroke
				(width 0.1524)
				(type default)
			)
			(layer "F.SilkS")
		)
		(fp_line
			(start -0.7874 0.4064)
			(end -0.7874 -0.4064)
			(stroke
				(width 0.1524)
				(type default)
			)
			(layer "F.SilkS")
		)
		(fp_line
			(start -0.7874 -0.4064)
			(end 0.7874 -0.4064)
			(stroke
				(width 0.1524)
				(type default)
			)
			(layer "F.SilkS")
		)
		(fp_line
			(start 0.67945 0.3048)
			(end 0.120396 0.3048)
			(stroke
				(width 0.1)
				(type default)
			)
			(layer "F.Fab")
		)
		(fp_line
			(start 0.67945 -0.3048)
			(end 0.67945 0.3048)
			(stroke
				(width 0.1)
				(type default)
			)
			(layer "F.Fab")
		)
		(fp_line
			(start 0.12065 -0.2794)
			(end 0.12065 -0.3048)
			(stroke
				(width 0.1)
				(type default)
			)
			(layer "F.Fab")
		)
		(fp_line
			(start 0.12065 -0.3048)
			(end 0.67945 -0.3048)
			(stroke
				(width 0.1)
				(type default)
			)
			(layer "F.Fab")
		)
		(fp_line
			(start 0.120396 0.3048)
			(end 0.120396 0.2794)
			(stroke
				(width 0.1)
				(type default)
			)
			(layer "F.Fab")
		)
		(fp_line
			(start 0.120396 0.2794)
			(end -0.12065 0.2794)
			(stroke
				(width 0.1)
				(type default)
			)
			(layer "F.Fab")
		)
		(fp_line
			(start -0.12065 0.3048)
			(end -0.67945 0.3048)
			(stroke
				(width 0.1)
				(type default)
			)
			(layer "F.Fab")
		)
		(fp_line
			(start -0.12065 0.2794)
			(end -0.12065 0.3048)
			(stroke
				(width 0.1)
				(type default)
			)
			(layer "F.Fab")
		)
		(fp_line
			(start -0.12065 -0.2794)
			(end 0.12065 -0.2794)
			(stroke
				(width 0.1)
				(type default)
			)
			(layer "F.Fab")
		)
		(fp_line
			(start -0.12065 -0.305054)
			(end -0.12065 -0.2794)
			(stroke
				(width 0.1)
				(type default)
			)
			(layer "F.Fab")
		)
		(fp_line
			(start -0.67945 0.3048)
			(end -0.67945 -0.305054)
			(stroke
				(width 0.1)
				(type default)
			)
			(layer "F.Fab")
		)
		(fp_line
			(start -0.67945 -0.305054)
			(end -0.12065 -0.305054)
			(stroke
				(width 0.1)
				(type default)
			)
			(layer "F.Fab")
		)
		(pad "1" smd circle
			(at -0.40005 0 180)
			(size 0 0)
			(layers "F.Cu" "F.Mask" "F.Paste")
			(net "E1S_0_PERST1_CLKREQ_N")
		)
		(pad "2" smd circle
			(at 0.40005 0 180)
			(size 0 0)
			(layers "F.Cu" "F.Mask" "F.Paste")
			(net "GND")
		)
	)
	(footprint ""
		(layer "F.Cu")
		(at 24.768556 -130.26898 180)
		(property "Reference" "PR665"
			(at 0 0 180)
			(layer "F.SilkS")
			(hide yes)
			(effects
				(font
					(size 1.27 1.27)
				)
			)
		)
		(property "Value" ""
			(at 0 0 180)
			(layer "F.Fab")
			(effects
				(font
					(size 1.27 1.27)
				)
			)
		)
		(duplicate_pad_numbers_are_jumpers no)
		(fp_line
			(start 0.7874 0.4064)
			(end -0.7874 0.4064)
			(stroke
				(width 0.1524)
				(type default)
			)
			(layer "F.SilkS")
		)
		(fp_line
			(start 0.7874 -0.4064)
			(end 0.7874 0.4064)
			(stroke
				(width 0.1524)
				(type default)
			)
			(layer "F.SilkS")
		)
		(fp_line
			(start -0.7874 0.4064)
			(end -0.7874 -0.4064)
			(stroke
				(width 0.1524)
				(type default)
			)
			(layer "F.SilkS")
		)
		(fp_line
			(start -0.7874 -0.4064)
			(end 0.7874 -0.4064)
			(stroke
				(width 0.1524)
				(type default)
			)
			(layer "F.SilkS")
		)
		(fp_line
			(start 0.67945 0.3048)
			(end 0.120396 0.3048)
			(stroke
				(width 0.1)
				(type default)
			)
			(layer "F.Fab")
		)
		(fp_line
			(start 0.67945 -0.3048)
			(end 0.67945 0.3048)
			(stroke
				(width 0.1)
				(type default)
			)
			(layer "F.Fab")
		)
		(fp_line
			(start 0.12065 -0.2794)
			(end 0.12065 -0.3048)
			(stroke
				(width 0.1)
				(type default)
			)
			(layer "F.Fab")
		)
		(fp_line
			(start 0.12065 -0.3048)
			(end 0.67945 -0.3048)
			(stroke
				(width 0.1)
				(type default)
			)
			(layer "F.Fab")
		)
		(fp_line
			(start 0.120396 0.3048)
			(end 0.120396 0.2794)
			(stroke
				(width 0.1)
				(type default)
			)
			(layer "F.Fab")
		)
		(fp_line
			(start 0.120396 0.2794)
			(end -0.12065 0.2794)
			(stroke
				(width 0.1)
				(type default)
			)
			(layer "F.Fab")
		)
		(fp_line
			(start -0.12065 0.3048)
			(end -0.67945 0.3048)
			(stroke
				(width 0.1)
				(type default)
			)
			(layer "F.Fab")
		)
		(fp_line
			(start -0.12065 0.2794)
			(end -0.12065 0.3048)
			(stroke
				(width 0.1)
				(type default)
			)
			(layer "F.Fab")
		)
		(fp_line
			(start -0.12065 -0.2794)
			(end 0.12065 -0.2794)
			(stroke
				(width 0.1)
				(type default)
			)
			(layer "F.Fab")
		)
		(fp_line
			(start -0.12065 -0.305054)
			(end -0.12065 -0.2794)
			(stroke
				(width 0.1)
				(type default)
			)
			(layer "F.Fab")
		)
		(fp_line
			(start -0.67945 0.3048)
			(end -0.67945 -0.305054)
			(stroke
				(width 0.1)
				(type default)
			)
			(layer "F.Fab")
		)
		(fp_line
			(start -0.67945 -0.305054)
			(end -0.12065 -0.305054)
			(stroke
				(width 0.1)
				(type default)
			)
			(layer "F.Fab")
		)
		(pad "1" smd circle
			(at -0.40005 0 180)
			(size 0 0)
			(layers "F.Cu" "F.Mask" "F.Paste")
			(net "PVCCINFAON_CPU1_ATSEN")
		)
		(pad "2" smd circle
			(at 0.40005 0 180)
			(size 0 0)
			(layers "F.Cu" "F.Mask" "F.Paste")
			(net "GND")
		)
	)
	(footprint ""
		(layer "F.Cu")
		(at 198.41464 -68.026788)
		(property "Reference" "PC2203"
			(at 0 0 0)
			(layer "F.SilkS")
			(hide yes)
			(effects
				(font
					(size 1.27 1.27)
				)
			)
		)
		(property "Value" ""
			(at 0 0 0)
			(layer "F.Fab")
			(effects
				(font
					(size 1.27 1.27)
				)
			)
		)
		(duplicate_pad_numbers_are_jumpers no)
		(fp_line
			(start -0.7874 -0.4064)
			(end 0.7874 -0.4064)
			(stroke
				(width 0.1524)
				(type default)
			)
			(layer "F.SilkS")
		)
		(fp_line
			(start -0.7874 0.4064)
			(end -0.7874 -0.4064)
			(stroke
				(width 0.1524)
				(type default)
			)
			(layer "F.SilkS")
		)
		(fp_line
			(start 0.7874 -0.4064)
			(end 0.7874 0.4064)
			(stroke
				(width 0.1524)
				(type default)
			)
			(layer "F.SilkS")
		)
		(fp_line
			(start 0.7874 0.4064)
			(end -0.7874 0.4064)
			(stroke
				(width 0.1524)
				(type default)
			)
			(layer "F.SilkS")
		)
		(fp_line
			(start -0.67945 -0.305054)
			(end -0.12065 -0.305054)
			(stroke
				(width 0.1)
				(type default)
			)
			(layer "F.Fab")
		)
		(fp_line
			(start -0.67945 0.3048)
			(end -0.67945 -0.305054)
			(stroke
				(width 0.1)
				(type default)
			)
			(layer "F.Fab")
		)
		(fp_line
			(start -0.12065 -0.305054)
			(end -0.12065 -0.2794)
			(stroke
				(width 0.1)
				(type default)
			)
			(layer "F.Fab")
		)
		(fp_line
			(start -0.12065 -0.2794)
			(end 0.12065 -0.2794)
			(stroke
				(width 0.1)
				(type default)
			)
			(layer "F.Fab")
		)
		(fp_line
			(start -0.12065 0.2794)
			(end -0.12065 0.3048)
			(stroke
				(width 0.1)
				(type default)
			)
			(layer "F.Fab")
		)
		(fp_line
			(start -0.12065 0.3048)
			(end -0.67945 0.3048)
			(stroke
				(width 0.1)
				(type default)
			)
			(layer "F.Fab")
		)
		(fp_line
			(start 0.120396 0.2794)
			(end -0.12065 0.2794)
			(stroke
				(width 0.1)
				(type default)
			)
			(layer "F.Fab")
		)
		(fp_line
			(start 0.120396 0.3048)
			(end 0.120396 0.2794)
			(stroke
				(width 0.1)
				(type default)
			)
			(layer "F.Fab")
		)
		(fp_line
			(start 0.12065 -0.3048)
			(end 0.67945 -0.3048)
			(stroke
				(width 0.1)
				(type default)
			)
			(layer "F.Fab")
		)
		(fp_line
			(start 0.12065 -0.2794)
			(end 0.12065 -0.3048)
			(stroke
				(width 0.1)
				(type default)
			)
			(layer "F.Fab")
		)
		(fp_line
			(start 0.67945 -0.3048)
			(end 0.67945 0.3048)
			(stroke
				(width 0.1)
				(type default)
			)
			(layer "F.Fab")
		)
		(fp_line
			(start 0.67945 0.3048)
			(end 0.120396 0.3048)
			(stroke
				(width 0.1)
				(type default)
			)
			(layer "F.Fab")
		)
		(pad "1" smd circle
			(at -0.40005 0)
			(size 0 0)
			(layers "F.Cu" "F.Mask" "F.Paste")
			(net "P3V3_E1S_GATE_0_PU293")
		)
		(pad "2" smd circle
			(at 0.40005 0)
			(size 0 0)
			(layers "F.Cu" "F.Mask" "F.Paste")
			(net "GND")
		)
	)
	(footprint ""
		(layer "F.Cu")
		(at 140.00988 -46.954948 180)
		(property "Reference" "R3298"
			(at 0 0 180)
			(layer "F.SilkS")
			(hide yes)
			(effects
				(font
					(size 1.27 1.27)
				)
			)
		)
		(property "Value" ""
			(at 0 0 180)
			(layer "F.Fab")
			(effects
				(font
					(size 1.27 1.27)
				)
			)
		)
		(duplicate_pad_numbers_are_jumpers no)
		(fp_line
			(start 0.7874 0.4064)
			(end -0.7874 0.4064)
			(stroke
				(width 0.1524)
				(type default)
			)
			(layer "F.SilkS")
		)
		(fp_line
			(start 0.7874 -0.4064)
			(end 0.7874 0.4064)
			(stroke
				(width 0.1524)
				(type default)
			)
			(layer "F.SilkS")
		)
		(fp_line
			(start -0.7874 0.4064)
			(end -0.7874 -0.4064)
			(stroke
				(width 0.1524)
				(type default)
			)
			(layer "F.SilkS")
		)
		(fp_line
			(start -0.7874 -0.4064)
			(end 0.7874 -0.4064)
			(stroke
				(width 0.1524)
				(type default)
			)
			(layer "F.SilkS")
		)
		(fp_line
			(start 0.67945 0.3048)
			(end 0.120396 0.3048)
			(stroke
				(width 0.1)
				(type default)
			)
			(layer "F.Fab")
		)
		(fp_line
			(start 0.67945 -0.3048)
			(end 0.67945 0.3048)
			(stroke
				(width 0.1)
				(type default)
			)
			(layer "F.Fab")
		)
		(fp_line
			(start 0.12065 -0.2794)
			(end 0.12065 -0.3048)
			(stroke
				(width 0.1)
				(type default)
			)
			(layer "F.Fab")
		)
		(fp_line
			(start 0.12065 -0.3048)
			(end 0.67945 -0.3048)
			(stroke
				(width 0.1)
				(type default)
			)
			(layer "F.Fab")
		)
		(fp_line
			(start 0.120396 0.3048)
			(end 0.120396 0.2794)
			(stroke
				(width 0.1)
				(type default)
			)
			(layer "F.Fab")
		)
		(fp_line
			(start 0.120396 0.2794)
			(end -0.12065 0.2794)
			(stroke
				(width 0.1)
				(type default)
			)
			(layer "F.Fab")
		)
		(fp_line
			(start -0.12065 0.3048)
			(end -0.67945 0.3048)
			(stroke
				(width 0.1)
				(type default)
			)
			(layer "F.Fab")
		)
		(fp_line
			(start -0.12065 0.2794)
			(end -0.12065 0.3048)
			(stroke
				(width 0.1)
				(type default)
			)
			(layer "F.Fab")
		)
		(fp_line
			(start -0.12065 -0.2794)
			(end 0.12065 -0.2794)
			(stroke
				(width 0.1)
				(type default)
			)
			(layer "F.Fab")
		)
		(fp_line
			(start -0.12065 -0.305054)
			(end -0.12065 -0.2794)
			(stroke
				(width 0.1)
				(type default)
			)
			(layer "F.Fab")
		)
		(fp_line
			(start -0.67945 0.3048)
			(end -0.67945 -0.305054)
			(stroke
				(width 0.1)
				(type default)
			)
			(layer "F.Fab")
		)
		(fp_line
			(start -0.67945 -0.305054)
			(end -0.12065 -0.305054)
			(stroke
				(width 0.1)
				(type default)
			)
			(layer "F.Fab")
		)
		(pad "1" smd circle
			(at -0.40005 0 180)
			(size 0 0)
			(layers "F.Cu" "F.Mask" "F.Paste")
			(net "P3V3_AUX")
		)
		(pad "2" smd circle
			(at 0.40005 0 180)
			(size 0 0)
			(layers "F.Cu" "F.Mask" "F.Paste")
			(net "HDD_ACTIVITY_BUF_N")
		)
	)
	(footprint ""
		(layer "F.Cu")
		(at 382.165352 -345.393264 90)
		(property "Reference" "PC226"
			(at 0 0 90)
			(layer "F.SilkS")
			(hide yes)
			(effects
				(font
					(size 1.27 1.27)
				)
			)
		)
		(property "Value" ""
			(at 0 0 90)
			(layer "F.Fab")
			(effects
				(font
					(size 1.27 1.27)
				)
			)
		)
		(duplicate_pad_numbers_are_jumpers no)
		(fp_line
			(start 0.7874 -0.4064)
			(end 0.7874 0.4064)
			(stroke
				(width 0.1524)
				(type default)
			)
			(layer "F.SilkS")
		)
		(fp_line
			(start -0.7874 -0.4064)
			(end 0.7874 -0.4064)
			(stroke
				(width 0.1524)
				(type default)
			)
			(layer "F.SilkS")
		)
		(fp_line
			(start 0.7874 0.4064)
			(end -0.7874 0.4064)
			(stroke
				(width 0.1524)
				(type default)
			)
			(layer "F.SilkS")
		)
		(fp_line
			(start -0.7874 0.4064)
			(end -0.7874 -0.4064)
			(stroke
				(width 0.1524)
				(type default)
			)
			(layer "F.SilkS")
		)
		(fp_line
			(start -0.12065 -0.305054)
			(end -0.12065 -0.2794)
			(stroke
				(width 0.1)
				(type default)
			)
			(layer "F.Fab")
		)
		(fp_line
			(start -0.67945 -0.305054)
			(end -0.12065 -0.305054)
			(stroke
				(width 0.1)
				(type default)
			)
			(layer "F.Fab")
		)
		(fp_line
			(start 0.67945 -0.3048)
			(end 0.67945 0.3048)
			(stroke
				(width 0.1)
				(type default)
			)
			(layer "F.Fab")
		)
		(fp_line
			(start 0.12065 -0.3048)
			(end 0.67945 -0.3048)
			(stroke
				(width 0.1)
				(type default)
			)
			(layer "F.Fab")
		)
		(fp_line
			(start 0.12065 -0.2794)
			(end 0.12065 -0.3048)
			(stroke
				(width 0.1)
				(type default)
			)
			(layer "F.Fab")
		)
		(fp_line
			(start -0.12065 -0.2794)
			(end 0.12065 -0.2794)
			(stroke
				(width 0.1)
				(type default)
			)
			(layer "F.Fab")
		)
		(fp_line
			(start 0.120396 0.2794)
			(end -0.12065 0.2794)
			(stroke
				(width 0.1)
				(type default)
			)
			(layer "F.Fab")
		)
		(fp_line
			(start -0.12065 0.2794)
			(end -0.12065 0.3048)
			(stroke
				(width 0.1)
				(type default)
			)
			(layer "F.Fab")
		)
		(fp_line
			(start 0.67945 0.3048)
			(end 0.120396 0.3048)
			(stroke
				(width 0.1)
				(type default)
			)
			(layer "F.Fab")
		)
		(fp_line
			(start 0.120396 0.3048)
			(end 0.120396 0.2794)
			(stroke
				(width 0.1)
				(type default)
			)
			(layer "F.Fab")
		)
		(fp_line
			(start -0.12065 0.3048)
			(end -0.67945 0.3048)
			(stroke
				(width 0.1)
				(type default)
			)
			(layer "F.Fab")
		)
		(fp_line
			(start -0.67945 0.3048)
			(end -0.67945 -0.305054)
			(stroke
				(width 0.1)
				(type default)
			)
			(layer "F.Fab")
		)
		(pad "1" smd circle
			(at -0.40005 0 90)
			(size 0 0)
			(layers "F.Cu" "F.Mask" "F.Paste")
			(net "PVCCIN_CPU0_VDD8")
		)
		(pad "2" smd circle
			(at 0.40005 0 90)
			(size 0 0)
			(layers "F.Cu" "F.Mask" "F.Paste")
			(net "GND")
		)
	)
	(footprint ""
		(layer "F.Cu")
		(at 367.44783 -245.634002 -90)
		(property "Reference" "C403"
			(at 0 0 270)
			(layer "F.SilkS")
			(hide yes)
			(effects
				(font
					(size 1.27 1.27)
				)
			)
		)
		(property "Value" ""
			(at 0 0 270)
			(layer "F.Fab")
			(effects
				(font
					(size 1.27 1.27)
				)
			)
		)
		(duplicate_pad_numbers_are_jumpers no)
		(fp_line
			(start -0.7874 0.4064)
			(end -0.7874 -0.4064)
			(stroke
				(width 0.1524)
				(type default)
			)
			(layer "F.SilkS")
		)
		(fp_line
			(start 0.7874 0.4064)
			(end -0.7874 0.4064)
			(stroke
				(width 0.1524)
				(type default)
			)
			(layer "F.SilkS")
		)
		(fp_line
			(start -0.7874 -0.4064)
			(end 0.7874 -0.4064)
			(stroke
				(width 0.1524)
				(type default)
			)
			(layer "F.SilkS")
		)
		(fp_line
			(start 0.7874 -0.4064)
			(end 0.7874 0.4064)
			(stroke
				(width 0.1524)
				(type default)
			)
			(layer "F.SilkS")
		)
		(fp_line
			(start -0.67945 0.3048)
			(end -0.67945 -0.305054)
			(stroke
				(width 0.1)
				(type default)
			)
			(layer "F.Fab")
		)
		(fp_line
			(start -0.12065 0.3048)
			(end -0.67945 0.3048)
			(stroke
				(width 0.1)
				(type default)
			)
			(layer "F.Fab")
		)
		(fp_line
			(start 0.120396 0.3048)
			(end 0.120396 0.2794)
			(stroke
				(width 0.1)
				(type default)
			)
			(layer "F.Fab")
		)
		(fp_line
			(start 0.67945 0.3048)
			(end 0.120396 0.3048)
			(stroke
				(width 0.1)
				(type default)
			)
			(layer "F.Fab")
		)
		(fp_line
			(start -0.12065 0.2794)
			(end -0.12065 0.3048)
			(stroke
				(width 0.1)
				(type default)
			)
			(layer "F.Fab")
		)
		(fp_line
			(start 0.120396 0.2794)
			(end -0.12065 0.2794)
			(stroke
				(width 0.1)
				(type default)
			)
			(layer "F.Fab")
		)
		(fp_line
			(start -0.12065 -0.2794)
			(end 0.12065 -0.2794)
			(stroke
				(width 0.1)
				(type default)
			)
			(layer "F.Fab")
		)
		(fp_line
			(start 0.12065 -0.2794)
			(end 0.12065 -0.3048)
			(stroke
				(width 0.1)
				(type default)
			)
			(layer "F.Fab")
		)
		(fp_line
			(start 0.12065 -0.3048)
			(end 0.67945 -0.3048)
			(stroke
				(width 0.1)
				(type default)
			)
			(layer "F.Fab")
		)
		(fp_line
			(start 0.67945 -0.3048)
			(end 0.67945 0.3048)
			(stroke
				(width 0.1)
				(type default)
			)
			(layer "F.Fab")
		)
		(fp_line
			(start -0.67945 -0.305054)
			(end -0.12065 -0.305054)
			(stroke
				(width 0.1)
				(type default)
			)
			(layer "F.Fab")
		)
		(fp_line
			(start -0.12065 -0.305054)
			(end -0.12065 -0.2794)
			(stroke
				(width 0.1)
				(type default)
			)
			(layer "F.Fab")
		)
		(pad "1" smd circle
			(at -0.40005 0 270)
			(size 0 0)
			(layers "F.Cu" "F.Mask" "F.Paste")
			(net "PVCCD_HV_CPU0")
		)
		(pad "2" smd circle
			(at 0.40005 0 270)
			(size 0 0)
			(layers "F.Cu" "F.Mask" "F.Paste")
			(net "GND")
		)
	)
	(footprint ""
		(layer "F.Cu")
		(at 388.014972 -76.171044 90)
		(property "Reference" "PC1233"
			(at 0 0 90)
			(layer "F.SilkS")
			(hide yes)
			(effects
				(font
					(size 1.27 1.27)
				)
			)
		)
		(property "Value" ""
			(at 0 0 90)
			(layer "F.Fab")
			(effects
				(font
					(size 1.27 1.27)
				)
			)
		)
		(duplicate_pad_numbers_are_jumpers no)
		(fp_line
			(start 1.524 -0.762)
			(end 1.524 0.762)
			(stroke
				(width 0.1524)
				(type default)
			)
			(layer "F.SilkS")
		)
		(fp_line
			(start -1.524 -0.762)
			(end 1.524 -0.762)
			(stroke
				(width 0.1524)
				(type default)
			)
			(layer "F.SilkS")
		)
		(fp_line
			(start 1.524 0.762)
			(end -1.524 0.762)
			(stroke
				(width 0.1524)
				(type default)
			)
			(layer "F.SilkS")
		)
		(fp_line
			(start -1.524 0.762)
			(end -1.524 -0.762)
			(stroke
				(width 0.1524)
				(type default)
			)
			(layer "F.SilkS")
		)
		(fp_line
			(start 1.1049 -0.724916)
			(end -1.1049 -0.724916)
			(stroke
				(width 0.1)
				(type default)
			)
			(layer "F.Fab")
		)
		(fp_line
			(start -1.1049 -0.724916)
			(end -1.1049 0.724916)
			(stroke
				(width 0.1)
				(type default)
			)
			(layer "F.Fab")
		)
		(fp_line
			(start 1.1049 0.724916)
			(end 1.1049 -0.724916)
			(stroke
				(width 0.1)
				(type default)
			)
			(layer "F.Fab")
		)
		(fp_line
			(start -1.1049 0.724916)
			(end 1.1049 0.724916)
			(stroke
				(width 0.1)
				(type default)
			)
			(layer "F.Fab")
		)
		(pad "1" smd rect
			(at -0.889 0 270)
			(size 1.016 1.27)
			(layers "F.Cu" "F.Mask" "F.Paste")
			(net "SW_P1V8_PCH_AUX_FLT")
		)
		(pad "2" smd rect
			(at 0.889 0 270)
			(size 1.016 1.27)
			(layers "F.Cu" "F.Mask" "F.Paste")
			(net "GND")
		)
	)
	(footprint ""
		(layer "F.Cu")
		(at 119.508016 -251.375672 90)
		(property "Reference" "C258"
			(at 0 0 90)
			(layer "F.SilkS")
			(hide yes)
			(effects
				(font
					(size 1.27 1.27)
				)
			)
		)
		(property "Value" ""
			(at 0 0 90)
			(layer "F.Fab")
			(effects
				(font
					(size 1.27 1.27)
				)
			)
		)
		(duplicate_pad_numbers_are_jumpers no)
		(fp_line
			(start 0.7874 -0.4064)
			(end 0.7874 0.4064)
			(stroke
				(width 0.1524)
				(type default)
			)
			(layer "F.SilkS")
		)
		(fp_line
			(start -0.7874 -0.4064)
			(end 0.7874 -0.4064)
			(stroke
				(width 0.1524)
				(type default)
			)
			(layer "F.SilkS")
		)
		(fp_line
			(start 0.7874 0.4064)
			(end -0.7874 0.4064)
			(stroke
				(width 0.1524)
				(type default)
			)
			(layer "F.SilkS")
		)
		(fp_line
			(start -0.7874 0.4064)
			(end -0.7874 -0.4064)
			(stroke
				(width 0.1524)
				(type default)
			)
			(layer "F.SilkS")
		)
		(fp_line
			(start -0.12065 -0.305054)
			(end -0.12065 -0.2794)
			(stroke
				(width 0.1)
				(type default)
			)
			(layer "F.Fab")
		)
		(fp_line
			(start -0.67945 -0.305054)
			(end -0.12065 -0.305054)
			(stroke
				(width 0.1)
				(type default)
			)
			(layer "F.Fab")
		)
		(fp_line
			(start 0.67945 -0.3048)
			(end 0.67945 0.3048)
			(stroke
				(width 0.1)
				(type default)
			)
			(layer "F.Fab")
		)
		(fp_line
			(start 0.12065 -0.3048)
			(end 0.67945 -0.3048)
			(stroke
				(width 0.1)
				(type default)
			)
			(layer "F.Fab")
		)
		(fp_line
			(start 0.12065 -0.2794)
			(end 0.12065 -0.3048)
			(stroke
				(width 0.1)
				(type default)
			)
			(layer "F.Fab")
		)
		(fp_line
			(start -0.12065 -0.2794)
			(end 0.12065 -0.2794)
			(stroke
				(width 0.1)
				(type default)
			)
			(layer "F.Fab")
		)
		(fp_line
			(start 0.120396 0.2794)
			(end -0.12065 0.2794)
			(stroke
				(width 0.1)
				(type default)
			)
			(layer "F.Fab")
		)
		(fp_line
			(start -0.12065 0.2794)
			(end -0.12065 0.3048)
			(stroke
				(width 0.1)
				(type default)
			)
			(layer "F.Fab")
		)
		(fp_line
			(start 0.67945 0.3048)
			(end 0.120396 0.3048)
			(stroke
				(width 0.1)
				(type default)
			)
			(layer "F.Fab")
		)
		(fp_line
			(start 0.120396 0.3048)
			(end 0.120396 0.2794)
			(stroke
				(width 0.1)
				(type default)
			)
			(layer "F.Fab")
		)
		(fp_line
			(start -0.12065 0.3048)
			(end -0.67945 0.3048)
			(stroke
				(width 0.1)
				(type default)
			)
			(layer "F.Fab")
		)
		(fp_line
			(start -0.67945 0.3048)
			(end -0.67945 -0.305054)
			(stroke
				(width 0.1)
				(type default)
			)
			(layer "F.Fab")
		)
		(pad "1" smd circle
			(at -0.40005 0 90)
			(size 0 0)
			(layers "F.Cu" "F.Mask" "F.Paste")
			(net "PVCCIN_CPU1")
		)
		(pad "2" smd circle
			(at 0.40005 0 90)
			(size 0 0)
			(layers "F.Cu" "F.Mask" "F.Paste")
			(net "GND")
		)
	)
	(footprint ""
		(layer "F.Cu")
		(at 317.396622 -54.803548)
		(property "Reference" "R623"
			(at 0 0 0)
			(layer "F.SilkS")
			(hide yes)
			(effects
				(font
					(size 1.27 1.27)
				)
			)
		)
		(property "Value" ""
			(at 0 0 0)
			(layer "F.Fab")
			(effects
				(font
					(size 1.27 1.27)
				)
			)
		)
		(duplicate_pad_numbers_are_jumpers no)
		(fp_line
			(start -0.7874 -0.4064)
			(end 0.7874 -0.4064)
			(stroke
				(width 0.1524)
				(type default)
			)
			(layer "F.SilkS")
		)
		(fp_line
			(start -0.7874 0.4064)
			(end -0.7874 -0.4064)
			(stroke
				(width 0.1524)
				(type default)
			)
			(layer "F.SilkS")
		)
		(fp_line
			(start 0.7874 -0.4064)
			(end 0.7874 0.4064)
			(stroke
				(width 0.1524)
				(type default)
			)
			(layer "F.SilkS")
		)
		(fp_line
			(start 0.7874 0.4064)
			(end -0.7874 0.4064)
			(stroke
				(width 0.1524)
				(type default)
			)
			(layer "F.SilkS")
		)
		(fp_line
			(start -0.67945 -0.305054)
			(end -0.12065 -0.305054)
			(stroke
				(width 0.1)
				(type default)
			)
			(layer "F.Fab")
		)
		(fp_line
			(start -0.67945 0.3048)
			(end -0.67945 -0.305054)
			(stroke
				(width 0.1)
				(type default)
			)
			(layer "F.Fab")
		)
		(fp_line
			(start -0.12065 -0.305054)
			(end -0.12065 -0.2794)
			(stroke
				(width 0.1)
				(type default)
			)
			(layer "F.Fab")
		)
		(fp_line
			(start -0.12065 -0.2794)
			(end 0.12065 -0.2794)
			(stroke
				(width 0.1)
				(type default)
			)
			(layer "F.Fab")
		)
		(fp_line
			(start -0.12065 0.2794)
			(end -0.12065 0.3048)
			(stroke
				(width 0.1)
				(type default)
			)
			(layer "F.Fab")
		)
		(fp_line
			(start -0.12065 0.3048)
			(end -0.67945 0.3048)
			(stroke
				(width 0.1)
				(type default)
			)
			(layer "F.Fab")
		)
		(fp_line
			(start 0.120396 0.2794)
			(end -0.12065 0.2794)
			(stroke
				(width 0.1)
				(type default)
			)
			(layer "F.Fab")
		)
		(fp_line
			(start 0.120396 0.3048)
			(end 0.120396 0.2794)
			(stroke
				(width 0.1)
				(type default)
			)
			(layer "F.Fab")
		)
		(fp_line
			(start 0.12065 -0.3048)
			(end 0.67945 -0.3048)
			(stroke
				(width 0.1)
				(type default)
			)
			(layer "F.Fab")
		)
		(fp_line
			(start 0.12065 -0.2794)
			(end 0.12065 -0.3048)
			(stroke
				(width 0.1)
				(type default)
			)
			(layer "F.Fab")
		)
		(fp_line
			(start 0.67945 -0.3048)
			(end 0.67945 0.3048)
			(stroke
				(width 0.1)
				(type default)
			)
			(layer "F.Fab")
		)
		(fp_line
			(start 0.67945 0.3048)
			(end 0.120396 0.3048)
			(stroke
				(width 0.1)
				(type default)
			)
			(layer "F.Fab")
		)
		(pad "1" smd circle
			(at -0.40005 0)
			(size 0 0)
			(layers "F.Cu" "F.Mask" "F.Paste")
			(net "P3V3_AUX")
		)
		(pad "2" smd circle
			(at 0.40005 0)
			(size 0 0)
			(layers "F.Cu" "F.Mask" "F.Paste")
			(net "FM_PCH_XTALSEL")
		)
	)
	(footprint ""
		(layer "F.Cu")
		(at 73.28408 -144.665192 180)
		(property "Reference" "PR566"
			(at 0 0 180)
			(layer "F.SilkS")
			(hide yes)
			(effects
				(font
					(size 1.27 1.27)
				)
			)
		)
		(property "Value" ""
			(at 0 0 180)
			(layer "F.Fab")
			(effects
				(font
					(size 1.27 1.27)
				)
			)
		)
		(duplicate_pad_numbers_are_jumpers no)
		(fp_line
			(start 0.7874 0.4064)
			(end -0.7874 0.4064)
			(stroke
				(width 0.1524)
				(type default)
			)
			(layer "F.SilkS")
		)
		(fp_line
			(start 0.7874 -0.4064)
			(end 0.7874 0.4064)
			(stroke
				(width 0.1524)
				(type default)
			)
			(layer "F.SilkS")
		)
		(fp_line
			(start -0.7874 0.4064)
			(end -0.7874 -0.4064)
			(stroke
				(width 0.1524)
				(type default)
			)
			(layer "F.SilkS")
		)
		(fp_line
			(start -0.7874 -0.4064)
			(end 0.7874 -0.4064)
			(stroke
				(width 0.1524)
				(type default)
			)
			(layer "F.SilkS")
		)
		(fp_line
			(start 0.67945 0.3048)
			(end 0.120396 0.3048)
			(stroke
				(width 0.1)
				(type default)
			)
			(layer "F.Fab")
		)
		(fp_line
			(start 0.67945 -0.3048)
			(end 0.67945 0.3048)
			(stroke
				(width 0.1)
				(type default)
			)
			(layer "F.Fab")
		)
		(fp_line
			(start 0.12065 -0.2794)
			(end 0.12065 -0.3048)
			(stroke
				(width 0.1)
				(type default)
			)
			(layer "F.Fab")
		)
		(fp_line
			(start 0.12065 -0.3048)
			(end 0.67945 -0.3048)
			(stroke
				(width 0.1)
				(type default)
			)
			(layer "F.Fab")
		)
		(fp_line
			(start 0.120396 0.3048)
			(end 0.120396 0.2794)
			(stroke
				(width 0.1)
				(type default)
			)
			(layer "F.Fab")
		)
		(fp_line
			(start 0.120396 0.2794)
			(end -0.12065 0.2794)
			(stroke
				(width 0.1)
				(type default)
			)
			(layer "F.Fab")
		)
		(fp_line
			(start -0.12065 0.3048)
			(end -0.67945 0.3048)
			(stroke
				(width 0.1)
				(type default)
			)
			(layer "F.Fab")
		)
		(fp_line
			(start -0.12065 0.2794)
			(end -0.12065 0.3048)
			(stroke
				(width 0.1)
				(type default)
			)
			(layer "F.Fab")
		)
		(fp_line
			(start -0.12065 -0.2794)
			(end 0.12065 -0.2794)
			(stroke
				(width 0.1)
				(type default)
			)
			(layer "F.Fab")
		)
		(fp_line
			(start -0.12065 -0.305054)
			(end -0.12065 -0.2794)
			(stroke
				(width 0.1)
				(type default)
			)
			(layer "F.Fab")
		)
		(fp_line
			(start -0.67945 0.3048)
			(end -0.67945 -0.305054)
			(stroke
				(width 0.1)
				(type default)
			)
			(layer "F.Fab")
		)
		(fp_line
			(start -0.67945 -0.305054)
			(end -0.12065 -0.305054)
			(stroke
				(width 0.1)
				(type default)
			)
			(layer "F.Fab")
		)
		(pad "1" smd circle
			(at -0.40005 0 180)
			(size 0 0)
			(layers "F.Cu" "F.Mask" "F.Paste")
			(net "VSENSE_PVCCINFAON_CPU1_DN")
		)
		(pad "2" smd circle
			(at 0.40005 0 180)
			(size 0 0)
			(layers "F.Cu" "F.Mask" "F.Paste")
			(net "GND")
		)
	)
	(footprint ""
		(layer "F.Cu")
		(at 322.90004 -160.50006)
		(property "Reference" "H88"
			(at -6.47192 -4.13131 0)
			(unlocked yes)
			(layer "F.SilkS")
			(effects
				(font
					(size 0.7874 0.5842)
					(thickness 0.1524)
				)
				(justify left)
			)
		)
		(property "Value" ""
			(at 0 0 0)
			(layer "F.Fab")
			(effects
				(font
					(size 1.27 1.27)
				)
			)
		)
		(duplicate_pad_numbers_are_jumpers no)
		(pad "1" thru_hole circle
			(at 0 0)
			(size 10.0076 10.0076)
			(drill 5.6134)
			(layers "*.Cu" "*.Mask")
			(remove_unused_layers no)
			(net "GND")
			(clearance -1.9431)
		)
	)
	(footprint ""
		(layer "F.Cu")
		(at 61.475366 -174.230792)
		(property "Reference" "PL20"
			(at -6.598666 -4.515358 0)
			(unlocked yes)
			(layer "F.SilkS")
			(effects
				(font
					(size 0.7874 0.5842)
					(thickness 0.1524)
				)
				(justify left)
			)
		)
		(property "Value" ""
			(at 0 0 0)
			(layer "F.Fab")
			(effects
				(font
					(size 1.27 1.27)
				)
			)
		)
		(duplicate_pad_numbers_are_jumpers no)
		(fp_line
			(start -4.800092 -3.199892)
			(end 4.800092 -3.199892)
			(stroke
				(width 0.1524)
				(type default)
			)
			(layer "F.SilkS")
		)
		(fp_line
			(start -4.800092 -1.6891)
			(end -4.800092 -3.199892)
			(stroke
				(width 0.1524)
				(type default)
			)
			(layer "F.SilkS")
		)
		(fp_line
			(start -4.800092 3.199892)
			(end -4.800092 1.6891)
			(stroke
				(width 0.1524)
				(type default)
			)
			(layer "F.SilkS")
		)
		(fp_line
			(start 4.800092 -3.199892)
			(end 4.800092 -1.6891)
			(stroke
				(width 0.1524)
				(type default)
			)
			(layer "F.SilkS")
		)
		(fp_line
			(start 4.800092 1.6891)
			(end 4.800092 3.199892)
			(stroke
				(width 0.1524)
				(type default)
			)
			(layer "F.SilkS")
		)
		(fp_line
			(start 4.800092 3.199892)
			(end -4.800092 3.199892)
			(stroke
				(width 0.1524)
				(type default)
			)
			(layer "F.SilkS")
		)
		(fp_line
			(start -4.800092 -3.199892)
			(end 4.800092 -3.199892)
			(stroke
				(width 0.1)
				(type default)
			)
			(layer "F.Fab")
		)
		(fp_line
			(start -4.800092 3.199892)
			(end -4.800092 -3.199892)
			(stroke
				(width 0.1)
				(type default)
			)
			(layer "F.Fab")
		)
		(fp_line
			(start 4.800092 -3.199892)
			(end 4.800092 3.199892)
			(stroke
				(width 0.1)
				(type default)
			)
			(layer "F.Fab")
		)
		(fp_line
			(start 4.800092 3.199892)
			(end -4.800092 3.199892)
			(stroke
				(width 0.1)
				(type default)
			)
			(layer "F.Fab")
		)
		(pad "1" smd rect
			(at -3.350006 0 90)
			(size 3.0988 3.2004)
			(layers "F.Cu" "F.Mask" "F.Paste")
			(net "SW_PVCCFA_EHV_CPU1_SW1")
		)
		(pad "2" smd rect
			(at 3.350006 0 90)
			(size 3.0988 3.2004)
			(layers "F.Cu" "F.Mask" "F.Paste")
			(net "PVCCFA_EHV_CPU1")
		)
	)
	(footprint ""
		(layer "F.Cu")
		(at 51.593496 -113.72977)
		(property "Reference" "R3723"
			(at 0 0 0)
			(layer "F.SilkS")
			(hide yes)
			(effects
				(font
					(size 1.27 1.27)
				)
			)
		)
		(property "Value" ""
			(at 0 0 0)
			(layer "F.Fab")
			(effects
				(font
					(size 1.27 1.27)
				)
			)
		)
		(duplicate_pad_numbers_are_jumpers no)
		(fp_line
			(start -0.7874 -0.4064)
			(end 0.7874 -0.4064)
			(stroke
				(width 0.1524)
				(type default)
			)
			(layer "F.SilkS")
		)
		(fp_line
			(start -0.7874 0.4064)
			(end -0.7874 -0.4064)
			(stroke
				(width 0.1524)
				(type default)
			)
			(layer "F.SilkS")
		)
		(fp_line
			(start 0.7874 -0.4064)
			(end 0.7874 0.4064)
			(stroke
				(width 0.1524)
				(type default)
			)
			(layer "F.SilkS")
		)
		(fp_line
			(start 0.7874 0.4064)
			(end -0.7874 0.4064)
			(stroke
				(width 0.1524)
				(type default)
			)
			(layer "F.SilkS")
		)
		(fp_line
			(start -0.67945 -0.305054)
			(end -0.12065 -0.305054)
			(stroke
				(width 0.1)
				(type default)
			)
			(layer "F.Fab")
		)
		(fp_line
			(start -0.67945 0.3048)
			(end -0.67945 -0.305054)
			(stroke
				(width 0.1)
				(type default)
			)
			(layer "F.Fab")
		)
		(fp_line
			(start -0.12065 -0.305054)
			(end -0.12065 -0.2794)
			(stroke
				(width 0.1)
				(type default)
			)
			(layer "F.Fab")
		)
		(fp_line
			(start -0.12065 -0.2794)
			(end 0.12065 -0.2794)
			(stroke
				(width 0.1)
				(type default)
			)
			(layer "F.Fab")
		)
		(fp_line
			(start -0.12065 0.2794)
			(end -0.12065 0.3048)
			(stroke
				(width 0.1)
				(type default)
			)
			(layer "F.Fab")
		)
		(fp_line
			(start -0.12065 0.3048)
			(end -0.67945 0.3048)
			(stroke
				(width 0.1)
				(type default)
			)
			(layer "F.Fab")
		)
		(fp_line
			(start 0.120396 0.2794)
			(end -0.12065 0.2794)
			(stroke
				(width 0.1)
				(type default)
			)
			(layer "F.Fab")
		)
		(fp_line
			(start 0.120396 0.3048)
			(end 0.120396 0.2794)
			(stroke
				(width 0.1)
				(type default)
			)
			(layer "F.Fab")
		)
		(fp_line
			(start 0.12065 -0.3048)
			(end 0.67945 -0.3048)
			(stroke
				(width 0.1)
				(type default)
			)
			(layer "F.Fab")
		)
		(fp_line
			(start 0.12065 -0.2794)
			(end 0.12065 -0.3048)
			(stroke
				(width 0.1)
				(type default)
			)
			(layer "F.Fab")
		)
		(fp_line
			(start 0.67945 -0.3048)
			(end 0.67945 0.3048)
			(stroke
				(width 0.1)
				(type default)
			)
			(layer "F.Fab")
		)
		(fp_line
			(start 0.67945 0.3048)
			(end 0.120396 0.3048)
			(stroke
				(width 0.1)
				(type default)
			)
			(layer "F.Fab")
		)
		(pad "1" smd circle
			(at -0.40005 0)
			(size 0 0)
			(layers "F.Cu" "F.Mask" "F.Paste")
			(net "P3V3_AUX")
		)
		(pad "2" smd circle
			(at 0.40005 0)
			(size 0 0)
			(layers "F.Cu" "F.Mask" "F.Paste")
			(net "SMB_VR_3V3AUX_SCL")
		)
	)
	(footprint ""
		(layer "F.Cu")
		(at 182.58282 -419.47338 -90)
		(property "Reference" "R4796"
			(at 0 0 270)
			(layer "F.SilkS")
			(hide yes)
			(effects
				(font
					(size 1.27 1.27)
				)
			)
		)
		(property "Value" ""
			(at 0 0 270)
			(layer "F.Fab")
			(effects
				(font
					(size 1.27 1.27)
				)
			)
		)
		(duplicate_pad_numbers_are_jumpers no)
		(fp_line
			(start -0.7874 0.4064)
			(end -0.7874 -0.4064)
			(stroke
				(width 0.1524)
				(type default)
			)
			(layer "F.SilkS")
		)
		(fp_line
			(start 0.7874 0.4064)
			(end -0.7874 0.4064)
			(stroke
				(width 0.1524)
				(type default)
			)
			(layer "F.SilkS")
		)
		(fp_line
			(start -0.7874 -0.4064)
			(end 0.7874 -0.4064)
			(stroke
				(width 0.1524)
				(type default)
			)
			(layer "F.SilkS")
		)
		(fp_line
			(start 0.7874 -0.4064)
			(end 0.7874 0.4064)
			(stroke
				(width 0.1524)
				(type default)
			)
			(layer "F.SilkS")
		)
		(fp_line
			(start -0.67945 0.3048)
			(end -0.67945 -0.305054)
			(stroke
				(width 0.1)
				(type default)
			)
			(layer "F.Fab")
		)
		(fp_line
			(start -0.12065 0.3048)
			(end -0.67945 0.3048)
			(stroke
				(width 0.1)
				(type default)
			)
			(layer "F.Fab")
		)
		(fp_line
			(start 0.120396 0.3048)
			(end 0.120396 0.2794)
			(stroke
				(width 0.1)
				(type default)
			)
			(layer "F.Fab")
		)
		(fp_line
			(start 0.67945 0.3048)
			(end 0.120396 0.3048)
			(stroke
				(width 0.1)
				(type default)
			)
			(layer "F.Fab")
		)
		(fp_line
			(start -0.12065 0.2794)
			(end -0.12065 0.3048)
			(stroke
				(width 0.1)
				(type default)
			)
			(layer "F.Fab")
		)
		(fp_line
			(start 0.120396 0.2794)
			(end -0.12065 0.2794)
			(stroke
				(width 0.1)
				(type default)
			)
			(layer "F.Fab")
		)
		(fp_line
			(start -0.12065 -0.2794)
			(end 0.12065 -0.2794)
			(stroke
				(width 0.1)
				(type default)
			)
			(layer "F.Fab")
		)
		(fp_line
			(start 0.12065 -0.2794)
			(end 0.12065 -0.3048)
			(stroke
				(width 0.1)
				(type default)
			)
			(layer "F.Fab")
		)
		(fp_line
			(start 0.12065 -0.3048)
			(end 0.67945 -0.3048)
			(stroke
				(width 0.1)
				(type default)
			)
			(layer "F.Fab")
		)
		(fp_line
			(start 0.67945 -0.3048)
			(end 0.67945 0.3048)
			(stroke
				(width 0.1)
				(type default)
			)
			(layer "F.Fab")
		)
		(fp_line
			(start -0.67945 -0.305054)
			(end -0.12065 -0.305054)
			(stroke
				(width 0.1)
				(type default)
			)
			(layer "F.Fab")
		)
		(fp_line
			(start -0.12065 -0.305054)
			(end -0.12065 -0.2794)
			(stroke
				(width 0.1)
				(type default)
			)
			(layer "F.Fab")
		)
		(pad "1" smd circle
			(at -0.40005 0 270)
			(size 0 0)
			(layers "F.Cu" "F.Mask" "F.Paste")
			(net "HSC_OC_VOL")
		)
		(pad "2" smd circle
			(at 0.40005 0 270)
			(size 0 0)
			(layers "F.Cu" "F.Mask" "F.Paste")
			(net "GND")
		)
	)
	(footprint ""
		(layer "F.Cu")
		(at 68.212462 -39.421562)
		(property "Reference" "R3609"
			(at 0 0 0)
			(layer "F.SilkS")
			(hide yes)
			(effects
				(font
					(size 1.27 1.27)
				)
			)
		)
		(property "Value" ""
			(at 0 0 0)
			(layer "F.Fab")
			(effects
				(font
					(size 1.27 1.27)
				)
			)
		)
		(duplicate_pad_numbers_are_jumpers no)
		(fp_line
			(start -0.7874 -0.4064)
			(end 0.7874 -0.4064)
			(stroke
				(width 0.1524)
				(type default)
			)
			(layer "F.SilkS")
		)
		(fp_line
			(start -0.7874 0.4064)
			(end -0.7874 -0.4064)
			(stroke
				(width 0.1524)
				(type default)
			)
			(layer "F.SilkS")
		)
		(fp_line
			(start 0.7874 -0.4064)
			(end 0.7874 0.4064)
			(stroke
				(width 0.1524)
				(type default)
			)
			(layer "F.SilkS")
		)
		(fp_line
			(start 0.7874 0.4064)
			(end -0.7874 0.4064)
			(stroke
				(width 0.1524)
				(type default)
			)
			(layer "F.SilkS")
		)
		(fp_line
			(start -0.67945 -0.305054)
			(end -0.12065 -0.305054)
			(stroke
				(width 0.1)
				(type default)
			)
			(layer "F.Fab")
		)
		(fp_line
			(start -0.67945 0.3048)
			(end -0.67945 -0.305054)
			(stroke
				(width 0.1)
				(type default)
			)
			(layer "F.Fab")
		)
		(fp_line
			(start -0.12065 -0.305054)
			(end -0.12065 -0.2794)
			(stroke
				(width 0.1)
				(type default)
			)
			(layer "F.Fab")
		)
		(fp_line
			(start -0.12065 -0.2794)
			(end 0.12065 -0.2794)
			(stroke
				(width 0.1)
				(type default)
			)
			(layer "F.Fab")
		)
		(fp_line
			(start -0.12065 0.2794)
			(end -0.12065 0.3048)
			(stroke
				(width 0.1)
				(type default)
			)
			(layer "F.Fab")
		)
		(fp_line
			(start -0.12065 0.3048)
			(end -0.67945 0.3048)
			(stroke
				(width 0.1)
				(type default)
			)
			(layer "F.Fab")
		)
		(fp_line
			(start 0.120396 0.2794)
			(end -0.12065 0.2794)
			(stroke
				(width 0.1)
				(type default)
			)
			(layer "F.Fab")
		)
		(fp_line
			(start 0.120396 0.3048)
			(end 0.120396 0.2794)
			(stroke
				(width 0.1)
				(type default)
			)
			(layer "F.Fab")
		)
		(fp_line
			(start 0.12065 -0.3048)
			(end 0.67945 -0.3048)
			(stroke
				(width 0.1)
				(type default)
			)
			(layer "F.Fab")
		)
		(fp_line
			(start 0.12065 -0.2794)
			(end 0.12065 -0.3048)
			(stroke
				(width 0.1)
				(type default)
			)
			(layer "F.Fab")
		)
		(fp_line
			(start 0.67945 -0.3048)
			(end 0.67945 0.3048)
			(stroke
				(width 0.1)
				(type default)
			)
			(layer "F.Fab")
		)
		(fp_line
			(start 0.67945 0.3048)
			(end 0.120396 0.3048)
			(stroke
				(width 0.1)
				(type default)
			)
			(layer "F.Fab")
		)
		(pad "1" smd circle
			(at -0.40005 0)
			(size 0 0)
			(layers "F.Cu" "F.Mask" "F.Paste")
			(net "GND")
		)
		(pad "2" smd circle
			(at 0.40005 0)
			(size 0 0)
			(layers "F.Cu" "F.Mask" "F.Paste")
			(net "INA230_3_A0")
		)
	)
	(footprint ""
		(layer "F.Cu")
		(at 255.447546 -42.886122 90)
		(property "Reference" "PC2209"
			(at 0 0 90)
			(layer "F.SilkS")
			(hide yes)
			(effects
				(font
					(size 1.27 1.27)
				)
			)
		)
		(property "Value" ""
			(at 0 0 90)
			(layer "F.Fab")
			(effects
				(font
					(size 1.27 1.27)
				)
			)
		)
		(duplicate_pad_numbers_are_jumpers no)
		(fp_line
			(start 0.7874 -0.4064)
			(end 0.7874 0.4064)
			(stroke
				(width 0.1524)
				(type default)
			)
			(layer "F.SilkS")
		)
		(fp_line
			(start -0.7874 -0.4064)
			(end 0.7874 -0.4064)
			(stroke
				(width 0.1524)
				(type default)
			)
			(layer "F.SilkS")
		)
		(fp_line
			(start 0.7874 0.4064)
			(end -0.7874 0.4064)
			(stroke
				(width 0.1524)
				(type default)
			)
			(layer "F.SilkS")
		)
		(fp_line
			(start -0.7874 0.4064)
			(end -0.7874 -0.4064)
			(stroke
				(width 0.1524)
				(type default)
			)
			(layer "F.SilkS")
		)
		(fp_line
			(start -0.12065 -0.305054)
			(end -0.12065 -0.2794)
			(stroke
				(width 0.1)
				(type default)
			)
			(layer "F.Fab")
		)
		(fp_line
			(start -0.67945 -0.305054)
			(end -0.12065 -0.305054)
			(stroke
				(width 0.1)
				(type default)
			)
			(layer "F.Fab")
		)
		(fp_line
			(start 0.67945 -0.3048)
			(end 0.67945 0.3048)
			(stroke
				(width 0.1)
				(type default)
			)
			(layer "F.Fab")
		)
		(fp_line
			(start 0.12065 -0.3048)
			(end 0.67945 -0.3048)
			(stroke
				(width 0.1)
				(type default)
			)
			(layer "F.Fab")
		)
		(fp_line
			(start 0.12065 -0.2794)
			(end 0.12065 -0.3048)
			(stroke
				(width 0.1)
				(type default)
			)
			(layer "F.Fab")
		)
		(fp_line
			(start -0.12065 -0.2794)
			(end 0.12065 -0.2794)
			(stroke
				(width 0.1)
				(type default)
			)
			(layer "F.Fab")
		)
		(fp_line
			(start 0.120396 0.2794)
			(end -0.12065 0.2794)
			(stroke
				(width 0.1)
				(type default)
			)
			(layer "F.Fab")
		)
		(fp_line
			(start -0.12065 0.2794)
			(end -0.12065 0.3048)
			(stroke
				(width 0.1)
				(type default)
			)
			(layer "F.Fab")
		)
		(fp_line
			(start 0.67945 0.3048)
			(end 0.120396 0.3048)
			(stroke
				(width 0.1)
				(type default)
			)
			(layer "F.Fab")
		)
		(fp_line
			(start 0.120396 0.3048)
			(end 0.120396 0.2794)
			(stroke
				(width 0.1)
				(type default)
			)
			(layer "F.Fab")
		)
		(fp_line
			(start -0.12065 0.3048)
			(end -0.67945 0.3048)
			(stroke
				(width 0.1)
				(type default)
			)
			(layer "F.Fab")
		)
		(fp_line
			(start -0.67945 0.3048)
			(end -0.67945 -0.305054)
			(stroke
				(width 0.1)
				(type default)
			)
			(layer "F.Fab")
		)
		(pad "1" smd circle
			(at -0.40005 0 90)
			(size 0 0)
			(layers "F.Cu" "F.Mask" "F.Paste")
			(net "P12V_E1S_VCC_0")
		)
		(pad "2" smd circle
			(at 0.40005 0 90)
			(size 0 0)
			(layers "F.Cu" "F.Mask" "F.Paste")
			(net "GND")
		)
	)
	(footprint ""
		(layer "F.Cu")
		(at 416.347148 -258.091686)
		(property "Reference" "J9"
			(at -3.683 -81.702148 0)
			(unlocked yes)
			(layer "F.SilkS")
			(effects
				(font
					(size 0.7874 0.5842)
					(thickness 0.1524)
				)
				(justify left)
			)
		)
		(property "Value" ""
			(at 0 0 0)
			(layer "F.Fab")
			(effects
				(font
					(size 1.27 1.27)
				)
			)
		)
		(duplicate_pad_numbers_are_jumpers no)
		(fp_line
			(start -3.24993 -81.000092)
			(end -3.24993 75.482958)
			(stroke
				(width 0.1524)
				(type default)
			)
			(layer "F.SilkS")
		)
		(fp_line
			(start 2.983992 81.000092)
			(end 3.24993 81.000092)
			(stroke
				(width 0.1524)
				(type default)
			)
			(layer "F.SilkS")
		)
		(fp_line
			(start 3.24993 -81.000092)
			(end -3.24993 -81.000092)
			(stroke
				(width 0.1524)
				(type default)
			)
			(layer "F.SilkS")
		)
		(fp_line
			(start 3.24993 -72.00011)
			(end -3.24993 -72.00011)
			(stroke
				(width 0.1524)
				(type default)
			)
			(layer "F.SilkS")
		)
		(fp_line
			(start 3.24993 72.00011)
			(end -3.24993 72.00011)
			(stroke
				(width 0.1524)
				(type default)
			)
			(layer "F.SilkS")
		)
		(fp_line
			(start 3.24993 72.135238)
			(end 3.24993 -81.000092)
			(stroke
				(width 0.1524)
				(type default)
			)
			(layer "F.SilkS")
		)
		(fp_line
			(start 3.24993 81.000092)
			(end 3.24993 73.641458)
			(stroke
				(width 0.1524)
				(type default)
			)
			(layer "F.SilkS")
		)
		(fp_poly
			(pts
				(xy -4.372356 -63.804038) (xy -3.356356 -63.296038) (xy -4.372356 -62.788038)
			)
			(stroke
				(width 0)
				(type default)
			)
			(fill yes)
			(layer "F.SilkS")
		)
		(fp_line
			(start -3.24993 -81.000092)
			(end -3.24993 81.000092)
			(stroke
				(width 0.1)
				(type default)
			)
			(layer "F.Fab")
		)
		(fp_line
			(start -3.24993 81.000092)
			(end 3.24993 81.000092)
			(stroke
				(width 0.1)
				(type default)
			)
			(layer "F.Fab")
		)
		(fp_line
			(start 3.24993 -81.000092)
			(end -3.24993 -81.000092)
			(stroke
				(width 0.1)
				(type default)
			)
			(layer "F.Fab")
		)
		(fp_line
			(start 3.24993 -72.00011)
			(end -3.24993 -72.00011)
			(stroke
				(width 0.1)
				(type default)
			)
			(layer "F.Fab")
		)
		(fp_line
			(start 3.24993 -71.000112)
			(end -3.24993 -71.000112)
			(stroke
				(width 0.1)
				(type default)
			)
			(layer "F.Fab")
		)
		(fp_line
			(start 3.24993 71.000112)
			(end -3.24993 71.000112)
			(stroke
				(width 0.1)
				(type default)
			)
			(layer "F.Fab")
		)
		(fp_line
			(start 3.24993 72.00011)
			(end -3.24993 72.00011)
			(stroke
				(width 0.1)
				(type default)
			)
			(layer "F.Fab")
		)
		(fp_line
			(start 3.24993 81.000092)
			(end 3.24993 -81.000092)
			(stroke
				(width 0.1)
				(type default)
			)
			(layer "F.Fab")
		)
		(fp_poly
			(pts
				(xy -4.445 -63.832994) (xy -4.445 -62.816994) (xy -3.429 -63.324994)
			)
			(stroke
				(width 0)
				(type default)
			)
			(fill yes)
			(layer "F.Fab")
		)
		(pad "1" smd rect
			(at -2.050034 -63.324994 270)
			(size 0.519938 1.4986)
			(layers "F.Cu" "F.Mask" "F.Paste")
			(net "P12V_S3_AUX_CPU0_NVDIMM")
		)
		(pad "2" smd rect
			(at -2.050034 -62.47511 270)
			(size 0.519938 1.4986)
			(layers "F.Cu" "F.Mask" "F.Paste")
			(net "TP_CHE_CPU0_DIMM1_FRU_0")
		)
		(pad "3" smd rect
			(at -2.050034 -61.624972 270)
			(size 0.519938 1.4986)
			(layers "F.Cu" "F.Mask" "F.Paste")
			(net "P3V3_AUX")
		)
		(pad "4" smd rect
			(at -2.050034 -60.775088 270)
			(size 0.519938 1.4986)
			(layers "F.Cu" "F.Mask" "F.Paste")
			(net "I3C_SPD_DDREFGH_CPU0_LVC1_SCL_R")
		)
		(pad "5" smd rect
			(at -2.050034 -59.92495 270)
			(size 0.519938 1.4986)
			(layers "F.Cu" "F.Mask" "F.Paste")
			(net "I3C_SPD_DDREFGH_CPU0_LVC1_SDA")
		)
		(pad "6" smd rect
			(at -2.050034 -59.075066 270)
			(size 0.519938 1.4986)
			(layers "F.Cu" "F.Mask" "F.Paste")
			(net "GND")
		)
		(pad "7" smd rect
			(at -2.050034 -58.224928 270)
			(size 0.519938 1.4986)
			(layers "F.Cu" "F.Mask" "F.Paste")
			(net "M_E_CPU0_SA_DQ<0>")
		)
		(pad "8" smd rect
			(at -2.050034 -57.375044 270)
			(size 0.519938 1.4986)
			(layers "F.Cu" "F.Mask" "F.Paste")
			(net "GND")
		)
		(pad "9" smd rect
			(at -2.050034 -56.524906 270)
			(size 0.519938 1.4986)
			(layers "F.Cu" "F.Mask" "F.Paste")
			(net "M_E_CPU0_SA_DQ<1>")
		)
		(pad "10" smd rect
			(at -2.050034 -55.675022 270)
			(size 0.519938 1.4986)
			(layers "F.Cu" "F.Mask" "F.Paste")
			(net "GND")
		)
		(pad "11" smd rect
			(at -2.050034 -54.824884 270)
			(size 0.519938 1.4986)
			(layers "F.Cu" "F.Mask" "F.Paste")
			(net "M_E_CPU0_SA_DQS_DP<0>")
		)
		(pad "12" smd rect
			(at -2.050034 -53.975 270)
			(size 0.519938 1.4986)
			(layers "F.Cu" "F.Mask" "F.Paste")
			(net "M_E_CPU0_SA_DQS_DN<0>")
		)
		(pad "13" smd rect
			(at -2.050034 -53.125116 270)
			(size 0.519938 1.4986)
			(layers "F.Cu" "F.Mask" "F.Paste")
			(net "GND")
		)
		(pad "14" smd rect
			(at -2.050034 -52.274978 270)
			(size 0.519938 1.4986)
			(layers "F.Cu" "F.Mask" "F.Paste")
			(net "M_E_CPU0_SA_DQ<4>")
		)
		(pad "15" smd rect
			(at -2.050034 -51.425094 270)
			(size 0.519938 1.4986)
			(layers "F.Cu" "F.Mask" "F.Paste")
			(net "GND")
		)
		(pad "16" smd rect
			(at -2.050034 -50.574956 270)
			(size 0.519938 1.4986)
			(layers "F.Cu" "F.Mask" "F.Paste")
			(net "M_E_CPU0_SA_DQ<5>")
		)
		(pad "17" smd rect
			(at -2.050034 -49.725072 270)
			(size 0.519938 1.4986)
			(layers "F.Cu" "F.Mask" "F.Paste")
			(net "GND")
		)
		(pad "18" smd rect
			(at -2.050034 -48.874934 270)
			(size 0.519938 1.4986)
			(layers "F.Cu" "F.Mask" "F.Paste")
			(net "M_E_CPU0_SA_DQ<8>")
		)
		(pad "19" smd rect
			(at -2.050034 -48.02505 270)
			(size 0.519938 1.4986)
			(layers "F.Cu" "F.Mask" "F.Paste")
			(net "GND")
		)
		(pad "20" smd rect
			(at -2.050034 -47.174912 270)
			(size 0.519938 1.4986)
			(layers "F.Cu" "F.Mask" "F.Paste")
			(net "M_E_CPU0_SA_DQ<9>")
		)
		(pad "21" smd rect
			(at -2.050034 -46.325028 270)
			(size 0.519938 1.4986)
			(layers "F.Cu" "F.Mask" "F.Paste")
			(net "GND")
		)
		(pad "22" smd rect
			(at -2.050034 -45.47489 270)
			(size 0.519938 1.4986)
			(layers "F.Cu" "F.Mask" "F.Paste")
			(net "M_E_CPU0_SA_DQS_DP<1>")
		)
		(pad "23" smd rect
			(at -2.050034 -44.625006 270)
			(size 0.519938 1.4986)
			(layers "F.Cu" "F.Mask" "F.Paste")
			(net "M_E_CPU0_SA_DQS_DN<1>")
		)
		(pad "24" smd rect
			(at -2.050034 -43.775122 270)
			(size 0.519938 1.4986)
			(layers "F.Cu" "F.Mask" "F.Paste")
			(net "GND")
		)
		(pad "25" smd rect
			(at -2.050034 -42.924984 270)
			(size 0.519938 1.4986)
			(layers "F.Cu" "F.Mask" "F.Paste")
			(net "M_E_CPU0_SA_DQ<12>")
		)
		(pad "26" smd rect
			(at -2.050034 -42.0751 270)
			(size 0.519938 1.4986)
			(layers "F.Cu" "F.Mask" "F.Paste")
			(net "GND")
		)
		(pad "27" smd rect
			(at -2.050034 -41.224962 270)
			(size 0.519938 1.4986)
			(layers "F.Cu" "F.Mask" "F.Paste")
			(net "M_E_CPU0_SA_DQ<13>")
		)
		(pad "28" smd rect
			(at -2.050034 -40.375078 270)
			(size 0.519938 1.4986)
			(layers "F.Cu" "F.Mask" "F.Paste")
			(net "GND")
		)
		(pad "29" smd rect
			(at -2.050034 -39.52494 270)
			(size 0.519938 1.4986)
			(layers "F.Cu" "F.Mask" "F.Paste")
			(net "M_E_CPU0_SA_DQ<16>")
		)
		(pad "30" smd rect
			(at -2.050034 -38.675056 270)
			(size 0.519938 1.4986)
			(layers "F.Cu" "F.Mask" "F.Paste")
			(net "GND")
		)
		(pad "31" smd rect
			(at -2.050034 -37.824918 270)
			(size 0.519938 1.4986)
			(layers "F.Cu" "F.Mask" "F.Paste")
			(net "M_E_CPU0_SA_DQ<17>")
		)
		(pad "32" smd rect
			(at -2.050034 -36.975034 270)
			(size 0.519938 1.4986)
			(layers "F.Cu" "F.Mask" "F.Paste")
			(net "GND")
		)
		(pad "33" smd rect
			(at -2.050034 -36.124896 270)
			(size 0.519938 1.4986)
			(layers "F.Cu" "F.Mask" "F.Paste")
			(net "M_E_CPU0_SA_DQS_DP<2>")
		)
		(pad "34" smd rect
			(at -2.050034 -35.275012 270)
			(size 0.519938 1.4986)
			(layers "F.Cu" "F.Mask" "F.Paste")
			(net "M_E_CPU0_SA_DQS_DN<2>")
		)
		(pad "35" smd rect
			(at -2.050034 -34.425128 270)
			(size 0.519938 1.4986)
			(layers "F.Cu" "F.Mask" "F.Paste")
			(net "GND")
		)
		(pad "36" smd rect
			(at -2.050034 -33.57499 270)
			(size 0.519938 1.4986)
			(layers "F.Cu" "F.Mask" "F.Paste")
			(net "M_E_CPU0_SA_DQ<20>")
		)
		(pad "37" smd rect
			(at -2.050034 -32.725106 270)
			(size 0.519938 1.4986)
			(layers "F.Cu" "F.Mask" "F.Paste")
			(net "GND")
		)
		(pad "38" smd rect
			(at -2.050034 -31.874968 270)
			(size 0.519938 1.4986)
			(layers "F.Cu" "F.Mask" "F.Paste")
			(net "M_E_CPU0_SA_DQ<21>")
		)
		(pad "39" smd rect
			(at -2.050034 -31.025084 270)
			(size 0.519938 1.4986)
			(layers "F.Cu" "F.Mask" "F.Paste")
			(net "GND")
		)
		(pad "40" smd rect
			(at -2.050034 -30.174946 270)
			(size 0.519938 1.4986)
			(layers "F.Cu" "F.Mask" "F.Paste")
			(net "M_E_CPU0_SA_DQ<24>")
		)
		(pad "41" smd rect
			(at -2.050034 -29.325062 270)
			(size 0.519938 1.4986)
			(layers "F.Cu" "F.Mask" "F.Paste")
			(net "GND")
		)
		(pad "42" smd rect
			(at -2.050034 -28.474924 270)
			(size 0.519938 1.4986)
			(layers "F.Cu" "F.Mask" "F.Paste")
			(net "M_E_CPU0_SA_DQ<25>")
		)
		(pad "43" smd rect
			(at -2.050034 -27.62504 270)
			(size 0.519938 1.4986)
			(layers "F.Cu" "F.Mask" "F.Paste")
			(net "GND")
		)
		(pad "44" smd rect
			(at -2.050034 -26.774902 270)
			(size 0.519938 1.4986)
			(layers "F.Cu" "F.Mask" "F.Paste")
			(net "M_E_CPU0_SA_DQS_DP<3>")
		)
		(pad "45" smd rect
			(at -2.050034 -25.925018 270)
			(size 0.519938 1.4986)
			(layers "F.Cu" "F.Mask" "F.Paste")
			(net "M_E_CPU0_SA_DQS_DN<3>")
		)
		(pad "46" smd rect
			(at -2.050034 -25.07488 270)
			(size 0.519938 1.4986)
			(layers "F.Cu" "F.Mask" "F.Paste")
			(net "GND")
		)
		(pad "47" smd rect
			(at -2.050034 -24.224996 270)
			(size 0.519938 1.4986)
			(layers "F.Cu" "F.Mask" "F.Paste")
			(net "M_E_CPU0_SA_DQ<28>")
		)
		(pad "48" smd rect
			(at -2.050034 -23.375112 270)
			(size 0.519938 1.4986)
			(layers "F.Cu" "F.Mask" "F.Paste")
			(net "GND")
		)
		(pad "49" smd rect
			(at -2.050034 -22.524974 270)
			(size 0.519938 1.4986)
			(layers "F.Cu" "F.Mask" "F.Paste")
			(net "M_E_CPU0_SA_DQ<29>")
		)
		(pad "50" smd rect
			(at -2.050034 -21.67509 270)
			(size 0.519938 1.4986)
			(layers "F.Cu" "F.Mask" "F.Paste")
			(net "GND")
		)
		(pad "51" smd rect
			(at -2.050034 -20.824952 270)
			(size 0.519938 1.4986)
			(layers "F.Cu" "F.Mask" "F.Paste")
			(net "M_E_CPU0_SA_CB<0>")
		)
		(pad "52" smd rect
			(at -2.050034 -19.975068 270)
			(size 0.519938 1.4986)
			(layers "F.Cu" "F.Mask" "F.Paste")
			(net "GND")
		)
		(pad "53" smd rect
			(at -2.050034 -19.12493 270)
			(size 0.519938 1.4986)
			(layers "F.Cu" "F.Mask" "F.Paste")
			(net "M_E_CPU0_SA_CB<1>")
		)
		(pad "54" smd rect
			(at -2.050034 -18.275046 270)
			(size 0.519938 1.4986)
			(layers "F.Cu" "F.Mask" "F.Paste")
			(net "GND")
		)
		(pad "55" smd rect
			(at -2.050034 -17.424908 270)
			(size 0.519938 1.4986)
			(layers "F.Cu" "F.Mask" "F.Paste")
			(net "M_E_CPU0_SA_DQS_DP<4>")
		)
		(pad "56" smd rect
			(at -2.050034 -16.575024 270)
			(size 0.519938 1.4986)
			(layers "F.Cu" "F.Mask" "F.Paste")
			(net "M_E_CPU0_SA_DQS_DN<4>")
		)
		(pad "57" smd rect
			(at -2.050034 -15.724886 270)
			(size 0.519938 1.4986)
			(layers "F.Cu" "F.Mask" "F.Paste")
			(net "GND")
		)
		(pad "58" smd rect
			(at -2.050034 -14.875002 270)
			(size 0.519938 1.4986)
			(layers "F.Cu" "F.Mask" "F.Paste")
			(net "M_E_CPU0_SA_CB<4>")
		)
		(pad "59" smd rect
			(at -2.050034 -14.025118 270)
			(size 0.519938 1.4986)
			(layers "F.Cu" "F.Mask" "F.Paste")
			(net "GND")
		)
		(pad "60" smd rect
			(at -2.050034 -13.17498 270)
			(size 0.519938 1.4986)
			(layers "F.Cu" "F.Mask" "F.Paste")
			(net "M_E_CPU0_SA_CB<5>")
		)
		(pad "61" smd rect
			(at -2.050034 -12.325096 270)
			(size 0.519938 1.4986)
			(layers "F.Cu" "F.Mask" "F.Paste")
			(net "GND")
		)
		(pad "62" smd rect
			(at -2.050034 -11.474958 270)
			(size 0.519938 1.4986)
			(layers "F.Cu" "F.Mask" "F.Paste")
			(net "M_E_CPU0_ALERT_N")
		)
		(pad "63" smd rect
			(at -2.050034 -10.625074 270)
			(size 0.519938 1.4986)
			(layers "F.Cu" "F.Mask" "F.Paste")
			(net "GND")
		)
		(pad "64" smd rect
			(at -2.050034 -9.774936 270)
			(size 0.519938 1.4986)
			(layers "F.Cu" "F.Mask" "F.Paste")
			(net "M_E_CPU0_SA_CS_N<0>")
		)
		(pad "65" smd rect
			(at -2.050034 -8.925052 270)
			(size 0.519938 1.4986)
			(layers "F.Cu" "F.Mask" "F.Paste")
			(net "GND")
		)
		(pad "66" smd rect
			(at -2.050034 -8.074914 270)
			(size 0.519938 1.4986)
			(layers "F.Cu" "F.Mask" "F.Paste")
			(net "M_E_CPU0_SA_CA<0>")
		)
		(pad "67" smd rect
			(at -2.050034 -7.22503 270)
			(size 0.519938 1.4986)
			(layers "F.Cu" "F.Mask" "F.Paste")
			(net "GND")
		)
		(pad "68" smd rect
			(at -2.050034 -6.374892 270)
			(size 0.519938 1.4986)
			(layers "F.Cu" "F.Mask" "F.Paste")
			(net "M_E_CPU0_SA_CA<2>")
		)
		(pad "69" smd rect
			(at -2.050034 -5.525008 270)
			(size 0.519938 1.4986)
			(layers "F.Cu" "F.Mask" "F.Paste")
			(net "GND")
		)
		(pad "70" smd rect
			(at -2.050034 -4.675124 270)
			(size 0.519938 1.4986)
			(layers "F.Cu" "F.Mask" "F.Paste")
			(net "M_E_CPU0_SA_CA<4>")
		)
		(pad "71" smd rect
			(at -2.050034 -3.824986 270)
			(size 0.519938 1.4986)
			(layers "F.Cu" "F.Mask" "F.Paste")
			(net "GND")
		)
		(pad "72" smd rect
			(at -2.050034 -2.975102 270)
			(size 0.519938 1.4986)
			(layers "F.Cu" "F.Mask" "F.Paste")
			(net "M_E_CPU0_SA_CA<6>")
		)
		(pad "73" smd rect
			(at -2.050034 -2.124964 270)
			(size 0.519938 1.4986)
			(layers "F.Cu" "F.Mask" "F.Paste")
			(net "GND")
		)
		(pad "74" smd rect
			(at -2.050034 -1.27508 270)
			(size 0.519938 1.4986)
			(layers "F.Cu" "F.Mask" "F.Paste")
			(net "M_E_CPU0_SA_PAR")
		)
		(pad "75" smd rect
			(at -2.050034 -0.424942 270)
			(size 0.519938 1.4986)
			(layers "F.Cu" "F.Mask" "F.Paste")
			(net "GND")
		)
		(pad "76" smd rect
			(at -2.050034 5.525008 270)
			(size 0.519938 1.4986)
			(layers "F.Cu" "F.Mask" "F.Paste")
			(net "M_E_CPU0_SB_CA<0>")
		)
		(pad "77" smd rect
			(at -2.050034 6.374892 270)
			(size 0.519938 1.4986)
			(layers "F.Cu" "F.Mask" "F.Paste")
			(net "GND")
		)
		(pad "78" smd rect
			(at -2.050034 7.22503 270)
			(size 0.519938 1.4986)
			(layers "F.Cu" "F.Mask" "F.Paste")
			(net "M_E_CPU0_SB_CA<2>")
		)
		(pad "79" smd rect
			(at -2.050034 8.074914 270)
			(size 0.519938 1.4986)
			(layers "F.Cu" "F.Mask" "F.Paste")
			(net "GND")
		)
		(pad "80" smd rect
			(at -2.050034 8.925052 270)
			(size 0.519938 1.4986)
			(layers "F.Cu" "F.Mask" "F.Paste")
			(net "M_E_CPU0_SB_CA<4>")
		)
		(pad "81" smd rect
			(at -2.050034 9.774936 270)
			(size 0.519938 1.4986)
			(layers "F.Cu" "F.Mask" "F.Paste")
			(net "GND")
		)
		(pad "82" smd rect
			(at -2.050034 10.625074 270)
			(size 0.519938 1.4986)
			(layers "F.Cu" "F.Mask" "F.Paste")
			(net "M_E_CPU0_SB_CA<6>")
		)
		(pad "83" smd rect
			(at -2.050034 11.474958 270)
			(size 0.519938 1.4986)
			(layers "F.Cu" "F.Mask" "F.Paste")
			(net "GND")
		)
		(pad "84" smd rect
			(at -2.050034 12.325096 270)
			(size 0.519938 1.4986)
			(layers "F.Cu" "F.Mask" "F.Paste")
			(net "M_E_CPU0_SB_CS_N<0>")
		)
		(pad "85" smd rect
			(at -2.050034 13.17498 270)
			(size 0.519938 1.4986)
			(layers "F.Cu" "F.Mask" "F.Paste")
			(net "GND")
		)
		(pad "86" smd rect
			(at -2.050034 14.025118 270)
			(size 0.519938 1.4986)
			(layers "F.Cu" "F.Mask" "F.Paste")
			(net "M_E_CPU0_SA_RSP<0>")
		)
		(pad "87" smd rect
			(at -2.050034 14.875002 270)
			(size 0.519938 1.4986)
			(layers "F.Cu" "F.Mask" "F.Paste")
			(net "M_E_CPU0_SB_RSP<0>")
		)
		(pad "88" smd rect
			(at -2.050034 15.724886 270)
			(size 0.519938 1.4986)
			(layers "F.Cu" "F.Mask" "F.Paste")
			(net "GND")
		)
		(pad "89" smd rect
			(at -2.050034 16.575024 270)
			(size 0.519938 1.4986)
			(layers "F.Cu" "F.Mask" "F.Paste")
			(net "M_E_CPU0_SB_CB<4>")
		)
		(pad "90" smd rect
			(at -2.050034 17.424908 270)
			(size 0.519938 1.4986)
			(layers "F.Cu" "F.Mask" "F.Paste")
			(net "GND")
		)
		(pad "91" smd rect
			(at -2.050034 18.275046 270)
			(size 0.519938 1.4986)
			(layers "F.Cu" "F.Mask" "F.Paste")
			(net "M_E_CPU0_SB_CB<5>")
		)
		(pad "92" smd rect
			(at -2.050034 19.12493 270)
			(size 0.519938 1.4986)
			(layers "F.Cu" "F.Mask" "F.Paste")
			(net "GND")
		)
		(pad "93" smd rect
			(at -2.050034 19.975068 270)
			(size 0.519938 1.4986)
			(layers "F.Cu" "F.Mask" "F.Paste")
			(net "M_E_CPU0_SB_DQS_DP<9>")
		)
		(pad "94" smd rect
			(at -2.050034 20.824952 270)
			(size 0.519938 1.4986)
			(layers "F.Cu" "F.Mask" "F.Paste")
			(net "M_E_CPU0_SB_DQS_DN<9>")
		)
		(pad "95" smd rect
			(at -2.050034 21.67509 270)
			(size 0.519938 1.4986)
			(layers "F.Cu" "F.Mask" "F.Paste")
			(net "GND")
		)
		(pad "96" smd rect
			(at -2.050034 22.524974 270)
			(size 0.519938 1.4986)
			(layers "F.Cu" "F.Mask" "F.Paste")
			(net "M_E_CPU0_SB_CB<0>")
		)
		(pad "97" smd rect
			(at -2.050034 23.375112 270)
			(size 0.519938 1.4986)
			(layers "F.Cu" "F.Mask" "F.Paste")
			(net "GND")
		)
		(pad "98" smd rect
			(at -2.050034 24.224996 270)
			(size 0.519938 1.4986)
			(layers "F.Cu" "F.Mask" "F.Paste")
			(net "M_E_CPU0_SB_CB<1>")
		)
		(pad "99" smd rect
			(at -2.050034 25.07488 270)
			(size 0.519938 1.4986)
			(layers "F.Cu" "F.Mask" "F.Paste")
			(net "GND")
		)
		(pad "100" smd rect
			(at -2.050034 25.925018 270)
			(size 0.519938 1.4986)
			(layers "F.Cu" "F.Mask" "F.Paste")
			(net "M_E_CPU0_SB_DQ<0>")
		)
		(pad "101" smd rect
			(at -2.050034 26.774902 270)
			(size 0.519938 1.4986)
			(layers "F.Cu" "F.Mask" "F.Paste")
			(net "GND")
		)
		(pad "102" smd rect
			(at -2.050034 27.62504 270)
			(size 0.519938 1.4986)
			(layers "F.Cu" "F.Mask" "F.Paste")
			(net "M_E_CPU0_SB_DQ<1>")
		)
		(pad "103" smd rect
			(at -2.050034 28.474924 270)
			(size 0.519938 1.4986)
			(layers "F.Cu" "F.Mask" "F.Paste")
			(net "GND")
		)
		(pad "104" smd rect
			(at -2.050034 29.325062 270)
			(size 0.519938 1.4986)
			(layers "F.Cu" "F.Mask" "F.Paste")
			(net "M_E_CPU0_SB_DQS_DP<0>")
		)
		(pad "105" smd rect
			(at -2.050034 30.174946 270)
			(size 0.519938 1.4986)
			(layers "F.Cu" "F.Mask" "F.Paste")
			(net "M_E_CPU0_SB_DQS_DN<0>")
		)
		(pad "106" smd rect
			(at -2.050034 31.025084 270)
			(size 0.519938 1.4986)
			(layers "F.Cu" "F.Mask" "F.Paste")
			(net "GND")
		)
		(pad "107" smd rect
			(at -2.050034 31.874968 270)
			(size 0.519938 1.4986)
			(layers "F.Cu" "F.Mask" "F.Paste")
			(net "M_E_CPU0_SB_DQ<4>")
		)
		(pad "108" smd rect
			(at -2.050034 32.725106 270)
			(size 0.519938 1.4986)
			(layers "F.Cu" "F.Mask" "F.Paste")
			(net "GND")
		)
		(pad "109" smd rect
			(at -2.050034 33.57499 270)
			(size 0.519938 1.4986)
			(layers "F.Cu" "F.Mask" "F.Paste")
			(net "M_E_CPU0_SB_DQ<5>")
		)
		(pad "110" smd rect
			(at -2.050034 34.425128 270)
			(size 0.519938 1.4986)
			(layers "F.Cu" "F.Mask" "F.Paste")
			(net "GND")
		)
		(pad "111" smd rect
			(at -2.050034 35.275012 270)
			(size 0.519938 1.4986)
			(layers "F.Cu" "F.Mask" "F.Paste")
			(net "M_E_CPU0_SB_DQ<8>")
		)
		(pad "112" smd rect
			(at -2.050034 36.124896 270)
			(size 0.519938 1.4986)
			(layers "F.Cu" "F.Mask" "F.Paste")
			(net "GND")
		)
		(pad "113" smd rect
			(at -2.050034 36.975034 270)
			(size 0.519938 1.4986)
			(layers "F.Cu" "F.Mask" "F.Paste")
			(net "M_E_CPU0_SB_DQ<9>")
		)
		(pad "114" smd rect
			(at -2.050034 37.824918 270)
			(size 0.519938 1.4986)
			(layers "F.Cu" "F.Mask" "F.Paste")
			(net "GND")
		)
		(pad "115" smd rect
			(at -2.050034 38.675056 270)
			(size 0.519938 1.4986)
			(layers "F.Cu" "F.Mask" "F.Paste")
			(net "M_E_CPU0_SB_DQS_DP<1>")
		)
		(pad "116" smd rect
			(at -2.050034 39.52494 270)
			(size 0.519938 1.4986)
			(layers "F.Cu" "F.Mask" "F.Paste")
			(net "M_E_CPU0_SB_DQS_DN<1>")
		)
		(pad "117" smd rect
			(at -2.050034 40.375078 270)
			(size 0.519938 1.4986)
			(layers "F.Cu" "F.Mask" "F.Paste")
			(net "GND")
		)
		(pad "118" smd rect
			(at -2.050034 41.224962 270)
			(size 0.519938 1.4986)
			(layers "F.Cu" "F.Mask" "F.Paste")
			(net "M_E_CPU0_SB_DQ<12>")
		)
		(pad "119" smd rect
			(at -2.050034 42.0751 270)
			(size 0.519938 1.4986)
			(layers "F.Cu" "F.Mask" "F.Paste")
			(net "GND")
		)
		(pad "120" smd rect
			(at -2.050034 42.924984 270)
			(size 0.519938 1.4986)
			(layers "F.Cu" "F.Mask" "F.Paste")
			(net "M_E_CPU0_SB_DQ<13>")
		)
		(pad "121" smd rect
			(at -2.050034 43.775122 270)
			(size 0.519938 1.4986)
			(layers "F.Cu" "F.Mask" "F.Paste")
			(net "GND")
		)
		(pad "122" smd rect
			(at -2.050034 44.625006 270)
			(size 0.519938 1.4986)
			(layers "F.Cu" "F.Mask" "F.Paste")
			(net "M_E_CPU0_SB_DQ<16>")
		)
		(pad "123" smd rect
			(at -2.050034 45.47489 270)
			(size 0.519938 1.4986)
			(layers "F.Cu" "F.Mask" "F.Paste")
			(net "GND")
		)
		(pad "124" smd rect
			(at -2.050034 46.325028 270)
			(size 0.519938 1.4986)
			(layers "F.Cu" "F.Mask" "F.Paste")
			(net "M_E_CPU0_SB_DQ<17>")
		)
		(pad "125" smd rect
			(at -2.050034 47.174912 270)
			(size 0.519938 1.4986)
			(layers "F.Cu" "F.Mask" "F.Paste")
			(net "GND")
		)
		(pad "126" smd rect
			(at -2.050034 48.02505 270)
			(size 0.519938 1.4986)
			(layers "F.Cu" "F.Mask" "F.Paste")
			(net "M_E_CPU0_SB_DQS_DP<2>")
		)
		(pad "127" smd rect
			(at -2.050034 48.874934 270)
			(size 0.519938 1.4986)
			(layers "F.Cu" "F.Mask" "F.Paste")
			(net "M_E_CPU0_SB_DQS_DN<2>")
		)
		(pad "128" smd rect
			(at -2.050034 49.725072 270)
			(size 0.519938 1.4986)
			(layers "F.Cu" "F.Mask" "F.Paste")
			(net "GND")
		)
		(pad "129" smd rect
			(at -2.050034 50.574956 270)
			(size 0.519938 1.4986)
			(layers "F.Cu" "F.Mask" "F.Paste")
			(net "M_E_CPU0_SB_DQ<20>")
		)
		(pad "130" smd rect
			(at -2.050034 51.425094 270)
			(size 0.519938 1.4986)
			(layers "F.Cu" "F.Mask" "F.Paste")
			(net "GND")
		)
		(pad "131" smd rect
			(at -2.050034 52.274978 270)
			(size 0.519938 1.4986)
			(layers "F.Cu" "F.Mask" "F.Paste")
			(net "M_E_CPU0_SB_DQ<21>")
		)
		(pad "132" smd rect
			(at -2.050034 53.125116 270)
			(size 0.519938 1.4986)
			(layers "F.Cu" "F.Mask" "F.Paste")
			(net "GND")
		)
		(pad "133" smd rect
			(at -2.050034 53.975 270)
			(size 0.519938 1.4986)
			(layers "F.Cu" "F.Mask" "F.Paste")
			(net "M_E_CPU0_SB_DQ<24>")
		)
		(pad "134" smd rect
			(at -2.050034 54.824884 270)
			(size 0.519938 1.4986)
			(layers "F.Cu" "F.Mask" "F.Paste")
			(net "GND")
		)
		(pad "135" smd rect
			(at -2.050034 55.675022 270)
			(size 0.519938 1.4986)
			(layers "F.Cu" "F.Mask" "F.Paste")
			(net "M_E_CPU0_SB_DQ<25>")
		)
		(pad "136" smd rect
			(at -2.050034 56.524906 270)
			(size 0.519938 1.4986)
			(layers "F.Cu" "F.Mask" "F.Paste")
			(net "GND")
		)
		(pad "137" smd rect
			(at -2.050034 57.375044 270)
			(size 0.519938 1.4986)
			(layers "F.Cu" "F.Mask" "F.Paste")
			(net "M_E_CPU0_SB_DQS_DP<3>")
		)
		(pad "138" smd rect
			(at -2.050034 58.224928 270)
			(size 0.519938 1.4986)
			(layers "F.Cu" "F.Mask" "F.Paste")
			(net "M_E_CPU0_SB_DQS_DN<3>")
		)
		(pad "139" smd rect
			(at -2.050034 59.075066 270)
			(size 0.519938 1.4986)
			(layers "F.Cu" "F.Mask" "F.Paste")
			(net "GND")
		)
		(pad "140" smd rect
			(at -2.050034 59.92495 270)
			(size 0.519938 1.4986)
			(layers "F.Cu" "F.Mask" "F.Paste")
			(net "M_E_CPU0_SB_DQ<28>")
		)
		(pad "141" smd rect
			(at -2.050034 60.775088 270)
			(size 0.519938 1.4986)
			(layers "F.Cu" "F.Mask" "F.Paste")
			(net "GND")
		)
		(pad "142" smd rect
			(at -2.050034 61.624972 270)
			(size 0.519938 1.4986)
			(layers "F.Cu" "F.Mask" "F.Paste")
			(net "M_E_CPU0_SB_DQ<29>")
		)
		(pad "143" smd rect
			(at -2.050034 62.47511 270)
			(size 0.519938 1.4986)
			(layers "F.Cu" "F.Mask" "F.Paste")
			(net "GND")
		)
		(pad "144" smd rect
			(at -2.050034 63.324994 270)
			(size 0.519938 1.4986)
			(layers "F.Cu" "F.Mask" "F.Paste")
			(net "TP_CHE_CPU0_DIMM1_FRU_1")
		)
		(pad "145" smd rect
			(at 2.050034 -63.324994 270)
			(size 0.519938 1.4986)
			(layers "F.Cu" "F.Mask" "F.Paste")
			(net "P12V_S3_AUX_CPU0_NVDIMM")
		)
		(pad "146" smd rect
			(at 2.050034 -62.47511 270)
			(size 0.519938 1.4986)
			(layers "F.Cu" "F.Mask" "F.Paste")
			(net "P12V_S3_AUX_CPU0_NVDIMM")
		)
		(pad "147" smd rect
			(at 2.050034 -61.624972 270)
			(size 0.519938 1.4986)
			(layers "F.Cu" "F.Mask" "F.Paste")
			(net "PWRGD_CHE_CPU0_DIMM1")
		)
		(pad "148" smd rect
			(at 2.050034 -60.775088 270)
			(size 0.519938 1.4986)
			(layers "F.Cu" "F.Mask" "F.Paste")
			(net "PD_CHE_CPU0_DIMM1_SAA")
		)
		(pad "149" smd rect
			(at 2.050034 -59.92495 270)
			(size 0.519938 1.4986)
			(layers "F.Cu" "F.Mask" "F.Paste")
			(net "TP_CHE_CPU0_DIMM1_FRU_2")
		)
		(pad "150" smd rect
			(at 2.050034 -59.075066 270)
			(size 0.519938 1.4986)
			(layers "F.Cu" "F.Mask" "F.Paste")
			(net "TP_CHE_CPU0_DIMM1_FRU_3")
		)
		(pad "151" smd rect
			(at 2.050034 -58.224928 270)
			(size 0.519938 1.4986)
			(layers "F.Cu" "F.Mask" "F.Paste")
			(net "GND")
		)
		(pad "152" smd rect
			(at 2.050034 -57.375044 270)
			(size 0.519938 1.4986)
			(layers "F.Cu" "F.Mask" "F.Paste")
			(net "M_E_CPU0_SA_DQ<2>")
		)
		(pad "153" smd rect
			(at 2.050034 -56.524906 270)
			(size 0.519938 1.4986)
			(layers "F.Cu" "F.Mask" "F.Paste")
			(net "GND")
		)
		(pad "154" smd rect
			(at 2.050034 -55.675022 270)
			(size 0.519938 1.4986)
			(layers "F.Cu" "F.Mask" "F.Paste")
			(net "M_E_CPU0_SA_DQ<3>")
		)
		(pad "155" smd rect
			(at 2.050034 -54.824884 270)
			(size 0.519938 1.4986)
			(layers "F.Cu" "F.Mask" "F.Paste")
			(net "GND")
		)
		(pad "156" smd rect
			(at 2.050034 -53.975 270)
			(size 0.519938 1.4986)
			(layers "F.Cu" "F.Mask" "F.Paste")
			(net "M_E_CPU0_SA_DQS_DN<5>")
		)
		(pad "157" smd rect
			(at 2.050034 -53.125116 270)
			(size 0.519938 1.4986)
			(layers "F.Cu" "F.Mask" "F.Paste")
			(net "M_E_CPU0_SA_DQS_DP<5>")
		)
		(pad "158" smd rect
			(at 2.050034 -52.274978 270)
			(size 0.519938 1.4986)
			(layers "F.Cu" "F.Mask" "F.Paste")
			(net "GND")
		)
		(pad "159" smd rect
			(at 2.050034 -51.425094 270)
			(size 0.519938 1.4986)
			(layers "F.Cu" "F.Mask" "F.Paste")
			(net "M_E_CPU0_SA_DQ<6>")
		)
		(pad "160" smd rect
			(at 2.050034 -50.574956 270)
			(size 0.519938 1.4986)
			(layers "F.Cu" "F.Mask" "F.Paste")
			(net "GND")
		)
		(pad "161" smd rect
			(at 2.050034 -49.725072 270)
			(size 0.519938 1.4986)
			(layers "F.Cu" "F.Mask" "F.Paste")
			(net "M_E_CPU0_SA_DQ<7>")
		)
		(pad "162" smd rect
			(at 2.050034 -48.874934 270)
			(size 0.519938 1.4986)
			(layers "F.Cu" "F.Mask" "F.Paste")
			(net "GND")
		)
		(pad "163" smd rect
			(at 2.050034 -48.02505 270)
			(size 0.519938 1.4986)
			(layers "F.Cu" "F.Mask" "F.Paste")
			(net "M_E_CPU0_SA_DQ<10>")
		)
		(pad "164" smd rect
			(at 2.050034 -47.174912 270)
			(size 0.519938 1.4986)
			(layers "F.Cu" "F.Mask" "F.Paste")
			(net "GND")
		)
		(pad "165" smd rect
			(at 2.050034 -46.325028 270)
			(size 0.519938 1.4986)
			(layers "F.Cu" "F.Mask" "F.Paste")
			(net "M_E_CPU0_SA_DQ<11>")
		)
		(pad "166" smd rect
			(at 2.050034 -45.47489 270)
			(size 0.519938 1.4986)
			(layers "F.Cu" "F.Mask" "F.Paste")
			(net "GND")
		)
		(pad "167" smd rect
			(at 2.050034 -44.625006 270)
			(size 0.519938 1.4986)
			(layers "F.Cu" "F.Mask" "F.Paste")
			(net "M_E_CPU0_SA_DQS_DN<6>")
		)
		(pad "168" smd rect
			(at 2.050034 -43.775122 270)
			(size 0.519938 1.4986)
			(layers "F.Cu" "F.Mask" "F.Paste")
			(net "M_E_CPU0_SA_DQS_DP<6>")
		)
		(pad "169" smd rect
			(at 2.050034 -42.924984 270)
			(size 0.519938 1.4986)
			(layers "F.Cu" "F.Mask" "F.Paste")
			(net "GND")
		)
		(pad "170" smd rect
			(at 2.050034 -42.0751 270)
			(size 0.519938 1.4986)
			(layers "F.Cu" "F.Mask" "F.Paste")
			(net "M_E_CPU0_SA_DQ<14>")
		)
		(pad "171" smd rect
			(at 2.050034 -41.224962 270)
			(size 0.519938 1.4986)
			(layers "F.Cu" "F.Mask" "F.Paste")
			(net "GND")
		)
		(pad "172" smd rect
			(at 2.050034 -40.375078 270)
			(size 0.519938 1.4986)
			(layers "F.Cu" "F.Mask" "F.Paste")
			(net "M_E_CPU0_SA_DQ<15>")
		)
		(pad "173" smd rect
			(at 2.050034 -39.52494 270)
			(size 0.519938 1.4986)
			(layers "F.Cu" "F.Mask" "F.Paste")
			(net "GND")
		)
		(pad "174" smd rect
			(at 2.050034 -38.675056 270)
			(size 0.519938 1.4986)
			(layers "F.Cu" "F.Mask" "F.Paste")
			(net "M_E_CPU0_SA_DQ<18>")
		)
		(pad "175" smd rect
			(at 2.050034 -37.824918 270)
			(size 0.519938 1.4986)
			(layers "F.Cu" "F.Mask" "F.Paste")
			(net "GND")
		)
		(pad "176" smd rect
			(at 2.050034 -36.975034 270)
			(size 0.519938 1.4986)
			(layers "F.Cu" "F.Mask" "F.Paste")
			(net "M_E_CPU0_SA_DQ<19>")
		)
		(pad "177" smd rect
			(at 2.050034 -36.124896 270)
			(size 0.519938 1.4986)
			(layers "F.Cu" "F.Mask" "F.Paste")
			(net "GND")
		)
		(pad "178" smd rect
			(at 2.050034 -35.275012 270)
			(size 0.519938 1.4986)
			(layers "F.Cu" "F.Mask" "F.Paste")
			(net "M_E_CPU0_SA_DQS_DN<7>")
		)
		(pad "179" smd rect
			(at 2.050034 -34.425128 270)
			(size 0.519938 1.4986)
			(layers "F.Cu" "F.Mask" "F.Paste")
			(net "M_E_CPU0_SA_DQS_DP<7>")
		)
		(pad "180" smd rect
			(at 2.050034 -33.57499 270)
			(size 0.519938 1.4986)
			(layers "F.Cu" "F.Mask" "F.Paste")
			(net "GND")
		)
		(pad "181" smd rect
			(at 2.050034 -32.725106 270)
			(size 0.519938 1.4986)
			(layers "F.Cu" "F.Mask" "F.Paste")
			(net "M_E_CPU0_SA_DQ<22>")
		)
		(pad "182" smd rect
			(at 2.050034 -31.874968 270)
			(size 0.519938 1.4986)
			(layers "F.Cu" "F.Mask" "F.Paste")
			(net "GND")
		)
		(pad "183" smd rect
			(at 2.050034 -31.025084 270)
			(size 0.519938 1.4986)
			(layers "F.Cu" "F.Mask" "F.Paste")
			(net "M_E_CPU0_SA_DQ<23>")
		)
		(pad "184" smd rect
			(at 2.050034 -30.174946 270)
			(size 0.519938 1.4986)
			(layers "F.Cu" "F.Mask" "F.Paste")
			(net "GND")
		)
		(pad "185" smd rect
			(at 2.050034 -29.325062 270)
			(size 0.519938 1.4986)
			(layers "F.Cu" "F.Mask" "F.Paste")
			(net "M_E_CPU0_SA_DQ<26>")
		)
		(pad "186" smd rect
			(at 2.050034 -28.474924 270)
			(size 0.519938 1.4986)
			(layers "F.Cu" "F.Mask" "F.Paste")
			(net "GND")
		)
		(pad "187" smd rect
			(at 2.050034 -27.62504 270)
			(size 0.519938 1.4986)
			(layers "F.Cu" "F.Mask" "F.Paste")
			(net "M_E_CPU0_SA_DQ<27>")
		)
		(pad "188" smd rect
			(at 2.050034 -26.774902 270)
			(size 0.519938 1.4986)
			(layers "F.Cu" "F.Mask" "F.Paste")
			(net "GND")
		)
		(pad "189" smd rect
			(at 2.050034 -25.925018 270)
			(size 0.519938 1.4986)
			(layers "F.Cu" "F.Mask" "F.Paste")
			(net "M_E_CPU0_SA_DQS_DN<8>")
		)
		(pad "190" smd rect
			(at 2.050034 -25.07488 270)
			(size 0.519938 1.4986)
			(layers "F.Cu" "F.Mask" "F.Paste")
			(net "M_E_CPU0_SA_DQS_DP<8>")
		)
		(pad "191" smd rect
			(at 2.050034 -24.224996 270)
			(size 0.519938 1.4986)
			(layers "F.Cu" "F.Mask" "F.Paste")
			(net "GND")
		)
		(pad "192" smd rect
			(at 2.050034 -23.375112 270)
			(size 0.519938 1.4986)
			(layers "F.Cu" "F.Mask" "F.Paste")
			(net "M_E_CPU0_SA_DQ<30>")
		)
		(pad "193" smd rect
			(at 2.050034 -22.524974 270)
			(size 0.519938 1.4986)
			(layers "F.Cu" "F.Mask" "F.Paste")
			(net "GND")
		)
		(pad "194" smd rect
			(at 2.050034 -21.67509 270)
			(size 0.519938 1.4986)
			(layers "F.Cu" "F.Mask" "F.Paste")
			(net "M_E_CPU0_SA_DQ<31>")
		)
		(pad "195" smd rect
			(at 2.050034 -20.824952 270)
			(size 0.519938 1.4986)
			(layers "F.Cu" "F.Mask" "F.Paste")
			(net "GND")
		)
		(pad "196" smd rect
			(at 2.050034 -19.975068 270)
			(size 0.519938 1.4986)
			(layers "F.Cu" "F.Mask" "F.Paste")
			(net "M_E_CPU0_SA_CB<2>")
		)
		(pad "197" smd rect
			(at 2.050034 -19.12493 270)
			(size 0.519938 1.4986)
			(layers "F.Cu" "F.Mask" "F.Paste")
			(net "GND")
		)
		(pad "198" smd rect
			(at 2.050034 -18.275046 270)
			(size 0.519938 1.4986)
			(layers "F.Cu" "F.Mask" "F.Paste")
			(net "M_E_CPU0_SA_CB<3>")
		)
		(pad "199" smd rect
			(at 2.050034 -17.424908 270)
			(size 0.519938 1.4986)
			(layers "F.Cu" "F.Mask" "F.Paste")
			(net "GND")
		)
		(pad "200" smd rect
			(at 2.050034 -16.575024 270)
			(size 0.519938 1.4986)
			(layers "F.Cu" "F.Mask" "F.Paste")
			(net "M_E_CPU0_SA_DQS_DN<9>")
		)
		(pad "201" smd rect
			(at 2.050034 -15.724886 270)
			(size 0.519938 1.4986)
			(layers "F.Cu" "F.Mask" "F.Paste")
			(net "M_E_CPU0_SA_DQS_DP<9>")
		)
		(pad "202" smd rect
			(at 2.050034 -14.875002 270)
			(size 0.519938 1.4986)
			(layers "F.Cu" "F.Mask" "F.Paste")
			(net "GND")
		)
		(pad "203" smd rect
			(at 2.050034 -14.025118 270)
			(size 0.519938 1.4986)
			(layers "F.Cu" "F.Mask" "F.Paste")
			(net "M_E_CPU0_SA_CB<6>")
		)
		(pad "204" smd rect
			(at 2.050034 -13.17498 270)
			(size 0.519938 1.4986)
			(layers "F.Cu" "F.Mask" "F.Paste")
			(net "GND")
		)
		(pad "205" smd rect
			(at 2.050034 -12.325096 270)
			(size 0.519938 1.4986)
			(layers "F.Cu" "F.Mask" "F.Paste")
			(net "M_E_CPU0_SA_CB<7>")
		)
		(pad "206" smd rect
			(at 2.050034 -11.474958 270)
			(size 0.519938 1.4986)
			(layers "F.Cu" "F.Mask" "F.Paste")
			(net "GND")
		)
		(pad "207" smd rect
			(at 2.050034 -10.625074 270)
			(size 0.519938 1.4986)
			(layers "F.Cu" "F.Mask" "F.Paste")
			(net "RST_M_EF_CPU0_FPGA_N")
		)
		(pad "208" smd rect
			(at 2.050034 -9.774936 270)
			(size 0.519938 1.4986)
			(layers "F.Cu" "F.Mask" "F.Paste")
			(net "GND")
		)
		(pad "209" smd rect
			(at 2.050034 -8.925052 270)
			(size 0.519938 1.4986)
			(layers "F.Cu" "F.Mask" "F.Paste")
			(net "M_E_CPU0_SA_CS_N<1>")
		)
		(pad "210" smd rect
			(at 2.050034 -8.074914 270)
			(size 0.519938 1.4986)
			(layers "F.Cu" "F.Mask" "F.Paste")
			(net "GND")
		)
		(pad "211" smd rect
			(at 2.050034 -7.22503 270)
			(size 0.519938 1.4986)
			(layers "F.Cu" "F.Mask" "F.Paste")
			(net "M_E_CPU0_SA_CA<1>")
		)
		(pad "212" smd rect
			(at 2.050034 -6.374892 270)
			(size 0.519938 1.4986)
			(layers "F.Cu" "F.Mask" "F.Paste")
			(net "GND")
		)
		(pad "213" smd rect
			(at 2.050034 -5.525008 270)
			(size 0.519938 1.4986)
			(layers "F.Cu" "F.Mask" "F.Paste")
			(net "M_E_CPU0_SA_CA<3>")
		)
		(pad "214" smd rect
			(at 2.050034 -4.675124 270)
			(size 0.519938 1.4986)
			(layers "F.Cu" "F.Mask" "F.Paste")
			(net "GND")
		)
		(pad "215" smd rect
			(at 2.050034 -3.824986 270)
			(size 0.519938 1.4986)
			(layers "F.Cu" "F.Mask" "F.Paste")
			(net "M_E_CPU0_SA_CA<5>")
		)
		(pad "216" smd rect
			(at 2.050034 -2.975102 270)
			(size 0.519938 1.4986)
			(layers "F.Cu" "F.Mask" "F.Paste")
			(net "GND")
		)
		(pad "217" smd rect
			(at 2.050034 -2.124964 270)
			(size 0.519938 1.4986)
			(layers "F.Cu" "F.Mask" "F.Paste")
			(net "M_E_CPU0_CLK_DP<0>")
		)
		(pad "218" smd rect
			(at 2.050034 -1.27508 270)
			(size 0.519938 1.4986)
			(layers "F.Cu" "F.Mask" "F.Paste")
			(net "M_E_CPU0_CLK_DN<0>")
		)
		(pad "219" smd rect
			(at 2.050034 -0.424942 270)
			(size 0.519938 1.4986)
			(layers "F.Cu" "F.Mask" "F.Paste")
			(net "GND")
		)
		(pad "220" smd rect
			(at 2.050034 5.525008 270)
			(size 0.519938 1.4986)
			(layers "F.Cu" "F.Mask" "F.Paste")
			(net "TP_CHE_CPU0_DIMM1_FRU_4")
		)
		(pad "221" smd rect
			(at 2.050034 6.374892 270)
			(size 0.519938 1.4986)
			(layers "F.Cu" "F.Mask" "F.Paste")
			(net "M_E_CPU0_SB_CA<1>")
		)
		(pad "222" smd rect
			(at 2.050034 7.22503 270)
			(size 0.519938 1.4986)
			(layers "F.Cu" "F.Mask" "F.Paste")
			(net "GND")
		)
		(pad "223" smd rect
			(at 2.050034 8.074914 270)
			(size 0.519938 1.4986)
			(layers "F.Cu" "F.Mask" "F.Paste")
			(net "M_E_CPU0_SB_CA<3>")
		)
		(pad "224" smd rect
			(at 2.050034 8.925052 270)
			(size 0.519938 1.4986)
			(layers "F.Cu" "F.Mask" "F.Paste")
			(net "GND")
		)
		(pad "225" smd rect
			(at 2.050034 9.774936 270)
			(size 0.519938 1.4986)
			(layers "F.Cu" "F.Mask" "F.Paste")
			(net "M_E_CPU0_SB_CA<5>")
		)
		(pad "226" smd rect
			(at 2.050034 10.625074 270)
			(size 0.519938 1.4986)
			(layers "F.Cu" "F.Mask" "F.Paste")
			(net "GND")
		)
		(pad "227" smd rect
			(at 2.050034 11.474958 270)
			(size 0.519938 1.4986)
			(layers "F.Cu" "F.Mask" "F.Paste")
			(net "M_E_CPU0_SB_PAR")
		)
		(pad "228" smd rect
			(at 2.050034 12.325096 270)
			(size 0.519938 1.4986)
			(layers "F.Cu" "F.Mask" "F.Paste")
			(net "GND")
		)
		(pad "229" smd rect
			(at 2.050034 13.17498 270)
			(size 0.519938 1.4986)
			(layers "F.Cu" "F.Mask" "F.Paste")
			(net "M_E_CPU0_SB_CS_N<1>")
		)
		(pad "230" smd rect
			(at 2.050034 14.025118 270)
			(size 0.519938 1.4986)
			(layers "F.Cu" "F.Mask" "F.Paste")
			(net "GND")
		)
		(pad "231" smd rect
			(at 2.050034 14.875002 270)
			(size 0.519938 1.4986)
			(layers "F.Cu" "F.Mask" "F.Paste")
			(net "TP_CHE_CPU0_DIMM1_FRU_5")
		)
		(pad "232" smd rect
			(at 2.050034 15.724886 270)
			(size 0.519938 1.4986)
			(layers "F.Cu" "F.Mask" "F.Paste")
			(net "TP_CHE_CPU0_DIMM1_FRU_6")
		)
		(pad "233" smd rect
			(at 2.050034 16.575024 270)
			(size 0.519938 1.4986)
			(layers "F.Cu" "F.Mask" "F.Paste")
			(net "GND")
		)
		(pad "234" smd rect
			(at 2.050034 17.424908 270)
			(size 0.519938 1.4986)
			(layers "F.Cu" "F.Mask" "F.Paste")
			(net "M_E_CPU0_SB_CB<6>")
		)
		(pad "235" smd rect
			(at 2.050034 18.275046 270)
			(size 0.519938 1.4986)
			(layers "F.Cu" "F.Mask" "F.Paste")
			(net "GND")
		)
		(pad "236" smd rect
			(at 2.050034 19.12493 270)
			(size 0.519938 1.4986)
			(layers "F.Cu" "F.Mask" "F.Paste")
			(net "M_E_CPU0_SB_CB<7>")
		)
		(pad "237" smd rect
			(at 2.050034 19.975068 270)
			(size 0.519938 1.4986)
			(layers "F.Cu" "F.Mask" "F.Paste")
			(net "GND")
		)
		(pad "238" smd rect
			(at 2.050034 20.824952 270)
			(size 0.519938 1.4986)
			(layers "F.Cu" "F.Mask" "F.Paste")
			(net "M_E_CPU0_SB_DQS_DN<4>")
		)
		(pad "239" smd rect
			(at 2.050034 21.67509 270)
			(size 0.519938 1.4986)
			(layers "F.Cu" "F.Mask" "F.Paste")
			(net "M_E_CPU0_SB_DQS_DP<4>")
		)
		(pad "240" smd rect
			(at 2.050034 22.524974 270)
			(size 0.519938 1.4986)
			(layers "F.Cu" "F.Mask" "F.Paste")
			(net "GND")
		)
		(pad "241" smd rect
			(at 2.050034 23.375112 270)
			(size 0.519938 1.4986)
			(layers "F.Cu" "F.Mask" "F.Paste")
			(net "M_E_CPU0_SB_CB<2>")
		)
		(pad "242" smd rect
			(at 2.050034 24.224996 270)
			(size 0.519938 1.4986)
			(layers "F.Cu" "F.Mask" "F.Paste")
			(net "GND")
		)
		(pad "243" smd rect
			(at 2.050034 25.07488 270)
			(size 0.519938 1.4986)
			(layers "F.Cu" "F.Mask" "F.Paste")
			(net "M_E_CPU0_SB_CB<3>")
		)
		(pad "244" smd rect
			(at 2.050034 25.925018 270)
			(size 0.519938 1.4986)
			(layers "F.Cu" "F.Mask" "F.Paste")
			(net "GND")
		)
		(pad "245" smd rect
			(at 2.050034 26.774902 270)
			(size 0.519938 1.4986)
			(layers "F.Cu" "F.Mask" "F.Paste")
			(net "M_E_CPU0_SB_DQ<2>")
		)
		(pad "246" smd rect
			(at 2.050034 27.62504 270)
			(size 0.519938 1.4986)
			(layers "F.Cu" "F.Mask" "F.Paste")
			(net "GND")
		)
		(pad "247" smd rect
			(at 2.050034 28.474924 270)
			(size 0.519938 1.4986)
			(layers "F.Cu" "F.Mask" "F.Paste")
			(net "M_E_CPU0_SB_DQ<3>")
		)
		(pad "248" smd rect
			(at 2.050034 29.325062 270)
			(size 0.519938 1.4986)
			(layers "F.Cu" "F.Mask" "F.Paste")
			(net "GND")
		)
		(pad "249" smd rect
			(at 2.050034 30.174946 270)
			(size 0.519938 1.4986)
			(layers "F.Cu" "F.Mask" "F.Paste")
			(net "M_E_CPU0_SB_DQS_DN<5>")
		)
		(pad "250" smd rect
			(at 2.050034 31.025084 270)
			(size 0.519938 1.4986)
			(layers "F.Cu" "F.Mask" "F.Paste")
			(net "M_E_CPU0_SB_DQS_DP<5>")
		)
		(pad "251" smd rect
			(at 2.050034 31.874968 270)
			(size 0.519938 1.4986)
			(layers "F.Cu" "F.Mask" "F.Paste")
			(net "GND")
		)
		(pad "252" smd rect
			(at 2.050034 32.725106 270)
			(size 0.519938 1.4986)
			(layers "F.Cu" "F.Mask" "F.Paste")
			(net "M_E_CPU0_SB_DQ<6>")
		)
		(pad "253" smd rect
			(at 2.050034 33.57499 270)
			(size 0.519938 1.4986)
			(layers "F.Cu" "F.Mask" "F.Paste")
			(net "GND")
		)
		(pad "254" smd rect
			(at 2.050034 34.425128 270)
			(size 0.519938 1.4986)
			(layers "F.Cu" "F.Mask" "F.Paste")
			(net "M_E_CPU0_SB_DQ<7>")
		)
		(pad "255" smd rect
			(at 2.050034 35.275012 270)
			(size 0.519938 1.4986)
			(layers "F.Cu" "F.Mask" "F.Paste")
			(net "GND")
		)
		(pad "256" smd rect
			(at 2.050034 36.124896 270)
			(size 0.519938 1.4986)
			(layers "F.Cu" "F.Mask" "F.Paste")
			(net "M_E_CPU0_SB_DQ<10>")
		)
		(pad "257" smd rect
			(at 2.050034 36.975034 270)
			(size 0.519938 1.4986)
			(layers "F.Cu" "F.Mask" "F.Paste")
			(net "GND")
		)
		(pad "258" smd rect
			(at 2.050034 37.824918 270)
			(size 0.519938 1.4986)
			(layers "F.Cu" "F.Mask" "F.Paste")
			(net "M_E_CPU0_SB_DQ<11>")
		)
		(pad "259" smd rect
			(at 2.050034 38.675056 270)
			(size 0.519938 1.4986)
			(layers "F.Cu" "F.Mask" "F.Paste")
			(net "GND")
		)
		(pad "260" smd rect
			(at 2.050034 39.52494 270)
			(size 0.519938 1.4986)
			(layers "F.Cu" "F.Mask" "F.Paste")
			(net "M_E_CPU0_SB_DQS_DN<6>")
		)
		(pad "261" smd rect
			(at 2.050034 40.375078 270)
			(size 0.519938 1.4986)
			(layers "F.Cu" "F.Mask" "F.Paste")
			(net "M_E_CPU0_SB_DQS_DP<6>")
		)
		(pad "262" smd rect
			(at 2.050034 41.224962 270)
			(size 0.519938 1.4986)
			(layers "F.Cu" "F.Mask" "F.Paste")
			(net "GND")
		)
		(pad "263" smd rect
			(at 2.050034 42.0751 270)
			(size 0.519938 1.4986)
			(layers "F.Cu" "F.Mask" "F.Paste")
			(net "M_E_CPU0_SB_DQ<14>")
		)
		(pad "264" smd rect
			(at 2.050034 42.924984 270)
			(size 0.519938 1.4986)
			(layers "F.Cu" "F.Mask" "F.Paste")
			(net "GND")
		)
		(pad "265" smd rect
			(at 2.050034 43.775122 270)
			(size 0.519938 1.4986)
			(layers "F.Cu" "F.Mask" "F.Paste")
			(net "M_E_CPU0_SB_DQ<15>")
		)
		(pad "266" smd rect
			(at 2.050034 44.625006 270)
			(size 0.519938 1.4986)
			(layers "F.Cu" "F.Mask" "F.Paste")
			(net "GND")
		)
		(pad "267" smd rect
			(at 2.050034 45.47489 270)
			(size 0.519938 1.4986)
			(layers "F.Cu" "F.Mask" "F.Paste")
			(net "M_E_CPU0_SB_DQ<18>")
		)
		(pad "268" smd rect
			(at 2.050034 46.325028 270)
			(size 0.519938 1.4986)
			(layers "F.Cu" "F.Mask" "F.Paste")
			(net "GND")
		)
		(pad "269" smd rect
			(at 2.050034 47.174912 270)
			(size 0.519938 1.4986)
			(layers "F.Cu" "F.Mask" "F.Paste")
			(net "M_E_CPU0_SB_DQ<19>")
		)
		(pad "270" smd rect
			(at 2.050034 48.02505 270)
			(size 0.519938 1.4986)
			(layers "F.Cu" "F.Mask" "F.Paste")
			(net "GND")
		)
		(pad "271" smd rect
			(at 2.050034 48.874934 270)
			(size 0.519938 1.4986)
			(layers "F.Cu" "F.Mask" "F.Paste")
			(net "M_E_CPU0_SB_DQS_DN<7>")
		)
		(pad "272" smd rect
			(at 2.050034 49.725072 270)
			(size 0.519938 1.4986)
			(layers "F.Cu" "F.Mask" "F.Paste")
			(net "M_E_CPU0_SB_DQS_DP<7>")
		)
		(pad "273" smd rect
			(at 2.050034 50.574956 270)
			(size 0.519938 1.4986)
			(layers "F.Cu" "F.Mask" "F.Paste")
			(net "GND")
		)
		(pad "274" smd rect
			(at 2.050034 51.425094 270)
			(size 0.519938 1.4986)
			(layers "F.Cu" "F.Mask" "F.Paste")
			(net "M_E_CPU0_SB_DQ<22>")
		)
		(pad "275" smd rect
			(at 2.050034 52.274978 270)
			(size 0.519938 1.4986)
			(layers "F.Cu" "F.Mask" "F.Paste")
			(net "GND")
		)
		(pad "276" smd rect
			(at 2.050034 53.125116 270)
			(size 0.519938 1.4986)
			(layers "F.Cu" "F.Mask" "F.Paste")
			(net "M_E_CPU0_SB_DQ<23>")
		)
		(pad "277" smd rect
			(at 2.050034 53.975 270)
			(size 0.519938 1.4986)
			(layers "F.Cu" "F.Mask" "F.Paste")
			(net "GND")
		)
		(pad "278" smd rect
			(at 2.050034 54.824884 270)
			(size 0.519938 1.4986)
			(layers "F.Cu" "F.Mask" "F.Paste")
			(net "M_E_CPU0_SB_DQ<26>")
		)
		(pad "279" smd rect
			(at 2.050034 55.675022 270)
			(size 0.519938 1.4986)
			(layers "F.Cu" "F.Mask" "F.Paste")
			(net "GND")
		)
		(pad "280" smd rect
			(at 2.050034 56.524906 270)
			(size 0.519938 1.4986)
			(layers "F.Cu" "F.Mask" "F.Paste")
			(net "M_E_CPU0_SB_DQ<27>")
		)
		(pad "281" smd rect
			(at 2.050034 57.375044 270)
			(size 0.519938 1.4986)
			(layers "F.Cu" "F.Mask" "F.Paste")
			(net "GND")
		)
		(pad "282" smd rect
			(at 2.050034 58.224928 270)
			(size 0.519938 1.4986)
			(layers "F.Cu" "F.Mask" "F.Paste")
			(net "M_E_CPU0_SB_DQS_DN<8>")
		)
		(pad "283" smd rect
			(at 2.050034 59.075066 270)
			(size 0.519938 1.4986)
			(layers "F.Cu" "F.Mask" "F.Paste")
			(net "M_E_CPU0_SB_DQS_DP<8>")
		)
		(pad "284" smd rect
			(at 2.050034 59.92495 270)
			(size 0.519938 1.4986)
			(layers "F.Cu" "F.Mask" "F.Paste")
			(net "GND")
		)
		(pad "285" smd rect
			(at 2.050034 60.775088 270)
			(size 0.519938 1.4986)
			(layers "F.Cu" "F.Mask" "F.Paste")
			(net "M_E_CPU0_SB_DQ<30>")
		)
		(pad "286" smd rect
			(at 2.050034 61.624972 270)
			(size 0.519938 1.4986)
			(layers "F.Cu" "F.Mask" "F.Paste")
			(net "GND")
		)
		(pad "287" smd rect
			(at 2.050034 62.47511 270)
			(size 0.519938 1.4986)
			(layers "F.Cu" "F.Mask" "F.Paste")
			(net "M_E_CPU0_SB_DQ<31>")
		)
		(pad "288" smd rect
			(at 2.050034 63.324994 270)
			(size 0.519938 1.4986)
			(layers "F.Cu" "F.Mask" "F.Paste")
			(net "GND")
		)
		(pad "G1" thru_hole oval
			(at 0 -68.97497)
			(size 2.8194 1.5748)
			(drill oval 2.4384 1.1938)
			(layers "*.Cu" "*.Mask")
			(remove_unused_layers no)
			(net "GND")
			(clearance 0.127)
			(thermal_gap 0.127)
		)
		(pad "G2" thru_hole oval
			(at 0 3.875024)
			(size 2.8194 1.5748)
			(drill oval 2.4384 1.1938)
			(layers "*.Cu" "*.Mask")
			(remove_unused_layers no)
			(net "GND")
			(clearance 0.127)
			(thermal_gap 0.127)
		)
		(pad "G3" thru_hole oval
			(at 0 68.97497)
			(size 2.8194 1.5748)
			(drill oval 2.4384 1.1938)
			(layers "*.Cu" "*.Mask")
			(remove_unused_layers no)
			(net "GND")
			(clearance 0.127)
			(thermal_gap 0.127)
		)
	)
	(footprint ""
		(layer "F.Cu")
		(at 413.48025 -408.517344 -90)
		(property "Reference" "C897"
			(at 0 0 270)
			(layer "F.SilkS")
			(hide yes)
			(effects
				(font
					(size 1.27 1.27)
				)
			)
		)
		(property "Value" ""
			(at 0 0 270)
			(layer "F.Fab")
			(effects
				(font
					(size 1.27 1.27)
				)
			)
		)
		(duplicate_pad_numbers_are_jumpers no)
		(fp_line
			(start -0.299974 0.150114)
			(end -0.299974 -0.150114)
			(stroke
				(width 0.1)
				(type default)
			)
			(layer "F.Fab")
		)
		(fp_line
			(start 0.299974 0.150114)
			(end -0.299974 0.150114)
			(stroke
				(width 0.1)
				(type default)
			)
			(layer "F.Fab")
		)
		(fp_line
			(start -0.299974 -0.150114)
			(end 0.299974 -0.150114)
			(stroke
				(width 0.1)
				(type default)
			)
			(layer "F.Fab")
		)
		(fp_line
			(start 0.299974 -0.150114)
			(end 0.299974 0.150114)
			(stroke
				(width 0.1)
				(type default)
			)
			(layer "F.Fab")
		)
		(pad "1" smd rect
			(at -0.2667 0 270)
			(size 0.3048 0.381)
			(layers "F.Cu" "F.Mask" "F.Paste")
			(net "P5E_CPU0_PE3_TX_C_DP<2>")
		)
		(pad "2" smd rect
			(at 0.2667 0 270)
			(size 0.3048 0.381)
			(layers "F.Cu" "F.Mask" "F.Paste")
			(net "P5E_CPU0_PE3_TX_DP<2>")
		)
	)
	(footprint ""
		(layer "F.Cu")
		(at 135.56488 -100.167948 -90)
		(property "Reference" "R4414"
			(at 0 0 270)
			(layer "F.SilkS")
			(hide yes)
			(effects
				(font
					(size 1.27 1.27)
				)
			)
		)
		(property "Value" ""
			(at 0 0 270)
			(layer "F.Fab")
			(effects
				(font
					(size 1.27 1.27)
				)
			)
		)
		(duplicate_pad_numbers_are_jumpers no)
		(fp_line
			(start -0.7874 0.4064)
			(end -0.7874 -0.4064)
			(stroke
				(width 0.1524)
				(type default)
			)
			(layer "F.SilkS")
		)
		(fp_line
			(start 0.7874 0.4064)
			(end -0.7874 0.4064)
			(stroke
				(width 0.1524)
				(type default)
			)
			(layer "F.SilkS")
		)
		(fp_line
			(start -0.7874 -0.4064)
			(end 0.7874 -0.4064)
			(stroke
				(width 0.1524)
				(type default)
			)
			(layer "F.SilkS")
		)
		(fp_line
			(start 0.7874 -0.4064)
			(end 0.7874 0.4064)
			(stroke
				(width 0.1524)
				(type default)
			)
			(layer "F.SilkS")
		)
		(fp_line
			(start -0.67945 0.3048)
			(end -0.67945 -0.305054)
			(stroke
				(width 0.1)
				(type default)
			)
			(layer "F.Fab")
		)
		(fp_line
			(start -0.12065 0.3048)
			(end -0.67945 0.3048)
			(stroke
				(width 0.1)
				(type default)
			)
			(layer "F.Fab")
		)
		(fp_line
			(start 0.120396 0.3048)
			(end 0.120396 0.2794)
			(stroke
				(width 0.1)
				(type default)
			)
			(layer "F.Fab")
		)
		(fp_line
			(start 0.67945 0.3048)
			(end 0.120396 0.3048)
			(stroke
				(width 0.1)
				(type default)
			)
			(layer "F.Fab")
		)
		(fp_line
			(start -0.12065 0.2794)
			(end -0.12065 0.3048)
			(stroke
				(width 0.1)
				(type default)
			)
			(layer "F.Fab")
		)
		(fp_line
			(start 0.120396 0.2794)
			(end -0.12065 0.2794)
			(stroke
				(width 0.1)
				(type default)
			)
			(layer "F.Fab")
		)
		(fp_line
			(start -0.12065 -0.2794)
			(end 0.12065 -0.2794)
			(stroke
				(width 0.1)
				(type default)
			)
			(layer "F.Fab")
		)
		(fp_line
			(start 0.12065 -0.2794)
			(end 0.12065 -0.3048)
			(stroke
				(width 0.1)
				(type default)
			)
			(layer "F.Fab")
		)
		(fp_line
			(start 0.12065 -0.3048)
			(end 0.67945 -0.3048)
			(stroke
				(width 0.1)
				(type default)
			)
			(layer "F.Fab")
		)
		(fp_line
			(start 0.67945 -0.3048)
			(end 0.67945 0.3048)
			(stroke
				(width 0.1)
				(type default)
			)
			(layer "F.Fab")
		)
		(fp_line
			(start -0.67945 -0.305054)
			(end -0.12065 -0.305054)
			(stroke
				(width 0.1)
				(type default)
			)
			(layer "F.Fab")
		)
		(fp_line
			(start -0.12065 -0.305054)
			(end -0.12065 -0.2794)
			(stroke
				(width 0.1)
				(type default)
			)
			(layer "F.Fab")
		)
		(pad "1" smd circle
			(at -0.40005 0 270)
			(size 0 0)
			(layers "F.Cu" "F.Mask" "F.Paste")
			(net "H_CPU1_MEMTRIP_VT_N")
		)
		(pad "2" smd circle
			(at 0.40005 0 270)
			(size 0 0)
			(layers "F.Cu" "F.Mask" "F.Paste")
			(net "H_CPU1_MEMTRIP_LVC1_N")
		)
	)
	(footprint ""
		(layer "F.Cu")
		(at 431.47488 -128.361948 90)
		(property "Reference" "PR4231"
			(at 0 0 90)
			(layer "F.SilkS")
			(hide yes)
			(effects
				(font
					(size 1.27 1.27)
				)
			)
		)
		(property "Value" ""
			(at 0 0 90)
			(layer "F.Fab")
			(effects
				(font
					(size 1.27 1.27)
				)
			)
		)
		(duplicate_pad_numbers_are_jumpers no)
		(fp_line
			(start 0.7874 -0.4064)
			(end 0.7874 0.4064)
			(stroke
				(width 0.1524)
				(type default)
			)
			(layer "F.SilkS")
		)
		(fp_line
			(start -0.7874 -0.4064)
			(end 0.7874 -0.4064)
			(stroke
				(width 0.1524)
				(type default)
			)
			(layer "F.SilkS")
		)
		(fp_line
			(start 0.7874 0.4064)
			(end -0.7874 0.4064)
			(stroke
				(width 0.1524)
				(type default)
			)
			(layer "F.SilkS")
		)
		(fp_line
			(start -0.7874 0.4064)
			(end -0.7874 -0.4064)
			(stroke
				(width 0.1524)
				(type default)
			)
			(layer "F.SilkS")
		)
		(fp_line
			(start -0.12065 -0.305054)
			(end -0.12065 -0.2794)
			(stroke
				(width 0.1)
				(type default)
			)
			(layer "F.Fab")
		)
		(fp_line
			(start -0.67945 -0.305054)
			(end -0.12065 -0.305054)
			(stroke
				(width 0.1)
				(type default)
			)
			(layer "F.Fab")
		)
		(fp_line
			(start 0.67945 -0.3048)
			(end 0.67945 0.3048)
			(stroke
				(width 0.1)
				(type default)
			)
			(layer "F.Fab")
		)
		(fp_line
			(start 0.12065 -0.3048)
			(end 0.67945 -0.3048)
			(stroke
				(width 0.1)
				(type default)
			)
			(layer "F.Fab")
		)
		(fp_line
			(start 0.12065 -0.2794)
			(end 0.12065 -0.3048)
			(stroke
				(width 0.1)
				(type default)
			)
			(layer "F.Fab")
		)
		(fp_line
			(start -0.12065 -0.2794)
			(end 0.12065 -0.2794)
			(stroke
				(width 0.1)
				(type default)
			)
			(layer "F.Fab")
		)
		(fp_line
			(start 0.120396 0.2794)
			(end -0.12065 0.2794)
			(stroke
				(width 0.1)
				(type default)
			)
			(layer "F.Fab")
		)
		(fp_line
			(start -0.12065 0.2794)
			(end -0.12065 0.3048)
			(stroke
				(width 0.1)
				(type default)
			)
			(layer "F.Fab")
		)
		(fp_line
			(start 0.67945 0.3048)
			(end 0.120396 0.3048)
			(stroke
				(width 0.1)
				(type default)
			)
			(layer "F.Fab")
		)
		(fp_line
			(start 0.120396 0.3048)
			(end 0.120396 0.2794)
			(stroke
				(width 0.1)
				(type default)
			)
			(layer "F.Fab")
		)
		(fp_line
			(start -0.12065 0.3048)
			(end -0.67945 0.3048)
			(stroke
				(width 0.1)
				(type default)
			)
			(layer "F.Fab")
		)
		(fp_line
			(start -0.67945 0.3048)
			(end -0.67945 -0.305054)
			(stroke
				(width 0.1)
				(type default)
			)
			(layer "F.Fab")
		)
		(pad "1" smd circle
			(at -0.40005 0 90)
			(size 0 0)
			(layers "F.Cu" "F.Mask" "F.Paste")
			(net "NC_PVCCD_HV_CPU0_ACSP3")
		)
		(pad "2" smd circle
			(at 0.40005 0 90)
			(size 0 0)
			(layers "F.Cu" "F.Mask" "F.Paste")
			(net "GND")
		)
	)
	(footprint ""
		(layer "F.Cu")
		(at 46.178724 -353.61626 -90)
		(property "Reference" "PC1194_P1_4"
			(at 0 0 270)
			(layer "F.SilkS")
			(hide yes)
			(effects
				(font
					(size 1.27 1.27)
				)
			)
		)
		(property "Value" ""
			(at 0 0 270)
			(layer "F.Fab")
			(effects
				(font
					(size 1.27 1.27)
				)
			)
		)
		(duplicate_pad_numbers_are_jumpers no)
		(fp_line
			(start -0.7874 0.4064)
			(end -0.7874 -0.4064)
			(stroke
				(width 0.1524)
				(type default)
			)
			(layer "F.SilkS")
		)
		(fp_line
			(start 0.7874 0.4064)
			(end -0.7874 0.4064)
			(stroke
				(width 0.1524)
				(type default)
			)
			(layer "F.SilkS")
		)
		(fp_line
			(start -0.7874 -0.4064)
			(end 0.7874 -0.4064)
			(stroke
				(width 0.1524)
				(type default)
			)
			(layer "F.SilkS")
		)
		(fp_line
			(start 0.7874 -0.4064)
			(end 0.7874 0.4064)
			(stroke
				(width 0.1524)
				(type default)
			)
			(layer "F.SilkS")
		)
		(fp_line
			(start -0.67945 0.3048)
			(end -0.67945 -0.305054)
			(stroke
				(width 0.1)
				(type default)
			)
			(layer "F.Fab")
		)
		(fp_line
			(start -0.12065 0.3048)
			(end -0.67945 0.3048)
			(stroke
				(width 0.1)
				(type default)
			)
			(layer "F.Fab")
		)
		(fp_line
			(start 0.120396 0.3048)
			(end 0.120396 0.2794)
			(stroke
				(width 0.1)
				(type default)
			)
			(layer "F.Fab")
		)
		(fp_line
			(start 0.67945 0.3048)
			(end 0.120396 0.3048)
			(stroke
				(width 0.1)
				(type default)
			)
			(layer "F.Fab")
		)
		(fp_line
			(start -0.12065 0.2794)
			(end -0.12065 0.3048)
			(stroke
				(width 0.1)
				(type default)
			)
			(layer "F.Fab")
		)
		(fp_line
			(start 0.120396 0.2794)
			(end -0.12065 0.2794)
			(stroke
				(width 0.1)
				(type default)
			)
			(layer "F.Fab")
		)
		(fp_line
			(start -0.12065 -0.2794)
			(end 0.12065 -0.2794)
			(stroke
				(width 0.1)
				(type default)
			)
			(layer "F.Fab")
		)
		(fp_line
			(start 0.12065 -0.2794)
			(end 0.12065 -0.3048)
			(stroke
				(width 0.1)
				(type default)
			)
			(layer "F.Fab")
		)
		(fp_line
			(start 0.12065 -0.3048)
			(end 0.67945 -0.3048)
			(stroke
				(width 0.1)
				(type default)
			)
			(layer "F.Fab")
		)
		(fp_line
			(start 0.67945 -0.3048)
			(end 0.67945 0.3048)
			(stroke
				(width 0.1)
				(type default)
			)
			(layer "F.Fab")
		)
		(fp_line
			(start -0.67945 -0.305054)
			(end -0.12065 -0.305054)
			(stroke
				(width 0.1)
				(type default)
			)
			(layer "F.Fab")
		)
		(fp_line
			(start -0.12065 -0.305054)
			(end -0.12065 -0.2794)
			(stroke
				(width 0.1)
				(type default)
			)
			(layer "F.Fab")
		)
		(pad "1" smd circle
			(at -0.40005 0 270)
			(size 0 0)
			(layers "F.Cu" "F.Mask" "F.Paste")
			(net "SW_P12V_PVCCFA_EHV_FIVRA_CPU1_L")
		)
		(pad "2" smd circle
			(at 0.40005 0 270)
			(size 0 0)
			(layers "F.Cu" "F.Mask" "F.Paste")
			(net "GND")
		)
	)
	(footprint ""
		(layer "F.Cu")
		(at 186.8932 -93.91015 90)
		(property "Reference" "R4751"
			(at 0 0 90)
			(layer "F.SilkS")
			(hide yes)
			(effects
				(font
					(size 1.27 1.27)
				)
			)
		)
		(property "Value" ""
			(at 0 0 90)
			(layer "F.Fab")
			(effects
				(font
					(size 1.27 1.27)
				)
			)
		)
		(duplicate_pad_numbers_are_jumpers no)
		(fp_line
			(start 0.7874 -0.4064)
			(end 0.7874 0.4064)
			(stroke
				(width 0.1524)
				(type default)
			)
			(layer "F.SilkS")
		)
		(fp_line
			(start -0.7874 -0.4064)
			(end 0.7874 -0.4064)
			(stroke
				(width 0.1524)
				(type default)
			)
			(layer "F.SilkS")
		)
		(fp_line
			(start 0.7874 0.4064)
			(end -0.7874 0.4064)
			(stroke
				(width 0.1524)
				(type default)
			)
			(layer "F.SilkS")
		)
		(fp_line
			(start -0.7874 0.4064)
			(end -0.7874 -0.4064)
			(stroke
				(width 0.1524)
				(type default)
			)
			(layer "F.SilkS")
		)
		(fp_line
			(start -0.12065 -0.305054)
			(end -0.12065 -0.2794)
			(stroke
				(width 0.1)
				(type default)
			)
			(layer "F.Fab")
		)
		(fp_line
			(start -0.67945 -0.305054)
			(end -0.12065 -0.305054)
			(stroke
				(width 0.1)
				(type default)
			)
			(layer "F.Fab")
		)
		(fp_line
			(start 0.67945 -0.3048)
			(end 0.67945 0.3048)
			(stroke
				(width 0.1)
				(type default)
			)
			(layer "F.Fab")
		)
		(fp_line
			(start 0.12065 -0.3048)
			(end 0.67945 -0.3048)
			(stroke
				(width 0.1)
				(type default)
			)
			(layer "F.Fab")
		)
		(fp_line
			(start 0.12065 -0.2794)
			(end 0.12065 -0.3048)
			(stroke
				(width 0.1)
				(type default)
			)
			(layer "F.Fab")
		)
		(fp_line
			(start -0.12065 -0.2794)
			(end 0.12065 -0.2794)
			(stroke
				(width 0.1)
				(type default)
			)
			(layer "F.Fab")
		)
		(fp_line
			(start 0.120396 0.2794)
			(end -0.12065 0.2794)
			(stroke
				(width 0.1)
				(type default)
			)
			(layer "F.Fab")
		)
		(fp_line
			(start -0.12065 0.2794)
			(end -0.12065 0.3048)
			(stroke
				(width 0.1)
				(type default)
			)
			(layer "F.Fab")
		)
		(fp_line
			(start 0.67945 0.3048)
			(end 0.120396 0.3048)
			(stroke
				(width 0.1)
				(type default)
			)
			(layer "F.Fab")
		)
		(fp_line
			(start 0.120396 0.3048)
			(end 0.120396 0.2794)
			(stroke
				(width 0.1)
				(type default)
			)
			(layer "F.Fab")
		)
		(fp_line
			(start -0.12065 0.3048)
			(end -0.67945 0.3048)
			(stroke
				(width 0.1)
				(type default)
			)
			(layer "F.Fab")
		)
		(fp_line
			(start -0.67945 0.3048)
			(end -0.67945 -0.305054)
			(stroke
				(width 0.1)
				(type default)
			)
			(layer "F.Fab")
		)
		(pad "1" smd circle
			(at -0.40005 0 90)
			(size 0 0)
			(layers "F.Cu" "F.Mask" "F.Paste")
			(net "HP_LVC3_OCP_V3_1_PWRGD_R")
		)
		(pad "2" smd circle
			(at 0.40005 0 90)
			(size 0 0)
			(layers "F.Cu" "F.Mask" "F.Paste")
			(net "HP_LVC3_OCP_V3_1_FUSE_PWRGD")
		)
	)
	(footprint ""
		(layer "F.Cu")
		(at 364.50143 -245.634002 -90)
		(property "Reference" "C997"
			(at 0 0 270)
			(layer "F.SilkS")
			(hide yes)
			(effects
				(font
					(size 1.27 1.27)
				)
			)
		)
		(property "Value" ""
			(at 0 0 270)
			(layer "F.Fab")
			(effects
				(font
					(size 1.27 1.27)
				)
			)
		)
		(duplicate_pad_numbers_are_jumpers no)
		(fp_line
			(start -0.7874 0.4064)
			(end -0.7874 -0.4064)
			(stroke
				(width 0.1524)
				(type default)
			)
			(layer "F.SilkS")
		)
		(fp_line
			(start 0.7874 0.4064)
			(end -0.7874 0.4064)
			(stroke
				(width 0.1524)
				(type default)
			)
			(layer "F.SilkS")
		)
		(fp_line
			(start -0.7874 -0.4064)
			(end 0.7874 -0.4064)
			(stroke
				(width 0.1524)
				(type default)
			)
			(layer "F.SilkS")
		)
		(fp_line
			(start 0.7874 -0.4064)
			(end 0.7874 0.4064)
			(stroke
				(width 0.1524)
				(type default)
			)
			(layer "F.SilkS")
		)
		(fp_line
			(start -0.67945 0.3048)
			(end -0.67945 -0.305054)
			(stroke
				(width 0.1)
				(type default)
			)
			(layer "F.Fab")
		)
		(fp_line
			(start -0.12065 0.3048)
			(end -0.67945 0.3048)
			(stroke
				(width 0.1)
				(type default)
			)
			(layer "F.Fab")
		)
		(fp_line
			(start 0.120396 0.3048)
			(end 0.120396 0.2794)
			(stroke
				(width 0.1)
				(type default)
			)
			(layer "F.Fab")
		)
		(fp_line
			(start 0.67945 0.3048)
			(end 0.120396 0.3048)
			(stroke
				(width 0.1)
				(type default)
			)
			(layer "F.Fab")
		)
		(fp_line
			(start -0.12065 0.2794)
			(end -0.12065 0.3048)
			(stroke
				(width 0.1)
				(type default)
			)
			(layer "F.Fab")
		)
		(fp_line
			(start 0.120396 0.2794)
			(end -0.12065 0.2794)
			(stroke
				(width 0.1)
				(type default)
			)
			(layer "F.Fab")
		)
		(fp_line
			(start -0.12065 -0.2794)
			(end 0.12065 -0.2794)
			(stroke
				(width 0.1)
				(type default)
			)
			(layer "F.Fab")
		)
		(fp_line
			(start 0.12065 -0.2794)
			(end 0.12065 -0.3048)
			(stroke
				(width 0.1)
				(type default)
			)
			(layer "F.Fab")
		)
		(fp_line
			(start 0.12065 -0.3048)
			(end 0.67945 -0.3048)
			(stroke
				(width 0.1)
				(type default)
			)
			(layer "F.Fab")
		)
		(fp_line
			(start 0.67945 -0.3048)
			(end 0.67945 0.3048)
			(stroke
				(width 0.1)
				(type default)
			)
			(layer "F.Fab")
		)
		(fp_line
			(start -0.67945 -0.305054)
			(end -0.12065 -0.305054)
			(stroke
				(width 0.1)
				(type default)
			)
			(layer "F.Fab")
		)
		(fp_line
			(start -0.12065 -0.305054)
			(end -0.12065 -0.2794)
			(stroke
				(width 0.1)
				(type default)
			)
			(layer "F.Fab")
		)
		(pad "1" smd circle
			(at -0.40005 0 270)
			(size 0 0)
			(layers "F.Cu" "F.Mask" "F.Paste")
			(net "PVCCIN_CPU0")
		)
		(pad "2" smd circle
			(at 0.40005 0 270)
			(size 0 0)
			(layers "F.Cu" "F.Mask" "F.Paste")
			(net "GND")
		)
	)
	(footprint ""
		(layer "F.Cu")
		(at 299.865034 -409.69184)
		(property "Reference" "R4689"
			(at 0 0 0)
			(layer "F.SilkS")
			(hide yes)
			(effects
				(font
					(size 1.27 1.27)
				)
			)
		)
		(property "Value" ""
			(at 0 0 0)
			(layer "F.Fab")
			(effects
				(font
					(size 1.27 1.27)
				)
			)
		)
		(duplicate_pad_numbers_are_jumpers no)
		(fp_line
			(start -0.7874 -0.4064)
			(end 0.7874 -0.4064)
			(stroke
				(width 0.1524)
				(type default)
			)
			(layer "F.SilkS")
		)
		(fp_line
			(start -0.7874 0.4064)
			(end -0.7874 -0.4064)
			(stroke
				(width 0.1524)
				(type default)
			)
			(layer "F.SilkS")
		)
		(fp_line
			(start 0.7874 -0.4064)
			(end 0.7874 0.4064)
			(stroke
				(width 0.1524)
				(type default)
			)
			(layer "F.SilkS")
		)
		(fp_line
			(start 0.7874 0.4064)
			(end -0.7874 0.4064)
			(stroke
				(width 0.1524)
				(type default)
			)
			(layer "F.SilkS")
		)
		(fp_line
			(start -0.67945 -0.305054)
			(end -0.12065 -0.305054)
			(stroke
				(width 0.1)
				(type default)
			)
			(layer "F.Fab")
		)
		(fp_line
			(start -0.67945 0.3048)
			(end -0.67945 -0.305054)
			(stroke
				(width 0.1)
				(type default)
			)
			(layer "F.Fab")
		)
		(fp_line
			(start -0.12065 -0.305054)
			(end -0.12065 -0.2794)
			(stroke
				(width 0.1)
				(type default)
			)
			(layer "F.Fab")
		)
		(fp_line
			(start -0.12065 -0.2794)
			(end 0.12065 -0.2794)
			(stroke
				(width 0.1)
				(type default)
			)
			(layer "F.Fab")
		)
		(fp_line
			(start -0.12065 0.2794)
			(end -0.12065 0.3048)
			(stroke
				(width 0.1)
				(type default)
			)
			(layer "F.Fab")
		)
		(fp_line
			(start -0.12065 0.3048)
			(end -0.67945 0.3048)
			(stroke
				(width 0.1)
				(type default)
			)
			(layer "F.Fab")
		)
		(fp_line
			(start 0.120396 0.2794)
			(end -0.12065 0.2794)
			(stroke
				(width 0.1)
				(type default)
			)
			(layer "F.Fab")
		)
		(fp_line
			(start 0.120396 0.3048)
			(end 0.120396 0.2794)
			(stroke
				(width 0.1)
				(type default)
			)
			(layer "F.Fab")
		)
		(fp_line
			(start 0.12065 -0.3048)
			(end 0.67945 -0.3048)
			(stroke
				(width 0.1)
				(type default)
			)
			(layer "F.Fab")
		)
		(fp_line
			(start 0.12065 -0.2794)
			(end 0.12065 -0.3048)
			(stroke
				(width 0.1)
				(type default)
			)
			(layer "F.Fab")
		)
		(fp_line
			(start 0.67945 -0.3048)
			(end 0.67945 0.3048)
			(stroke
				(width 0.1)
				(type default)
			)
			(layer "F.Fab")
		)
		(fp_line
			(start 0.67945 0.3048)
			(end 0.120396 0.3048)
			(stroke
				(width 0.1)
				(type default)
			)
			(layer "F.Fab")
		)
		(pad "1" smd circle
			(at -0.40005 0)
			(size 0 0)
			(layers "F.Cu" "F.Mask" "F.Paste")
			(net "SMB_LM75_0_3V3AUX_SCL")
		)
		(pad "2" smd circle
			(at 0.40005 0)
			(size 0 0)
			(layers "F.Cu" "F.Mask" "F.Paste")
			(net "SMB_HSC_TYPE_ADC_SCL")
		)
	)
	(footprint ""
		(layer "F.Cu")
		(at 104.89946 -344.029284 90)
		(property "Reference" "PC588"
			(at 0 0 90)
			(layer "F.SilkS")
			(hide yes)
			(effects
				(font
					(size 1.27 1.27)
				)
			)
		)
		(property "Value" ""
			(at 0 0 90)
			(layer "F.Fab")
			(effects
				(font
					(size 1.27 1.27)
				)
			)
		)
		(duplicate_pad_numbers_are_jumpers no)
		(fp_line
			(start -3.400044 1.249934)
			(end 3.400044 1.249934)
			(stroke
				(width 0.1524)
				(type default)
			)
			(layer "F.SilkS")
		)
		(fp_circle
			(center 0 1.249934)
			(end 0 4.649978)
			(stroke
				(width 0.1524)
				(type default)
			)
			(fill no)
			(layer "F.SilkS")
		)
		(fp_poly
			(pts
				(arc
					(start -3.400044 1.249934)
					(mid 0 4.649978)
					(end 3.400044 1.249934)
				)
			)
			(stroke
				(width 0)
				(type default)
			)
			(fill yes)
			(layer "F.SilkS")
		)
		(fp_circle
			(center 0 1.249934)
			(end 0 4.649978)
			(stroke
				(width 0.1)
				(type default)
			)
			(fill no)
			(layer "F.Fab")
		)
		(pad "1" thru_hole rect
			(at 0 0 90)
			(size 1.524 1.524)
			(drill 1.016)
			(layers "*.Cu" "*.Mask")
			(remove_unused_layers no)
			(net "SW_P12V_PVCCIN_CPU1_FLT")
			(clearance 0)
			(padstack
				(mode front_inner_back)
				(layer "Inner"
					(shape circle)
					(size 1.524 1.524)
					(clearance 0)
				)
				(layer "B.Cu"
					(shape rect)
					(size 1.524 1.524)
					(clearance 0)
				)
			)
		)
		(pad "2" thru_hole circle
			(at 0 2.500122 90)
			(size 1.524 1.524)
			(drill 1.016)
			(layers "*.Cu" "*.Mask")
			(remove_unused_layers no)
			(net "GND")
			(clearance 0)
		)
	)
	(footprint ""
		(layer "F.Cu")
		(at 357.683816 -336.192368 90)
		(property "Reference" "PC271"
			(at 0 0 90)
			(layer "F.SilkS")
			(hide yes)
			(effects
				(font
					(size 1.27 1.27)
				)
			)
		)
		(property "Value" ""
			(at 0 0 90)
			(layer "F.Fab")
			(effects
				(font
					(size 1.27 1.27)
				)
			)
		)
		(duplicate_pad_numbers_are_jumpers no)
		(fp_line
			(start 0.7874 -0.4064)
			(end 0.7874 0.4064)
			(stroke
				(width 0.1524)
				(type default)
			)
			(layer "F.SilkS")
		)
		(fp_line
			(start -0.7874 -0.4064)
			(end 0.7874 -0.4064)
			(stroke
				(width 0.1524)
				(type default)
			)
			(layer "F.SilkS")
		)
		(fp_line
			(start 0.7874 0.4064)
			(end -0.7874 0.4064)
			(stroke
				(width 0.1524)
				(type default)
			)
			(layer "F.SilkS")
		)
		(fp_line
			(start -0.7874 0.4064)
			(end -0.7874 -0.4064)
			(stroke
				(width 0.1524)
				(type default)
			)
			(layer "F.SilkS")
		)
		(fp_line
			(start -0.12065 -0.305054)
			(end -0.12065 -0.2794)
			(stroke
				(width 0.1)
				(type default)
			)
			(layer "F.Fab")
		)
		(fp_line
			(start -0.67945 -0.305054)
			(end -0.12065 -0.305054)
			(stroke
				(width 0.1)
				(type default)
			)
			(layer "F.Fab")
		)
		(fp_line
			(start 0.67945 -0.3048)
			(end 0.67945 0.3048)
			(stroke
				(width 0.1)
				(type default)
			)
			(layer "F.Fab")
		)
		(fp_line
			(start 0.12065 -0.3048)
			(end 0.67945 -0.3048)
			(stroke
				(width 0.1)
				(type default)
			)
			(layer "F.Fab")
		)
		(fp_line
			(start 0.12065 -0.2794)
			(end 0.12065 -0.3048)
			(stroke
				(width 0.1)
				(type default)
			)
			(layer "F.Fab")
		)
		(fp_line
			(start -0.12065 -0.2794)
			(end 0.12065 -0.2794)
			(stroke
				(width 0.1)
				(type default)
			)
			(layer "F.Fab")
		)
		(fp_line
			(start 0.120396 0.2794)
			(end -0.12065 0.2794)
			(stroke
				(width 0.1)
				(type default)
			)
			(layer "F.Fab")
		)
		(fp_line
			(start -0.12065 0.2794)
			(end -0.12065 0.3048)
			(stroke
				(width 0.1)
				(type default)
			)
			(layer "F.Fab")
		)
		(fp_line
			(start 0.67945 0.3048)
			(end 0.120396 0.3048)
			(stroke
				(width 0.1)
				(type default)
			)
			(layer "F.Fab")
		)
		(fp_line
			(start 0.120396 0.3048)
			(end 0.120396 0.2794)
			(stroke
				(width 0.1)
				(type default)
			)
			(layer "F.Fab")
		)
		(fp_line
			(start -0.12065 0.3048)
			(end -0.67945 0.3048)
			(stroke
				(width 0.1)
				(type default)
			)
			(layer "F.Fab")
		)
		(fp_line
			(start -0.67945 0.3048)
			(end -0.67945 -0.305054)
			(stroke
				(width 0.1)
				(type default)
			)
			(layer "F.Fab")
		)
		(pad "1" smd circle
			(at -0.40005 0 90)
			(size 0 0)
			(layers "F.Cu" "F.Mask" "F.Paste")
			(net "PVCCIN_CPU0_VDD3")
		)
		(pad "2" smd circle
			(at 0.40005 0 90)
			(size 0 0)
			(layers "F.Cu" "F.Mask" "F.Paste")
			(net "GND")
		)
	)
	(footprint ""
		(layer "F.Cu")
		(at 122.636534 -40.351456)
		(property "Reference" "C1882"
			(at 0 0 0)
			(layer "F.SilkS")
			(hide yes)
			(effects
				(font
					(size 1.27 1.27)
				)
			)
		)
		(property "Value" ""
			(at 0 0 0)
			(layer "F.Fab")
			(effects
				(font
					(size 1.27 1.27)
				)
			)
		)
		(duplicate_pad_numbers_are_jumpers no)
		(fp_line
			(start -0.7874 -0.4064)
			(end 0.7874 -0.4064)
			(stroke
				(width 0.1524)
				(type default)
			)
			(layer "F.SilkS")
		)
		(fp_line
			(start -0.7874 0.4064)
			(end -0.7874 -0.4064)
			(stroke
				(width 0.1524)
				(type default)
			)
			(layer "F.SilkS")
		)
		(fp_line
			(start 0.7874 -0.4064)
			(end 0.7874 0.4064)
			(stroke
				(width 0.1524)
				(type default)
			)
			(layer "F.SilkS")
		)
		(fp_line
			(start 0.7874 0.4064)
			(end -0.7874 0.4064)
			(stroke
				(width 0.1524)
				(type default)
			)
			(layer "F.SilkS")
		)
		(fp_line
			(start -0.67945 -0.305054)
			(end -0.12065 -0.305054)
			(stroke
				(width 0.1)
				(type default)
			)
			(layer "F.Fab")
		)
		(fp_line
			(start -0.67945 0.3048)
			(end -0.67945 -0.305054)
			(stroke
				(width 0.1)
				(type default)
			)
			(layer "F.Fab")
		)
		(fp_line
			(start -0.12065 -0.305054)
			(end -0.12065 -0.2794)
			(stroke
				(width 0.1)
				(type default)
			)
			(layer "F.Fab")
		)
		(fp_line
			(start -0.12065 -0.2794)
			(end 0.12065 -0.2794)
			(stroke
				(width 0.1)
				(type default)
			)
			(layer "F.Fab")
		)
		(fp_line
			(start -0.12065 0.2794)
			(end -0.12065 0.3048)
			(stroke
				(width 0.1)
				(type default)
			)
			(layer "F.Fab")
		)
		(fp_line
			(start -0.12065 0.3048)
			(end -0.67945 0.3048)
			(stroke
				(width 0.1)
				(type default)
			)
			(layer "F.Fab")
		)
		(fp_line
			(start 0.120396 0.2794)
			(end -0.12065 0.2794)
			(stroke
				(width 0.1)
				(type default)
			)
			(layer "F.Fab")
		)
		(fp_line
			(start 0.120396 0.3048)
			(end 0.120396 0.2794)
			(stroke
				(width 0.1)
				(type default)
			)
			(layer "F.Fab")
		)
		(fp_line
			(start 0.12065 -0.3048)
			(end 0.67945 -0.3048)
			(stroke
				(width 0.1)
				(type default)
			)
			(layer "F.Fab")
		)
		(fp_line
			(start 0.12065 -0.2794)
			(end 0.12065 -0.3048)
			(stroke
				(width 0.1)
				(type default)
			)
			(layer "F.Fab")
		)
		(fp_line
			(start 0.67945 -0.3048)
			(end 0.67945 0.3048)
			(stroke
				(width 0.1)
				(type default)
			)
			(layer "F.Fab")
		)
		(fp_line
			(start 0.67945 0.3048)
			(end 0.120396 0.3048)
			(stroke
				(width 0.1)
				(type default)
			)
			(layer "F.Fab")
		)
		(pad "1" smd circle
			(at -0.40005 0)
			(size 0 0)
			(layers "F.Cu" "F.Mask" "F.Paste")
			(net "P3V3_AUX")
		)
		(pad "2" smd circle
			(at 0.40005 0)
			(size 0 0)
			(layers "F.Cu" "F.Mask" "F.Paste")
			(net "GND")
		)
	)
	(footprint ""
		(layer "F.Cu")
		(at 263.542526 -94.888558)
		(property "Reference" "C108"
			(at 0 0 0)
			(layer "F.SilkS")
			(hide yes)
			(effects
				(font
					(size 1.27 1.27)
				)
			)
		)
		(property "Value" ""
			(at 0 0 0)
			(layer "F.Fab")
			(effects
				(font
					(size 1.27 1.27)
				)
			)
		)
		(duplicate_pad_numbers_are_jumpers no)
		(fp_line
			(start -1.2954 -0.5842)
			(end 1.2954 -0.5842)
			(stroke
				(width 0.1524)
				(type default)
			)
			(layer "F.SilkS")
		)
		(fp_line
			(start -1.2954 0.5842)
			(end -1.2954 -0.5842)
			(stroke
				(width 0.1524)
				(type default)
			)
			(layer "F.SilkS")
		)
		(fp_line
			(start 0 -0.5842)
			(end 0 0.5842)
			(stroke
				(width 0.1524)
				(type default)
			)
			(layer "F.SilkS")
		)
		(fp_line
			(start 1.2954 -0.5842)
			(end 1.2954 0.5842)
			(stroke
				(width 0.1524)
				(type default)
			)
			(layer "F.SilkS")
		)
		(fp_line
			(start 1.2954 0.5842)
			(end -1.2954 0.5842)
			(stroke
				(width 0.1524)
				(type default)
			)
			(layer "F.SilkS")
		)
		(fp_line
			(start -1.1938 -0.4064)
			(end -0.8636 -0.4064)
			(stroke
				(width 0.1)
				(type default)
			)
			(layer "F.Fab")
		)
		(fp_line
			(start -1.1938 0.4064)
			(end -1.1938 -0.4064)
			(stroke
				(width 0.1)
				(type default)
			)
			(layer "F.Fab")
		)
		(fp_line
			(start -0.8636 -0.4572)
			(end 0.8636 -0.4572)
			(stroke
				(width 0.1)
				(type default)
			)
			(layer "F.Fab")
		)
		(fp_line
			(start -0.8636 -0.4064)
			(end -0.8636 -0.4572)
			(stroke
				(width 0.1)
				(type default)
			)
			(layer "F.Fab")
		)
		(fp_line
			(start -0.8636 0.4064)
			(end -1.1938 0.4064)
			(stroke
				(width 0.1)
				(type default)
			)
			(layer "F.Fab")
		)
		(fp_line
			(start -0.8636 0.4572)
			(end -0.8636 0.4064)
			(stroke
				(width 0.1)
				(type default)
			)
			(layer "F.Fab")
		)
		(fp_line
			(start 0.8636 -0.4572)
			(end 0.8636 -0.4064)
			(stroke
				(width 0.1)
				(type default)
			)
			(layer "F.Fab")
		)
		(fp_line
			(start 0.8636 -0.4064)
			(end 1.1938 -0.4064)
			(stroke
				(width 0.1)
				(type default)
			)
			(layer "F.Fab")
		)
		(fp_line
			(start 0.8636 0.4064)
			(end 0.8636 0.4572)
			(stroke
				(width 0.1)
				(type default)
			)
			(layer "F.Fab")
		)
		(fp_line
			(start 0.8636 0.4572)
			(end -0.8636 0.4572)
			(stroke
				(width 0.1)
				(type default)
			)
			(layer "F.Fab")
		)
		(fp_line
			(start 1.1938 -0.4064)
			(end 1.1938 0.4064)
			(stroke
				(width 0.1)
				(type default)
			)
			(layer "F.Fab")
		)
		(fp_line
			(start 1.1938 0.4064)
			(end 0.8636 0.4064)
			(stroke
				(width 0.1)
				(type default)
			)
			(layer "F.Fab")
		)
		(pad "1" smd rect
			(at -0.7366 0 270)
			(size 0.7112 0.8128)
			(layers "F.Cu" "F.Mask" "F.Paste")
			(net "P3V3_AUX_CLK_GEN_VDD_CK440")
		)
		(pad "2" smd rect
			(at 0.7366 0 270)
			(size 0.7112 0.8128)
			(layers "F.Cu" "F.Mask" "F.Paste")
			(net "GND")
		)
	)
	(footprint ""
		(layer "F.Cu")
		(at 38.812724 -358.129586 -90)
		(property "Reference" "PC1370"
			(at 0 0 270)
			(layer "F.SilkS")
			(hide yes)
			(effects
				(font
					(size 1.27 1.27)
				)
			)
		)
		(property "Value" ""
			(at 0 0 270)
			(layer "F.Fab")
			(effects
				(font
					(size 1.27 1.27)
				)
			)
		)
		(duplicate_pad_numbers_are_jumpers no)
		(fp_line
			(start -0.7874 0.4064)
			(end -0.7874 -0.4064)
			(stroke
				(width 0.1524)
				(type default)
			)
			(layer "F.SilkS")
		)
		(fp_line
			(start 0.7874 0.4064)
			(end -0.7874 0.4064)
			(stroke
				(width 0.1524)
				(type default)
			)
			(layer "F.SilkS")
		)
		(fp_line
			(start -0.7874 -0.4064)
			(end 0.7874 -0.4064)
			(stroke
				(width 0.1524)
				(type default)
			)
			(layer "F.SilkS")
		)
		(fp_line
			(start 0.7874 -0.4064)
			(end 0.7874 0.4064)
			(stroke
				(width 0.1524)
				(type default)
			)
			(layer "F.SilkS")
		)
		(fp_line
			(start -0.67945 0.3048)
			(end -0.67945 -0.305054)
			(stroke
				(width 0.1)
				(type default)
			)
			(layer "F.Fab")
		)
		(fp_line
			(start -0.12065 0.3048)
			(end -0.67945 0.3048)
			(stroke
				(width 0.1)
				(type default)
			)
			(layer "F.Fab")
		)
		(fp_line
			(start 0.120396 0.3048)
			(end 0.120396 0.2794)
			(stroke
				(width 0.1)
				(type default)
			)
			(layer "F.Fab")
		)
		(fp_line
			(start 0.67945 0.3048)
			(end 0.120396 0.3048)
			(stroke
				(width 0.1)
				(type default)
			)
			(layer "F.Fab")
		)
		(fp_line
			(start -0.12065 0.2794)
			(end -0.12065 0.3048)
			(stroke
				(width 0.1)
				(type default)
			)
			(layer "F.Fab")
		)
		(fp_line
			(start 0.120396 0.2794)
			(end -0.12065 0.2794)
			(stroke
				(width 0.1)
				(type default)
			)
			(layer "F.Fab")
		)
		(fp_line
			(start -0.12065 -0.2794)
			(end 0.12065 -0.2794)
			(stroke
				(width 0.1)
				(type default)
			)
			(layer "F.Fab")
		)
		(fp_line
			(start 0.12065 -0.2794)
			(end 0.12065 -0.3048)
			(stroke
				(width 0.1)
				(type default)
			)
			(layer "F.Fab")
		)
		(fp_line
			(start 0.12065 -0.3048)
			(end 0.67945 -0.3048)
			(stroke
				(width 0.1)
				(type default)
			)
			(layer "F.Fab")
		)
		(fp_line
			(start 0.67945 -0.3048)
			(end 0.67945 0.3048)
			(stroke
				(width 0.1)
				(type default)
			)
			(layer "F.Fab")
		)
		(fp_line
			(start -0.67945 -0.305054)
			(end -0.12065 -0.305054)
			(stroke
				(width 0.1)
				(type default)
			)
			(layer "F.Fab")
		)
		(fp_line
			(start -0.12065 -0.305054)
			(end -0.12065 -0.2794)
			(stroke
				(width 0.1)
				(type default)
			)
			(layer "F.Fab")
		)
		(pad "1" smd circle
			(at -0.40005 0 270)
			(size 0 0)
			(layers "F.Cu" "F.Mask" "F.Paste")
			(net "GND")
		)
		(pad "2" smd circle
			(at 0.40005 0 270)
			(size 0 0)
			(layers "F.Cu" "F.Mask" "F.Paste")
			(net "PVCCIN_CPU1_VREF")
		)
	)
	(footprint ""
		(layer "F.Cu")
		(at 74.106786 -65.082674 -90)
		(property "Reference" "R3079"
			(at 0 0 270)
			(layer "F.SilkS")
			(hide yes)
			(effects
				(font
					(size 1.27 1.27)
				)
			)
		)
		(property "Value" ""
			(at 0 0 270)
			(layer "F.Fab")
			(effects
				(font
					(size 1.27 1.27)
				)
			)
		)
		(duplicate_pad_numbers_are_jumpers no)
		(fp_line
			(start -0.7874 0.4064)
			(end -0.7874 -0.4064)
			(stroke
				(width 0.1524)
				(type default)
			)
			(layer "F.SilkS")
		)
		(fp_line
			(start 0.7874 0.4064)
			(end -0.7874 0.4064)
			(stroke
				(width 0.1524)
				(type default)
			)
			(layer "F.SilkS")
		)
		(fp_line
			(start -0.7874 -0.4064)
			(end 0.7874 -0.4064)
			(stroke
				(width 0.1524)
				(type default)
			)
			(layer "F.SilkS")
		)
		(fp_line
			(start 0.7874 -0.4064)
			(end 0.7874 0.4064)
			(stroke
				(width 0.1524)
				(type default)
			)
			(layer "F.SilkS")
		)
		(fp_line
			(start -0.67945 0.3048)
			(end -0.67945 -0.305054)
			(stroke
				(width 0.1)
				(type default)
			)
			(layer "F.Fab")
		)
		(fp_line
			(start -0.12065 0.3048)
			(end -0.67945 0.3048)
			(stroke
				(width 0.1)
				(type default)
			)
			(layer "F.Fab")
		)
		(fp_line
			(start 0.120396 0.3048)
			(end 0.120396 0.2794)
			(stroke
				(width 0.1)
				(type default)
			)
			(layer "F.Fab")
		)
		(fp_line
			(start 0.67945 0.3048)
			(end 0.120396 0.3048)
			(stroke
				(width 0.1)
				(type default)
			)
			(layer "F.Fab")
		)
		(fp_line
			(start -0.12065 0.2794)
			(end -0.12065 0.3048)
			(stroke
				(width 0.1)
				(type default)
			)
			(layer "F.Fab")
		)
		(fp_line
			(start 0.120396 0.2794)
			(end -0.12065 0.2794)
			(stroke
				(width 0.1)
				(type default)
			)
			(layer "F.Fab")
		)
		(fp_line
			(start -0.12065 -0.2794)
			(end 0.12065 -0.2794)
			(stroke
				(width 0.1)
				(type default)
			)
			(layer "F.Fab")
		)
		(fp_line
			(start 0.12065 -0.2794)
			(end 0.12065 -0.3048)
			(stroke
				(width 0.1)
				(type default)
			)
			(layer "F.Fab")
		)
		(fp_line
			(start 0.12065 -0.3048)
			(end 0.67945 -0.3048)
			(stroke
				(width 0.1)
				(type default)
			)
			(layer "F.Fab")
		)
		(fp_line
			(start 0.67945 -0.3048)
			(end 0.67945 0.3048)
			(stroke
				(width 0.1)
				(type default)
			)
			(layer "F.Fab")
		)
		(fp_line
			(start -0.67945 -0.305054)
			(end -0.12065 -0.305054)
			(stroke
				(width 0.1)
				(type default)
			)
			(layer "F.Fab")
		)
		(fp_line
			(start -0.12065 -0.305054)
			(end -0.12065 -0.2794)
			(stroke
				(width 0.1)
				(type default)
			)
			(layer "F.Fab")
		)
		(pad "1" smd circle
			(at -0.40005 0 270)
			(size 0 0)
			(layers "F.Cu" "F.Mask" "F.Paste")
			(net "LED_RST_PLD_CPU0_DRAM_EF_N")
		)
		(pad "2" smd circle
			(at 0.40005 0 270)
			(size 0 0)
			(layers "F.Cu" "F.Mask" "F.Paste")
			(net "P3V3_AUX")
		)
	)
	(footprint ""
		(layer "F.Cu")
		(at 79.501238 -402.371052 -90)
		(property "Reference" "C731"
			(at 0 0 270)
			(layer "F.SilkS")
			(hide yes)
			(effects
				(font
					(size 1.27 1.27)
				)
			)
		)
		(property "Value" ""
			(at 0 0 270)
			(layer "F.Fab")
			(effects
				(font
					(size 1.27 1.27)
				)
			)
		)
		(duplicate_pad_numbers_are_jumpers no)
		(fp_line
			(start -0.299974 0.150114)
			(end -0.299974 -0.150114)
			(stroke
				(width 0.1)
				(type default)
			)
			(layer "F.Fab")
		)
		(fp_line
			(start 0.299974 0.150114)
			(end -0.299974 0.150114)
			(stroke
				(width 0.1)
				(type default)
			)
			(layer "F.Fab")
		)
		(fp_line
			(start -0.299974 -0.150114)
			(end 0.299974 -0.150114)
			(stroke
				(width 0.1)
				(type default)
			)
			(layer "F.Fab")
		)
		(fp_line
			(start 0.299974 -0.150114)
			(end 0.299974 0.150114)
			(stroke
				(width 0.1)
				(type default)
			)
			(layer "F.Fab")
		)
		(pad "1" smd rect
			(at -0.2667 0 270)
			(size 0.3048 0.381)
			(layers "F.Cu" "F.Mask" "F.Paste")
			(net "P5E_CPU1_PE0_TX_C_DP<5>")
		)
		(pad "2" smd rect
			(at 0.2667 0 270)
			(size 0.3048 0.381)
			(layers "F.Cu" "F.Mask" "F.Paste")
			(net "P5E_CPU1_PE0_TX_DP<5>")
		)
	)
	(footprint ""
		(layer "F.Cu")
		(at 193.60388 -103.685848 180)
		(property "Reference" "R3045"
			(at 0 0 180)
			(layer "F.SilkS")
			(hide yes)
			(effects
				(font
					(size 1.27 1.27)
				)
			)
		)
		(property "Value" ""
			(at 0 0 180)
			(layer "F.Fab")
			(effects
				(font
					(size 1.27 1.27)
				)
			)
		)
		(duplicate_pad_numbers_are_jumpers no)
		(fp_line
			(start 0.7874 0.4064)
			(end -0.7874 0.4064)
			(stroke
				(width 0.1524)
				(type default)
			)
			(layer "F.SilkS")
		)
		(fp_line
			(start 0.7874 -0.4064)
			(end 0.7874 0.4064)
			(stroke
				(width 0.1524)
				(type default)
			)
			(layer "F.SilkS")
		)
		(fp_line
			(start -0.7874 0.4064)
			(end -0.7874 -0.4064)
			(stroke
				(width 0.1524)
				(type default)
			)
			(layer "F.SilkS")
		)
		(fp_line
			(start -0.7874 -0.4064)
			(end 0.7874 -0.4064)
			(stroke
				(width 0.1524)
				(type default)
			)
			(layer "F.SilkS")
		)
		(fp_line
			(start 0.67945 0.3048)
			(end 0.120396 0.3048)
			(stroke
				(width 0.1)
				(type default)
			)
			(layer "F.Fab")
		)
		(fp_line
			(start 0.67945 -0.3048)
			(end 0.67945 0.3048)
			(stroke
				(width 0.1)
				(type default)
			)
			(layer "F.Fab")
		)
		(fp_line
			(start 0.12065 -0.2794)
			(end 0.12065 -0.3048)
			(stroke
				(width 0.1)
				(type default)
			)
			(layer "F.Fab")
		)
		(fp_line
			(start 0.12065 -0.3048)
			(end 0.67945 -0.3048)
			(stroke
				(width 0.1)
				(type default)
			)
			(layer "F.Fab")
		)
		(fp_line
			(start 0.120396 0.3048)
			(end 0.120396 0.2794)
			(stroke
				(width 0.1)
				(type default)
			)
			(layer "F.Fab")
		)
		(fp_line
			(start 0.120396 0.2794)
			(end -0.12065 0.2794)
			(stroke
				(width 0.1)
				(type default)
			)
			(layer "F.Fab")
		)
		(fp_line
			(start -0.12065 0.3048)
			(end -0.67945 0.3048)
			(stroke
				(width 0.1)
				(type default)
			)
			(layer "F.Fab")
		)
		(fp_line
			(start -0.12065 0.2794)
			(end -0.12065 0.3048)
			(stroke
				(width 0.1)
				(type default)
			)
			(layer "F.Fab")
		)
		(fp_line
			(start -0.12065 -0.2794)
			(end 0.12065 -0.2794)
			(stroke
				(width 0.1)
				(type default)
			)
			(layer "F.Fab")
		)
		(fp_line
			(start -0.12065 -0.305054)
			(end -0.12065 -0.2794)
			(stroke
				(width 0.1)
				(type default)
			)
			(layer "F.Fab")
		)
		(fp_line
			(start -0.67945 0.3048)
			(end -0.67945 -0.305054)
			(stroke
				(width 0.1)
				(type default)
			)
			(layer "F.Fab")
		)
		(fp_line
			(start -0.67945 -0.305054)
			(end -0.12065 -0.305054)
			(stroke
				(width 0.1)
				(type default)
			)
			(layer "F.Fab")
		)
		(pad "1" smd circle
			(at -0.40005 0 180)
			(size 0 0)
			(layers "F.Cu" "F.Mask" "F.Paste")
			(net "IRQ_UV_DETECT_N")
		)
		(pad "2" smd circle
			(at 0.40005 0 180)
			(size 0 0)
			(layers "F.Cu" "F.Mask" "F.Paste")
			(net "IRQ_UV_DETECT_R_N")
		)
	)
	(footprint ""
		(layer "F.Cu")
		(at 106.70921 -413.687768 180)
		(property "Reference" "R3354"
			(at 0 0 180)
			(layer "F.SilkS")
			(hide yes)
			(effects
				(font
					(size 1.27 1.27)
				)
			)
		)
		(property "Value" ""
			(at 0 0 180)
			(layer "F.Fab")
			(effects
				(font
					(size 1.27 1.27)
				)
			)
		)
		(duplicate_pad_numbers_are_jumpers no)
		(fp_line
			(start 0.7874 0.4064)
			(end -0.7874 0.4064)
			(stroke
				(width 0.1524)
				(type default)
			)
			(layer "F.SilkS")
		)
		(fp_line
			(start 0.7874 0.01016)
			(end 0.7874 0.4064)
			(stroke
				(width 0.1524)
				(type default)
			)
			(layer "F.SilkS")
		)
		(fp_line
			(start -0.40767 -0.4064)
			(end 0.44323 -0.4064)
			(stroke
				(width 0.1524)
				(type default)
			)
			(layer "F.SilkS")
		)
		(fp_line
			(start -0.7874 0.4064)
			(end -0.7874 -0.03556)
			(stroke
				(width 0.1524)
				(type default)
			)
			(layer "F.SilkS")
		)
		(fp_line
			(start 0.67945 0.3048)
			(end 0.120396 0.3048)
			(stroke
				(width 0.1)
				(type default)
			)
			(layer "F.Fab")
		)
		(fp_line
			(start 0.67945 -0.3048)
			(end 0.67945 0.3048)
			(stroke
				(width 0.1)
				(type default)
			)
			(layer "F.Fab")
		)
		(fp_line
			(start 0.12065 -0.2794)
			(end 0.12065 -0.3048)
			(stroke
				(width 0.1)
				(type default)
			)
			(layer "F.Fab")
		)
		(fp_line
			(start 0.12065 -0.3048)
			(end 0.67945 -0.3048)
			(stroke
				(width 0.1)
				(type default)
			)
			(layer "F.Fab")
		)
		(fp_line
			(start 0.120396 0.3048)
			(end 0.120396 0.2794)
			(stroke
				(width 0.1)
				(type default)
			)
			(layer "F.Fab")
		)
		(fp_line
			(start 0.120396 0.2794)
			(end -0.12065 0.2794)
			(stroke
				(width 0.1)
				(type default)
			)
			(layer "F.Fab")
		)
		(fp_line
			(start -0.12065 0.3048)
			(end -0.67945 0.3048)
			(stroke
				(width 0.1)
				(type default)
			)
			(layer "F.Fab")
		)
		(fp_line
			(start -0.12065 0.2794)
			(end -0.12065 0.3048)
			(stroke
				(width 0.1)
				(type default)
			)
			(layer "F.Fab")
		)
		(fp_line
			(start -0.12065 -0.2794)
			(end 0.12065 -0.2794)
			(stroke
				(width 0.1)
				(type default)
			)
			(layer "F.Fab")
		)
		(fp_line
			(start -0.12065 -0.305054)
			(end -0.12065 -0.2794)
			(stroke
				(width 0.1)
				(type default)
			)
			(layer "F.Fab")
		)
		(fp_line
			(start -0.67945 0.3048)
			(end -0.67945 -0.305054)
			(stroke
				(width 0.1)
				(type default)
			)
			(layer "F.Fab")
		)
		(fp_line
			(start -0.67945 -0.305054)
			(end -0.12065 -0.305054)
			(stroke
				(width 0.1)
				(type default)
			)
			(layer "F.Fab")
		)
		(pad "1" smd circle
			(at -0.40005 0 180)
			(size 0 0)
			(layers "F.Cu" "F.Mask" "F.Paste")
			(net "CLK_100M_GPU_2_R_DP")
		)
		(pad "2" smd circle
			(at 0.40005 0 180)
			(size 0 0)
			(layers "F.Cu" "F.Mask" "F.Paste")
			(net "CLK_100M_GPU_2_DP")
		)
	)
	(footprint ""
		(layer "F.Cu")
		(at 228.410008 -402.994622 90)
		(property "Reference" "PC2223"
			(at 0 0 90)
			(layer "F.SilkS")
			(hide yes)
			(effects
				(font
					(size 1.27 1.27)
				)
			)
		)
		(property "Value" ""
			(at 0 0 90)
			(layer "F.Fab")
			(effects
				(font
					(size 1.27 1.27)
				)
			)
		)
		(duplicate_pad_numbers_are_jumpers no)
		(fp_line
			(start 0.7874 -0.4064)
			(end 0.7874 0.4064)
			(stroke
				(width 0.1524)
				(type default)
			)
			(layer "F.SilkS")
		)
		(fp_line
			(start -0.7874 -0.4064)
			(end 0.7874 -0.4064)
			(stroke
				(width 0.1524)
				(type default)
			)
			(layer "F.SilkS")
		)
		(fp_line
			(start 0.7874 0.4064)
			(end -0.7874 0.4064)
			(stroke
				(width 0.1524)
				(type default)
			)
			(layer "F.SilkS")
		)
		(fp_line
			(start -0.7874 0.4064)
			(end -0.7874 -0.4064)
			(stroke
				(width 0.1524)
				(type default)
			)
			(layer "F.SilkS")
		)
		(fp_line
			(start -0.12065 -0.305054)
			(end -0.12065 -0.2794)
			(stroke
				(width 0.1)
				(type default)
			)
			(layer "F.Fab")
		)
		(fp_line
			(start -0.67945 -0.305054)
			(end -0.12065 -0.305054)
			(stroke
				(width 0.1)
				(type default)
			)
			(layer "F.Fab")
		)
		(fp_line
			(start 0.67945 -0.3048)
			(end 0.67945 0.3048)
			(stroke
				(width 0.1)
				(type default)
			)
			(layer "F.Fab")
		)
		(fp_line
			(start 0.12065 -0.3048)
			(end 0.67945 -0.3048)
			(stroke
				(width 0.1)
				(type default)
			)
			(layer "F.Fab")
		)
		(fp_line
			(start 0.12065 -0.2794)
			(end 0.12065 -0.3048)
			(stroke
				(width 0.1)
				(type default)
			)
			(layer "F.Fab")
		)
		(fp_line
			(start -0.12065 -0.2794)
			(end 0.12065 -0.2794)
			(stroke
				(width 0.1)
				(type default)
			)
			(layer "F.Fab")
		)
		(fp_line
			(start 0.120396 0.2794)
			(end -0.12065 0.2794)
			(stroke
				(width 0.1)
				(type default)
			)
			(layer "F.Fab")
		)
		(fp_line
			(start -0.12065 0.2794)
			(end -0.12065 0.3048)
			(stroke
				(width 0.1)
				(type default)
			)
			(layer "F.Fab")
		)
		(fp_line
			(start 0.67945 0.3048)
			(end 0.120396 0.3048)
			(stroke
				(width 0.1)
				(type default)
			)
			(layer "F.Fab")
		)
		(fp_line
			(start 0.120396 0.3048)
			(end 0.120396 0.2794)
			(stroke
				(width 0.1)
				(type default)
			)
			(layer "F.Fab")
		)
		(fp_line
			(start -0.12065 0.3048)
			(end -0.67945 0.3048)
			(stroke
				(width 0.1)
				(type default)
			)
			(layer "F.Fab")
		)
		(fp_line
			(start -0.67945 0.3048)
			(end -0.67945 -0.305054)
			(stroke
				(width 0.1)
				(type default)
			)
			(layer "F.Fab")
		)
		(pad "1" smd circle
			(at -0.40005 0 90)
			(size 0 0)
			(layers "F.Cu" "F.Mask" "F.Paste")
			(net "HSC_VDD_R_4")
		)
		(pad "2" smd circle
			(at 0.40005 0 90)
			(size 0 0)
			(layers "F.Cu" "F.Mask" "F.Paste")
			(net "AGND_HSC")
		)
	)
	(footprint ""
		(layer "F.Cu")
		(at 236.649768 -352.49993)
		(property "Reference" "H95"
			(at -5.03682 -5.100828 0)
			(unlocked yes)
			(layer "F.SilkS")
			(effects
				(font
					(size 0.7874 0.5842)
					(thickness 0.1524)
				)
				(justify left)
			)
		)
		(property "Value" ""
			(at 0 0 0)
			(layer "F.Fab")
			(effects
				(font
					(size 1.27 1.27)
				)
			)
		)
		(duplicate_pad_numbers_are_jumpers no)
		(pad "1" thru_hole circle
			(at 0 0)
			(size 10.0076 10.0076)
			(drill 5.6134)
			(layers "*.Cu" "*.Mask")
			(remove_unused_layers no)
			(net "GND")
			(clearance -1.9431)
		)
	)
	(footprint ""
		(layer "F.Cu")
		(at 387.62813 -402.371052 -90)
		(property "Reference" "C944"
			(at 0 0 270)
			(layer "F.SilkS")
			(hide yes)
			(effects
				(font
					(size 1.27 1.27)
				)
			)
		)
		(property "Value" ""
			(at 0 0 270)
			(layer "F.Fab")
			(effects
				(font
					(size 1.27 1.27)
				)
			)
		)
		(duplicate_pad_numbers_are_jumpers no)
		(fp_line
			(start -0.299974 0.150114)
			(end -0.299974 -0.150114)
			(stroke
				(width 0.1)
				(type default)
			)
			(layer "F.Fab")
		)
		(fp_line
			(start 0.299974 0.150114)
			(end -0.299974 0.150114)
			(stroke
				(width 0.1)
				(type default)
			)
			(layer "F.Fab")
		)
		(fp_line
			(start -0.299974 -0.150114)
			(end 0.299974 -0.150114)
			(stroke
				(width 0.1)
				(type default)
			)
			(layer "F.Fab")
		)
		(fp_line
			(start 0.299974 -0.150114)
			(end 0.299974 0.150114)
			(stroke
				(width 0.1)
				(type default)
			)
			(layer "F.Fab")
		)
		(pad "1" smd rect
			(at -0.2667 0 270)
			(size 0.3048 0.381)
			(layers "F.Cu" "F.Mask" "F.Paste")
			(net "P5E_CPU0_PE2_TX_C_DN<10>")
		)
		(pad "2" smd rect
			(at 0.2667 0 270)
			(size 0.3048 0.381)
			(layers "F.Cu" "F.Mask" "F.Paste")
			(net "P5E_CPU0_PE2_TX_DN<10>")
		)
	)
	(footprint ""
		(layer "F.Cu")
		(at 309.278528 -408.517344 -90)
		(property "Reference" "C905"
			(at 0 0 270)
			(layer "F.SilkS")
			(hide yes)
			(effects
				(font
					(size 1.27 1.27)
				)
			)
		)
		(property "Value" ""
			(at 0 0 270)
			(layer "F.Fab")
			(effects
				(font
					(size 1.27 1.27)
				)
			)
		)
		(duplicate_pad_numbers_are_jumpers no)
		(fp_line
			(start -0.299974 0.150114)
			(end -0.299974 -0.150114)
			(stroke
				(width 0.1)
				(type default)
			)
			(layer "F.Fab")
		)
		(fp_line
			(start 0.299974 0.150114)
			(end -0.299974 0.150114)
			(stroke
				(width 0.1)
				(type default)
			)
			(layer "F.Fab")
		)
		(fp_line
			(start -0.299974 -0.150114)
			(end 0.299974 -0.150114)
			(stroke
				(width 0.1)
				(type default)
			)
			(layer "F.Fab")
		)
		(fp_line
			(start 0.299974 -0.150114)
			(end 0.299974 0.150114)
			(stroke
				(width 0.1)
				(type default)
			)
			(layer "F.Fab")
		)
		(pad "1" smd rect
			(at -0.2667 0 270)
			(size 0.3048 0.381)
			(layers "F.Cu" "F.Mask" "F.Paste")
			(net "P5E_CPU0_PE0_TX_C_DP<14>")
		)
		(pad "2" smd rect
			(at 0.2667 0 270)
			(size 0.3048 0.381)
			(layers "F.Cu" "F.Mask" "F.Paste")
			(net "P5E_CPU0_PE0_TX_DP<14>")
		)
	)
	(footprint ""
		(layer "F.Cu")
		(at 374.275858 -421.525446 -90)
		(property "Reference" "C2010"
			(at 0 0 270)
			(layer "F.SilkS")
			(hide yes)
			(effects
				(font
					(size 1.27 1.27)
				)
			)
		)
		(property "Value" ""
			(at 0 0 270)
			(layer "F.Fab")
			(effects
				(font
					(size 1.27 1.27)
				)
			)
		)
		(duplicate_pad_numbers_are_jumpers no)
		(fp_line
			(start -0.7874 0.4064)
			(end -0.7874 -0.4064)
			(stroke
				(width 0.1524)
				(type default)
			)
			(layer "F.SilkS")
		)
		(fp_line
			(start 0.7874 0.4064)
			(end -0.7874 0.4064)
			(stroke
				(width 0.1524)
				(type default)
			)
			(layer "F.SilkS")
		)
		(fp_line
			(start -0.7874 -0.4064)
			(end 0.7874 -0.4064)
			(stroke
				(width 0.1524)
				(type default)
			)
			(layer "F.SilkS")
		)
		(fp_line
			(start 0.7874 -0.4064)
			(end 0.7874 0.4064)
			(stroke
				(width 0.1524)
				(type default)
			)
			(layer "F.SilkS")
		)
		(fp_line
			(start -0.67945 0.3048)
			(end -0.67945 -0.305054)
			(stroke
				(width 0.1)
				(type default)
			)
			(layer "F.Fab")
		)
		(fp_line
			(start -0.12065 0.3048)
			(end -0.67945 0.3048)
			(stroke
				(width 0.1)
				(type default)
			)
			(layer "F.Fab")
		)
		(fp_line
			(start 0.120396 0.3048)
			(end 0.120396 0.2794)
			(stroke
				(width 0.1)
				(type default)
			)
			(layer "F.Fab")
		)
		(fp_line
			(start 0.67945 0.3048)
			(end 0.120396 0.3048)
			(stroke
				(width 0.1)
				(type default)
			)
			(layer "F.Fab")
		)
		(fp_line
			(start -0.12065 0.2794)
			(end -0.12065 0.3048)
			(stroke
				(width 0.1)
				(type default)
			)
			(layer "F.Fab")
		)
		(fp_line
			(start 0.120396 0.2794)
			(end -0.12065 0.2794)
			(stroke
				(width 0.1)
				(type default)
			)
			(layer "F.Fab")
		)
		(fp_line
			(start -0.12065 -0.2794)
			(end 0.12065 -0.2794)
			(stroke
				(width 0.1)
				(type default)
			)
			(layer "F.Fab")
		)
		(fp_line
			(start 0.12065 -0.2794)
			(end 0.12065 -0.3048)
			(stroke
				(width 0.1)
				(type default)
			)
			(layer "F.Fab")
		)
		(fp_line
			(start 0.12065 -0.3048)
			(end 0.67945 -0.3048)
			(stroke
				(width 0.1)
				(type default)
			)
			(layer "F.Fab")
		)
		(fp_line
			(start 0.67945 -0.3048)
			(end 0.67945 0.3048)
			(stroke
				(width 0.1)
				(type default)
			)
			(layer "F.Fab")
		)
		(fp_line
			(start -0.67945 -0.305054)
			(end -0.12065 -0.305054)
			(stroke
				(width 0.1)
				(type default)
			)
			(layer "F.Fab")
		)
		(fp_line
			(start -0.12065 -0.305054)
			(end -0.12065 -0.2794)
			(stroke
				(width 0.1)
				(type default)
			)
			(layer "F.Fab")
		)
		(pad "1" smd circle
			(at -0.40005 0 270)
			(size 0 0)
			(layers "F.Cu" "F.Mask" "F.Paste")
			(net "P3V3_AUX")
		)
		(pad "2" smd circle
			(at 0.40005 0 270)
			(size 0 0)
			(layers "F.Cu" "F.Mask" "F.Paste")
			(net "GND")
		)
	)
	(footprint ""
		(layer "F.Cu")
		(at 263.55294 -133.005068 180)
		(property "Reference" "R4541"
			(at 0 0 180)
			(layer "F.SilkS")
			(hide yes)
			(effects
				(font
					(size 1.27 1.27)
				)
			)
		)
		(property "Value" ""
			(at 0 0 180)
			(layer "F.Fab")
			(effects
				(font
					(size 1.27 1.27)
				)
			)
		)
		(duplicate_pad_numbers_are_jumpers no)
		(fp_line
			(start 0.7874 0.4064)
			(end -0.7874 0.4064)
			(stroke
				(width 0.1524)
				(type default)
			)
			(layer "F.SilkS")
		)
		(fp_line
			(start 0.7874 -0.4064)
			(end 0.7874 0.4064)
			(stroke
				(width 0.1524)
				(type default)
			)
			(layer "F.SilkS")
		)
		(fp_line
			(start -0.7874 0.4064)
			(end -0.7874 -0.4064)
			(stroke
				(width 0.1524)
				(type default)
			)
			(layer "F.SilkS")
		)
		(fp_line
			(start -0.7874 -0.4064)
			(end 0.7874 -0.4064)
			(stroke
				(width 0.1524)
				(type default)
			)
			(layer "F.SilkS")
		)
		(fp_line
			(start 0.67945 0.3048)
			(end 0.120396 0.3048)
			(stroke
				(width 0.1)
				(type default)
			)
			(layer "F.Fab")
		)
		(fp_line
			(start 0.67945 -0.3048)
			(end 0.67945 0.3048)
			(stroke
				(width 0.1)
				(type default)
			)
			(layer "F.Fab")
		)
		(fp_line
			(start 0.12065 -0.2794)
			(end 0.12065 -0.3048)
			(stroke
				(width 0.1)
				(type default)
			)
			(layer "F.Fab")
		)
		(fp_line
			(start 0.12065 -0.3048)
			(end 0.67945 -0.3048)
			(stroke
				(width 0.1)
				(type default)
			)
			(layer "F.Fab")
		)
		(fp_line
			(start 0.120396 0.3048)
			(end 0.120396 0.2794)
			(stroke
				(width 0.1)
				(type default)
			)
			(layer "F.Fab")
		)
		(fp_line
			(start 0.120396 0.2794)
			(end -0.12065 0.2794)
			(stroke
				(width 0.1)
				(type default)
			)
			(layer "F.Fab")
		)
		(fp_line
			(start -0.12065 0.3048)
			(end -0.67945 0.3048)
			(stroke
				(width 0.1)
				(type default)
			)
			(layer "F.Fab")
		)
		(fp_line
			(start -0.12065 0.2794)
			(end -0.12065 0.3048)
			(stroke
				(width 0.1)
				(type default)
			)
			(layer "F.Fab")
		)
		(fp_line
			(start -0.12065 -0.2794)
			(end 0.12065 -0.2794)
			(stroke
				(width 0.1)
				(type default)
			)
			(layer "F.Fab")
		)
		(fp_line
			(start -0.12065 -0.305054)
			(end -0.12065 -0.2794)
			(stroke
				(width 0.1)
				(type default)
			)
			(layer "F.Fab")
		)
		(fp_line
			(start -0.67945 0.3048)
			(end -0.67945 -0.305054)
			(stroke
				(width 0.1)
				(type default)
			)
			(layer "F.Fab")
		)
		(fp_line
			(start -0.67945 -0.305054)
			(end -0.12065 -0.305054)
			(stroke
				(width 0.1)
				(type default)
			)
			(layer "F.Fab")
		)
		(pad "1" smd circle
			(at -0.40005 0 180)
			(size 0 0)
			(layers "F.Cu" "F.Mask" "F.Paste")
			(net "SMB_HOST_CLK_BUF_ISO_3V3AUX_S_2")
		)
		(pad "2" smd circle
			(at 0.40005 0 180)
			(size 0 0)
			(layers "F.Cu" "F.Mask" "F.Paste")
			(net "SMB_HOST_CLK_BUF_ISO_3V3AUX_SDA")
		)
	)
	(footprint ""
		(layer "F.Cu")
		(at 87.545926 -342.270334)
		(property "Reference" "PR291"
			(at 0 0 0)
			(layer "F.SilkS")
			(hide yes)
			(effects
				(font
					(size 1.27 1.27)
				)
			)
		)
		(property "Value" ""
			(at 0 0 0)
			(layer "F.Fab")
			(effects
				(font
					(size 1.27 1.27)
				)
			)
		)
		(duplicate_pad_numbers_are_jumpers no)
		(fp_line
			(start -0.7874 -0.4064)
			(end 0.7874 -0.4064)
			(stroke
				(width 0.1524)
				(type default)
			)
			(layer "F.SilkS")
		)
		(fp_line
			(start -0.7874 0.4064)
			(end -0.7874 -0.4064)
			(stroke
				(width 0.1524)
				(type default)
			)
			(layer "F.SilkS")
		)
		(fp_line
			(start 0.7874 -0.4064)
			(end 0.7874 0.4064)
			(stroke
				(width 0.1524)
				(type default)
			)
			(layer "F.SilkS")
		)
		(fp_line
			(start 0.7874 0.4064)
			(end -0.7874 0.4064)
			(stroke
				(width 0.1524)
				(type default)
			)
			(layer "F.SilkS")
		)
		(fp_line
			(start -0.67945 -0.305054)
			(end -0.12065 -0.305054)
			(stroke
				(width 0.1)
				(type default)
			)
			(layer "F.Fab")
		)
		(fp_line
			(start -0.67945 0.3048)
			(end -0.67945 -0.305054)
			(stroke
				(width 0.1)
				(type default)
			)
			(layer "F.Fab")
		)
		(fp_line
			(start -0.12065 -0.305054)
			(end -0.12065 -0.2794)
			(stroke
				(width 0.1)
				(type default)
			)
			(layer "F.Fab")
		)
		(fp_line
			(start -0.12065 -0.2794)
			(end 0.12065 -0.2794)
			(stroke
				(width 0.1)
				(type default)
			)
			(layer "F.Fab")
		)
		(fp_line
			(start -0.12065 0.2794)
			(end -0.12065 0.3048)
			(stroke
				(width 0.1)
				(type default)
			)
			(layer "F.Fab")
		)
		(fp_line
			(start -0.12065 0.3048)
			(end -0.67945 0.3048)
			(stroke
				(width 0.1)
				(type default)
			)
			(layer "F.Fab")
		)
		(fp_line
			(start 0.120396 0.2794)
			(end -0.12065 0.2794)
			(stroke
				(width 0.1)
				(type default)
			)
			(layer "F.Fab")
		)
		(fp_line
			(start 0.120396 0.3048)
			(end 0.120396 0.2794)
			(stroke
				(width 0.1)
				(type default)
			)
			(layer "F.Fab")
		)
		(fp_line
			(start 0.12065 -0.3048)
			(end 0.67945 -0.3048)
			(stroke
				(width 0.1)
				(type default)
			)
			(layer "F.Fab")
		)
		(fp_line
			(start 0.12065 -0.2794)
			(end 0.12065 -0.3048)
			(stroke
				(width 0.1)
				(type default)
			)
			(layer "F.Fab")
		)
		(fp_line
			(start 0.67945 -0.3048)
			(end 0.67945 0.3048)
			(stroke
				(width 0.1)
				(type default)
			)
			(layer "F.Fab")
		)
		(fp_line
			(start 0.67945 0.3048)
			(end 0.120396 0.3048)
			(stroke
				(width 0.1)
				(type default)
			)
			(layer "F.Fab")
		)
		(pad "1" smd circle
			(at -0.40005 0)
			(size 0 0)
			(layers "F.Cu" "F.Mask" "F.Paste")
			(net "PVCCIN_CPU1_LSET6")
		)
		(pad "2" smd circle
			(at 0.40005 0)
			(size 0 0)
			(layers "F.Cu" "F.Mask" "F.Paste")
			(net "GND")
		)
	)
	(footprint ""
		(layer "F.Cu")
		(at 51.593496 -112.33277)
		(property "Reference" "R3726"
			(at 0 0 0)
			(layer "F.SilkS")
			(hide yes)
			(effects
				(font
					(size 1.27 1.27)
				)
			)
		)
		(property "Value" ""
			(at 0 0 0)
			(layer "F.Fab")
			(effects
				(font
					(size 1.27 1.27)
				)
			)
		)
		(duplicate_pad_numbers_are_jumpers no)
		(fp_line
			(start -0.7874 -0.4064)
			(end 0.7874 -0.4064)
			(stroke
				(width 0.1524)
				(type default)
			)
			(layer "F.SilkS")
		)
		(fp_line
			(start -0.7874 0.4064)
			(end -0.7874 -0.4064)
			(stroke
				(width 0.1524)
				(type default)
			)
			(layer "F.SilkS")
		)
		(fp_line
			(start 0.7874 -0.4064)
			(end 0.7874 0.4064)
			(stroke
				(width 0.1524)
				(type default)
			)
			(layer "F.SilkS")
		)
		(fp_line
			(start 0.7874 0.4064)
			(end -0.7874 0.4064)
			(stroke
				(width 0.1524)
				(type default)
			)
			(layer "F.SilkS")
		)
		(fp_line
			(start -0.67945 -0.305054)
			(end -0.12065 -0.305054)
			(stroke
				(width 0.1)
				(type default)
			)
			(layer "F.Fab")
		)
		(fp_line
			(start -0.67945 0.3048)
			(end -0.67945 -0.305054)
			(stroke
				(width 0.1)
				(type default)
			)
			(layer "F.Fab")
		)
		(fp_line
			(start -0.12065 -0.305054)
			(end -0.12065 -0.2794)
			(stroke
				(width 0.1)
				(type default)
			)
			(layer "F.Fab")
		)
		(fp_line
			(start -0.12065 -0.2794)
			(end 0.12065 -0.2794)
			(stroke
				(width 0.1)
				(type default)
			)
			(layer "F.Fab")
		)
		(fp_line
			(start -0.12065 0.2794)
			(end -0.12065 0.3048)
			(stroke
				(width 0.1)
				(type default)
			)
			(layer "F.Fab")
		)
		(fp_line
			(start -0.12065 0.3048)
			(end -0.67945 0.3048)
			(stroke
				(width 0.1)
				(type default)
			)
			(layer "F.Fab")
		)
		(fp_line
			(start 0.120396 0.2794)
			(end -0.12065 0.2794)
			(stroke
				(width 0.1)
				(type default)
			)
			(layer "F.Fab")
		)
		(fp_line
			(start 0.120396 0.3048)
			(end 0.120396 0.2794)
			(stroke
				(width 0.1)
				(type default)
			)
			(layer "F.Fab")
		)
		(fp_line
			(start 0.12065 -0.3048)
			(end 0.67945 -0.3048)
			(stroke
				(width 0.1)
				(type default)
			)
			(layer "F.Fab")
		)
		(fp_line
			(start 0.12065 -0.2794)
			(end 0.12065 -0.3048)
			(stroke
				(width 0.1)
				(type default)
			)
			(layer "F.Fab")
		)
		(fp_line
			(start 0.67945 -0.3048)
			(end 0.67945 0.3048)
			(stroke
				(width 0.1)
				(type default)
			)
			(layer "F.Fab")
		)
		(fp_line
			(start 0.67945 0.3048)
			(end 0.120396 0.3048)
			(stroke
				(width 0.1)
				(type default)
			)
			(layer "F.Fab")
		)
		(pad "1" smd circle
			(at -0.40005 0)
			(size 0 0)
			(layers "F.Cu" "F.Mask" "F.Paste")
			(net "P3V3_AUX")
		)
		(pad "2" smd circle
			(at 0.40005 0)
			(size 0 0)
			(layers "F.Cu" "F.Mask" "F.Paste")
			(net "SMB_LM75_0_3V3AUX_SDA")
		)
	)
	(footprint ""
		(layer "F.Cu")
		(at 315.110622 -52.288948 180)
		(property "Reference" "R1263"
			(at 0 0 180)
			(layer "F.SilkS")
			(hide yes)
			(effects
				(font
					(size 1.27 1.27)
				)
			)
		)
		(property "Value" ""
			(at 0 0 180)
			(layer "F.Fab")
			(effects
				(font
					(size 1.27 1.27)
				)
			)
		)
		(duplicate_pad_numbers_are_jumpers no)
		(fp_line
			(start 0.7874 0.4064)
			(end -0.7874 0.4064)
			(stroke
				(width 0.1524)
				(type default)
			)
			(layer "F.SilkS")
		)
		(fp_line
			(start 0.7874 -0.4064)
			(end 0.7874 0.4064)
			(stroke
				(width 0.1524)
				(type default)
			)
			(layer "F.SilkS")
		)
		(fp_line
			(start -0.7874 0.4064)
			(end -0.7874 -0.4064)
			(stroke
				(width 0.1524)
				(type default)
			)
			(layer "F.SilkS")
		)
		(fp_line
			(start -0.7874 -0.4064)
			(end 0.7874 -0.4064)
			(stroke
				(width 0.1524)
				(type default)
			)
			(layer "F.SilkS")
		)
		(fp_line
			(start 0.67945 0.3048)
			(end 0.120396 0.3048)
			(stroke
				(width 0.1)
				(type default)
			)
			(layer "F.Fab")
		)
		(fp_line
			(start 0.67945 -0.3048)
			(end 0.67945 0.3048)
			(stroke
				(width 0.1)
				(type default)
			)
			(layer "F.Fab")
		)
		(fp_line
			(start 0.12065 -0.2794)
			(end 0.12065 -0.3048)
			(stroke
				(width 0.1)
				(type default)
			)
			(layer "F.Fab")
		)
		(fp_line
			(start 0.12065 -0.3048)
			(end 0.67945 -0.3048)
			(stroke
				(width 0.1)
				(type default)
			)
			(layer "F.Fab")
		)
		(fp_line
			(start 0.120396 0.3048)
			(end 0.120396 0.2794)
			(stroke
				(width 0.1)
				(type default)
			)
			(layer "F.Fab")
		)
		(fp_line
			(start 0.120396 0.2794)
			(end -0.12065 0.2794)
			(stroke
				(width 0.1)
				(type default)
			)
			(layer "F.Fab")
		)
		(fp_line
			(start -0.12065 0.3048)
			(end -0.67945 0.3048)
			(stroke
				(width 0.1)
				(type default)
			)
			(layer "F.Fab")
		)
		(fp_line
			(start -0.12065 0.2794)
			(end -0.12065 0.3048)
			(stroke
				(width 0.1)
				(type default)
			)
			(layer "F.Fab")
		)
		(fp_line
			(start -0.12065 -0.2794)
			(end 0.12065 -0.2794)
			(stroke
				(width 0.1)
				(type default)
			)
			(layer "F.Fab")
		)
		(fp_line
			(start -0.12065 -0.305054)
			(end -0.12065 -0.2794)
			(stroke
				(width 0.1)
				(type default)
			)
			(layer "F.Fab")
		)
		(fp_line
			(start -0.67945 0.3048)
			(end -0.67945 -0.305054)
			(stroke
				(width 0.1)
				(type default)
			)
			(layer "F.Fab")
		)
		(fp_line
			(start -0.67945 -0.305054)
			(end -0.12065 -0.305054)
			(stroke
				(width 0.1)
				(type default)
			)
			(layer "F.Fab")
		)
		(pad "1" smd circle
			(at -0.40005 0 180)
			(size 0 0)
			(layers "F.Cu" "F.Mask" "F.Paste")
			(net "FM_PLT_BMC_THERMTRIP_R_N")
		)
		(pad "2" smd circle
			(at 0.40005 0 180)
			(size 0 0)
			(layers "F.Cu" "F.Mask" "F.Paste")
			(net "FM_PCH_BMC_THERMTRIP_N")
		)
	)
	(footprint ""
		(layer "F.Cu")
		(at 104.277922 -338.86013)
		(property "Reference" "PR325"
			(at 0 0 0)
			(layer "F.SilkS")
			(hide yes)
			(effects
				(font
					(size 1.27 1.27)
				)
			)
		)
		(property "Value" ""
			(at 0 0 0)
			(layer "F.Fab")
			(effects
				(font
					(size 1.27 1.27)
				)
			)
		)
		(duplicate_pad_numbers_are_jumpers no)
		(fp_line
			(start -0.7874 -0.4064)
			(end 0.7874 -0.4064)
			(stroke
				(width 0.1524)
				(type default)
			)
			(layer "F.SilkS")
		)
		(fp_line
			(start -0.7874 0.4064)
			(end -0.7874 -0.4064)
			(stroke
				(width 0.1524)
				(type default)
			)
			(layer "F.SilkS")
		)
		(fp_line
			(start 0.7874 -0.4064)
			(end 0.7874 0.4064)
			(stroke
				(width 0.1524)
				(type default)
			)
			(layer "F.SilkS")
		)
		(fp_line
			(start 0.7874 0.4064)
			(end -0.7874 0.4064)
			(stroke
				(width 0.1524)
				(type default)
			)
			(layer "F.SilkS")
		)
		(fp_line
			(start -0.67945 -0.305054)
			(end -0.12065 -0.305054)
			(stroke
				(width 0.1)
				(type default)
			)
			(layer "F.Fab")
		)
		(fp_line
			(start -0.67945 0.3048)
			(end -0.67945 -0.305054)
			(stroke
				(width 0.1)
				(type default)
			)
			(layer "F.Fab")
		)
		(fp_line
			(start -0.12065 -0.305054)
			(end -0.12065 -0.2794)
			(stroke
				(width 0.1)
				(type default)
			)
			(layer "F.Fab")
		)
		(fp_line
			(start -0.12065 -0.2794)
			(end 0.12065 -0.2794)
			(stroke
				(width 0.1)
				(type default)
			)
			(layer "F.Fab")
		)
		(fp_line
			(start -0.12065 0.2794)
			(end -0.12065 0.3048)
			(stroke
				(width 0.1)
				(type default)
			)
			(layer "F.Fab")
		)
		(fp_line
			(start -0.12065 0.3048)
			(end -0.67945 0.3048)
			(stroke
				(width 0.1)
				(type default)
			)
			(layer "F.Fab")
		)
		(fp_line
			(start 0.120396 0.2794)
			(end -0.12065 0.2794)
			(stroke
				(width 0.1)
				(type default)
			)
			(layer "F.Fab")
		)
		(fp_line
			(start 0.120396 0.3048)
			(end 0.120396 0.2794)
			(stroke
				(width 0.1)
				(type default)
			)
			(layer "F.Fab")
		)
		(fp_line
			(start 0.12065 -0.3048)
			(end 0.67945 -0.3048)
			(stroke
				(width 0.1)
				(type default)
			)
			(layer "F.Fab")
		)
		(fp_line
			(start 0.12065 -0.2794)
			(end 0.12065 -0.3048)
			(stroke
				(width 0.1)
				(type default)
			)
			(layer "F.Fab")
		)
		(fp_line
			(start 0.67945 -0.3048)
			(end 0.67945 0.3048)
			(stroke
				(width 0.1)
				(type default)
			)
			(layer "F.Fab")
		)
		(fp_line
			(start 0.67945 0.3048)
			(end 0.120396 0.3048)
			(stroke
				(width 0.1)
				(type default)
			)
			(layer "F.Fab")
		)
		(pad "1" smd circle
			(at -0.40005 0)
			(size 0 0)
			(layers "F.Cu" "F.Mask" "F.Paste")
			(net "PVCCIN_CPU1_LSET2")
		)
		(pad "2" smd circle
			(at 0.40005 0)
			(size 0 0)
			(layers "F.Cu" "F.Mask" "F.Paste")
			(net "GND")
		)
	)
	(footprint ""
		(layer "F.Cu")
		(at 31.29788 -433.923948)
		(property "Reference" "R3466"
			(at 0 0 0)
			(layer "F.SilkS")
			(hide yes)
			(effects
				(font
					(size 1.27 1.27)
				)
			)
		)
		(property "Value" ""
			(at 0 0 0)
			(layer "F.Fab")
			(effects
				(font
					(size 1.27 1.27)
				)
			)
		)
		(duplicate_pad_numbers_are_jumpers no)
		(fp_line
			(start -0.7874 -0.4064)
			(end 0.7874 -0.4064)
			(stroke
				(width 0.1524)
				(type default)
			)
			(layer "F.SilkS")
		)
		(fp_line
			(start -0.7874 0.4064)
			(end -0.7874 -0.4064)
			(stroke
				(width 0.1524)
				(type default)
			)
			(layer "F.SilkS")
		)
		(fp_line
			(start 0.7874 -0.4064)
			(end 0.7874 0.4064)
			(stroke
				(width 0.1524)
				(type default)
			)
			(layer "F.SilkS")
		)
		(fp_line
			(start 0.7874 0.4064)
			(end -0.7874 0.4064)
			(stroke
				(width 0.1524)
				(type default)
			)
			(layer "F.SilkS")
		)
		(fp_line
			(start -0.67945 -0.305054)
			(end -0.12065 -0.305054)
			(stroke
				(width 0.1)
				(type default)
			)
			(layer "F.Fab")
		)
		(fp_line
			(start -0.67945 0.3048)
			(end -0.67945 -0.305054)
			(stroke
				(width 0.1)
				(type default)
			)
			(layer "F.Fab")
		)
		(fp_line
			(start -0.12065 -0.305054)
			(end -0.12065 -0.2794)
			(stroke
				(width 0.1)
				(type default)
			)
			(layer "F.Fab")
		)
		(fp_line
			(start -0.12065 -0.2794)
			(end 0.12065 -0.2794)
			(stroke
				(width 0.1)
				(type default)
			)
			(layer "F.Fab")
		)
		(fp_line
			(start -0.12065 0.2794)
			(end -0.12065 0.3048)
			(stroke
				(width 0.1)
				(type default)
			)
			(layer "F.Fab")
		)
		(fp_line
			(start -0.12065 0.3048)
			(end -0.67945 0.3048)
			(stroke
				(width 0.1)
				(type default)
			)
			(layer "F.Fab")
		)
		(fp_line
			(start 0.120396 0.2794)
			(end -0.12065 0.2794)
			(stroke
				(width 0.1)
				(type default)
			)
			(layer "F.Fab")
		)
		(fp_line
			(start 0.120396 0.3048)
			(end 0.120396 0.2794)
			(stroke
				(width 0.1)
				(type default)
			)
			(layer "F.Fab")
		)
		(fp_line
			(start 0.12065 -0.3048)
			(end 0.67945 -0.3048)
			(stroke
				(width 0.1)
				(type default)
			)
			(layer "F.Fab")
		)
		(fp_line
			(start 0.12065 -0.2794)
			(end 0.12065 -0.3048)
			(stroke
				(width 0.1)
				(type default)
			)
			(layer "F.Fab")
		)
		(fp_line
			(start 0.67945 -0.3048)
			(end 0.67945 0.3048)
			(stroke
				(width 0.1)
				(type default)
			)
			(layer "F.Fab")
		)
		(fp_line
			(start 0.67945 0.3048)
			(end 0.120396 0.3048)
			(stroke
				(width 0.1)
				(type default)
			)
			(layer "F.Fab")
		)
		(pad "1" smd circle
			(at -0.40005 0)
			(size 0 0)
			(layers "F.Cu" "F.Mask" "F.Paste")
			(net "RST_PERST_2_SWB_BUF_R_N")
		)
		(pad "2" smd circle
			(at 0.40005 0)
			(size 0 0)
			(layers "F.Cu" "F.Mask" "F.Paste")
			(net "GND")
		)
	)
	(footprint ""
		(layer "F.Cu")
		(at 12.530582 -423.629836 -90)
		(property "Reference" "R2983"
			(at 0 0 270)
			(layer "F.SilkS")
			(hide yes)
			(effects
				(font
					(size 1.27 1.27)
				)
			)
		)
		(property "Value" ""
			(at 0 0 270)
			(layer "F.Fab")
			(effects
				(font
					(size 1.27 1.27)
				)
			)
		)
		(duplicate_pad_numbers_are_jumpers no)
		(fp_line
			(start -0.7874 0.4064)
			(end -0.7874 -0.4064)
			(stroke
				(width 0.1524)
				(type default)
			)
			(layer "F.SilkS")
		)
		(fp_line
			(start 0.7874 0.4064)
			(end -0.7874 0.4064)
			(stroke
				(width 0.1524)
				(type default)
			)
			(layer "F.SilkS")
		)
		(fp_line
			(start -0.7874 -0.4064)
			(end 0.7874 -0.4064)
			(stroke
				(width 0.1524)
				(type default)
			)
			(layer "F.SilkS")
		)
		(fp_line
			(start 0.7874 -0.4064)
			(end 0.7874 0.4064)
			(stroke
				(width 0.1524)
				(type default)
			)
			(layer "F.SilkS")
		)
		(fp_line
			(start -0.67945 0.3048)
			(end -0.67945 -0.305054)
			(stroke
				(width 0.1)
				(type default)
			)
			(layer "F.Fab")
		)
		(fp_line
			(start -0.12065 0.3048)
			(end -0.67945 0.3048)
			(stroke
				(width 0.1)
				(type default)
			)
			(layer "F.Fab")
		)
		(fp_line
			(start 0.120396 0.3048)
			(end 0.120396 0.2794)
			(stroke
				(width 0.1)
				(type default)
			)
			(layer "F.Fab")
		)
		(fp_line
			(start 0.67945 0.3048)
			(end 0.120396 0.3048)
			(stroke
				(width 0.1)
				(type default)
			)
			(layer "F.Fab")
		)
		(fp_line
			(start -0.12065 0.2794)
			(end -0.12065 0.3048)
			(stroke
				(width 0.1)
				(type default)
			)
			(layer "F.Fab")
		)
		(fp_line
			(start 0.120396 0.2794)
			(end -0.12065 0.2794)
			(stroke
				(width 0.1)
				(type default)
			)
			(layer "F.Fab")
		)
		(fp_line
			(start -0.12065 -0.2794)
			(end 0.12065 -0.2794)
			(stroke
				(width 0.1)
				(type default)
			)
			(layer "F.Fab")
		)
		(fp_line
			(start 0.12065 -0.2794)
			(end 0.12065 -0.3048)
			(stroke
				(width 0.1)
				(type default)
			)
			(layer "F.Fab")
		)
		(fp_line
			(start 0.12065 -0.3048)
			(end 0.67945 -0.3048)
			(stroke
				(width 0.1)
				(type default)
			)
			(layer "F.Fab")
		)
		(fp_line
			(start 0.67945 -0.3048)
			(end 0.67945 0.3048)
			(stroke
				(width 0.1)
				(type default)
			)
			(layer "F.Fab")
		)
		(fp_line
			(start -0.67945 -0.305054)
			(end -0.12065 -0.305054)
			(stroke
				(width 0.1)
				(type default)
			)
			(layer "F.Fab")
		)
		(fp_line
			(start -0.12065 -0.305054)
			(end -0.12065 -0.2794)
			(stroke
				(width 0.1)
				(type default)
			)
			(layer "F.Fab")
		)
		(pad "1" smd circle
			(at -0.40005 0 270)
			(size 0 0)
			(layers "F.Cu" "F.Mask" "F.Paste")
			(net "SMB_IOEXP_3V3AUX_SDA")
		)
		(pad "2" smd circle
			(at 0.40005 0 270)
			(size 0 0)
			(layers "F.Cu" "F.Mask" "F.Paste")
			(net "SMB_IOEXP_3V3AUX_SDA_R1")
		)
	)
	(footprint ""
		(layer "F.Cu")
		(at 100.50018 -435.600094)
		(property "Reference" "H92"
			(at -5.01396 -4.694428 0)
			(unlocked yes)
			(layer "F.SilkS")
			(effects
				(font
					(size 0.7874 0.5842)
					(thickness 0.1524)
				)
				(justify left)
			)
		)
		(property "Value" ""
			(at 0 0 0)
			(layer "F.Fab")
			(effects
				(font
					(size 1.27 1.27)
				)
			)
		)
		(duplicate_pad_numbers_are_jumpers no)
		(pad "1" thru_hole circle
			(at 0 0)
			(size 10.0076 10.0076)
			(drill 5.6134)
			(layers "*.Cu" "*.Mask")
			(remove_unused_layers no)
			(net "GND")
			(clearance -1.9431)
		)
	)
	(footprint ""
		(layer "F.Cu")
		(at 314.03544 -63.076328 180)
		(property "Reference" "R4565"
			(at 0 0 180)
			(layer "F.SilkS")
			(hide yes)
			(effects
				(font
					(size 1.27 1.27)
				)
			)
		)
		(property "Value" ""
			(at 0 0 180)
			(layer "F.Fab")
			(effects
				(font
					(size 1.27 1.27)
				)
			)
		)
		(duplicate_pad_numbers_are_jumpers no)
		(fp_line
			(start 0.7874 0.4064)
			(end -0.7874 0.4064)
			(stroke
				(width 0.1524)
				(type default)
			)
			(layer "F.SilkS")
		)
		(fp_line
			(start 0.7874 -0.4064)
			(end 0.7874 0.4064)
			(stroke
				(width 0.1524)
				(type default)
			)
			(layer "F.SilkS")
		)
		(fp_line
			(start -0.7874 0.4064)
			(end -0.7874 -0.4064)
			(stroke
				(width 0.1524)
				(type default)
			)
			(layer "F.SilkS")
		)
		(fp_line
			(start -0.7874 -0.4064)
			(end 0.7874 -0.4064)
			(stroke
				(width 0.1524)
				(type default)
			)
			(layer "F.SilkS")
		)
		(fp_line
			(start 0.67945 0.3048)
			(end 0.120396 0.3048)
			(stroke
				(width 0.1)
				(type default)
			)
			(layer "F.Fab")
		)
		(fp_line
			(start 0.67945 -0.3048)
			(end 0.67945 0.3048)
			(stroke
				(width 0.1)
				(type default)
			)
			(layer "F.Fab")
		)
		(fp_line
			(start 0.12065 -0.2794)
			(end 0.12065 -0.3048)
			(stroke
				(width 0.1)
				(type default)
			)
			(layer "F.Fab")
		)
		(fp_line
			(start 0.12065 -0.3048)
			(end 0.67945 -0.3048)
			(stroke
				(width 0.1)
				(type default)
			)
			(layer "F.Fab")
		)
		(fp_line
			(start 0.120396 0.3048)
			(end 0.120396 0.2794)
			(stroke
				(width 0.1)
				(type default)
			)
			(layer "F.Fab")
		)
		(fp_line
			(start 0.120396 0.2794)
			(end -0.12065 0.2794)
			(stroke
				(width 0.1)
				(type default)
			)
			(layer "F.Fab")
		)
		(fp_line
			(start -0.12065 0.3048)
			(end -0.67945 0.3048)
			(stroke
				(width 0.1)
				(type default)
			)
			(layer "F.Fab")
		)
		(fp_line
			(start -0.12065 0.2794)
			(end -0.12065 0.3048)
			(stroke
				(width 0.1)
				(type default)
			)
			(layer "F.Fab")
		)
		(fp_line
			(start -0.12065 -0.2794)
			(end 0.12065 -0.2794)
			(stroke
				(width 0.1)
				(type default)
			)
			(layer "F.Fab")
		)
		(fp_line
			(start -0.12065 -0.305054)
			(end -0.12065 -0.2794)
			(stroke
				(width 0.1)
				(type default)
			)
			(layer "F.Fab")
		)
		(fp_line
			(start -0.67945 0.3048)
			(end -0.67945 -0.305054)
			(stroke
				(width 0.1)
				(type default)
			)
			(layer "F.Fab")
		)
		(fp_line
			(start -0.67945 -0.305054)
			(end -0.12065 -0.305054)
			(stroke
				(width 0.1)
				(type default)
			)
			(layer "F.Fab")
		)
		(pad "1" smd circle
			(at -0.40005 0 180)
			(size 0 0)
			(layers "F.Cu" "F.Mask" "F.Paste")
			(net "PD_GPP_I_13")
		)
		(pad "2" smd circle
			(at 0.40005 0 180)
			(size 0 0)
			(layers "F.Cu" "F.Mask" "F.Paste")
			(net "GND")
		)
	)
	(footprint ""
		(layer "F.Cu")
		(at 68.2117 -36.294568)
		(property "Reference" "R4092"
			(at 0 0 0)
			(layer "F.SilkS")
			(hide yes)
			(effects
				(font
					(size 1.27 1.27)
				)
			)
		)
		(property "Value" ""
			(at 0 0 0)
			(layer "F.Fab")
			(effects
				(font
					(size 1.27 1.27)
				)
			)
		)
		(duplicate_pad_numbers_are_jumpers no)
		(fp_line
			(start -0.7874 -0.4064)
			(end 0.7874 -0.4064)
			(stroke
				(width 0.1524)
				(type default)
			)
			(layer "F.SilkS")
		)
		(fp_line
			(start -0.7874 0.4064)
			(end -0.7874 -0.4064)
			(stroke
				(width 0.1524)
				(type default)
			)
			(layer "F.SilkS")
		)
		(fp_line
			(start 0.7874 -0.4064)
			(end 0.7874 0.4064)
			(stroke
				(width 0.1524)
				(type default)
			)
			(layer "F.SilkS")
		)
		(fp_line
			(start 0.7874 0.4064)
			(end -0.7874 0.4064)
			(stroke
				(width 0.1524)
				(type default)
			)
			(layer "F.SilkS")
		)
		(fp_line
			(start -0.67945 -0.305054)
			(end -0.12065 -0.305054)
			(stroke
				(width 0.1)
				(type default)
			)
			(layer "F.Fab")
		)
		(fp_line
			(start -0.67945 0.3048)
			(end -0.67945 -0.305054)
			(stroke
				(width 0.1)
				(type default)
			)
			(layer "F.Fab")
		)
		(fp_line
			(start -0.12065 -0.305054)
			(end -0.12065 -0.2794)
			(stroke
				(width 0.1)
				(type default)
			)
			(layer "F.Fab")
		)
		(fp_line
			(start -0.12065 -0.2794)
			(end 0.12065 -0.2794)
			(stroke
				(width 0.1)
				(type default)
			)
			(layer "F.Fab")
		)
		(fp_line
			(start -0.12065 0.2794)
			(end -0.12065 0.3048)
			(stroke
				(width 0.1)
				(type default)
			)
			(layer "F.Fab")
		)
		(fp_line
			(start -0.12065 0.3048)
			(end -0.67945 0.3048)
			(stroke
				(width 0.1)
				(type default)
			)
			(layer "F.Fab")
		)
		(fp_line
			(start 0.120396 0.2794)
			(end -0.12065 0.2794)
			(stroke
				(width 0.1)
				(type default)
			)
			(layer "F.Fab")
		)
		(fp_line
			(start 0.120396 0.3048)
			(end 0.120396 0.2794)
			(stroke
				(width 0.1)
				(type default)
			)
			(layer "F.Fab")
		)
		(fp_line
			(start 0.12065 -0.3048)
			(end 0.67945 -0.3048)
			(stroke
				(width 0.1)
				(type default)
			)
			(layer "F.Fab")
		)
		(fp_line
			(start 0.12065 -0.2794)
			(end 0.12065 -0.3048)
			(stroke
				(width 0.1)
				(type default)
			)
			(layer "F.Fab")
		)
		(fp_line
			(start 0.67945 -0.3048)
			(end 0.67945 0.3048)
			(stroke
				(width 0.1)
				(type default)
			)
			(layer "F.Fab")
		)
		(fp_line
			(start 0.67945 0.3048)
			(end 0.120396 0.3048)
			(stroke
				(width 0.1)
				(type default)
			)
			(layer "F.Fab")
		)
		(pad "1" smd circle
			(at -0.40005 0)
			(size 0 0)
			(layers "F.Cu" "F.Mask" "F.Paste")
			(net "P3V3_AUX")
		)
		(pad "2" smd circle
			(at 0.40005 0)
			(size 0 0)
			(layers "F.Cu" "F.Mask" "F.Paste")
			(net "OCP_V3_2_P3V3_ADC_ALERT_R")
		)
	)
	(footprint ""
		(layer "F.Cu")
		(at 73.6092 -53.546248 180)
		(property "Reference" "PC2142"
			(at 0 0 180)
			(layer "F.SilkS")
			(hide yes)
			(effects
				(font
					(size 1.27 1.27)
				)
			)
		)
		(property "Value" ""
			(at 0 0 180)
			(layer "F.Fab")
			(effects
				(font
					(size 1.27 1.27)
				)
			)
		)
		(duplicate_pad_numbers_are_jumpers no)
		(fp_line
			(start 1.524 0.762)
			(end -1.524 0.762)
			(stroke
				(width 0.1524)
				(type default)
			)
			(layer "F.SilkS")
		)
		(fp_line
			(start 1.524 -0.762)
			(end 1.524 0.762)
			(stroke
				(width 0.1524)
				(type default)
			)
			(layer "F.SilkS")
		)
		(fp_line
			(start -1.524 0.762)
			(end -1.524 -0.762)
			(stroke
				(width 0.1524)
				(type default)
			)
			(layer "F.SilkS")
		)
		(fp_line
			(start -1.524 -0.762)
			(end 1.524 -0.762)
			(stroke
				(width 0.1524)
				(type default)
			)
			(layer "F.SilkS")
		)
		(fp_line
			(start 1.1049 0.724916)
			(end 1.1049 -0.724916)
			(stroke
				(width 0.1)
				(type default)
			)
			(layer "F.Fab")
		)
		(fp_line
			(start 1.1049 -0.724916)
			(end -1.1049 -0.724916)
			(stroke
				(width 0.1)
				(type default)
			)
			(layer "F.Fab")
		)
		(fp_line
			(start -1.1049 0.724916)
			(end 1.1049 0.724916)
			(stroke
				(width 0.1)
				(type default)
			)
			(layer "F.Fab")
		)
		(fp_line
			(start -1.1049 -0.724916)
			(end -1.1049 0.724916)
			(stroke
				(width 0.1)
				(type default)
			)
			(layer "F.Fab")
		)
		(pad "1" smd rect
			(at -0.889 0)
			(size 1.016 1.27)
			(layers "F.Cu" "F.Mask" "F.Paste")
			(net "P3V3_OCP_V3_2_R")
		)
		(pad "2" smd rect
			(at 0.889 0)
			(size 1.016 1.27)
			(layers "F.Cu" "F.Mask" "F.Paste")
			(net "GND")
		)
	)
	(footprint ""
		(layer "F.Cu")
		(at 294.39108 -53.68798 180)
		(property "Reference" "R4072"
			(at 0 0 180)
			(layer "F.SilkS")
			(hide yes)
			(effects
				(font
					(size 1.27 1.27)
				)
			)
		)
		(property "Value" ""
			(at 0 0 180)
			(layer "F.Fab")
			(effects
				(font
					(size 1.27 1.27)
				)
			)
		)
		(duplicate_pad_numbers_are_jumpers no)
		(fp_line
			(start 0.7874 0.4064)
			(end -0.7874 0.4064)
			(stroke
				(width 0.1524)
				(type default)
			)
			(layer "F.SilkS")
		)
		(fp_line
			(start 0.7874 -0.4064)
			(end 0.7874 0.4064)
			(stroke
				(width 0.1524)
				(type default)
			)
			(layer "F.SilkS")
		)
		(fp_line
			(start -0.7874 0.4064)
			(end -0.7874 -0.4064)
			(stroke
				(width 0.1524)
				(type default)
			)
			(layer "F.SilkS")
		)
		(fp_line
			(start -0.7874 -0.4064)
			(end 0.7874 -0.4064)
			(stroke
				(width 0.1524)
				(type default)
			)
			(layer "F.SilkS")
		)
		(fp_line
			(start 0.67945 0.3048)
			(end 0.120396 0.3048)
			(stroke
				(width 0.1)
				(type default)
			)
			(layer "F.Fab")
		)
		(fp_line
			(start 0.67945 -0.3048)
			(end 0.67945 0.3048)
			(stroke
				(width 0.1)
				(type default)
			)
			(layer "F.Fab")
		)
		(fp_line
			(start 0.12065 -0.2794)
			(end 0.12065 -0.3048)
			(stroke
				(width 0.1)
				(type default)
			)
			(layer "F.Fab")
		)
		(fp_line
			(start 0.12065 -0.3048)
			(end 0.67945 -0.3048)
			(stroke
				(width 0.1)
				(type default)
			)
			(layer "F.Fab")
		)
		(fp_line
			(start 0.120396 0.3048)
			(end 0.120396 0.2794)
			(stroke
				(width 0.1)
				(type default)
			)
			(layer "F.Fab")
		)
		(fp_line
			(start 0.120396 0.2794)
			(end -0.12065 0.2794)
			(stroke
				(width 0.1)
				(type default)
			)
			(layer "F.Fab")
		)
		(fp_line
			(start -0.12065 0.3048)
			(end -0.67945 0.3048)
			(stroke
				(width 0.1)
				(type default)
			)
			(layer "F.Fab")
		)
		(fp_line
			(start -0.12065 0.2794)
			(end -0.12065 0.3048)
			(stroke
				(width 0.1)
				(type default)
			)
			(layer "F.Fab")
		)
		(fp_line
			(start -0.12065 -0.2794)
			(end 0.12065 -0.2794)
			(stroke
				(width 0.1)
				(type default)
			)
			(layer "F.Fab")
		)
		(fp_line
			(start -0.12065 -0.305054)
			(end -0.12065 -0.2794)
			(stroke
				(width 0.1)
				(type default)
			)
			(layer "F.Fab")
		)
		(fp_line
			(start -0.67945 0.3048)
			(end -0.67945 -0.305054)
			(stroke
				(width 0.1)
				(type default)
			)
			(layer "F.Fab")
		)
		(fp_line
			(start -0.67945 -0.305054)
			(end -0.12065 -0.305054)
			(stroke
				(width 0.1)
				(type default)
			)
			(layer "F.Fab")
		)
		(pad "1" smd circle
			(at -0.40005 0 180)
			(size 0 0)
			(layers "F.Cu" "F.Mask" "F.Paste")
			(net "P12V_AUX")
		)
		(pad "2" smd circle
			(at 0.40005 0 180)
			(size 0 0)
			(layers "F.Cu" "F.Mask" "F.Paste")
			(net "P3V3_E1S_0_EN_G")
		)
	)
	(footprint ""
		(layer "F.Cu")
		(at 46.087792 -393.315444)
		(property "Reference" "R4647"
			(at 0 0 0)
			(layer "F.SilkS")
			(hide yes)
			(effects
				(font
					(size 1.27 1.27)
				)
			)
		)
		(property "Value" ""
			(at 0 0 0)
			(layer "F.Fab")
			(effects
				(font
					(size 1.27 1.27)
				)
			)
		)
		(duplicate_pad_numbers_are_jumpers no)
		(fp_line
			(start -0.7874 -0.4064)
			(end 0.7874 -0.4064)
			(stroke
				(width 0.1524)
				(type default)
			)
			(layer "F.SilkS")
		)
		(fp_line
			(start -0.7874 0.4064)
			(end -0.7874 -0.4064)
			(stroke
				(width 0.1524)
				(type default)
			)
			(layer "F.SilkS")
		)
		(fp_line
			(start 0.7874 -0.4064)
			(end 0.7874 0.4064)
			(stroke
				(width 0.1524)
				(type default)
			)
			(layer "F.SilkS")
		)
		(fp_line
			(start 0.7874 0.4064)
			(end -0.7874 0.4064)
			(stroke
				(width 0.1524)
				(type default)
			)
			(layer "F.SilkS")
		)
		(fp_line
			(start -0.67945 -0.305054)
			(end -0.12065 -0.305054)
			(stroke
				(width 0.1)
				(type default)
			)
			(layer "F.Fab")
		)
		(fp_line
			(start -0.67945 0.3048)
			(end -0.67945 -0.305054)
			(stroke
				(width 0.1)
				(type default)
			)
			(layer "F.Fab")
		)
		(fp_line
			(start -0.12065 -0.305054)
			(end -0.12065 -0.2794)
			(stroke
				(width 0.1)
				(type default)
			)
			(layer "F.Fab")
		)
		(fp_line
			(start -0.12065 -0.2794)
			(end 0.12065 -0.2794)
			(stroke
				(width 0.1)
				(type default)
			)
			(layer "F.Fab")
		)
		(fp_line
			(start -0.12065 0.2794)
			(end -0.12065 0.3048)
			(stroke
				(width 0.1)
				(type default)
			)
			(layer "F.Fab")
		)
		(fp_line
			(start -0.12065 0.3048)
			(end -0.67945 0.3048)
			(stroke
				(width 0.1)
				(type default)
			)
			(layer "F.Fab")
		)
		(fp_line
			(start 0.120396 0.2794)
			(end -0.12065 0.2794)
			(stroke
				(width 0.1)
				(type default)
			)
			(layer "F.Fab")
		)
		(fp_line
			(start 0.120396 0.3048)
			(end 0.120396 0.2794)
			(stroke
				(width 0.1)
				(type default)
			)
			(layer "F.Fab")
		)
		(fp_line
			(start 0.12065 -0.3048)
			(end 0.67945 -0.3048)
			(stroke
				(width 0.1)
				(type default)
			)
			(layer "F.Fab")
		)
		(fp_line
			(start 0.12065 -0.2794)
			(end 0.12065 -0.3048)
			(stroke
				(width 0.1)
				(type default)
			)
			(layer "F.Fab")
		)
		(fp_line
			(start 0.67945 -0.3048)
			(end 0.67945 0.3048)
			(stroke
				(width 0.1)
				(type default)
			)
			(layer "F.Fab")
		)
		(fp_line
			(start 0.67945 0.3048)
			(end 0.120396 0.3048)
			(stroke
				(width 0.1)
				(type default)
			)
			(layer "F.Fab")
		)
		(pad "1" smd circle
			(at -0.40005 0)
			(size 0 0)
			(layers "F.Cu" "F.Mask" "F.Paste")
			(net "FM_P2E_BUF2_VODA_DB")
		)
		(pad "2" smd circle
			(at 0.40005 0)
			(size 0 0)
			(layers "F.Cu" "F.Mask" "F.Paste")
			(net "GND")
		)
	)
	(footprint ""
		(layer "F.Cu")
		(at 9.58088 -54.955948)
		(property "Reference" "R3061"
			(at 0 0 0)
			(layer "F.SilkS")
			(hide yes)
			(effects
				(font
					(size 1.27 1.27)
				)
			)
		)
		(property "Value" ""
			(at 0 0 0)
			(layer "F.Fab")
			(effects
				(font
					(size 1.27 1.27)
				)
			)
		)
		(duplicate_pad_numbers_are_jumpers no)
		(fp_line
			(start -0.7874 -0.4064)
			(end 0.7874 -0.4064)
			(stroke
				(width 0.1524)
				(type default)
			)
			(layer "F.SilkS")
		)
		(fp_line
			(start -0.7874 0.4064)
			(end -0.7874 -0.4064)
			(stroke
				(width 0.1524)
				(type default)
			)
			(layer "F.SilkS")
		)
		(fp_line
			(start 0.7874 -0.4064)
			(end 0.7874 0.4064)
			(stroke
				(width 0.1524)
				(type default)
			)
			(layer "F.SilkS")
		)
		(fp_line
			(start 0.7874 0.4064)
			(end -0.7874 0.4064)
			(stroke
				(width 0.1524)
				(type default)
			)
			(layer "F.SilkS")
		)
		(fp_line
			(start -0.67945 -0.305054)
			(end -0.12065 -0.305054)
			(stroke
				(width 0.1)
				(type default)
			)
			(layer "F.Fab")
		)
		(fp_line
			(start -0.67945 0.3048)
			(end -0.67945 -0.305054)
			(stroke
				(width 0.1)
				(type default)
			)
			(layer "F.Fab")
		)
		(fp_line
			(start -0.12065 -0.305054)
			(end -0.12065 -0.2794)
			(stroke
				(width 0.1)
				(type default)
			)
			(layer "F.Fab")
		)
		(fp_line
			(start -0.12065 -0.2794)
			(end 0.12065 -0.2794)
			(stroke
				(width 0.1)
				(type default)
			)
			(layer "F.Fab")
		)
		(fp_line
			(start -0.12065 0.2794)
			(end -0.12065 0.3048)
			(stroke
				(width 0.1)
				(type default)
			)
			(layer "F.Fab")
		)
		(fp_line
			(start -0.12065 0.3048)
			(end -0.67945 0.3048)
			(stroke
				(width 0.1)
				(type default)
			)
			(layer "F.Fab")
		)
		(fp_line
			(start 0.120396 0.2794)
			(end -0.12065 0.2794)
			(stroke
				(width 0.1)
				(type default)
			)
			(layer "F.Fab")
		)
		(fp_line
			(start 0.120396 0.3048)
			(end 0.120396 0.2794)
			(stroke
				(width 0.1)
				(type default)
			)
			(layer "F.Fab")
		)
		(fp_line
			(start 0.12065 -0.3048)
			(end 0.67945 -0.3048)
			(stroke
				(width 0.1)
				(type default)
			)
			(layer "F.Fab")
		)
		(fp_line
			(start 0.12065 -0.2794)
			(end 0.12065 -0.3048)
			(stroke
				(width 0.1)
				(type default)
			)
			(layer "F.Fab")
		)
		(fp_line
			(start 0.67945 -0.3048)
			(end 0.67945 0.3048)
			(stroke
				(width 0.1)
				(type default)
			)
			(layer "F.Fab")
		)
		(fp_line
			(start 0.67945 0.3048)
			(end 0.120396 0.3048)
			(stroke
				(width 0.1)
				(type default)
			)
			(layer "F.Fab")
		)
		(pad "1" smd circle
			(at -0.40005 0)
			(size 0 0)
			(layers "F.Cu" "F.Mask" "F.Paste")
			(net "SMB_SML1_PMBUS_3V3AUX_PCH_SDA")
		)
		(pad "2" smd circle
			(at 0.40005 0)
			(size 0 0)
			(layers "F.Cu" "F.Mask" "F.Paste")
			(net "SMB_PMBUS_SML1_ME_SDA")
		)
	)
	(footprint ""
		(layer "F.Cu")
		(at 164.14115 -432.865276 -90)
		(property "Reference" "R2667"
			(at 0 0 270)
			(layer "F.SilkS")
			(hide yes)
			(effects
				(font
					(size 1.27 1.27)
				)
			)
		)
		(property "Value" ""
			(at 0 0 270)
			(layer "F.Fab")
			(effects
				(font
					(size 1.27 1.27)
				)
			)
		)
		(duplicate_pad_numbers_are_jumpers no)
		(fp_line
			(start -0.7874 0.4064)
			(end -0.7874 -0.4064)
			(stroke
				(width 0.1524)
				(type default)
			)
			(layer "F.SilkS")
		)
		(fp_line
			(start 0.7874 0.4064)
			(end -0.7874 0.4064)
			(stroke
				(width 0.1524)
				(type default)
			)
			(layer "F.SilkS")
		)
		(fp_line
			(start -0.7874 -0.4064)
			(end 0.7874 -0.4064)
			(stroke
				(width 0.1524)
				(type default)
			)
			(layer "F.SilkS")
		)
		(fp_line
			(start 0.7874 -0.4064)
			(end 0.7874 0.4064)
			(stroke
				(width 0.1524)
				(type default)
			)
			(layer "F.SilkS")
		)
		(fp_line
			(start -0.67945 0.3048)
			(end -0.67945 -0.305054)
			(stroke
				(width 0.1)
				(type default)
			)
			(layer "F.Fab")
		)
		(fp_line
			(start -0.12065 0.3048)
			(end -0.67945 0.3048)
			(stroke
				(width 0.1)
				(type default)
			)
			(layer "F.Fab")
		)
		(fp_line
			(start 0.120396 0.3048)
			(end 0.120396 0.2794)
			(stroke
				(width 0.1)
				(type default)
			)
			(layer "F.Fab")
		)
		(fp_line
			(start 0.67945 0.3048)
			(end 0.120396 0.3048)
			(stroke
				(width 0.1)
				(type default)
			)
			(layer "F.Fab")
		)
		(fp_line
			(start -0.12065 0.2794)
			(end -0.12065 0.3048)
			(stroke
				(width 0.1)
				(type default)
			)
			(layer "F.Fab")
		)
		(fp_line
			(start 0.120396 0.2794)
			(end -0.12065 0.2794)
			(stroke
				(width 0.1)
				(type default)
			)
			(layer "F.Fab")
		)
		(fp_line
			(start -0.12065 -0.2794)
			(end 0.12065 -0.2794)
			(stroke
				(width 0.1)
				(type default)
			)
			(layer "F.Fab")
		)
		(fp_line
			(start 0.12065 -0.2794)
			(end 0.12065 -0.3048)
			(stroke
				(width 0.1)
				(type default)
			)
			(layer "F.Fab")
		)
		(fp_line
			(start 0.12065 -0.3048)
			(end 0.67945 -0.3048)
			(stroke
				(width 0.1)
				(type default)
			)
			(layer "F.Fab")
		)
		(fp_line
			(start 0.67945 -0.3048)
			(end 0.67945 0.3048)
			(stroke
				(width 0.1)
				(type default)
			)
			(layer "F.Fab")
		)
		(fp_line
			(start -0.67945 -0.305054)
			(end -0.12065 -0.305054)
			(stroke
				(width 0.1)
				(type default)
			)
			(layer "F.Fab")
		)
		(fp_line
			(start -0.12065 -0.305054)
			(end -0.12065 -0.2794)
			(stroke
				(width 0.1)
				(type default)
			)
			(layer "F.Fab")
		)
		(pad "1" smd circle
			(at -0.40005 0 270)
			(size 0 0)
			(layers "F.Cu" "F.Mask" "F.Paste")
			(net "P3V3_AUX")
		)
		(pad "2" smd circle
			(at 0.40005 0 270)
			(size 0 0)
			(layers "F.Cu" "F.Mask" "F.Paste")
			(net "SMB_BMC_SWB_BUF_R_SCL")
		)
	)
	(footprint ""
		(layer "F.Cu")
		(at 105.132886 -324.445376)
		(property "Reference" "PL30"
			(at -12.69492 7.099554 90)
			(unlocked yes)
			(layer "F.SilkS")
			(effects
				(font
					(size 0.7874 0.5842)
					(thickness 0.1524)
				)
				(justify left)
			)
		)
		(property "Value" ""
			(at 0 0 0)
			(layer "F.Fab")
			(effects
				(font
					(size 1.27 1.27)
				)
			)
		)
		(duplicate_pad_numbers_are_jumpers no)
		(fp_line
			(start -3.750056 -5.500116)
			(end -2.393442 -5.500116)
			(stroke
				(width 0.1524)
				(type default)
			)
			(layer "F.SilkS")
		)
		(fp_line
			(start -3.750056 5.500116)
			(end -3.750056 -5.500116)
			(stroke
				(width 0.1524)
				(type default)
			)
			(layer "F.SilkS")
		)
		(fp_line
			(start -2.393442 5.500116)
			(end -3.750056 5.500116)
			(stroke
				(width 0.1524)
				(type default)
			)
			(layer "F.SilkS")
		)
		(fp_line
			(start 2.393442 5.500116)
			(end 3.750056 5.500116)
			(stroke
				(width 0.1524)
				(type default)
			)
			(layer "F.SilkS")
		)
		(fp_line
			(start 3.750056 -5.500116)
			(end 2.393442 -5.500116)
			(stroke
				(width 0.1524)
				(type default)
			)
			(layer "F.SilkS")
		)
		(fp_line
			(start 3.750056 5.500116)
			(end 3.750056 -5.500116)
			(stroke
				(width 0.1524)
				(type default)
			)
			(layer "F.SilkS")
		)
		(fp_poly
			(pts
				(xy -3.418586 -6.86943) (xy -3.05943 -5.791708) (xy -4.136898 -6.150864)
			)
			(stroke
				(width 0)
				(type default)
			)
			(fill yes)
			(layer "F.SilkS")
		)
		(fp_line
			(start -3.750056 -5.500116)
			(end -3.750056 5.500116)
			(stroke
				(width 0.1)
				(type default)
			)
			(layer "F.Fab")
		)
		(fp_line
			(start -3.750056 5.500116)
			(end 3.750056 5.500116)
			(stroke
				(width 0.1)
				(type default)
			)
			(layer "F.Fab")
		)
		(fp_line
			(start 3.750056 -5.500116)
			(end -3.750056 -5.500116)
			(stroke
				(width 0.1)
				(type default)
			)
			(layer "F.Fab")
		)
		(fp_line
			(start 3.750056 5.500116)
			(end 3.750056 -5.500116)
			(stroke
				(width 0.1)
				(type default)
			)
			(layer "F.Fab")
		)
		(fp_poly
			(pts
				(xy -4.9276 -4.757928) (xy -4.9276 -3.741928) (xy -3.9116 -4.249928)
			)
			(stroke
				(width 0)
				(type default)
			)
			(fill yes)
			(layer "F.Fab")
		)
		(pad "1" smd rect
			(at 0 -4.249928 270)
			(size 2.413 4.5212)
			(layers "F.Cu" "F.Mask" "F.Paste")
			(net "SW_PVCCIN_CPU1_SW2")
		)
		(pad "2" smd rect
			(at 0 -1.175004 270)
			(size 1.3716 4.5212)
			(layers "F.Cu" "F.Mask" "F.Paste")
			(net "IND_P1_CPL2")
		)
		(pad "3" smd rect
			(at 0 1.175004 270)
			(size 1.3716 4.5212)
			(layers "F.Cu" "F.Mask" "F.Paste")
			(net "IND_P1_CPL1")
		)
		(pad "4" smd rect
			(at 0 4.249928 270)
			(size 2.413 4.5212)
			(layers "F.Cu" "F.Mask" "F.Paste")
			(net "PVCCIN_CPU1")
		)
	)
	(footprint ""
		(layer "F.Cu")
		(at 349.014034 -68.21678)
		(property "Reference" "C147"
			(at 0 0 0)
			(layer "F.SilkS")
			(hide yes)
			(effects
				(font
					(size 1.27 1.27)
				)
			)
		)
		(property "Value" ""
			(at 0 0 0)
			(layer "F.Fab")
			(effects
				(font
					(size 1.27 1.27)
				)
			)
		)
		(duplicate_pad_numbers_are_jumpers no)
		(fp_line
			(start -0.299974 -0.150114)
			(end 0.299974 -0.150114)
			(stroke
				(width 0.1)
				(type default)
			)
			(layer "F.Fab")
		)
		(fp_line
			(start -0.299974 0.150114)
			(end -0.299974 -0.150114)
			(stroke
				(width 0.1)
				(type default)
			)
			(layer "F.Fab")
		)
		(fp_line
			(start 0.299974 -0.150114)
			(end 0.299974 0.150114)
			(stroke
				(width 0.1)
				(type default)
			)
			(layer "F.Fab")
		)
		(fp_line
			(start 0.299974 0.150114)
			(end -0.299974 0.150114)
			(stroke
				(width 0.1)
				(type default)
			)
			(layer "F.Fab")
		)
		(pad "1" smd rect
			(at -0.2667 0)
			(size 0.3048 0.381)
			(layers "F.Cu" "F.Mask" "F.Paste")
			(net "DMI_CPU0_PCH_TX_C_DN<3>")
		)
		(pad "2" smd rect
			(at 0.2667 0)
			(size 0.3048 0.381)
			(layers "F.Cu" "F.Mask" "F.Paste")
			(net "DMI_CPU0_PCH_TX_DN<3>")
		)
	)
	(footprint ""
		(layer "F.Cu")
		(at 299.02023 -48.304196 180)
		(property "Reference" "R2973"
			(at 0 0 180)
			(layer "F.SilkS")
			(hide yes)
			(effects
				(font
					(size 1.27 1.27)
				)
			)
		)
		(property "Value" ""
			(at 0 0 180)
			(layer "F.Fab")
			(effects
				(font
					(size 1.27 1.27)
				)
			)
		)
		(duplicate_pad_numbers_are_jumpers no)
		(fp_line
			(start 0.7874 0.4064)
			(end -0.7874 0.4064)
			(stroke
				(width 0.1524)
				(type default)
			)
			(layer "F.SilkS")
		)
		(fp_line
			(start 0.7874 -0.4064)
			(end 0.7874 0.4064)
			(stroke
				(width 0.1524)
				(type default)
			)
			(layer "F.SilkS")
		)
		(fp_line
			(start -0.7874 0.4064)
			(end -0.7874 -0.4064)
			(stroke
				(width 0.1524)
				(type default)
			)
			(layer "F.SilkS")
		)
		(fp_line
			(start -0.7874 -0.4064)
			(end 0.7874 -0.4064)
			(stroke
				(width 0.1524)
				(type default)
			)
			(layer "F.SilkS")
		)
		(fp_line
			(start 0.67945 0.3048)
			(end 0.120396 0.3048)
			(stroke
				(width 0.1)
				(type default)
			)
			(layer "F.Fab")
		)
		(fp_line
			(start 0.67945 -0.3048)
			(end 0.67945 0.3048)
			(stroke
				(width 0.1)
				(type default)
			)
			(layer "F.Fab")
		)
		(fp_line
			(start 0.12065 -0.2794)
			(end 0.12065 -0.3048)
			(stroke
				(width 0.1)
				(type default)
			)
			(layer "F.Fab")
		)
		(fp_line
			(start 0.12065 -0.3048)
			(end 0.67945 -0.3048)
			(stroke
				(width 0.1)
				(type default)
			)
			(layer "F.Fab")
		)
		(fp_line
			(start 0.120396 0.3048)
			(end 0.120396 0.2794)
			(stroke
				(width 0.1)
				(type default)
			)
			(layer "F.Fab")
		)
		(fp_line
			(start 0.120396 0.2794)
			(end -0.12065 0.2794)
			(stroke
				(width 0.1)
				(type default)
			)
			(layer "F.Fab")
		)
		(fp_line
			(start -0.12065 0.3048)
			(end -0.67945 0.3048)
			(stroke
				(width 0.1)
				(type default)
			)
			(layer "F.Fab")
		)
		(fp_line
			(start -0.12065 0.2794)
			(end -0.12065 0.3048)
			(stroke
				(width 0.1)
				(type default)
			)
			(layer "F.Fab")
		)
		(fp_line
			(start -0.12065 -0.2794)
			(end 0.12065 -0.2794)
			(stroke
				(width 0.1)
				(type default)
			)
			(layer "F.Fab")
		)
		(fp_line
			(start -0.12065 -0.305054)
			(end -0.12065 -0.2794)
			(stroke
				(width 0.1)
				(type default)
			)
			(layer "F.Fab")
		)
		(fp_line
			(start -0.67945 0.3048)
			(end -0.67945 -0.305054)
			(stroke
				(width 0.1)
				(type default)
			)
			(layer "F.Fab")
		)
		(fp_line
			(start -0.67945 -0.305054)
			(end -0.12065 -0.305054)
			(stroke
				(width 0.1)
				(type default)
			)
			(layer "F.Fab")
		)
		(pad "1" smd circle
			(at -0.40005 0 180)
			(size 0 0)
			(layers "F.Cu" "F.Mask" "F.Paste")
			(net "FAB_REV_ID2")
		)
		(pad "2" smd circle
			(at 0.40005 0 180)
			(size 0 0)
			(layers "F.Cu" "F.Mask" "F.Paste")
			(net "GND")
		)
	)
	(footprint ""
		(layer "F.Cu")
		(at 32.82188 -258.091686)
		(property "Reference" "J22"
			(at -1.420622 -81.912714 0)
			(unlocked yes)
			(layer "F.SilkS")
			(effects
				(font
					(size 0.7874 0.5842)
					(thickness 0.1524)
				)
				(justify left)
			)
		)
		(property "Value" ""
			(at 0 0 0)
			(layer "F.Fab")
			(effects
				(font
					(size 1.27 1.27)
				)
			)
		)
		(duplicate_pad_numbers_are_jumpers no)
		(fp_line
			(start -3.24993 -81.000092)
			(end -3.24993 81.000092)
			(stroke
				(width 0.1524)
				(type default)
			)
			(layer "F.SilkS")
		)
		(fp_line
			(start -3.24993 81.000092)
			(end 1.20904 81.000092)
			(stroke
				(width 0.1524)
				(type default)
			)
			(layer "F.SilkS")
		)
		(fp_line
			(start 3.24993 -81.000092)
			(end -3.24993 -81.000092)
			(stroke
				(width 0.1524)
				(type default)
			)
			(layer "F.SilkS")
		)
		(fp_line
			(start 3.24993 -72.00011)
			(end -3.24993 -72.00011)
			(stroke
				(width 0.1524)
				(type default)
			)
			(layer "F.SilkS")
		)
		(fp_line
			(start 3.24993 72.00011)
			(end -3.24993 72.00011)
			(stroke
				(width 0.1524)
				(type default)
			)
			(layer "F.SilkS")
		)
		(fp_line
			(start 3.24993 74.677778)
			(end 3.24993 -81.000092)
			(stroke
				(width 0.1524)
				(type default)
			)
			(layer "F.SilkS")
		)
		(fp_poly
			(pts
				(xy -4.186682 -63.71209) (xy -3.350768 -63.294006) (xy -4.186682 -62.875922)
			)
			(stroke
				(width 0)
				(type default)
			)
			(fill yes)
			(layer "F.SilkS")
		)
		(fp_line
			(start -3.24993 -81.000092)
			(end -3.24993 81.000092)
			(stroke
				(width 0.1)
				(type default)
			)
			(layer "F.Fab")
		)
		(fp_line
			(start -3.24993 81.000092)
			(end 3.24993 81.000092)
			(stroke
				(width 0.1)
				(type default)
			)
			(layer "F.Fab")
		)
		(fp_line
			(start 3.24993 -81.000092)
			(end -3.24993 -81.000092)
			(stroke
				(width 0.1)
				(type default)
			)
			(layer "F.Fab")
		)
		(fp_line
			(start 3.24993 -72.00011)
			(end -3.24993 -72.00011)
			(stroke
				(width 0.1)
				(type default)
			)
			(layer "F.Fab")
		)
		(fp_line
			(start 3.24993 -71.000112)
			(end -3.24993 -71.000112)
			(stroke
				(width 0.1)
				(type default)
			)
			(layer "F.Fab")
		)
		(fp_line
			(start 3.24993 71.000112)
			(end -3.24993 71.000112)
			(stroke
				(width 0.1)
				(type default)
			)
			(layer "F.Fab")
		)
		(fp_line
			(start 3.24993 72.00011)
			(end -3.24993 72.00011)
			(stroke
				(width 0.1)
				(type default)
			)
			(layer "F.Fab")
		)
		(fp_line
			(start 3.24993 81.000092)
			(end 3.24993 -81.000092)
			(stroke
				(width 0.1)
				(type default)
			)
			(layer "F.Fab")
		)
		(fp_poly
			(pts
				(xy -4.445 -63.832994) (xy -4.445 -62.816994) (xy -3.429 -63.324994)
			)
			(stroke
				(width 0)
				(type default)
			)
			(fill yes)
			(layer "F.Fab")
		)
		(pad "1" smd rect
			(at -2.050034 -63.324994 270)
			(size 0.519938 1.4986)
			(layers "F.Cu" "F.Mask" "F.Paste")
			(net "P12V_S3_AUX_CPU1_NVDIMM")
		)
		(pad "2" smd rect
			(at -2.050034 -62.47511 270)
			(size 0.519938 1.4986)
			(layers "F.Cu" "F.Mask" "F.Paste")
			(net "TP_CHC_CPU1_DIMM2_FRU_0")
		)
		(pad "3" smd rect
			(at -2.050034 -61.624972 270)
			(size 0.519938 1.4986)
			(layers "F.Cu" "F.Mask" "F.Paste")
			(net "P3V3_AUX")
		)
		(pad "4" smd rect
			(at -2.050034 -60.775088 270)
			(size 0.519938 1.4986)
			(layers "F.Cu" "F.Mask" "F.Paste")
			(net "I3C_SPD_DDRABCD_CPU1_LVC1_SCL_5")
		)
		(pad "5" smd rect
			(at -2.050034 -59.92495 270)
			(size 0.519938 1.4986)
			(layers "F.Cu" "F.Mask" "F.Paste")
			(net "I3C_SPD_DDRABCD_CPU1_LVC1_SDA")
		)
		(pad "6" smd rect
			(at -2.050034 -59.075066 270)
			(size 0.519938 1.4986)
			(layers "F.Cu" "F.Mask" "F.Paste")
			(net "GND")
		)
		(pad "7" smd rect
			(at -2.050034 -58.224928 270)
			(size 0.519938 1.4986)
			(layers "F.Cu" "F.Mask" "F.Paste")
			(net "M_C_CPU1_SA_DQ<0>")
		)
		(pad "8" smd rect
			(at -2.050034 -57.375044 270)
			(size 0.519938 1.4986)
			(layers "F.Cu" "F.Mask" "F.Paste")
			(net "GND")
		)
		(pad "9" smd rect
			(at -2.050034 -56.524906 270)
			(size 0.519938 1.4986)
			(layers "F.Cu" "F.Mask" "F.Paste")
			(net "M_C_CPU1_SA_DQ<1>")
		)
		(pad "10" smd rect
			(at -2.050034 -55.675022 270)
			(size 0.519938 1.4986)
			(layers "F.Cu" "F.Mask" "F.Paste")
			(net "GND")
		)
		(pad "11" smd rect
			(at -2.050034 -54.824884 270)
			(size 0.519938 1.4986)
			(layers "F.Cu" "F.Mask" "F.Paste")
			(net "M_C_CPU1_SA_DQS_DP<0>")
		)
		(pad "12" smd rect
			(at -2.050034 -53.975 270)
			(size 0.519938 1.4986)
			(layers "F.Cu" "F.Mask" "F.Paste")
			(net "M_C_CPU1_SA_DQS_DN<0>")
		)
		(pad "13" smd rect
			(at -2.050034 -53.125116 270)
			(size 0.519938 1.4986)
			(layers "F.Cu" "F.Mask" "F.Paste")
			(net "GND")
		)
		(pad "14" smd rect
			(at -2.050034 -52.274978 270)
			(size 0.519938 1.4986)
			(layers "F.Cu" "F.Mask" "F.Paste")
			(net "M_C_CPU1_SA_DQ<4>")
		)
		(pad "15" smd rect
			(at -2.050034 -51.425094 270)
			(size 0.519938 1.4986)
			(layers "F.Cu" "F.Mask" "F.Paste")
			(net "GND")
		)
		(pad "16" smd rect
			(at -2.050034 -50.574956 270)
			(size 0.519938 1.4986)
			(layers "F.Cu" "F.Mask" "F.Paste")
			(net "M_C_CPU1_SA_DQ<5>")
		)
		(pad "17" smd rect
			(at -2.050034 -49.725072 270)
			(size 0.519938 1.4986)
			(layers "F.Cu" "F.Mask" "F.Paste")
			(net "GND")
		)
		(pad "18" smd rect
			(at -2.050034 -48.874934 270)
			(size 0.519938 1.4986)
			(layers "F.Cu" "F.Mask" "F.Paste")
			(net "M_C_CPU1_SA_DQ<8>")
		)
		(pad "19" smd rect
			(at -2.050034 -48.02505 270)
			(size 0.519938 1.4986)
			(layers "F.Cu" "F.Mask" "F.Paste")
			(net "GND")
		)
		(pad "20" smd rect
			(at -2.050034 -47.174912 270)
			(size 0.519938 1.4986)
			(layers "F.Cu" "F.Mask" "F.Paste")
			(net "M_C_CPU1_SA_DQ<9>")
		)
		(pad "21" smd rect
			(at -2.050034 -46.325028 270)
			(size 0.519938 1.4986)
			(layers "F.Cu" "F.Mask" "F.Paste")
			(net "GND")
		)
		(pad "22" smd rect
			(at -2.050034 -45.47489 270)
			(size 0.519938 1.4986)
			(layers "F.Cu" "F.Mask" "F.Paste")
			(net "M_C_CPU1_SA_DQS_DP<1>")
		)
		(pad "23" smd rect
			(at -2.050034 -44.625006 270)
			(size 0.519938 1.4986)
			(layers "F.Cu" "F.Mask" "F.Paste")
			(net "M_C_CPU1_SA_DQS_DN<1>")
		)
		(pad "24" smd rect
			(at -2.050034 -43.775122 270)
			(size 0.519938 1.4986)
			(layers "F.Cu" "F.Mask" "F.Paste")
			(net "GND")
		)
		(pad "25" smd rect
			(at -2.050034 -42.924984 270)
			(size 0.519938 1.4986)
			(layers "F.Cu" "F.Mask" "F.Paste")
			(net "M_C_CPU1_SA_DQ<12>")
		)
		(pad "26" smd rect
			(at -2.050034 -42.0751 270)
			(size 0.519938 1.4986)
			(layers "F.Cu" "F.Mask" "F.Paste")
			(net "GND")
		)
		(pad "27" smd rect
			(at -2.050034 -41.224962 270)
			(size 0.519938 1.4986)
			(layers "F.Cu" "F.Mask" "F.Paste")
			(net "M_C_CPU1_SA_DQ<13>")
		)
		(pad "28" smd rect
			(at -2.050034 -40.375078 270)
			(size 0.519938 1.4986)
			(layers "F.Cu" "F.Mask" "F.Paste")
			(net "GND")
		)
		(pad "29" smd rect
			(at -2.050034 -39.52494 270)
			(size 0.519938 1.4986)
			(layers "F.Cu" "F.Mask" "F.Paste")
			(net "M_C_CPU1_SA_DQ<16>")
		)
		(pad "30" smd rect
			(at -2.050034 -38.675056 270)
			(size 0.519938 1.4986)
			(layers "F.Cu" "F.Mask" "F.Paste")
			(net "GND")
		)
		(pad "31" smd rect
			(at -2.050034 -37.824918 270)
			(size 0.519938 1.4986)
			(layers "F.Cu" "F.Mask" "F.Paste")
			(net "M_C_CPU1_SA_DQ<17>")
		)
		(pad "32" smd rect
			(at -2.050034 -36.975034 270)
			(size 0.519938 1.4986)
			(layers "F.Cu" "F.Mask" "F.Paste")
			(net "GND")
		)
		(pad "33" smd rect
			(at -2.050034 -36.124896 270)
			(size 0.519938 1.4986)
			(layers "F.Cu" "F.Mask" "F.Paste")
			(net "M_C_CPU1_SA_DQS_DP<2>")
		)
		(pad "34" smd rect
			(at -2.050034 -35.275012 270)
			(size 0.519938 1.4986)
			(layers "F.Cu" "F.Mask" "F.Paste")
			(net "M_C_CPU1_SA_DQS_DN<2>")
		)
		(pad "35" smd rect
			(at -2.050034 -34.425128 270)
			(size 0.519938 1.4986)
			(layers "F.Cu" "F.Mask" "F.Paste")
			(net "GND")
		)
		(pad "36" smd rect
			(at -2.050034 -33.57499 270)
			(size 0.519938 1.4986)
			(layers "F.Cu" "F.Mask" "F.Paste")
			(net "M_C_CPU1_SA_DQ<20>")
		)
		(pad "37" smd rect
			(at -2.050034 -32.725106 270)
			(size 0.519938 1.4986)
			(layers "F.Cu" "F.Mask" "F.Paste")
			(net "GND")
		)
		(pad "38" smd rect
			(at -2.050034 -31.874968 270)
			(size 0.519938 1.4986)
			(layers "F.Cu" "F.Mask" "F.Paste")
			(net "M_C_CPU1_SA_DQ<21>")
		)
		(pad "39" smd rect
			(at -2.050034 -31.025084 270)
			(size 0.519938 1.4986)
			(layers "F.Cu" "F.Mask" "F.Paste")
			(net "GND")
		)
		(pad "40" smd rect
			(at -2.050034 -30.174946 270)
			(size 0.519938 1.4986)
			(layers "F.Cu" "F.Mask" "F.Paste")
			(net "M_C_CPU1_SA_DQ<24>")
		)
		(pad "41" smd rect
			(at -2.050034 -29.325062 270)
			(size 0.519938 1.4986)
			(layers "F.Cu" "F.Mask" "F.Paste")
			(net "GND")
		)
		(pad "42" smd rect
			(at -2.050034 -28.474924 270)
			(size 0.519938 1.4986)
			(layers "F.Cu" "F.Mask" "F.Paste")
			(net "M_C_CPU1_SA_DQ<25>")
		)
		(pad "43" smd rect
			(at -2.050034 -27.62504 270)
			(size 0.519938 1.4986)
			(layers "F.Cu" "F.Mask" "F.Paste")
			(net "GND")
		)
		(pad "44" smd rect
			(at -2.050034 -26.774902 270)
			(size 0.519938 1.4986)
			(layers "F.Cu" "F.Mask" "F.Paste")
			(net "M_C_CPU1_SA_DQS_DP<3>")
		)
		(pad "45" smd rect
			(at -2.050034 -25.925018 270)
			(size 0.519938 1.4986)
			(layers "F.Cu" "F.Mask" "F.Paste")
			(net "M_C_CPU1_SA_DQS_DN<3>")
		)
		(pad "46" smd rect
			(at -2.050034 -25.07488 270)
			(size 0.519938 1.4986)
			(layers "F.Cu" "F.Mask" "F.Paste")
			(net "GND")
		)
		(pad "47" smd rect
			(at -2.050034 -24.224996 270)
			(size 0.519938 1.4986)
			(layers "F.Cu" "F.Mask" "F.Paste")
			(net "M_C_CPU1_SA_DQ<28>")
		)
		(pad "48" smd rect
			(at -2.050034 -23.375112 270)
			(size 0.519938 1.4986)
			(layers "F.Cu" "F.Mask" "F.Paste")
			(net "GND")
		)
		(pad "49" smd rect
			(at -2.050034 -22.524974 270)
			(size 0.519938 1.4986)
			(layers "F.Cu" "F.Mask" "F.Paste")
			(net "M_C_CPU1_SA_DQ<29>")
		)
		(pad "50" smd rect
			(at -2.050034 -21.67509 270)
			(size 0.519938 1.4986)
			(layers "F.Cu" "F.Mask" "F.Paste")
			(net "GND")
		)
		(pad "51" smd rect
			(at -2.050034 -20.824952 270)
			(size 0.519938 1.4986)
			(layers "F.Cu" "F.Mask" "F.Paste")
			(net "M_C_CPU1_SA_CB<0>")
		)
		(pad "52" smd rect
			(at -2.050034 -19.975068 270)
			(size 0.519938 1.4986)
			(layers "F.Cu" "F.Mask" "F.Paste")
			(net "GND")
		)
		(pad "53" smd rect
			(at -2.050034 -19.12493 270)
			(size 0.519938 1.4986)
			(layers "F.Cu" "F.Mask" "F.Paste")
			(net "M_C_CPU1_SA_CB<1>")
		)
		(pad "54" smd rect
			(at -2.050034 -18.275046 270)
			(size 0.519938 1.4986)
			(layers "F.Cu" "F.Mask" "F.Paste")
			(net "GND")
		)
		(pad "55" smd rect
			(at -2.050034 -17.424908 270)
			(size 0.519938 1.4986)
			(layers "F.Cu" "F.Mask" "F.Paste")
			(net "M_C_CPU1_SA_DQS_DP<4>")
		)
		(pad "56" smd rect
			(at -2.050034 -16.575024 270)
			(size 0.519938 1.4986)
			(layers "F.Cu" "F.Mask" "F.Paste")
			(net "M_C_CPU1_SA_DQS_DN<4>")
		)
		(pad "57" smd rect
			(at -2.050034 -15.724886 270)
			(size 0.519938 1.4986)
			(layers "F.Cu" "F.Mask" "F.Paste")
			(net "GND")
		)
		(pad "58" smd rect
			(at -2.050034 -14.875002 270)
			(size 0.519938 1.4986)
			(layers "F.Cu" "F.Mask" "F.Paste")
			(net "M_C_CPU1_SA_CB<4>")
		)
		(pad "59" smd rect
			(at -2.050034 -14.025118 270)
			(size 0.519938 1.4986)
			(layers "F.Cu" "F.Mask" "F.Paste")
			(net "GND")
		)
		(pad "60" smd rect
			(at -2.050034 -13.17498 270)
			(size 0.519938 1.4986)
			(layers "F.Cu" "F.Mask" "F.Paste")
			(net "M_C_CPU1_SA_CB<5>")
		)
		(pad "61" smd rect
			(at -2.050034 -12.325096 270)
			(size 0.519938 1.4986)
			(layers "F.Cu" "F.Mask" "F.Paste")
			(net "GND")
		)
		(pad "62" smd rect
			(at -2.050034 -11.474958 270)
			(size 0.519938 1.4986)
			(layers "F.Cu" "F.Mask" "F.Paste")
			(net "M_C_CPU1_ALERT_N")
		)
		(pad "63" smd rect
			(at -2.050034 -10.625074 270)
			(size 0.519938 1.4986)
			(layers "F.Cu" "F.Mask" "F.Paste")
			(net "GND")
		)
		(pad "64" smd rect
			(at -2.050034 -9.774936 270)
			(size 0.519938 1.4986)
			(layers "F.Cu" "F.Mask" "F.Paste")
			(net "M_C_CPU1_SA_CS_N<2>")
		)
		(pad "65" smd rect
			(at -2.050034 -8.925052 270)
			(size 0.519938 1.4986)
			(layers "F.Cu" "F.Mask" "F.Paste")
			(net "GND")
		)
		(pad "66" smd rect
			(at -2.050034 -8.074914 270)
			(size 0.519938 1.4986)
			(layers "F.Cu" "F.Mask" "F.Paste")
			(net "M_C_CPU1_SA_CA<0>")
		)
		(pad "67" smd rect
			(at -2.050034 -7.22503 270)
			(size 0.519938 1.4986)
			(layers "F.Cu" "F.Mask" "F.Paste")
			(net "GND")
		)
		(pad "68" smd rect
			(at -2.050034 -6.374892 270)
			(size 0.519938 1.4986)
			(layers "F.Cu" "F.Mask" "F.Paste")
			(net "M_C_CPU1_SA_CA<2>")
		)
		(pad "69" smd rect
			(at -2.050034 -5.525008 270)
			(size 0.519938 1.4986)
			(layers "F.Cu" "F.Mask" "F.Paste")
			(net "GND")
		)
		(pad "70" smd rect
			(at -2.050034 -4.675124 270)
			(size 0.519938 1.4986)
			(layers "F.Cu" "F.Mask" "F.Paste")
			(net "M_C_CPU1_SA_CA<4>")
		)
		(pad "71" smd rect
			(at -2.050034 -3.824986 270)
			(size 0.519938 1.4986)
			(layers "F.Cu" "F.Mask" "F.Paste")
			(net "GND")
		)
		(pad "72" smd rect
			(at -2.050034 -2.975102 270)
			(size 0.519938 1.4986)
			(layers "F.Cu" "F.Mask" "F.Paste")
			(net "M_C_CPU1_SA_CA<6>")
		)
		(pad "73" smd rect
			(at -2.050034 -2.124964 270)
			(size 0.519938 1.4986)
			(layers "F.Cu" "F.Mask" "F.Paste")
			(net "GND")
		)
		(pad "74" smd rect
			(at -2.050034 -1.27508 270)
			(size 0.519938 1.4986)
			(layers "F.Cu" "F.Mask" "F.Paste")
			(net "M_C_CPU1_SA_PAR")
		)
		(pad "75" smd rect
			(at -2.050034 -0.424942 270)
			(size 0.519938 1.4986)
			(layers "F.Cu" "F.Mask" "F.Paste")
			(net "GND")
		)
		(pad "76" smd rect
			(at -2.050034 5.525008 270)
			(size 0.519938 1.4986)
			(layers "F.Cu" "F.Mask" "F.Paste")
			(net "M_C_CPU1_SB_CA<0>")
		)
		(pad "77" smd rect
			(at -2.050034 6.374892 270)
			(size 0.519938 1.4986)
			(layers "F.Cu" "F.Mask" "F.Paste")
			(net "GND")
		)
		(pad "78" smd rect
			(at -2.050034 7.22503 270)
			(size 0.519938 1.4986)
			(layers "F.Cu" "F.Mask" "F.Paste")
			(net "M_C_CPU1_SB_CA<2>")
		)
		(pad "79" smd rect
			(at -2.050034 8.074914 270)
			(size 0.519938 1.4986)
			(layers "F.Cu" "F.Mask" "F.Paste")
			(net "GND")
		)
		(pad "80" smd rect
			(at -2.050034 8.925052 270)
			(size 0.519938 1.4986)
			(layers "F.Cu" "F.Mask" "F.Paste")
			(net "M_C_CPU1_SB_CA<4>")
		)
		(pad "81" smd rect
			(at -2.050034 9.774936 270)
			(size 0.519938 1.4986)
			(layers "F.Cu" "F.Mask" "F.Paste")
			(net "GND")
		)
		(pad "82" smd rect
			(at -2.050034 10.625074 270)
			(size 0.519938 1.4986)
			(layers "F.Cu" "F.Mask" "F.Paste")
			(net "M_C_CPU1_SB_CA<6>")
		)
		(pad "83" smd rect
			(at -2.050034 11.474958 270)
			(size 0.519938 1.4986)
			(layers "F.Cu" "F.Mask" "F.Paste")
			(net "GND")
		)
		(pad "84" smd rect
			(at -2.050034 12.325096 270)
			(size 0.519938 1.4986)
			(layers "F.Cu" "F.Mask" "F.Paste")
			(net "M_C_CPU1_SB_CS_N<2>")
		)
		(pad "85" smd rect
			(at -2.050034 13.17498 270)
			(size 0.519938 1.4986)
			(layers "F.Cu" "F.Mask" "F.Paste")
			(net "GND")
		)
		(pad "86" smd rect
			(at -2.050034 14.025118 270)
			(size 0.519938 1.4986)
			(layers "F.Cu" "F.Mask" "F.Paste")
			(net "M_C_CPU1_SA_RSP<1>")
		)
		(pad "87" smd rect
			(at -2.050034 14.875002 270)
			(size 0.519938 1.4986)
			(layers "F.Cu" "F.Mask" "F.Paste")
			(net "M_C_CPU1_SB_RSP<1>")
		)
		(pad "88" smd rect
			(at -2.050034 15.724886 270)
			(size 0.519938 1.4986)
			(layers "F.Cu" "F.Mask" "F.Paste")
			(net "GND")
		)
		(pad "89" smd rect
			(at -2.050034 16.575024 270)
			(size 0.519938 1.4986)
			(layers "F.Cu" "F.Mask" "F.Paste")
			(net "M_C_CPU1_SB_CB<4>")
		)
		(pad "90" smd rect
			(at -2.050034 17.424908 270)
			(size 0.519938 1.4986)
			(layers "F.Cu" "F.Mask" "F.Paste")
			(net "GND")
		)
		(pad "91" smd rect
			(at -2.050034 18.275046 270)
			(size 0.519938 1.4986)
			(layers "F.Cu" "F.Mask" "F.Paste")
			(net "M_C_CPU1_SB_CB<5>")
		)
		(pad "92" smd rect
			(at -2.050034 19.12493 270)
			(size 0.519938 1.4986)
			(layers "F.Cu" "F.Mask" "F.Paste")
			(net "GND")
		)
		(pad "93" smd rect
			(at -2.050034 19.975068 270)
			(size 0.519938 1.4986)
			(layers "F.Cu" "F.Mask" "F.Paste")
			(net "M_C_CPU1_SB_DQS_DP<9>")
		)
		(pad "94" smd rect
			(at -2.050034 20.824952 270)
			(size 0.519938 1.4986)
			(layers "F.Cu" "F.Mask" "F.Paste")
			(net "M_C_CPU1_SB_DQS_DN<9>")
		)
		(pad "95" smd rect
			(at -2.050034 21.67509 270)
			(size 0.519938 1.4986)
			(layers "F.Cu" "F.Mask" "F.Paste")
			(net "GND")
		)
		(pad "96" smd rect
			(at -2.050034 22.524974 270)
			(size 0.519938 1.4986)
			(layers "F.Cu" "F.Mask" "F.Paste")
			(net "M_C_CPU1_SB_CB<0>")
		)
		(pad "97" smd rect
			(at -2.050034 23.375112 270)
			(size 0.519938 1.4986)
			(layers "F.Cu" "F.Mask" "F.Paste")
			(net "GND")
		)
		(pad "98" smd rect
			(at -2.050034 24.224996 270)
			(size 0.519938 1.4986)
			(layers "F.Cu" "F.Mask" "F.Paste")
			(net "M_C_CPU1_SB_CB<1>")
		)
		(pad "99" smd rect
			(at -2.050034 25.07488 270)
			(size 0.519938 1.4986)
			(layers "F.Cu" "F.Mask" "F.Paste")
			(net "GND")
		)
		(pad "100" smd rect
			(at -2.050034 25.925018 270)
			(size 0.519938 1.4986)
			(layers "F.Cu" "F.Mask" "F.Paste")
			(net "M_C_CPU1_SB_DQ<0>")
		)
		(pad "101" smd rect
			(at -2.050034 26.774902 270)
			(size 0.519938 1.4986)
			(layers "F.Cu" "F.Mask" "F.Paste")
			(net "GND")
		)
		(pad "102" smd rect
			(at -2.050034 27.62504 270)
			(size 0.519938 1.4986)
			(layers "F.Cu" "F.Mask" "F.Paste")
			(net "M_C_CPU1_SB_DQ<1>")
		)
		(pad "103" smd rect
			(at -2.050034 28.474924 270)
			(size 0.519938 1.4986)
			(layers "F.Cu" "F.Mask" "F.Paste")
			(net "GND")
		)
		(pad "104" smd rect
			(at -2.050034 29.325062 270)
			(size 0.519938 1.4986)
			(layers "F.Cu" "F.Mask" "F.Paste")
			(net "M_C_CPU1_SB_DQS_DP<0>")
		)
		(pad "105" smd rect
			(at -2.050034 30.174946 270)
			(size 0.519938 1.4986)
			(layers "F.Cu" "F.Mask" "F.Paste")
			(net "M_C_CPU1_SB_DQS_DN<0>")
		)
		(pad "106" smd rect
			(at -2.050034 31.025084 270)
			(size 0.519938 1.4986)
			(layers "F.Cu" "F.Mask" "F.Paste")
			(net "GND")
		)
		(pad "107" smd rect
			(at -2.050034 31.874968 270)
			(size 0.519938 1.4986)
			(layers "F.Cu" "F.Mask" "F.Paste")
			(net "M_C_CPU1_SB_DQ<4>")
		)
		(pad "108" smd rect
			(at -2.050034 32.725106 270)
			(size 0.519938 1.4986)
			(layers "F.Cu" "F.Mask" "F.Paste")
			(net "GND")
		)
		(pad "109" smd rect
			(at -2.050034 33.57499 270)
			(size 0.519938 1.4986)
			(layers "F.Cu" "F.Mask" "F.Paste")
			(net "M_C_CPU1_SB_DQ<5>")
		)
		(pad "110" smd rect
			(at -2.050034 34.425128 270)
			(size 0.519938 1.4986)
			(layers "F.Cu" "F.Mask" "F.Paste")
			(net "GND")
		)
		(pad "111" smd rect
			(at -2.050034 35.275012 270)
			(size 0.519938 1.4986)
			(layers "F.Cu" "F.Mask" "F.Paste")
			(net "M_C_CPU1_SB_DQ<8>")
		)
		(pad "112" smd rect
			(at -2.050034 36.124896 270)
			(size 0.519938 1.4986)
			(layers "F.Cu" "F.Mask" "F.Paste")
			(net "GND")
		)
		(pad "113" smd rect
			(at -2.050034 36.975034 270)
			(size 0.519938 1.4986)
			(layers "F.Cu" "F.Mask" "F.Paste")
			(net "M_C_CPU1_SB_DQ<9>")
		)
		(pad "114" smd rect
			(at -2.050034 37.824918 270)
			(size 0.519938 1.4986)
			(layers "F.Cu" "F.Mask" "F.Paste")
			(net "GND")
		)
		(pad "115" smd rect
			(at -2.050034 38.675056 270)
			(size 0.519938 1.4986)
			(layers "F.Cu" "F.Mask" "F.Paste")
			(net "M_C_CPU1_SB_DQS_DP<1>")
		)
		(pad "116" smd rect
			(at -2.050034 39.52494 270)
			(size 0.519938 1.4986)
			(layers "F.Cu" "F.Mask" "F.Paste")
			(net "M_C_CPU1_SB_DQS_DN<1>")
		)
		(pad "117" smd rect
			(at -2.050034 40.375078 270)
			(size 0.519938 1.4986)
			(layers "F.Cu" "F.Mask" "F.Paste")
			(net "GND")
		)
		(pad "118" smd rect
			(at -2.050034 41.224962 270)
			(size 0.519938 1.4986)
			(layers "F.Cu" "F.Mask" "F.Paste")
			(net "M_C_CPU1_SB_DQ<12>")
		)
		(pad "119" smd rect
			(at -2.050034 42.0751 270)
			(size 0.519938 1.4986)
			(layers "F.Cu" "F.Mask" "F.Paste")
			(net "GND")
		)
		(pad "120" smd rect
			(at -2.050034 42.924984 270)
			(size 0.519938 1.4986)
			(layers "F.Cu" "F.Mask" "F.Paste")
			(net "M_C_CPU1_SB_DQ<13>")
		)
		(pad "121" smd rect
			(at -2.050034 43.775122 270)
			(size 0.519938 1.4986)
			(layers "F.Cu" "F.Mask" "F.Paste")
			(net "GND")
		)
		(pad "122" smd rect
			(at -2.050034 44.625006 270)
			(size 0.519938 1.4986)
			(layers "F.Cu" "F.Mask" "F.Paste")
			(net "M_C_CPU1_SB_DQ<16>")
		)
		(pad "123" smd rect
			(at -2.050034 45.47489 270)
			(size 0.519938 1.4986)
			(layers "F.Cu" "F.Mask" "F.Paste")
			(net "GND")
		)
		(pad "124" smd rect
			(at -2.050034 46.325028 270)
			(size 0.519938 1.4986)
			(layers "F.Cu" "F.Mask" "F.Paste")
			(net "M_C_CPU1_SB_DQ<17>")
		)
		(pad "125" smd rect
			(at -2.050034 47.174912 270)
			(size 0.519938 1.4986)
			(layers "F.Cu" "F.Mask" "F.Paste")
			(net "GND")
		)
		(pad "126" smd rect
			(at -2.050034 48.02505 270)
			(size 0.519938 1.4986)
			(layers "F.Cu" "F.Mask" "F.Paste")
			(net "M_C_CPU1_SB_DQS_DP<2>")
		)
		(pad "127" smd rect
			(at -2.050034 48.874934 270)
			(size 0.519938 1.4986)
			(layers "F.Cu" "F.Mask" "F.Paste")
			(net "M_C_CPU1_SB_DQS_DN<2>")
		)
		(pad "128" smd rect
			(at -2.050034 49.725072 270)
			(size 0.519938 1.4986)
			(layers "F.Cu" "F.Mask" "F.Paste")
			(net "GND")
		)
		(pad "129" smd rect
			(at -2.050034 50.574956 270)
			(size 0.519938 1.4986)
			(layers "F.Cu" "F.Mask" "F.Paste")
			(net "M_C_CPU1_SB_DQ<20>")
		)
		(pad "130" smd rect
			(at -2.050034 51.425094 270)
			(size 0.519938 1.4986)
			(layers "F.Cu" "F.Mask" "F.Paste")
			(net "GND")
		)
		(pad "131" smd rect
			(at -2.050034 52.274978 270)
			(size 0.519938 1.4986)
			(layers "F.Cu" "F.Mask" "F.Paste")
			(net "M_C_CPU1_SB_DQ<21>")
		)
		(pad "132" smd rect
			(at -2.050034 53.125116 270)
			(size 0.519938 1.4986)
			(layers "F.Cu" "F.Mask" "F.Paste")
			(net "GND")
		)
		(pad "133" smd rect
			(at -2.050034 53.975 270)
			(size 0.519938 1.4986)
			(layers "F.Cu" "F.Mask" "F.Paste")
			(net "M_C_CPU1_SB_DQ<24>")
		)
		(pad "134" smd rect
			(at -2.050034 54.824884 270)
			(size 0.519938 1.4986)
			(layers "F.Cu" "F.Mask" "F.Paste")
			(net "GND")
		)
		(pad "135" smd rect
			(at -2.050034 55.675022 270)
			(size 0.519938 1.4986)
			(layers "F.Cu" "F.Mask" "F.Paste")
			(net "M_C_CPU1_SB_DQ<25>")
		)
		(pad "136" smd rect
			(at -2.050034 56.524906 270)
			(size 0.519938 1.4986)
			(layers "F.Cu" "F.Mask" "F.Paste")
			(net "GND")
		)
		(pad "137" smd rect
			(at -2.050034 57.375044 270)
			(size 0.519938 1.4986)
			(layers "F.Cu" "F.Mask" "F.Paste")
			(net "M_C_CPU1_SB_DQS_DP<3>")
		)
		(pad "138" smd rect
			(at -2.050034 58.224928 270)
			(size 0.519938 1.4986)
			(layers "F.Cu" "F.Mask" "F.Paste")
			(net "M_C_CPU1_SB_DQS_DN<3>")
		)
		(pad "139" smd rect
			(at -2.050034 59.075066 270)
			(size 0.519938 1.4986)
			(layers "F.Cu" "F.Mask" "F.Paste")
			(net "GND")
		)
		(pad "140" smd rect
			(at -2.050034 59.92495 270)
			(size 0.519938 1.4986)
			(layers "F.Cu" "F.Mask" "F.Paste")
			(net "M_C_CPU1_SB_DQ<28>")
		)
		(pad "141" smd rect
			(at -2.050034 60.775088 270)
			(size 0.519938 1.4986)
			(layers "F.Cu" "F.Mask" "F.Paste")
			(net "GND")
		)
		(pad "142" smd rect
			(at -2.050034 61.624972 270)
			(size 0.519938 1.4986)
			(layers "F.Cu" "F.Mask" "F.Paste")
			(net "M_C_CPU1_SB_DQ<29>")
		)
		(pad "143" smd rect
			(at -2.050034 62.47511 270)
			(size 0.519938 1.4986)
			(layers "F.Cu" "F.Mask" "F.Paste")
			(net "GND")
		)
		(pad "144" smd rect
			(at -2.050034 63.324994 270)
			(size 0.519938 1.4986)
			(layers "F.Cu" "F.Mask" "F.Paste")
			(net "TP_CHC_CPU1_DIMM2_FRU_1")
		)
		(pad "145" smd rect
			(at 2.050034 -63.324994 270)
			(size 0.519938 1.4986)
			(layers "F.Cu" "F.Mask" "F.Paste")
			(net "P12V_S3_AUX_CPU1_NVDIMM")
		)
		(pad "146" smd rect
			(at 2.050034 -62.47511 270)
			(size 0.519938 1.4986)
			(layers "F.Cu" "F.Mask" "F.Paste")
			(net "P12V_S3_AUX_CPU1_NVDIMM")
		)
		(pad "147" smd rect
			(at 2.050034 -61.624972 270)
			(size 0.519938 1.4986)
			(layers "F.Cu" "F.Mask" "F.Paste")
			(net "PWRGD_CHC_CPU1_DIMM2")
		)
		(pad "148" smd rect
			(at 2.050034 -60.775088 270)
			(size 0.519938 1.4986)
			(layers "F.Cu" "F.Mask" "F.Paste")
			(net "PD_CHC_CPU1_DIMM2_SAA")
		)
		(pad "149" smd rect
			(at 2.050034 -59.92495 270)
			(size 0.519938 1.4986)
			(layers "F.Cu" "F.Mask" "F.Paste")
			(net "TP_CHC_CPU1_DIMM2_FRU_2")
		)
		(pad "150" smd rect
			(at 2.050034 -59.075066 270)
			(size 0.519938 1.4986)
			(layers "F.Cu" "F.Mask" "F.Paste")
			(net "TP_CHC_CPU1_DIMM2_FRU_3")
		)
		(pad "151" smd rect
			(at 2.050034 -58.224928 270)
			(size 0.519938 1.4986)
			(layers "F.Cu" "F.Mask" "F.Paste")
			(net "GND")
		)
		(pad "152" smd rect
			(at 2.050034 -57.375044 270)
			(size 0.519938 1.4986)
			(layers "F.Cu" "F.Mask" "F.Paste")
			(net "M_C_CPU1_SA_DQ<2>")
		)
		(pad "153" smd rect
			(at 2.050034 -56.524906 270)
			(size 0.519938 1.4986)
			(layers "F.Cu" "F.Mask" "F.Paste")
			(net "GND")
		)
		(pad "154" smd rect
			(at 2.050034 -55.675022 270)
			(size 0.519938 1.4986)
			(layers "F.Cu" "F.Mask" "F.Paste")
			(net "M_C_CPU1_SA_DQ<3>")
		)
		(pad "155" smd rect
			(at 2.050034 -54.824884 270)
			(size 0.519938 1.4986)
			(layers "F.Cu" "F.Mask" "F.Paste")
			(net "GND")
		)
		(pad "156" smd rect
			(at 2.050034 -53.975 270)
			(size 0.519938 1.4986)
			(layers "F.Cu" "F.Mask" "F.Paste")
			(net "M_C_CPU1_SA_DQS_DN<5>")
		)
		(pad "157" smd rect
			(at 2.050034 -53.125116 270)
			(size 0.519938 1.4986)
			(layers "F.Cu" "F.Mask" "F.Paste")
			(net "M_C_CPU1_SA_DQS_DP<5>")
		)
		(pad "158" smd rect
			(at 2.050034 -52.274978 270)
			(size 0.519938 1.4986)
			(layers "F.Cu" "F.Mask" "F.Paste")
			(net "GND")
		)
		(pad "159" smd rect
			(at 2.050034 -51.425094 270)
			(size 0.519938 1.4986)
			(layers "F.Cu" "F.Mask" "F.Paste")
			(net "M_C_CPU1_SA_DQ<6>")
		)
		(pad "160" smd rect
			(at 2.050034 -50.574956 270)
			(size 0.519938 1.4986)
			(layers "F.Cu" "F.Mask" "F.Paste")
			(net "GND")
		)
		(pad "161" smd rect
			(at 2.050034 -49.725072 270)
			(size 0.519938 1.4986)
			(layers "F.Cu" "F.Mask" "F.Paste")
			(net "M_C_CPU1_SA_DQ<7>")
		)
		(pad "162" smd rect
			(at 2.050034 -48.874934 270)
			(size 0.519938 1.4986)
			(layers "F.Cu" "F.Mask" "F.Paste")
			(net "GND")
		)
		(pad "163" smd rect
			(at 2.050034 -48.02505 270)
			(size 0.519938 1.4986)
			(layers "F.Cu" "F.Mask" "F.Paste")
			(net "M_C_CPU1_SA_DQ<10>")
		)
		(pad "164" smd rect
			(at 2.050034 -47.174912 270)
			(size 0.519938 1.4986)
			(layers "F.Cu" "F.Mask" "F.Paste")
			(net "GND")
		)
		(pad "165" smd rect
			(at 2.050034 -46.325028 270)
			(size 0.519938 1.4986)
			(layers "F.Cu" "F.Mask" "F.Paste")
			(net "M_C_CPU1_SA_DQ<11>")
		)
		(pad "166" smd rect
			(at 2.050034 -45.47489 270)
			(size 0.519938 1.4986)
			(layers "F.Cu" "F.Mask" "F.Paste")
			(net "GND")
		)
		(pad "167" smd rect
			(at 2.050034 -44.625006 270)
			(size 0.519938 1.4986)
			(layers "F.Cu" "F.Mask" "F.Paste")
			(net "M_C_CPU1_SA_DQS_DN<6>")
		)
		(pad "168" smd rect
			(at 2.050034 -43.775122 270)
			(size 0.519938 1.4986)
			(layers "F.Cu" "F.Mask" "F.Paste")
			(net "M_C_CPU1_SA_DQS_DP<6>")
		)
		(pad "169" smd rect
			(at 2.050034 -42.924984 270)
			(size 0.519938 1.4986)
			(layers "F.Cu" "F.Mask" "F.Paste")
			(net "GND")
		)
		(pad "170" smd rect
			(at 2.050034 -42.0751 270)
			(size 0.519938 1.4986)
			(layers "F.Cu" "F.Mask" "F.Paste")
			(net "M_C_CPU1_SA_DQ<14>")
		)
		(pad "171" smd rect
			(at 2.050034 -41.224962 270)
			(size 0.519938 1.4986)
			(layers "F.Cu" "F.Mask" "F.Paste")
			(net "GND")
		)
		(pad "172" smd rect
			(at 2.050034 -40.375078 270)
			(size 0.519938 1.4986)
			(layers "F.Cu" "F.Mask" "F.Paste")
			(net "M_C_CPU1_SA_DQ<15>")
		)
		(pad "173" smd rect
			(at 2.050034 -39.52494 270)
			(size 0.519938 1.4986)
			(layers "F.Cu" "F.Mask" "F.Paste")
			(net "GND")
		)
		(pad "174" smd rect
			(at 2.050034 -38.675056 270)
			(size 0.519938 1.4986)
			(layers "F.Cu" "F.Mask" "F.Paste")
			(net "M_C_CPU1_SA_DQ<18>")
		)
		(pad "175" smd rect
			(at 2.050034 -37.824918 270)
			(size 0.519938 1.4986)
			(layers "F.Cu" "F.Mask" "F.Paste")
			(net "GND")
		)
		(pad "176" smd rect
			(at 2.050034 -36.975034 270)
			(size 0.519938 1.4986)
			(layers "F.Cu" "F.Mask" "F.Paste")
			(net "M_C_CPU1_SA_DQ<19>")
		)
		(pad "177" smd rect
			(at 2.050034 -36.124896 270)
			(size 0.519938 1.4986)
			(layers "F.Cu" "F.Mask" "F.Paste")
			(net "GND")
		)
		(pad "178" smd rect
			(at 2.050034 -35.275012 270)
			(size 0.519938 1.4986)
			(layers "F.Cu" "F.Mask" "F.Paste")
			(net "M_C_CPU1_SA_DQS_DN<7>")
		)
		(pad "179" smd rect
			(at 2.050034 -34.425128 270)
			(size 0.519938 1.4986)
			(layers "F.Cu" "F.Mask" "F.Paste")
			(net "M_C_CPU1_SA_DQS_DP<7>")
		)
		(pad "180" smd rect
			(at 2.050034 -33.57499 270)
			(size 0.519938 1.4986)
			(layers "F.Cu" "F.Mask" "F.Paste")
			(net "GND")
		)
		(pad "181" smd rect
			(at 2.050034 -32.725106 270)
			(size 0.519938 1.4986)
			(layers "F.Cu" "F.Mask" "F.Paste")
			(net "M_C_CPU1_SA_DQ<22>")
		)
		(pad "182" smd rect
			(at 2.050034 -31.874968 270)
			(size 0.519938 1.4986)
			(layers "F.Cu" "F.Mask" "F.Paste")
			(net "GND")
		)
		(pad "183" smd rect
			(at 2.050034 -31.025084 270)
			(size 0.519938 1.4986)
			(layers "F.Cu" "F.Mask" "F.Paste")
			(net "M_C_CPU1_SA_DQ<23>")
		)
		(pad "184" smd rect
			(at 2.050034 -30.174946 270)
			(size 0.519938 1.4986)
			(layers "F.Cu" "F.Mask" "F.Paste")
			(net "GND")
		)
		(pad "185" smd rect
			(at 2.050034 -29.325062 270)
			(size 0.519938 1.4986)
			(layers "F.Cu" "F.Mask" "F.Paste")
			(net "M_C_CPU1_SA_DQ<26>")
		)
		(pad "186" smd rect
			(at 2.050034 -28.474924 270)
			(size 0.519938 1.4986)
			(layers "F.Cu" "F.Mask" "F.Paste")
			(net "GND")
		)
		(pad "187" smd rect
			(at 2.050034 -27.62504 270)
			(size 0.519938 1.4986)
			(layers "F.Cu" "F.Mask" "F.Paste")
			(net "M_C_CPU1_SA_DQ<27>")
		)
		(pad "188" smd rect
			(at 2.050034 -26.774902 270)
			(size 0.519938 1.4986)
			(layers "F.Cu" "F.Mask" "F.Paste")
			(net "GND")
		)
		(pad "189" smd rect
			(at 2.050034 -25.925018 270)
			(size 0.519938 1.4986)
			(layers "F.Cu" "F.Mask" "F.Paste")
			(net "M_C_CPU1_SA_DQS_DN<8>")
		)
		(pad "190" smd rect
			(at 2.050034 -25.07488 270)
			(size 0.519938 1.4986)
			(layers "F.Cu" "F.Mask" "F.Paste")
			(net "M_C_CPU1_SA_DQS_DP<8>")
		)
		(pad "191" smd rect
			(at 2.050034 -24.224996 270)
			(size 0.519938 1.4986)
			(layers "F.Cu" "F.Mask" "F.Paste")
			(net "GND")
		)
		(pad "192" smd rect
			(at 2.050034 -23.375112 270)
			(size 0.519938 1.4986)
			(layers "F.Cu" "F.Mask" "F.Paste")
			(net "M_C_CPU1_SA_DQ<30>")
		)
		(pad "193" smd rect
			(at 2.050034 -22.524974 270)
			(size 0.519938 1.4986)
			(layers "F.Cu" "F.Mask" "F.Paste")
			(net "GND")
		)
		(pad "194" smd rect
			(at 2.050034 -21.67509 270)
			(size 0.519938 1.4986)
			(layers "F.Cu" "F.Mask" "F.Paste")
			(net "M_C_CPU1_SA_DQ<31>")
		)
		(pad "195" smd rect
			(at 2.050034 -20.824952 270)
			(size 0.519938 1.4986)
			(layers "F.Cu" "F.Mask" "F.Paste")
			(net "GND")
		)
		(pad "196" smd rect
			(at 2.050034 -19.975068 270)
			(size 0.519938 1.4986)
			(layers "F.Cu" "F.Mask" "F.Paste")
			(net "M_C_CPU1_SA_CB<2>")
		)
		(pad "197" smd rect
			(at 2.050034 -19.12493 270)
			(size 0.519938 1.4986)
			(layers "F.Cu" "F.Mask" "F.Paste")
			(net "GND")
		)
		(pad "198" smd rect
			(at 2.050034 -18.275046 270)
			(size 0.519938 1.4986)
			(layers "F.Cu" "F.Mask" "F.Paste")
			(net "M_C_CPU1_SA_CB<3>")
		)
		(pad "199" smd rect
			(at 2.050034 -17.424908 270)
			(size 0.519938 1.4986)
			(layers "F.Cu" "F.Mask" "F.Paste")
			(net "GND")
		)
		(pad "200" smd rect
			(at 2.050034 -16.575024 270)
			(size 0.519938 1.4986)
			(layers "F.Cu" "F.Mask" "F.Paste")
			(net "M_C_CPU1_SA_DQS_DN<9>")
		)
		(pad "201" smd rect
			(at 2.050034 -15.724886 270)
			(size 0.519938 1.4986)
			(layers "F.Cu" "F.Mask" "F.Paste")
			(net "M_C_CPU1_SA_DQS_DP<9>")
		)
		(pad "202" smd rect
			(at 2.050034 -14.875002 270)
			(size 0.519938 1.4986)
			(layers "F.Cu" "F.Mask" "F.Paste")
			(net "GND")
		)
		(pad "203" smd rect
			(at 2.050034 -14.025118 270)
			(size 0.519938 1.4986)
			(layers "F.Cu" "F.Mask" "F.Paste")
			(net "M_C_CPU1_SA_CB<6>")
		)
		(pad "204" smd rect
			(at 2.050034 -13.17498 270)
			(size 0.519938 1.4986)
			(layers "F.Cu" "F.Mask" "F.Paste")
			(net "GND")
		)
		(pad "205" smd rect
			(at 2.050034 -12.325096 270)
			(size 0.519938 1.4986)
			(layers "F.Cu" "F.Mask" "F.Paste")
			(net "M_C_CPU1_SA_CB<7>")
		)
		(pad "206" smd rect
			(at 2.050034 -11.474958 270)
			(size 0.519938 1.4986)
			(layers "F.Cu" "F.Mask" "F.Paste")
			(net "GND")
		)
		(pad "207" smd rect
			(at 2.050034 -10.625074 270)
			(size 0.519938 1.4986)
			(layers "F.Cu" "F.Mask" "F.Paste")
			(net "RST_M_CD_CPU1_FPGA_N")
		)
		(pad "208" smd rect
			(at 2.050034 -9.774936 270)
			(size 0.519938 1.4986)
			(layers "F.Cu" "F.Mask" "F.Paste")
			(net "GND")
		)
		(pad "209" smd rect
			(at 2.050034 -8.925052 270)
			(size 0.519938 1.4986)
			(layers "F.Cu" "F.Mask" "F.Paste")
			(net "M_C_CPU1_SA_CS_N<3>")
		)
		(pad "210" smd rect
			(at 2.050034 -8.074914 270)
			(size 0.519938 1.4986)
			(layers "F.Cu" "F.Mask" "F.Paste")
			(net "GND")
		)
		(pad "211" smd rect
			(at 2.050034 -7.22503 270)
			(size 0.519938 1.4986)
			(layers "F.Cu" "F.Mask" "F.Paste")
			(net "M_C_CPU1_SA_CA<1>")
		)
		(pad "212" smd rect
			(at 2.050034 -6.374892 270)
			(size 0.519938 1.4986)
			(layers "F.Cu" "F.Mask" "F.Paste")
			(net "GND")
		)
		(pad "213" smd rect
			(at 2.050034 -5.525008 270)
			(size 0.519938 1.4986)
			(layers "F.Cu" "F.Mask" "F.Paste")
			(net "M_C_CPU1_SA_CA<3>")
		)
		(pad "214" smd rect
			(at 2.050034 -4.675124 270)
			(size 0.519938 1.4986)
			(layers "F.Cu" "F.Mask" "F.Paste")
			(net "GND")
		)
		(pad "215" smd rect
			(at 2.050034 -3.824986 270)
			(size 0.519938 1.4986)
			(layers "F.Cu" "F.Mask" "F.Paste")
			(net "M_C_CPU1_SA_CA<5>")
		)
		(pad "216" smd rect
			(at 2.050034 -2.975102 270)
			(size 0.519938 1.4986)
			(layers "F.Cu" "F.Mask" "F.Paste")
			(net "GND")
		)
		(pad "217" smd rect
			(at 2.050034 -2.124964 270)
			(size 0.519938 1.4986)
			(layers "F.Cu" "F.Mask" "F.Paste")
			(net "M_C_CPU1_CLK_DP<1>")
		)
		(pad "218" smd rect
			(at 2.050034 -1.27508 270)
			(size 0.519938 1.4986)
			(layers "F.Cu" "F.Mask" "F.Paste")
			(net "M_C_CPU1_CLK_DN<1>")
		)
		(pad "219" smd rect
			(at 2.050034 -0.424942 270)
			(size 0.519938 1.4986)
			(layers "F.Cu" "F.Mask" "F.Paste")
			(net "GND")
		)
		(pad "220" smd rect
			(at 2.050034 5.525008 270)
			(size 0.519938 1.4986)
			(layers "F.Cu" "F.Mask" "F.Paste")
			(net "TP_CHC_CPU1_DIMM2_FRU_4")
		)
		(pad "221" smd rect
			(at 2.050034 6.374892 270)
			(size 0.519938 1.4986)
			(layers "F.Cu" "F.Mask" "F.Paste")
			(net "M_C_CPU1_SB_CA<1>")
		)
		(pad "222" smd rect
			(at 2.050034 7.22503 270)
			(size 0.519938 1.4986)
			(layers "F.Cu" "F.Mask" "F.Paste")
			(net "GND")
		)
		(pad "223" smd rect
			(at 2.050034 8.074914 270)
			(size 0.519938 1.4986)
			(layers "F.Cu" "F.Mask" "F.Paste")
			(net "M_C_CPU1_SB_CA<3>")
		)
		(pad "224" smd rect
			(at 2.050034 8.925052 270)
			(size 0.519938 1.4986)
			(layers "F.Cu" "F.Mask" "F.Paste")
			(net "GND")
		)
		(pad "225" smd rect
			(at 2.050034 9.774936 270)
			(size 0.519938 1.4986)
			(layers "F.Cu" "F.Mask" "F.Paste")
			(net "M_C_CPU1_SB_CA<5>")
		)
		(pad "226" smd rect
			(at 2.050034 10.625074 270)
			(size 0.519938 1.4986)
			(layers "F.Cu" "F.Mask" "F.Paste")
			(net "GND")
		)
		(pad "227" smd rect
			(at 2.050034 11.474958 270)
			(size 0.519938 1.4986)
			(layers "F.Cu" "F.Mask" "F.Paste")
			(net "M_C_CPU1_SB_PAR")
		)
		(pad "228" smd rect
			(at 2.050034 12.325096 270)
			(size 0.519938 1.4986)
			(layers "F.Cu" "F.Mask" "F.Paste")
			(net "GND")
		)
		(pad "229" smd rect
			(at 2.050034 13.17498 270)
			(size 0.519938 1.4986)
			(layers "F.Cu" "F.Mask" "F.Paste")
			(net "M_C_CPU1_SB_CS_N<3>")
		)
		(pad "230" smd rect
			(at 2.050034 14.025118 270)
			(size 0.519938 1.4986)
			(layers "F.Cu" "F.Mask" "F.Paste")
			(net "GND")
		)
		(pad "231" smd rect
			(at 2.050034 14.875002 270)
			(size 0.519938 1.4986)
			(layers "F.Cu" "F.Mask" "F.Paste")
			(net "TP_CHC_CPU1_DIMM2_FRU_5")
		)
		(pad "232" smd rect
			(at 2.050034 15.724886 270)
			(size 0.519938 1.4986)
			(layers "F.Cu" "F.Mask" "F.Paste")
			(net "TP_CHC_CPU1_DIMM2_FRU_6")
		)
		(pad "233" smd rect
			(at 2.050034 16.575024 270)
			(size 0.519938 1.4986)
			(layers "F.Cu" "F.Mask" "F.Paste")
			(net "GND")
		)
		(pad "234" smd rect
			(at 2.050034 17.424908 270)
			(size 0.519938 1.4986)
			(layers "F.Cu" "F.Mask" "F.Paste")
			(net "M_C_CPU1_SB_CB<6>")
		)
		(pad "235" smd rect
			(at 2.050034 18.275046 270)
			(size 0.519938 1.4986)
			(layers "F.Cu" "F.Mask" "F.Paste")
			(net "GND")
		)
		(pad "236" smd rect
			(at 2.050034 19.12493 270)
			(size 0.519938 1.4986)
			(layers "F.Cu" "F.Mask" "F.Paste")
			(net "M_C_CPU1_SB_CB<7>")
		)
		(pad "237" smd rect
			(at 2.050034 19.975068 270)
			(size 0.519938 1.4986)
			(layers "F.Cu" "F.Mask" "F.Paste")
			(net "GND")
		)
		(pad "238" smd rect
			(at 2.050034 20.824952 270)
			(size 0.519938 1.4986)
			(layers "F.Cu" "F.Mask" "F.Paste")
			(net "M_C_CPU1_SB_DQS_DN<4>")
		)
		(pad "239" smd rect
			(at 2.050034 21.67509 270)
			(size 0.519938 1.4986)
			(layers "F.Cu" "F.Mask" "F.Paste")
			(net "M_C_CPU1_SB_DQS_DP<4>")
		)
		(pad "240" smd rect
			(at 2.050034 22.524974 270)
			(size 0.519938 1.4986)
			(layers "F.Cu" "F.Mask" "F.Paste")
			(net "GND")
		)
		(pad "241" smd rect
			(at 2.050034 23.375112 270)
			(size 0.519938 1.4986)
			(layers "F.Cu" "F.Mask" "F.Paste")
			(net "M_C_CPU1_SB_CB<2>")
		)
		(pad "242" smd rect
			(at 2.050034 24.224996 270)
			(size 0.519938 1.4986)
			(layers "F.Cu" "F.Mask" "F.Paste")
			(net "GND")
		)
		(pad "243" smd rect
			(at 2.050034 25.07488 270)
			(size 0.519938 1.4986)
			(layers "F.Cu" "F.Mask" "F.Paste")
			(net "M_C_CPU1_SB_CB<3>")
		)
		(pad "244" smd rect
			(at 2.050034 25.925018 270)
			(size 0.519938 1.4986)
			(layers "F.Cu" "F.Mask" "F.Paste")
			(net "GND")
		)
		(pad "245" smd rect
			(at 2.050034 26.774902 270)
			(size 0.519938 1.4986)
			(layers "F.Cu" "F.Mask" "F.Paste")
			(net "M_C_CPU1_SB_DQ<2>")
		)
		(pad "246" smd rect
			(at 2.050034 27.62504 270)
			(size 0.519938 1.4986)
			(layers "F.Cu" "F.Mask" "F.Paste")
			(net "GND")
		)
		(pad "247" smd rect
			(at 2.050034 28.474924 270)
			(size 0.519938 1.4986)
			(layers "F.Cu" "F.Mask" "F.Paste")
			(net "M_C_CPU1_SB_DQ<3>")
		)
		(pad "248" smd rect
			(at 2.050034 29.325062 270)
			(size 0.519938 1.4986)
			(layers "F.Cu" "F.Mask" "F.Paste")
			(net "GND")
		)
		(pad "249" smd rect
			(at 2.050034 30.174946 270)
			(size 0.519938 1.4986)
			(layers "F.Cu" "F.Mask" "F.Paste")
			(net "M_C_CPU1_SB_DQS_DN<5>")
		)
		(pad "250" smd rect
			(at 2.050034 31.025084 270)
			(size 0.519938 1.4986)
			(layers "F.Cu" "F.Mask" "F.Paste")
			(net "M_C_CPU1_SB_DQS_DP<5>")
		)
		(pad "251" smd rect
			(at 2.050034 31.874968 270)
			(size 0.519938 1.4986)
			(layers "F.Cu" "F.Mask" "F.Paste")
			(net "GND")
		)
		(pad "252" smd rect
			(at 2.050034 32.725106 270)
			(size 0.519938 1.4986)
			(layers "F.Cu" "F.Mask" "F.Paste")
			(net "M_C_CPU1_SB_DQ<6>")
		)
		(pad "253" smd rect
			(at 2.050034 33.57499 270)
			(size 0.519938 1.4986)
			(layers "F.Cu" "F.Mask" "F.Paste")
			(net "GND")
		)
		(pad "254" smd rect
			(at 2.050034 34.425128 270)
			(size 0.519938 1.4986)
			(layers "F.Cu" "F.Mask" "F.Paste")
			(net "M_C_CPU1_SB_DQ<7>")
		)
		(pad "255" smd rect
			(at 2.050034 35.275012 270)
			(size 0.519938 1.4986)
			(layers "F.Cu" "F.Mask" "F.Paste")
			(net "GND")
		)
		(pad "256" smd rect
			(at 2.050034 36.124896 270)
			(size 0.519938 1.4986)
			(layers "F.Cu" "F.Mask" "F.Paste")
			(net "M_C_CPU1_SB_DQ<10>")
		)
		(pad "257" smd rect
			(at 2.050034 36.975034 270)
			(size 0.519938 1.4986)
			(layers "F.Cu" "F.Mask" "F.Paste")
			(net "GND")
		)
		(pad "258" smd rect
			(at 2.050034 37.824918 270)
			(size 0.519938 1.4986)
			(layers "F.Cu" "F.Mask" "F.Paste")
			(net "M_C_CPU1_SB_DQ<11>")
		)
		(pad "259" smd rect
			(at 2.050034 38.675056 270)
			(size 0.519938 1.4986)
			(layers "F.Cu" "F.Mask" "F.Paste")
			(net "GND")
		)
		(pad "260" smd rect
			(at 2.050034 39.52494 270)
			(size 0.519938 1.4986)
			(layers "F.Cu" "F.Mask" "F.Paste")
			(net "M_C_CPU1_SB_DQS_DN<6>")
		)
		(pad "261" smd rect
			(at 2.050034 40.375078 270)
			(size 0.519938 1.4986)
			(layers "F.Cu" "F.Mask" "F.Paste")
			(net "M_C_CPU1_SB_DQS_DP<6>")
		)
		(pad "262" smd rect
			(at 2.050034 41.224962 270)
			(size 0.519938 1.4986)
			(layers "F.Cu" "F.Mask" "F.Paste")
			(net "GND")
		)
		(pad "263" smd rect
			(at 2.050034 42.0751 270)
			(size 0.519938 1.4986)
			(layers "F.Cu" "F.Mask" "F.Paste")
			(net "M_C_CPU1_SB_DQ<14>")
		)
		(pad "264" smd rect
			(at 2.050034 42.924984 270)
			(size 0.519938 1.4986)
			(layers "F.Cu" "F.Mask" "F.Paste")
			(net "GND")
		)
		(pad "265" smd rect
			(at 2.050034 43.775122 270)
			(size 0.519938 1.4986)
			(layers "F.Cu" "F.Mask" "F.Paste")
			(net "M_C_CPU1_SB_DQ<15>")
		)
		(pad "266" smd rect
			(at 2.050034 44.625006 270)
			(size 0.519938 1.4986)
			(layers "F.Cu" "F.Mask" "F.Paste")
			(net "GND")
		)
		(pad "267" smd rect
			(at 2.050034 45.47489 270)
			(size 0.519938 1.4986)
			(layers "F.Cu" "F.Mask" "F.Paste")
			(net "M_C_CPU1_SB_DQ<18>")
		)
		(pad "268" smd rect
			(at 2.050034 46.325028 270)
			(size 0.519938 1.4986)
			(layers "F.Cu" "F.Mask" "F.Paste")
			(net "GND")
		)
		(pad "269" smd rect
			(at 2.050034 47.174912 270)
			(size 0.519938 1.4986)
			(layers "F.Cu" "F.Mask" "F.Paste")
			(net "M_C_CPU1_SB_DQ<19>")
		)
		(pad "270" smd rect
			(at 2.050034 48.02505 270)
			(size 0.519938 1.4986)
			(layers "F.Cu" "F.Mask" "F.Paste")
			(net "GND")
		)
		(pad "271" smd rect
			(at 2.050034 48.874934 270)
			(size 0.519938 1.4986)
			(layers "F.Cu" "F.Mask" "F.Paste")
			(net "M_C_CPU1_SB_DQS_DN<7>")
		)
		(pad "272" smd rect
			(at 2.050034 49.725072 270)
			(size 0.519938 1.4986)
			(layers "F.Cu" "F.Mask" "F.Paste")
			(net "M_C_CPU1_SB_DQS_DP<7>")
		)
		(pad "273" smd rect
			(at 2.050034 50.574956 270)
			(size 0.519938 1.4986)
			(layers "F.Cu" "F.Mask" "F.Paste")
			(net "GND")
		)
		(pad "274" smd rect
			(at 2.050034 51.425094 270)
			(size 0.519938 1.4986)
			(layers "F.Cu" "F.Mask" "F.Paste")
			(net "M_C_CPU1_SB_DQ<22>")
		)
		(pad "275" smd rect
			(at 2.050034 52.274978 270)
			(size 0.519938 1.4986)
			(layers "F.Cu" "F.Mask" "F.Paste")
			(net "GND")
		)
		(pad "276" smd rect
			(at 2.050034 53.125116 270)
			(size 0.519938 1.4986)
			(layers "F.Cu" "F.Mask" "F.Paste")
			(net "M_C_CPU1_SB_DQ<23>")
		)
		(pad "277" smd rect
			(at 2.050034 53.975 270)
			(size 0.519938 1.4986)
			(layers "F.Cu" "F.Mask" "F.Paste")
			(net "GND")
		)
		(pad "278" smd rect
			(at 2.050034 54.824884 270)
			(size 0.519938 1.4986)
			(layers "F.Cu" "F.Mask" "F.Paste")
			(net "M_C_CPU1_SB_DQ<26>")
		)
		(pad "279" smd rect
			(at 2.050034 55.675022 270)
			(size 0.519938 1.4986)
			(layers "F.Cu" "F.Mask" "F.Paste")
			(net "GND")
		)
		(pad "280" smd rect
			(at 2.050034 56.524906 270)
			(size 0.519938 1.4986)
			(layers "F.Cu" "F.Mask" "F.Paste")
			(net "M_C_CPU1_SB_DQ<27>")
		)
		(pad "281" smd rect
			(at 2.050034 57.375044 270)
			(size 0.519938 1.4986)
			(layers "F.Cu" "F.Mask" "F.Paste")
			(net "GND")
		)
		(pad "282" smd rect
			(at 2.050034 58.224928 270)
			(size 0.519938 1.4986)
			(layers "F.Cu" "F.Mask" "F.Paste")
			(net "M_C_CPU1_SB_DQS_DN<8>")
		)
		(pad "283" smd rect
			(at 2.050034 59.075066 270)
			(size 0.519938 1.4986)
			(layers "F.Cu" "F.Mask" "F.Paste")
			(net "M_C_CPU1_SB_DQS_DP<8>")
		)
		(pad "284" smd rect
			(at 2.050034 59.92495 270)
			(size 0.519938 1.4986)
			(layers "F.Cu" "F.Mask" "F.Paste")
			(net "GND")
		)
		(pad "285" smd rect
			(at 2.050034 60.775088 270)
			(size 0.519938 1.4986)
			(layers "F.Cu" "F.Mask" "F.Paste")
			(net "M_C_CPU1_SB_DQ<30>")
		)
		(pad "286" smd rect
			(at 2.050034 61.624972 270)
			(size 0.519938 1.4986)
			(layers "F.Cu" "F.Mask" "F.Paste")
			(net "GND")
		)
		(pad "287" smd rect
			(at 2.050034 62.47511 270)
			(size 0.519938 1.4986)
			(layers "F.Cu" "F.Mask" "F.Paste")
			(net "M_C_CPU1_SB_DQ<31>")
		)
		(pad "288" smd rect
			(at 2.050034 63.324994 270)
			(size 0.519938 1.4986)
			(layers "F.Cu" "F.Mask" "F.Paste")
			(net "GND")
		)
		(pad "G1" thru_hole oval
			(at 0 -68.97497)
			(size 2.8194 1.5748)
			(drill oval 2.4384 1.1938)
			(layers "*.Cu" "*.Mask")
			(remove_unused_layers no)
			(net "GND")
			(clearance 0.127)
			(thermal_gap 0.127)
		)
		(pad "G2" thru_hole oval
			(at 0 3.875024)
			(size 2.8194 1.5748)
			(drill oval 2.4384 1.1938)
			(layers "*.Cu" "*.Mask")
			(remove_unused_layers no)
			(net "GND")
			(clearance 0.127)
			(thermal_gap 0.127)
		)
		(pad "G3" thru_hole oval
			(at 0 68.97497)
			(size 2.8194 1.5748)
			(drill oval 2.4384 1.1938)
			(layers "*.Cu" "*.Mask")
			(remove_unused_layers no)
			(net "GND")
			(clearance 0.127)
			(thermal_gap 0.127)
		)
	)
	(footprint ""
		(layer "F.Cu")
		(at 453.719946 -102.598728)
		(property "Reference" "R1908"
			(at 0 0 0)
			(layer "F.SilkS")
			(hide yes)
			(effects
				(font
					(size 1.27 1.27)
				)
			)
		)
		(property "Value" ""
			(at 0 0 0)
			(layer "F.Fab")
			(effects
				(font
					(size 1.27 1.27)
				)
			)
		)
		(duplicate_pad_numbers_are_jumpers no)
		(fp_line
			(start -0.7874 -0.4064)
			(end 0.7874 -0.4064)
			(stroke
				(width 0.1524)
				(type default)
			)
			(layer "F.SilkS")
		)
		(fp_line
			(start -0.7874 0.4064)
			(end -0.7874 -0.4064)
			(stroke
				(width 0.1524)
				(type default)
			)
			(layer "F.SilkS")
		)
		(fp_line
			(start 0.7874 -0.4064)
			(end 0.7874 0.4064)
			(stroke
				(width 0.1524)
				(type default)
			)
			(layer "F.SilkS")
		)
		(fp_line
			(start 0.7874 0.4064)
			(end -0.7874 0.4064)
			(stroke
				(width 0.1524)
				(type default)
			)
			(layer "F.SilkS")
		)
		(fp_line
			(start -0.67945 -0.305054)
			(end -0.12065 -0.305054)
			(stroke
				(width 0.1)
				(type default)
			)
			(layer "F.Fab")
		)
		(fp_line
			(start -0.67945 0.3048)
			(end -0.67945 -0.305054)
			(stroke
				(width 0.1)
				(type default)
			)
			(layer "F.Fab")
		)
		(fp_line
			(start -0.12065 -0.305054)
			(end -0.12065 -0.2794)
			(stroke
				(width 0.1)
				(type default)
			)
			(layer "F.Fab")
		)
		(fp_line
			(start -0.12065 -0.2794)
			(end 0.12065 -0.2794)
			(stroke
				(width 0.1)
				(type default)
			)
			(layer "F.Fab")
		)
		(fp_line
			(start -0.12065 0.2794)
			(end -0.12065 0.3048)
			(stroke
				(width 0.1)
				(type default)
			)
			(layer "F.Fab")
		)
		(fp_line
			(start -0.12065 0.3048)
			(end -0.67945 0.3048)
			(stroke
				(width 0.1)
				(type default)
			)
			(layer "F.Fab")
		)
		(fp_line
			(start 0.120396 0.2794)
			(end -0.12065 0.2794)
			(stroke
				(width 0.1)
				(type default)
			)
			(layer "F.Fab")
		)
		(fp_line
			(start 0.120396 0.3048)
			(end 0.120396 0.2794)
			(stroke
				(width 0.1)
				(type default)
			)
			(layer "F.Fab")
		)
		(fp_line
			(start 0.12065 -0.3048)
			(end 0.67945 -0.3048)
			(stroke
				(width 0.1)
				(type default)
			)
			(layer "F.Fab")
		)
		(fp_line
			(start 0.12065 -0.2794)
			(end 0.12065 -0.3048)
			(stroke
				(width 0.1)
				(type default)
			)
			(layer "F.Fab")
		)
		(fp_line
			(start 0.67945 -0.3048)
			(end 0.67945 0.3048)
			(stroke
				(width 0.1)
				(type default)
			)
			(layer "F.Fab")
		)
		(fp_line
			(start 0.67945 0.3048)
			(end 0.120396 0.3048)
			(stroke
				(width 0.1)
				(type default)
			)
			(layer "F.Fab")
		)
		(pad "1" smd circle
			(at -0.40005 0)
			(size 0 0)
			(layers "F.Cu" "F.Mask" "F.Paste")
			(net "P3V3_AUX")
		)
		(pad "2" smd circle
			(at 0.40005 0)
			(size 0 0)
			(layers "F.Cu" "F.Mask" "F.Paste")
			(net "OCP_SFF_PRSNT3_R_N")
		)
	)
	(footprint ""
		(layer "F.Cu")
		(at 40.627554 -111.606838 180)
		(property "Reference" "R3865"
			(at 0 0 180)
			(layer "F.SilkS")
			(hide yes)
			(effects
				(font
					(size 1.27 1.27)
				)
			)
		)
		(property "Value" ""
			(at 0 0 180)
			(layer "F.Fab")
			(effects
				(font
					(size 1.27 1.27)
				)
			)
		)
		(duplicate_pad_numbers_are_jumpers no)
		(fp_line
			(start 0.7874 0.4064)
			(end -0.7874 0.4064)
			(stroke
				(width 0.1524)
				(type default)
			)
			(layer "F.SilkS")
		)
		(fp_line
			(start 0.7874 -0.4064)
			(end 0.7874 0.4064)
			(stroke
				(width 0.1524)
				(type default)
			)
			(layer "F.SilkS")
		)
		(fp_line
			(start -0.7874 0.4064)
			(end -0.7874 -0.4064)
			(stroke
				(width 0.1524)
				(type default)
			)
			(layer "F.SilkS")
		)
		(fp_line
			(start -0.7874 -0.4064)
			(end 0.7874 -0.4064)
			(stroke
				(width 0.1524)
				(type default)
			)
			(layer "F.SilkS")
		)
		(fp_line
			(start 0.67945 0.3048)
			(end 0.120396 0.3048)
			(stroke
				(width 0.1)
				(type default)
			)
			(layer "F.Fab")
		)
		(fp_line
			(start 0.67945 -0.3048)
			(end 0.67945 0.3048)
			(stroke
				(width 0.1)
				(type default)
			)
			(layer "F.Fab")
		)
		(fp_line
			(start 0.12065 -0.2794)
			(end 0.12065 -0.3048)
			(stroke
				(width 0.1)
				(type default)
			)
			(layer "F.Fab")
		)
		(fp_line
			(start 0.12065 -0.3048)
			(end 0.67945 -0.3048)
			(stroke
				(width 0.1)
				(type default)
			)
			(layer "F.Fab")
		)
		(fp_line
			(start 0.120396 0.3048)
			(end 0.120396 0.2794)
			(stroke
				(width 0.1)
				(type default)
			)
			(layer "F.Fab")
		)
		(fp_line
			(start 0.120396 0.2794)
			(end -0.12065 0.2794)
			(stroke
				(width 0.1)
				(type default)
			)
			(layer "F.Fab")
		)
		(fp_line
			(start -0.12065 0.3048)
			(end -0.67945 0.3048)
			(stroke
				(width 0.1)
				(type default)
			)
			(layer "F.Fab")
		)
		(fp_line
			(start -0.12065 0.2794)
			(end -0.12065 0.3048)
			(stroke
				(width 0.1)
				(type default)
			)
			(layer "F.Fab")
		)
		(fp_line
			(start -0.12065 -0.2794)
			(end 0.12065 -0.2794)
			(stroke
				(width 0.1)
				(type default)
			)
			(layer "F.Fab")
		)
		(fp_line
			(start -0.12065 -0.305054)
			(end -0.12065 -0.2794)
			(stroke
				(width 0.1)
				(type default)
			)
			(layer "F.Fab")
		)
		(fp_line
			(start -0.67945 0.3048)
			(end -0.67945 -0.305054)
			(stroke
				(width 0.1)
				(type default)
			)
			(layer "F.Fab")
		)
		(fp_line
			(start -0.67945 -0.305054)
			(end -0.12065 -0.305054)
			(stroke
				(width 0.1)
				(type default)
			)
			(layer "F.Fab")
		)
		(pad "1" smd rect
			(at -0.40005 0)
			(size 0.4572 0.508)
			(layers "F.Cu" "F.Mask" "F.Paste")
			(net "P12V_OCP_SFF_ISENSE_MAM_TIC")
		)
		(pad "2" smd rect
			(at 0.40005 0)
			(size 0.4572 0.508)
			(layers "F.Cu" "F.Mask" "F.Paste")
			(net "P12V_OCP_SFF_ISENSE_TIC")
		)
	)
	(footprint ""
		(layer "F.Cu")
		(at 213.93658 -127.782828 180)
		(property "Reference" "U95"
			(at -1.36144 -3.72491 0)
			(unlocked yes)
			(layer "F.SilkS")
			(effects
				(font
					(size 0.7874 0.5842)
					(thickness 0.1524)
				)
				(justify left)
			)
		)
		(property "Value" ""
			(at 0 0 180)
			(layer "F.Fab")
			(effects
				(font
					(size 1.27 1.27)
				)
			)
		)
		(duplicate_pad_numbers_are_jumpers no)
		(fp_line
			(start 1.400048 1.100074)
			(end -1.400048 1.100074)
			(stroke
				(width 0.1524)
				(type default)
			)
			(layer "F.SilkS")
		)
		(fp_line
			(start 1.400048 -1.100074)
			(end 1.400048 1.100074)
			(stroke
				(width 0.1524)
				(type default)
			)
			(layer "F.SilkS")
		)
		(fp_line
			(start 1.400048 -1.100074)
			(end -1.400048 -1.100074)
			(stroke
				(width 0.1524)
				(type default)
			)
			(layer "F.SilkS")
		)
		(fp_line
			(start -1.400048 1.100074)
			(end -1.400048 -1.100074)
			(stroke
				(width 0.1524)
				(type default)
			)
			(layer "F.SilkS")
		)
		(fp_poly
			(pts
				(xy -1.247394 -1.455928) (xy -1.755394 -2.471928) (xy -0.739394 -2.471928)
			)
			(stroke
				(width 0)
				(type default)
			)
			(fill yes)
			(layer "F.SilkS")
		)
		(fp_line
			(start 0.674878 1.100074)
			(end -0.674878 1.100074)
			(stroke
				(width 0.1)
				(type default)
			)
			(layer "F.Fab")
		)
		(fp_line
			(start 0.674878 -1.100074)
			(end 0.674878 1.100074)
			(stroke
				(width 0.1)
				(type default)
			)
			(layer "F.Fab")
		)
		(fp_line
			(start -0.674878 1.100074)
			(end -0.674878 -1.100074)
			(stroke
				(width 0.1)
				(type default)
			)
			(layer "F.Fab")
		)
		(fp_line
			(start -0.674878 -1.100074)
			(end 0.674878 -1.100074)
			(stroke
				(width 0.1)
				(type default)
			)
			(layer "F.Fab")
		)
		(fp_poly
			(pts
				(xy -1.590548 -0.649986) (xy -2.606548 -1.157986) (xy -2.606548 -0.141986)
			)
			(stroke
				(width 0)
				(type default)
			)
			(fill yes)
			(layer "F.Fab")
		)
		(pad "1" smd rect
			(at -0.94996 -0.649986 90)
			(size 0.4318 0.6096)
			(layers "F.Cu" "F.Mask" "F.Paste")
			(net "Net_1913")
		)
		(pad "2" smd rect
			(at -0.94996 0 90)
			(size 0.4318 0.6096)
			(layers "F.Cu" "F.Mask" "F.Paste")
			(net "PWRGD_DSW_PWROK_R1")
		)
		(pad "3" smd rect
			(at -0.94996 0.649986 90)
			(size 0.4318 0.6096)
			(layers "F.Cu" "F.Mask" "F.Paste")
			(net "GND")
		)
		(pad "4" smd rect
			(at 0.94996 0.649986 90)
			(size 0.4318 0.6096)
			(layers "F.Cu" "F.Mask" "F.Paste")
			(net "PWRGD_DSW_PWROK_R2")
		)
		(pad "5" smd rect
			(at 0.94996 -0.649986 90)
			(size 0.4318 0.6096)
			(layers "F.Cu" "F.Mask" "F.Paste")
			(net "P3V3_AUX")
		)
	)
	(footprint ""
		(layer "F.Cu")
		(at 102.845616 -356.668578)
		(property "Reference" "R311"
			(at 0 0 0)
			(layer "F.SilkS")
			(hide yes)
			(effects
				(font
					(size 1.27 1.27)
				)
			)
		)
		(property "Value" ""
			(at 0 0 0)
			(layer "F.Fab")
			(effects
				(font
					(size 1.27 1.27)
				)
			)
		)
		(duplicate_pad_numbers_are_jumpers no)
		(fp_line
			(start -0.7874 -0.4064)
			(end 0.7874 -0.4064)
			(stroke
				(width 0.1524)
				(type default)
			)
			(layer "F.SilkS")
		)
		(fp_line
			(start -0.7874 0.4064)
			(end -0.7874 -0.4064)
			(stroke
				(width 0.1524)
				(type default)
			)
			(layer "F.SilkS")
		)
		(fp_line
			(start 0.7874 -0.4064)
			(end 0.7874 0.4064)
			(stroke
				(width 0.1524)
				(type default)
			)
			(layer "F.SilkS")
		)
		(fp_line
			(start 0.7874 0.4064)
			(end -0.7874 0.4064)
			(stroke
				(width 0.1524)
				(type default)
			)
			(layer "F.SilkS")
		)
		(fp_line
			(start -0.67945 -0.305054)
			(end -0.12065 -0.305054)
			(stroke
				(width 0.1)
				(type default)
			)
			(layer "F.Fab")
		)
		(fp_line
			(start -0.67945 0.3048)
			(end -0.67945 -0.305054)
			(stroke
				(width 0.1)
				(type default)
			)
			(layer "F.Fab")
		)
		(fp_line
			(start -0.12065 -0.305054)
			(end -0.12065 -0.2794)
			(stroke
				(width 0.1)
				(type default)
			)
			(layer "F.Fab")
		)
		(fp_line
			(start -0.12065 -0.2794)
			(end 0.12065 -0.2794)
			(stroke
				(width 0.1)
				(type default)
			)
			(layer "F.Fab")
		)
		(fp_line
			(start -0.12065 0.2794)
			(end -0.12065 0.3048)
			(stroke
				(width 0.1)
				(type default)
			)
			(layer "F.Fab")
		)
		(fp_line
			(start -0.12065 0.3048)
			(end -0.67945 0.3048)
			(stroke
				(width 0.1)
				(type default)
			)
			(layer "F.Fab")
		)
		(fp_line
			(start 0.120396 0.2794)
			(end -0.12065 0.2794)
			(stroke
				(width 0.1)
				(type default)
			)
			(layer "F.Fab")
		)
		(fp_line
			(start 0.120396 0.3048)
			(end 0.120396 0.2794)
			(stroke
				(width 0.1)
				(type default)
			)
			(layer "F.Fab")
		)
		(fp_line
			(start 0.12065 -0.3048)
			(end 0.67945 -0.3048)
			(stroke
				(width 0.1)
				(type default)
			)
			(layer "F.Fab")
		)
		(fp_line
			(start 0.12065 -0.2794)
			(end 0.12065 -0.3048)
			(stroke
				(width 0.1)
				(type default)
			)
			(layer "F.Fab")
		)
		(fp_line
			(start 0.67945 -0.3048)
			(end 0.67945 0.3048)
			(stroke
				(width 0.1)
				(type default)
			)
			(layer "F.Fab")
		)
		(fp_line
			(start 0.67945 0.3048)
			(end 0.120396 0.3048)
			(stroke
				(width 0.1)
				(type default)
			)
			(layer "F.Fab")
		)
		(pad "1" smd circle
			(at -0.40005 0)
			(size 0 0)
			(layers "F.Cu" "F.Mask" "F.Paste")
			(net "SVID_DIO0_CPU1_R")
		)
		(pad "2" smd circle
			(at 0.40005 0)
			(size 0 0)
			(layers "F.Cu" "F.Mask" "F.Paste")
			(net "SVID_DIO_PVCCIN_CPU1_R")
		)
	)
	(footprint ""
		(layer "F.Cu")
		(at 302.85436 -430.65827 -90)
		(property "Reference" "R4132"
			(at 0 0 270)
			(layer "F.SilkS")
			(hide yes)
			(effects
				(font
					(size 1.27 1.27)
				)
			)
		)
		(property "Value" ""
			(at 0 0 270)
			(layer "F.Fab")
			(effects
				(font
					(size 1.27 1.27)
				)
			)
		)
		(duplicate_pad_numbers_are_jumpers no)
		(fp_line
			(start -0.7874 0.4064)
			(end -0.7874 -0.4064)
			(stroke
				(width 0.1524)
				(type default)
			)
			(layer "F.SilkS")
		)
		(fp_line
			(start 0.7874 0.4064)
			(end -0.7874 0.4064)
			(stroke
				(width 0.1524)
				(type default)
			)
			(layer "F.SilkS")
		)
		(fp_line
			(start -0.7874 -0.4064)
			(end 0.7874 -0.4064)
			(stroke
				(width 0.1524)
				(type default)
			)
			(layer "F.SilkS")
		)
		(fp_line
			(start 0.7874 -0.4064)
			(end 0.7874 0.4064)
			(stroke
				(width 0.1524)
				(type default)
			)
			(layer "F.SilkS")
		)
		(fp_line
			(start -0.67945 0.3048)
			(end -0.67945 -0.305054)
			(stroke
				(width 0.1)
				(type default)
			)
			(layer "F.Fab")
		)
		(fp_line
			(start -0.12065 0.3048)
			(end -0.67945 0.3048)
			(stroke
				(width 0.1)
				(type default)
			)
			(layer "F.Fab")
		)
		(fp_line
			(start 0.120396 0.3048)
			(end 0.120396 0.2794)
			(stroke
				(width 0.1)
				(type default)
			)
			(layer "F.Fab")
		)
		(fp_line
			(start 0.67945 0.3048)
			(end 0.120396 0.3048)
			(stroke
				(width 0.1)
				(type default)
			)
			(layer "F.Fab")
		)
		(fp_line
			(start -0.12065 0.2794)
			(end -0.12065 0.3048)
			(stroke
				(width 0.1)
				(type default)
			)
			(layer "F.Fab")
		)
		(fp_line
			(start 0.120396 0.2794)
			(end -0.12065 0.2794)
			(stroke
				(width 0.1)
				(type default)
			)
			(layer "F.Fab")
		)
		(fp_line
			(start -0.12065 -0.2794)
			(end 0.12065 -0.2794)
			(stroke
				(width 0.1)
				(type default)
			)
			(layer "F.Fab")
		)
		(fp_line
			(start 0.12065 -0.2794)
			(end 0.12065 -0.3048)
			(stroke
				(width 0.1)
				(type default)
			)
			(layer "F.Fab")
		)
		(fp_line
			(start 0.12065 -0.3048)
			(end 0.67945 -0.3048)
			(stroke
				(width 0.1)
				(type default)
			)
			(layer "F.Fab")
		)
		(fp_line
			(start 0.67945 -0.3048)
			(end 0.67945 0.3048)
			(stroke
				(width 0.1)
				(type default)
			)
			(layer "F.Fab")
		)
		(fp_line
			(start -0.67945 -0.305054)
			(end -0.12065 -0.305054)
			(stroke
				(width 0.1)
				(type default)
			)
			(layer "F.Fab")
		)
		(fp_line
			(start -0.12065 -0.305054)
			(end -0.12065 -0.2794)
			(stroke
				(width 0.1)
				(type default)
			)
			(layer "F.Fab")
		)
		(pad "1" smd circle
			(at -0.40005 0 270)
			(size 0 0)
			(layers "F.Cu" "F.Mask" "F.Paste")
			(net "GPU_3V3IO_RSVD3_FFU")
		)
		(pad "2" smd circle
			(at 0.40005 0 270)
			(size 0 0)
			(layers "F.Cu" "F.Mask" "F.Paste")
			(net "GND")
		)
	)
	(footprint ""
		(layer "F.Cu")
		(at 187.50788 -99.659948 -90)
		(property "Reference" "R188"
			(at 0 0 270)
			(layer "F.SilkS")
			(hide yes)
			(effects
				(font
					(size 1.27 1.27)
				)
			)
		)
		(property "Value" ""
			(at 0 0 270)
			(layer "F.Fab")
			(effects
				(font
					(size 1.27 1.27)
				)
			)
		)
		(duplicate_pad_numbers_are_jumpers no)
		(fp_line
			(start -0.7874 0.4064)
			(end -0.7874 -0.4064)
			(stroke
				(width 0.1524)
				(type default)
			)
			(layer "F.SilkS")
		)
		(fp_line
			(start 0.7874 0.4064)
			(end -0.7874 0.4064)
			(stroke
				(width 0.1524)
				(type default)
			)
			(layer "F.SilkS")
		)
		(fp_line
			(start -0.7874 -0.4064)
			(end 0.7874 -0.4064)
			(stroke
				(width 0.1524)
				(type default)
			)
			(layer "F.SilkS")
		)
		(fp_line
			(start 0.7874 -0.4064)
			(end 0.7874 0.4064)
			(stroke
				(width 0.1524)
				(type default)
			)
			(layer "F.SilkS")
		)
		(fp_line
			(start -0.67945 0.3048)
			(end -0.67945 -0.305054)
			(stroke
				(width 0.1)
				(type default)
			)
			(layer "F.Fab")
		)
		(fp_line
			(start -0.12065 0.3048)
			(end -0.67945 0.3048)
			(stroke
				(width 0.1)
				(type default)
			)
			(layer "F.Fab")
		)
		(fp_line
			(start 0.120396 0.3048)
			(end 0.120396 0.2794)
			(stroke
				(width 0.1)
				(type default)
			)
			(layer "F.Fab")
		)
		(fp_line
			(start 0.67945 0.3048)
			(end 0.120396 0.3048)
			(stroke
				(width 0.1)
				(type default)
			)
			(layer "F.Fab")
		)
		(fp_line
			(start -0.12065 0.2794)
			(end -0.12065 0.3048)
			(stroke
				(width 0.1)
				(type default)
			)
			(layer "F.Fab")
		)
		(fp_line
			(start 0.120396 0.2794)
			(end -0.12065 0.2794)
			(stroke
				(width 0.1)
				(type default)
			)
			(layer "F.Fab")
		)
		(fp_line
			(start -0.12065 -0.2794)
			(end 0.12065 -0.2794)
			(stroke
				(width 0.1)
				(type default)
			)
			(layer "F.Fab")
		)
		(fp_line
			(start 0.12065 -0.2794)
			(end 0.12065 -0.3048)
			(stroke
				(width 0.1)
				(type default)
			)
			(layer "F.Fab")
		)
		(fp_line
			(start 0.12065 -0.3048)
			(end 0.67945 -0.3048)
			(stroke
				(width 0.1)
				(type default)
			)
			(layer "F.Fab")
		)
		(fp_line
			(start 0.67945 -0.3048)
			(end 0.67945 0.3048)
			(stroke
				(width 0.1)
				(type default)
			)
			(layer "F.Fab")
		)
		(fp_line
			(start -0.67945 -0.305054)
			(end -0.12065 -0.305054)
			(stroke
				(width 0.1)
				(type default)
			)
			(layer "F.Fab")
		)
		(fp_line
			(start -0.12065 -0.305054)
			(end -0.12065 -0.2794)
			(stroke
				(width 0.1)
				(type default)
			)
			(layer "F.Fab")
		)
		(pad "1" smd circle
			(at -0.40005 0 270)
			(size 0 0)
			(layers "F.Cu" "F.Mask" "F.Paste")
			(net "H_CPU_NMI_LVC1_R_N")
		)
		(pad "2" smd circle
			(at 0.40005 0 270)
			(size 0 0)
			(layers "F.Cu" "F.Mask" "F.Paste")
			(net "H_CPU_NMI_LVC1_N")
		)
	)
	(footprint ""
		(layer "F.Cu")
		(at 114.81308 -400.414998 -90)
		(property "Reference" "R3030"
			(at 0 0 270)
			(layer "F.SilkS")
			(hide yes)
			(effects
				(font
					(size 1.27 1.27)
				)
			)
		)
		(property "Value" ""
			(at 0 0 270)
			(layer "F.Fab")
			(effects
				(font
					(size 1.27 1.27)
				)
			)
		)
		(duplicate_pad_numbers_are_jumpers no)
		(fp_line
			(start -0.7874 0.4064)
			(end -0.7874 -0.4064)
			(stroke
				(width 0.1524)
				(type default)
			)
			(layer "F.SilkS")
		)
		(fp_line
			(start 0.7874 0.4064)
			(end -0.7874 0.4064)
			(stroke
				(width 0.1524)
				(type default)
			)
			(layer "F.SilkS")
		)
		(fp_line
			(start -0.7874 -0.4064)
			(end 0.7874 -0.4064)
			(stroke
				(width 0.1524)
				(type default)
			)
			(layer "F.SilkS")
		)
		(fp_line
			(start 0.7874 -0.4064)
			(end 0.7874 0.4064)
			(stroke
				(width 0.1524)
				(type default)
			)
			(layer "F.SilkS")
		)
		(fp_line
			(start -0.67945 0.3048)
			(end -0.67945 -0.305054)
			(stroke
				(width 0.1)
				(type default)
			)
			(layer "F.Fab")
		)
		(fp_line
			(start -0.12065 0.3048)
			(end -0.67945 0.3048)
			(stroke
				(width 0.1)
				(type default)
			)
			(layer "F.Fab")
		)
		(fp_line
			(start 0.120396 0.3048)
			(end 0.120396 0.2794)
			(stroke
				(width 0.1)
				(type default)
			)
			(layer "F.Fab")
		)
		(fp_line
			(start 0.67945 0.3048)
			(end 0.120396 0.3048)
			(stroke
				(width 0.1)
				(type default)
			)
			(layer "F.Fab")
		)
		(fp_line
			(start -0.12065 0.2794)
			(end -0.12065 0.3048)
			(stroke
				(width 0.1)
				(type default)
			)
			(layer "F.Fab")
		)
		(fp_line
			(start 0.120396 0.2794)
			(end -0.12065 0.2794)
			(stroke
				(width 0.1)
				(type default)
			)
			(layer "F.Fab")
		)
		(fp_line
			(start -0.12065 -0.2794)
			(end 0.12065 -0.2794)
			(stroke
				(width 0.1)
				(type default)
			)
			(layer "F.Fab")
		)
		(fp_line
			(start 0.12065 -0.2794)
			(end 0.12065 -0.3048)
			(stroke
				(width 0.1)
				(type default)
			)
			(layer "F.Fab")
		)
		(fp_line
			(start 0.12065 -0.3048)
			(end 0.67945 -0.3048)
			(stroke
				(width 0.1)
				(type default)
			)
			(layer "F.Fab")
		)
		(fp_line
			(start 0.67945 -0.3048)
			(end 0.67945 0.3048)
			(stroke
				(width 0.1)
				(type default)
			)
			(layer "F.Fab")
		)
		(fp_line
			(start -0.67945 -0.305054)
			(end -0.12065 -0.305054)
			(stroke
				(width 0.1)
				(type default)
			)
			(layer "F.Fab")
		)
		(fp_line
			(start -0.12065 -0.305054)
			(end -0.12065 -0.2794)
			(stroke
				(width 0.1)
				(type default)
			)
			(layer "F.Fab")
		)
		(pad "1" smd circle
			(at -0.40005 0 270)
			(size 0 0)
			(layers "F.Cu" "F.Mask" "F.Paste")
			(net "P3V3_AUX")
		)
		(pad "2" smd circle
			(at 0.40005 0 270)
			(size 0 0)
			(layers "F.Cu" "F.Mask" "F.Paste")
			(net "FM_SMB_1_ALERT_GPU_ISO_N")
		)
	)
	(footprint ""
		(layer "F.Cu")
		(at 272.394934 -67.455796 180)
		(property "Reference" "PC1224"
			(at 0 0 180)
			(layer "F.SilkS")
			(hide yes)
			(effects
				(font
					(size 1.27 1.27)
				)
			)
		)
		(property "Value" ""
			(at 0 0 180)
			(layer "F.Fab")
			(effects
				(font
					(size 1.27 1.27)
				)
			)
		)
		(duplicate_pad_numbers_are_jumpers no)
		(fp_line
			(start 0.7874 0.4064)
			(end -0.7874 0.4064)
			(stroke
				(width 0.1524)
				(type default)
			)
			(layer "F.SilkS")
		)
		(fp_line
			(start 0.7874 -0.4064)
			(end 0.7874 0.4064)
			(stroke
				(width 0.1524)
				(type default)
			)
			(layer "F.SilkS")
		)
		(fp_line
			(start -0.7874 0.4064)
			(end -0.7874 -0.4064)
			(stroke
				(width 0.1524)
				(type default)
			)
			(layer "F.SilkS")
		)
		(fp_line
			(start -0.7874 -0.4064)
			(end 0.7874 -0.4064)
			(stroke
				(width 0.1524)
				(type default)
			)
			(layer "F.SilkS")
		)
		(fp_line
			(start 0.67945 0.3048)
			(end 0.120396 0.3048)
			(stroke
				(width 0.1)
				(type default)
			)
			(layer "F.Fab")
		)
		(fp_line
			(start 0.67945 -0.3048)
			(end 0.67945 0.3048)
			(stroke
				(width 0.1)
				(type default)
			)
			(layer "F.Fab")
		)
		(fp_line
			(start 0.12065 -0.2794)
			(end 0.12065 -0.3048)
			(stroke
				(width 0.1)
				(type default)
			)
			(layer "F.Fab")
		)
		(fp_line
			(start 0.12065 -0.3048)
			(end 0.67945 -0.3048)
			(stroke
				(width 0.1)
				(type default)
			)
			(layer "F.Fab")
		)
		(fp_line
			(start 0.120396 0.3048)
			(end 0.120396 0.2794)
			(stroke
				(width 0.1)
				(type default)
			)
			(layer "F.Fab")
		)
		(fp_line
			(start 0.120396 0.2794)
			(end -0.12065 0.2794)
			(stroke
				(width 0.1)
				(type default)
			)
			(layer "F.Fab")
		)
		(fp_line
			(start -0.12065 0.3048)
			(end -0.67945 0.3048)
			(stroke
				(width 0.1)
				(type default)
			)
			(layer "F.Fab")
		)
		(fp_line
			(start -0.12065 0.2794)
			(end -0.12065 0.3048)
			(stroke
				(width 0.1)
				(type default)
			)
			(layer "F.Fab")
		)
		(fp_line
			(start -0.12065 -0.2794)
			(end 0.12065 -0.2794)
			(stroke
				(width 0.1)
				(type default)
			)
			(layer "F.Fab")
		)
		(fp_line
			(start -0.12065 -0.305054)
			(end -0.12065 -0.2794)
			(stroke
				(width 0.1)
				(type default)
			)
			(layer "F.Fab")
		)
		(fp_line
			(start -0.67945 0.3048)
			(end -0.67945 -0.305054)
			(stroke
				(width 0.1)
				(type default)
			)
			(layer "F.Fab")
		)
		(fp_line
			(start -0.67945 -0.305054)
			(end -0.12065 -0.305054)
			(stroke
				(width 0.1)
				(type default)
			)
			(layer "F.Fab")
		)
		(pad "1" smd circle
			(at -0.40005 0 180)
			(size 0 0)
			(layers "F.Cu" "F.Mask" "F.Paste")
			(net "P1V05_PCH_AUX")
		)
		(pad "2" smd circle
			(at 0.40005 0 180)
			(size 0 0)
			(layers "F.Cu" "F.Mask" "F.Paste")
			(net "GND")
		)
	)
	(footprint ""
		(layer "F.Cu")
		(at 437.425846 -381.47498 180)
		(property "Reference" "PC1856"
			(at 0 0 180)
			(layer "F.SilkS")
			(hide yes)
			(effects
				(font
					(size 1.27 1.27)
				)
			)
		)
		(property "Value" ""
			(at 0 0 180)
			(layer "F.Fab")
			(effects
				(font
					(size 1.27 1.27)
				)
			)
		)
		(duplicate_pad_numbers_are_jumpers no)
		(fp_line
			(start 1.524 0.762)
			(end -1.524 0.762)
			(stroke
				(width 0.1524)
				(type default)
			)
			(layer "F.SilkS")
		)
		(fp_line
			(start 1.524 -0.762)
			(end 1.524 0.762)
			(stroke
				(width 0.1524)
				(type default)
			)
			(layer "F.SilkS")
		)
		(fp_line
			(start -1.524 0.762)
			(end -1.524 -0.762)
			(stroke
				(width 0.1524)
				(type default)
			)
			(layer "F.SilkS")
		)
		(fp_line
			(start -1.524 -0.762)
			(end 1.524 -0.762)
			(stroke
				(width 0.1524)
				(type default)
			)
			(layer "F.SilkS")
		)
		(fp_line
			(start 1.1049 0.724916)
			(end 1.1049 -0.724916)
			(stroke
				(width 0.1)
				(type default)
			)
			(layer "F.Fab")
		)
		(fp_line
			(start 1.1049 -0.724916)
			(end -1.1049 -0.724916)
			(stroke
				(width 0.1)
				(type default)
			)
			(layer "F.Fab")
		)
		(fp_line
			(start -1.1049 0.724916)
			(end 1.1049 0.724916)
			(stroke
				(width 0.1)
				(type default)
			)
			(layer "F.Fab")
		)
		(fp_line
			(start -1.1049 -0.724916)
			(end -1.1049 0.724916)
			(stroke
				(width 0.1)
				(type default)
			)
			(layer "F.Fab")
		)
		(pad "1" smd rect
			(at -0.889 0)
			(size 1.016 1.27)
			(layers "F.Cu" "F.Mask" "F.Paste")
			(net "P5V_AUX")
		)
		(pad "2" smd rect
			(at 0.889 0)
			(size 1.016 1.27)
			(layers "F.Cu" "F.Mask" "F.Paste")
			(net "GND")
		)
	)
	(footprint ""
		(layer "F.Cu")
		(at 22.13356 -164.735256)
		(property "Reference" "R2579"
			(at 0 0 0)
			(layer "F.SilkS")
			(hide yes)
			(effects
				(font
					(size 1.27 1.27)
				)
			)
		)
		(property "Value" ""
			(at 0 0 0)
			(layer "F.Fab")
			(effects
				(font
					(size 1.27 1.27)
				)
			)
		)
		(duplicate_pad_numbers_are_jumpers no)
		(fp_line
			(start -0.7874 -0.4064)
			(end 0.7874 -0.4064)
			(stroke
				(width 0.1524)
				(type default)
			)
			(layer "F.SilkS")
		)
		(fp_line
			(start -0.7874 0.4064)
			(end -0.7874 -0.4064)
			(stroke
				(width 0.1524)
				(type default)
			)
			(layer "F.SilkS")
		)
		(fp_line
			(start 0.7874 -0.4064)
			(end 0.7874 0.4064)
			(stroke
				(width 0.1524)
				(type default)
			)
			(layer "F.SilkS")
		)
		(fp_line
			(start 0.7874 0.4064)
			(end -0.7874 0.4064)
			(stroke
				(width 0.1524)
				(type default)
			)
			(layer "F.SilkS")
		)
		(fp_line
			(start -0.67945 -0.305054)
			(end -0.12065 -0.305054)
			(stroke
				(width 0.1)
				(type default)
			)
			(layer "F.Fab")
		)
		(fp_line
			(start -0.67945 0.3048)
			(end -0.67945 -0.305054)
			(stroke
				(width 0.1)
				(type default)
			)
			(layer "F.Fab")
		)
		(fp_line
			(start -0.12065 -0.305054)
			(end -0.12065 -0.2794)
			(stroke
				(width 0.1)
				(type default)
			)
			(layer "F.Fab")
		)
		(fp_line
			(start -0.12065 -0.2794)
			(end 0.12065 -0.2794)
			(stroke
				(width 0.1)
				(type default)
			)
			(layer "F.Fab")
		)
		(fp_line
			(start -0.12065 0.2794)
			(end -0.12065 0.3048)
			(stroke
				(width 0.1)
				(type default)
			)
			(layer "F.Fab")
		)
		(fp_line
			(start -0.12065 0.3048)
			(end -0.67945 0.3048)
			(stroke
				(width 0.1)
				(type default)
			)
			(layer "F.Fab")
		)
		(fp_line
			(start 0.120396 0.2794)
			(end -0.12065 0.2794)
			(stroke
				(width 0.1)
				(type default)
			)
			(layer "F.Fab")
		)
		(fp_line
			(start 0.120396 0.3048)
			(end 0.120396 0.2794)
			(stroke
				(width 0.1)
				(type default)
			)
			(layer "F.Fab")
		)
		(fp_line
			(start 0.12065 -0.3048)
			(end 0.67945 -0.3048)
			(stroke
				(width 0.1)
				(type default)
			)
			(layer "F.Fab")
		)
		(fp_line
			(start 0.12065 -0.2794)
			(end 0.12065 -0.3048)
			(stroke
				(width 0.1)
				(type default)
			)
			(layer "F.Fab")
		)
		(fp_line
			(start 0.67945 -0.3048)
			(end 0.67945 0.3048)
			(stroke
				(width 0.1)
				(type default)
			)
			(layer "F.Fab")
		)
		(fp_line
			(start 0.67945 0.3048)
			(end 0.120396 0.3048)
			(stroke
				(width 0.1)
				(type default)
			)
			(layer "F.Fab")
		)
		(pad "1" smd circle
			(at -0.40005 0)
			(size 0 0)
			(layers "F.Cu" "F.Mask" "F.Paste")
			(net "SVID_DIO1_CPU1_R")
		)
		(pad "2" smd circle
			(at 0.40005 0)
			(size 0 0)
			(layers "F.Cu" "F.Mask" "F.Paste")
			(net "SVID_DIO_PVCCD_HV_CPU1_R")
		)
	)
	(footprint ""
		(layer "F.Cu")
		(at 243.446808 -40.920162 -90)
		(property "Reference" "C1276"
			(at 0 0 270)
			(layer "F.SilkS")
			(hide yes)
			(effects
				(font
					(size 1.27 1.27)
				)
			)
		)
		(property "Value" ""
			(at 0 0 270)
			(layer "F.Fab")
			(effects
				(font
					(size 1.27 1.27)
				)
			)
		)
		(duplicate_pad_numbers_are_jumpers no)
		(fp_line
			(start -1.524 0.762)
			(end -1.524 -0.762)
			(stroke
				(width 0.1524)
				(type default)
			)
			(layer "F.SilkS")
		)
		(fp_line
			(start 1.524 0.762)
			(end -1.524 0.762)
			(stroke
				(width 0.1524)
				(type default)
			)
			(layer "F.SilkS")
		)
		(fp_line
			(start -1.524 -0.762)
			(end 1.524 -0.762)
			(stroke
				(width 0.1524)
				(type default)
			)
			(layer "F.SilkS")
		)
		(fp_line
			(start 1.524 -0.762)
			(end 1.524 0.762)
			(stroke
				(width 0.1524)
				(type default)
			)
			(layer "F.SilkS")
		)
		(fp_line
			(start -1.1049 0.724916)
			(end 1.1049 0.724916)
			(stroke
				(width 0.1)
				(type default)
			)
			(layer "F.Fab")
		)
		(fp_line
			(start 1.1049 0.724916)
			(end 1.1049 -0.724916)
			(stroke
				(width 0.1)
				(type default)
			)
			(layer "F.Fab")
		)
		(fp_line
			(start -1.1049 -0.724916)
			(end -1.1049 0.724916)
			(stroke
				(width 0.1)
				(type default)
			)
			(layer "F.Fab")
		)
		(fp_line
			(start 1.1049 -0.724916)
			(end -1.1049 -0.724916)
			(stroke
				(width 0.1)
				(type default)
			)
			(layer "F.Fab")
		)
		(pad "1" smd rect
			(at -0.889 0 90)
			(size 1.016 1.27)
			(layers "F.Cu" "F.Mask" "F.Paste")
			(net "P12V_E1S_0")
		)
		(pad "2" smd rect
			(at 0.889 0 90)
			(size 1.016 1.27)
			(layers "F.Cu" "F.Mask" "F.Paste")
			(net "GND")
		)
	)
	(footprint ""
		(layer "F.Cu")
		(at 28.081732 -406.687274)
		(property "Reference" "Q101"
			(at 0.40894 -2.037588 0)
			(unlocked yes)
			(layer "F.SilkS")
			(effects
				(font
					(size 0.7874 0.5842)
					(thickness 0.1524)
				)
				(justify left)
			)
		)
		(property "Value" ""
			(at 0 0 0)
			(layer "F.Fab")
			(effects
				(font
					(size 1.27 1.27)
				)
			)
		)
		(duplicate_pad_numbers_are_jumpers no)
		(fp_line
			(start -1.332738 -1.100074)
			(end -0.4826 -1.100074)
			(stroke
				(width 0.1524)
				(type default)
			)
			(layer "F.SilkS")
		)
		(fp_line
			(start -1.332738 1.100074)
			(end -1.332738 -1.100074)
			(stroke
				(width 0.1524)
				(type default)
			)
			(layer "F.SilkS")
		)
		(fp_line
			(start -0.4826 -1.100074)
			(end 0 -0.541274)
			(stroke
				(width 0.1524)
				(type default)
			)
			(layer "F.SilkS")
		)
		(fp_line
			(start 0 -0.541274)
			(end 0.4826 -1.100074)
			(stroke
				(width 0.1524)
				(type default)
			)
			(layer "F.SilkS")
		)
		(fp_line
			(start 0.4826 -1.100074)
			(end 1.332738 -1.100074)
			(stroke
				(width 0.1524)
				(type default)
			)
			(layer "F.SilkS")
		)
		(fp_line
			(start 1.332738 -1.100074)
			(end 1.332738 1.100074)
			(stroke
				(width 0.1524)
				(type default)
			)
			(layer "F.SilkS")
		)
		(fp_line
			(start 1.332738 1.100074)
			(end -1.332738 1.100074)
			(stroke
				(width 0.1524)
				(type default)
			)
			(layer "F.SilkS")
		)
		(fp_poly
			(pts
				(xy -1.895602 -1.706626) (xy -1.647444 -0.961898) (xy -2.392172 -1.210056)
			)
			(stroke
				(width 0)
				(type default)
			)
			(fill yes)
			(layer "F.SilkS")
		)
		(fp_line
			(start -0.674878 -1.100074)
			(end 0.674878 -1.100074)
			(stroke
				(width 0.1)
				(type default)
			)
			(layer "F.Fab")
		)
		(fp_line
			(start -0.674878 1.100074)
			(end -0.674878 -1.100074)
			(stroke
				(width 0.1)
				(type default)
			)
			(layer "F.Fab")
		)
		(fp_line
			(start 0.674878 -1.100074)
			(end 0.674878 1.100074)
			(stroke
				(width 0.1)
				(type default)
			)
			(layer "F.Fab")
		)
		(fp_line
			(start 0.674878 1.100074)
			(end -0.674878 1.100074)
			(stroke
				(width 0.1)
				(type default)
			)
			(layer "F.Fab")
		)
		(fp_poly
			(pts
				(xy -2.2352 -0.298958) (xy -2.2352 -1.001014) (xy -1.533144 -0.649986)
			)
			(stroke
				(width 0)
				(type default)
			)
			(fill yes)
			(layer "F.Fab")
		)
		(pad "1" smd rect
			(at -0.94996 -0.649986 90)
			(size 0.4318 0.508)
			(layers "F.Cu" "F.Mask" "F.Paste")
			(net "GND")
		)
		(pad "2" smd rect
			(at -0.94996 0 90)
			(size 0.4318 0.508)
			(layers "F.Cu" "F.Mask" "F.Paste")
			(net "GPU_FPGA_THERM_OVERT_N")
		)
		(pad "3" smd rect
			(at -0.94996 0.649986 90)
			(size 0.4318 0.508)
			(layers "F.Cu" "F.Mask" "F.Paste")
			(net "GPU_FPGA_THERM_OVERT_ISO_N")
		)
		(pad "4" smd rect
			(at 0.94996 0.649986 90)
			(size 0.4318 0.508)
			(layers "F.Cu" "F.Mask" "F.Paste")
			(net "GND")
		)
		(pad "5" smd rect
			(at 0.94996 0 90)
			(size 0.4318 0.508)
			(layers "F.Cu" "F.Mask" "F.Paste")
			(net "GPU_FPGA_THERM_OVERT")
		)
		(pad "6" smd rect
			(at 0.94996 -0.649986 90)
			(size 0.4318 0.508)
			(layers "F.Cu" "F.Mask" "F.Paste")
			(net "GPU_FPGA_THERM_OVERT")
		)
	)
	(footprint ""
		(layer "F.Cu")
		(at 353.248214 -251.375418 90)
		(property "Reference" "C1018"
			(at 0 0 90)
			(layer "F.SilkS")
			(hide yes)
			(effects
				(font
					(size 1.27 1.27)
				)
			)
		)
		(property "Value" ""
			(at 0 0 90)
			(layer "F.Fab")
			(effects
				(font
					(size 1.27 1.27)
				)
			)
		)
		(duplicate_pad_numbers_are_jumpers no)
		(fp_line
			(start 0.7874 -0.4064)
			(end 0.7874 0.4064)
			(stroke
				(width 0.1524)
				(type default)
			)
			(layer "F.SilkS")
		)
		(fp_line
			(start -0.7874 -0.4064)
			(end 0.7874 -0.4064)
			(stroke
				(width 0.1524)
				(type default)
			)
			(layer "F.SilkS")
		)
		(fp_line
			(start 0.7874 0.4064)
			(end -0.7874 0.4064)
			(stroke
				(width 0.1524)
				(type default)
			)
			(layer "F.SilkS")
		)
		(fp_line
			(start -0.7874 0.4064)
			(end -0.7874 -0.4064)
			(stroke
				(width 0.1524)
				(type default)
			)
			(layer "F.SilkS")
		)
		(fp_line
			(start -0.12065 -0.305054)
			(end -0.12065 -0.2794)
			(stroke
				(width 0.1)
				(type default)
			)
			(layer "F.Fab")
		)
		(fp_line
			(start -0.67945 -0.305054)
			(end -0.12065 -0.305054)
			(stroke
				(width 0.1)
				(type default)
			)
			(layer "F.Fab")
		)
		(fp_line
			(start 0.67945 -0.3048)
			(end 0.67945 0.3048)
			(stroke
				(width 0.1)
				(type default)
			)
			(layer "F.Fab")
		)
		(fp_line
			(start 0.12065 -0.3048)
			(end 0.67945 -0.3048)
			(stroke
				(width 0.1)
				(type default)
			)
			(layer "F.Fab")
		)
		(fp_line
			(start 0.12065 -0.2794)
			(end 0.12065 -0.3048)
			(stroke
				(width 0.1)
				(type default)
			)
			(layer "F.Fab")
		)
		(fp_line
			(start -0.12065 -0.2794)
			(end 0.12065 -0.2794)
			(stroke
				(width 0.1)
				(type default)
			)
			(layer "F.Fab")
		)
		(fp_line
			(start 0.120396 0.2794)
			(end -0.12065 0.2794)
			(stroke
				(width 0.1)
				(type default)
			)
			(layer "F.Fab")
		)
		(fp_line
			(start -0.12065 0.2794)
			(end -0.12065 0.3048)
			(stroke
				(width 0.1)
				(type default)
			)
			(layer "F.Fab")
		)
		(fp_line
			(start 0.67945 0.3048)
			(end 0.120396 0.3048)
			(stroke
				(width 0.1)
				(type default)
			)
			(layer "F.Fab")
		)
		(fp_line
			(start 0.120396 0.3048)
			(end 0.120396 0.2794)
			(stroke
				(width 0.1)
				(type default)
			)
			(layer "F.Fab")
		)
		(fp_line
			(start -0.12065 0.3048)
			(end -0.67945 0.3048)
			(stroke
				(width 0.1)
				(type default)
			)
			(layer "F.Fab")
		)
		(fp_line
			(start -0.67945 0.3048)
			(end -0.67945 -0.305054)
			(stroke
				(width 0.1)
				(type default)
			)
			(layer "F.Fab")
		)
		(pad "1" smd circle
			(at -0.40005 0 90)
			(size 0 0)
			(layers "F.Cu" "F.Mask" "F.Paste")
			(net "PVCCIN_CPU0")
		)
		(pad "2" smd circle
			(at 0.40005 0 90)
			(size 0 0)
			(layers "F.Cu" "F.Mask" "F.Paste")
			(net "GND")
		)
	)
	(footprint ""
		(layer "F.Cu")
		(at 126.065026 -339.602572 90)
		(property "Reference" "PC502"
			(at 0 0 90)
			(layer "F.SilkS")
			(hide yes)
			(effects
				(font
					(size 1.27 1.27)
				)
			)
		)
		(property "Value" ""
			(at 0 0 90)
			(layer "F.Fab")
			(effects
				(font
					(size 1.27 1.27)
				)
			)
		)
		(duplicate_pad_numbers_are_jumpers no)
		(fp_line
			(start 0.7874 -0.4064)
			(end 0.7874 0.4064)
			(stroke
				(width 0.1524)
				(type default)
			)
			(layer "F.SilkS")
		)
		(fp_line
			(start -0.7874 -0.4064)
			(end 0.7874 -0.4064)
			(stroke
				(width 0.1524)
				(type default)
			)
			(layer "F.SilkS")
		)
		(fp_line
			(start 0.7874 0.4064)
			(end -0.7874 0.4064)
			(stroke
				(width 0.1524)
				(type default)
			)
			(layer "F.SilkS")
		)
		(fp_line
			(start -0.7874 0.4064)
			(end -0.7874 -0.4064)
			(stroke
				(width 0.1524)
				(type default)
			)
			(layer "F.SilkS")
		)
		(fp_line
			(start -0.12065 -0.305054)
			(end -0.12065 -0.2794)
			(stroke
				(width 0.1)
				(type default)
			)
			(layer "F.Fab")
		)
		(fp_line
			(start -0.67945 -0.305054)
			(end -0.12065 -0.305054)
			(stroke
				(width 0.1)
				(type default)
			)
			(layer "F.Fab")
		)
		(fp_line
			(start 0.67945 -0.3048)
			(end 0.67945 0.3048)
			(stroke
				(width 0.1)
				(type default)
			)
			(layer "F.Fab")
		)
		(fp_line
			(start 0.12065 -0.3048)
			(end 0.67945 -0.3048)
			(stroke
				(width 0.1)
				(type default)
			)
			(layer "F.Fab")
		)
		(fp_line
			(start 0.12065 -0.2794)
			(end 0.12065 -0.3048)
			(stroke
				(width 0.1)
				(type default)
			)
			(layer "F.Fab")
		)
		(fp_line
			(start -0.12065 -0.2794)
			(end 0.12065 -0.2794)
			(stroke
				(width 0.1)
				(type default)
			)
			(layer "F.Fab")
		)
		(fp_line
			(start 0.120396 0.2794)
			(end -0.12065 0.2794)
			(stroke
				(width 0.1)
				(type default)
			)
			(layer "F.Fab")
		)
		(fp_line
			(start -0.12065 0.2794)
			(end -0.12065 0.3048)
			(stroke
				(width 0.1)
				(type default)
			)
			(layer "F.Fab")
		)
		(fp_line
			(start 0.67945 0.3048)
			(end 0.120396 0.3048)
			(stroke
				(width 0.1)
				(type default)
			)
			(layer "F.Fab")
		)
		(fp_line
			(start 0.120396 0.3048)
			(end 0.120396 0.2794)
			(stroke
				(width 0.1)
				(type default)
			)
			(layer "F.Fab")
		)
		(fp_line
			(start -0.12065 0.3048)
			(end -0.67945 0.3048)
			(stroke
				(width 0.1)
				(type default)
			)
			(layer "F.Fab")
		)
		(fp_line
			(start -0.67945 0.3048)
			(end -0.67945 -0.305054)
			(stroke
				(width 0.1)
				(type default)
			)
			(layer "F.Fab")
		)
		(pad "1" smd circle
			(at -0.40005 0 90)
			(size 0 0)
			(layers "F.Cu" "F.Mask" "F.Paste")
			(net "PVCCIN_CPU1_VDD5")
		)
		(pad "2" smd circle
			(at 0.40005 0 90)
			(size 0 0)
			(layers "F.Cu" "F.Mask" "F.Paste")
			(net "GND")
		)
	)
	(footprint ""
		(layer "F.Cu")
		(at 95.249238 -408.517344 -90)
		(property "Reference" "C678"
			(at 0 0 270)
			(layer "F.SilkS")
			(hide yes)
			(effects
				(font
					(size 1.27 1.27)
				)
			)
		)
		(property "Value" ""
			(at 0 0 270)
			(layer "F.Fab")
			(effects
				(font
					(size 1.27 1.27)
				)
			)
		)
		(duplicate_pad_numbers_are_jumpers no)
		(fp_line
			(start -0.299974 0.150114)
			(end -0.299974 -0.150114)
			(stroke
				(width 0.1)
				(type default)
			)
			(layer "F.Fab")
		)
		(fp_line
			(start 0.299974 0.150114)
			(end -0.299974 0.150114)
			(stroke
				(width 0.1)
				(type default)
			)
			(layer "F.Fab")
		)
		(fp_line
			(start -0.299974 -0.150114)
			(end 0.299974 -0.150114)
			(stroke
				(width 0.1)
				(type default)
			)
			(layer "F.Fab")
		)
		(fp_line
			(start 0.299974 -0.150114)
			(end 0.299974 0.150114)
			(stroke
				(width 0.1)
				(type default)
			)
			(layer "F.Fab")
		)
		(pad "1" smd rect
			(at -0.2667 0 270)
			(size 0.3048 0.381)
			(layers "F.Cu" "F.Mask" "F.Paste")
			(net "P5E_CPU1_PE4_TX_C_DN<15>")
		)
		(pad "2" smd rect
			(at 0.2667 0 270)
			(size 0.3048 0.381)
			(layers "F.Cu" "F.Mask" "F.Paste")
			(net "P5E_CPU1_PE4_TX_DN<15>")
		)
	)
	(footprint ""
		(layer "F.Cu")
		(at 111.13008 -122.132598 90)
		(property "Reference" "R932"
			(at 0 0 90)
			(layer "F.SilkS")
			(hide yes)
			(effects
				(font
					(size 1.27 1.27)
				)
			)
		)
		(property "Value" ""
			(at 0 0 90)
			(layer "F.Fab")
			(effects
				(font
					(size 1.27 1.27)
				)
			)
		)
		(duplicate_pad_numbers_are_jumpers no)
		(fp_line
			(start 0.7874 -0.4064)
			(end 0.7874 0.4064)
			(stroke
				(width 0.1524)
				(type default)
			)
			(layer "F.SilkS")
		)
		(fp_line
			(start -0.7874 -0.4064)
			(end 0.7874 -0.4064)
			(stroke
				(width 0.1524)
				(type default)
			)
			(layer "F.SilkS")
		)
		(fp_line
			(start 0.7874 0.4064)
			(end -0.7874 0.4064)
			(stroke
				(width 0.1524)
				(type default)
			)
			(layer "F.SilkS")
		)
		(fp_line
			(start -0.7874 0.4064)
			(end -0.7874 -0.4064)
			(stroke
				(width 0.1524)
				(type default)
			)
			(layer "F.SilkS")
		)
		(fp_line
			(start -0.12065 -0.305054)
			(end -0.12065 -0.2794)
			(stroke
				(width 0.1)
				(type default)
			)
			(layer "F.Fab")
		)
		(fp_line
			(start -0.67945 -0.305054)
			(end -0.12065 -0.305054)
			(stroke
				(width 0.1)
				(type default)
			)
			(layer "F.Fab")
		)
		(fp_line
			(start 0.67945 -0.3048)
			(end 0.67945 0.3048)
			(stroke
				(width 0.1)
				(type default)
			)
			(layer "F.Fab")
		)
		(fp_line
			(start 0.12065 -0.3048)
			(end 0.67945 -0.3048)
			(stroke
				(width 0.1)
				(type default)
			)
			(layer "F.Fab")
		)
		(fp_line
			(start 0.12065 -0.2794)
			(end 0.12065 -0.3048)
			(stroke
				(width 0.1)
				(type default)
			)
			(layer "F.Fab")
		)
		(fp_line
			(start -0.12065 -0.2794)
			(end 0.12065 -0.2794)
			(stroke
				(width 0.1)
				(type default)
			)
			(layer "F.Fab")
		)
		(fp_line
			(start 0.120396 0.2794)
			(end -0.12065 0.2794)
			(stroke
				(width 0.1)
				(type default)
			)
			(layer "F.Fab")
		)
		(fp_line
			(start -0.12065 0.2794)
			(end -0.12065 0.3048)
			(stroke
				(width 0.1)
				(type default)
			)
			(layer "F.Fab")
		)
		(fp_line
			(start 0.67945 0.3048)
			(end 0.120396 0.3048)
			(stroke
				(width 0.1)
				(type default)
			)
			(layer "F.Fab")
		)
		(fp_line
			(start 0.120396 0.3048)
			(end 0.120396 0.2794)
			(stroke
				(width 0.1)
				(type default)
			)
			(layer "F.Fab")
		)
		(fp_line
			(start -0.12065 0.3048)
			(end -0.67945 0.3048)
			(stroke
				(width 0.1)
				(type default)
			)
			(layer "F.Fab")
		)
		(fp_line
			(start -0.67945 0.3048)
			(end -0.67945 -0.305054)
			(stroke
				(width 0.1)
				(type default)
			)
			(layer "F.Fab")
		)
		(pad "1" smd circle
			(at -0.40005 0 90)
			(size 0 0)
			(layers "F.Cu" "F.Mask" "F.Paste")
			(net "RST_CPU0_DRAM_AB_N")
		)
		(pad "2" smd circle
			(at 0.40005 0 90)
			(size 0 0)
			(layers "F.Cu" "F.Mask" "F.Paste")
			(net "GND")
		)
	)
	(footprint ""
		(layer "F.Cu")
		(at 445.19088 -94.602808)
		(property "Reference" "R3563"
			(at 0 0 0)
			(layer "F.SilkS")
			(hide yes)
			(effects
				(font
					(size 1.27 1.27)
				)
			)
		)
		(property "Value" ""
			(at 0 0 0)
			(layer "F.Fab")
			(effects
				(font
					(size 1.27 1.27)
				)
			)
		)
		(duplicate_pad_numbers_are_jumpers no)
		(fp_line
			(start -0.7874 -0.4064)
			(end 0.7874 -0.4064)
			(stroke
				(width 0.1524)
				(type default)
			)
			(layer "F.SilkS")
		)
		(fp_line
			(start -0.7874 0.4064)
			(end -0.7874 -0.4064)
			(stroke
				(width 0.1524)
				(type default)
			)
			(layer "F.SilkS")
		)
		(fp_line
			(start 0.7874 -0.4064)
			(end 0.7874 0.4064)
			(stroke
				(width 0.1524)
				(type default)
			)
			(layer "F.SilkS")
		)
		(fp_line
			(start 0.7874 0.4064)
			(end -0.7874 0.4064)
			(stroke
				(width 0.1524)
				(type default)
			)
			(layer "F.SilkS")
		)
		(fp_line
			(start -0.67945 -0.305054)
			(end -0.12065 -0.305054)
			(stroke
				(width 0.1)
				(type default)
			)
			(layer "F.Fab")
		)
		(fp_line
			(start -0.67945 0.3048)
			(end -0.67945 -0.305054)
			(stroke
				(width 0.1)
				(type default)
			)
			(layer "F.Fab")
		)
		(fp_line
			(start -0.12065 -0.305054)
			(end -0.12065 -0.2794)
			(stroke
				(width 0.1)
				(type default)
			)
			(layer "F.Fab")
		)
		(fp_line
			(start -0.12065 -0.2794)
			(end 0.12065 -0.2794)
			(stroke
				(width 0.1)
				(type default)
			)
			(layer "F.Fab")
		)
		(fp_line
			(start -0.12065 0.2794)
			(end -0.12065 0.3048)
			(stroke
				(width 0.1)
				(type default)
			)
			(layer "F.Fab")
		)
		(fp_line
			(start -0.12065 0.3048)
			(end -0.67945 0.3048)
			(stroke
				(width 0.1)
				(type default)
			)
			(layer "F.Fab")
		)
		(fp_line
			(start 0.120396 0.2794)
			(end -0.12065 0.2794)
			(stroke
				(width 0.1)
				(type default)
			)
			(layer "F.Fab")
		)
		(fp_line
			(start 0.120396 0.3048)
			(end 0.120396 0.2794)
			(stroke
				(width 0.1)
				(type default)
			)
			(layer "F.Fab")
		)
		(fp_line
			(start 0.12065 -0.3048)
			(end 0.67945 -0.3048)
			(stroke
				(width 0.1)
				(type default)
			)
			(layer "F.Fab")
		)
		(fp_line
			(start 0.12065 -0.2794)
			(end 0.12065 -0.3048)
			(stroke
				(width 0.1)
				(type default)
			)
			(layer "F.Fab")
		)
		(fp_line
			(start 0.67945 -0.3048)
			(end 0.67945 0.3048)
			(stroke
				(width 0.1)
				(type default)
			)
			(layer "F.Fab")
		)
		(fp_line
			(start 0.67945 0.3048)
			(end 0.120396 0.3048)
			(stroke
				(width 0.1)
				(type default)
			)
			(layer "F.Fab")
		)
		(pad "1" smd circle
			(at -0.40005 0)
			(size 0 0)
			(layers "F.Cu" "F.Mask" "F.Paste")
			(net "OCP_SFF_P3V3_ADC_ALERT_R")
		)
		(pad "2" smd circle
			(at 0.40005 0)
			(size 0 0)
			(layers "F.Cu" "F.Mask" "F.Paste")
			(net "OCP_SFF_P3V3_ADC_ALERT")
		)
	)
	(footprint ""
		(layer "F.Cu")
		(at 482.66985 -242.495832 90)
		(property "Reference" "X34"
			(at -0.1778 -1.92913 90)
			(unlocked yes)
			(layer "F.SilkS")
			(effects
				(font
					(size 0.7874 0.5842)
					(thickness 0.1524)
				)
				(justify left)
			)
		)
		(property "Value" ""
			(at 0 0 90)
			(layer "F.Fab")
			(effects
				(font
					(size 1.27 1.27)
				)
			)
		)
		(property "Device Type" "TP_TDR_4P_FTS_TH-TP_TDR_4P_DIPA"
			(at 1.30175 1.27 180)
			(unlocked yes)
			(layer "F.Fab")
			(hide yes)
			(effects
				(font
					(size 0.635 0.4064)
					(thickness 0.1524)
				)
			)
		)
		(property "User Part Number" "N_A"
			(at 1.30175 1.27 180)
			(unlocked yes)
			(layer "Cmts.User")
			(hide yes)
			(effects
				(font
					(size 0.635 0.4064)
					(thickness 0.1524)
				)
			)
		)
		(duplicate_pad_numbers_are_jumpers no)
		(fp_line
			(start 2.54 -1.27)
			(end 0 -1.27)
			(stroke
				(width 0.1524)
				(type default)
			)
			(layer "F.SilkS")
		)
		(fp_line
			(start 0 -1.27)
			(end 0 -0.635)
			(stroke
				(width 0.1524)
				(type default)
			)
			(layer "F.SilkS")
		)
		(fp_line
			(start 2.54 -1.1303)
			(end 2.54 -1.27)
			(stroke
				(width 0.1524)
				(type default)
			)
			(layer "F.SilkS")
		)
		(fp_line
			(start 0 0.635)
			(end 0 1.905)
			(stroke
				(width 0.1524)
				(type default)
			)
			(layer "F.SilkS")
		)
		(fp_line
			(start 2.54 1.4097)
			(end 2.54 1.1303)
			(stroke
				(width 0.1524)
				(type default)
			)
			(layer "F.SilkS")
		)
		(fp_line
			(start 0 3.175)
			(end 0 3.81)
			(stroke
				(width 0.1524)
				(type default)
			)
			(layer "F.SilkS")
		)
		(fp_line
			(start 2.54 3.81)
			(end 2.54 3.6703)
			(stroke
				(width 0.1524)
				(type default)
			)
			(layer "F.SilkS")
		)
		(fp_line
			(start 0 3.81)
			(end 2.54 3.81)
			(stroke
				(width 0.1524)
				(type default)
			)
			(layer "F.SilkS")
		)
		(fp_poly
			(pts
				(xy -0.761746 0) (xy -2.285746 -0.762) (xy -2.285746 0.762)
			)
			(stroke
				(width 0)
				(type default)
			)
			(fill yes)
			(layer "F.SilkS")
		)
		(fp_line
			(start 2.54 -1.27)
			(end 0 -1.27)
			(stroke
				(width 0.1)
				(type default)
			)
			(layer "F.Fab")
		)
		(fp_line
			(start 0 -1.27)
			(end 0 3.81)
			(stroke
				(width 0.1)
				(type default)
			)
			(layer "F.Fab")
		)
		(fp_line
			(start 2.54 3.81)
			(end 2.54 -1.27)
			(stroke
				(width 0.1)
				(type default)
			)
			(layer "F.Fab")
		)
		(fp_line
			(start 0 3.81)
			(end 2.54 3.81)
			(stroke
				(width 0.1)
				(type default)
			)
			(layer "F.Fab")
		)
		(fp_poly
			(pts
				(xy -0.761746 0) (xy -2.285746 -0.762) (xy -2.285746 0.762)
			)
			(stroke
				(width 0)
				(type default)
			)
			(fill yes)
			(layer "F.Fab")
		)
		(pad "1" thru_hole circle
			(at 0 0 90)
			(size 1.0033 1.0033)
			(drill 0.249936)
			(layers "*.Cu" "*.Mask")
			(remove_unused_layers no)
			(net "TDR_DIFF_85_NECK_IN1_DP")
			(clearance 0.10795)
			(thermal_gap 0.10795)
			(padstack
				(mode front_inner_back)
				(layer "Inner"
					(shape circle)
					(size 0.8001 0.8001)
					(clearance 0.1524)
				)
				(layer "B.Cu"
					(shape circle)
					(size 1.0033 1.0033)
					(clearance 0.10795)
				)
			)
		)
		(pad "2" thru_hole circle
			(at 2.54 0 90)
			(size 1.9939 1.9939)
			(drill 0.249936)
			(layers "*.Cu" "*.Mask")
			(remove_unused_layers no)
			(net "T1_GND")
			(clearance 0.10795)
			(thermal_gap 0.10795)
			(padstack
				(mode front_inner_back)
				(layer "Inner"
					(shape circle)
					(size 0.8001 0.8001)
					(clearance 0.1524)
				)
				(layer "B.Cu"
					(shape circle)
					(size 1.9939 1.9939)
					(clearance 0.10795)
				)
			)
		)
		(pad "3" thru_hole circle
			(at 2.54 2.54 90)
			(size 1.9939 1.9939)
			(drill 0.249936)
			(layers "*.Cu" "*.Mask")
			(remove_unused_layers no)
			(net "T1_GND")
			(clearance 0.10795)
			(thermal_gap 0.10795)
			(padstack
				(mode front_inner_back)
				(layer "Inner"
					(shape circle)
					(size 0.8001 0.8001)
					(clearance 0.1524)
				)
				(layer "B.Cu"
					(shape circle)
					(size 1.9939 1.9939)
					(clearance 0.10795)
				)
			)
		)
		(pad "4" thru_hole circle
			(at 0 2.54 90)
			(size 1.0033 1.0033)
			(drill 0.249936)
			(layers "*.Cu" "*.Mask")
			(remove_unused_layers no)
			(net "TDR_DIFF_85_NECK_IN1_DN")
			(clearance 0.10795)
			(thermal_gap 0.10795)
			(padstack
				(mode front_inner_back)
				(layer "Inner"
					(shape circle)
					(size 0.8001 0.8001)
					(clearance 0.1524)
				)
				(layer "B.Cu"
					(shape circle)
					(size 1.0033 1.0033)
					(clearance 0.10795)
				)
			)
		)
	)
	(footprint ""
		(layer "F.Cu")
		(at 31.937452 -164.364162)
		(property "Reference" "PC393"
			(at 0 0 0)
			(layer "F.SilkS")
			(hide yes)
			(effects
				(font
					(size 1.27 1.27)
				)
			)
		)
		(property "Value" ""
			(at 0 0 0)
			(layer "F.Fab")
			(effects
				(font
					(size 1.27 1.27)
				)
			)
		)
		(duplicate_pad_numbers_are_jumpers no)
		(fp_line
			(start -0.7874 -0.4064)
			(end 0.7874 -0.4064)
			(stroke
				(width 0.1524)
				(type default)
			)
			(layer "F.SilkS")
		)
		(fp_line
			(start -0.7874 0.4064)
			(end -0.7874 -0.4064)
			(stroke
				(width 0.1524)
				(type default)
			)
			(layer "F.SilkS")
		)
		(fp_line
			(start 0.7874 -0.4064)
			(end 0.7874 0.4064)
			(stroke
				(width 0.1524)
				(type default)
			)
			(layer "F.SilkS")
		)
		(fp_line
			(start 0.7874 0.4064)
			(end -0.7874 0.4064)
			(stroke
				(width 0.1524)
				(type default)
			)
			(layer "F.SilkS")
		)
		(fp_line
			(start -0.67945 -0.305054)
			(end -0.12065 -0.305054)
			(stroke
				(width 0.1)
				(type default)
			)
			(layer "F.Fab")
		)
		(fp_line
			(start -0.67945 0.3048)
			(end -0.67945 -0.305054)
			(stroke
				(width 0.1)
				(type default)
			)
			(layer "F.Fab")
		)
		(fp_line
			(start -0.12065 -0.305054)
			(end -0.12065 -0.2794)
			(stroke
				(width 0.1)
				(type default)
			)
			(layer "F.Fab")
		)
		(fp_line
			(start -0.12065 -0.2794)
			(end 0.12065 -0.2794)
			(stroke
				(width 0.1)
				(type default)
			)
			(layer "F.Fab")
		)
		(fp_line
			(start -0.12065 0.2794)
			(end -0.12065 0.3048)
			(stroke
				(width 0.1)
				(type default)
			)
			(layer "F.Fab")
		)
		(fp_line
			(start -0.12065 0.3048)
			(end -0.67945 0.3048)
			(stroke
				(width 0.1)
				(type default)
			)
			(layer "F.Fab")
		)
		(fp_line
			(start 0.120396 0.2794)
			(end -0.12065 0.2794)
			(stroke
				(width 0.1)
				(type default)
			)
			(layer "F.Fab")
		)
		(fp_line
			(start 0.120396 0.3048)
			(end 0.120396 0.2794)
			(stroke
				(width 0.1)
				(type default)
			)
			(layer "F.Fab")
		)
		(fp_line
			(start 0.12065 -0.3048)
			(end 0.67945 -0.3048)
			(stroke
				(width 0.1)
				(type default)
			)
			(layer "F.Fab")
		)
		(fp_line
			(start 0.12065 -0.2794)
			(end 0.12065 -0.3048)
			(stroke
				(width 0.1)
				(type default)
			)
			(layer "F.Fab")
		)
		(fp_line
			(start 0.67945 -0.3048)
			(end 0.67945 0.3048)
			(stroke
				(width 0.1)
				(type default)
			)
			(layer "F.Fab")
		)
		(fp_line
			(start 0.67945 0.3048)
			(end 0.120396 0.3048)
			(stroke
				(width 0.1)
				(type default)
			)
			(layer "F.Fab")
		)
		(pad "1" smd circle
			(at -0.40005 0)
			(size 0 0)
			(layers "F.Cu" "F.Mask" "F.Paste")
			(net "PVCCD_HV_CPU1_ATSEN")
		)
		(pad "2" smd circle
			(at 0.40005 0)
			(size 0 0)
			(layers "F.Cu" "F.Mask" "F.Paste")
			(net "GND")
		)
	)
	(footprint ""
		(layer "F.Cu")
		(at 96.163638 -408.517344 -90)
		(property "Reference" "C679"
			(at 0 0 270)
			(layer "F.SilkS")
			(hide yes)
			(effects
				(font
					(size 1.27 1.27)
				)
			)
		)
		(property "Value" ""
			(at 0 0 270)
			(layer "F.Fab")
			(effects
				(font
					(size 1.27 1.27)
				)
			)
		)
		(duplicate_pad_numbers_are_jumpers no)
		(fp_line
			(start -0.299974 0.150114)
			(end -0.299974 -0.150114)
			(stroke
				(width 0.1)
				(type default)
			)
			(layer "F.Fab")
		)
		(fp_line
			(start 0.299974 0.150114)
			(end -0.299974 0.150114)
			(stroke
				(width 0.1)
				(type default)
			)
			(layer "F.Fab")
		)
		(fp_line
			(start -0.299974 -0.150114)
			(end 0.299974 -0.150114)
			(stroke
				(width 0.1)
				(type default)
			)
			(layer "F.Fab")
		)
		(fp_line
			(start 0.299974 -0.150114)
			(end 0.299974 0.150114)
			(stroke
				(width 0.1)
				(type default)
			)
			(layer "F.Fab")
		)
		(pad "1" smd rect
			(at -0.2667 0 270)
			(size 0.3048 0.381)
			(layers "F.Cu" "F.Mask" "F.Paste")
			(net "P5E_CPU1_PE4_TX_C_DP<15>")
		)
		(pad "2" smd rect
			(at 0.2667 0 270)
			(size 0.3048 0.381)
			(layers "F.Cu" "F.Mask" "F.Paste")
			(net "P5E_CPU1_PE4_TX_DP<15>")
		)
	)
	(footprint ""
		(layer "F.Cu")
		(at 216.065608 -407.871422 180)
		(property "Reference" "PR3912"
			(at 0 0 180)
			(layer "F.SilkS")
			(hide yes)
			(effects
				(font
					(size 1.27 1.27)
				)
			)
		)
		(property "Value" ""
			(at 0 0 180)
			(layer "F.Fab")
			(effects
				(font
					(size 1.27 1.27)
				)
			)
		)
		(duplicate_pad_numbers_are_jumpers no)
		(fp_line
			(start 0.7874 0.4064)
			(end -0.7874 0.4064)
			(stroke
				(width 0.1524)
				(type default)
			)
			(layer "F.SilkS")
		)
		(fp_line
			(start 0.7874 -0.4064)
			(end 0.7874 0.4064)
			(stroke
				(width 0.1524)
				(type default)
			)
			(layer "F.SilkS")
		)
		(fp_line
			(start -0.7874 0.4064)
			(end -0.7874 -0.4064)
			(stroke
				(width 0.1524)
				(type default)
			)
			(layer "F.SilkS")
		)
		(fp_line
			(start -0.7874 -0.4064)
			(end 0.7874 -0.4064)
			(stroke
				(width 0.1524)
				(type default)
			)
			(layer "F.SilkS")
		)
		(fp_line
			(start 0.67945 0.3048)
			(end 0.120396 0.3048)
			(stroke
				(width 0.1)
				(type default)
			)
			(layer "F.Fab")
		)
		(fp_line
			(start 0.67945 -0.3048)
			(end 0.67945 0.3048)
			(stroke
				(width 0.1)
				(type default)
			)
			(layer "F.Fab")
		)
		(fp_line
			(start 0.12065 -0.2794)
			(end 0.12065 -0.3048)
			(stroke
				(width 0.1)
				(type default)
			)
			(layer "F.Fab")
		)
		(fp_line
			(start 0.12065 -0.3048)
			(end 0.67945 -0.3048)
			(stroke
				(width 0.1)
				(type default)
			)
			(layer "F.Fab")
		)
		(fp_line
			(start 0.120396 0.3048)
			(end 0.120396 0.2794)
			(stroke
				(width 0.1)
				(type default)
			)
			(layer "F.Fab")
		)
		(fp_line
			(start 0.120396 0.2794)
			(end -0.12065 0.2794)
			(stroke
				(width 0.1)
				(type default)
			)
			(layer "F.Fab")
		)
		(fp_line
			(start -0.12065 0.3048)
			(end -0.67945 0.3048)
			(stroke
				(width 0.1)
				(type default)
			)
			(layer "F.Fab")
		)
		(fp_line
			(start -0.12065 0.2794)
			(end -0.12065 0.3048)
			(stroke
				(width 0.1)
				(type default)
			)
			(layer "F.Fab")
		)
		(fp_line
			(start -0.12065 -0.2794)
			(end 0.12065 -0.2794)
			(stroke
				(width 0.1)
				(type default)
			)
			(layer "F.Fab")
		)
		(fp_line
			(start -0.12065 -0.305054)
			(end -0.12065 -0.2794)
			(stroke
				(width 0.1)
				(type default)
			)
			(layer "F.Fab")
		)
		(fp_line
			(start -0.67945 0.3048)
			(end -0.67945 -0.305054)
			(stroke
				(width 0.1)
				(type default)
			)
			(layer "F.Fab")
		)
		(fp_line
			(start -0.67945 -0.305054)
			(end -0.12065 -0.305054)
			(stroke
				(width 0.1)
				(type default)
			)
			(layer "F.Fab")
		)
		(pad "1" smd circle
			(at -0.40005 0 180)
			(size 0 0)
			(layers "F.Cu" "F.Mask" "F.Paste")
			(net "AGND_HSC")
		)
		(pad "2" smd circle
			(at 0.40005 0 180)
			(size 0 0)
			(layers "F.Cu" "F.Mask" "F.Paste")
			(net "HSC_MODE_2")
		)
	)
	(footprint ""
		(layer "F.Cu")
		(at 218.08948 -126.761748)
		(property "Reference" "R1692"
			(at 0 0 0)
			(layer "F.SilkS")
			(hide yes)
			(effects
				(font
					(size 1.27 1.27)
				)
			)
		)
		(property "Value" ""
			(at 0 0 0)
			(layer "F.Fab")
			(effects
				(font
					(size 1.27 1.27)
				)
			)
		)
		(duplicate_pad_numbers_are_jumpers no)
		(fp_line
			(start -0.7874 -0.4064)
			(end 0.7874 -0.4064)
			(stroke
				(width 0.1524)
				(type default)
			)
			(layer "F.SilkS")
		)
		(fp_line
			(start -0.7874 0.4064)
			(end -0.7874 -0.4064)
			(stroke
				(width 0.1524)
				(type default)
			)
			(layer "F.SilkS")
		)
		(fp_line
			(start 0.7874 -0.4064)
			(end 0.7874 0.4064)
			(stroke
				(width 0.1524)
				(type default)
			)
			(layer "F.SilkS")
		)
		(fp_line
			(start 0.7874 0.4064)
			(end -0.7874 0.4064)
			(stroke
				(width 0.1524)
				(type default)
			)
			(layer "F.SilkS")
		)
		(fp_line
			(start -0.67945 -0.305054)
			(end -0.12065 -0.305054)
			(stroke
				(width 0.1)
				(type default)
			)
			(layer "F.Fab")
		)
		(fp_line
			(start -0.67945 0.3048)
			(end -0.67945 -0.305054)
			(stroke
				(width 0.1)
				(type default)
			)
			(layer "F.Fab")
		)
		(fp_line
			(start -0.12065 -0.305054)
			(end -0.12065 -0.2794)
			(stroke
				(width 0.1)
				(type default)
			)
			(layer "F.Fab")
		)
		(fp_line
			(start -0.12065 -0.2794)
			(end 0.12065 -0.2794)
			(stroke
				(width 0.1)
				(type default)
			)
			(layer "F.Fab")
		)
		(fp_line
			(start -0.12065 0.2794)
			(end -0.12065 0.3048)
			(stroke
				(width 0.1)
				(type default)
			)
			(layer "F.Fab")
		)
		(fp_line
			(start -0.12065 0.3048)
			(end -0.67945 0.3048)
			(stroke
				(width 0.1)
				(type default)
			)
			(layer "F.Fab")
		)
		(fp_line
			(start 0.120396 0.2794)
			(end -0.12065 0.2794)
			(stroke
				(width 0.1)
				(type default)
			)
			(layer "F.Fab")
		)
		(fp_line
			(start 0.120396 0.3048)
			(end 0.120396 0.2794)
			(stroke
				(width 0.1)
				(type default)
			)
			(layer "F.Fab")
		)
		(fp_line
			(start 0.12065 -0.3048)
			(end 0.67945 -0.3048)
			(stroke
				(width 0.1)
				(type default)
			)
			(layer "F.Fab")
		)
		(fp_line
			(start 0.12065 -0.2794)
			(end 0.12065 -0.3048)
			(stroke
				(width 0.1)
				(type default)
			)
			(layer "F.Fab")
		)
		(fp_line
			(start 0.67945 -0.3048)
			(end 0.67945 0.3048)
			(stroke
				(width 0.1)
				(type default)
			)
			(layer "F.Fab")
		)
		(fp_line
			(start 0.67945 0.3048)
			(end 0.120396 0.3048)
			(stroke
				(width 0.1)
				(type default)
			)
			(layer "F.Fab")
		)
		(pad "1" smd circle
			(at -0.40005 0)
			(size 0 0)
			(layers "F.Cu" "F.Mask" "F.Paste")
			(net "PWRGD_DSW_PWROK_R1")
		)
		(pad "2" smd circle
			(at 0.40005 0)
			(size 0 0)
			(layers "F.Cu" "F.Mask" "F.Paste")
			(net "GND")
		)
	)
	(footprint ""
		(layer "F.Cu")
		(at 48.931068 -175.179482 180)
		(property "Reference" "PR1798"
			(at 0 0 180)
			(layer "F.SilkS")
			(hide yes)
			(effects
				(font
					(size 1.27 1.27)
				)
			)
		)
		(property "Value" ""
			(at 0 0 180)
			(layer "F.Fab")
			(effects
				(font
					(size 1.27 1.27)
				)
			)
		)
		(duplicate_pad_numbers_are_jumpers no)
		(fp_line
			(start 0.7874 0.4064)
			(end -0.7874 0.4064)
			(stroke
				(width 0.1524)
				(type default)
			)
			(layer "F.SilkS")
		)
		(fp_line
			(start 0.7874 -0.4064)
			(end 0.7874 0.4064)
			(stroke
				(width 0.1524)
				(type default)
			)
			(layer "F.SilkS")
		)
		(fp_line
			(start -0.7874 0.4064)
			(end -0.7874 -0.4064)
			(stroke
				(width 0.1524)
				(type default)
			)
			(layer "F.SilkS")
		)
		(fp_line
			(start -0.7874 -0.4064)
			(end 0.7874 -0.4064)
			(stroke
				(width 0.1524)
				(type default)
			)
			(layer "F.SilkS")
		)
		(fp_line
			(start 0.67945 0.3048)
			(end 0.120396 0.3048)
			(stroke
				(width 0.1)
				(type default)
			)
			(layer "F.Fab")
		)
		(fp_line
			(start 0.67945 -0.3048)
			(end 0.67945 0.3048)
			(stroke
				(width 0.1)
				(type default)
			)
			(layer "F.Fab")
		)
		(fp_line
			(start 0.12065 -0.2794)
			(end 0.12065 -0.3048)
			(stroke
				(width 0.1)
				(type default)
			)
			(layer "F.Fab")
		)
		(fp_line
			(start 0.12065 -0.3048)
			(end 0.67945 -0.3048)
			(stroke
				(width 0.1)
				(type default)
			)
			(layer "F.Fab")
		)
		(fp_line
			(start 0.120396 0.3048)
			(end 0.120396 0.2794)
			(stroke
				(width 0.1)
				(type default)
			)
			(layer "F.Fab")
		)
		(fp_line
			(start 0.120396 0.2794)
			(end -0.12065 0.2794)
			(stroke
				(width 0.1)
				(type default)
			)
			(layer "F.Fab")
		)
		(fp_line
			(start -0.12065 0.3048)
			(end -0.67945 0.3048)
			(stroke
				(width 0.1)
				(type default)
			)
			(layer "F.Fab")
		)
		(fp_line
			(start -0.12065 0.2794)
			(end -0.12065 0.3048)
			(stroke
				(width 0.1)
				(type default)
			)
			(layer "F.Fab")
		)
		(fp_line
			(start -0.12065 -0.2794)
			(end 0.12065 -0.2794)
			(stroke
				(width 0.1)
				(type default)
			)
			(layer "F.Fab")
		)
		(fp_line
			(start -0.12065 -0.305054)
			(end -0.12065 -0.2794)
			(stroke
				(width 0.1)
				(type default)
			)
			(layer "F.Fab")
		)
		(fp_line
			(start -0.67945 0.3048)
			(end -0.67945 -0.305054)
			(stroke
				(width 0.1)
				(type default)
			)
			(layer "F.Fab")
		)
		(fp_line
			(start -0.67945 -0.305054)
			(end -0.12065 -0.305054)
			(stroke
				(width 0.1)
				(type default)
			)
			(layer "F.Fab")
		)
		(pad "1" smd circle
			(at -0.40005 0 180)
			(size 0 0)
			(layers "F.Cu" "F.Mask" "F.Paste")
			(net "SW_PVCCFA_EHV_CPU1_BOOT1")
		)
		(pad "2" smd circle
			(at 0.40005 0 180)
			(size 0 0)
			(layers "F.Cu" "F.Mask" "F.Paste")
			(net "SW_PVCCFA_EHV_CPU1_BOOT1_R")
		)
	)
	(footprint ""
		(layer "F.Cu")
		(at 20.60956 -75.132692)
		(property "Reference" "R3135"
			(at 0 0 0)
			(layer "F.SilkS")
			(hide yes)
			(effects
				(font
					(size 1.27 1.27)
				)
			)
		)
		(property "Value" ""
			(at 0 0 0)
			(layer "F.Fab")
			(effects
				(font
					(size 1.27 1.27)
				)
			)
		)
		(duplicate_pad_numbers_are_jumpers no)
		(fp_line
			(start -0.7874 -0.4064)
			(end 0.7874 -0.4064)
			(stroke
				(width 0.1524)
				(type default)
			)
			(layer "F.SilkS")
		)
		(fp_line
			(start -0.7874 0.4064)
			(end -0.7874 -0.4064)
			(stroke
				(width 0.1524)
				(type default)
			)
			(layer "F.SilkS")
		)
		(fp_line
			(start 0.7874 -0.4064)
			(end 0.7874 0.4064)
			(stroke
				(width 0.1524)
				(type default)
			)
			(layer "F.SilkS")
		)
		(fp_line
			(start 0.7874 0.4064)
			(end -0.7874 0.4064)
			(stroke
				(width 0.1524)
				(type default)
			)
			(layer "F.SilkS")
		)
		(fp_line
			(start -0.67945 -0.305054)
			(end -0.12065 -0.305054)
			(stroke
				(width 0.1)
				(type default)
			)
			(layer "F.Fab")
		)
		(fp_line
			(start -0.67945 0.3048)
			(end -0.67945 -0.305054)
			(stroke
				(width 0.1)
				(type default)
			)
			(layer "F.Fab")
		)
		(fp_line
			(start -0.12065 -0.305054)
			(end -0.12065 -0.2794)
			(stroke
				(width 0.1)
				(type default)
			)
			(layer "F.Fab")
		)
		(fp_line
			(start -0.12065 -0.2794)
			(end 0.12065 -0.2794)
			(stroke
				(width 0.1)
				(type default)
			)
			(layer "F.Fab")
		)
		(fp_line
			(start -0.12065 0.2794)
			(end -0.12065 0.3048)
			(stroke
				(width 0.1)
				(type default)
			)
			(layer "F.Fab")
		)
		(fp_line
			(start -0.12065 0.3048)
			(end -0.67945 0.3048)
			(stroke
				(width 0.1)
				(type default)
			)
			(layer "F.Fab")
		)
		(fp_line
			(start 0.120396 0.2794)
			(end -0.12065 0.2794)
			(stroke
				(width 0.1)
				(type default)
			)
			(layer "F.Fab")
		)
		(fp_line
			(start 0.120396 0.3048)
			(end 0.120396 0.2794)
			(stroke
				(width 0.1)
				(type default)
			)
			(layer "F.Fab")
		)
		(fp_line
			(start 0.12065 -0.3048)
			(end 0.67945 -0.3048)
			(stroke
				(width 0.1)
				(type default)
			)
			(layer "F.Fab")
		)
		(fp_line
			(start 0.12065 -0.2794)
			(end 0.12065 -0.3048)
			(stroke
				(width 0.1)
				(type default)
			)
			(layer "F.Fab")
		)
		(fp_line
			(start 0.67945 -0.3048)
			(end 0.67945 0.3048)
			(stroke
				(width 0.1)
				(type default)
			)
			(layer "F.Fab")
		)
		(fp_line
			(start 0.67945 0.3048)
			(end 0.120396 0.3048)
			(stroke
				(width 0.1)
				(type default)
			)
			(layer "F.Fab")
		)
		(pad "1" smd circle
			(at -0.40005 0)
			(size 0 0)
			(layers "F.Cu" "F.Mask" "F.Paste")
			(net "P3V3_AUX")
		)
		(pad "2" smd circle
			(at 0.40005 0)
			(size 0 0)
			(layers "F.Cu" "F.Mask" "F.Paste")
			(net "OCP_V3_2_PRSNT1_R_N")
		)
	)
	(footprint ""
		(layer "F.Cu")
		(at 256.14503 -70.40626 -90)
		(property "Reference" "PC1217"
			(at 0 0 270)
			(layer "F.SilkS")
			(hide yes)
			(effects
				(font
					(size 1.27 1.27)
				)
			)
		)
		(property "Value" ""
			(at 0 0 270)
			(layer "F.Fab")
			(effects
				(font
					(size 1.27 1.27)
				)
			)
		)
		(duplicate_pad_numbers_are_jumpers no)
		(fp_line
			(start -1.524 0.762)
			(end -1.524 -0.762)
			(stroke
				(width 0.1524)
				(type default)
			)
			(layer "F.SilkS")
		)
		(fp_line
			(start 1.524 0.762)
			(end -1.524 0.762)
			(stroke
				(width 0.1524)
				(type default)
			)
			(layer "F.SilkS")
		)
		(fp_line
			(start -1.524 -0.762)
			(end 1.524 -0.762)
			(stroke
				(width 0.1524)
				(type default)
			)
			(layer "F.SilkS")
		)
		(fp_line
			(start 1.524 -0.762)
			(end 1.524 0.762)
			(stroke
				(width 0.1524)
				(type default)
			)
			(layer "F.SilkS")
		)
		(fp_line
			(start -1.1049 0.724916)
			(end 1.1049 0.724916)
			(stroke
				(width 0.1)
				(type default)
			)
			(layer "F.Fab")
		)
		(fp_line
			(start 1.1049 0.724916)
			(end 1.1049 -0.724916)
			(stroke
				(width 0.1)
				(type default)
			)
			(layer "F.Fab")
		)
		(fp_line
			(start -1.1049 -0.724916)
			(end -1.1049 0.724916)
			(stroke
				(width 0.1)
				(type default)
			)
			(layer "F.Fab")
		)
		(fp_line
			(start 1.1049 -0.724916)
			(end -1.1049 -0.724916)
			(stroke
				(width 0.1)
				(type default)
			)
			(layer "F.Fab")
		)
		(pad "1" smd rect
			(at -0.889 0 90)
			(size 1.016 1.27)
			(layers "F.Cu" "F.Mask" "F.Paste")
			(net "SW_P12V_AUX_P1V05_PCH_AUX_FLT")
		)
		(pad "2" smd rect
			(at 0.889 0 90)
			(size 1.016 1.27)
			(layers "F.Cu" "F.Mask" "F.Paste")
			(net "GND")
		)
	)
	(footprint ""
		(layer "F.Cu")
		(at 82.706718 -21.016722 90)
		(property "Reference" "R3816"
			(at 0 0 90)
			(layer "F.SilkS")
			(hide yes)
			(effects
				(font
					(size 1.27 1.27)
				)
			)
		)
		(property "Value" ""
			(at 0 0 90)
			(layer "F.Fab")
			(effects
				(font
					(size 1.27 1.27)
				)
			)
		)
		(duplicate_pad_numbers_are_jumpers no)
		(fp_line
			(start 0.7874 -0.4064)
			(end 0.7874 0.4064)
			(stroke
				(width 0.1524)
				(type default)
			)
			(layer "F.SilkS")
		)
		(fp_line
			(start -0.7874 -0.4064)
			(end 0.7874 -0.4064)
			(stroke
				(width 0.1524)
				(type default)
			)
			(layer "F.SilkS")
		)
		(fp_line
			(start 0.7874 0.4064)
			(end -0.7874 0.4064)
			(stroke
				(width 0.1524)
				(type default)
			)
			(layer "F.SilkS")
		)
		(fp_line
			(start -0.7874 0.4064)
			(end -0.7874 -0.4064)
			(stroke
				(width 0.1524)
				(type default)
			)
			(layer "F.SilkS")
		)
		(fp_line
			(start -0.12065 -0.305054)
			(end -0.12065 -0.2794)
			(stroke
				(width 0.1)
				(type default)
			)
			(layer "F.Fab")
		)
		(fp_line
			(start -0.67945 -0.305054)
			(end -0.12065 -0.305054)
			(stroke
				(width 0.1)
				(type default)
			)
			(layer "F.Fab")
		)
		(fp_line
			(start 0.67945 -0.3048)
			(end 0.67945 0.3048)
			(stroke
				(width 0.1)
				(type default)
			)
			(layer "F.Fab")
		)
		(fp_line
			(start 0.12065 -0.3048)
			(end 0.67945 -0.3048)
			(stroke
				(width 0.1)
				(type default)
			)
			(layer "F.Fab")
		)
		(fp_line
			(start 0.12065 -0.2794)
			(end 0.12065 -0.3048)
			(stroke
				(width 0.1)
				(type default)
			)
			(layer "F.Fab")
		)
		(fp_line
			(start -0.12065 -0.2794)
			(end 0.12065 -0.2794)
			(stroke
				(width 0.1)
				(type default)
			)
			(layer "F.Fab")
		)
		(fp_line
			(start 0.120396 0.2794)
			(end -0.12065 0.2794)
			(stroke
				(width 0.1)
				(type default)
			)
			(layer "F.Fab")
		)
		(fp_line
			(start -0.12065 0.2794)
			(end -0.12065 0.3048)
			(stroke
				(width 0.1)
				(type default)
			)
			(layer "F.Fab")
		)
		(fp_line
			(start 0.67945 0.3048)
			(end 0.120396 0.3048)
			(stroke
				(width 0.1)
				(type default)
			)
			(layer "F.Fab")
		)
		(fp_line
			(start 0.120396 0.3048)
			(end 0.120396 0.2794)
			(stroke
				(width 0.1)
				(type default)
			)
			(layer "F.Fab")
		)
		(fp_line
			(start -0.12065 0.3048)
			(end -0.67945 0.3048)
			(stroke
				(width 0.1)
				(type default)
			)
			(layer "F.Fab")
		)
		(fp_line
			(start -0.67945 0.3048)
			(end -0.67945 -0.305054)
			(stroke
				(width 0.1)
				(type default)
			)
			(layer "F.Fab")
		)
		(pad "1" smd circle
			(at -0.40005 0 90)
			(size 0 0)
			(layers "F.Cu" "F.Mask" "F.Paste")
			(net "P3V3_AUX")
		)
		(pad "2" smd circle
			(at 0.40005 0 90)
			(size 0 0)
			(layers "F.Cu" "F.Mask" "F.Paste")
			(net "P12V_OCP_FAULT_2")
		)
	)
	(footprint ""
		(layer "F.Cu")
		(at 415.101786 -346.010992)
		(property "Reference" "PC1185"
			(at 0 0 0)
			(layer "F.SilkS")
			(hide yes)
			(effects
				(font
					(size 1.27 1.27)
				)
			)
		)
		(property "Value" ""
			(at 0 0 0)
			(layer "F.Fab")
			(effects
				(font
					(size 1.27 1.27)
				)
			)
		)
		(duplicate_pad_numbers_are_jumpers no)
		(fp_line
			(start 2.750058 0.999998)
			(end -2.750058 0.999998)
			(stroke
				(width 0.1524)
				(type default)
			)
			(layer "F.SilkS")
		)
		(fp_circle
			(center 0 0.999998)
			(end 2.750058 0.999998)
			(stroke
				(width 0.1524)
				(type default)
			)
			(fill no)
			(layer "F.SilkS")
		)
		(fp_poly
			(pts
				(arc
					(start 2.750058 0.999998)
					(mid 0 3.750056)
					(end -2.750058 0.999998)
				)
			)
			(stroke
				(width 0)
				(type default)
			)
			(fill yes)
			(layer "F.SilkS")
		)
		(fp_circle
			(center 0 0.999998)
			(end 2.750058 0.999998)
			(stroke
				(width 0.1)
				(type default)
			)
			(fill no)
			(layer "F.Fab")
		)
		(pad "1" thru_hole rect
			(at 0 0)
			(size 1.5748 1.5748)
			(drill 1.0668)
			(layers "*.Cu" "*.Mask")
			(remove_unused_layers no)
			(net "PVCCFA_EHV_FIVRA_CPU0")
			(clearance 0)
			(padstack
				(mode front_inner_back)
				(layer "Inner"
					(shape circle)
					(size 1.5748 1.5748)
					(clearance 0)
				)
				(layer "B.Cu"
					(shape rect)
					(size 1.5748 1.5748)
					(clearance 0)
				)
			)
		)
		(pad "2" thru_hole circle
			(at 0 1.999996)
			(size 1.5748 1.5748)
			(drill 1.0668)
			(layers "*.Cu" "*.Mask")
			(remove_unused_layers no)
			(net "GND")
			(clearance 0)
		)
	)
	(footprint ""
		(layer "F.Cu")
		(at 308.364128 -408.517344 -90)
		(property "Reference" "C904"
			(at 0 0 270)
			(layer "F.SilkS")
			(hide yes)
			(effects
				(font
					(size 1.27 1.27)
				)
			)
		)
		(property "Value" ""
			(at 0 0 270)
			(layer "F.Fab")
			(effects
				(font
					(size 1.27 1.27)
				)
			)
		)
		(duplicate_pad_numbers_are_jumpers no)
		(fp_line
			(start -0.299974 0.150114)
			(end -0.299974 -0.150114)
			(stroke
				(width 0.1)
				(type default)
			)
			(layer "F.Fab")
		)
		(fp_line
			(start 0.299974 0.150114)
			(end -0.299974 0.150114)
			(stroke
				(width 0.1)
				(type default)
			)
			(layer "F.Fab")
		)
		(fp_line
			(start -0.299974 -0.150114)
			(end 0.299974 -0.150114)
			(stroke
				(width 0.1)
				(type default)
			)
			(layer "F.Fab")
		)
		(fp_line
			(start 0.299974 -0.150114)
			(end 0.299974 0.150114)
			(stroke
				(width 0.1)
				(type default)
			)
			(layer "F.Fab")
		)
		(pad "1" smd rect
			(at -0.2667 0 270)
			(size 0.3048 0.381)
			(layers "F.Cu" "F.Mask" "F.Paste")
			(net "P5E_CPU0_PE0_TX_C_DN<14>")
		)
		(pad "2" smd rect
			(at 0.2667 0 270)
			(size 0.3048 0.381)
			(layers "F.Cu" "F.Mask" "F.Paste")
			(net "P5E_CPU0_PE0_TX_DN<14>")
		)
	)
	(footprint ""
		(layer "F.Cu")
		(at 105.21188 -423.763948 180)
		(property "Reference" "R4178"
			(at 0 0 180)
			(layer "F.SilkS")
			(hide yes)
			(effects
				(font
					(size 1.27 1.27)
				)
			)
		)
		(property "Value" ""
			(at 0 0 180)
			(layer "F.Fab")
			(effects
				(font
					(size 1.27 1.27)
				)
			)
		)
		(duplicate_pad_numbers_are_jumpers no)
		(fp_line
			(start 0.7874 0.4064)
			(end -0.7874 0.4064)
			(stroke
				(width 0.1524)
				(type default)
			)
			(layer "F.SilkS")
		)
		(fp_line
			(start 0.7874 -0.4064)
			(end 0.7874 0.4064)
			(stroke
				(width 0.1524)
				(type default)
			)
			(layer "F.SilkS")
		)
		(fp_line
			(start -0.7874 0.4064)
			(end -0.7874 -0.4064)
			(stroke
				(width 0.1524)
				(type default)
			)
			(layer "F.SilkS")
		)
		(fp_line
			(start -0.7874 -0.4064)
			(end 0.7874 -0.4064)
			(stroke
				(width 0.1524)
				(type default)
			)
			(layer "F.SilkS")
		)
		(fp_line
			(start 0.67945 0.3048)
			(end 0.120396 0.3048)
			(stroke
				(width 0.1)
				(type default)
			)
			(layer "F.Fab")
		)
		(fp_line
			(start 0.67945 -0.3048)
			(end 0.67945 0.3048)
			(stroke
				(width 0.1)
				(type default)
			)
			(layer "F.Fab")
		)
		(fp_line
			(start 0.12065 -0.2794)
			(end 0.12065 -0.3048)
			(stroke
				(width 0.1)
				(type default)
			)
			(layer "F.Fab")
		)
		(fp_line
			(start 0.12065 -0.3048)
			(end 0.67945 -0.3048)
			(stroke
				(width 0.1)
				(type default)
			)
			(layer "F.Fab")
		)
		(fp_line
			(start 0.120396 0.3048)
			(end 0.120396 0.2794)
			(stroke
				(width 0.1)
				(type default)
			)
			(layer "F.Fab")
		)
		(fp_line
			(start 0.120396 0.2794)
			(end -0.12065 0.2794)
			(stroke
				(width 0.1)
				(type default)
			)
			(layer "F.Fab")
		)
		(fp_line
			(start -0.12065 0.3048)
			(end -0.67945 0.3048)
			(stroke
				(width 0.1)
				(type default)
			)
			(layer "F.Fab")
		)
		(fp_line
			(start -0.12065 0.2794)
			(end -0.12065 0.3048)
			(stroke
				(width 0.1)
				(type default)
			)
			(layer "F.Fab")
		)
		(fp_line
			(start -0.12065 -0.2794)
			(end 0.12065 -0.2794)
			(stroke
				(width 0.1)
				(type default)
			)
			(layer "F.Fab")
		)
		(fp_line
			(start -0.12065 -0.305054)
			(end -0.12065 -0.2794)
			(stroke
				(width 0.1)
				(type default)
			)
			(layer "F.Fab")
		)
		(fp_line
			(start -0.67945 0.3048)
			(end -0.67945 -0.305054)
			(stroke
				(width 0.1)
				(type default)
			)
			(layer "F.Fab")
		)
		(fp_line
			(start -0.67945 -0.305054)
			(end -0.12065 -0.305054)
			(stroke
				(width 0.1)
				(type default)
			)
			(layer "F.Fab")
		)
		(pad "1" smd circle
			(at -0.40005 0 180)
			(size 0 0)
			(layers "F.Cu" "F.Mask" "F.Paste")
			(net "SMB_LM75_2_3V3AUX_SCL")
		)
		(pad "2" smd circle
			(at 0.40005 0 180)
			(size 0 0)
			(layers "F.Cu" "F.Mask" "F.Paste")
			(net "SMB_LM75_2_3V3AUX_SCL_R1")
		)
	)
	(footprint ""
		(layer "F.Cu")
		(at 114.957606 -354.065586)
		(property "Reference" "PC422"
			(at 0 0 0)
			(layer "F.SilkS")
			(hide yes)
			(effects
				(font
					(size 1.27 1.27)
				)
			)
		)
		(property "Value" ""
			(at 0 0 0)
			(layer "F.Fab")
			(effects
				(font
					(size 1.27 1.27)
				)
			)
		)
		(duplicate_pad_numbers_are_jumpers no)
		(fp_line
			(start -0.7874 -0.4064)
			(end 0.7874 -0.4064)
			(stroke
				(width 0.1524)
				(type default)
			)
			(layer "F.SilkS")
		)
		(fp_line
			(start -0.7874 0.4064)
			(end -0.7874 -0.4064)
			(stroke
				(width 0.1524)
				(type default)
			)
			(layer "F.SilkS")
		)
		(fp_line
			(start 0.7874 -0.4064)
			(end 0.7874 0.4064)
			(stroke
				(width 0.1524)
				(type default)
			)
			(layer "F.SilkS")
		)
		(fp_line
			(start 0.7874 0.4064)
			(end -0.7874 0.4064)
			(stroke
				(width 0.1524)
				(type default)
			)
			(layer "F.SilkS")
		)
		(fp_line
			(start -0.67945 -0.305054)
			(end -0.12065 -0.305054)
			(stroke
				(width 0.1)
				(type default)
			)
			(layer "F.Fab")
		)
		(fp_line
			(start -0.67945 0.3048)
			(end -0.67945 -0.305054)
			(stroke
				(width 0.1)
				(type default)
			)
			(layer "F.Fab")
		)
		(fp_line
			(start -0.12065 -0.305054)
			(end -0.12065 -0.2794)
			(stroke
				(width 0.1)
				(type default)
			)
			(layer "F.Fab")
		)
		(fp_line
			(start -0.12065 -0.2794)
			(end 0.12065 -0.2794)
			(stroke
				(width 0.1)
				(type default)
			)
			(layer "F.Fab")
		)
		(fp_line
			(start -0.12065 0.2794)
			(end -0.12065 0.3048)
			(stroke
				(width 0.1)
				(type default)
			)
			(layer "F.Fab")
		)
		(fp_line
			(start -0.12065 0.3048)
			(end -0.67945 0.3048)
			(stroke
				(width 0.1)
				(type default)
			)
			(layer "F.Fab")
		)
		(fp_line
			(start 0.120396 0.2794)
			(end -0.12065 0.2794)
			(stroke
				(width 0.1)
				(type default)
			)
			(layer "F.Fab")
		)
		(fp_line
			(start 0.120396 0.3048)
			(end 0.120396 0.2794)
			(stroke
				(width 0.1)
				(type default)
			)
			(layer "F.Fab")
		)
		(fp_line
			(start 0.12065 -0.3048)
			(end 0.67945 -0.3048)
			(stroke
				(width 0.1)
				(type default)
			)
			(layer "F.Fab")
		)
		(fp_line
			(start 0.12065 -0.2794)
			(end 0.12065 -0.3048)
			(stroke
				(width 0.1)
				(type default)
			)
			(layer "F.Fab")
		)
		(fp_line
			(start 0.67945 -0.3048)
			(end 0.67945 0.3048)
			(stroke
				(width 0.1)
				(type default)
			)
			(layer "F.Fab")
		)
		(fp_line
			(start 0.67945 0.3048)
			(end 0.120396 0.3048)
			(stroke
				(width 0.1)
				(type default)
			)
			(layer "F.Fab")
		)
		(pad "1" smd circle
			(at -0.40005 0)
			(size 0 0)
			(layers "F.Cu" "F.Mask" "F.Paste")
			(net "SH_PVCCFA_EHV_FIVRA_CPU1_R")
		)
		(pad "2" smd circle
			(at 0.40005 0)
			(size 0 0)
			(layers "F.Cu" "F.Mask" "F.Paste")
			(net "VSENSE_PVCCFA_EHV_FIVRA_CPU1_DN")
		)
	)
	(footprint ""
		(layer "F.Cu")
		(at 33.100518 -122.380502 -90)
		(property "Reference" "R2454"
			(at 0 0 270)
			(layer "F.SilkS")
			(hide yes)
			(effects
				(font
					(size 1.27 1.27)
				)
			)
		)
		(property "Value" ""
			(at 0 0 270)
			(layer "F.Fab")
			(effects
				(font
					(size 1.27 1.27)
				)
			)
		)
		(duplicate_pad_numbers_are_jumpers no)
		(fp_line
			(start -0.7874 0.4064)
			(end -0.7874 -0.4064)
			(stroke
				(width 0.1524)
				(type default)
			)
			(layer "F.SilkS")
		)
		(fp_line
			(start 0.7874 0.4064)
			(end -0.7874 0.4064)
			(stroke
				(width 0.1524)
				(type default)
			)
			(layer "F.SilkS")
		)
		(fp_line
			(start -0.7874 -0.4064)
			(end 0.7874 -0.4064)
			(stroke
				(width 0.1524)
				(type default)
			)
			(layer "F.SilkS")
		)
		(fp_line
			(start 0.7874 -0.4064)
			(end 0.7874 0.4064)
			(stroke
				(width 0.1524)
				(type default)
			)
			(layer "F.SilkS")
		)
		(fp_line
			(start -0.67945 0.3048)
			(end -0.67945 -0.305054)
			(stroke
				(width 0.1)
				(type default)
			)
			(layer "F.Fab")
		)
		(fp_line
			(start -0.12065 0.3048)
			(end -0.67945 0.3048)
			(stroke
				(width 0.1)
				(type default)
			)
			(layer "F.Fab")
		)
		(fp_line
			(start 0.120396 0.3048)
			(end 0.120396 0.2794)
			(stroke
				(width 0.1)
				(type default)
			)
			(layer "F.Fab")
		)
		(fp_line
			(start 0.67945 0.3048)
			(end 0.120396 0.3048)
			(stroke
				(width 0.1)
				(type default)
			)
			(layer "F.Fab")
		)
		(fp_line
			(start -0.12065 0.2794)
			(end -0.12065 0.3048)
			(stroke
				(width 0.1)
				(type default)
			)
			(layer "F.Fab")
		)
		(fp_line
			(start 0.120396 0.2794)
			(end -0.12065 0.2794)
			(stroke
				(width 0.1)
				(type default)
			)
			(layer "F.Fab")
		)
		(fp_line
			(start -0.12065 -0.2794)
			(end 0.12065 -0.2794)
			(stroke
				(width 0.1)
				(type default)
			)
			(layer "F.Fab")
		)
		(fp_line
			(start 0.12065 -0.2794)
			(end 0.12065 -0.3048)
			(stroke
				(width 0.1)
				(type default)
			)
			(layer "F.Fab")
		)
		(fp_line
			(start 0.12065 -0.3048)
			(end 0.67945 -0.3048)
			(stroke
				(width 0.1)
				(type default)
			)
			(layer "F.Fab")
		)
		(fp_line
			(start 0.67945 -0.3048)
			(end 0.67945 0.3048)
			(stroke
				(width 0.1)
				(type default)
			)
			(layer "F.Fab")
		)
		(fp_line
			(start -0.67945 -0.305054)
			(end -0.12065 -0.305054)
			(stroke
				(width 0.1)
				(type default)
			)
			(layer "F.Fab")
		)
		(fp_line
			(start -0.12065 -0.305054)
			(end -0.12065 -0.2794)
			(stroke
				(width 0.1)
				(type default)
			)
			(layer "F.Fab")
		)
		(pad "1" smd circle
			(at -0.40005 0 270)
			(size 0 0)
			(layers "F.Cu" "F.Mask" "F.Paste")
			(net "SMB_VR_3V3AUX_SDA_R")
		)
		(pad "2" smd circle
			(at 0.40005 0 270)
			(size 0 0)
			(layers "F.Cu" "F.Mask" "F.Paste")
			(net "SMB_VR_3V3AUX_SDA_R2")
		)
	)
	(footprint ""
		(layer "F.Cu")
		(at 418.48024 -153.069036 -90)
		(property "Reference" "PU42"
			(at -0.493522 -6.4643 0)
			(unlocked yes)
			(layer "F.SilkS")
			(effects
				(font
					(size 0.7874 0.5842)
					(thickness 0.1524)
				)
				(justify left)
			)
		)
		(property "Value" ""
			(at 0 0 270)
			(layer "F.Fab")
			(effects
				(font
					(size 1.27 1.27)
				)
			)
		)
		(duplicate_pad_numbers_are_jumpers no)
		(fp_line
			(start -2.050034 2.549906)
			(end -1.27 2.549906)
			(stroke
				(width 0.1524)
				(type default)
			)
			(layer "F.SilkS")
		)
		(fp_line
			(start 1.27 2.549906)
			(end 2.050034 2.549906)
			(stroke
				(width 0.1524)
				(type default)
			)
			(layer "F.SilkS")
		)
		(fp_line
			(start 2.050034 2.549906)
			(end 2.050034 1.88976)
			(stroke
				(width 0.1524)
				(type default)
			)
			(layer "F.SilkS")
		)
		(fp_line
			(start -2.050034 1.88976)
			(end -2.050034 2.549906)
			(stroke
				(width 0.1524)
				(type default)
			)
			(layer "F.SilkS")
		)
		(fp_line
			(start -2.050034 0.406654)
			(end -2.050034 0.786384)
			(stroke
				(width 0.1524)
				(type default)
			)
			(layer "F.SilkS")
		)
		(fp_line
			(start 2.050034 0.08636)
			(end 2.050034 -0.178308)
			(stroke
				(width 0.1524)
				(type default)
			)
			(layer "F.SilkS")
		)
		(fp_line
			(start 2.050034 -1.981708)
			(end 2.050034 -2.549906)
			(stroke
				(width 0.1524)
				(type default)
			)
			(layer "F.SilkS")
		)
		(fp_line
			(start -2.050034 -2.549906)
			(end -2.050034 -2.126742)
			(stroke
				(width 0.1524)
				(type default)
			)
			(layer "F.SilkS")
		)
		(fp_line
			(start -1.61671 -2.549906)
			(end -2.050034 -2.549906)
			(stroke
				(width 0.1524)
				(type default)
			)
			(layer "F.SilkS")
		)
		(fp_line
			(start 2.050034 -2.549906)
			(end 1.916684 -2.549906)
			(stroke
				(width 0.1524)
				(type default)
			)
			(layer "F.SilkS")
		)
		(fp_poly
			(pts
				(xy -2.69621 -2.060194) (xy -2.316988 -1.87071) (xy -2.69621 -1.680972)
			)
			(stroke
				(width 0)
				(type default)
			)
			(fill yes)
			(layer "F.SilkS")
		)
		(fp_line
			(start -2.050034 2.549906)
			(end 2.050034 2.549906)
			(stroke
				(width 0.1)
				(type default)
			)
			(layer "F.Fab")
		)
		(fp_line
			(start 2.050034 2.549906)
			(end 2.050034 -2.549906)
			(stroke
				(width 0.1)
				(type default)
			)
			(layer "F.Fab")
		)
		(fp_line
			(start -2.050034 -2.549906)
			(end -2.050034 2.549906)
			(stroke
				(width 0.1)
				(type default)
			)
			(layer "F.Fab")
		)
		(fp_line
			(start 2.050034 -2.549906)
			(end -2.050034 -2.549906)
			(stroke
				(width 0.1)
				(type default)
			)
			(layer "F.Fab")
		)
		(fp_poly
			(pts
				(xy -3.43789 -2.368042) (xy -3.43789 -1.352042) (xy -2.42189 -1.860042)
			)
			(stroke
				(width 0)
				(type default)
			)
			(fill yes)
			(layer "F.Fab")
		)
		(pad "1" smd rect
			(at -1.925066 -1.860042 180)
			(size 0.254 0.5588)
			(layers "F.Cu" "F.Mask" "F.Paste")
			(net "PVCCFA_EHV_CPU0_BTSEN")
		)
		(pad "2" smd rect
			(at -1.925066 -1.359916 180)
			(size 0.254 0.5588)
			(layers "F.Cu" "F.Mask" "F.Paste")
			(net "PVCCFA_EHV_CPU0_FAULT")
		)
		(pad "3" smd rect
			(at -1.925066 -0.860044 180)
			(size 0.254 0.5588)
			(layers "F.Cu" "F.Mask" "F.Paste")
			(net "PVCCFA_EHV_CPU0_NC1")
		)
		(pad "4" smd rect
			(at -1.925066 -0.359918 180)
			(size 0.254 0.5588)
			(layers "F.Cu" "F.Mask" "F.Paste")
			(net "PVCCFA_EHV_CPU0_VDD1")
		)
		(pad "5" smd rect
			(at -1.925066 0.139954 180)
			(size 0.254 0.5588)
			(layers "F.Cu" "F.Mask" "F.Paste")
			(net "PVCCFA_EHV_CPU0_LSET1")
		)
		(pad "6_7-13_15-29" smd circle
			(at 0 0.98806)
			(size 0 0)
			(layers "F.Cu" "F.Mask" "F.Paste")
			(net "GND")
		)
		(pad "8_12" smd rect
			(at 0 2.400046 180)
			(size 0.6096 2.2606)
			(layers "F.Cu" "F.Mask" "F.Paste")
			(net "SW_PVCCFA_EHV_CPU0_SW1")
		)
		(pad "16_18-28" smd rect
			(at 1.480566 -1.080008 270)
			(size 1.4478 1.524)
			(layers "F.Cu" "F.Mask" "F.Paste")
			(net "SW_P12V_PVCCINFAON_CPU0_FLT")
		)
		(pad "19" smd rect
			(at 1.649984 -2.424938 270)
			(size 0.254 0.5588)
			(layers "F.Cu" "F.Mask" "F.Paste")
			(net "SW_PVCCFA_EHV_CPU0_BOOTR1")
		)
		(pad "20" smd rect
			(at 1.150112 -2.424938 270)
			(size 0.254 0.5588)
			(layers "F.Cu" "F.Mask" "F.Paste")
			(net "SW_PVCCFA_EHV_CPU0_BOOT1")
		)
		(pad "21" smd rect
			(at 0.649986 -2.424938 270)
			(size 0.254 0.5588)
			(layers "F.Cu" "F.Mask" "F.Paste")
			(net "PVCCFA_EHV_CPU0_BPWM1")
		)
		(pad "22" smd rect
			(at 0.150114 -2.424938 270)
			(size 0.254 0.5588)
			(layers "F.Cu" "F.Mask" "F.Paste")
			(net "PVCCFA_EHV_CPU0_NC2")
		)
		(pad "23" smd rect
			(at -0.350012 -2.424938 270)
			(size 0.254 0.5588)
			(layers "F.Cu" "F.Mask" "F.Paste")
			(net "GND")
		)
		(pad "24" smd rect
			(at -0.849884 -2.424938 270)
			(size 0.254 0.5588)
			(layers "F.Cu" "F.Mask" "F.Paste")
			(net "PVCCINFAON_CPU0_VREF")
		)
		(pad "25" smd rect
			(at -1.35001 -2.424938 270)
			(size 0.254 0.5588)
			(layers "F.Cu" "F.Mask" "F.Paste")
			(net "PVCCFA_EHV_CPU0_BCSP1")
		)
		(pad "26" smd circle
			(at -0.490728 -1.009396)
			(size 0 0)
			(layers "F.Cu" "F.Mask" "F.Paste")
			(net "GND")
		)
		(pad "27" smd rect
			(at -1.124966 0.425958 180)
			(size 0.2032 0.3556)
			(layers "F.Cu" "F.Mask" "F.Paste")
			(net "Net_8494")
		)
		(zone
			(layer "F.Cu")
			(hatch none 0.5)
			(connect_pads
				(clearance 0)
			)
			(min_thickness 0.25)
			(keepout
				(tracks not_allowed)
				(vias allowed)
				(pads allowed)
				(copperpour not_allowed)
				(footprints allowed)
			)
			(placement
				(enabled no)
				(sheetname "")
			)
			(fill
				(thermal_gap 0.5)
				(thermal_bridge_width 0.5)
				(island_removal_mode 0)
			)
			(polygon
				(pts
					(xy 416.41014 -155.11907) (xy 416.67938 -155.11907) (xy 416.67938 -151.019002) (xy 416.4203 -151.019002)
					(xy 416.4203 -151.887936) (xy 416.435794 -151.887936) (xy 416.435794 -154.250136) (xy 416.41014 -154.250136)
				)
			)
		)
		(zone
			(layer "F.Cu")
			(hatch none 0.5)
			(connect_pads
				(clearance 0)
			)
			(min_thickness 0.25)
			(keepout
				(tracks not_allowed)
				(vias allowed)
				(pads allowed)
				(copperpour not_allowed)
				(footprints allowed)
			)
			(placement
				(enabled no)
				(sheetname "")
			)
			(fill
				(thermal_gap 0.5)
				(thermal_bridge_width 0.5)
				(island_removal_mode 0)
			)
			(polygon
				(pts
					(xy 420.10584 -154.663902) (xy 420.574978 -154.663902) (xy 420.574978 -151.019002) (xy 420.373048 -151.019002)
					(xy 420.373048 -152.36317) (xy 418.747448 -152.36317) (xy 418.747448 -151.019002) (xy 418.30498 -151.019002)
					(xy 418.30498 -152.499568) (xy 418.58946 -152.499568) (xy 418.58946 -152.632156) (xy 420.398448 -152.632156)
					(xy 420.398448 -154.257756) (xy 420.168832 -154.487372) (xy 420.10584 -154.487372)
				)
			)
		)
	)
	(footprint ""
		(layer "F.Cu")
		(at 444.733172 -32.173418 -90)
		(property "Reference" "R3834"
			(at 0 0 270)
			(layer "F.SilkS")
			(hide yes)
			(effects
				(font
					(size 1.27 1.27)
				)
			)
		)
		(property "Value" ""
			(at 0 0 270)
			(layer "F.Fab")
			(effects
				(font
					(size 1.27 1.27)
				)
			)
		)
		(duplicate_pad_numbers_are_jumpers no)
		(fp_line
			(start -0.7874 0.4064)
			(end -0.7874 -0.4064)
			(stroke
				(width 0.1524)
				(type default)
			)
			(layer "F.SilkS")
		)
		(fp_line
			(start 0.7874 0.4064)
			(end -0.7874 0.4064)
			(stroke
				(width 0.1524)
				(type default)
			)
			(layer "F.SilkS")
		)
		(fp_line
			(start -0.7874 -0.4064)
			(end 0.7874 -0.4064)
			(stroke
				(width 0.1524)
				(type default)
			)
			(layer "F.SilkS")
		)
		(fp_line
			(start 0.7874 -0.4064)
			(end 0.7874 0.4064)
			(stroke
				(width 0.1524)
				(type default)
			)
			(layer "F.SilkS")
		)
		(fp_line
			(start -0.67945 0.3048)
			(end -0.67945 -0.305054)
			(stroke
				(width 0.1)
				(type default)
			)
			(layer "F.Fab")
		)
		(fp_line
			(start -0.12065 0.3048)
			(end -0.67945 0.3048)
			(stroke
				(width 0.1)
				(type default)
			)
			(layer "F.Fab")
		)
		(fp_line
			(start 0.120396 0.3048)
			(end 0.120396 0.2794)
			(stroke
				(width 0.1)
				(type default)
			)
			(layer "F.Fab")
		)
		(fp_line
			(start 0.67945 0.3048)
			(end 0.120396 0.3048)
			(stroke
				(width 0.1)
				(type default)
			)
			(layer "F.Fab")
		)
		(fp_line
			(start -0.12065 0.2794)
			(end -0.12065 0.3048)
			(stroke
				(width 0.1)
				(type default)
			)
			(layer "F.Fab")
		)
		(fp_line
			(start 0.120396 0.2794)
			(end -0.12065 0.2794)
			(stroke
				(width 0.1)
				(type default)
			)
			(layer "F.Fab")
		)
		(fp_line
			(start -0.12065 -0.2794)
			(end 0.12065 -0.2794)
			(stroke
				(width 0.1)
				(type default)
			)
			(layer "F.Fab")
		)
		(fp_line
			(start 0.12065 -0.2794)
			(end 0.12065 -0.3048)
			(stroke
				(width 0.1)
				(type default)
			)
			(layer "F.Fab")
		)
		(fp_line
			(start 0.12065 -0.3048)
			(end 0.67945 -0.3048)
			(stroke
				(width 0.1)
				(type default)
			)
			(layer "F.Fab")
		)
		(fp_line
			(start 0.67945 -0.3048)
			(end 0.67945 0.3048)
			(stroke
				(width 0.1)
				(type default)
			)
			(layer "F.Fab")
		)
		(fp_line
			(start -0.67945 -0.305054)
			(end -0.12065 -0.305054)
			(stroke
				(width 0.1)
				(type default)
			)
			(layer "F.Fab")
		)
		(fp_line
			(start -0.12065 -0.305054)
			(end -0.12065 -0.2794)
			(stroke
				(width 0.1)
				(type default)
			)
			(layer "F.Fab")
		)
		(pad "1" smd circle
			(at -0.40005 0 270)
			(size 0 0)
			(layers "F.Cu" "F.Mask" "F.Paste")
			(net "HP_LVC3_OCP_V3_1_EN")
		)
		(pad "2" smd circle
			(at 0.40005 0 270)
			(size 0 0)
			(layers "F.Cu" "F.Mask" "F.Paste")
			(net "P12V_OCP_EN_1_R2")
		)
	)
	(footprint ""
		(layer "F.Cu")
		(at 506.378972 -342.873838)
		(property "Reference" "DB2"
			(at 2.71399 1.386586 90)
			(unlocked yes)
			(layer "F.SilkS")
			(effects
				(font
					(size 0.7874 0.5842)
					(thickness 0.1524)
				)
				(justify left)
			)
		)
		(property "Value" ""
			(at 0 0 0)
			(layer "F.Fab")
			(effects
				(font
					(size 1.27 1.27)
				)
			)
		)
		(duplicate_pad_numbers_are_jumpers no)
		(fp_line
			(start -3.330702 -4.771136)
			(end 3.330702 -4.771136)
			(stroke
				(width 0.1524)
				(type default)
			)
			(layer "F.SilkS")
		)
		(fp_line
			(start 0 4.011168)
			(end -3.330702 -4.771136)
			(stroke
				(width 0.1524)
				(type default)
			)
			(layer "F.SilkS")
		)
		(fp_line
			(start 3.330702 -4.771136)
			(end 0 4.011168)
			(stroke
				(width 0.1524)
				(type default)
			)
			(layer "F.SilkS")
		)
		(fp_line
			(start -3.330702 -4.771136)
			(end 3.330702 -4.771136)
			(stroke
				(width 0.1)
				(type default)
			)
			(layer "F.Fab")
		)
		(fp_line
			(start 0 4.011168)
			(end -3.330702 -4.771136)
			(stroke
				(width 0.1)
				(type default)
			)
			(layer "F.Fab")
		)
		(fp_line
			(start 3.330702 -4.771136)
			(end 0 4.011168)
			(stroke
				(width 0.1)
				(type default)
			)
			(layer "F.Fab")
		)
		(pad "1" thru_hole circle
			(at 0 0)
			(size 2.159 2.159)
			(drill 1.7018)
			(layers "*.Cu" "*.Mask")
			(remove_unused_layers no)
			(net "T1_GND")
			(clearance 0.0254)
			(thermal_gap 0.0254)
		)
		(pad "2" thru_hole circle
			(at -1.27 -3.348736)
			(size 2.159 2.159)
			(drill 1.7018)
			(layers "*.Cu" "*.Mask")
			(remove_unused_layers no)
			(net "TDR_SE_40_OHM_IN1")
			(clearance 0.0254)
			(thermal_gap 0.0254)
		)
		(pad "3" thru_hole circle
			(at 1.27 -3.348736)
			(size 2.159 2.159)
			(drill 1.7018)
			(layers "*.Cu" "*.Mask")
			(remove_unused_layers no)
			(net "TDR_SE_40_OHM_IN1")
			(clearance 0.0254)
			(thermal_gap 0.0254)
		)
	)
	(footprint ""
		(layer "F.Cu")
		(at 103.306372 -363.873034)
		(property "Reference" "R2521"
			(at 0 0 0)
			(layer "F.SilkS")
			(hide yes)
			(effects
				(font
					(size 1.27 1.27)
				)
			)
		)
		(property "Value" ""
			(at 0 0 0)
			(layer "F.Fab")
			(effects
				(font
					(size 1.27 1.27)
				)
			)
		)
		(duplicate_pad_numbers_are_jumpers no)
		(fp_line
			(start -0.7874 -0.4064)
			(end 0.7874 -0.4064)
			(stroke
				(width 0.1524)
				(type default)
			)
			(layer "F.SilkS")
		)
		(fp_line
			(start -0.7874 0.4064)
			(end -0.7874 -0.4064)
			(stroke
				(width 0.1524)
				(type default)
			)
			(layer "F.SilkS")
		)
		(fp_line
			(start 0.7874 -0.4064)
			(end 0.7874 0.4064)
			(stroke
				(width 0.1524)
				(type default)
			)
			(layer "F.SilkS")
		)
		(fp_line
			(start 0.7874 0.4064)
			(end -0.7874 0.4064)
			(stroke
				(width 0.1524)
				(type default)
			)
			(layer "F.SilkS")
		)
		(fp_line
			(start -0.67945 -0.305054)
			(end -0.12065 -0.305054)
			(stroke
				(width 0.1)
				(type default)
			)
			(layer "F.Fab")
		)
		(fp_line
			(start -0.67945 0.3048)
			(end -0.67945 -0.305054)
			(stroke
				(width 0.1)
				(type default)
			)
			(layer "F.Fab")
		)
		(fp_line
			(start -0.12065 -0.305054)
			(end -0.12065 -0.2794)
			(stroke
				(width 0.1)
				(type default)
			)
			(layer "F.Fab")
		)
		(fp_line
			(start -0.12065 -0.2794)
			(end 0.12065 -0.2794)
			(stroke
				(width 0.1)
				(type default)
			)
			(layer "F.Fab")
		)
		(fp_line
			(start -0.12065 0.2794)
			(end -0.12065 0.3048)
			(stroke
				(width 0.1)
				(type default)
			)
			(layer "F.Fab")
		)
		(fp_line
			(start -0.12065 0.3048)
			(end -0.67945 0.3048)
			(stroke
				(width 0.1)
				(type default)
			)
			(layer "F.Fab")
		)
		(fp_line
			(start 0.120396 0.2794)
			(end -0.12065 0.2794)
			(stroke
				(width 0.1)
				(type default)
			)
			(layer "F.Fab")
		)
		(fp_line
			(start 0.120396 0.3048)
			(end 0.120396 0.2794)
			(stroke
				(width 0.1)
				(type default)
			)
			(layer "F.Fab")
		)
		(fp_line
			(start 0.12065 -0.3048)
			(end 0.67945 -0.3048)
			(stroke
				(width 0.1)
				(type default)
			)
			(layer "F.Fab")
		)
		(fp_line
			(start 0.12065 -0.2794)
			(end 0.12065 -0.3048)
			(stroke
				(width 0.1)
				(type default)
			)
			(layer "F.Fab")
		)
		(fp_line
			(start 0.67945 -0.3048)
			(end 0.67945 0.3048)
			(stroke
				(width 0.1)
				(type default)
			)
			(layer "F.Fab")
		)
		(fp_line
			(start 0.67945 0.3048)
			(end 0.120396 0.3048)
			(stroke
				(width 0.1)
				(type default)
			)
			(layer "F.Fab")
		)
		(pad "1" smd circle
			(at -0.40005 0)
			(size 0 0)
			(layers "F.Cu" "F.Mask" "F.Paste")
			(net "SMB_VR_3V3AUX_SDA_R3")
		)
		(pad "2" smd circle
			(at 0.40005 0)
			(size 0 0)
			(layers "F.Cu" "F.Mask" "F.Paste")
			(net "SMB_DIO_PVCCIN_CPU1")
		)
	)
	(footprint ""
		(layer "F.Cu")
		(at 75.65009 -440.489848)
		(property "Reference" "J111"
			(at 1.96088 23.159212 0)
			(unlocked yes)
			(layer "F.SilkS")
			(effects
				(font
					(size 0.7874 0.5842)
					(thickness 0.1524)
				)
				(justify left)
			)
		)
		(property "Value" ""
			(at 0 0 0)
			(layer "F.Fab")
			(effects
				(font
					(size 1.27 1.27)
				)
			)
		)
		(duplicate_pad_numbers_are_jumpers no)
		(fp_line
			(start -4.249928 -11.999976)
			(end 18.64995 -11.999976)
			(stroke
				(width 0.1524)
				(type default)
			)
			(layer "F.SilkS")
		)
		(fp_line
			(start -4.249928 22.400006)
			(end -4.249928 -11.999976)
			(stroke
				(width 0.1524)
				(type default)
			)
			(layer "F.SilkS")
		)
		(fp_line
			(start -1.249934 -8.999982)
			(end -1.249934 19.400012)
			(stroke
				(width 0.1524)
				(type default)
			)
			(layer "F.SilkS")
		)
		(fp_line
			(start -1.249934 -1.500124)
			(end 15.649956 -1.500124)
			(stroke
				(width 0.1524)
				(type default)
			)
			(layer "F.SilkS")
		)
		(fp_line
			(start -1.249934 19.400012)
			(end 15.649956 19.400012)
			(stroke
				(width 0.1524)
				(type default)
			)
			(layer "F.SilkS")
		)
		(fp_line
			(start 0.0254 -0.9144)
			(end 1.0414 -0.9144)
			(stroke
				(width 0.1524)
				(type default)
			)
			(layer "F.SilkS")
		)
		(fp_line
			(start 0.5334 -1.4224)
			(end 0.0254 -0.9144)
			(stroke
				(width 0.1524)
				(type default)
			)
			(layer "F.SilkS")
		)
		(fp_line
			(start 0.5334 -1.4224)
			(end 0.5334 -0.5588)
			(stroke
				(width 0.1524)
				(type default)
			)
			(layer "F.SilkS")
		)
		(fp_line
			(start 0.5334 -0.5588)
			(end 1.8034 -0.5588)
			(stroke
				(width 0.1524)
				(type default)
			)
			(layer "F.SilkS")
		)
		(fp_line
			(start 1.0414 -0.9144)
			(end 0.5334 -1.4224)
			(stroke
				(width 0.1524)
				(type default)
			)
			(layer "F.SilkS")
		)
		(fp_line
			(start 1.8034 -0.5588)
			(end 2.032 -0.7874)
			(stroke
				(width 0.1524)
				(type default)
			)
			(layer "F.SilkS")
		)
		(fp_line
			(start 15.649956 -8.999982)
			(end -1.249934 -8.999982)
			(stroke
				(width 0.1524)
				(type default)
			)
			(layer "F.SilkS")
		)
		(fp_line
			(start 15.649956 19.400012)
			(end 15.649956 -8.999982)
			(stroke
				(width 0.1524)
				(type default)
			)
			(layer "F.SilkS")
		)
		(fp_line
			(start 18.64995 -11.999976)
			(end 18.64995 22.400006)
			(stroke
				(width 0.1524)
				(type default)
			)
			(layer "F.SilkS")
		)
		(fp_line
			(start 18.64995 22.400006)
			(end -4.249928 22.400006)
			(stroke
				(width 0.1524)
				(type default)
			)
			(layer "F.SilkS")
		)
		(fp_poly
			(pts
				(xy -2.202688 -0.33782) (xy -1.186688 0.17018) (xy -2.202688 0.67818)
			)
			(stroke
				(width 0)
				(type default)
			)
			(fill yes)
			(layer "F.SilkS")
		)
		(fp_line
			(start -4.249928 -11.999976)
			(end 18.64995 -11.999976)
			(stroke
				(width 0.1524)
				(type default)
			)
			(layer "B.SilkS")
		)
		(fp_line
			(start -4.249928 22.400006)
			(end -4.249928 -11.999976)
			(stroke
				(width 0.1524)
				(type default)
			)
			(layer "B.SilkS")
		)
		(fp_line
			(start 18.64995 -11.999976)
			(end 18.64995 22.400006)
			(stroke
				(width 0.1524)
				(type default)
			)
			(layer "B.SilkS")
		)
		(fp_line
			(start 18.64995 22.400006)
			(end -4.249928 22.400006)
			(stroke
				(width 0.1524)
				(type default)
			)
			(layer "B.SilkS")
		)
		(fp_line
			(start -4.249928 -11.999976)
			(end 18.64995 -11.999976)
			(stroke
				(width 0.1)
				(type default)
			)
			(layer "B.Fab")
		)
		(fp_line
			(start -4.249928 22.400006)
			(end -4.249928 -11.999976)
			(stroke
				(width 0.1)
				(type default)
			)
			(layer "B.Fab")
		)
		(fp_line
			(start 18.64995 -11.999976)
			(end 18.64995 22.400006)
			(stroke
				(width 0.1)
				(type default)
			)
			(layer "B.Fab")
		)
		(fp_line
			(start 18.64995 22.400006)
			(end -4.249928 22.400006)
			(stroke
				(width 0.1)
				(type default)
			)
			(layer "B.Fab")
		)
		(fp_line
			(start -1.249934 -8.999982)
			(end -1.249934 19.400012)
			(stroke
				(width 0.1)
				(type default)
			)
			(layer "F.Fab")
		)
		(fp_line
			(start -1.249934 19.400012)
			(end 15.649956 19.400012)
			(stroke
				(width 0.1)
				(type default)
			)
			(layer "F.Fab")
		)
		(fp_line
			(start 15.649956 -8.999982)
			(end -1.249934 -8.999982)
			(stroke
				(width 0.1)
				(type default)
			)
			(layer "F.Fab")
		)
		(fp_line
			(start 15.649956 19.400012)
			(end 15.649956 -8.999982)
			(stroke
				(width 0.1)
				(type default)
			)
			(layer "F.Fab")
		)
		(fp_poly
			(pts
				(xy -2.670048 -0.508) (xy -2.670048 0.508) (xy -1.654048 0)
			)
			(stroke
				(width 0)
				(type default)
			)
			(fill yes)
			(layer "F.Fab")
		)
		(fp_text user "I"
			(at -1.868932 9.90346 0)
			(unlocked yes)
			(layer "F.SilkS")
			(effects
				(font
					(size 0.7874 0.5842)
					(thickness 0.1524)
				)
			)
		)
		(fp_text user "J"
			(at -1.868932 11.10361 0)
			(unlocked yes)
			(layer "F.SilkS")
			(effects
				(font
					(size 0.7874 0.5842)
					(thickness 0.1524)
				)
			)
		)
		(fp_text user "K"
			(at -1.868932 12.303506 0)
			(unlocked yes)
			(layer "F.SilkS")
			(effects
				(font
					(size 0.7874 0.5842)
					(thickness 0.1524)
				)
			)
		)
		(fp_text user "L"
			(at -1.868932 13.503656 0)
			(unlocked yes)
			(layer "F.SilkS")
			(effects
				(font
					(size 0.7874 0.5842)
					(thickness 0.1524)
				)
			)
		)
		(fp_text user "M"
			(at -1.868932 14.703552 0)
			(unlocked yes)
			(layer "F.SilkS")
			(effects
				(font
					(size 0.7874 0.5842)
					(thickness 0.1524)
				)
			)
		)
		(fp_text user "N"
			(at -1.868932 15.903448 0)
			(unlocked yes)
			(layer "F.SilkS")
			(effects
				(font
					(size 0.7874 0.5842)
					(thickness 0.1524)
				)
			)
		)
		(fp_text user "C"
			(at -1.84531 2.59461 0)
			(unlocked yes)
			(layer "F.SilkS")
			(effects
				(font
					(size 0.7874 0.5842)
					(thickness 0.1524)
				)
			)
		)
		(fp_text user "D"
			(at -1.825752 3.799332 0)
			(unlocked yes)
			(layer "F.SilkS")
			(effects
				(font
					(size 0.7874 0.5842)
					(thickness 0.1524)
				)
			)
		)
		(fp_text user "E"
			(at -1.825752 4.999482 0)
			(unlocked yes)
			(layer "F.SilkS")
			(effects
				(font
					(size 0.7874 0.5842)
					(thickness 0.1524)
				)
			)
		)
		(fp_text user "F"
			(at -1.825752 6.199378 0)
			(unlocked yes)
			(layer "F.SilkS")
			(effects
				(font
					(size 0.7874 0.5842)
					(thickness 0.1524)
				)
			)
		)
		(fp_text user "G"
			(at -1.825752 7.399274 0)
			(unlocked yes)
			(layer "F.SilkS")
			(effects
				(font
					(size 0.7874 0.5842)
					(thickness 0.1524)
				)
			)
		)
		(fp_text user "H"
			(at -1.825752 8.599424 0)
			(unlocked yes)
			(layer "F.SilkS")
			(effects
				(font
					(size 0.7874 0.5842)
					(thickness 0.1524)
				)
			)
		)
		(fp_text user "B"
			(at -1.82499 1.35001 0)
			(unlocked yes)
			(layer "F.SilkS")
			(effects
				(font
					(size 0.7874 0.5842)
					(thickness 0.1524)
				)
			)
		)
		(fp_text user "1"
			(at -0.052578 20.15109 0)
			(unlocked yes)
			(layer "F.SilkS")
			(effects
				(font
					(size 0.7874 0.5842)
					(thickness 0.1524)
				)
			)
		)
		(fp_text user "2"
			(at 1.947418 20.15109 0)
			(unlocked yes)
			(layer "F.SilkS")
			(effects
				(font
					(size 0.7874 0.5842)
					(thickness 0.1524)
				)
			)
		)
		(fp_text user "EDGE OF DAUGHTER CARD"
			(at 2.2479 -0.899668 0)
			(unlocked yes)
			(layer "F.SilkS")
			(effects
				(font
					(size 0.635 0.4064)
					(thickness 0.1524)
				)
				(justify left)
			)
		)
		(fp_text user "3"
			(at 3.947414 20.15109 0)
			(unlocked yes)
			(layer "F.SilkS")
			(effects
				(font
					(size 0.7874 0.5842)
					(thickness 0.1524)
				)
			)
		)
		(fp_text user "4"
			(at 5.94741 20.15109 0)
			(unlocked yes)
			(layer "F.SilkS")
			(effects
				(font
					(size 0.7874 0.5842)
					(thickness 0.1524)
				)
			)
		)
		(fp_text user "5"
			(at 7.947406 20.15109 0)
			(unlocked yes)
			(layer "F.SilkS")
			(effects
				(font
					(size 0.7874 0.5842)
					(thickness 0.1524)
				)
			)
		)
		(fp_text user "6"
			(at 9.947402 20.15109 0)
			(unlocked yes)
			(layer "F.SilkS")
			(effects
				(font
					(size 0.7874 0.5842)
					(thickness 0.1524)
				)
			)
		)
		(fp_text user "7"
			(at 11.947398 20.15109 0)
			(unlocked yes)
			(layer "F.SilkS")
			(effects
				(font
					(size 0.7874 0.5842)
					(thickness 0.1524)
				)
			)
		)
		(fp_text user "8"
			(at 13.947394 20.15109 0)
			(unlocked yes)
			(layer "F.SilkS")
			(effects
				(font
					(size 0.7874 0.5842)
					(thickness 0.1524)
				)
			)
		)
		(fp_text user "PRESS-FIT"
			(at 17.240758 16.521684 90)
			(unlocked yes)
			(layer "F.SilkS")
			(effects
				(font
					(size 1.905 1.4224)
					(thickness 0.1524)
				)
				(justify left)
			)
		)
		(fp_text user "A"
			(at -1.342644 0.29591 0)
			(unlocked yes)
			(layer "B.SilkS")
			(effects
				(font
					(size 0.7874 0.5842)
					(thickness 0.1524)
				)
				(justify mirror)
			)
		)
		(fp_text user "G"
			(at -1.317244 7.71271 0)
			(unlocked yes)
			(layer "B.SilkS")
			(effects
				(font
					(size 0.7874 0.5842)
					(thickness 0.1524)
				)
				(justify mirror)
			)
		)
		(fp_text user "H"
			(at -1.291844 8.93191 0)
			(unlocked yes)
			(layer "B.SilkS")
			(effects
				(font
					(size 0.7874 0.5842)
					(thickness 0.1524)
				)
				(justify mirror)
			)
		)
		(fp_text user "B"
			(at -1.29032 1.622806 0)
			(unlocked yes)
			(layer "B.SilkS")
			(effects
				(font
					(size 0.7874 0.5842)
					(thickness 0.1524)
				)
				(justify mirror)
			)
		)
		(fp_text user "C"
			(at -1.29032 2.822956 0)
			(unlocked yes)
			(layer "B.SilkS")
			(effects
				(font
					(size 0.7874 0.5842)
					(thickness 0.1524)
				)
				(justify mirror)
			)
		)
		(fp_text user "D"
			(at -1.29032 4.022852 0)
			(unlocked yes)
			(layer "B.SilkS")
			(effects
				(font
					(size 0.7874 0.5842)
					(thickness 0.1524)
				)
				(justify mirror)
			)
		)
		(fp_text user "E"
			(at -1.29032 5.223002 0)
			(unlocked yes)
			(layer "B.SilkS")
			(effects
				(font
					(size 0.7874 0.5842)
					(thickness 0.1524)
				)
				(justify mirror)
			)
		)
		(fp_text user "F"
			(at -1.29032 6.422898 0)
			(unlocked yes)
			(layer "B.SilkS")
			(effects
				(font
					(size 0.7874 0.5842)
					(thickness 0.1524)
				)
				(justify mirror)
			)
		)
		(fp_text user "I"
			(at -1.29032 10.02284 0)
			(unlocked yes)
			(layer "B.SilkS")
			(effects
				(font
					(size 0.7874 0.5842)
					(thickness 0.1524)
				)
				(justify mirror)
			)
		)
		(fp_text user "J"
			(at -1.29032 11.22299 0)
			(unlocked yes)
			(layer "B.SilkS")
			(effects
				(font
					(size 0.7874 0.5842)
					(thickness 0.1524)
				)
				(justify mirror)
			)
		)
		(fp_text user "K"
			(at -1.29032 12.422886 0)
			(unlocked yes)
			(layer "B.SilkS")
			(effects
				(font
					(size 0.7874 0.5842)
					(thickness 0.1524)
				)
				(justify mirror)
			)
		)
		(fp_text user "L"
			(at -1.29032 13.623036 0)
			(unlocked yes)
			(layer "B.SilkS")
			(effects
				(font
					(size 0.7874 0.5842)
					(thickness 0.1524)
				)
				(justify mirror)
			)
		)
		(fp_text user "M"
			(at -1.29032 14.822932 0)
			(unlocked yes)
			(layer "B.SilkS")
			(effects
				(font
					(size 0.7874 0.5842)
					(thickness 0.1524)
				)
				(justify mirror)
			)
		)
		(fp_text user "N"
			(at -1.29032 16.022828 0)
			(unlocked yes)
			(layer "B.SilkS")
			(effects
				(font
					(size 0.7874 0.5842)
					(thickness 0.1524)
				)
				(justify mirror)
			)
		)
		(fp_text user "1"
			(at 0.071882 17.02181 0)
			(unlocked yes)
			(layer "B.SilkS")
			(effects
				(font
					(size 0.7874 0.5842)
					(thickness 0.1524)
				)
				(justify mirror)
			)
		)
		(fp_text user "2"
			(at 2.071878 17.02181 0)
			(unlocked yes)
			(layer "B.SilkS")
			(effects
				(font
					(size 0.7874 0.5842)
					(thickness 0.1524)
				)
				(justify mirror)
			)
		)
		(fp_text user "3"
			(at 4.071874 17.02181 0)
			(unlocked yes)
			(layer "B.SilkS")
			(effects
				(font
					(size 0.7874 0.5842)
					(thickness 0.1524)
				)
				(justify mirror)
			)
		)
		(fp_text user "4"
			(at 6.07187 17.02181 0)
			(unlocked yes)
			(layer "B.SilkS")
			(effects
				(font
					(size 0.7874 0.5842)
					(thickness 0.1524)
				)
				(justify mirror)
			)
		)
		(fp_text user "5"
			(at 8.071866 17.02181 0)
			(unlocked yes)
			(layer "B.SilkS")
			(effects
				(font
					(size 0.7874 0.5842)
					(thickness 0.1524)
				)
				(justify mirror)
			)
		)
		(fp_text user "6"
			(at 10.071862 17.02181 0)
			(unlocked yes)
			(layer "B.SilkS")
			(effects
				(font
					(size 0.7874 0.5842)
					(thickness 0.1524)
				)
				(justify mirror)
			)
		)
		(fp_text user "7"
			(at 12.071858 17.02181 0)
			(unlocked yes)
			(layer "B.SilkS")
			(effects
				(font
					(size 0.7874 0.5842)
					(thickness 0.1524)
				)
				(justify mirror)
			)
		)
		(fp_text user "8"
			(at 14.071854 17.02181 0)
			(unlocked yes)
			(layer "B.SilkS")
			(effects
				(font
					(size 0.7874 0.5842)
					(thickness 0.1524)
				)
				(justify mirror)
			)
		)
		(fp_text user "PRESS-FIT"
			(at 18.61439 20.14093 0)
			(unlocked yes)
			(layer "B.SilkS")
			(effects
				(font
					(size 1.905 1.4224)
					(thickness 0.1524)
				)
				(justify left mirror)
			)
		)
		(fp_text user "A"
			(at -1.199134 0 90)
			(unlocked yes)
			(layer "B.Fab")
			(effects
				(font
					(size 0.7874 0.5842)
					(thickness 0.1524)
				)
				(justify mirror)
			)
		)
		(fp_text user "G"
			(at -1.173734 7.4168 90)
			(unlocked yes)
			(layer "B.Fab")
			(effects
				(font
					(size 0.7874 0.5842)
					(thickness 0.1524)
				)
				(justify mirror)
			)
		)
		(fp_text user "H"
			(at -1.148334 8.636 90)
			(unlocked yes)
			(layer "B.Fab")
			(effects
				(font
					(size 0.7874 0.5842)
					(thickness 0.1524)
				)
				(justify mirror)
			)
		)
		(fp_text user "B"
			(at -1.14681 1.326896 90)
			(unlocked yes)
			(layer "B.Fab")
			(effects
				(font
					(size 0.7874 0.5842)
					(thickness 0.1524)
				)
				(justify mirror)
			)
		)
		(fp_text user "C"
			(at -1.14681 2.527046 90)
			(unlocked yes)
			(layer "B.Fab")
			(effects
				(font
					(size 0.7874 0.5842)
					(thickness 0.1524)
				)
				(justify mirror)
			)
		)
		(fp_text user "D"
			(at -1.14681 3.726942 90)
			(unlocked yes)
			(layer "B.Fab")
			(effects
				(font
					(size 0.7874 0.5842)
					(thickness 0.1524)
				)
				(justify mirror)
			)
		)
		(fp_text user "E"
			(at -1.14681 4.927092 90)
			(unlocked yes)
			(layer "B.Fab")
			(effects
				(font
					(size 0.7874 0.5842)
					(thickness 0.1524)
				)
				(justify mirror)
			)
		)
		(fp_text user "F"
			(at -1.14681 6.126988 90)
			(unlocked yes)
			(layer "B.Fab")
			(effects
				(font
					(size 0.7874 0.5842)
					(thickness 0.1524)
				)
				(justify mirror)
			)
		)
		(fp_text user "I"
			(at -1.14681 9.72693 90)
			(unlocked yes)
			(layer "B.Fab")
			(effects
				(font
					(size 0.7874 0.5842)
					(thickness 0.1524)
				)
				(justify mirror)
			)
		)
		(fp_text user "J"
			(at -1.14681 10.92708 90)
			(unlocked yes)
			(layer "B.Fab")
			(effects
				(font
					(size 0.7874 0.5842)
					(thickness 0.1524)
				)
				(justify mirror)
			)
		)
		(fp_text user "K"
			(at -1.14681 12.126976 90)
			(unlocked yes)
			(layer "B.Fab")
			(effects
				(font
					(size 0.7874 0.5842)
					(thickness 0.1524)
				)
				(justify mirror)
			)
		)
		(fp_text user "L"
			(at -1.14681 13.327126 90)
			(unlocked yes)
			(layer "B.Fab")
			(effects
				(font
					(size 0.7874 0.5842)
					(thickness 0.1524)
				)
				(justify mirror)
			)
		)
		(fp_text user "M"
			(at -1.14681 14.527022 90)
			(unlocked yes)
			(layer "B.Fab")
			(effects
				(font
					(size 0.7874 0.5842)
					(thickness 0.1524)
				)
				(justify mirror)
			)
		)
		(fp_text user "N"
			(at -1.14681 15.726918 90)
			(unlocked yes)
			(layer "B.Fab")
			(effects
				(font
					(size 0.7874 0.5842)
					(thickness 0.1524)
				)
				(justify mirror)
			)
		)
		(fp_text user "1"
			(at 0.060452 16.764 90)
			(unlocked yes)
			(layer "B.Fab")
			(effects
				(font
					(size 0.7874 0.5842)
					(thickness 0.1524)
				)
				(justify mirror)
			)
		)
		(fp_text user "2"
			(at 2.060448 16.764 90)
			(unlocked yes)
			(layer "B.Fab")
			(effects
				(font
					(size 0.7874 0.5842)
					(thickness 0.1524)
				)
				(justify mirror)
			)
		)
		(fp_text user "3"
			(at 4.060444 16.764 90)
			(unlocked yes)
			(layer "B.Fab")
			(effects
				(font
					(size 0.7874 0.5842)
					(thickness 0.1524)
				)
				(justify mirror)
			)
		)
		(fp_text user "4"
			(at 6.06044 16.764 90)
			(unlocked yes)
			(layer "B.Fab")
			(effects
				(font
					(size 0.7874 0.5842)
					(thickness 0.1524)
				)
				(justify mirror)
			)
		)
		(fp_text user "5"
			(at 8.060436 16.764 90)
			(unlocked yes)
			(layer "B.Fab")
			(effects
				(font
					(size 0.7874 0.5842)
					(thickness 0.1524)
				)
				(justify mirror)
			)
		)
		(fp_text user "6"
			(at 10.060432 16.764 90)
			(unlocked yes)
			(layer "B.Fab")
			(effects
				(font
					(size 0.7874 0.5842)
					(thickness 0.1524)
				)
				(justify mirror)
			)
		)
		(fp_text user "7"
			(at 12.060428 16.764 90)
			(unlocked yes)
			(layer "B.Fab")
			(effects
				(font
					(size 0.7874 0.5842)
					(thickness 0.1524)
				)
				(justify mirror)
			)
		)
		(fp_text user "8"
			(at 14.060424 16.764 90)
			(unlocked yes)
			(layer "B.Fab")
			(effects
				(font
					(size 0.7874 0.5842)
					(thickness 0.1524)
				)
				(justify mirror)
			)
		)
		(fp_text user "PRESS-FIT"
			(at 17.23771 -0.0762 90)
			(unlocked yes)
			(layer "B.Fab")
			(effects
				(font
					(size 1.905 1.4224)
					(thickness 0.1524)
				)
				(justify left mirror)
			)
		)
		(fp_text user "B"
			(at -2.253742 1.199896 90)
			(unlocked yes)
			(layer "F.Fab")
			(effects
				(font
					(size 0.7874 0.5842)
					(thickness 0.1524)
				)
			)
		)
		(fp_text user "C"
			(at -2.253742 2.400046 90)
			(unlocked yes)
			(layer "F.Fab")
			(effects
				(font
					(size 0.7874 0.5842)
					(thickness 0.1524)
				)
			)
		)
		(fp_text user "D"
			(at -2.253742 3.599942 90)
			(unlocked yes)
			(layer "F.Fab")
			(effects
				(font
					(size 0.7874 0.5842)
					(thickness 0.1524)
				)
			)
		)
		(fp_text user "E"
			(at -2.253742 4.800092 90)
			(unlocked yes)
			(layer "F.Fab")
			(effects
				(font
					(size 0.7874 0.5842)
					(thickness 0.1524)
				)
			)
		)
		(fp_text user "F"
			(at -2.253742 5.999988 90)
			(unlocked yes)
			(layer "F.Fab")
			(effects
				(font
					(size 0.7874 0.5842)
					(thickness 0.1524)
				)
			)
		)
		(fp_text user "G"
			(at -2.253742 7.199884 90)
			(unlocked yes)
			(layer "F.Fab")
			(effects
				(font
					(size 0.7874 0.5842)
					(thickness 0.1524)
				)
			)
		)
		(fp_text user "H"
			(at -2.253742 8.400034 90)
			(unlocked yes)
			(layer "F.Fab")
			(effects
				(font
					(size 0.7874 0.5842)
					(thickness 0.1524)
				)
			)
		)
		(fp_text user "I"
			(at -2.253742 9.59993 90)
			(unlocked yes)
			(layer "F.Fab")
			(effects
				(font
					(size 0.7874 0.5842)
					(thickness 0.1524)
				)
			)
		)
		(fp_text user "J"
			(at -2.253742 10.80008 90)
			(unlocked yes)
			(layer "F.Fab")
			(effects
				(font
					(size 0.7874 0.5842)
					(thickness 0.1524)
				)
			)
		)
		(fp_text user "K"
			(at -2.253742 11.999976 90)
			(unlocked yes)
			(layer "F.Fab")
			(effects
				(font
					(size 0.7874 0.5842)
					(thickness 0.1524)
				)
			)
		)
		(fp_text user "L"
			(at -2.253742 13.200126 90)
			(unlocked yes)
			(layer "F.Fab")
			(effects
				(font
					(size 0.7874 0.5842)
					(thickness 0.1524)
				)
			)
		)
		(fp_text user "M"
			(at -2.253742 14.400022 90)
			(unlocked yes)
			(layer "F.Fab")
			(effects
				(font
					(size 0.7874 0.5842)
					(thickness 0.1524)
				)
			)
		)
		(fp_text user "N"
			(at -2.253742 15.599918 90)
			(unlocked yes)
			(layer "F.Fab")
			(effects
				(font
					(size 0.7874 0.5842)
					(thickness 0.1524)
				)
			)
		)
		(fp_text user "1"
			(at 0.111252 19.8628 90)
			(unlocked yes)
			(layer "F.Fab")
			(effects
				(font
					(size 0.7874 0.5842)
					(thickness 0.1524)
				)
			)
		)
		(fp_text user "2"
			(at 2.111248 19.8628 90)
			(unlocked yes)
			(layer "F.Fab")
			(effects
				(font
					(size 0.7874 0.5842)
					(thickness 0.1524)
				)
			)
		)
		(fp_text user "3"
			(at 4.111244 19.8628 90)
			(unlocked yes)
			(layer "F.Fab")
			(effects
				(font
					(size 0.7874 0.5842)
					(thickness 0.1524)
				)
			)
		)
		(fp_text user "4"
			(at 6.11124 19.8628 90)
			(unlocked yes)
			(layer "F.Fab")
			(effects
				(font
					(size 0.7874 0.5842)
					(thickness 0.1524)
				)
			)
		)
		(fp_text user "5"
			(at 8.111236 19.8628 90)
			(unlocked yes)
			(layer "F.Fab")
			(effects
				(font
					(size 0.7874 0.5842)
					(thickness 0.1524)
				)
			)
		)
		(fp_text user "6"
			(at 10.111232 19.8628 90)
			(unlocked yes)
			(layer "F.Fab")
			(effects
				(font
					(size 0.7874 0.5842)
					(thickness 0.1524)
				)
			)
		)
		(fp_text user "7"
			(at 12.111228 19.8628 90)
			(unlocked yes)
			(layer "F.Fab")
			(effects
				(font
					(size 0.7874 0.5842)
					(thickness 0.1524)
				)
			)
		)
		(fp_text user "8"
			(at 14.111224 19.8628 90)
			(unlocked yes)
			(layer "F.Fab")
			(effects
				(font
					(size 0.7874 0.5842)
					(thickness 0.1524)
				)
			)
		)
		(fp_text user "PRESS-FIT"
			(at 17.240758 16.521684 90)
			(unlocked yes)
			(layer "F.Fab")
			(effects
				(font
					(size 1.905 1.4224)
					(thickness 0.1524)
				)
				(justify left)
			)
		)
		(pad "A1" thru_hole rect
			(at 0 0 180)
			(size 0.766318 0.766318)
			(drill 0.359918)
			(layers "*.Cu" "*.Mask")
			(remove_unused_layers no)
			(net "GPU_PEX_STRAP1")
			(clearance 0.0508)
			(thermal_gap 0.0508)
			(padstack
				(mode front_inner_back)
				(layer "Inner"
					(shape circle)
					(size 0.766318 0.766318)
					(clearance 0.0508)
				)
				(layer "B.Cu"
					(shape rect)
					(size 0.766318 0.766318)
					(clearance 0.0508)
				)
			)
		)
		(pad "A2" thru_hole circle
			(at 1.999996 0.199898 180)
			(size 0.906272 0.906272)
			(drill 0.499872)
			(layers "*.Cu" "*.Mask")
			(remove_unused_layers no)
			(net "GND")
			(clearance 0.0508)
			(thermal_gap 0.0508)
		)
		(pad "A3" thru_hole circle
			(at 3.999992 0 180)
			(size 0.766318 0.766318)
			(drill 0.359918)
			(layers "*.Cu" "*.Mask")
			(remove_unused_layers no)
			(net "GPU_BASE_ID0")
			(clearance 0.0508)
			(thermal_gap 0.0508)
		)
		(pad "A4" thru_hole circle
			(at 5.999988 0.199898 180)
			(size 0.906272 0.906272)
			(drill 0.499872)
			(layers "*.Cu" "*.Mask")
			(remove_unused_layers no)
			(net "GND")
			(clearance 0.0508)
			(thermal_gap 0.0508)
		)
		(pad "A5" thru_hole circle
			(at 7.999984 0 180)
			(size 0.766318 0.766318)
			(drill 0.359918)
			(layers "*.Cu" "*.Mask")
			(remove_unused_layers no)
			(net "GPU_PEX_STRAP0")
			(clearance 0.0508)
			(thermal_gap 0.0508)
		)
		(pad "A6" thru_hole circle
			(at 9.99998 0.199898 180)
			(size 0.906272 0.906272)
			(drill 0.499872)
			(layers "*.Cu" "*.Mask")
			(remove_unused_layers no)
			(net "GND")
			(clearance 0.0508)
			(thermal_gap 0.0508)
		)
		(pad "A7" thru_hole circle
			(at 11.999976 0 180)
			(size 0.766318 0.766318)
			(drill 0.359918)
			(layers "*.Cu" "*.Mask")
			(remove_unused_layers no)
			(net "GPU_FPGA_RST_R_BUF_N")
			(clearance 0.0508)
			(thermal_gap 0.0508)
		)
		(pad "A8" thru_hole circle
			(at 13.999972 0.199898 180)
			(size 0.906272 0.906272)
			(drill 0.499872)
			(layers "*.Cu" "*.Mask")
			(remove_unused_layers no)
			(net "GND")
			(clearance 0.0508)
			(thermal_gap 0.0508)
		)
		(pad "B1" thru_hole circle
			(at 0 1.199896 180)
			(size 0.906272 0.906272)
			(drill 0.499872)
			(layers "*.Cu" "*.Mask")
			(remove_unused_layers no)
			(net "GND")
			(clearance 0.0508)
			(thermal_gap 0.0508)
		)
		(pad "B3" thru_hole circle
			(at 3.999992 1.199896 180)
			(size 0.906272 0.906272)
			(drill 0.499872)
			(layers "*.Cu" "*.Mask")
			(remove_unused_layers no)
			(net "GND")
			(clearance 0.0508)
			(thermal_gap 0.0508)
		)
		(pad "B5" thru_hole circle
			(at 7.999984 1.199896 180)
			(size 0.906272 0.906272)
			(drill 0.499872)
			(layers "*.Cu" "*.Mask")
			(remove_unused_layers no)
			(net "GND")
			(clearance 0.0508)
			(thermal_gap 0.0508)
		)
		(pad "B7" thru_hole circle
			(at 11.999976 1.199896 180)
			(size 0.906272 0.906272)
			(drill 0.499872)
			(layers "*.Cu" "*.Mask")
			(remove_unused_layers no)
			(net "GND")
			(clearance 0.0508)
			(thermal_gap 0.0508)
		)
		(pad "D2" thru_hole circle
			(at 1.999996 3.800094 180)
			(size 0.906272 0.906272)
			(drill 0.499872)
			(layers "*.Cu" "*.Mask")
			(remove_unused_layers no)
			(net "GND")
			(clearance 0.0508)
			(thermal_gap 0.0508)
		)
		(pad "D4" thru_hole circle
			(at 5.999988 3.800094 180)
			(size 0.906272 0.906272)
			(drill 0.499872)
			(layers "*.Cu" "*.Mask")
			(remove_unused_layers no)
			(net "GND")
			(clearance 0.0508)
			(thermal_gap 0.0508)
		)
		(pad "D6" thru_hole circle
			(at 9.99998 3.800094 180)
			(size 0.906272 0.906272)
			(drill 0.499872)
			(layers "*.Cu" "*.Mask")
			(remove_unused_layers no)
			(net "GND")
			(clearance 0.0508)
			(thermal_gap 0.0508)
		)
		(pad "D8" thru_hole circle
			(at 13.999972 3.800094 180)
			(size 0.906272 0.906272)
			(drill 0.499872)
			(layers "*.Cu" "*.Mask")
			(remove_unused_layers no)
			(net "GND")
			(clearance 0.0508)
			(thermal_gap 0.0508)
		)
		(pad "E1" thru_hole circle
			(at 0 4.800092 180)
			(size 0.906272 0.906272)
			(drill 0.499872)
			(layers "*.Cu" "*.Mask")
			(remove_unused_layers no)
			(net "GND")
			(clearance 0.0508)
			(thermal_gap 0.0508)
		)
		(pad "E3" thru_hole circle
			(at 3.999992 4.800092 180)
			(size 0.906272 0.906272)
			(drill 0.499872)
			(layers "*.Cu" "*.Mask")
			(remove_unused_layers no)
			(net "GND")
			(clearance 0.0508)
			(thermal_gap 0.0508)
		)
		(pad "E5" thru_hole circle
			(at 7.999984 4.800092 180)
			(size 0.906272 0.906272)
			(drill 0.499872)
			(layers "*.Cu" "*.Mask")
			(remove_unused_layers no)
			(net "GND")
			(clearance 0.0508)
			(thermal_gap 0.0508)
		)
		(pad "E7" thru_hole circle
			(at 11.999976 4.800092 180)
			(size 0.906272 0.906272)
			(drill 0.499872)
			(layers "*.Cu" "*.Mask")
			(remove_unused_layers no)
			(net "GND")
			(clearance 0.0508)
			(thermal_gap 0.0508)
		)
		(pad "G2" thru_hole circle
			(at 1.999996 7.400036 180)
			(size 0.906272 0.906272)
			(drill 0.499872)
			(layers "*.Cu" "*.Mask")
			(remove_unused_layers no)
			(net "GND")
			(clearance 0.0508)
			(thermal_gap 0.0508)
		)
		(pad "G4" thru_hole circle
			(at 5.999988 7.400036 180)
			(size 0.906272 0.906272)
			(drill 0.499872)
			(layers "*.Cu" "*.Mask")
			(remove_unused_layers no)
			(net "GND")
			(clearance 0.0508)
			(thermal_gap 0.0508)
		)
		(pad "G6" thru_hole circle
			(at 9.99998 7.400036 180)
			(size 0.906272 0.906272)
			(drill 0.499872)
			(layers "*.Cu" "*.Mask")
			(remove_unused_layers no)
			(net "GND")
			(clearance 0.0508)
			(thermal_gap 0.0508)
		)
		(pad "G8" thru_hole circle
			(at 13.999972 7.400036 180)
			(size 0.906272 0.906272)
			(drill 0.499872)
			(layers "*.Cu" "*.Mask")
			(remove_unused_layers no)
			(net "GND")
			(clearance 0.0508)
			(thermal_gap 0.0508)
		)
		(pad "H1" thru_hole circle
			(at 0 8.400034 180)
			(size 0.906272 0.906272)
			(drill 0.499872)
			(layers "*.Cu" "*.Mask")
			(remove_unused_layers no)
			(net "GND")
			(clearance 0.0508)
			(thermal_gap 0.0508)
		)
		(pad "H3" thru_hole circle
			(at 3.999992 8.400034 180)
			(size 0.906272 0.906272)
			(drill 0.499872)
			(layers "*.Cu" "*.Mask")
			(remove_unused_layers no)
			(net "GND")
			(clearance 0.0508)
			(thermal_gap 0.0508)
		)
		(pad "H5" thru_hole circle
			(at 7.999984 8.400034 180)
			(size 0.906272 0.906272)
			(drill 0.499872)
			(layers "*.Cu" "*.Mask")
			(remove_unused_layers no)
			(net "GND")
			(clearance 0.0508)
			(thermal_gap 0.0508)
		)
		(pad "H7" thru_hole circle
			(at 11.999976 8.400034 180)
			(size 0.906272 0.906272)
			(drill 0.499872)
			(layers "*.Cu" "*.Mask")
			(remove_unused_layers no)
			(net "GND")
			(clearance 0.0508)
			(thermal_gap 0.0508)
		)
		(pad "J2" thru_hole circle
			(at 1.999996 10.999978 180)
			(size 0.906272 0.906272)
			(drill 0.499872)
			(layers "*.Cu" "*.Mask")
			(remove_unused_layers no)
			(net "GND")
			(clearance 0.0508)
			(thermal_gap 0.0508)
		)
		(pad "J4" thru_hole circle
			(at 5.999988 10.999978 180)
			(size 0.906272 0.906272)
			(drill 0.499872)
			(layers "*.Cu" "*.Mask")
			(remove_unused_layers no)
			(net "GND")
			(clearance 0.0508)
			(thermal_gap 0.0508)
		)
		(pad "J6" thru_hole circle
			(at 9.99998 10.999978 180)
			(size 0.906272 0.906272)
			(drill 0.499872)
			(layers "*.Cu" "*.Mask")
			(remove_unused_layers no)
			(net "GND")
			(clearance 0.0508)
			(thermal_gap 0.0508)
		)
		(pad "J8" thru_hole circle
			(at 13.999972 10.999978 180)
			(size 0.906272 0.906272)
			(drill 0.499872)
			(layers "*.Cu" "*.Mask")
			(remove_unused_layers no)
			(net "GND")
			(clearance 0.0508)
			(thermal_gap 0.0508)
		)
		(pad "K1" thru_hole circle
			(at 0 11.999976 180)
			(size 0.906272 0.906272)
			(drill 0.499872)
			(layers "*.Cu" "*.Mask")
			(remove_unused_layers no)
			(net "GND")
			(clearance 0.0508)
			(thermal_gap 0.0508)
		)
		(pad "K3" thru_hole circle
			(at 3.999992 11.999976 180)
			(size 0.906272 0.906272)
			(drill 0.499872)
			(layers "*.Cu" "*.Mask")
			(remove_unused_layers no)
			(net "GND")
			(clearance 0.0508)
			(thermal_gap 0.0508)
		)
		(pad "K5" thru_hole circle
			(at 7.999984 11.999976 180)
			(size 0.906272 0.906272)
			(drill 0.499872)
			(layers "*.Cu" "*.Mask")
			(remove_unused_layers no)
			(net "GND")
			(clearance 0.0508)
			(thermal_gap 0.0508)
		)
		(pad "K7" thru_hole circle
			(at 11.999976 11.999976 180)
			(size 0.906272 0.906272)
			(drill 0.499872)
			(layers "*.Cu" "*.Mask")
			(remove_unused_layers no)
			(net "GND")
			(clearance 0.0508)
			(thermal_gap 0.0508)
		)
		(pad "M2" thru_hole circle
			(at 1.999996 14.59992 180)
			(size 0.906272 0.906272)
			(drill 0.499872)
			(layers "*.Cu" "*.Mask")
			(remove_unused_layers no)
			(net "GND")
			(clearance 0.0508)
			(thermal_gap 0.0508)
		)
		(pad "M4" thru_hole circle
			(at 5.999988 14.59992 180)
			(size 0.906272 0.906272)
			(drill 0.499872)
			(layers "*.Cu" "*.Mask")
			(remove_unused_layers no)
			(net "GND")
			(clearance 0.0508)
			(thermal_gap 0.0508)
		)
		(pad "M6" thru_hole circle
			(at 9.99998 14.59992 180)
			(size 0.906272 0.906272)
			(drill 0.499872)
			(layers "*.Cu" "*.Mask")
			(remove_unused_layers no)
			(net "GND")
			(clearance 0.0508)
			(thermal_gap 0.0508)
		)
		(pad "M8" thru_hole circle
			(at 13.999972 14.59992 180)
			(size 0.906272 0.906272)
			(drill 0.499872)
			(layers "*.Cu" "*.Mask")
			(remove_unused_layers no)
			(net "GND")
			(clearance 0.0508)
			(thermal_gap 0.0508)
		)
		(pad "N1" thru_hole circle
			(at 0 15.599918 180)
			(size 0.906272 0.906272)
			(drill 0.499872)
			(layers "*.Cu" "*.Mask")
			(remove_unused_layers no)
			(net "GND")
			(clearance 0.0508)
			(thermal_gap 0.0508)
		)
		(pad "N2" thru_hole circle
			(at 1.999996 15.80007 180)
			(size 0.766318 0.766318)
			(drill 0.359918)
			(layers "*.Cu" "*.Mask")
			(remove_unused_layers no)
			(net "GPU_PRSNT_N")
			(clearance 0.0508)
			(thermal_gap 0.0508)
		)
		(pad "N3" thru_hole circle
			(at 3.999992 15.599918 180)
			(size 0.906272 0.906272)
			(drill 0.499872)
			(layers "*.Cu" "*.Mask")
			(remove_unused_layers no)
			(net "GND")
			(clearance 0.0508)
			(thermal_gap 0.0508)
		)
		(pad "N4" thru_hole circle
			(at 5.999988 15.80007 180)
			(size 0.766318 0.766318)
			(drill 0.359918)
			(layers "*.Cu" "*.Mask")
			(remove_unused_layers no)
			(net "FM_GPU_PWR_EN_R_BUF")
			(clearance 0.0508)
			(thermal_gap 0.0508)
		)
		(pad "N5" thru_hole circle
			(at 7.999984 15.599918 180)
			(size 0.906272 0.906272)
			(drill 0.499872)
			(layers "*.Cu" "*.Mask")
			(remove_unused_layers no)
			(net "GND")
			(clearance 0.0508)
			(thermal_gap 0.0508)
		)
		(pad "N6" thru_hole circle
			(at 9.99998 15.80007 180)
			(size 0.766318 0.766318)
			(drill 0.359918)
			(layers "*.Cu" "*.Mask")
			(remove_unused_layers no)
			(net "FM_GPU_PWRGD")
			(clearance 0.0508)
			(thermal_gap 0.0508)
		)
		(pad "N7" thru_hole circle
			(at 11.999976 15.599918 180)
			(size 0.906272 0.906272)
			(drill 0.499872)
			(layers "*.Cu" "*.Mask")
			(remove_unused_layers no)
			(net "GND")
			(clearance 0.0508)
			(thermal_gap 0.0508)
		)
		(pad "N8" thru_hole circle
			(at 13.999972 15.80007 180)
			(size 0.766318 0.766318)
			(drill 0.359918)
			(layers "*.Cu" "*.Mask")
			(remove_unused_layers no)
			(net "GPU_BASE_ID1")
			(clearance 0.0508)
			(thermal_gap 0.0508)
		)
	)
	(footprint ""
		(layer "F.Cu")
		(at 12.022582 -421.216836 90)
		(property "Reference" "C1713"
			(at 0 0 90)
			(layer "F.SilkS")
			(hide yes)
			(effects
				(font
					(size 1.27 1.27)
				)
			)
		)
		(property "Value" ""
			(at 0 0 90)
			(layer "F.Fab")
			(effects
				(font
					(size 1.27 1.27)
				)
			)
		)
		(duplicate_pad_numbers_are_jumpers no)
		(fp_line
			(start 0.7874 -0.4064)
			(end 0.7874 0.4064)
			(stroke
				(width 0.1524)
				(type default)
			)
			(layer "F.SilkS")
		)
		(fp_line
			(start -0.7874 -0.4064)
			(end 0.7874 -0.4064)
			(stroke
				(width 0.1524)
				(type default)
			)
			(layer "F.SilkS")
		)
		(fp_line
			(start 0.7874 0.4064)
			(end -0.7874 0.4064)
			(stroke
				(width 0.1524)
				(type default)
			)
			(layer "F.SilkS")
		)
		(fp_line
			(start -0.7874 0.4064)
			(end -0.7874 -0.4064)
			(stroke
				(width 0.1524)
				(type default)
			)
			(layer "F.SilkS")
		)
		(fp_line
			(start -0.12065 -0.305054)
			(end -0.12065 -0.2794)
			(stroke
				(width 0.1)
				(type default)
			)
			(layer "F.Fab")
		)
		(fp_line
			(start -0.67945 -0.305054)
			(end -0.12065 -0.305054)
			(stroke
				(width 0.1)
				(type default)
			)
			(layer "F.Fab")
		)
		(fp_line
			(start 0.67945 -0.3048)
			(end 0.67945 0.3048)
			(stroke
				(width 0.1)
				(type default)
			)
			(layer "F.Fab")
		)
		(fp_line
			(start 0.12065 -0.3048)
			(end 0.67945 -0.3048)
			(stroke
				(width 0.1)
				(type default)
			)
			(layer "F.Fab")
		)
		(fp_line
			(start 0.12065 -0.2794)
			(end 0.12065 -0.3048)
			(stroke
				(width 0.1)
				(type default)
			)
			(layer "F.Fab")
		)
		(fp_line
			(start -0.12065 -0.2794)
			(end 0.12065 -0.2794)
			(stroke
				(width 0.1)
				(type default)
			)
			(layer "F.Fab")
		)
		(fp_line
			(start 0.120396 0.2794)
			(end -0.12065 0.2794)
			(stroke
				(width 0.1)
				(type default)
			)
			(layer "F.Fab")
		)
		(fp_line
			(start -0.12065 0.2794)
			(end -0.12065 0.3048)
			(stroke
				(width 0.1)
				(type default)
			)
			(layer "F.Fab")
		)
		(fp_line
			(start 0.67945 0.3048)
			(end 0.120396 0.3048)
			(stroke
				(width 0.1)
				(type default)
			)
			(layer "F.Fab")
		)
		(fp_line
			(start 0.120396 0.3048)
			(end 0.120396 0.2794)
			(stroke
				(width 0.1)
				(type default)
			)
			(layer "F.Fab")
		)
		(fp_line
			(start -0.12065 0.3048)
			(end -0.67945 0.3048)
			(stroke
				(width 0.1)
				(type default)
			)
			(layer "F.Fab")
		)
		(fp_line
			(start -0.67945 0.3048)
			(end -0.67945 -0.305054)
			(stroke
				(width 0.1)
				(type default)
			)
			(layer "F.Fab")
		)
		(pad "1" smd circle
			(at -0.40005 0 90)
			(size 0 0)
			(layers "F.Cu" "F.Mask" "F.Paste")
			(net "P3V3_AUX")
		)
		(pad "2" smd circle
			(at 0.40005 0 90)
			(size 0 0)
			(layers "F.Cu" "F.Mask" "F.Paste")
			(net "GND")
		)
	)
	(footprint ""
		(layer "F.Cu")
		(at 371.672358 -99.185984 90)
		(property "Reference" "U84"
			(at 0.450596 -5.416042 0)
			(unlocked yes)
			(layer "F.SilkS")
			(effects
				(font
					(size 0.7874 0.5842)
					(thickness 0.1524)
				)
				(justify left)
			)
		)
		(property "Value" ""
			(at 0 0 90)
			(layer "F.Fab")
			(effects
				(font
					(size 1.27 1.27)
				)
			)
		)
		(duplicate_pad_numbers_are_jumpers no)
		(fp_line
			(start 2.0066 -2.5527)
			(end 2.0066 2.5527)
			(stroke
				(width 0.1524)
				(type default)
			)
			(layer "F.SilkS")
		)
		(fp_line
			(start 0.5715 -2.5527)
			(end 2.0066 -2.5527)
			(stroke
				(width 0.1524)
				(type default)
			)
			(layer "F.SilkS")
		)
		(fp_line
			(start -0.5715 -2.5527)
			(end 0 -1.9812)
			(stroke
				(width 0.1524)
				(type default)
			)
			(layer "F.SilkS")
		)
		(fp_line
			(start -2.0066 -2.5527)
			(end -0.5715 -2.5527)
			(stroke
				(width 0.1524)
				(type default)
			)
			(layer "F.SilkS")
		)
		(fp_line
			(start 0 -1.9812)
			(end 0.5715 -2.5527)
			(stroke
				(width 0.1524)
				(type default)
			)
			(layer "F.SilkS")
		)
		(fp_line
			(start 2.0066 2.5527)
			(end -2.0066 2.5527)
			(stroke
				(width 0.1524)
				(type default)
			)
			(layer "F.SilkS")
		)
		(fp_line
			(start -2.0066 2.5527)
			(end -2.0066 -2.5527)
			(stroke
				(width 0.1524)
				(type default)
			)
			(layer "F.SilkS")
		)
		(fp_poly
			(pts
				(xy -2.730246 -2.881122) (xy -3.058414 -2.327402) (xy -3.355086 -2.881122)
			)
			(stroke
				(width 0)
				(type default)
			)
			(fill yes)
			(layer "F.SilkS")
		)
		(fp_line
			(start 2.249932 -2.549906)
			(end 2.249932 2.549906)
			(stroke
				(width 0.1)
				(type default)
			)
			(layer "F.Fab")
		)
		(fp_line
			(start -2.249932 -2.549906)
			(end 2.249932 -2.549906)
			(stroke
				(width 0.1)
				(type default)
			)
			(layer "F.Fab")
		)
		(fp_line
			(start 2.249932 2.549906)
			(end -2.249932 2.549906)
			(stroke
				(width 0.1)
				(type default)
			)
			(layer "F.Fab")
		)
		(fp_line
			(start -2.249932 2.549906)
			(end -2.249932 -2.549906)
			(stroke
				(width 0.1)
				(type default)
			)
			(layer "F.Fab")
		)
		(fp_poly
			(pts
				(xy -4.36372 -1.608328) (xy -4.36372 -2.233168) (xy -3.81 -1.905)
			)
			(stroke
				(width 0)
				(type default)
			)
			(fill yes)
			(layer "F.Fab")
		)
		(pad "1" smd rect
			(at -2.921 -1.949958)
			(size 0.3556 1.4986)
			(layers "F.Cu" "F.Mask" "F.Paste")
			(net "PU_GTL2014_BMC_JTAG_DIR_1")
		)
		(pad "2" smd rect
			(at -2.921 -1.299972)
			(size 0.3556 1.4986)
			(layers "F.Cu" "F.Mask" "F.Paste")
			(net "JTAG_DBP_PREQ_R_N")
		)
		(pad "3" smd rect
			(at -2.921 -0.649986)
			(size 0.3556 1.4986)
			(layers "F.Cu" "F.Mask" "F.Paste")
			(net "FM_CPU_FBRK_DEBUG_N")
		)
		(pad "4" smd rect
			(at -2.921 0)
			(size 0.3556 1.4986)
			(layers "F.Cu" "F.Mask" "F.Paste")
			(net "PD_GTL2014_BMC_JTAG_VREF_1")
		)
		(pad "5" smd rect
			(at -2.921 0.649986)
			(size 0.3556 1.4986)
			(layers "F.Cu" "F.Mask" "F.Paste")
			(net "JTAG_DBP_FB_TDI")
		)
		(pad "6" smd rect
			(at -2.921 1.299972)
			(size 0.3556 1.4986)
			(layers "F.Cu" "F.Mask" "F.Paste")
			(net "JTAG_DBP_FB_TMS")
		)
		(pad "7" smd rect
			(at -2.921 1.949958)
			(size 0.3556 1.4986)
			(layers "F.Cu" "F.Mask" "F.Paste")
			(net "GND")
		)
		(pad "8" smd rect
			(at 2.921 1.949958)
			(size 0.3556 1.4986)
			(layers "F.Cu" "F.Mask" "F.Paste")
			(net "GND")
		)
		(pad "9" smd rect
			(at 2.921 1.299972)
			(size 0.3556 1.4986)
			(layers "F.Cu" "F.Mask" "F.Paste")
			(net "JTAG_BMC_DBP_TMS_R")
		)
		(pad "10" smd rect
			(at 2.921 0.649986)
			(size 0.3556 1.4986)
			(layers "F.Cu" "F.Mask" "F.Paste")
			(net "JTAG_BMC_DBP_TDI_R")
		)
		(pad "11" smd rect
			(at 2.921 0)
			(size 0.3556 1.4986)
			(layers "F.Cu" "F.Mask" "F.Paste")
			(net "GND")
		)
		(pad "12" smd rect
			(at 2.921 -0.649986)
			(size 0.3556 1.4986)
			(layers "F.Cu" "F.Mask" "F.Paste")
			(net "FM_BMC_CPU_FBRK_OUT_N")
		)
		(pad "13" smd rect
			(at 2.921 -1.299972)
			(size 0.3556 1.4986)
			(layers "F.Cu" "F.Mask" "F.Paste")
			(net "JTAG_DBP_BMC_PREQ_R1_N")
		)
		(pad "14" smd rect
			(at 2.921 -1.949958)
			(size 0.3556 1.4986)
			(layers "F.Cu" "F.Mask" "F.Paste")
			(net "P3V3_AUX")
		)
	)
	(footprint ""
		(layer "F.Cu")
		(at 466.094318 -39.106094)
		(property "Reference" "Q123"
			(at -1.32334 -2.675128 0)
			(unlocked yes)
			(layer "F.SilkS")
			(effects
				(font
					(size 0.7874 0.5842)
					(thickness 0.1524)
				)
				(justify left)
			)
		)
		(property "Value" ""
			(at 0 0 0)
			(layer "F.Fab")
			(effects
				(font
					(size 1.27 1.27)
				)
			)
		)
		(duplicate_pad_numbers_are_jumpers no)
		(fp_line
			(start -1.332738 -1.100074)
			(end -0.4826 -1.100074)
			(stroke
				(width 0.1524)
				(type default)
			)
			(layer "F.SilkS")
		)
		(fp_line
			(start -1.332738 1.100074)
			(end -1.332738 -1.100074)
			(stroke
				(width 0.1524)
				(type default)
			)
			(layer "F.SilkS")
		)
		(fp_line
			(start -0.4826 -1.100074)
			(end 0 -0.541274)
			(stroke
				(width 0.1524)
				(type default)
			)
			(layer "F.SilkS")
		)
		(fp_line
			(start 0 -0.541274)
			(end 0.4826 -1.100074)
			(stroke
				(width 0.1524)
				(type default)
			)
			(layer "F.SilkS")
		)
		(fp_line
			(start 0.4826 -1.100074)
			(end 1.332738 -1.100074)
			(stroke
				(width 0.1524)
				(type default)
			)
			(layer "F.SilkS")
		)
		(fp_line
			(start 1.332738 -1.100074)
			(end 1.332738 1.100074)
			(stroke
				(width 0.1524)
				(type default)
			)
			(layer "F.SilkS")
		)
		(fp_line
			(start 1.332738 1.100074)
			(end -1.332738 1.100074)
			(stroke
				(width 0.1524)
				(type default)
			)
			(layer "F.SilkS")
		)
		(fp_poly
			(pts
				(xy -0.672338 -2.038096) (xy -1.023366 -1.33604) (xy -1.374394 -2.038096)
			)
			(stroke
				(width 0)
				(type default)
			)
			(fill yes)
			(layer "F.SilkS")
		)
		(fp_line
			(start -0.674878 -1.100074)
			(end 0.674878 -1.100074)
			(stroke
				(width 0.1)
				(type default)
			)
			(layer "F.Fab")
		)
		(fp_line
			(start -0.674878 1.100074)
			(end -0.674878 -1.100074)
			(stroke
				(width 0.1)
				(type default)
			)
			(layer "F.Fab")
		)
		(fp_line
			(start 0.674878 -1.100074)
			(end 0.674878 1.100074)
			(stroke
				(width 0.1)
				(type default)
			)
			(layer "F.Fab")
		)
		(fp_line
			(start 0.674878 1.100074)
			(end -0.674878 1.100074)
			(stroke
				(width 0.1)
				(type default)
			)
			(layer "F.Fab")
		)
		(fp_poly
			(pts
				(xy -2.2352 -0.298958) (xy -2.2352 -1.001014) (xy -1.533144 -0.649986)
			)
			(stroke
				(width 0)
				(type default)
			)
			(fill yes)
			(layer "F.Fab")
		)
		(pad "1" smd rect
			(at -0.94996 -0.649986 90)
			(size 0.4318 0.508)
			(layers "F.Cu" "F.Mask" "F.Paste")
			(net "GND")
		)
		(pad "2" smd rect
			(at -0.94996 0 90)
			(size 0.4318 0.508)
			(layers "F.Cu" "F.Mask" "F.Paste")
			(net "P12V_OCP_EN_1_R")
		)
		(pad "3" smd rect
			(at -0.94996 0.649986 90)
			(size 0.4318 0.508)
			(layers "F.Cu" "F.Mask" "F.Paste")
			(net "P12V_OCP_UV_1_R")
		)
		(pad "4" smd rect
			(at 0.94996 0.649986 90)
			(size 0.4318 0.508)
			(layers "F.Cu" "F.Mask" "F.Paste")
			(net "GND")
		)
		(pad "5" smd rect
			(at 0.94996 0 90)
			(size 0.4318 0.508)
			(layers "F.Cu" "F.Mask" "F.Paste")
			(net "P12V_OCP_1_EN_G")
		)
		(pad "6" smd rect
			(at 0.94996 -0.649986 90)
			(size 0.4318 0.508)
			(layers "F.Cu" "F.Mask" "F.Paste")
			(net "P12V_OCP_1_EN_G")
		)
	)
	(footprint ""
		(layer "F.Cu")
		(at 279.39238 -437.53278)
		(property "Reference" "JP10"
			(at -1.4097 -2.009648 0)
			(unlocked yes)
			(layer "F.SilkS")
			(effects
				(font
					(size 0.7874 0.5842)
					(thickness 0.1524)
				)
				(justify left)
			)
		)
		(property "Value" ""
			(at 0 0 0)
			(layer "F.Fab")
			(effects
				(font
					(size 1.27 1.27)
				)
			)
		)
		(duplicate_pad_numbers_are_jumpers no)
		(fp_line
			(start -1.249934 -1.320038)
			(end 1.249934 -1.320038)
			(stroke
				(width 0.1524)
				(type default)
			)
			(layer "F.SilkS")
		)
		(fp_line
			(start -1.249934 6.400038)
			(end -1.249934 -1.320038)
			(stroke
				(width 0.1524)
				(type default)
			)
			(layer "F.SilkS")
		)
		(fp_line
			(start 1.249934 -1.320038)
			(end 1.249934 6.400038)
			(stroke
				(width 0.1524)
				(type default)
			)
			(layer "F.SilkS")
		)
		(fp_line
			(start 1.249934 6.400038)
			(end -1.249934 6.400038)
			(stroke
				(width 0.1524)
				(type default)
			)
			(layer "F.SilkS")
		)
		(fp_poly
			(pts
				(xy -2.5654 -0.556514) (xy -1.452372 0) (xy -2.5654 0.556514)
			)
			(stroke
				(width 0)
				(type default)
			)
			(fill yes)
			(layer "F.SilkS")
		)
		(fp_line
			(start -1.249934 -1.320038)
			(end 1.249934 -1.320038)
			(stroke
				(width 0.1)
				(type default)
			)
			(layer "F.Fab")
		)
		(fp_line
			(start -1.249934 6.400038)
			(end -1.249934 -1.320038)
			(stroke
				(width 0.1)
				(type default)
			)
			(layer "F.Fab")
		)
		(fp_line
			(start 1.249934 -1.320038)
			(end 1.249934 6.400038)
			(stroke
				(width 0.1)
				(type default)
			)
			(layer "F.Fab")
		)
		(fp_line
			(start 1.249934 6.400038)
			(end -1.249934 6.400038)
			(stroke
				(width 0.1)
				(type default)
			)
			(layer "F.Fab")
		)
		(fp_poly
			(pts
				(xy -2.5654 -0.556514) (xy -1.452372 0) (xy -2.5654 0.556514)
			)
			(stroke
				(width 0)
				(type default)
			)
			(fill yes)
			(layer "F.Fab")
		)
		(fp_text user "3"
			(at -1.778 5.13207 0)
			(unlocked yes)
			(layer "F.SilkS")
			(effects
				(font
					(size 0.7874 0.5842)
					(thickness 0.1524)
				)
			)
		)
		(fp_text user "3"
			(at -1.1557 5.18287 0)
			(unlocked yes)
			(layer "B.SilkS")
			(effects
				(font
					(size 0.7874 0.5842)
					(thickness 0.1524)
				)
				(justify mirror)
			)
		)
		(fp_text user "1"
			(at -1.143 0.02667 0)
			(unlocked yes)
			(layer "B.SilkS")
			(effects
				(font
					(size 0.7874 0.5842)
					(thickness 0.1524)
				)
				(justify mirror)
			)
		)
		(fp_text user "3"
			(at -1.1557 5.18287 0)
			(unlocked yes)
			(layer "B.Fab")
			(effects
				(font
					(size 0.7874 0.5842)
					(thickness 0.1524)
				)
				(justify mirror)
			)
		)
		(fp_text user "1"
			(at -1.143 0.02667 0)
			(unlocked yes)
			(layer "B.Fab")
			(effects
				(font
					(size 0.7874 0.5842)
					(thickness 0.1524)
				)
				(justify mirror)
			)
		)
		(fp_text user "3"
			(at -1.778 5.13207 0)
			(unlocked yes)
			(layer "F.Fab")
			(effects
				(font
					(size 0.7874 0.5842)
					(thickness 0.1524)
				)
			)
		)
		(pad "1" thru_hole rect
			(at 0 0)
			(size 1.5494 1.5494)
			(drill 1.0414)
			(layers "*.Cu" "*.Mask")
			(remove_unused_layers no)
			(net "SMB_SML1_PMBUS_HSC_MODULE_SCL")
			(clearance 0)
			(padstack
				(mode front_inner_back)
				(layer "Inner"
					(shape circle)
					(size 1.5494 1.5494)
					(clearance 0)
				)
				(layer "B.Cu"
					(shape rect)
					(size 1.5494 1.5494)
					(clearance 0)
				)
			)
		)
		(pad "2" thru_hole circle
			(at 0 2.54)
			(size 1.5494 1.5494)
			(drill 1.0414)
			(layers "*.Cu" "*.Mask")
			(remove_unused_layers no)
			(net "SMB_SML1_PMBUS_HSC_MODULE_SDA")
			(clearance 0)
		)
		(pad "3" thru_hole circle
			(at 0 5.08)
			(size 1.5494 1.5494)
			(drill 1.0414)
			(layers "*.Cu" "*.Mask")
			(remove_unused_layers no)
			(net "GND")
			(clearance 0)
		)
	)
	(footprint ""
		(layer "F.Cu")
		(at 220.15704 -47.58436)
		(property "Reference" "U336"
			(at -0.79502 -3.38963 0)
			(unlocked yes)
			(layer "F.SilkS")
			(effects
				(font
					(size 0.7874 0.5842)
					(thickness 0.1524)
				)
				(justify left)
			)
		)
		(property "Value" ""
			(at 0 0 0)
			(layer "F.Fab")
			(effects
				(font
					(size 1.27 1.27)
				)
			)
		)
		(duplicate_pad_numbers_are_jumpers no)
		(fp_line
			(start -1.759712 -1.500124)
			(end 1.759712 -1.500124)
			(stroke
				(width 0.1524)
				(type default)
			)
			(layer "F.SilkS")
		)
		(fp_line
			(start -1.759712 1.500124)
			(end -1.759712 -1.500124)
			(stroke
				(width 0.1524)
				(type default)
			)
			(layer "F.SilkS")
		)
		(fp_line
			(start 1.759712 -1.500124)
			(end 1.759712 1.500124)
			(stroke
				(width 0.1524)
				(type default)
			)
			(layer "F.SilkS")
		)
		(fp_line
			(start 1.759712 1.500124)
			(end -1.759712 1.500124)
			(stroke
				(width 0.1524)
				(type default)
			)
			(layer "F.SilkS")
		)
		(fp_line
			(start -0.700024 -1.500124)
			(end 0.700024 -1.500124)
			(stroke
				(width 0.1)
				(type default)
			)
			(layer "F.Fab")
		)
		(fp_line
			(start -0.700024 1.500124)
			(end -0.700024 -1.500124)
			(stroke
				(width 0.1)
				(type default)
			)
			(layer "F.Fab")
		)
		(fp_line
			(start 0.700024 -1.500124)
			(end 0.700024 1.500124)
			(stroke
				(width 0.1)
				(type default)
			)
			(layer "F.Fab")
		)
		(fp_line
			(start 0.700024 1.500124)
			(end -0.700024 1.500124)
			(stroke
				(width 0.1)
				(type default)
			)
			(layer "F.Fab")
		)
		(pad "1" smd rect
			(at -1.150112 -0.94996 270)
			(size 0.6604 0.9652)
			(layers "F.Cu" "F.Mask" "F.Paste")
			(net "GND")
		)
		(pad "2" smd rect
			(at -1.150112 0.94996 270)
			(size 0.6604 0.9652)
			(layers "F.Cu" "F.Mask" "F.Paste")
			(net "HP_E1S_0_P3V3_PWRGD")
		)
		(pad "3" smd rect
			(at 1.150112 0 270)
			(size 0.6604 0.9652)
			(layers "F.Cu" "F.Mask" "F.Paste")
			(net "P3V3_E1S_0")
		)
	)
	(footprint ""
		(layer "F.Cu")
		(at 22.809454 -113.415826 180)
		(property "Reference" "R1792"
			(at 0 0 180)
			(layer "F.SilkS")
			(hide yes)
			(effects
				(font
					(size 1.27 1.27)
				)
			)
		)
		(property "Value" ""
			(at 0 0 180)
			(layer "F.Fab")
			(effects
				(font
					(size 1.27 1.27)
				)
			)
		)
		(duplicate_pad_numbers_are_jumpers no)
		(fp_line
			(start 0.7874 0.4064)
			(end -0.7874 0.4064)
			(stroke
				(width 0.1524)
				(type default)
			)
			(layer "F.SilkS")
		)
		(fp_line
			(start 0.7874 -0.4064)
			(end 0.7874 0.4064)
			(stroke
				(width 0.1524)
				(type default)
			)
			(layer "F.SilkS")
		)
		(fp_line
			(start -0.7874 0.4064)
			(end -0.7874 -0.4064)
			(stroke
				(width 0.1524)
				(type default)
			)
			(layer "F.SilkS")
		)
		(fp_line
			(start -0.7874 -0.4064)
			(end 0.7874 -0.4064)
			(stroke
				(width 0.1524)
				(type default)
			)
			(layer "F.SilkS")
		)
		(fp_line
			(start 0.67945 0.3048)
			(end 0.120396 0.3048)
			(stroke
				(width 0.1)
				(type default)
			)
			(layer "F.Fab")
		)
		(fp_line
			(start 0.67945 -0.3048)
			(end 0.67945 0.3048)
			(stroke
				(width 0.1)
				(type default)
			)
			(layer "F.Fab")
		)
		(fp_line
			(start 0.12065 -0.2794)
			(end 0.12065 -0.3048)
			(stroke
				(width 0.1)
				(type default)
			)
			(layer "F.Fab")
		)
		(fp_line
			(start 0.12065 -0.3048)
			(end 0.67945 -0.3048)
			(stroke
				(width 0.1)
				(type default)
			)
			(layer "F.Fab")
		)
		(fp_line
			(start 0.120396 0.3048)
			(end 0.120396 0.2794)
			(stroke
				(width 0.1)
				(type default)
			)
			(layer "F.Fab")
		)
		(fp_line
			(start 0.120396 0.2794)
			(end -0.12065 0.2794)
			(stroke
				(width 0.1)
				(type default)
			)
			(layer "F.Fab")
		)
		(fp_line
			(start -0.12065 0.3048)
			(end -0.67945 0.3048)
			(stroke
				(width 0.1)
				(type default)
			)
			(layer "F.Fab")
		)
		(fp_line
			(start -0.12065 0.2794)
			(end -0.12065 0.3048)
			(stroke
				(width 0.1)
				(type default)
			)
			(layer "F.Fab")
		)
		(fp_line
			(start -0.12065 -0.2794)
			(end 0.12065 -0.2794)
			(stroke
				(width 0.1)
				(type default)
			)
			(layer "F.Fab")
		)
		(fp_line
			(start -0.12065 -0.305054)
			(end -0.12065 -0.2794)
			(stroke
				(width 0.1)
				(type default)
			)
			(layer "F.Fab")
		)
		(fp_line
			(start -0.67945 0.3048)
			(end -0.67945 -0.305054)
			(stroke
				(width 0.1)
				(type default)
			)
			(layer "F.Fab")
		)
		(fp_line
			(start -0.67945 -0.305054)
			(end -0.12065 -0.305054)
			(stroke
				(width 0.1)
				(type default)
			)
			(layer "F.Fab")
		)
		(pad "1" smd circle
			(at -0.40005 0 180)
			(size 0 0)
			(layers "F.Cu" "F.Mask" "F.Paste")
			(net "SMB_VR_3V3AUX_SDA_R1")
		)
		(pad "2" smd circle
			(at 0.40005 0 180)
			(size 0 0)
			(layers "F.Cu" "F.Mask" "F.Paste")
			(net "SMB_SEN_MAM_3V3AUX_SDA")
		)
	)
	(footprint ""
		(layer "F.Cu")
		(at 366.3696 -408.1272)
		(property "Reference" "R4737"
			(at 0 0 0)
			(layer "F.SilkS")
			(hide yes)
			(effects
				(font
					(size 1.27 1.27)
				)
			)
		)
		(property "Value" ""
			(at 0 0 0)
			(layer "F.Fab")
			(effects
				(font
					(size 1.27 1.27)
				)
			)
		)
		(duplicate_pad_numbers_are_jumpers no)
		(fp_line
			(start -0.7874 -0.4064)
			(end 0.7874 -0.4064)
			(stroke
				(width 0.1524)
				(type default)
			)
			(layer "F.SilkS")
		)
		(fp_line
			(start -0.7874 0.4064)
			(end -0.7874 -0.4064)
			(stroke
				(width 0.1524)
				(type default)
			)
			(layer "F.SilkS")
		)
		(fp_line
			(start 0.7874 -0.4064)
			(end 0.7874 0.4064)
			(stroke
				(width 0.1524)
				(type default)
			)
			(layer "F.SilkS")
		)
		(fp_line
			(start 0.7874 0.4064)
			(end -0.7874 0.4064)
			(stroke
				(width 0.1524)
				(type default)
			)
			(layer "F.SilkS")
		)
		(fp_line
			(start -0.67945 -0.305054)
			(end -0.12065 -0.305054)
			(stroke
				(width 0.1)
				(type default)
			)
			(layer "F.Fab")
		)
		(fp_line
			(start -0.67945 0.3048)
			(end -0.67945 -0.305054)
			(stroke
				(width 0.1)
				(type default)
			)
			(layer "F.Fab")
		)
		(fp_line
			(start -0.12065 -0.305054)
			(end -0.12065 -0.2794)
			(stroke
				(width 0.1)
				(type default)
			)
			(layer "F.Fab")
		)
		(fp_line
			(start -0.12065 -0.2794)
			(end 0.12065 -0.2794)
			(stroke
				(width 0.1)
				(type default)
			)
			(layer "F.Fab")
		)
		(fp_line
			(start -0.12065 0.2794)
			(end -0.12065 0.3048)
			(stroke
				(width 0.1)
				(type default)
			)
			(layer "F.Fab")
		)
		(fp_line
			(start -0.12065 0.3048)
			(end -0.67945 0.3048)
			(stroke
				(width 0.1)
				(type default)
			)
			(layer "F.Fab")
		)
		(fp_line
			(start 0.120396 0.2794)
			(end -0.12065 0.2794)
			(stroke
				(width 0.1)
				(type default)
			)
			(layer "F.Fab")
		)
		(fp_line
			(start 0.120396 0.3048)
			(end 0.120396 0.2794)
			(stroke
				(width 0.1)
				(type default)
			)
			(layer "F.Fab")
		)
		(fp_line
			(start 0.12065 -0.3048)
			(end 0.67945 -0.3048)
			(stroke
				(width 0.1)
				(type default)
			)
			(layer "F.Fab")
		)
		(fp_line
			(start 0.12065 -0.2794)
			(end 0.12065 -0.3048)
			(stroke
				(width 0.1)
				(type default)
			)
			(layer "F.Fab")
		)
		(fp_line
			(start 0.67945 -0.3048)
			(end 0.67945 0.3048)
			(stroke
				(width 0.1)
				(type default)
			)
			(layer "F.Fab")
		)
		(fp_line
			(start 0.67945 0.3048)
			(end 0.120396 0.3048)
			(stroke
				(width 0.1)
				(type default)
			)
			(layer "F.Fab")
		)
		(pad "1" smd circle
			(at -0.40005 0)
			(size 0 0)
			(layers "F.Cu" "F.Mask" "F.Paste")
			(net "P3V3_AUX")
		)
		(pad "2" smd circle
			(at 0.40005 0)
			(size 0 0)
			(layers "F.Cu" "F.Mask" "F.Paste")
			(net "PRSNT_CABLE_SWB_B1_N")
		)
	)
	(footprint ""
		(layer "F.Cu")
		(at 486.113836 -470.036144)
		(property "Reference" "JP4003_12"
			(at -2.172716 -3.824224 0)
			(unlocked yes)
			(layer "F.SilkS")
			(effects
				(font
					(size 0.7874 0.5842)
					(thickness 0.1524)
				)
				(justify left)
			)
		)
		(property "Value" ""
			(at 0 0 0)
			(layer "F.Fab")
			(effects
				(font
					(size 1.27 1.27)
				)
			)
		)
		(duplicate_pad_numbers_are_jumpers no)
		(pad "1" smd circle
			(at 0 0)
			(size 0.762 0.762)
			(layers "F.Cu" "F.Mask" "F.Paste")
			(net "Net_8607")
		)
	)
	(footprint ""
		(layer "F.Cu")
		(at 371.23624 -315.66739 90)
		(property "Reference" "PC16"
			(at 0 0 90)
			(layer "F.SilkS")
			(hide yes)
			(effects
				(font
					(size 1.27 1.27)
				)
			)
		)
		(property "Value" ""
			(at 0 0 90)
			(layer "F.Fab")
			(effects
				(font
					(size 1.27 1.27)
				)
			)
		)
		(duplicate_pad_numbers_are_jumpers no)
		(fp_line
			(start 2.750058 0.999998)
			(end -2.750058 0.999998)
			(stroke
				(width 0.1524)
				(type default)
			)
			(layer "F.SilkS")
		)
		(fp_circle
			(center 0 0.999998)
			(end 0 3.750056)
			(stroke
				(width 0.1524)
				(type default)
			)
			(fill no)
			(layer "F.SilkS")
		)
		(fp_poly
			(pts
				(arc
					(start 2.750058 0.999998)
					(mid 0 3.750056)
					(end -2.750058 0.999998)
				)
			)
			(stroke
				(width 0)
				(type default)
			)
			(fill yes)
			(layer "F.SilkS")
		)
		(fp_circle
			(center 0 0.999998)
			(end 0 3.750056)
			(stroke
				(width 0.1)
				(type default)
			)
			(fill no)
			(layer "F.Fab")
		)
		(pad "1" thru_hole rect
			(at 0 0 90)
			(size 1.5748 1.5748)
			(drill 1.0668)
			(layers "*.Cu" "*.Mask")
			(remove_unused_layers no)
			(net "PVCCIN_CPU0")
			(clearance 0)
			(padstack
				(mode front_inner_back)
				(layer "Inner"
					(shape circle)
					(size 1.5748 1.5748)
					(clearance 0)
				)
				(layer "B.Cu"
					(shape rect)
					(size 1.5748 1.5748)
					(clearance 0)
				)
			)
		)
		(pad "2" thru_hole circle
			(at 0 1.999996 90)
			(size 1.5748 1.5748)
			(drill 1.0668)
			(layers "*.Cu" "*.Mask")
			(remove_unused_layers no)
			(net "GND")
			(clearance 0)
		)
	)
	(footprint ""
		(layer "F.Cu")
		(at 131.466844 -132.707126 180)
		(property "Reference" "R3396"
			(at 0 0 180)
			(layer "F.SilkS")
			(hide yes)
			(effects
				(font
					(size 1.27 1.27)
				)
			)
		)
		(property "Value" ""
			(at 0 0 180)
			(layer "F.Fab")
			(effects
				(font
					(size 1.27 1.27)
				)
			)
		)
		(duplicate_pad_numbers_are_jumpers no)
		(fp_line
			(start 0.7874 0.4064)
			(end -0.7874 0.4064)
			(stroke
				(width 0.1524)
				(type default)
			)
			(layer "F.SilkS")
		)
		(fp_line
			(start 0.7874 -0.4064)
			(end 0.7874 0.4064)
			(stroke
				(width 0.1524)
				(type default)
			)
			(layer "F.SilkS")
		)
		(fp_line
			(start -0.7874 0.4064)
			(end -0.7874 -0.4064)
			(stroke
				(width 0.1524)
				(type default)
			)
			(layer "F.SilkS")
		)
		(fp_line
			(start -0.7874 -0.4064)
			(end 0.7874 -0.4064)
			(stroke
				(width 0.1524)
				(type default)
			)
			(layer "F.SilkS")
		)
		(fp_line
			(start 0.67945 0.3048)
			(end 0.120396 0.3048)
			(stroke
				(width 0.1)
				(type default)
			)
			(layer "F.Fab")
		)
		(fp_line
			(start 0.67945 -0.3048)
			(end 0.67945 0.3048)
			(stroke
				(width 0.1)
				(type default)
			)
			(layer "F.Fab")
		)
		(fp_line
			(start 0.12065 -0.2794)
			(end 0.12065 -0.3048)
			(stroke
				(width 0.1)
				(type default)
			)
			(layer "F.Fab")
		)
		(fp_line
			(start 0.12065 -0.3048)
			(end 0.67945 -0.3048)
			(stroke
				(width 0.1)
				(type default)
			)
			(layer "F.Fab")
		)
		(fp_line
			(start 0.120396 0.3048)
			(end 0.120396 0.2794)
			(stroke
				(width 0.1)
				(type default)
			)
			(layer "F.Fab")
		)
		(fp_line
			(start 0.120396 0.2794)
			(end -0.12065 0.2794)
			(stroke
				(width 0.1)
				(type default)
			)
			(layer "F.Fab")
		)
		(fp_line
			(start -0.12065 0.3048)
			(end -0.67945 0.3048)
			(stroke
				(width 0.1)
				(type default)
			)
			(layer "F.Fab")
		)
		(fp_line
			(start -0.12065 0.2794)
			(end -0.12065 0.3048)
			(stroke
				(width 0.1)
				(type default)
			)
			(layer "F.Fab")
		)
		(fp_line
			(start -0.12065 -0.2794)
			(end 0.12065 -0.2794)
			(stroke
				(width 0.1)
				(type default)
			)
			(layer "F.Fab")
		)
		(fp_line
			(start -0.12065 -0.305054)
			(end -0.12065 -0.2794)
			(stroke
				(width 0.1)
				(type default)
			)
			(layer "F.Fab")
		)
		(fp_line
			(start -0.67945 0.3048)
			(end -0.67945 -0.305054)
			(stroke
				(width 0.1)
				(type default)
			)
			(layer "F.Fab")
		)
		(fp_line
			(start -0.67945 -0.305054)
			(end -0.12065 -0.305054)
			(stroke
				(width 0.1)
				(type default)
			)
			(layer "F.Fab")
		)
		(pad "1" smd circle
			(at -0.40005 0 180)
			(size 0 0)
			(layers "F.Cu" "F.Mask" "F.Paste")
			(net "P3V3_AUX")
		)
		(pad "2" smd circle
			(at 0.40005 0 180)
			(size 0 0)
			(layers "F.Cu" "F.Mask" "F.Paste")
			(net "SMB_INA230_3V3AUX_SDA")
		)
	)
	(footprint ""
		(layer "F.Cu")
		(at 144.564608 -106.168698 -90)
		(property "Reference" "R4391"
			(at 0 0 270)
			(layer "F.SilkS")
			(hide yes)
			(effects
				(font
					(size 1.27 1.27)
				)
			)
		)
		(property "Value" ""
			(at 0 0 270)
			(layer "F.Fab")
			(effects
				(font
					(size 1.27 1.27)
				)
			)
		)
		(duplicate_pad_numbers_are_jumpers no)
		(fp_line
			(start -0.7874 0.4064)
			(end -0.7874 -0.4064)
			(stroke
				(width 0.1524)
				(type default)
			)
			(layer "F.SilkS")
		)
		(fp_line
			(start 0.7874 0.4064)
			(end -0.7874 0.4064)
			(stroke
				(width 0.1524)
				(type default)
			)
			(layer "F.SilkS")
		)
		(fp_line
			(start -0.7874 -0.4064)
			(end 0.7874 -0.4064)
			(stroke
				(width 0.1524)
				(type default)
			)
			(layer "F.SilkS")
		)
		(fp_line
			(start 0.7874 -0.4064)
			(end 0.7874 0.4064)
			(stroke
				(width 0.1524)
				(type default)
			)
			(layer "F.SilkS")
		)
		(fp_line
			(start -0.67945 0.3048)
			(end -0.67945 -0.305054)
			(stroke
				(width 0.1)
				(type default)
			)
			(layer "F.Fab")
		)
		(fp_line
			(start -0.12065 0.3048)
			(end -0.67945 0.3048)
			(stroke
				(width 0.1)
				(type default)
			)
			(layer "F.Fab")
		)
		(fp_line
			(start 0.120396 0.3048)
			(end 0.120396 0.2794)
			(stroke
				(width 0.1)
				(type default)
			)
			(layer "F.Fab")
		)
		(fp_line
			(start 0.67945 0.3048)
			(end 0.120396 0.3048)
			(stroke
				(width 0.1)
				(type default)
			)
			(layer "F.Fab")
		)
		(fp_line
			(start -0.12065 0.2794)
			(end -0.12065 0.3048)
			(stroke
				(width 0.1)
				(type default)
			)
			(layer "F.Fab")
		)
		(fp_line
			(start 0.120396 0.2794)
			(end -0.12065 0.2794)
			(stroke
				(width 0.1)
				(type default)
			)
			(layer "F.Fab")
		)
		(fp_line
			(start -0.12065 -0.2794)
			(end 0.12065 -0.2794)
			(stroke
				(width 0.1)
				(type default)
			)
			(layer "F.Fab")
		)
		(fp_line
			(start 0.12065 -0.2794)
			(end 0.12065 -0.3048)
			(stroke
				(width 0.1)
				(type default)
			)
			(layer "F.Fab")
		)
		(fp_line
			(start 0.12065 -0.3048)
			(end 0.67945 -0.3048)
			(stroke
				(width 0.1)
				(type default)
			)
			(layer "F.Fab")
		)
		(fp_line
			(start 0.67945 -0.3048)
			(end 0.67945 0.3048)
			(stroke
				(width 0.1)
				(type default)
			)
			(layer "F.Fab")
		)
		(fp_line
			(start -0.67945 -0.305054)
			(end -0.12065 -0.305054)
			(stroke
				(width 0.1)
				(type default)
			)
			(layer "F.Fab")
		)
		(fp_line
			(start -0.12065 -0.305054)
			(end -0.12065 -0.2794)
			(stroke
				(width 0.1)
				(type default)
			)
			(layer "F.Fab")
		)
		(pad "1" smd circle
			(at -0.40005 0 270)
			(size 0 0)
			(layers "F.Cu" "F.Mask" "F.Paste")
			(net "PD_GTL2014_ERROR_B0")
		)
		(pad "2" smd circle
			(at 0.40005 0 270)
			(size 0 0)
			(layers "F.Cu" "F.Mask" "F.Paste")
			(net "GND")
		)
	)
	(footprint ""
		(layer "F.Cu")
		(at 289.27806 -95.760794)
		(property "Reference" "C629"
			(at 0 0 0)
			(layer "F.SilkS")
			(hide yes)
			(effects
				(font
					(size 1.27 1.27)
				)
			)
		)
		(property "Value" ""
			(at 0 0 0)
			(layer "F.Fab")
			(effects
				(font
					(size 1.27 1.27)
				)
			)
		)
		(duplicate_pad_numbers_are_jumpers no)
		(fp_line
			(start -0.7874 -0.4064)
			(end 0.7874 -0.4064)
			(stroke
				(width 0.1524)
				(type default)
			)
			(layer "F.SilkS")
		)
		(fp_line
			(start -0.7874 0.4064)
			(end -0.7874 -0.4064)
			(stroke
				(width 0.1524)
				(type default)
			)
			(layer "F.SilkS")
		)
		(fp_line
			(start 0.7874 -0.4064)
			(end 0.7874 0.4064)
			(stroke
				(width 0.1524)
				(type default)
			)
			(layer "F.SilkS")
		)
		(fp_line
			(start 0.7874 0.4064)
			(end -0.7874 0.4064)
			(stroke
				(width 0.1524)
				(type default)
			)
			(layer "F.SilkS")
		)
		(fp_line
			(start -0.67945 -0.305054)
			(end -0.12065 -0.305054)
			(stroke
				(width 0.1)
				(type default)
			)
			(layer "F.Fab")
		)
		(fp_line
			(start -0.67945 0.3048)
			(end -0.67945 -0.305054)
			(stroke
				(width 0.1)
				(type default)
			)
			(layer "F.Fab")
		)
		(fp_line
			(start -0.12065 -0.305054)
			(end -0.12065 -0.2794)
			(stroke
				(width 0.1)
				(type default)
			)
			(layer "F.Fab")
		)
		(fp_line
			(start -0.12065 -0.2794)
			(end 0.12065 -0.2794)
			(stroke
				(width 0.1)
				(type default)
			)
			(layer "F.Fab")
		)
		(fp_line
			(start -0.12065 0.2794)
			(end -0.12065 0.3048)
			(stroke
				(width 0.1)
				(type default)
			)
			(layer "F.Fab")
		)
		(fp_line
			(start -0.12065 0.3048)
			(end -0.67945 0.3048)
			(stroke
				(width 0.1)
				(type default)
			)
			(layer "F.Fab")
		)
		(fp_line
			(start 0.120396 0.2794)
			(end -0.12065 0.2794)
			(stroke
				(width 0.1)
				(type default)
			)
			(layer "F.Fab")
		)
		(fp_line
			(start 0.120396 0.3048)
			(end 0.120396 0.2794)
			(stroke
				(width 0.1)
				(type default)
			)
			(layer "F.Fab")
		)
		(fp_line
			(start 0.12065 -0.3048)
			(end 0.67945 -0.3048)
			(stroke
				(width 0.1)
				(type default)
			)
			(layer "F.Fab")
		)
		(fp_line
			(start 0.12065 -0.2794)
			(end 0.12065 -0.3048)
			(stroke
				(width 0.1)
				(type default)
			)
			(layer "F.Fab")
		)
		(fp_line
			(start 0.67945 -0.3048)
			(end 0.67945 0.3048)
			(stroke
				(width 0.1)
				(type default)
			)
			(layer "F.Fab")
		)
		(fp_line
			(start 0.67945 0.3048)
			(end 0.120396 0.3048)
			(stroke
				(width 0.1)
				(type default)
			)
			(layer "F.Fab")
		)
		(pad "1" smd circle
			(at -0.40005 0)
			(size 0 0)
			(layers "F.Cu" "F.Mask" "F.Paste")
			(net "P3V3_AUX")
		)
		(pad "2" smd circle
			(at 0.40005 0)
			(size 0 0)
			(layers "F.Cu" "F.Mask" "F.Paste")
			(net "GND")
		)
	)
	(footprint ""
		(layer "F.Cu")
		(at 102.86619 -65.12306 -90)
		(property "Reference" "R3097"
			(at 0 0 270)
			(layer "F.SilkS")
			(hide yes)
			(effects
				(font
					(size 1.27 1.27)
				)
			)
		)
		(property "Value" ""
			(at 0 0 270)
			(layer "F.Fab")
			(effects
				(font
					(size 1.27 1.27)
				)
			)
		)
		(duplicate_pad_numbers_are_jumpers no)
		(fp_line
			(start -0.7874 0.4064)
			(end -0.7874 -0.4064)
			(stroke
				(width 0.1524)
				(type default)
			)
			(layer "F.SilkS")
		)
		(fp_line
			(start 0.7874 0.4064)
			(end -0.7874 0.4064)
			(stroke
				(width 0.1524)
				(type default)
			)
			(layer "F.SilkS")
		)
		(fp_line
			(start -0.7874 -0.4064)
			(end 0.7874 -0.4064)
			(stroke
				(width 0.1524)
				(type default)
			)
			(layer "F.SilkS")
		)
		(fp_line
			(start 0.7874 -0.4064)
			(end 0.7874 0.4064)
			(stroke
				(width 0.1524)
				(type default)
			)
			(layer "F.SilkS")
		)
		(fp_line
			(start -0.67945 0.3048)
			(end -0.67945 -0.305054)
			(stroke
				(width 0.1)
				(type default)
			)
			(layer "F.Fab")
		)
		(fp_line
			(start -0.12065 0.3048)
			(end -0.67945 0.3048)
			(stroke
				(width 0.1)
				(type default)
			)
			(layer "F.Fab")
		)
		(fp_line
			(start 0.120396 0.3048)
			(end 0.120396 0.2794)
			(stroke
				(width 0.1)
				(type default)
			)
			(layer "F.Fab")
		)
		(fp_line
			(start 0.67945 0.3048)
			(end 0.120396 0.3048)
			(stroke
				(width 0.1)
				(type default)
			)
			(layer "F.Fab")
		)
		(fp_line
			(start -0.12065 0.2794)
			(end -0.12065 0.3048)
			(stroke
				(width 0.1)
				(type default)
			)
			(layer "F.Fab")
		)
		(fp_line
			(start 0.120396 0.2794)
			(end -0.12065 0.2794)
			(stroke
				(width 0.1)
				(type default)
			)
			(layer "F.Fab")
		)
		(fp_line
			(start -0.12065 -0.2794)
			(end 0.12065 -0.2794)
			(stroke
				(width 0.1)
				(type default)
			)
			(layer "F.Fab")
		)
		(fp_line
			(start 0.12065 -0.2794)
			(end 0.12065 -0.3048)
			(stroke
				(width 0.1)
				(type default)
			)
			(layer "F.Fab")
		)
		(fp_line
			(start 0.12065 -0.3048)
			(end 0.67945 -0.3048)
			(stroke
				(width 0.1)
				(type default)
			)
			(layer "F.Fab")
		)
		(fp_line
			(start 0.67945 -0.3048)
			(end 0.67945 0.3048)
			(stroke
				(width 0.1)
				(type default)
			)
			(layer "F.Fab")
		)
		(fp_line
			(start -0.67945 -0.305054)
			(end -0.12065 -0.305054)
			(stroke
				(width 0.1)
				(type default)
			)
			(layer "F.Fab")
		)
		(fp_line
			(start -0.12065 -0.305054)
			(end -0.12065 -0.2794)
			(stroke
				(width 0.1)
				(type default)
			)
			(layer "F.Fab")
		)
		(pad "1" smd circle
			(at -0.40005 0 270)
			(size 0 0)
			(layers "F.Cu" "F.Mask" "F.Paste")
			(net "LED_PWRGD_PVNN_MAIN_CPU1")
		)
		(pad "2" smd circle
			(at 0.40005 0 270)
			(size 0 0)
			(layers "F.Cu" "F.Mask" "F.Paste")
			(net "P3V3_AUX")
		)
	)
	(footprint ""
		(layer "F.Cu")
		(at 309.259224 -438.187846 -90)
		(property "Reference" "R4127"
			(at 0 0 270)
			(layer "F.SilkS")
			(hide yes)
			(effects
				(font
					(size 1.27 1.27)
				)
			)
		)
		(property "Value" ""
			(at 0 0 270)
			(layer "F.Fab")
			(effects
				(font
					(size 1.27 1.27)
				)
			)
		)
		(duplicate_pad_numbers_are_jumpers no)
		(fp_line
			(start -0.7874 0.4064)
			(end -0.7874 -0.4064)
			(stroke
				(width 0.1524)
				(type default)
			)
			(layer "F.SilkS")
		)
		(fp_line
			(start 0.7874 0.4064)
			(end -0.7874 0.4064)
			(stroke
				(width 0.1524)
				(type default)
			)
			(layer "F.SilkS")
		)
		(fp_line
			(start -0.7874 -0.4064)
			(end 0.7874 -0.4064)
			(stroke
				(width 0.1524)
				(type default)
			)
			(layer "F.SilkS")
		)
		(fp_line
			(start 0.7874 -0.4064)
			(end 0.7874 0.4064)
			(stroke
				(width 0.1524)
				(type default)
			)
			(layer "F.SilkS")
		)
		(fp_line
			(start -0.67945 0.3048)
			(end -0.67945 -0.305054)
			(stroke
				(width 0.1)
				(type default)
			)
			(layer "F.Fab")
		)
		(fp_line
			(start -0.12065 0.3048)
			(end -0.67945 0.3048)
			(stroke
				(width 0.1)
				(type default)
			)
			(layer "F.Fab")
		)
		(fp_line
			(start 0.120396 0.3048)
			(end 0.120396 0.2794)
			(stroke
				(width 0.1)
				(type default)
			)
			(layer "F.Fab")
		)
		(fp_line
			(start 0.67945 0.3048)
			(end 0.120396 0.3048)
			(stroke
				(width 0.1)
				(type default)
			)
			(layer "F.Fab")
		)
		(fp_line
			(start -0.12065 0.2794)
			(end -0.12065 0.3048)
			(stroke
				(width 0.1)
				(type default)
			)
			(layer "F.Fab")
		)
		(fp_line
			(start 0.120396 0.2794)
			(end -0.12065 0.2794)
			(stroke
				(width 0.1)
				(type default)
			)
			(layer "F.Fab")
		)
		(fp_line
			(start -0.12065 -0.2794)
			(end 0.12065 -0.2794)
			(stroke
				(width 0.1)
				(type default)
			)
			(layer "F.Fab")
		)
		(fp_line
			(start 0.12065 -0.2794)
			(end 0.12065 -0.3048)
			(stroke
				(width 0.1)
				(type default)
			)
			(layer "F.Fab")
		)
		(fp_line
			(start 0.12065 -0.3048)
			(end 0.67945 -0.3048)
			(stroke
				(width 0.1)
				(type default)
			)
			(layer "F.Fab")
		)
		(fp_line
			(start 0.67945 -0.3048)
			(end 0.67945 0.3048)
			(stroke
				(width 0.1)
				(type default)
			)
			(layer "F.Fab")
		)
		(fp_line
			(start -0.67945 -0.305054)
			(end -0.12065 -0.305054)
			(stroke
				(width 0.1)
				(type default)
			)
			(layer "F.Fab")
		)
		(fp_line
			(start -0.12065 -0.305054)
			(end -0.12065 -0.2794)
			(stroke
				(width 0.1)
				(type default)
			)
			(layer "F.Fab")
		)
		(pad "1" smd circle
			(at -0.40005 0 270)
			(size 0 0)
			(layers "F.Cu" "F.Mask" "F.Paste")
			(net "P3V3_AUX")
		)
		(pad "2" smd circle
			(at 0.40005 0 270)
			(size 0 0)
			(layers "F.Cu" "F.Mask" "F.Paste")
			(net "GPU_3V3IO_RSVD1_FFU_N")
		)
	)
	(footprint ""
		(layer "F.Cu")
		(at 35.840162 -122.380502 90)
		(property "Reference" "R1661"
			(at 0 0 90)
			(layer "F.SilkS")
			(hide yes)
			(effects
				(font
					(size 1.27 1.27)
				)
			)
		)
		(property "Value" ""
			(at 0 0 90)
			(layer "F.Fab")
			(effects
				(font
					(size 1.27 1.27)
				)
			)
		)
		(duplicate_pad_numbers_are_jumpers no)
		(fp_line
			(start 0.7874 -0.4064)
			(end 0.7874 0.4064)
			(stroke
				(width 0.1524)
				(type default)
			)
			(layer "F.SilkS")
		)
		(fp_line
			(start -0.7874 -0.4064)
			(end 0.7874 -0.4064)
			(stroke
				(width 0.1524)
				(type default)
			)
			(layer "F.SilkS")
		)
		(fp_line
			(start 0.7874 0.4064)
			(end -0.7874 0.4064)
			(stroke
				(width 0.1524)
				(type default)
			)
			(layer "F.SilkS")
		)
		(fp_line
			(start -0.7874 0.4064)
			(end -0.7874 -0.4064)
			(stroke
				(width 0.1524)
				(type default)
			)
			(layer "F.SilkS")
		)
		(fp_line
			(start -0.12065 -0.305054)
			(end -0.12065 -0.2794)
			(stroke
				(width 0.1)
				(type default)
			)
			(layer "F.Fab")
		)
		(fp_line
			(start -0.67945 -0.305054)
			(end -0.12065 -0.305054)
			(stroke
				(width 0.1)
				(type default)
			)
			(layer "F.Fab")
		)
		(fp_line
			(start 0.67945 -0.3048)
			(end 0.67945 0.3048)
			(stroke
				(width 0.1)
				(type default)
			)
			(layer "F.Fab")
		)
		(fp_line
			(start 0.12065 -0.3048)
			(end 0.67945 -0.3048)
			(stroke
				(width 0.1)
				(type default)
			)
			(layer "F.Fab")
		)
		(fp_line
			(start 0.12065 -0.2794)
			(end 0.12065 -0.3048)
			(stroke
				(width 0.1)
				(type default)
			)
			(layer "F.Fab")
		)
		(fp_line
			(start -0.12065 -0.2794)
			(end 0.12065 -0.2794)
			(stroke
				(width 0.1)
				(type default)
			)
			(layer "F.Fab")
		)
		(fp_line
			(start 0.120396 0.2794)
			(end -0.12065 0.2794)
			(stroke
				(width 0.1)
				(type default)
			)
			(layer "F.Fab")
		)
		(fp_line
			(start -0.12065 0.2794)
			(end -0.12065 0.3048)
			(stroke
				(width 0.1)
				(type default)
			)
			(layer "F.Fab")
		)
		(fp_line
			(start 0.67945 0.3048)
			(end 0.120396 0.3048)
			(stroke
				(width 0.1)
				(type default)
			)
			(layer "F.Fab")
		)
		(fp_line
			(start 0.120396 0.3048)
			(end 0.120396 0.2794)
			(stroke
				(width 0.1)
				(type default)
			)
			(layer "F.Fab")
		)
		(fp_line
			(start -0.12065 0.3048)
			(end -0.67945 0.3048)
			(stroke
				(width 0.1)
				(type default)
			)
			(layer "F.Fab")
		)
		(fp_line
			(start -0.67945 0.3048)
			(end -0.67945 -0.305054)
			(stroke
				(width 0.1)
				(type default)
			)
			(layer "F.Fab")
		)
		(pad "1" smd circle
			(at -0.40005 0 90)
			(size 0 0)
			(layers "F.Cu" "F.Mask" "F.Paste")
			(net "SMB_VR_3V3AUX_SCL")
		)
		(pad "2" smd circle
			(at 0.40005 0 90)
			(size 0 0)
			(layers "F.Cu" "F.Mask" "F.Paste")
			(net "SMB_VR_3V3AUX_SCL_R")
		)
	)
	(footprint ""
		(layer "F.Cu")
		(at 77.381354 -65.082674 -90)
		(property "Reference" "R3080"
			(at 0 0 270)
			(layer "F.SilkS")
			(hide yes)
			(effects
				(font
					(size 1.27 1.27)
				)
			)
		)
		(property "Value" ""
			(at 0 0 270)
			(layer "F.Fab")
			(effects
				(font
					(size 1.27 1.27)
				)
			)
		)
		(duplicate_pad_numbers_are_jumpers no)
		(fp_line
			(start -0.7874 0.4064)
			(end -0.7874 -0.4064)
			(stroke
				(width 0.1524)
				(type default)
			)
			(layer "F.SilkS")
		)
		(fp_line
			(start 0.7874 0.4064)
			(end -0.7874 0.4064)
			(stroke
				(width 0.1524)
				(type default)
			)
			(layer "F.SilkS")
		)
		(fp_line
			(start -0.7874 -0.4064)
			(end 0.7874 -0.4064)
			(stroke
				(width 0.1524)
				(type default)
			)
			(layer "F.SilkS")
		)
		(fp_line
			(start 0.7874 -0.4064)
			(end 0.7874 0.4064)
			(stroke
				(width 0.1524)
				(type default)
			)
			(layer "F.SilkS")
		)
		(fp_line
			(start -0.67945 0.3048)
			(end -0.67945 -0.305054)
			(stroke
				(width 0.1)
				(type default)
			)
			(layer "F.Fab")
		)
		(fp_line
			(start -0.12065 0.3048)
			(end -0.67945 0.3048)
			(stroke
				(width 0.1)
				(type default)
			)
			(layer "F.Fab")
		)
		(fp_line
			(start 0.120396 0.3048)
			(end 0.120396 0.2794)
			(stroke
				(width 0.1)
				(type default)
			)
			(layer "F.Fab")
		)
		(fp_line
			(start 0.67945 0.3048)
			(end 0.120396 0.3048)
			(stroke
				(width 0.1)
				(type default)
			)
			(layer "F.Fab")
		)
		(fp_line
			(start -0.12065 0.2794)
			(end -0.12065 0.3048)
			(stroke
				(width 0.1)
				(type default)
			)
			(layer "F.Fab")
		)
		(fp_line
			(start 0.120396 0.2794)
			(end -0.12065 0.2794)
			(stroke
				(width 0.1)
				(type default)
			)
			(layer "F.Fab")
		)
		(fp_line
			(start -0.12065 -0.2794)
			(end 0.12065 -0.2794)
			(stroke
				(width 0.1)
				(type default)
			)
			(layer "F.Fab")
		)
		(fp_line
			(start 0.12065 -0.2794)
			(end 0.12065 -0.3048)
			(stroke
				(width 0.1)
				(type default)
			)
			(layer "F.Fab")
		)
		(fp_line
			(start 0.12065 -0.3048)
			(end 0.67945 -0.3048)
			(stroke
				(width 0.1)
				(type default)
			)
			(layer "F.Fab")
		)
		(fp_line
			(start 0.67945 -0.3048)
			(end 0.67945 0.3048)
			(stroke
				(width 0.1)
				(type default)
			)
			(layer "F.Fab")
		)
		(fp_line
			(start -0.67945 -0.305054)
			(end -0.12065 -0.305054)
			(stroke
				(width 0.1)
				(type default)
			)
			(layer "F.Fab")
		)
		(fp_line
			(start -0.12065 -0.305054)
			(end -0.12065 -0.2794)
			(stroke
				(width 0.1)
				(type default)
			)
			(layer "F.Fab")
		)
		(pad "1" smd circle
			(at -0.40005 0 270)
			(size 0 0)
			(layers "F.Cu" "F.Mask" "F.Paste")
			(net "LED_RST_PLD_CPU0_DRAM_CD_N")
		)
		(pad "2" smd circle
			(at 0.40005 0 270)
			(size 0 0)
			(layers "F.Cu" "F.Mask" "F.Paste")
			(net "P3V3_AUX")
		)
	)
	(footprint ""
		(layer "F.Cu")
		(at 159.258 -126.365 -90)
		(property "Reference" "R4640"
			(at 0 0 270)
			(layer "F.SilkS")
			(hide yes)
			(effects
				(font
					(size 1.27 1.27)
				)
			)
		)
		(property "Value" ""
			(at 0 0 270)
			(layer "F.Fab")
			(effects
				(font
					(size 1.27 1.27)
				)
			)
		)
		(duplicate_pad_numbers_are_jumpers no)
		(fp_line
			(start -2.234946 0.9271)
			(end -2.234946 -0.9271)
			(stroke
				(width 0.1524)
				(type default)
			)
			(layer "F.SilkS")
		)
		(fp_line
			(start 2.234946 0.9271)
			(end -2.234946 0.9271)
			(stroke
				(width 0.1524)
				(type default)
			)
			(layer "F.SilkS")
		)
		(fp_line
			(start -2.234946 -0.9271)
			(end 2.234946 -0.9271)
			(stroke
				(width 0.1524)
				(type default)
			)
			(layer "F.SilkS")
		)
		(fp_line
			(start 2.234946 -0.9271)
			(end 2.234946 0.9271)
			(stroke
				(width 0.1524)
				(type default)
			)
			(layer "F.SilkS")
		)
		(fp_line
			(start -1.575054 0.824992)
			(end 1.575054 0.824992)
			(stroke
				(width 0.1)
				(type default)
			)
			(layer "F.Fab")
		)
		(fp_line
			(start 1.575054 0.824992)
			(end 1.575054 -0.824992)
			(stroke
				(width 0.1)
				(type default)
			)
			(layer "F.Fab")
		)
		(fp_line
			(start -1.575054 -0.824992)
			(end -1.575054 0.824992)
			(stroke
				(width 0.1)
				(type default)
			)
			(layer "F.Fab")
		)
		(fp_line
			(start 1.575054 -0.824992)
			(end -1.575054 -0.824992)
			(stroke
				(width 0.1)
				(type default)
			)
			(layer "F.Fab")
		)
		(pad "1" smd rect
			(at -1.599946 0 270)
			(size 1.016 1.6002)
			(layers "F.Cu" "F.Mask" "F.Paste")
			(net "P5V")
		)
		(pad "2" smd rect
			(at 1.599946 0 270)
			(size 1.016 1.6002)
			(layers "F.Cu" "F.Mask" "F.Paste")
			(net "VR_P5V_EN_D")
		)
	)
	(footprint ""
		(layer "F.Cu")
		(at 374.16359 -64.866012)
		(property "Reference" "R756"
			(at 0 0 0)
			(layer "F.SilkS")
			(hide yes)
			(effects
				(font
					(size 1.27 1.27)
				)
			)
		)
		(property "Value" ""
			(at 0 0 0)
			(layer "F.Fab")
			(effects
				(font
					(size 1.27 1.27)
				)
			)
		)
		(duplicate_pad_numbers_are_jumpers no)
		(fp_line
			(start -0.7874 -0.4064)
			(end 0.7874 -0.4064)
			(stroke
				(width 0.1524)
				(type default)
			)
			(layer "F.SilkS")
		)
		(fp_line
			(start -0.7874 0.4064)
			(end -0.7874 -0.4064)
			(stroke
				(width 0.1524)
				(type default)
			)
			(layer "F.SilkS")
		)
		(fp_line
			(start 0.7874 -0.4064)
			(end 0.7874 0.4064)
			(stroke
				(width 0.1524)
				(type default)
			)
			(layer "F.SilkS")
		)
		(fp_line
			(start 0.7874 0.4064)
			(end -0.7874 0.4064)
			(stroke
				(width 0.1524)
				(type default)
			)
			(layer "F.SilkS")
		)
		(fp_line
			(start -0.67945 -0.305054)
			(end -0.12065 -0.305054)
			(stroke
				(width 0.1)
				(type default)
			)
			(layer "F.Fab")
		)
		(fp_line
			(start -0.67945 0.3048)
			(end -0.67945 -0.305054)
			(stroke
				(width 0.1)
				(type default)
			)
			(layer "F.Fab")
		)
		(fp_line
			(start -0.12065 -0.305054)
			(end -0.12065 -0.2794)
			(stroke
				(width 0.1)
				(type default)
			)
			(layer "F.Fab")
		)
		(fp_line
			(start -0.12065 -0.2794)
			(end 0.12065 -0.2794)
			(stroke
				(width 0.1)
				(type default)
			)
			(layer "F.Fab")
		)
		(fp_line
			(start -0.12065 0.2794)
			(end -0.12065 0.3048)
			(stroke
				(width 0.1)
				(type default)
			)
			(layer "F.Fab")
		)
		(fp_line
			(start -0.12065 0.3048)
			(end -0.67945 0.3048)
			(stroke
				(width 0.1)
				(type default)
			)
			(layer "F.Fab")
		)
		(fp_line
			(start 0.120396 0.2794)
			(end -0.12065 0.2794)
			(stroke
				(width 0.1)
				(type default)
			)
			(layer "F.Fab")
		)
		(fp_line
			(start 0.120396 0.3048)
			(end 0.120396 0.2794)
			(stroke
				(width 0.1)
				(type default)
			)
			(layer "F.Fab")
		)
		(fp_line
			(start 0.12065 -0.3048)
			(end 0.67945 -0.3048)
			(stroke
				(width 0.1)
				(type default)
			)
			(layer "F.Fab")
		)
		(fp_line
			(start 0.12065 -0.2794)
			(end 0.12065 -0.3048)
			(stroke
				(width 0.1)
				(type default)
			)
			(layer "F.Fab")
		)
		(fp_line
			(start 0.67945 -0.3048)
			(end 0.67945 0.3048)
			(stroke
				(width 0.1)
				(type default)
			)
			(layer "F.Fab")
		)
		(fp_line
			(start 0.67945 0.3048)
			(end 0.120396 0.3048)
			(stroke
				(width 0.1)
				(type default)
			)
			(layer "F.Fab")
		)
		(pad "1" smd circle
			(at -0.40005 0)
			(size 0 0)
			(layers "F.Cu" "F.Mask" "F.Paste")
			(net "JTAG_DBP_PRDY_N")
		)
		(pad "2" smd circle
			(at 0.40005 0)
			(size 0 0)
			(layers "F.Cu" "F.Mask" "F.Paste")
			(net "H_DBP_PRDY_N_PCH")
		)
	)
	(footprint ""
		(layer "F.Cu")
		(at 34.177478 -439.339228 -90)
		(property "Reference" "R2987"
			(at 0 0 270)
			(layer "F.SilkS")
			(hide yes)
			(effects
				(font
					(size 1.27 1.27)
				)
			)
		)
		(property "Value" ""
			(at 0 0 270)
			(layer "F.Fab")
			(effects
				(font
					(size 1.27 1.27)
				)
			)
		)
		(duplicate_pad_numbers_are_jumpers no)
		(fp_line
			(start -0.7874 0.4064)
			(end -0.7874 -0.4064)
			(stroke
				(width 0.1524)
				(type default)
			)
			(layer "F.SilkS")
		)
		(fp_line
			(start 0.7874 0.4064)
			(end -0.7874 0.4064)
			(stroke
				(width 0.1524)
				(type default)
			)
			(layer "F.SilkS")
		)
		(fp_line
			(start -0.7874 -0.4064)
			(end 0.7874 -0.4064)
			(stroke
				(width 0.1524)
				(type default)
			)
			(layer "F.SilkS")
		)
		(fp_line
			(start 0.7874 -0.4064)
			(end 0.7874 0.4064)
			(stroke
				(width 0.1524)
				(type default)
			)
			(layer "F.SilkS")
		)
		(fp_line
			(start -0.67945 0.3048)
			(end -0.67945 -0.305054)
			(stroke
				(width 0.1)
				(type default)
			)
			(layer "F.Fab")
		)
		(fp_line
			(start -0.12065 0.3048)
			(end -0.67945 0.3048)
			(stroke
				(width 0.1)
				(type default)
			)
			(layer "F.Fab")
		)
		(fp_line
			(start 0.120396 0.3048)
			(end 0.120396 0.2794)
			(stroke
				(width 0.1)
				(type default)
			)
			(layer "F.Fab")
		)
		(fp_line
			(start 0.67945 0.3048)
			(end 0.120396 0.3048)
			(stroke
				(width 0.1)
				(type default)
			)
			(layer "F.Fab")
		)
		(fp_line
			(start -0.12065 0.2794)
			(end -0.12065 0.3048)
			(stroke
				(width 0.1)
				(type default)
			)
			(layer "F.Fab")
		)
		(fp_line
			(start 0.120396 0.2794)
			(end -0.12065 0.2794)
			(stroke
				(width 0.1)
				(type default)
			)
			(layer "F.Fab")
		)
		(fp_line
			(start -0.12065 -0.2794)
			(end 0.12065 -0.2794)
			(stroke
				(width 0.1)
				(type default)
			)
			(layer "F.Fab")
		)
		(fp_line
			(start 0.12065 -0.2794)
			(end 0.12065 -0.3048)
			(stroke
				(width 0.1)
				(type default)
			)
			(layer "F.Fab")
		)
		(fp_line
			(start 0.12065 -0.3048)
			(end 0.67945 -0.3048)
			(stroke
				(width 0.1)
				(type default)
			)
			(layer "F.Fab")
		)
		(fp_line
			(start 0.67945 -0.3048)
			(end 0.67945 0.3048)
			(stroke
				(width 0.1)
				(type default)
			)
			(layer "F.Fab")
		)
		(fp_line
			(start -0.67945 -0.305054)
			(end -0.12065 -0.305054)
			(stroke
				(width 0.1)
				(type default)
			)
			(layer "F.Fab")
		)
		(fp_line
			(start -0.12065 -0.305054)
			(end -0.12065 -0.2794)
			(stroke
				(width 0.1)
				(type default)
			)
			(layer "F.Fab")
		)
		(pad "1" smd circle
			(at -0.40005 0 270)
			(size 0 0)
			(layers "F.Cu" "F.Mask" "F.Paste")
			(net "SMB_2_BMC_GPU_R_SDA")
		)
		(pad "2" smd circle
			(at 0.40005 0 270)
			(size 0 0)
			(layers "F.Cu" "F.Mask" "F.Paste")
			(net "SMB_2_BMC_GPU_BUF_R_SDA")
		)
	)
	(footprint ""
		(layer "F.Cu")
		(at 160.782 -103.342948)
		(property "Reference" "R1751"
			(at 0 0 0)
			(layer "F.SilkS")
			(hide yes)
			(effects
				(font
					(size 1.27 1.27)
				)
			)
		)
		(property "Value" ""
			(at 0 0 0)
			(layer "F.Fab")
			(effects
				(font
					(size 1.27 1.27)
				)
			)
		)
		(duplicate_pad_numbers_are_jumpers no)
		(fp_line
			(start -0.7874 -0.4064)
			(end 0.7874 -0.4064)
			(stroke
				(width 0.1524)
				(type default)
			)
			(layer "F.SilkS")
		)
		(fp_line
			(start -0.7874 0.4064)
			(end -0.7874 -0.4064)
			(stroke
				(width 0.1524)
				(type default)
			)
			(layer "F.SilkS")
		)
		(fp_line
			(start 0.7874 -0.4064)
			(end 0.7874 0.4064)
			(stroke
				(width 0.1524)
				(type default)
			)
			(layer "F.SilkS")
		)
		(fp_line
			(start 0.7874 0.4064)
			(end -0.7874 0.4064)
			(stroke
				(width 0.1524)
				(type default)
			)
			(layer "F.SilkS")
		)
		(fp_line
			(start -0.67945 -0.305054)
			(end -0.12065 -0.305054)
			(stroke
				(width 0.1)
				(type default)
			)
			(layer "F.Fab")
		)
		(fp_line
			(start -0.67945 0.3048)
			(end -0.67945 -0.305054)
			(stroke
				(width 0.1)
				(type default)
			)
			(layer "F.Fab")
		)
		(fp_line
			(start -0.12065 -0.305054)
			(end -0.12065 -0.2794)
			(stroke
				(width 0.1)
				(type default)
			)
			(layer "F.Fab")
		)
		(fp_line
			(start -0.12065 -0.2794)
			(end 0.12065 -0.2794)
			(stroke
				(width 0.1)
				(type default)
			)
			(layer "F.Fab")
		)
		(fp_line
			(start -0.12065 0.2794)
			(end -0.12065 0.3048)
			(stroke
				(width 0.1)
				(type default)
			)
			(layer "F.Fab")
		)
		(fp_line
			(start -0.12065 0.3048)
			(end -0.67945 0.3048)
			(stroke
				(width 0.1)
				(type default)
			)
			(layer "F.Fab")
		)
		(fp_line
			(start 0.120396 0.2794)
			(end -0.12065 0.2794)
			(stroke
				(width 0.1)
				(type default)
			)
			(layer "F.Fab")
		)
		(fp_line
			(start 0.120396 0.3048)
			(end 0.120396 0.2794)
			(stroke
				(width 0.1)
				(type default)
			)
			(layer "F.Fab")
		)
		(fp_line
			(start 0.12065 -0.3048)
			(end 0.67945 -0.3048)
			(stroke
				(width 0.1)
				(type default)
			)
			(layer "F.Fab")
		)
		(fp_line
			(start 0.12065 -0.2794)
			(end 0.12065 -0.3048)
			(stroke
				(width 0.1)
				(type default)
			)
			(layer "F.Fab")
		)
		(fp_line
			(start 0.67945 -0.3048)
			(end 0.67945 0.3048)
			(stroke
				(width 0.1)
				(type default)
			)
			(layer "F.Fab")
		)
		(fp_line
			(start 0.67945 0.3048)
			(end 0.120396 0.3048)
			(stroke
				(width 0.1)
				(type default)
			)
			(layer "F.Fab")
		)
		(pad "1" smd circle
			(at -0.40005 0)
			(size 0 0)
			(layers "F.Cu" "F.Mask" "F.Paste")
			(net "SGPIO_DO_0")
		)
		(pad "2" smd circle
			(at 0.40005 0)
			(size 0 0)
			(layers "F.Cu" "F.Mask" "F.Paste")
			(net "SGPIO_DEBUG_PLD_DOUT")
		)
	)
	(footprint ""
		(layer "F.Cu")
		(at 435.997858 -106.76636 180)
		(property "Reference" "PR3798"
			(at 0 0 180)
			(layer "F.SilkS")
			(hide yes)
			(effects
				(font
					(size 1.27 1.27)
				)
			)
		)
		(property "Value" ""
			(at 0 0 180)
			(layer "F.Fab")
			(effects
				(font
					(size 1.27 1.27)
				)
			)
		)
		(duplicate_pad_numbers_are_jumpers no)
		(fp_line
			(start 0.7874 0.4064)
			(end -0.7874 0.4064)
			(stroke
				(width 0.1524)
				(type default)
			)
			(layer "F.SilkS")
		)
		(fp_line
			(start 0.7874 -0.4064)
			(end 0.7874 0.4064)
			(stroke
				(width 0.1524)
				(type default)
			)
			(layer "F.SilkS")
		)
		(fp_line
			(start -0.7874 0.4064)
			(end -0.7874 -0.4064)
			(stroke
				(width 0.1524)
				(type default)
			)
			(layer "F.SilkS")
		)
		(fp_line
			(start -0.7874 -0.4064)
			(end 0.7874 -0.4064)
			(stroke
				(width 0.1524)
				(type default)
			)
			(layer "F.SilkS")
		)
		(fp_line
			(start 0.67945 0.3048)
			(end 0.120396 0.3048)
			(stroke
				(width 0.1)
				(type default)
			)
			(layer "F.Fab")
		)
		(fp_line
			(start 0.67945 -0.3048)
			(end 0.67945 0.3048)
			(stroke
				(width 0.1)
				(type default)
			)
			(layer "F.Fab")
		)
		(fp_line
			(start 0.12065 -0.2794)
			(end 0.12065 -0.3048)
			(stroke
				(width 0.1)
				(type default)
			)
			(layer "F.Fab")
		)
		(fp_line
			(start 0.12065 -0.3048)
			(end 0.67945 -0.3048)
			(stroke
				(width 0.1)
				(type default)
			)
			(layer "F.Fab")
		)
		(fp_line
			(start 0.120396 0.3048)
			(end 0.120396 0.2794)
			(stroke
				(width 0.1)
				(type default)
			)
			(layer "F.Fab")
		)
		(fp_line
			(start 0.120396 0.2794)
			(end -0.12065 0.2794)
			(stroke
				(width 0.1)
				(type default)
			)
			(layer "F.Fab")
		)
		(fp_line
			(start -0.12065 0.3048)
			(end -0.67945 0.3048)
			(stroke
				(width 0.1)
				(type default)
			)
			(layer "F.Fab")
		)
		(fp_line
			(start -0.12065 0.2794)
			(end -0.12065 0.3048)
			(stroke
				(width 0.1)
				(type default)
			)
			(layer "F.Fab")
		)
		(fp_line
			(start -0.12065 -0.2794)
			(end 0.12065 -0.2794)
			(stroke
				(width 0.1)
				(type default)
			)
			(layer "F.Fab")
		)
		(fp_line
			(start -0.12065 -0.305054)
			(end -0.12065 -0.2794)
			(stroke
				(width 0.1)
				(type default)
			)
			(layer "F.Fab")
		)
		(fp_line
			(start -0.67945 0.3048)
			(end -0.67945 -0.305054)
			(stroke
				(width 0.1)
				(type default)
			)
			(layer "F.Fab")
		)
		(fp_line
			(start -0.67945 -0.305054)
			(end -0.12065 -0.305054)
			(stroke
				(width 0.1)
				(type default)
			)
			(layer "F.Fab")
		)
		(pad "1" smd circle
			(at -0.40005 0 180)
			(size 0 0)
			(layers "F.Cu" "F.Mask" "F.Paste")
			(net "P3V3_AUX")
		)
		(pad "2" smd circle
			(at 0.40005 0 180)
			(size 0 0)
			(layers "F.Cu" "F.Mask" "F.Paste")
			(net "P3V3_OCP_VCC_1")
		)
	)
	(footprint ""
		(layer "F.Cu")
		(at 131.75488 -92.674948 -90)
		(property "Reference" "R4407"
			(at 0 0 270)
			(layer "F.SilkS")
			(hide yes)
			(effects
				(font
					(size 1.27 1.27)
				)
			)
		)
		(property "Value" ""
			(at 0 0 270)
			(layer "F.Fab")
			(effects
				(font
					(size 1.27 1.27)
				)
			)
		)
		(duplicate_pad_numbers_are_jumpers no)
		(fp_line
			(start -0.7874 0.4064)
			(end -0.7874 -0.4064)
			(stroke
				(width 0.1524)
				(type default)
			)
			(layer "F.SilkS")
		)
		(fp_line
			(start 0.7874 0.4064)
			(end -0.7874 0.4064)
			(stroke
				(width 0.1524)
				(type default)
			)
			(layer "F.SilkS")
		)
		(fp_line
			(start -0.7874 -0.4064)
			(end 0.7874 -0.4064)
			(stroke
				(width 0.1524)
				(type default)
			)
			(layer "F.SilkS")
		)
		(fp_line
			(start 0.7874 -0.4064)
			(end 0.7874 0.4064)
			(stroke
				(width 0.1524)
				(type default)
			)
			(layer "F.SilkS")
		)
		(fp_line
			(start -0.67945 0.3048)
			(end -0.67945 -0.305054)
			(stroke
				(width 0.1)
				(type default)
			)
			(layer "F.Fab")
		)
		(fp_line
			(start -0.12065 0.3048)
			(end -0.67945 0.3048)
			(stroke
				(width 0.1)
				(type default)
			)
			(layer "F.Fab")
		)
		(fp_line
			(start 0.120396 0.3048)
			(end 0.120396 0.2794)
			(stroke
				(width 0.1)
				(type default)
			)
			(layer "F.Fab")
		)
		(fp_line
			(start 0.67945 0.3048)
			(end 0.120396 0.3048)
			(stroke
				(width 0.1)
				(type default)
			)
			(layer "F.Fab")
		)
		(fp_line
			(start -0.12065 0.2794)
			(end -0.12065 0.3048)
			(stroke
				(width 0.1)
				(type default)
			)
			(layer "F.Fab")
		)
		(fp_line
			(start 0.120396 0.2794)
			(end -0.12065 0.2794)
			(stroke
				(width 0.1)
				(type default)
			)
			(layer "F.Fab")
		)
		(fp_line
			(start -0.12065 -0.2794)
			(end 0.12065 -0.2794)
			(stroke
				(width 0.1)
				(type default)
			)
			(layer "F.Fab")
		)
		(fp_line
			(start 0.12065 -0.2794)
			(end 0.12065 -0.3048)
			(stroke
				(width 0.1)
				(type default)
			)
			(layer "F.Fab")
		)
		(fp_line
			(start 0.12065 -0.3048)
			(end 0.67945 -0.3048)
			(stroke
				(width 0.1)
				(type default)
			)
			(layer "F.Fab")
		)
		(fp_line
			(start 0.67945 -0.3048)
			(end 0.67945 0.3048)
			(stroke
				(width 0.1)
				(type default)
			)
			(layer "F.Fab")
		)
		(fp_line
			(start -0.67945 -0.305054)
			(end -0.12065 -0.305054)
			(stroke
				(width 0.1)
				(type default)
			)
			(layer "F.Fab")
		)
		(fp_line
			(start -0.12065 -0.305054)
			(end -0.12065 -0.2794)
			(stroke
				(width 0.1)
				(type default)
			)
			(layer "F.Fab")
		)
		(pad "1" smd circle
			(at -0.40005 0 270)
			(size 0 0)
			(layers "F.Cu" "F.Mask" "F.Paste")
			(net "H_CPU0_MEMHOT_OUT_VT_N")
		)
		(pad "2" smd circle
			(at 0.40005 0 270)
			(size 0 0)
			(layers "F.Cu" "F.Mask" "F.Paste")
			(net "H_CPU0_MEMHOT_OUT_LVC1_N")
		)
	)
	(footprint ""
		(layer "F.Cu")
		(at 35.176206 -133.845046 -90)
		(property "Reference" "PR273"
			(at 0 0 270)
			(layer "F.SilkS")
			(hide yes)
			(effects
				(font
					(size 1.27 1.27)
				)
			)
		)
		(property "Value" ""
			(at 0 0 270)
			(layer "F.Fab")
			(effects
				(font
					(size 1.27 1.27)
				)
			)
		)
		(duplicate_pad_numbers_are_jumpers no)
		(fp_line
			(start -0.7874 0.4064)
			(end -0.7874 -0.4064)
			(stroke
				(width 0.1524)
				(type default)
			)
			(layer "F.SilkS")
		)
		(fp_line
			(start 0.7874 0.4064)
			(end -0.7874 0.4064)
			(stroke
				(width 0.1524)
				(type default)
			)
			(layer "F.SilkS")
		)
		(fp_line
			(start -0.7874 -0.4064)
			(end 0.7874 -0.4064)
			(stroke
				(width 0.1524)
				(type default)
			)
			(layer "F.SilkS")
		)
		(fp_line
			(start 0.7874 -0.4064)
			(end 0.7874 0.4064)
			(stroke
				(width 0.1524)
				(type default)
			)
			(layer "F.SilkS")
		)
		(fp_line
			(start -0.67945 0.3048)
			(end -0.67945 -0.305054)
			(stroke
				(width 0.1)
				(type default)
			)
			(layer "F.Fab")
		)
		(fp_line
			(start -0.12065 0.3048)
			(end -0.67945 0.3048)
			(stroke
				(width 0.1)
				(type default)
			)
			(layer "F.Fab")
		)
		(fp_line
			(start 0.120396 0.3048)
			(end 0.120396 0.2794)
			(stroke
				(width 0.1)
				(type default)
			)
			(layer "F.Fab")
		)
		(fp_line
			(start 0.67945 0.3048)
			(end 0.120396 0.3048)
			(stroke
				(width 0.1)
				(type default)
			)
			(layer "F.Fab")
		)
		(fp_line
			(start -0.12065 0.2794)
			(end -0.12065 0.3048)
			(stroke
				(width 0.1)
				(type default)
			)
			(layer "F.Fab")
		)
		(fp_line
			(start 0.120396 0.2794)
			(end -0.12065 0.2794)
			(stroke
				(width 0.1)
				(type default)
			)
			(layer "F.Fab")
		)
		(fp_line
			(start -0.12065 -0.2794)
			(end 0.12065 -0.2794)
			(stroke
				(width 0.1)
				(type default)
			)
			(layer "F.Fab")
		)
		(fp_line
			(start 0.12065 -0.2794)
			(end 0.12065 -0.3048)
			(stroke
				(width 0.1)
				(type default)
			)
			(layer "F.Fab")
		)
		(fp_line
			(start 0.12065 -0.3048)
			(end 0.67945 -0.3048)
			(stroke
				(width 0.1)
				(type default)
			)
			(layer "F.Fab")
		)
		(fp_line
			(start 0.67945 -0.3048)
			(end 0.67945 0.3048)
			(stroke
				(width 0.1)
				(type default)
			)
			(layer "F.Fab")
		)
		(fp_line
			(start -0.67945 -0.305054)
			(end -0.12065 -0.305054)
			(stroke
				(width 0.1)
				(type default)
			)
			(layer "F.Fab")
		)
		(fp_line
			(start -0.12065 -0.305054)
			(end -0.12065 -0.2794)
			(stroke
				(width 0.1)
				(type default)
			)
			(layer "F.Fab")
		)
		(pad "1" smd circle
			(at -0.40005 0 270)
			(size 0 0)
			(layers "F.Cu" "F.Mask" "F.Paste")
			(net "SH_PVCCINFAON_CPU1")
		)
		(pad "2" smd circle
			(at 0.40005 0 270)
			(size 0 0)
			(layers "F.Cu" "F.Mask" "F.Paste")
			(net "SH_PVCCINFAON_CPU1_R")
		)
	)
	(footprint ""
		(layer "F.Cu")
		(at 385.716272 -61.813948)
		(property "Reference" "R764"
			(at 0 0 0)
			(layer "F.SilkS")
			(hide yes)
			(effects
				(font
					(size 1.27 1.27)
				)
			)
		)
		(property "Value" ""
			(at 0 0 0)
			(layer "F.Fab")
			(effects
				(font
					(size 1.27 1.27)
				)
			)
		)
		(duplicate_pad_numbers_are_jumpers no)
		(fp_line
			(start -0.7874 -0.4064)
			(end 0.7874 -0.4064)
			(stroke
				(width 0.1524)
				(type default)
			)
			(layer "F.SilkS")
		)
		(fp_line
			(start -0.7874 0.4064)
			(end -0.7874 -0.4064)
			(stroke
				(width 0.1524)
				(type default)
			)
			(layer "F.SilkS")
		)
		(fp_line
			(start 0.7874 -0.4064)
			(end 0.7874 0.4064)
			(stroke
				(width 0.1524)
				(type default)
			)
			(layer "F.SilkS")
		)
		(fp_line
			(start 0.7874 0.4064)
			(end -0.7874 0.4064)
			(stroke
				(width 0.1524)
				(type default)
			)
			(layer "F.SilkS")
		)
		(fp_line
			(start -0.67945 -0.305054)
			(end -0.12065 -0.305054)
			(stroke
				(width 0.1)
				(type default)
			)
			(layer "F.Fab")
		)
		(fp_line
			(start -0.67945 0.3048)
			(end -0.67945 -0.305054)
			(stroke
				(width 0.1)
				(type default)
			)
			(layer "F.Fab")
		)
		(fp_line
			(start -0.12065 -0.305054)
			(end -0.12065 -0.2794)
			(stroke
				(width 0.1)
				(type default)
			)
			(layer "F.Fab")
		)
		(fp_line
			(start -0.12065 -0.2794)
			(end 0.12065 -0.2794)
			(stroke
				(width 0.1)
				(type default)
			)
			(layer "F.Fab")
		)
		(fp_line
			(start -0.12065 0.2794)
			(end -0.12065 0.3048)
			(stroke
				(width 0.1)
				(type default)
			)
			(layer "F.Fab")
		)
		(fp_line
			(start -0.12065 0.3048)
			(end -0.67945 0.3048)
			(stroke
				(width 0.1)
				(type default)
			)
			(layer "F.Fab")
		)
		(fp_line
			(start 0.120396 0.2794)
			(end -0.12065 0.2794)
			(stroke
				(width 0.1)
				(type default)
			)
			(layer "F.Fab")
		)
		(fp_line
			(start 0.120396 0.3048)
			(end 0.120396 0.2794)
			(stroke
				(width 0.1)
				(type default)
			)
			(layer "F.Fab")
		)
		(fp_line
			(start 0.12065 -0.3048)
			(end 0.67945 -0.3048)
			(stroke
				(width 0.1)
				(type default)
			)
			(layer "F.Fab")
		)
		(fp_line
			(start 0.12065 -0.2794)
			(end 0.12065 -0.3048)
			(stroke
				(width 0.1)
				(type default)
			)
			(layer "F.Fab")
		)
		(fp_line
			(start 0.67945 -0.3048)
			(end 0.67945 0.3048)
			(stroke
				(width 0.1)
				(type default)
			)
			(layer "F.Fab")
		)
		(fp_line
			(start 0.67945 0.3048)
			(end 0.120396 0.3048)
			(stroke
				(width 0.1)
				(type default)
			)
			(layer "F.Fab")
		)
		(pad "1" smd circle
			(at -0.40005 0)
			(size 0 0)
			(layers "F.Cu" "F.Mask" "F.Paste")
			(net "JTAG_DBP_PRDY_N")
		)
		(pad "2" smd circle
			(at 0.40005 0)
			(size 0 0)
			(layers "F.Cu" "F.Mask" "F.Paste")
			(net "JTAG_DBP_PRDY_R1_N")
		)
	)
	(footprint ""
		(layer "F.Cu")
		(at 123.370848 -361.563158 90)
		(property "Reference" "PC1265"
			(at 0 0 90)
			(layer "F.SilkS")
			(hide yes)
			(effects
				(font
					(size 1.27 1.27)
				)
			)
		)
		(property "Value" ""
			(at 0 0 90)
			(layer "F.Fab")
			(effects
				(font
					(size 1.27 1.27)
				)
			)
		)
		(duplicate_pad_numbers_are_jumpers no)
		(fp_line
			(start 0.7874 -0.4064)
			(end 0.7874 0.4064)
			(stroke
				(width 0.1524)
				(type default)
			)
			(layer "F.SilkS")
		)
		(fp_line
			(start -0.7874 -0.4064)
			(end 0.7874 -0.4064)
			(stroke
				(width 0.1524)
				(type default)
			)
			(layer "F.SilkS")
		)
		(fp_line
			(start 0.7874 0.4064)
			(end -0.7874 0.4064)
			(stroke
				(width 0.1524)
				(type default)
			)
			(layer "F.SilkS")
		)
		(fp_line
			(start -0.7874 0.4064)
			(end -0.7874 -0.4064)
			(stroke
				(width 0.1524)
				(type default)
			)
			(layer "F.SilkS")
		)
		(fp_line
			(start -0.12065 -0.305054)
			(end -0.12065 -0.2794)
			(stroke
				(width 0.1)
				(type default)
			)
			(layer "F.Fab")
		)
		(fp_line
			(start -0.67945 -0.305054)
			(end -0.12065 -0.305054)
			(stroke
				(width 0.1)
				(type default)
			)
			(layer "F.Fab")
		)
		(fp_line
			(start 0.67945 -0.3048)
			(end 0.67945 0.3048)
			(stroke
				(width 0.1)
				(type default)
			)
			(layer "F.Fab")
		)
		(fp_line
			(start 0.12065 -0.3048)
			(end 0.67945 -0.3048)
			(stroke
				(width 0.1)
				(type default)
			)
			(layer "F.Fab")
		)
		(fp_line
			(start 0.12065 -0.2794)
			(end 0.12065 -0.3048)
			(stroke
				(width 0.1)
				(type default)
			)
			(layer "F.Fab")
		)
		(fp_line
			(start -0.12065 -0.2794)
			(end 0.12065 -0.2794)
			(stroke
				(width 0.1)
				(type default)
			)
			(layer "F.Fab")
		)
		(fp_line
			(start 0.120396 0.2794)
			(end -0.12065 0.2794)
			(stroke
				(width 0.1)
				(type default)
			)
			(layer "F.Fab")
		)
		(fp_line
			(start -0.12065 0.2794)
			(end -0.12065 0.3048)
			(stroke
				(width 0.1)
				(type default)
			)
			(layer "F.Fab")
		)
		(fp_line
			(start 0.67945 0.3048)
			(end 0.120396 0.3048)
			(stroke
				(width 0.1)
				(type default)
			)
			(layer "F.Fab")
		)
		(fp_line
			(start 0.120396 0.3048)
			(end 0.120396 0.2794)
			(stroke
				(width 0.1)
				(type default)
			)
			(layer "F.Fab")
		)
		(fp_line
			(start -0.12065 0.3048)
			(end -0.67945 0.3048)
			(stroke
				(width 0.1)
				(type default)
			)
			(layer "F.Fab")
		)
		(fp_line
			(start -0.67945 0.3048)
			(end -0.67945 -0.305054)
			(stroke
				(width 0.1)
				(type default)
			)
			(layer "F.Fab")
		)
		(pad "1" smd circle
			(at -0.40005 0 90)
			(size 0 0)
			(layers "F.Cu" "F.Mask" "F.Paste")
			(net "SW_PVPP_HBM_CPU1_BST")
		)
		(pad "2" smd circle
			(at 0.40005 0 90)
			(size 0 0)
			(layers "F.Cu" "F.Mask" "F.Paste")
			(net "SW_PVPP_HBM_CPU1_SW")
		)
	)
	(footprint ""
		(layer "F.Cu")
		(at 76.90231 -74.901552 -90)
		(property "Reference" "R3094"
			(at 0 0 270)
			(layer "F.SilkS")
			(hide yes)
			(effects
				(font
					(size 1.27 1.27)
				)
			)
		)
		(property "Value" ""
			(at 0 0 270)
			(layer "F.Fab")
			(effects
				(font
					(size 1.27 1.27)
				)
			)
		)
		(duplicate_pad_numbers_are_jumpers no)
		(fp_line
			(start -0.7874 0.4064)
			(end -0.7874 -0.4064)
			(stroke
				(width 0.1524)
				(type default)
			)
			(layer "F.SilkS")
		)
		(fp_line
			(start 0.7874 0.4064)
			(end -0.7874 0.4064)
			(stroke
				(width 0.1524)
				(type default)
			)
			(layer "F.SilkS")
		)
		(fp_line
			(start -0.7874 -0.4064)
			(end 0.7874 -0.4064)
			(stroke
				(width 0.1524)
				(type default)
			)
			(layer "F.SilkS")
		)
		(fp_line
			(start 0.7874 -0.4064)
			(end 0.7874 0.4064)
			(stroke
				(width 0.1524)
				(type default)
			)
			(layer "F.SilkS")
		)
		(fp_line
			(start -0.67945 0.3048)
			(end -0.67945 -0.305054)
			(stroke
				(width 0.1)
				(type default)
			)
			(layer "F.Fab")
		)
		(fp_line
			(start -0.12065 0.3048)
			(end -0.67945 0.3048)
			(stroke
				(width 0.1)
				(type default)
			)
			(layer "F.Fab")
		)
		(fp_line
			(start 0.120396 0.3048)
			(end 0.120396 0.2794)
			(stroke
				(width 0.1)
				(type default)
			)
			(layer "F.Fab")
		)
		(fp_line
			(start 0.67945 0.3048)
			(end 0.120396 0.3048)
			(stroke
				(width 0.1)
				(type default)
			)
			(layer "F.Fab")
		)
		(fp_line
			(start -0.12065 0.2794)
			(end -0.12065 0.3048)
			(stroke
				(width 0.1)
				(type default)
			)
			(layer "F.Fab")
		)
		(fp_line
			(start 0.120396 0.2794)
			(end -0.12065 0.2794)
			(stroke
				(width 0.1)
				(type default)
			)
			(layer "F.Fab")
		)
		(fp_line
			(start -0.12065 -0.2794)
			(end 0.12065 -0.2794)
			(stroke
				(width 0.1)
				(type default)
			)
			(layer "F.Fab")
		)
		(fp_line
			(start 0.12065 -0.2794)
			(end 0.12065 -0.3048)
			(stroke
				(width 0.1)
				(type default)
			)
			(layer "F.Fab")
		)
		(fp_line
			(start 0.12065 -0.3048)
			(end 0.67945 -0.3048)
			(stroke
				(width 0.1)
				(type default)
			)
			(layer "F.Fab")
		)
		(fp_line
			(start 0.67945 -0.3048)
			(end 0.67945 0.3048)
			(stroke
				(width 0.1)
				(type default)
			)
			(layer "F.Fab")
		)
		(fp_line
			(start -0.67945 -0.305054)
			(end -0.12065 -0.305054)
			(stroke
				(width 0.1)
				(type default)
			)
			(layer "F.Fab")
		)
		(fp_line
			(start -0.12065 -0.305054)
			(end -0.12065 -0.2794)
			(stroke
				(width 0.1)
				(type default)
			)
			(layer "F.Fab")
		)
		(pad "1" smd circle
			(at -0.40005 0 270)
			(size 0 0)
			(layers "F.Cu" "F.Mask" "F.Paste")
			(net "LED_PWRGD_PVPP_HBM_CPU1")
		)
		(pad "2" smd circle
			(at 0.40005 0 270)
			(size 0 0)
			(layers "F.Cu" "F.Mask" "F.Paste")
			(net "P3V3_AUX")
		)
	)
	(footprint ""
		(layer "F.Cu")
		(at 428.179992 -386.171948)
		(property "Reference" "Q71"
			(at 0.546608 -2.16789 0)
			(unlocked yes)
			(layer "F.SilkS")
			(effects
				(font
					(size 0.7874 0.5842)
					(thickness 0.1524)
				)
				(justify left)
			)
		)
		(property "Value" ""
			(at 0 0 0)
			(layer "F.Fab")
			(effects
				(font
					(size 1.27 1.27)
				)
			)
		)
		(duplicate_pad_numbers_are_jumpers no)
		(fp_line
			(start -1.332738 -1.100074)
			(end -0.4826 -1.100074)
			(stroke
				(width 0.1524)
				(type default)
			)
			(layer "F.SilkS")
		)
		(fp_line
			(start -1.332738 1.100074)
			(end -1.332738 -1.100074)
			(stroke
				(width 0.1524)
				(type default)
			)
			(layer "F.SilkS")
		)
		(fp_line
			(start -0.4826 -1.100074)
			(end 0 -0.541274)
			(stroke
				(width 0.1524)
				(type default)
			)
			(layer "F.SilkS")
		)
		(fp_line
			(start 0 -0.541274)
			(end 0.4826 -1.100074)
			(stroke
				(width 0.1524)
				(type default)
			)
			(layer "F.SilkS")
		)
		(fp_line
			(start 0.4826 -1.100074)
			(end 1.332738 -1.100074)
			(stroke
				(width 0.1524)
				(type default)
			)
			(layer "F.SilkS")
		)
		(fp_line
			(start 1.332738 -1.100074)
			(end 1.332738 1.100074)
			(stroke
				(width 0.1524)
				(type default)
			)
			(layer "F.SilkS")
		)
		(fp_line
			(start 1.332738 1.100074)
			(end -1.332738 1.100074)
			(stroke
				(width 0.1524)
				(type default)
			)
			(layer "F.SilkS")
		)
		(fp_poly
			(pts
				(xy -0.639318 -2.126488) (xy -0.990346 -1.424432) (xy -1.341374 -2.126488)
			)
			(stroke
				(width 0)
				(type default)
			)
			(fill yes)
			(layer "F.SilkS")
		)
		(fp_line
			(start -0.674878 -1.100074)
			(end 0.674878 -1.100074)
			(stroke
				(width 0.1)
				(type default)
			)
			(layer "F.Fab")
		)
		(fp_line
			(start -0.674878 1.100074)
			(end -0.674878 -1.100074)
			(stroke
				(width 0.1)
				(type default)
			)
			(layer "F.Fab")
		)
		(fp_line
			(start 0.674878 -1.100074)
			(end 0.674878 1.100074)
			(stroke
				(width 0.1)
				(type default)
			)
			(layer "F.Fab")
		)
		(fp_line
			(start 0.674878 1.100074)
			(end -0.674878 1.100074)
			(stroke
				(width 0.1)
				(type default)
			)
			(layer "F.Fab")
		)
		(fp_poly
			(pts
				(xy -2.2352 -0.298958) (xy -2.2352 -1.001014) (xy -1.533144 -0.649986)
			)
			(stroke
				(width 0)
				(type default)
			)
			(fill yes)
			(layer "F.Fab")
		)
		(pad "1" smd rect
			(at -0.94996 -0.649986 90)
			(size 0.4318 0.508)
			(layers "F.Cu" "F.Mask" "F.Paste")
			(net "GND")
		)
		(pad "2" smd rect
			(at -0.94996 0 90)
			(size 0.4318 0.508)
			(layers "F.Cu" "F.Mask" "F.Paste")
			(net "FM_SWB_PWRGD")
		)
		(pad "3" smd rect
			(at -0.94996 0.649986 90)
			(size 0.4318 0.508)
			(layers "F.Cu" "F.Mask" "F.Paste")
			(net "FM_SWB_PWRGD_ISO")
		)
		(pad "4" smd rect
			(at 0.94996 0.649986 90)
			(size 0.4318 0.508)
			(layers "F.Cu" "F.Mask" "F.Paste")
			(net "GND")
		)
		(pad "5" smd rect
			(at 0.94996 0 90)
			(size 0.4318 0.508)
			(layers "F.Cu" "F.Mask" "F.Paste")
			(net "FM_SWB_PWRGD_N")
		)
		(pad "6" smd rect
			(at 0.94996 -0.649986 90)
			(size 0.4318 0.508)
			(layers "F.Cu" "F.Mask" "F.Paste")
			(net "FM_SWB_PWRGD_N")
		)
	)
	(footprint ""
		(layer "F.Cu")
		(at 42.708576 -58.655712)
		(property "Reference" "D143"
			(at 4.258564 -0.413258 0)
			(unlocked yes)
			(layer "F.SilkS")
			(effects
				(font
					(size 0.7874 0.5842)
					(thickness 0.1524)
				)
				(justify left)
			)
		)
		(property "Value" ""
			(at 0 0 0)
			(layer "F.Fab")
			(effects
				(font
					(size 1.27 1.27)
				)
			)
		)
		(duplicate_pad_numbers_are_jumpers no)
		(fp_line
			(start -0.90678 0.4826)
			(end -0.90678 -0.4699)
			(stroke
				(width 0.1524)
				(type default)
			)
			(layer "F.SilkS")
		)
		(fp_line
			(start -0.89408 -0.4826)
			(end 0.90678 -0.4826)
			(stroke
				(width 0.1524)
				(type default)
			)
			(layer "F.SilkS")
		)
		(fp_line
			(start -0.79248 -0.4826)
			(end 1.03378 -0.4826)
			(stroke
				(width 0.1524)
				(type default)
			)
			(layer "F.SilkS")
		)
		(fp_line
			(start -0.64008 -0.4826)
			(end 1.16078 -0.4826)
			(stroke
				(width 0.1524)
				(type default)
			)
			(layer "F.SilkS")
		)
		(fp_line
			(start 0.90678 -0.4826)
			(end 0.90678 0.4826)
			(stroke
				(width 0.1524)
				(type default)
			)
			(layer "F.SilkS")
		)
		(fp_line
			(start 0.90678 0.4826)
			(end -0.90678 0.4826)
			(stroke
				(width 0.1524)
				(type default)
			)
			(layer "F.SilkS")
		)
		(fp_line
			(start 1.03378 -0.4826)
			(end 1.03378 0.4826)
			(stroke
				(width 0.1524)
				(type default)
			)
			(layer "F.SilkS")
		)
		(fp_line
			(start 1.03378 0.4826)
			(end -0.79248 0.4826)
			(stroke
				(width 0.1524)
				(type default)
			)
			(layer "F.SilkS")
		)
		(fp_line
			(start 1.16078 -0.4826)
			(end 1.16078 0.4826)
			(stroke
				(width 0.1524)
				(type default)
			)
			(layer "F.SilkS")
		)
		(fp_line
			(start 1.16078 0.4826)
			(end -0.64008 0.4826)
			(stroke
				(width 0.1524)
				(type default)
			)
			(layer "F.SilkS")
		)
		(fp_line
			(start -0.499872 -0.249936)
			(end 0.499872 -0.249936)
			(stroke
				(width 0.1)
				(type default)
			)
			(layer "F.Fab")
		)
		(fp_line
			(start -0.499872 0.249936)
			(end -0.499872 -0.249936)
			(stroke
				(width 0.1)
				(type default)
			)
			(layer "F.Fab")
		)
		(fp_line
			(start 0.499872 -0.249936)
			(end 0.499872 0.249936)
			(stroke
				(width 0.1)
				(type default)
			)
			(layer "F.Fab")
		)
		(fp_line
			(start 0.499872 0.249936)
			(end -0.499872 0.249936)
			(stroke
				(width 0.1)
				(type default)
			)
			(layer "F.Fab")
		)
		(pad "A" smd rect
			(at -0.47498 0)
			(size 0.6096 0.7112)
			(layers "F.Cu" "F.Mask" "F.Paste")
			(net "LED_P12V_PSU_R1")
		)
		(pad "C" smd rect
			(at 0.47498 0)
			(size 0.6096 0.7112)
			(layers "F.Cu" "F.Mask" "F.Paste")
			(net "GND")
		)
	)
	(footprint ""
		(layer "F.Cu")
		(at 143.90116 -112.434624)
		(property "Reference" "R4759"
			(at 0 0 0)
			(layer "F.SilkS")
			(hide yes)
			(effects
				(font
					(size 1.27 1.27)
				)
			)
		)
		(property "Value" ""
			(at 0 0 0)
			(layer "F.Fab")
			(effects
				(font
					(size 1.27 1.27)
				)
			)
		)
		(duplicate_pad_numbers_are_jumpers no)
		(fp_line
			(start -0.7874 -0.4064)
			(end 0.7874 -0.4064)
			(stroke
				(width 0.1524)
				(type default)
			)
			(layer "F.SilkS")
		)
		(fp_line
			(start -0.7874 0.4064)
			(end -0.7874 -0.4064)
			(stroke
				(width 0.1524)
				(type default)
			)
			(layer "F.SilkS")
		)
		(fp_line
			(start 0.7874 -0.4064)
			(end 0.7874 0.4064)
			(stroke
				(width 0.1524)
				(type default)
			)
			(layer "F.SilkS")
		)
		(fp_line
			(start 0.7874 0.4064)
			(end -0.7874 0.4064)
			(stroke
				(width 0.1524)
				(type default)
			)
			(layer "F.SilkS")
		)
		(fp_line
			(start -0.67945 -0.305054)
			(end -0.12065 -0.305054)
			(stroke
				(width 0.1)
				(type default)
			)
			(layer "F.Fab")
		)
		(fp_line
			(start -0.67945 0.3048)
			(end -0.67945 -0.305054)
			(stroke
				(width 0.1)
				(type default)
			)
			(layer "F.Fab")
		)
		(fp_line
			(start -0.12065 -0.305054)
			(end -0.12065 -0.2794)
			(stroke
				(width 0.1)
				(type default)
			)
			(layer "F.Fab")
		)
		(fp_line
			(start -0.12065 -0.2794)
			(end 0.12065 -0.2794)
			(stroke
				(width 0.1)
				(type default)
			)
			(layer "F.Fab")
		)
		(fp_line
			(start -0.12065 0.2794)
			(end -0.12065 0.3048)
			(stroke
				(width 0.1)
				(type default)
			)
			(layer "F.Fab")
		)
		(fp_line
			(start -0.12065 0.3048)
			(end -0.67945 0.3048)
			(stroke
				(width 0.1)
				(type default)
			)
			(layer "F.Fab")
		)
		(fp_line
			(start 0.120396 0.2794)
			(end -0.12065 0.2794)
			(stroke
				(width 0.1)
				(type default)
			)
			(layer "F.Fab")
		)
		(fp_line
			(start 0.120396 0.3048)
			(end 0.120396 0.2794)
			(stroke
				(width 0.1)
				(type default)
			)
			(layer "F.Fab")
		)
		(fp_line
			(start 0.12065 -0.3048)
			(end 0.67945 -0.3048)
			(stroke
				(width 0.1)
				(type default)
			)
			(layer "F.Fab")
		)
		(fp_line
			(start 0.12065 -0.2794)
			(end 0.12065 -0.3048)
			(stroke
				(width 0.1)
				(type default)
			)
			(layer "F.Fab")
		)
		(fp_line
			(start 0.67945 -0.3048)
			(end 0.67945 0.3048)
			(stroke
				(width 0.1)
				(type default)
			)
			(layer "F.Fab")
		)
		(fp_line
			(start 0.67945 0.3048)
			(end 0.120396 0.3048)
			(stroke
				(width 0.1)
				(type default)
			)
			(layer "F.Fab")
		)
		(pad "1" smd circle
			(at -0.40005 0)
			(size 0 0)
			(layers "F.Cu" "F.Mask" "F.Paste")
			(net "OCP_V3_2_AUX_PWR_EN_R2")
		)
		(pad "2" smd circle
			(at 0.40005 0)
			(size 0 0)
			(layers "F.Cu" "F.Mask" "F.Paste")
			(net "OCP_V3_2_AUX_PWR_EN")
		)
	)
	(footprint ""
		(layer "F.Cu")
		(at 420.14394 -109.271308 -90)
		(property "Reference" "R3845"
			(at 0 0 270)
			(layer "F.SilkS")
			(hide yes)
			(effects
				(font
					(size 1.27 1.27)
				)
			)
		)
		(property "Value" ""
			(at 0 0 270)
			(layer "F.Fab")
			(effects
				(font
					(size 1.27 1.27)
				)
			)
		)
		(duplicate_pad_numbers_are_jumpers no)
		(fp_line
			(start -0.7874 0.4064)
			(end -0.7874 -0.4064)
			(stroke
				(width 0.1524)
				(type default)
			)
			(layer "F.SilkS")
		)
		(fp_line
			(start 0.7874 0.4064)
			(end -0.7874 0.4064)
			(stroke
				(width 0.1524)
				(type default)
			)
			(layer "F.SilkS")
		)
		(fp_line
			(start -0.7874 -0.4064)
			(end 0.7874 -0.4064)
			(stroke
				(width 0.1524)
				(type default)
			)
			(layer "F.SilkS")
		)
		(fp_line
			(start 0.7874 -0.4064)
			(end 0.7874 0.4064)
			(stroke
				(width 0.1524)
				(type default)
			)
			(layer "F.SilkS")
		)
		(fp_line
			(start -0.67945 0.3048)
			(end -0.67945 -0.305054)
			(stroke
				(width 0.1)
				(type default)
			)
			(layer "F.Fab")
		)
		(fp_line
			(start -0.12065 0.3048)
			(end -0.67945 0.3048)
			(stroke
				(width 0.1)
				(type default)
			)
			(layer "F.Fab")
		)
		(fp_line
			(start 0.120396 0.3048)
			(end 0.120396 0.2794)
			(stroke
				(width 0.1)
				(type default)
			)
			(layer "F.Fab")
		)
		(fp_line
			(start 0.67945 0.3048)
			(end 0.120396 0.3048)
			(stroke
				(width 0.1)
				(type default)
			)
			(layer "F.Fab")
		)
		(fp_line
			(start -0.12065 0.2794)
			(end -0.12065 0.3048)
			(stroke
				(width 0.1)
				(type default)
			)
			(layer "F.Fab")
		)
		(fp_line
			(start 0.120396 0.2794)
			(end -0.12065 0.2794)
			(stroke
				(width 0.1)
				(type default)
			)
			(layer "F.Fab")
		)
		(fp_line
			(start -0.12065 -0.2794)
			(end 0.12065 -0.2794)
			(stroke
				(width 0.1)
				(type default)
			)
			(layer "F.Fab")
		)
		(fp_line
			(start 0.12065 -0.2794)
			(end 0.12065 -0.3048)
			(stroke
				(width 0.1)
				(type default)
			)
			(layer "F.Fab")
		)
		(fp_line
			(start 0.12065 -0.3048)
			(end 0.67945 -0.3048)
			(stroke
				(width 0.1)
				(type default)
			)
			(layer "F.Fab")
		)
		(fp_line
			(start 0.67945 -0.3048)
			(end 0.67945 0.3048)
			(stroke
				(width 0.1)
				(type default)
			)
			(layer "F.Fab")
		)
		(fp_line
			(start -0.67945 -0.305054)
			(end -0.12065 -0.305054)
			(stroke
				(width 0.1)
				(type default)
			)
			(layer "F.Fab")
		)
		(fp_line
			(start -0.12065 -0.305054)
			(end -0.12065 -0.2794)
			(stroke
				(width 0.1)
				(type default)
			)
			(layer "F.Fab")
		)
		(pad "1" smd circle
			(at -0.40005 0 270)
			(size 0 0)
			(layers "F.Cu" "F.Mask" "F.Paste")
			(net "HP_LVC3_OCP_V3_1_EN")
		)
		(pad "2" smd circle
			(at 0.40005 0 270)
			(size 0 0)
			(layers "F.Cu" "F.Mask" "F.Paste")
			(net "P3V3_OCP_EN_1_R2")
		)
	)
	(footprint ""
		(layer "F.Cu")
		(at 420.682166 -133.114034 180)
		(property "Reference" "PC223"
			(at 0 0 180)
			(layer "F.SilkS")
			(hide yes)
			(effects
				(font
					(size 1.27 1.27)
				)
			)
		)
		(property "Value" ""
			(at 0 0 180)
			(layer "F.Fab")
			(effects
				(font
					(size 1.27 1.27)
				)
			)
		)
		(duplicate_pad_numbers_are_jumpers no)
		(fp_line
			(start 0.7874 0.4064)
			(end -0.7874 0.4064)
			(stroke
				(width 0.1524)
				(type default)
			)
			(layer "F.SilkS")
		)
		(fp_line
			(start 0.7874 -0.4064)
			(end 0.7874 0.4064)
			(stroke
				(width 0.1524)
				(type default)
			)
			(layer "F.SilkS")
		)
		(fp_line
			(start -0.7874 0.4064)
			(end -0.7874 -0.4064)
			(stroke
				(width 0.1524)
				(type default)
			)
			(layer "F.SilkS")
		)
		(fp_line
			(start -0.7874 -0.4064)
			(end 0.7874 -0.4064)
			(stroke
				(width 0.1524)
				(type default)
			)
			(layer "F.SilkS")
		)
		(fp_line
			(start 0.67945 0.3048)
			(end 0.120396 0.3048)
			(stroke
				(width 0.1)
				(type default)
			)
			(layer "F.Fab")
		)
		(fp_line
			(start 0.67945 -0.3048)
			(end 0.67945 0.3048)
			(stroke
				(width 0.1)
				(type default)
			)
			(layer "F.Fab")
		)
		(fp_line
			(start 0.12065 -0.2794)
			(end 0.12065 -0.3048)
			(stroke
				(width 0.1)
				(type default)
			)
			(layer "F.Fab")
		)
		(fp_line
			(start 0.12065 -0.3048)
			(end 0.67945 -0.3048)
			(stroke
				(width 0.1)
				(type default)
			)
			(layer "F.Fab")
		)
		(fp_line
			(start 0.120396 0.3048)
			(end 0.120396 0.2794)
			(stroke
				(width 0.1)
				(type default)
			)
			(layer "F.Fab")
		)
		(fp_line
			(start 0.120396 0.2794)
			(end -0.12065 0.2794)
			(stroke
				(width 0.1)
				(type default)
			)
			(layer "F.Fab")
		)
		(fp_line
			(start -0.12065 0.3048)
			(end -0.67945 0.3048)
			(stroke
				(width 0.1)
				(type default)
			)
			(layer "F.Fab")
		)
		(fp_line
			(start -0.12065 0.2794)
			(end -0.12065 0.3048)
			(stroke
				(width 0.1)
				(type default)
			)
			(layer "F.Fab")
		)
		(fp_line
			(start -0.12065 -0.2794)
			(end 0.12065 -0.2794)
			(stroke
				(width 0.1)
				(type default)
			)
			(layer "F.Fab")
		)
		(fp_line
			(start -0.12065 -0.305054)
			(end -0.12065 -0.2794)
			(stroke
				(width 0.1)
				(type default)
			)
			(layer "F.Fab")
		)
		(fp_line
			(start -0.67945 0.3048)
			(end -0.67945 -0.305054)
			(stroke
				(width 0.1)
				(type default)
			)
			(layer "F.Fab")
		)
		(fp_line
			(start -0.67945 -0.305054)
			(end -0.12065 -0.305054)
			(stroke
				(width 0.1)
				(type default)
			)
			(layer "F.Fab")
		)
		(pad "1" smd circle
			(at -0.40005 0 180)
			(size 0 0)
			(layers "F.Cu" "F.Mask" "F.Paste")
			(net "PVCCINFAON_CPU0_VCC")
		)
		(pad "2" smd circle
			(at 0.40005 0 180)
			(size 0 0)
			(layers "F.Cu" "F.Mask" "F.Paste")
			(net "GND")
		)
	)
	(footprint ""
		(layer "F.Cu")
		(at 120.187974 -338.86013)
		(property "Reference" "PR297"
			(at 0 0 0)
			(layer "F.SilkS")
			(hide yes)
			(effects
				(font
					(size 1.27 1.27)
				)
			)
		)
		(property "Value" ""
			(at 0 0 0)
			(layer "F.Fab")
			(effects
				(font
					(size 1.27 1.27)
				)
			)
		)
		(duplicate_pad_numbers_are_jumpers no)
		(fp_line
			(start -0.7874 -0.4064)
			(end 0.7874 -0.4064)
			(stroke
				(width 0.1524)
				(type default)
			)
			(layer "F.SilkS")
		)
		(fp_line
			(start -0.7874 0.4064)
			(end -0.7874 -0.4064)
			(stroke
				(width 0.1524)
				(type default)
			)
			(layer "F.SilkS")
		)
		(fp_line
			(start 0.7874 -0.4064)
			(end 0.7874 0.4064)
			(stroke
				(width 0.1524)
				(type default)
			)
			(layer "F.SilkS")
		)
		(fp_line
			(start 0.7874 0.4064)
			(end -0.7874 0.4064)
			(stroke
				(width 0.1524)
				(type default)
			)
			(layer "F.SilkS")
		)
		(fp_line
			(start -0.67945 -0.305054)
			(end -0.12065 -0.305054)
			(stroke
				(width 0.1)
				(type default)
			)
			(layer "F.Fab")
		)
		(fp_line
			(start -0.67945 0.3048)
			(end -0.67945 -0.305054)
			(stroke
				(width 0.1)
				(type default)
			)
			(layer "F.Fab")
		)
		(fp_line
			(start -0.12065 -0.305054)
			(end -0.12065 -0.2794)
			(stroke
				(width 0.1)
				(type default)
			)
			(layer "F.Fab")
		)
		(fp_line
			(start -0.12065 -0.2794)
			(end 0.12065 -0.2794)
			(stroke
				(width 0.1)
				(type default)
			)
			(layer "F.Fab")
		)
		(fp_line
			(start -0.12065 0.2794)
			(end -0.12065 0.3048)
			(stroke
				(width 0.1)
				(type default)
			)
			(layer "F.Fab")
		)
		(fp_line
			(start -0.12065 0.3048)
			(end -0.67945 0.3048)
			(stroke
				(width 0.1)
				(type default)
			)
			(layer "F.Fab")
		)
		(fp_line
			(start 0.120396 0.2794)
			(end -0.12065 0.2794)
			(stroke
				(width 0.1)
				(type default)
			)
			(layer "F.Fab")
		)
		(fp_line
			(start 0.120396 0.3048)
			(end 0.120396 0.2794)
			(stroke
				(width 0.1)
				(type default)
			)
			(layer "F.Fab")
		)
		(fp_line
			(start 0.12065 -0.3048)
			(end 0.67945 -0.3048)
			(stroke
				(width 0.1)
				(type default)
			)
			(layer "F.Fab")
		)
		(fp_line
			(start 0.12065 -0.2794)
			(end 0.12065 -0.3048)
			(stroke
				(width 0.1)
				(type default)
			)
			(layer "F.Fab")
		)
		(fp_line
			(start 0.67945 -0.3048)
			(end 0.67945 0.3048)
			(stroke
				(width 0.1)
				(type default)
			)
			(layer "F.Fab")
		)
		(fp_line
			(start 0.67945 0.3048)
			(end 0.120396 0.3048)
			(stroke
				(width 0.1)
				(type default)
			)
			(layer "F.Fab")
		)
		(pad "1" smd circle
			(at -0.40005 0)
			(size 0 0)
			(layers "F.Cu" "F.Mask" "F.Paste")
			(net "PVCCIN_CPU1_LSET4")
		)
		(pad "2" smd circle
			(at 0.40005 0)
			(size 0 0)
			(layers "F.Cu" "F.Mask" "F.Paste")
			(net "GND")
		)
	)
	(footprint ""
		(layer "F.Cu")
		(at 24.71928 -176.850548 180)
		(property "Reference" "PC28"
			(at 0 0 180)
			(layer "F.SilkS")
			(hide yes)
			(effects
				(font
					(size 1.27 1.27)
				)
			)
		)
		(property "Value" ""
			(at 0 0 180)
			(layer "F.Fab")
			(effects
				(font
					(size 1.27 1.27)
				)
			)
		)
		(duplicate_pad_numbers_are_jumpers no)
		(fp_line
			(start 0.7874 0.4064)
			(end -0.7874 0.4064)
			(stroke
				(width 0.1524)
				(type default)
			)
			(layer "F.SilkS")
		)
		(fp_line
			(start 0.7874 -0.4064)
			(end 0.7874 0.4064)
			(stroke
				(width 0.1524)
				(type default)
			)
			(layer "F.SilkS")
		)
		(fp_line
			(start -0.7874 0.4064)
			(end -0.7874 -0.4064)
			(stroke
				(width 0.1524)
				(type default)
			)
			(layer "F.SilkS")
		)
		(fp_line
			(start -0.7874 -0.4064)
			(end 0.7874 -0.4064)
			(stroke
				(width 0.1524)
				(type default)
			)
			(layer "F.SilkS")
		)
		(fp_line
			(start 0.67945 0.3048)
			(end 0.120396 0.3048)
			(stroke
				(width 0.1)
				(type default)
			)
			(layer "F.Fab")
		)
		(fp_line
			(start 0.67945 -0.3048)
			(end 0.67945 0.3048)
			(stroke
				(width 0.1)
				(type default)
			)
			(layer "F.Fab")
		)
		(fp_line
			(start 0.12065 -0.2794)
			(end 0.12065 -0.3048)
			(stroke
				(width 0.1)
				(type default)
			)
			(layer "F.Fab")
		)
		(fp_line
			(start 0.12065 -0.3048)
			(end 0.67945 -0.3048)
			(stroke
				(width 0.1)
				(type default)
			)
			(layer "F.Fab")
		)
		(fp_line
			(start 0.120396 0.3048)
			(end 0.120396 0.2794)
			(stroke
				(width 0.1)
				(type default)
			)
			(layer "F.Fab")
		)
		(fp_line
			(start 0.120396 0.2794)
			(end -0.12065 0.2794)
			(stroke
				(width 0.1)
				(type default)
			)
			(layer "F.Fab")
		)
		(fp_line
			(start -0.12065 0.3048)
			(end -0.67945 0.3048)
			(stroke
				(width 0.1)
				(type default)
			)
			(layer "F.Fab")
		)
		(fp_line
			(start -0.12065 0.2794)
			(end -0.12065 0.3048)
			(stroke
				(width 0.1)
				(type default)
			)
			(layer "F.Fab")
		)
		(fp_line
			(start -0.12065 -0.2794)
			(end 0.12065 -0.2794)
			(stroke
				(width 0.1)
				(type default)
			)
			(layer "F.Fab")
		)
		(fp_line
			(start -0.12065 -0.305054)
			(end -0.12065 -0.2794)
			(stroke
				(width 0.1)
				(type default)
			)
			(layer "F.Fab")
		)
		(fp_line
			(start -0.67945 0.3048)
			(end -0.67945 -0.305054)
			(stroke
				(width 0.1)
				(type default)
			)
			(layer "F.Fab")
		)
		(fp_line
			(start -0.67945 -0.305054)
			(end -0.12065 -0.305054)
			(stroke
				(width 0.1)
				(type default)
			)
			(layer "F.Fab")
		)
		(pad "1" smd circle
			(at -0.40005 0 180)
			(size 0 0)
			(layers "F.Cu" "F.Mask" "F.Paste")
			(net "PVNN_MAIN_CPU1_REF")
		)
		(pad "2" smd circle
			(at 0.40005 0 180)
			(size 0 0)
			(layers "F.Cu" "F.Mask" "F.Paste")
			(net "GND")
		)
	)
	(footprint ""
		(layer "F.Cu")
		(at 80.681068 -333.61884)
		(property "Reference" "PL25"
			(at -2.416556 6.896354 0)
			(unlocked yes)
			(layer "F.SilkS")
			(effects
				(font
					(size 0.7874 0.5842)
					(thickness 0.1524)
				)
				(justify left)
			)
		)
		(property "Value" ""
			(at 0 0 0)
			(layer "F.Fab")
			(effects
				(font
					(size 1.27 1.27)
				)
			)
		)
		(duplicate_pad_numbers_are_jumpers no)
		(fp_line
			(start -3.750056 -5.500116)
			(end -2.393442 -5.500116)
			(stroke
				(width 0.1524)
				(type default)
			)
			(layer "F.SilkS")
		)
		(fp_line
			(start -3.750056 5.500116)
			(end -3.750056 -5.500116)
			(stroke
				(width 0.1524)
				(type default)
			)
			(layer "F.SilkS")
		)
		(fp_line
			(start -2.393442 5.500116)
			(end -3.750056 5.500116)
			(stroke
				(width 0.1524)
				(type default)
			)
			(layer "F.SilkS")
		)
		(fp_line
			(start 2.393442 5.500116)
			(end 3.750056 5.500116)
			(stroke
				(width 0.1524)
				(type default)
			)
			(layer "F.SilkS")
		)
		(fp_line
			(start 3.750056 -5.500116)
			(end 2.393442 -5.500116)
			(stroke
				(width 0.1524)
				(type default)
			)
			(layer "F.SilkS")
		)
		(fp_line
			(start 3.750056 5.500116)
			(end 3.750056 -5.500116)
			(stroke
				(width 0.1524)
				(type default)
			)
			(layer "F.SilkS")
		)
		(fp_poly
			(pts
				(xy -3.607054 -7.02945) (xy -3.247898 -5.951728) (xy -4.32562 -6.310884)
			)
			(stroke
				(width 0)
				(type default)
			)
			(fill yes)
			(layer "F.SilkS")
		)
		(fp_line
			(start -3.750056 -5.500116)
			(end -3.750056 5.500116)
			(stroke
				(width 0.1)
				(type default)
			)
			(layer "F.Fab")
		)
		(fp_line
			(start -3.750056 5.500116)
			(end 3.750056 5.500116)
			(stroke
				(width 0.1)
				(type default)
			)
			(layer "F.Fab")
		)
		(fp_line
			(start 3.750056 -5.500116)
			(end -3.750056 -5.500116)
			(stroke
				(width 0.1)
				(type default)
			)
			(layer "F.Fab")
		)
		(fp_line
			(start 3.750056 5.500116)
			(end 3.750056 -5.500116)
			(stroke
				(width 0.1)
				(type default)
			)
			(layer "F.Fab")
		)
		(fp_poly
			(pts
				(xy -4.9276 -4.757928) (xy -4.9276 -3.741928) (xy -3.9116 -4.249928)
			)
			(stroke
				(width 0)
				(type default)
			)
			(fill yes)
			(layer "F.Fab")
		)
		(pad "1" smd rect
			(at 0 -4.249928 270)
			(size 2.413 4.5212)
			(layers "F.Cu" "F.Mask" "F.Paste")
			(net "SW_PVCCIN_CPU1_SW7")
		)
		(pad "2" smd rect
			(at 0 -1.175004 270)
			(size 1.3716 4.5212)
			(layers "F.Cu" "F.Mask" "F.Paste")
			(net "IND_P1_CPL7")
		)
		(pad "3" smd rect
			(at 0 1.175004 270)
			(size 1.3716 4.5212)
			(layers "F.Cu" "F.Mask" "F.Paste")
			(net "GND")
		)
		(pad "4" smd rect
			(at 0 4.249928 270)
			(size 2.413 4.5212)
			(layers "F.Cu" "F.Mask" "F.Paste")
			(net "PVCCIN_CPU1")
		)
	)
	(footprint ""
		(layer "F.Cu")
		(at 448.478402 -77.829918 90)
		(property "Reference" "PR831"
			(at 0 0 90)
			(layer "F.SilkS")
			(hide yes)
			(effects
				(font
					(size 1.27 1.27)
				)
			)
		)
		(property "Value" ""
			(at 0 0 90)
			(layer "F.Fab")
			(effects
				(font
					(size 1.27 1.27)
				)
			)
		)
		(duplicate_pad_numbers_are_jumpers no)
		(fp_line
			(start 0.7874 -0.4064)
			(end 0.7874 0.4064)
			(stroke
				(width 0.1524)
				(type default)
			)
			(layer "F.SilkS")
		)
		(fp_line
			(start -0.7874 -0.4064)
			(end 0.7874 -0.4064)
			(stroke
				(width 0.1524)
				(type default)
			)
			(layer "F.SilkS")
		)
		(fp_line
			(start 0.7874 0.4064)
			(end -0.7874 0.4064)
			(stroke
				(width 0.1524)
				(type default)
			)
			(layer "F.SilkS")
		)
		(fp_line
			(start -0.7874 0.4064)
			(end -0.7874 -0.4064)
			(stroke
				(width 0.1524)
				(type default)
			)
			(layer "F.SilkS")
		)
		(fp_line
			(start -0.12065 -0.305054)
			(end -0.12065 -0.2794)
			(stroke
				(width 0.1)
				(type default)
			)
			(layer "F.Fab")
		)
		(fp_line
			(start -0.67945 -0.305054)
			(end -0.12065 -0.305054)
			(stroke
				(width 0.1)
				(type default)
			)
			(layer "F.Fab")
		)
		(fp_line
			(start 0.67945 -0.3048)
			(end 0.67945 0.3048)
			(stroke
				(width 0.1)
				(type default)
			)
			(layer "F.Fab")
		)
		(fp_line
			(start 0.12065 -0.3048)
			(end 0.67945 -0.3048)
			(stroke
				(width 0.1)
				(type default)
			)
			(layer "F.Fab")
		)
		(fp_line
			(start 0.12065 -0.2794)
			(end 0.12065 -0.3048)
			(stroke
				(width 0.1)
				(type default)
			)
			(layer "F.Fab")
		)
		(fp_line
			(start -0.12065 -0.2794)
			(end 0.12065 -0.2794)
			(stroke
				(width 0.1)
				(type default)
			)
			(layer "F.Fab")
		)
		(fp_line
			(start 0.120396 0.2794)
			(end -0.12065 0.2794)
			(stroke
				(width 0.1)
				(type default)
			)
			(layer "F.Fab")
		)
		(fp_line
			(start -0.12065 0.2794)
			(end -0.12065 0.3048)
			(stroke
				(width 0.1)
				(type default)
			)
			(layer "F.Fab")
		)
		(fp_line
			(start 0.67945 0.3048)
			(end 0.120396 0.3048)
			(stroke
				(width 0.1)
				(type default)
			)
			(layer "F.Fab")
		)
		(fp_line
			(start 0.120396 0.3048)
			(end 0.120396 0.2794)
			(stroke
				(width 0.1)
				(type default)
			)
			(layer "F.Fab")
		)
		(fp_line
			(start -0.12065 0.3048)
			(end -0.67945 0.3048)
			(stroke
				(width 0.1)
				(type default)
			)
			(layer "F.Fab")
		)
		(fp_line
			(start -0.67945 0.3048)
			(end -0.67945 -0.305054)
			(stroke
				(width 0.1)
				(type default)
			)
			(layer "F.Fab")
		)
		(pad "1" smd circle
			(at -0.40005 0 90)
			(size 0 0)
			(layers "F.Cu" "F.Mask" "F.Paste")
			(net "P3V3_AUX_FB")
		)
		(pad "2" smd circle
			(at 0.40005 0 90)
			(size 0 0)
			(layers "F.Cu" "F.Mask" "F.Paste")
			(net "P3V3_AUX")
		)
	)
	(footprint ""
		(layer "F.Cu")
		(at 131.466844 -127.119126 180)
		(property "Reference" "R2985"
			(at 0 0 180)
			(layer "F.SilkS")
			(hide yes)
			(effects
				(font
					(size 1.27 1.27)
				)
			)
		)
		(property "Value" ""
			(at 0 0 180)
			(layer "F.Fab")
			(effects
				(font
					(size 1.27 1.27)
				)
			)
		)
		(duplicate_pad_numbers_are_jumpers no)
		(fp_line
			(start 0.7874 0.4064)
			(end -0.7874 0.4064)
			(stroke
				(width 0.1524)
				(type default)
			)
			(layer "F.SilkS")
		)
		(fp_line
			(start 0.7874 -0.4064)
			(end 0.7874 0.4064)
			(stroke
				(width 0.1524)
				(type default)
			)
			(layer "F.SilkS")
		)
		(fp_line
			(start -0.7874 0.4064)
			(end -0.7874 -0.4064)
			(stroke
				(width 0.1524)
				(type default)
			)
			(layer "F.SilkS")
		)
		(fp_line
			(start -0.7874 -0.4064)
			(end 0.7874 -0.4064)
			(stroke
				(width 0.1524)
				(type default)
			)
			(layer "F.SilkS")
		)
		(fp_line
			(start 0.67945 0.3048)
			(end 0.120396 0.3048)
			(stroke
				(width 0.1)
				(type default)
			)
			(layer "F.Fab")
		)
		(fp_line
			(start 0.67945 -0.3048)
			(end 0.67945 0.3048)
			(stroke
				(width 0.1)
				(type default)
			)
			(layer "F.Fab")
		)
		(fp_line
			(start 0.12065 -0.2794)
			(end 0.12065 -0.3048)
			(stroke
				(width 0.1)
				(type default)
			)
			(layer "F.Fab")
		)
		(fp_line
			(start 0.12065 -0.3048)
			(end 0.67945 -0.3048)
			(stroke
				(width 0.1)
				(type default)
			)
			(layer "F.Fab")
		)
		(fp_line
			(start 0.120396 0.3048)
			(end 0.120396 0.2794)
			(stroke
				(width 0.1)
				(type default)
			)
			(layer "F.Fab")
		)
		(fp_line
			(start 0.120396 0.2794)
			(end -0.12065 0.2794)
			(stroke
				(width 0.1)
				(type default)
			)
			(layer "F.Fab")
		)
		(fp_line
			(start -0.12065 0.3048)
			(end -0.67945 0.3048)
			(stroke
				(width 0.1)
				(type default)
			)
			(layer "F.Fab")
		)
		(fp_line
			(start -0.12065 0.2794)
			(end -0.12065 0.3048)
			(stroke
				(width 0.1)
				(type default)
			)
			(layer "F.Fab")
		)
		(fp_line
			(start -0.12065 -0.2794)
			(end 0.12065 -0.2794)
			(stroke
				(width 0.1)
				(type default)
			)
			(layer "F.Fab")
		)
		(fp_line
			(start -0.12065 -0.305054)
			(end -0.12065 -0.2794)
			(stroke
				(width 0.1)
				(type default)
			)
			(layer "F.Fab")
		)
		(fp_line
			(start -0.67945 0.3048)
			(end -0.67945 -0.305054)
			(stroke
				(width 0.1)
				(type default)
			)
			(layer "F.Fab")
		)
		(fp_line
			(start -0.67945 -0.305054)
			(end -0.12065 -0.305054)
			(stroke
				(width 0.1)
				(type default)
			)
			(layer "F.Fab")
		)
		(pad "1" smd circle
			(at -0.40005 0 180)
			(size 0 0)
			(layers "F.Cu" "F.Mask" "F.Paste")
			(net "P3V3_AUX")
		)
		(pad "2" smd circle
			(at 0.40005 0 180)
			(size 0 0)
			(layers "F.Cu" "F.Mask" "F.Paste")
			(net "SMB_BMC_SWB_SDA")
		)
	)
	(footprint ""
		(layer "F.Cu")
		(at 424.204892 -395.619478)
		(property "Reference" "R3437"
			(at 0 0 0)
			(layer "F.SilkS")
			(hide yes)
			(effects
				(font
					(size 1.27 1.27)
				)
			)
		)
		(property "Value" ""
			(at 0 0 0)
			(layer "F.Fab")
			(effects
				(font
					(size 1.27 1.27)
				)
			)
		)
		(duplicate_pad_numbers_are_jumpers no)
		(fp_line
			(start -0.7874 -0.4064)
			(end 0.7874 -0.4064)
			(stroke
				(width 0.1524)
				(type default)
			)
			(layer "F.SilkS")
		)
		(fp_line
			(start -0.7874 0.4064)
			(end -0.7874 -0.4064)
			(stroke
				(width 0.1524)
				(type default)
			)
			(layer "F.SilkS")
		)
		(fp_line
			(start 0.7874 -0.4064)
			(end 0.7874 0.4064)
			(stroke
				(width 0.1524)
				(type default)
			)
			(layer "F.SilkS")
		)
		(fp_line
			(start 0.7874 0.4064)
			(end -0.7874 0.4064)
			(stroke
				(width 0.1524)
				(type default)
			)
			(layer "F.SilkS")
		)
		(fp_line
			(start -0.67945 -0.305054)
			(end -0.12065 -0.305054)
			(stroke
				(width 0.1)
				(type default)
			)
			(layer "F.Fab")
		)
		(fp_line
			(start -0.67945 0.3048)
			(end -0.67945 -0.305054)
			(stroke
				(width 0.1)
				(type default)
			)
			(layer "F.Fab")
		)
		(fp_line
			(start -0.12065 -0.305054)
			(end -0.12065 -0.2794)
			(stroke
				(width 0.1)
				(type default)
			)
			(layer "F.Fab")
		)
		(fp_line
			(start -0.12065 -0.2794)
			(end 0.12065 -0.2794)
			(stroke
				(width 0.1)
				(type default)
			)
			(layer "F.Fab")
		)
		(fp_line
			(start -0.12065 0.2794)
			(end -0.12065 0.3048)
			(stroke
				(width 0.1)
				(type default)
			)
			(layer "F.Fab")
		)
		(fp_line
			(start -0.12065 0.3048)
			(end -0.67945 0.3048)
			(stroke
				(width 0.1)
				(type default)
			)
			(layer "F.Fab")
		)
		(fp_line
			(start 0.120396 0.2794)
			(end -0.12065 0.2794)
			(stroke
				(width 0.1)
				(type default)
			)
			(layer "F.Fab")
		)
		(fp_line
			(start 0.120396 0.3048)
			(end 0.120396 0.2794)
			(stroke
				(width 0.1)
				(type default)
			)
			(layer "F.Fab")
		)
		(fp_line
			(start 0.12065 -0.3048)
			(end 0.67945 -0.3048)
			(stroke
				(width 0.1)
				(type default)
			)
			(layer "F.Fab")
		)
		(fp_line
			(start 0.12065 -0.2794)
			(end 0.12065 -0.3048)
			(stroke
				(width 0.1)
				(type default)
			)
			(layer "F.Fab")
		)
		(fp_line
			(start 0.67945 -0.3048)
			(end 0.67945 0.3048)
			(stroke
				(width 0.1)
				(type default)
			)
			(layer "F.Fab")
		)
		(fp_line
			(start 0.67945 0.3048)
			(end 0.120396 0.3048)
			(stroke
				(width 0.1)
				(type default)
			)
			(layer "F.Fab")
		)
		(pad "1" smd circle
			(at -0.40005 0)
			(size 0 0)
			(layers "F.Cu" "F.Mask" "F.Paste")
			(net "P3V3_AUX")
		)
		(pad "2" smd circle
			(at 0.40005 0)
			(size 0 0)
			(layers "F.Cu" "F.Mask" "F.Paste")
			(net "GPU_FPGA_OVERT_ISO_N")
		)
	)
	(footprint ""
		(layer "F.Cu")
		(at 23.890478 -17.623536 90)
		(property "Reference" "C812"
			(at 0 0 90)
			(layer "F.SilkS")
			(hide yes)
			(effects
				(font
					(size 1.27 1.27)
				)
			)
		)
		(property "Value" ""
			(at 0 0 90)
			(layer "F.Fab")
			(effects
				(font
					(size 1.27 1.27)
				)
			)
		)
		(duplicate_pad_numbers_are_jumpers no)
		(fp_line
			(start 0.299974 -0.150114)
			(end 0.299974 0.150114)
			(stroke
				(width 0.1)
				(type default)
			)
			(layer "F.Fab")
		)
		(fp_line
			(start -0.299974 -0.150114)
			(end 0.299974 -0.150114)
			(stroke
				(width 0.1)
				(type default)
			)
			(layer "F.Fab")
		)
		(fp_line
			(start 0.299974 0.150114)
			(end -0.299974 0.150114)
			(stroke
				(width 0.1)
				(type default)
			)
			(layer "F.Fab")
		)
		(fp_line
			(start -0.299974 0.150114)
			(end -0.299974 -0.150114)
			(stroke
				(width 0.1)
				(type default)
			)
			(layer "F.Fab")
		)
		(pad "1" smd rect
			(at -0.2667 0 90)
			(size 0.3048 0.381)
			(layers "F.Cu" "F.Mask" "F.Paste")
			(net "P5E_CPU1_PE1_TX_C_DN<12>")
		)
		(pad "2" smd rect
			(at 0.2667 0 90)
			(size 0.3048 0.381)
			(layers "F.Cu" "F.Mask" "F.Paste")
			(net "P5E_CPU1_PE1_TX_DN<12>")
		)
	)
	(footprint ""
		(layer "F.Cu")
		(at 356.616 -415.127948)
		(property "Reference" "R4561"
			(at 0 0 0)
			(layer "F.SilkS")
			(hide yes)
			(effects
				(font
					(size 1.27 1.27)
				)
			)
		)
		(property "Value" ""
			(at 0 0 0)
			(layer "F.Fab")
			(effects
				(font
					(size 1.27 1.27)
				)
			)
		)
		(duplicate_pad_numbers_are_jumpers no)
		(fp_line
			(start -0.7874 -0.4064)
			(end 0.7874 -0.4064)
			(stroke
				(width 0.1524)
				(type default)
			)
			(layer "F.SilkS")
		)
		(fp_line
			(start -0.7874 0.4064)
			(end -0.7874 -0.4064)
			(stroke
				(width 0.1524)
				(type default)
			)
			(layer "F.SilkS")
		)
		(fp_line
			(start 0.7874 -0.4064)
			(end 0.7874 0.4064)
			(stroke
				(width 0.1524)
				(type default)
			)
			(layer "F.SilkS")
		)
		(fp_line
			(start 0.7874 0.4064)
			(end -0.7874 0.4064)
			(stroke
				(width 0.1524)
				(type default)
			)
			(layer "F.SilkS")
		)
		(fp_line
			(start -0.67945 -0.305054)
			(end -0.12065 -0.305054)
			(stroke
				(width 0.1)
				(type default)
			)
			(layer "F.Fab")
		)
		(fp_line
			(start -0.67945 0.3048)
			(end -0.67945 -0.305054)
			(stroke
				(width 0.1)
				(type default)
			)
			(layer "F.Fab")
		)
		(fp_line
			(start -0.12065 -0.305054)
			(end -0.12065 -0.2794)
			(stroke
				(width 0.1)
				(type default)
			)
			(layer "F.Fab")
		)
		(fp_line
			(start -0.12065 -0.2794)
			(end 0.12065 -0.2794)
			(stroke
				(width 0.1)
				(type default)
			)
			(layer "F.Fab")
		)
		(fp_line
			(start -0.12065 0.2794)
			(end -0.12065 0.3048)
			(stroke
				(width 0.1)
				(type default)
			)
			(layer "F.Fab")
		)
		(fp_line
			(start -0.12065 0.3048)
			(end -0.67945 0.3048)
			(stroke
				(width 0.1)
				(type default)
			)
			(layer "F.Fab")
		)
		(fp_line
			(start 0.120396 0.2794)
			(end -0.12065 0.2794)
			(stroke
				(width 0.1)
				(type default)
			)
			(layer "F.Fab")
		)
		(fp_line
			(start 0.120396 0.3048)
			(end 0.120396 0.2794)
			(stroke
				(width 0.1)
				(type default)
			)
			(layer "F.Fab")
		)
		(fp_line
			(start 0.12065 -0.3048)
			(end 0.67945 -0.3048)
			(stroke
				(width 0.1)
				(type default)
			)
			(layer "F.Fab")
		)
		(fp_line
			(start 0.12065 -0.2794)
			(end 0.12065 -0.3048)
			(stroke
				(width 0.1)
				(type default)
			)
			(layer "F.Fab")
		)
		(fp_line
			(start 0.67945 -0.3048)
			(end 0.67945 0.3048)
			(stroke
				(width 0.1)
				(type default)
			)
			(layer "F.Fab")
		)
		(fp_line
			(start 0.67945 0.3048)
			(end 0.120396 0.3048)
			(stroke
				(width 0.1)
				(type default)
			)
			(layer "F.Fab")
		)
		(pad "1" smd circle
			(at -0.40005 0)
			(size 0 0)
			(layers "F.Cu" "F.Mask" "F.Paste")
			(net "P3V3_AUX")
		)
		(pad "2" smd circle
			(at 0.40005 0)
			(size 0 0)
			(layers "F.Cu" "F.Mask" "F.Paste")
			(net "SWB_HSC_PWRGD_ISO")
		)
	)
	(footprint ""
		(layer "F.Cu")
		(at 36.956238 -131.77774 180)
		(property "Reference" "R2561"
			(at 0 0 180)
			(layer "F.SilkS")
			(hide yes)
			(effects
				(font
					(size 1.27 1.27)
				)
			)
		)
		(property "Value" ""
			(at 0 0 180)
			(layer "F.Fab")
			(effects
				(font
					(size 1.27 1.27)
				)
			)
		)
		(duplicate_pad_numbers_are_jumpers no)
		(fp_line
			(start 0.7874 0.4064)
			(end -0.7874 0.4064)
			(stroke
				(width 0.1524)
				(type default)
			)
			(layer "F.SilkS")
		)
		(fp_line
			(start 0.7874 -0.4064)
			(end 0.7874 0.4064)
			(stroke
				(width 0.1524)
				(type default)
			)
			(layer "F.SilkS")
		)
		(fp_line
			(start -0.7874 0.4064)
			(end -0.7874 -0.4064)
			(stroke
				(width 0.1524)
				(type default)
			)
			(layer "F.SilkS")
		)
		(fp_line
			(start -0.7874 -0.4064)
			(end 0.7874 -0.4064)
			(stroke
				(width 0.1524)
				(type default)
			)
			(layer "F.SilkS")
		)
		(fp_line
			(start 0.67945 0.3048)
			(end 0.120396 0.3048)
			(stroke
				(width 0.1)
				(type default)
			)
			(layer "F.Fab")
		)
		(fp_line
			(start 0.67945 -0.3048)
			(end 0.67945 0.3048)
			(stroke
				(width 0.1)
				(type default)
			)
			(layer "F.Fab")
		)
		(fp_line
			(start 0.12065 -0.2794)
			(end 0.12065 -0.3048)
			(stroke
				(width 0.1)
				(type default)
			)
			(layer "F.Fab")
		)
		(fp_line
			(start 0.12065 -0.3048)
			(end 0.67945 -0.3048)
			(stroke
				(width 0.1)
				(type default)
			)
			(layer "F.Fab")
		)
		(fp_line
			(start 0.120396 0.3048)
			(end 0.120396 0.2794)
			(stroke
				(width 0.1)
				(type default)
			)
			(layer "F.Fab")
		)
		(fp_line
			(start 0.120396 0.2794)
			(end -0.12065 0.2794)
			(stroke
				(width 0.1)
				(type default)
			)
			(layer "F.Fab")
		)
		(fp_line
			(start -0.12065 0.3048)
			(end -0.67945 0.3048)
			(stroke
				(width 0.1)
				(type default)
			)
			(layer "F.Fab")
		)
		(fp_line
			(start -0.12065 0.2794)
			(end -0.12065 0.3048)
			(stroke
				(width 0.1)
				(type default)
			)
			(layer "F.Fab")
		)
		(fp_line
			(start -0.12065 -0.2794)
			(end 0.12065 -0.2794)
			(stroke
				(width 0.1)
				(type default)
			)
			(layer "F.Fab")
		)
		(fp_line
			(start -0.12065 -0.305054)
			(end -0.12065 -0.2794)
			(stroke
				(width 0.1)
				(type default)
			)
			(layer "F.Fab")
		)
		(fp_line
			(start -0.67945 0.3048)
			(end -0.67945 -0.305054)
			(stroke
				(width 0.1)
				(type default)
			)
			(layer "F.Fab")
		)
		(fp_line
			(start -0.67945 -0.305054)
			(end -0.12065 -0.305054)
			(stroke
				(width 0.1)
				(type default)
			)
			(layer "F.Fab")
		)
		(pad "1" smd circle
			(at -0.40005 0 180)
			(size 0 0)
			(layers "F.Cu" "F.Mask" "F.Paste")
			(net "SVID_ALERT0_CPU1_R_N")
		)
		(pad "2" smd circle
			(at 0.40005 0 180)
			(size 0 0)
			(layers "F.Cu" "F.Mask" "F.Paste")
			(net "SVID_ALERT_PVCCINFAON_CPU1_R")
		)
	)
	(footprint ""
		(layer "F.Cu")
		(at 157.02788 -112.486948)
		(property "Reference" "R3481"
			(at 0 0 0)
			(layer "F.SilkS")
			(hide yes)
			(effects
				(font
					(size 1.27 1.27)
				)
			)
		)
		(property "Value" ""
			(at 0 0 0)
			(layer "F.Fab")
			(effects
				(font
					(size 1.27 1.27)
				)
			)
		)
		(duplicate_pad_numbers_are_jumpers no)
		(fp_line
			(start -0.7874 -0.4064)
			(end 0.7874 -0.4064)
			(stroke
				(width 0.1524)
				(type default)
			)
			(layer "F.SilkS")
		)
		(fp_line
			(start -0.7874 0.4064)
			(end -0.7874 -0.4064)
			(stroke
				(width 0.1524)
				(type default)
			)
			(layer "F.SilkS")
		)
		(fp_line
			(start 0.7874 -0.4064)
			(end 0.7874 0.4064)
			(stroke
				(width 0.1524)
				(type default)
			)
			(layer "F.SilkS")
		)
		(fp_line
			(start 0.7874 0.4064)
			(end -0.7874 0.4064)
			(stroke
				(width 0.1524)
				(type default)
			)
			(layer "F.SilkS")
		)
		(fp_line
			(start -0.67945 -0.305054)
			(end -0.12065 -0.305054)
			(stroke
				(width 0.1)
				(type default)
			)
			(layer "F.Fab")
		)
		(fp_line
			(start -0.67945 0.3048)
			(end -0.67945 -0.305054)
			(stroke
				(width 0.1)
				(type default)
			)
			(layer "F.Fab")
		)
		(fp_line
			(start -0.12065 -0.305054)
			(end -0.12065 -0.2794)
			(stroke
				(width 0.1)
				(type default)
			)
			(layer "F.Fab")
		)
		(fp_line
			(start -0.12065 -0.2794)
			(end 0.12065 -0.2794)
			(stroke
				(width 0.1)
				(type default)
			)
			(layer "F.Fab")
		)
		(fp_line
			(start -0.12065 0.2794)
			(end -0.12065 0.3048)
			(stroke
				(width 0.1)
				(type default)
			)
			(layer "F.Fab")
		)
		(fp_line
			(start -0.12065 0.3048)
			(end -0.67945 0.3048)
			(stroke
				(width 0.1)
				(type default)
			)
			(layer "F.Fab")
		)
		(fp_line
			(start 0.120396 0.2794)
			(end -0.12065 0.2794)
			(stroke
				(width 0.1)
				(type default)
			)
			(layer "F.Fab")
		)
		(fp_line
			(start 0.120396 0.3048)
			(end 0.120396 0.2794)
			(stroke
				(width 0.1)
				(type default)
			)
			(layer "F.Fab")
		)
		(fp_line
			(start 0.12065 -0.3048)
			(end 0.67945 -0.3048)
			(stroke
				(width 0.1)
				(type default)
			)
			(layer "F.Fab")
		)
		(fp_line
			(start 0.12065 -0.2794)
			(end 0.12065 -0.3048)
			(stroke
				(width 0.1)
				(type default)
			)
			(layer "F.Fab")
		)
		(fp_line
			(start 0.67945 -0.3048)
			(end 0.67945 0.3048)
			(stroke
				(width 0.1)
				(type default)
			)
			(layer "F.Fab")
		)
		(fp_line
			(start 0.67945 0.3048)
			(end 0.120396 0.3048)
			(stroke
				(width 0.1)
				(type default)
			)
			(layer "F.Fab")
		)
		(pad "1" smd circle
			(at -0.40005 0)
			(size 0 0)
			(layers "F.Cu" "F.Mask" "F.Paste")
			(net "GPU_HMC_PRSNT_ISO_N")
		)
		(pad "2" smd circle
			(at 0.40005 0)
			(size 0 0)
			(layers "F.Cu" "F.Mask" "F.Paste")
			(net "GPU_HMC_PRSNT_ISO_R_N")
		)
	)
	(footprint ""
		(layer "F.Cu")
		(at 369.2652 -407.67)
		(property "Reference" "Q153"
			(at -1.8288 -3.086608 0)
			(unlocked yes)
			(layer "F.SilkS")
			(effects
				(font
					(size 0.7874 0.5842)
					(thickness 0.1524)
				)
				(justify left)
			)
		)
		(property "Value" ""
			(at 0 0 0)
			(layer "F.Fab")
			(effects
				(font
					(size 1.27 1.27)
				)
			)
		)
		(duplicate_pad_numbers_are_jumpers no)
		(fp_line
			(start -1.332738 -1.100074)
			(end -0.4826 -1.100074)
			(stroke
				(width 0.1524)
				(type default)
			)
			(layer "F.SilkS")
		)
		(fp_line
			(start -1.332738 1.100074)
			(end -1.332738 -1.100074)
			(stroke
				(width 0.1524)
				(type default)
			)
			(layer "F.SilkS")
		)
		(fp_line
			(start -0.4826 -1.100074)
			(end 0 -0.541274)
			(stroke
				(width 0.1524)
				(type default)
			)
			(layer "F.SilkS")
		)
		(fp_line
			(start 0 -0.541274)
			(end 0.4826 -1.100074)
			(stroke
				(width 0.1524)
				(type default)
			)
			(layer "F.SilkS")
		)
		(fp_line
			(start 0.4826 -1.100074)
			(end 1.332738 -1.100074)
			(stroke
				(width 0.1524)
				(type default)
			)
			(layer "F.SilkS")
		)
		(fp_line
			(start 1.332738 -1.100074)
			(end 1.332738 1.100074)
			(stroke
				(width 0.1524)
				(type default)
			)
			(layer "F.SilkS")
		)
		(fp_line
			(start 1.332738 1.100074)
			(end -1.332738 1.100074)
			(stroke
				(width 0.1524)
				(type default)
			)
			(layer "F.SilkS")
		)
		(fp_poly
			(pts
				(xy -1.804924 -1.575816) (xy -1.308608 -2.072386) (xy -1.060196 -1.327658)
			)
			(stroke
				(width 0)
				(type default)
			)
			(fill yes)
			(layer "F.SilkS")
		)
		(fp_line
			(start -0.674878 -1.100074)
			(end 0.674878 -1.100074)
			(stroke
				(width 0.1)
				(type default)
			)
			(layer "F.Fab")
		)
		(fp_line
			(start -0.674878 1.100074)
			(end -0.674878 -1.100074)
			(stroke
				(width 0.1)
				(type default)
			)
			(layer "F.Fab")
		)
		(fp_line
			(start 0.674878 -1.100074)
			(end 0.674878 1.100074)
			(stroke
				(width 0.1)
				(type default)
			)
			(layer "F.Fab")
		)
		(fp_line
			(start 0.674878 1.100074)
			(end -0.674878 1.100074)
			(stroke
				(width 0.1)
				(type default)
			)
			(layer "F.Fab")
		)
		(fp_poly
			(pts
				(xy -2.2352 -0.298958) (xy -2.2352 -1.001014) (xy -1.533144 -0.649986)
			)
			(stroke
				(width 0)
				(type default)
			)
			(fill yes)
			(layer "F.Fab")
		)
		(pad "1" smd rect
			(at -0.94996 -0.649986 90)
			(size 0.4318 0.508)
			(layers "F.Cu" "F.Mask" "F.Paste")
			(net "GND")
		)
		(pad "2" smd rect
			(at -0.94996 0 90)
			(size 0.4318 0.508)
			(layers "F.Cu" "F.Mask" "F.Paste")
			(net "PRSNT_CABLE_SWB_B1_N")
		)
		(pad "3" smd rect
			(at -0.94996 0.649986 90)
			(size 0.4318 0.508)
			(layers "F.Cu" "F.Mask" "F.Paste")
			(net "PRSNT_CABLE_SWB_B1_ISO_N")
		)
		(pad "4" smd rect
			(at 0.94996 0.649986 90)
			(size 0.4318 0.508)
			(layers "F.Cu" "F.Mask" "F.Paste")
			(net "GND")
		)
		(pad "5" smd rect
			(at 0.94996 0 90)
			(size 0.4318 0.508)
			(layers "F.Cu" "F.Mask" "F.Paste")
			(net "PRSNT_CABLE_SWB_B1")
		)
		(pad "6" smd rect
			(at 0.94996 -0.649986 90)
			(size 0.4318 0.508)
			(layers "F.Cu" "F.Mask" "F.Paste")
			(net "PRSNT_CABLE_SWB_B1")
		)
	)
	(footprint ""
		(layer "F.Cu")
		(at 215.95588 -34.508948 180)
		(property "Reference" "R3592"
			(at 0 0 180)
			(layer "F.SilkS")
			(hide yes)
			(effects
				(font
					(size 1.27 1.27)
				)
			)
		)
		(property "Value" ""
			(at 0 0 180)
			(layer "F.Fab")
			(effects
				(font
					(size 1.27 1.27)
				)
			)
		)
		(duplicate_pad_numbers_are_jumpers no)
		(fp_line
			(start 0.7874 0.4064)
			(end -0.7874 0.4064)
			(stroke
				(width 0.1524)
				(type default)
			)
			(layer "F.SilkS")
		)
		(fp_line
			(start 0.7874 -0.4064)
			(end 0.7874 0.4064)
			(stroke
				(width 0.1524)
				(type default)
			)
			(layer "F.SilkS")
		)
		(fp_line
			(start -0.7874 0.4064)
			(end -0.7874 -0.4064)
			(stroke
				(width 0.1524)
				(type default)
			)
			(layer "F.SilkS")
		)
		(fp_line
			(start -0.7874 -0.4064)
			(end 0.7874 -0.4064)
			(stroke
				(width 0.1524)
				(type default)
			)
			(layer "F.SilkS")
		)
		(fp_line
			(start 0.67945 0.3048)
			(end 0.120396 0.3048)
			(stroke
				(width 0.1)
				(type default)
			)
			(layer "F.Fab")
		)
		(fp_line
			(start 0.67945 -0.3048)
			(end 0.67945 0.3048)
			(stroke
				(width 0.1)
				(type default)
			)
			(layer "F.Fab")
		)
		(fp_line
			(start 0.12065 -0.2794)
			(end 0.12065 -0.3048)
			(stroke
				(width 0.1)
				(type default)
			)
			(layer "F.Fab")
		)
		(fp_line
			(start 0.12065 -0.3048)
			(end 0.67945 -0.3048)
			(stroke
				(width 0.1)
				(type default)
			)
			(layer "F.Fab")
		)
		(fp_line
			(start 0.120396 0.3048)
			(end 0.120396 0.2794)
			(stroke
				(width 0.1)
				(type default)
			)
			(layer "F.Fab")
		)
		(fp_line
			(start 0.120396 0.2794)
			(end -0.12065 0.2794)
			(stroke
				(width 0.1)
				(type default)
			)
			(layer "F.Fab")
		)
		(fp_line
			(start -0.12065 0.3048)
			(end -0.67945 0.3048)
			(stroke
				(width 0.1)
				(type default)
			)
			(layer "F.Fab")
		)
		(fp_line
			(start -0.12065 0.2794)
			(end -0.12065 0.3048)
			(stroke
				(width 0.1)
				(type default)
			)
			(layer "F.Fab")
		)
		(fp_line
			(start -0.12065 -0.2794)
			(end 0.12065 -0.2794)
			(stroke
				(width 0.1)
				(type default)
			)
			(layer "F.Fab")
		)
		(fp_line
			(start -0.12065 -0.305054)
			(end -0.12065 -0.2794)
			(stroke
				(width 0.1)
				(type default)
			)
			(layer "F.Fab")
		)
		(fp_line
			(start -0.67945 0.3048)
			(end -0.67945 -0.305054)
			(stroke
				(width 0.1)
				(type default)
			)
			(layer "F.Fab")
		)
		(fp_line
			(start -0.67945 -0.305054)
			(end -0.12065 -0.305054)
			(stroke
				(width 0.1)
				(type default)
			)
			(layer "F.Fab")
		)
		(pad "1" smd circle
			(at -0.40005 0 180)
			(size 0 0)
			(layers "F.Cu" "F.Mask" "F.Paste")
			(net "SMB_INA230_3V3AUX_SCL")
		)
		(pad "2" smd circle
			(at 0.40005 0 180)
			(size 0 0)
			(layers "F.Cu" "F.Mask" "F.Paste")
			(net "SMB_INA230_5_3V3AUX_SCL_R")
		)
	)
	(footprint ""
		(layer "F.Cu")
		(at 463.215736 -385.742434 90)
		(property "Reference" "PC1849"
			(at 0 0 90)
			(layer "F.SilkS")
			(hide yes)
			(effects
				(font
					(size 1.27 1.27)
				)
			)
		)
		(property "Value" ""
			(at 0 0 90)
			(layer "F.Fab")
			(effects
				(font
					(size 1.27 1.27)
				)
			)
		)
		(duplicate_pad_numbers_are_jumpers no)
		(fp_line
			(start 1.524 -0.762)
			(end 1.524 0.762)
			(stroke
				(width 0.1524)
				(type default)
			)
			(layer "F.SilkS")
		)
		(fp_line
			(start -1.524 -0.762)
			(end 1.524 -0.762)
			(stroke
				(width 0.1524)
				(type default)
			)
			(layer "F.SilkS")
		)
		(fp_line
			(start 1.524 0.762)
			(end -1.524 0.762)
			(stroke
				(width 0.1524)
				(type default)
			)
			(layer "F.SilkS")
		)
		(fp_line
			(start -1.524 0.762)
			(end -1.524 -0.762)
			(stroke
				(width 0.1524)
				(type default)
			)
			(layer "F.SilkS")
		)
		(fp_line
			(start 1.1049 -0.724916)
			(end -1.1049 -0.724916)
			(stroke
				(width 0.1)
				(type default)
			)
			(layer "F.Fab")
		)
		(fp_line
			(start -1.1049 -0.724916)
			(end -1.1049 0.724916)
			(stroke
				(width 0.1)
				(type default)
			)
			(layer "F.Fab")
		)
		(fp_line
			(start 1.1049 0.724916)
			(end 1.1049 -0.724916)
			(stroke
				(width 0.1)
				(type default)
			)
			(layer "F.Fab")
		)
		(fp_line
			(start -1.1049 0.724916)
			(end 1.1049 0.724916)
			(stroke
				(width 0.1)
				(type default)
			)
			(layer "F.Fab")
		)
		(pad "1" smd rect
			(at -0.889 0 270)
			(size 1.016 1.27)
			(layers "F.Cu" "F.Mask" "F.Paste")
			(net "SW_P5V_AUX_FLT")
		)
		(pad "2" smd rect
			(at 0.889 0 270)
			(size 1.016 1.27)
			(layers "F.Cu" "F.Mask" "F.Paste")
			(net "GND")
		)
	)
	(footprint ""
		(layer "F.Cu")
		(at 62.35446 -165.11397)
		(property "Reference" "PL17"
			(at -4.10718 -4.488688 0)
			(unlocked yes)
			(layer "F.SilkS")
			(effects
				(font
					(size 0.7874 0.5842)
					(thickness 0.1524)
				)
				(justify left)
			)
		)
		(property "Value" ""
			(at 0 0 0)
			(layer "F.Fab")
			(effects
				(font
					(size 1.27 1.27)
				)
			)
		)
		(duplicate_pad_numbers_are_jumpers no)
		(fp_line
			(start -3.24993 -3.24993)
			(end 3.24993 -3.24993)
			(stroke
				(width 0.1524)
				(type default)
			)
			(layer "F.SilkS")
		)
		(fp_line
			(start -3.24993 -2.2352)
			(end -3.24993 -3.24993)
			(stroke
				(width 0.1524)
				(type default)
			)
			(layer "F.SilkS")
		)
		(fp_line
			(start -3.24993 3.24993)
			(end -3.24993 2.2352)
			(stroke
				(width 0.1524)
				(type default)
			)
			(layer "F.SilkS")
		)
		(fp_line
			(start 3.24993 -3.24993)
			(end 3.24993 -2.2352)
			(stroke
				(width 0.1524)
				(type default)
			)
			(layer "F.SilkS")
		)
		(fp_line
			(start 3.24993 2.2352)
			(end 3.24993 3.24993)
			(stroke
				(width 0.1524)
				(type default)
			)
			(layer "F.SilkS")
		)
		(fp_line
			(start 3.24993 3.24993)
			(end -3.24993 3.24993)
			(stroke
				(width 0.1524)
				(type default)
			)
			(layer "F.SilkS")
		)
		(fp_line
			(start -3.24993 -3.24993)
			(end 3.24993 -3.24993)
			(stroke
				(width 0.1)
				(type default)
			)
			(layer "F.Fab")
		)
		(fp_line
			(start -3.24993 3.24993)
			(end -3.24993 -3.24993)
			(stroke
				(width 0.1)
				(type default)
			)
			(layer "F.Fab")
		)
		(fp_line
			(start 3.24993 -3.24993)
			(end 3.24993 3.24993)
			(stroke
				(width 0.1)
				(type default)
			)
			(layer "F.Fab")
		)
		(fp_line
			(start 3.24993 3.24993)
			(end -3.24993 3.24993)
			(stroke
				(width 0.1)
				(type default)
			)
			(layer "F.Fab")
		)
		(pad "1" smd rect
			(at -2.29997 0)
			(size 2.0066 4.2164)
			(layers "F.Cu" "F.Mask" "F.Paste")
			(net "SW_PVCCD_HV_CPU1_SW1")
		)
		(pad "2" smd rect
			(at 2.29997 0)
			(size 2.0066 4.2164)
			(layers "F.Cu" "F.Mask" "F.Paste")
			(net "PVCCD_HV_CPU1")
		)
	)
	(footprint ""
		(layer "F.Cu")
		(at 126.396242 -354.844858)
		(property "Reference" "PC1259"
			(at 0 0 0)
			(layer "F.SilkS")
			(hide yes)
			(effects
				(font
					(size 1.27 1.27)
				)
			)
		)
		(property "Value" ""
			(at 0 0 0)
			(layer "F.Fab")
			(effects
				(font
					(size 1.27 1.27)
				)
			)
		)
		(duplicate_pad_numbers_are_jumpers no)
		(fp_line
			(start -1.524 -0.762)
			(end 1.524 -0.762)
			(stroke
				(width 0.1524)
				(type default)
			)
			(layer "F.SilkS")
		)
		(fp_line
			(start -1.524 0.762)
			(end -1.524 -0.762)
			(stroke
				(width 0.1524)
				(type default)
			)
			(layer "F.SilkS")
		)
		(fp_line
			(start 1.524 -0.762)
			(end 1.524 0.762)
			(stroke
				(width 0.1524)
				(type default)
			)
			(layer "F.SilkS")
		)
		(fp_line
			(start 1.524 0.762)
			(end -1.524 0.762)
			(stroke
				(width 0.1524)
				(type default)
			)
			(layer "F.SilkS")
		)
		(fp_line
			(start -1.1049 -0.724916)
			(end -1.1049 0.724916)
			(stroke
				(width 0.1)
				(type default)
			)
			(layer "F.Fab")
		)
		(fp_line
			(start -1.1049 0.724916)
			(end 1.1049 0.724916)
			(stroke
				(width 0.1)
				(type default)
			)
			(layer "F.Fab")
		)
		(fp_line
			(start 1.1049 -0.724916)
			(end -1.1049 -0.724916)
			(stroke
				(width 0.1)
				(type default)
			)
			(layer "F.Fab")
		)
		(fp_line
			(start 1.1049 0.724916)
			(end 1.1049 -0.724916)
			(stroke
				(width 0.1)
				(type default)
			)
			(layer "F.Fab")
		)
		(pad "1" smd rect
			(at -0.889 0 180)
			(size 1.016 1.27)
			(layers "F.Cu" "F.Mask" "F.Paste")
			(net "SW_P12V_PVCCIN_CPU1_FLT")
		)
		(pad "2" smd rect
			(at 0.889 0 180)
			(size 1.016 1.27)
			(layers "F.Cu" "F.Mask" "F.Paste")
			(net "GND")
		)
	)
	(footprint ""
		(layer "F.Cu")
		(at 48.581818 -178.060604 90)
		(property "Reference" "PC430"
			(at 0 0 90)
			(layer "F.SilkS")
			(hide yes)
			(effects
				(font
					(size 1.27 1.27)
				)
			)
		)
		(property "Value" ""
			(at 0 0 90)
			(layer "F.Fab")
			(effects
				(font
					(size 1.27 1.27)
				)
			)
		)
		(duplicate_pad_numbers_are_jumpers no)
		(fp_line
			(start 0.7874 -0.4064)
			(end 0.7874 0.4064)
			(stroke
				(width 0.1524)
				(type default)
			)
			(layer "F.SilkS")
		)
		(fp_line
			(start -0.7874 -0.4064)
			(end 0.7874 -0.4064)
			(stroke
				(width 0.1524)
				(type default)
			)
			(layer "F.SilkS")
		)
		(fp_line
			(start 0.7874 0.4064)
			(end -0.7874 0.4064)
			(stroke
				(width 0.1524)
				(type default)
			)
			(layer "F.SilkS")
		)
		(fp_line
			(start -0.7874 0.4064)
			(end -0.7874 -0.4064)
			(stroke
				(width 0.1524)
				(type default)
			)
			(layer "F.SilkS")
		)
		(fp_line
			(start -0.12065 -0.305054)
			(end -0.12065 -0.2794)
			(stroke
				(width 0.1)
				(type default)
			)
			(layer "F.Fab")
		)
		(fp_line
			(start -0.67945 -0.305054)
			(end -0.12065 -0.305054)
			(stroke
				(width 0.1)
				(type default)
			)
			(layer "F.Fab")
		)
		(fp_line
			(start 0.67945 -0.3048)
			(end 0.67945 0.3048)
			(stroke
				(width 0.1)
				(type default)
			)
			(layer "F.Fab")
		)
		(fp_line
			(start 0.12065 -0.3048)
			(end 0.67945 -0.3048)
			(stroke
				(width 0.1)
				(type default)
			)
			(layer "F.Fab")
		)
		(fp_line
			(start 0.12065 -0.2794)
			(end 0.12065 -0.3048)
			(stroke
				(width 0.1)
				(type default)
			)
			(layer "F.Fab")
		)
		(fp_line
			(start -0.12065 -0.2794)
			(end 0.12065 -0.2794)
			(stroke
				(width 0.1)
				(type default)
			)
			(layer "F.Fab")
		)
		(fp_line
			(start 0.120396 0.2794)
			(end -0.12065 0.2794)
			(stroke
				(width 0.1)
				(type default)
			)
			(layer "F.Fab")
		)
		(fp_line
			(start -0.12065 0.2794)
			(end -0.12065 0.3048)
			(stroke
				(width 0.1)
				(type default)
			)
			(layer "F.Fab")
		)
		(fp_line
			(start 0.67945 0.3048)
			(end 0.120396 0.3048)
			(stroke
				(width 0.1)
				(type default)
			)
			(layer "F.Fab")
		)
		(fp_line
			(start 0.120396 0.3048)
			(end 0.120396 0.2794)
			(stroke
				(width 0.1)
				(type default)
			)
			(layer "F.Fab")
		)
		(fp_line
			(start -0.12065 0.3048)
			(end -0.67945 0.3048)
			(stroke
				(width 0.1)
				(type default)
			)
			(layer "F.Fab")
		)
		(fp_line
			(start -0.67945 0.3048)
			(end -0.67945 -0.305054)
			(stroke
				(width 0.1)
				(type default)
			)
			(layer "F.Fab")
		)
		(pad "1" smd circle
			(at -0.40005 0 90)
			(size 0 0)
			(layers "F.Cu" "F.Mask" "F.Paste")
			(net "SW_P12V_PVCCINFAON_CPU1_FLT")
		)
		(pad "2" smd circle
			(at 0.40005 0 90)
			(size 0 0)
			(layers "F.Cu" "F.Mask" "F.Paste")
			(net "GND")
		)
	)
	(footprint ""
		(layer "F.Cu")
		(at 371.297962 -361.570778 90)
		(property "Reference" "PC1252"
			(at 0 0 90)
			(layer "F.SilkS")
			(hide yes)
			(effects
				(font
					(size 1.27 1.27)
				)
			)
		)
		(property "Value" ""
			(at 0 0 90)
			(layer "F.Fab")
			(effects
				(font
					(size 1.27 1.27)
				)
			)
		)
		(duplicate_pad_numbers_are_jumpers no)
		(fp_line
			(start 0.7874 -0.4064)
			(end 0.7874 0.4064)
			(stroke
				(width 0.1524)
				(type default)
			)
			(layer "F.SilkS")
		)
		(fp_line
			(start -0.7874 -0.4064)
			(end 0.7874 -0.4064)
			(stroke
				(width 0.1524)
				(type default)
			)
			(layer "F.SilkS")
		)
		(fp_line
			(start 0.7874 0.4064)
			(end -0.7874 0.4064)
			(stroke
				(width 0.1524)
				(type default)
			)
			(layer "F.SilkS")
		)
		(fp_line
			(start -0.7874 0.4064)
			(end -0.7874 -0.4064)
			(stroke
				(width 0.1524)
				(type default)
			)
			(layer "F.SilkS")
		)
		(fp_line
			(start -0.12065 -0.305054)
			(end -0.12065 -0.2794)
			(stroke
				(width 0.1)
				(type default)
			)
			(layer "F.Fab")
		)
		(fp_line
			(start -0.67945 -0.305054)
			(end -0.12065 -0.305054)
			(stroke
				(width 0.1)
				(type default)
			)
			(layer "F.Fab")
		)
		(fp_line
			(start 0.67945 -0.3048)
			(end 0.67945 0.3048)
			(stroke
				(width 0.1)
				(type default)
			)
			(layer "F.Fab")
		)
		(fp_line
			(start 0.12065 -0.3048)
			(end 0.67945 -0.3048)
			(stroke
				(width 0.1)
				(type default)
			)
			(layer "F.Fab")
		)
		(fp_line
			(start 0.12065 -0.2794)
			(end 0.12065 -0.3048)
			(stroke
				(width 0.1)
				(type default)
			)
			(layer "F.Fab")
		)
		(fp_line
			(start -0.12065 -0.2794)
			(end 0.12065 -0.2794)
			(stroke
				(width 0.1)
				(type default)
			)
			(layer "F.Fab")
		)
		(fp_line
			(start 0.120396 0.2794)
			(end -0.12065 0.2794)
			(stroke
				(width 0.1)
				(type default)
			)
			(layer "F.Fab")
		)
		(fp_line
			(start -0.12065 0.2794)
			(end -0.12065 0.3048)
			(stroke
				(width 0.1)
				(type default)
			)
			(layer "F.Fab")
		)
		(fp_line
			(start 0.67945 0.3048)
			(end 0.120396 0.3048)
			(stroke
				(width 0.1)
				(type default)
			)
			(layer "F.Fab")
		)
		(fp_line
			(start 0.120396 0.3048)
			(end 0.120396 0.2794)
			(stroke
				(width 0.1)
				(type default)
			)
			(layer "F.Fab")
		)
		(fp_line
			(start -0.12065 0.3048)
			(end -0.67945 0.3048)
			(stroke
				(width 0.1)
				(type default)
			)
			(layer "F.Fab")
		)
		(fp_line
			(start -0.67945 0.3048)
			(end -0.67945 -0.305054)
			(stroke
				(width 0.1)
				(type default)
			)
			(layer "F.Fab")
		)
		(pad "1" smd circle
			(at -0.40005 0 90)
			(size 0 0)
			(layers "F.Cu" "F.Mask" "F.Paste")
			(net "SW_PVPP_HBM_CPU0_BST")
		)
		(pad "2" smd circle
			(at 0.40005 0 90)
			(size 0 0)
			(layers "F.Cu" "F.Mask" "F.Paste")
			(net "SW_PVPP_HBM_CPU0_SW")
		)
	)
	(footprint ""
		(layer "F.Cu")
		(at 350.75876 -352.02114 180)
		(property "Reference" "PJ47"
			(at 2.338324 -1.363472 0)
			(unlocked yes)
			(layer "F.SilkS")
			(effects
				(font
					(size 0.7874 0.5842)
					(thickness 0.1524)
				)
				(justify left)
			)
		)
		(property "Value" ""
			(at 0 0 180)
			(layer "F.Fab")
			(effects
				(font
					(size 1.27 1.27)
				)
			)
		)
		(duplicate_pad_numbers_are_jumpers no)
		(pad "1" smd circle
			(at -0.7493 0 270)
			(size 0 0)
			(layers "F.Cu" "F.Mask" "F.Paste")
			(net "VSENSE_PVCCIN_CPU0_DP")
		)
		(pad "2" smd rect
			(at 0.7493 0 90)
			(size 0.7112 0.8128)
			(layers "F.Cu" "F.Mask" "F.Paste")
			(net "SH_PVCCIN_CPU0")
		)
		(zone
			(layer "F.Cu")
			(hatch none 0.5)
			(connect_pads
				(clearance 0)
			)
			(min_thickness 0.25)
			(keepout
				(tracks allowed)
				(vias not_allowed)
				(pads allowed)
				(copperpour not_allowed)
				(footprints allowed)
			)
			(placement
				(enabled no)
				(sheetname "")
			)
			(fill
				(thermal_gap 0.5)
				(thermal_bridge_width 0.5)
				(island_removal_mode 0)
			)
			(polygon
				(pts
					(xy 349.55226 -351.61474) (xy 351.93986 -351.61474) (xy 351.93986 -352.432366) (xy 349.55226 -352.432366)
				)
			)
		)
	)
	(footprint ""
		(layer "F.Cu")
		(at 119.508016 -245.634256 -90)
		(property "Reference" "C429"
			(at 0 0 270)
			(layer "F.SilkS")
			(hide yes)
			(effects
				(font
					(size 1.27 1.27)
				)
			)
		)
		(property "Value" ""
			(at 0 0 270)
			(layer "F.Fab")
			(effects
				(font
					(size 1.27 1.27)
				)
			)
		)
		(duplicate_pad_numbers_are_jumpers no)
		(fp_line
			(start -0.7874 0.4064)
			(end -0.7874 -0.4064)
			(stroke
				(width 0.1524)
				(type default)
			)
			(layer "F.SilkS")
		)
		(fp_line
			(start 0.7874 0.4064)
			(end -0.7874 0.4064)
			(stroke
				(width 0.1524)
				(type default)
			)
			(layer "F.SilkS")
		)
		(fp_line
			(start -0.7874 -0.4064)
			(end 0.7874 -0.4064)
			(stroke
				(width 0.1524)
				(type default)
			)
			(layer "F.SilkS")
		)
		(fp_line
			(start 0.7874 -0.4064)
			(end 0.7874 0.4064)
			(stroke
				(width 0.1524)
				(type default)
			)
			(layer "F.SilkS")
		)
		(fp_line
			(start -0.67945 0.3048)
			(end -0.67945 -0.305054)
			(stroke
				(width 0.1)
				(type default)
			)
			(layer "F.Fab")
		)
		(fp_line
			(start -0.12065 0.3048)
			(end -0.67945 0.3048)
			(stroke
				(width 0.1)
				(type default)
			)
			(layer "F.Fab")
		)
		(fp_line
			(start 0.120396 0.3048)
			(end 0.120396 0.2794)
			(stroke
				(width 0.1)
				(type default)
			)
			(layer "F.Fab")
		)
		(fp_line
			(start 0.67945 0.3048)
			(end 0.120396 0.3048)
			(stroke
				(width 0.1)
				(type default)
			)
			(layer "F.Fab")
		)
		(fp_line
			(start -0.12065 0.2794)
			(end -0.12065 0.3048)
			(stroke
				(width 0.1)
				(type default)
			)
			(layer "F.Fab")
		)
		(fp_line
			(start 0.120396 0.2794)
			(end -0.12065 0.2794)
			(stroke
				(width 0.1)
				(type default)
			)
			(layer "F.Fab")
		)
		(fp_line
			(start -0.12065 -0.2794)
			(end 0.12065 -0.2794)
			(stroke
				(width 0.1)
				(type default)
			)
			(layer "F.Fab")
		)
		(fp_line
			(start 0.12065 -0.2794)
			(end 0.12065 -0.3048)
			(stroke
				(width 0.1)
				(type default)
			)
			(layer "F.Fab")
		)
		(fp_line
			(start 0.12065 -0.3048)
			(end 0.67945 -0.3048)
			(stroke
				(width 0.1)
				(type default)
			)
			(layer "F.Fab")
		)
		(fp_line
			(start 0.67945 -0.3048)
			(end 0.67945 0.3048)
			(stroke
				(width 0.1)
				(type default)
			)
			(layer "F.Fab")
		)
		(fp_line
			(start -0.67945 -0.305054)
			(end -0.12065 -0.305054)
			(stroke
				(width 0.1)
				(type default)
			)
			(layer "F.Fab")
		)
		(fp_line
			(start -0.12065 -0.305054)
			(end -0.12065 -0.2794)
			(stroke
				(width 0.1)
				(type default)
			)
			(layer "F.Fab")
		)
		(pad "1" smd circle
			(at -0.40005 0 270)
			(size 0 0)
			(layers "F.Cu" "F.Mask" "F.Paste")
			(net "PVCCD_HV_CPU1")
		)
		(pad "2" smd circle
			(at 0.40005 0 270)
			(size 0 0)
			(layers "F.Cu" "F.Mask" "F.Paste")
			(net "GND")
		)
	)
	(footprint ""
		(layer "F.Cu")
		(at 204.93736 -116.804948 180)
		(property "Reference" "R4172"
			(at 0 0 180)
			(layer "F.SilkS")
			(hide yes)
			(effects
				(font
					(size 1.27 1.27)
				)
			)
		)
		(property "Value" ""
			(at 0 0 180)
			(layer "F.Fab")
			(effects
				(font
					(size 1.27 1.27)
				)
			)
		)
		(duplicate_pad_numbers_are_jumpers no)
		(fp_line
			(start 0.7874 0.4064)
			(end -0.7874 0.4064)
			(stroke
				(width 0.1524)
				(type default)
			)
			(layer "F.SilkS")
		)
		(fp_line
			(start 0.7874 -0.4064)
			(end 0.7874 0.4064)
			(stroke
				(width 0.1524)
				(type default)
			)
			(layer "F.SilkS")
		)
		(fp_line
			(start -0.7874 0.4064)
			(end -0.7874 -0.4064)
			(stroke
				(width 0.1524)
				(type default)
			)
			(layer "F.SilkS")
		)
		(fp_line
			(start -0.7874 -0.4064)
			(end 0.7874 -0.4064)
			(stroke
				(width 0.1524)
				(type default)
			)
			(layer "F.SilkS")
		)
		(fp_line
			(start 0.67945 0.3048)
			(end 0.120396 0.3048)
			(stroke
				(width 0.1)
				(type default)
			)
			(layer "F.Fab")
		)
		(fp_line
			(start 0.67945 -0.3048)
			(end 0.67945 0.3048)
			(stroke
				(width 0.1)
				(type default)
			)
			(layer "F.Fab")
		)
		(fp_line
			(start 0.12065 -0.2794)
			(end 0.12065 -0.3048)
			(stroke
				(width 0.1)
				(type default)
			)
			(layer "F.Fab")
		)
		(fp_line
			(start 0.12065 -0.3048)
			(end 0.67945 -0.3048)
			(stroke
				(width 0.1)
				(type default)
			)
			(layer "F.Fab")
		)
		(fp_line
			(start 0.120396 0.3048)
			(end 0.120396 0.2794)
			(stroke
				(width 0.1)
				(type default)
			)
			(layer "F.Fab")
		)
		(fp_line
			(start 0.120396 0.2794)
			(end -0.12065 0.2794)
			(stroke
				(width 0.1)
				(type default)
			)
			(layer "F.Fab")
		)
		(fp_line
			(start -0.12065 0.3048)
			(end -0.67945 0.3048)
			(stroke
				(width 0.1)
				(type default)
			)
			(layer "F.Fab")
		)
		(fp_line
			(start -0.12065 0.2794)
			(end -0.12065 0.3048)
			(stroke
				(width 0.1)
				(type default)
			)
			(layer "F.Fab")
		)
		(fp_line
			(start -0.12065 -0.2794)
			(end 0.12065 -0.2794)
			(stroke
				(width 0.1)
				(type default)
			)
			(layer "F.Fab")
		)
		(fp_line
			(start -0.12065 -0.305054)
			(end -0.12065 -0.2794)
			(stroke
				(width 0.1)
				(type default)
			)
			(layer "F.Fab")
		)
		(fp_line
			(start -0.67945 0.3048)
			(end -0.67945 -0.305054)
			(stroke
				(width 0.1)
				(type default)
			)
			(layer "F.Fab")
		)
		(fp_line
			(start -0.67945 -0.305054)
			(end -0.12065 -0.305054)
			(stroke
				(width 0.1)
				(type default)
			)
			(layer "F.Fab")
		)
		(pad "1" smd circle
			(at -0.40005 0 180)
			(size 0 0)
			(layers "F.Cu" "F.Mask" "F.Paste")
			(net "GPU_3V3IO_RSVD4_ISO")
		)
		(pad "2" smd circle
			(at 0.40005 0 180)
			(size 0 0)
			(layers "F.Cu" "F.Mask" "F.Paste")
			(net "GPU_3V3IO_RSVD4_ISO_R")
		)
	)
	(footprint ""
		(layer "F.Cu")
		(at 186.87034 -360.26471)
		(property "Reference" "PC1682"
			(at 0 0 0)
			(layer "F.SilkS")
			(hide yes)
			(effects
				(font
					(size 1.27 1.27)
				)
			)
		)
		(property "Value" ""
			(at 0 0 0)
			(layer "F.Fab")
			(effects
				(font
					(size 1.27 1.27)
				)
			)
		)
		(duplicate_pad_numbers_are_jumpers no)
		(fp_line
			(start -1.524 -0.762)
			(end 1.524 -0.762)
			(stroke
				(width 0.1524)
				(type default)
			)
			(layer "F.SilkS")
		)
		(fp_line
			(start -1.524 0.762)
			(end -1.524 -0.762)
			(stroke
				(width 0.1524)
				(type default)
			)
			(layer "F.SilkS")
		)
		(fp_line
			(start 1.524 -0.762)
			(end 1.524 0.762)
			(stroke
				(width 0.1524)
				(type default)
			)
			(layer "F.SilkS")
		)
		(fp_line
			(start 1.524 0.762)
			(end -1.524 0.762)
			(stroke
				(width 0.1524)
				(type default)
			)
			(layer "F.SilkS")
		)
		(fp_line
			(start -1.1049 -0.724916)
			(end -1.1049 0.724916)
			(stroke
				(width 0.1)
				(type default)
			)
			(layer "F.Fab")
		)
		(fp_line
			(start -1.1049 0.724916)
			(end 1.1049 0.724916)
			(stroke
				(width 0.1)
				(type default)
			)
			(layer "F.Fab")
		)
		(fp_line
			(start 1.1049 -0.724916)
			(end -1.1049 -0.724916)
			(stroke
				(width 0.1)
				(type default)
			)
			(layer "F.Fab")
		)
		(fp_line
			(start 1.1049 0.724916)
			(end 1.1049 -0.724916)
			(stroke
				(width 0.1)
				(type default)
			)
			(layer "F.Fab")
		)
		(pad "1" smd rect
			(at -0.889 0 180)
			(size 1.016 1.27)
			(layers "F.Cu" "F.Mask" "F.Paste")
			(net "SW_P12V_PVCCFA_EHV_FIVRA_CPU1_R")
		)
		(pad "2" smd rect
			(at 0.889 0 180)
			(size 1.016 1.27)
			(layers "F.Cu" "F.Mask" "F.Paste")
			(net "GND")
		)
	)
	(footprint ""
		(layer "F.Cu")
		(at 418.2618 -16.088614 90)
		(property "Reference" "C859"
			(at 0 0 90)
			(layer "F.SilkS")
			(hide yes)
			(effects
				(font
					(size 1.27 1.27)
				)
			)
		)
		(property "Value" ""
			(at 0 0 90)
			(layer "F.Fab")
			(effects
				(font
					(size 1.27 1.27)
				)
			)
		)
		(duplicate_pad_numbers_are_jumpers no)
		(fp_line
			(start 0.299974 -0.150114)
			(end 0.299974 0.150114)
			(stroke
				(width 0.1)
				(type default)
			)
			(layer "F.Fab")
		)
		(fp_line
			(start -0.299974 -0.150114)
			(end 0.299974 -0.150114)
			(stroke
				(width 0.1)
				(type default)
			)
			(layer "F.Fab")
		)
		(fp_line
			(start 0.299974 0.150114)
			(end -0.299974 0.150114)
			(stroke
				(width 0.1)
				(type default)
			)
			(layer "F.Fab")
		)
		(fp_line
			(start -0.299974 0.150114)
			(end -0.299974 -0.150114)
			(stroke
				(width 0.1)
				(type default)
			)
			(layer "F.Fab")
		)
		(pad "1" smd rect
			(at -0.2667 0 90)
			(size 0.3048 0.381)
			(layers "F.Cu" "F.Mask" "F.Paste")
			(net "P5E_CPU0_PE1_TX_C_DP<5>")
		)
		(pad "2" smd rect
			(at 0.2667 0 90)
			(size 0.3048 0.381)
			(layers "F.Cu" "F.Mask" "F.Paste")
			(net "P5E_CPU0_PE1_TX_DP<5>")
		)
	)
	(footprint ""
		(layer "F.Cu")
		(at 253.86157 -50.366422 180)
		(property "Reference" "PU292"
			(at 7.20217 0.018034 0)
			(unlocked yes)
			(layer "F.SilkS")
			(effects
				(font
					(size 0.7874 0.5842)
					(thickness 0.1524)
				)
				(justify left)
			)
		)
		(property "Value" ""
			(at 0 0 180)
			(layer "F.Fab")
			(effects
				(font
					(size 1.27 1.27)
				)
			)
		)
		(duplicate_pad_numbers_are_jumpers no)
		(fp_line
			(start 1.549908 2.549906)
			(end 1.549908 2.253996)
			(stroke
				(width 0.1524)
				(type default)
			)
			(layer "F.SilkS")
		)
		(fp_line
			(start 1.549908 -2.253996)
			(end 1.549908 -2.549906)
			(stroke
				(width 0.1524)
				(type default)
			)
			(layer "F.SilkS")
		)
		(fp_line
			(start 1.549908 -2.549906)
			(end 0.752094 -2.549906)
			(stroke
				(width 0.1524)
				(type default)
			)
			(layer "F.SilkS")
		)
		(fp_line
			(start 0.753872 2.549906)
			(end 1.549908 2.549906)
			(stroke
				(width 0.1524)
				(type default)
			)
			(layer "F.SilkS")
		)
		(fp_line
			(start 0.2413 -2.549906)
			(end -0.2413 -2.549906)
			(stroke
				(width 0.1524)
				(type default)
			)
			(layer "F.SilkS")
		)
		(fp_line
			(start -0.245872 2.549906)
			(end 0.245872 2.549906)
			(stroke
				(width 0.1524)
				(type default)
			)
			(layer "F.SilkS")
		)
		(fp_line
			(start -0.752094 -2.549906)
			(end -1.549908 -2.549906)
			(stroke
				(width 0.1524)
				(type default)
			)
			(layer "F.SilkS")
		)
		(fp_line
			(start -1.549908 2.549906)
			(end -0.753872 2.549906)
			(stroke
				(width 0.1524)
				(type default)
			)
			(layer "F.SilkS")
		)
		(fp_line
			(start -1.549908 2.253996)
			(end -1.549908 2.549906)
			(stroke
				(width 0.1524)
				(type default)
			)
			(layer "F.SilkS")
		)
		(fp_line
			(start -1.549908 -2.549906)
			(end -1.549908 -2.251964)
			(stroke
				(width 0.1524)
				(type default)
			)
			(layer "F.SilkS")
		)
		(fp_poly
			(pts
				(xy -2.60731 -2.833878) (xy -1.869948 -3.259582) (xy -1.812798 -2.309368)
			)
			(stroke
				(width 0)
				(type default)
			)
			(fill yes)
			(layer "F.SilkS")
		)
		(fp_line
			(start 1.549908 2.549906)
			(end 1.549908 -2.549906)
			(stroke
				(width 0.1)
				(type default)
			)
			(layer "F.Fab")
		)
		(fp_line
			(start 1.549908 -2.549906)
			(end -1.549908 -2.549906)
			(stroke
				(width 0.1)
				(type default)
			)
			(layer "F.Fab")
		)
		(fp_line
			(start -1.549908 2.549906)
			(end 1.549908 2.549906)
			(stroke
				(width 0.1)
				(type default)
			)
			(layer "F.Fab")
		)
		(fp_line
			(start -1.549908 -2.549906)
			(end -1.549908 2.549906)
			(stroke
				(width 0.1)
				(type default)
			)
			(layer "F.Fab")
		)
		(fp_poly
			(pts
				(xy -1.891538 -1.999996) (xy -2.7432 -1.574292) (xy -2.7432 -2.4257)
			)
			(stroke
				(width 0)
				(type default)
			)
			(fill yes)
			(layer "F.Fab")
		)
		(fp_text user "11"
			(at 2.89687 5.385054 0)
			(unlocked yes)
			(layer "F.SilkS")
			(effects
				(font
					(size 0.635 0.4064)
					(thickness 0.1524)
				)
			)
		)
		(fp_text user "12"
			(at 2.66319 1.054354 0)
			(unlocked yes)
			(layer "F.SilkS")
			(effects
				(font
					(size 0.635 0.4064)
					(thickness 0.1524)
				)
			)
		)
		(fp_text user "20"
			(at 1.33223 -3.296666 0)
			(unlocked yes)
			(layer "F.SilkS")
			(effects
				(font
					(size 0.635 0.4064)
					(thickness 0.1524)
				)
			)
		)
		(fp_text user "21_22"
			(at -2.01803 -4.109466 0)
			(unlocked yes)
			(layer "F.SilkS")
			(effects
				(font
					(size 0.635 0.4064)
					(thickness 0.1524)
				)
			)
		)
		(fp_text user "10"
			(at -2.38379 3.007614 0)
			(unlocked yes)
			(layer "F.SilkS")
			(effects
				(font
					(size 0.635 0.4064)
					(thickness 0.1524)
				)
			)
		)
		(fp_text user "9"
			(at -2.44221 1.478534 0)
			(unlocked yes)
			(layer "F.SilkS")
			(effects
				(font
					(size 0.635 0.4064)
					(thickness 0.1524)
				)
			)
		)
		(fp_text user "12"
			(at 2.207768 2.7178 90)
			(unlocked yes)
			(layer "F.Fab")
			(effects
				(font
					(size 0.635 0.4064)
					(thickness 0.1524)
				)
			)
		)
		(fp_text user "20"
			(at 2.055368 -2.7686 90)
			(unlocked yes)
			(layer "F.Fab")
			(effects
				(font
					(size 0.635 0.4064)
					(thickness 0.1524)
				)
			)
		)
		(fp_text user "11"
			(at 1.1938 3.329432 180)
			(unlocked yes)
			(layer "F.Fab")
			(effects
				(font
					(size 0.635 0.4064)
					(thickness 0.1524)
				)
			)
		)
		(fp_text user "21_22"
			(at -0.0762 -3.401568 180)
			(unlocked yes)
			(layer "F.Fab")
			(effects
				(font
					(size 0.635 0.4064)
					(thickness 0.1524)
				)
			)
		)
		(fp_text user "10"
			(at -1.4224 3.253232 180)
			(unlocked yes)
			(layer "F.Fab")
			(effects
				(font
					(size 0.635 0.4064)
					(thickness 0.1524)
				)
			)
		)
		(fp_text user "9"
			(at -2.338832 2.5908 90)
			(unlocked yes)
			(layer "F.Fab")
			(effects
				(font
					(size 0.635 0.4064)
					(thickness 0.1524)
				)
			)
		)
		(pad "1" smd circle
			(at -1.374902 -1.999996 90)
			(size 0 0)
			(layers "F.Cu" "F.Mask" "F.Paste")
			(net "P12V_E1S_EN_0_R2")
		)
		(pad "2" smd rect
			(at -1.400048 -1.500124 90)
			(size 0.254 0.8128)
			(layers "F.Cu" "F.Mask" "F.Paste")
			(net "GND")
		)
		(pad "3" smd rect
			(at -1.400048 -0.999998 90)
			(size 0.254 0.8128)
			(layers "F.Cu" "F.Mask" "F.Paste")
			(net "GND")
		)
		(pad "4" smd rect
			(at -1.400048 -0.499872 90)
			(size 0.254 0.8128)
			(layers "F.Cu" "F.Mask" "F.Paste")
			(net "P12V_E1S_TIMER_0")
		)
		(pad "5" smd rect
			(at -1.400048 0 90)
			(size 0.254 0.8128)
			(layers "F.Cu" "F.Mask" "F.Paste")
			(net "P12V_E1S_ISET_0")
		)
		(pad "6" smd rect
			(at -1.400048 0.499872 90)
			(size 0.254 0.8128)
			(layers "F.Cu" "F.Mask" "F.Paste")
			(net "P12V_E1S_SS_0")
		)
		(pad "7" smd rect
			(at -1.400048 0.999998 90)
			(size 0.254 0.8128)
			(layers "F.Cu" "F.Mask" "F.Paste")
			(net "GND")
		)
		(pad "8" smd rect
			(at -1.400048 1.500124 90)
			(size 0.254 0.8128)
			(layers "F.Cu" "F.Mask" "F.Paste")
			(net "P12V_E1S_IMON_0")
		)
		(pad "9" smd rect
			(at -1.400048 1.999996 90)
			(size 0.254 0.8128)
			(layers "F.Cu" "F.Mask" "F.Paste")
			(net "P12V_E1S_FLTB_0")
		)
		(pad "10" smd rect
			(at -0.499872 2.400046 180)
			(size 0.254 0.8128)
			(layers "F.Cu" "F.Mask" "F.Paste")
			(net "HP_LVC3_E1S_0_HSC_PWRGD")
		)
		(pad "11" smd rect
			(at 0.499872 2.400046 180)
			(size 0.254 0.8128)
			(layers "F.Cu" "F.Mask" "F.Paste")
			(net "P12V_E1S_OV_FB_0")
		)
		(pad "12" smd rect
			(at 1.400048 1.999996 90)
			(size 0.254 0.8128)
			(layers "F.Cu" "F.Mask" "F.Paste")
			(net "P12V_E1S_AVIN_PD_0")
		)
		(pad "13" smd rect
			(at 1.400048 1.500124 90)
			(size 0.254 0.8128)
			(layers "F.Cu" "F.Mask" "F.Paste")
			(net "P12V_E1S_0")
		)
		(pad "14" smd rect
			(at 1.400048 0.999998 90)
			(size 0.254 0.8128)
			(layers "F.Cu" "F.Mask" "F.Paste")
			(net "P12V_E1S_0")
		)
		(pad "15" smd rect
			(at 1.400048 0.499872 90)
			(size 0.254 0.8128)
			(layers "F.Cu" "F.Mask" "F.Paste")
			(net "P12V_E1S_0")
		)
		(pad "16" smd rect
			(at 1.400048 0 90)
			(size 0.254 0.8128)
			(layers "F.Cu" "F.Mask" "F.Paste")
			(net "P12V_E1S_0")
		)
		(pad "17" smd rect
			(at 1.400048 -0.499872 90)
			(size 0.254 0.8128)
			(layers "F.Cu" "F.Mask" "F.Paste")
			(net "P12V_E1S_0")
		)
		(pad "18" smd rect
			(at 1.400048 -0.999998 90)
			(size 0.254 0.8128)
			(layers "F.Cu" "F.Mask" "F.Paste")
			(net "P12V_E1S_0")
		)
		(pad "19" smd rect
			(at 1.400048 -1.500124 90)
			(size 0.254 0.8128)
			(layers "F.Cu" "F.Mask" "F.Paste")
			(net "P12V_E1S_0")
		)
		(pad "20" smd rect
			(at 1.400048 -1.999996 90)
			(size 0.254 0.8128)
			(layers "F.Cu" "F.Mask" "F.Paste")
			(net "P12V_E1S_0")
		)
		(pad "21_22" smd circle
			(at 0.499872 -2.337562 90)
			(size 0 0)
			(layers "F.Cu" "F.Mask" "F.Paste")
			(net "P12V_AUX")
		)
		(pad "23" smd rect
			(at 0 -1.100074 90)
			(size 0.254 1.27)
			(layers "F.Cu" "F.Mask" "F.Paste")
			(net "P12V_AUX")
		)
		(pad "24" smd rect
			(at 0 -0.199898 90)
			(size 0.254 1.27)
			(layers "F.Cu" "F.Mask" "F.Paste")
			(net "P12V_AUX")
		)
		(pad "25" smd rect
			(at 0 0.700024 90)
			(size 0.254 1.27)
			(layers "F.Cu" "F.Mask" "F.Paste")
			(net "P12V_AUX")
		)
		(pad "26" smd rect
			(at 0 1.599946 90)
			(size 0.254 1.27)
			(layers "F.Cu" "F.Mask" "F.Paste")
			(net "P12V_AUX")
		)
	)
	(footprint ""
		(layer "F.Cu")
		(at 440.358276 -103.340916 90)
		(property "Reference" "U334"
			(at -1.397 -2.225548 90)
			(unlocked yes)
			(layer "F.SilkS")
			(effects
				(font
					(size 0.7874 0.5842)
					(thickness 0.1524)
				)
				(justify left)
			)
		)
		(property "Value" ""
			(at 0 0 90)
			(layer "F.Fab")
			(effects
				(font
					(size 1.27 1.27)
				)
			)
		)
		(duplicate_pad_numbers_are_jumpers no)
		(fp_line
			(start 1.733296 -1.549908)
			(end 0.660908 -1.549908)
			(stroke
				(width 0.1524)
				(type default)
			)
			(layer "F.SilkS")
		)
		(fp_line
			(start 0.660908 -1.549908)
			(end 0 -0.889)
			(stroke
				(width 0.1524)
				(type default)
			)
			(layer "F.SilkS")
		)
		(fp_line
			(start -0.660908 -1.549908)
			(end -1.733296 -1.549908)
			(stroke
				(width 0.1524)
				(type default)
			)
			(layer "F.SilkS")
		)
		(fp_line
			(start -1.733296 -1.549908)
			(end -1.733296 1.549908)
			(stroke
				(width 0.1524)
				(type default)
			)
			(layer "F.SilkS")
		)
		(fp_line
			(start 0 -0.889)
			(end -0.660908 -1.549908)
			(stroke
				(width 0.1524)
				(type default)
			)
			(layer "F.SilkS")
		)
		(fp_line
			(start 1.733296 1.549908)
			(end 1.733296 -1.549908)
			(stroke
				(width 0.1524)
				(type default)
			)
			(layer "F.SilkS")
		)
		(fp_line
			(start -1.733296 1.549908)
			(end 1.733296 1.549908)
			(stroke
				(width 0.1524)
				(type default)
			)
			(layer "F.SilkS")
		)
		(fp_poly
			(pts
				(xy -2.10693 -2.095246) (xy -2.46634 -1.73609) (xy -1.927352 -1.556512)
			)
			(stroke
				(width 0)
				(type default)
			)
			(fill yes)
			(layer "F.SilkS")
		)
		(fp_line
			(start 0.849884 -1.549908)
			(end -0.849884 -1.549908)
			(stroke
				(width 0.1)
				(type default)
			)
			(layer "F.Fab")
		)
		(fp_line
			(start -0.849884 -1.549908)
			(end -0.849884 1.549908)
			(stroke
				(width 0.1)
				(type default)
			)
			(layer "F.Fab")
		)
		(fp_line
			(start 0.849884 1.549908)
			(end 0.849884 -1.549908)
			(stroke
				(width 0.1)
				(type default)
			)
			(layer "F.Fab")
		)
		(fp_line
			(start -0.849884 1.549908)
			(end 0.849884 1.549908)
			(stroke
				(width 0.1)
				(type default)
			)
			(layer "F.Fab")
		)
		(fp_poly
			(pts
				(xy -2.4384 -1.20396) (xy -2.4384 -0.69596) (xy -1.9304 -0.94996)
			)
			(stroke
				(width 0)
				(type default)
			)
			(fill yes)
			(layer "F.Fab")
		)
		(pad "1" smd rect
			(at -1.199896 -0.94996)
			(size 0.5588 0.8128)
			(layers "F.Cu" "F.Mask" "F.Paste")
			(net "HP_LVC3_OCP_V3_1_PWRGD_R2")
		)
		(pad "2" smd rect
			(at -1.199896 0)
			(size 0.5588 0.8128)
			(layers "F.Cu" "F.Mask" "F.Paste")
			(net "OCP_SFF_AUX_PWR_PLD_EN_R")
		)
		(pad "3" smd rect
			(at -1.199896 0.94996)
			(size 0.5588 0.8128)
			(layers "F.Cu" "F.Mask" "F.Paste")
			(net "GND")
		)
		(pad "4" smd rect
			(at 1.199896 0.94996)
			(size 0.5588 0.8128)
			(layers "F.Cu" "F.Mask" "F.Paste")
			(net "OCP_SFF_AUX_PWR_EN_R2")
		)
		(pad "5" smd rect
			(at 1.199896 -0.94996)
			(size 0.5588 0.8128)
			(layers "F.Cu" "F.Mask" "F.Paste")
			(net "P3V3_AUX")
		)
	)
	(footprint ""
		(layer "F.Cu")
		(at 120.269 -62.575948 90)
		(property "Reference" "JP16"
			(at -0.02667 6.985 0)
			(unlocked yes)
			(layer "F.SilkS")
			(effects
				(font
					(size 0.7874 0.5842)
					(thickness 0.1524)
				)
				(justify left)
			)
		)
		(property "Value" ""
			(at 0 0 90)
			(layer "F.Fab")
			(effects
				(font
					(size 1.27 1.27)
				)
			)
		)
		(duplicate_pad_numbers_are_jumpers no)
		(fp_line
			(start 1.249934 -1.320038)
			(end 1.249934 6.400038)
			(stroke
				(width 0.1524)
				(type default)
			)
			(layer "F.SilkS")
		)
		(fp_line
			(start -1.249934 -1.320038)
			(end 1.249934 -1.320038)
			(stroke
				(width 0.1524)
				(type default)
			)
			(layer "F.SilkS")
		)
		(fp_line
			(start 1.249934 6.400038)
			(end -1.249934 6.400038)
			(stroke
				(width 0.1524)
				(type default)
			)
			(layer "F.SilkS")
		)
		(fp_line
			(start -1.249934 6.400038)
			(end -1.249934 -1.320038)
			(stroke
				(width 0.1524)
				(type default)
			)
			(layer "F.SilkS")
		)
		(fp_poly
			(pts
				(xy -2.156206 -2.266442) (xy -1.72339 -1.09982) (xy -2.916428 -1.453642)
			)
			(stroke
				(width 0)
				(type default)
			)
			(fill yes)
			(layer "F.SilkS")
		)
		(fp_line
			(start 1.249934 -1.320038)
			(end 1.249934 6.400038)
			(stroke
				(width 0.1)
				(type default)
			)
			(layer "F.Fab")
		)
		(fp_line
			(start -1.249934 -1.320038)
			(end 1.249934 -1.320038)
			(stroke
				(width 0.1)
				(type default)
			)
			(layer "F.Fab")
		)
		(fp_line
			(start 1.249934 6.400038)
			(end -1.249934 6.400038)
			(stroke
				(width 0.1)
				(type default)
			)
			(layer "F.Fab")
		)
		(fp_line
			(start -1.249934 6.400038)
			(end -1.249934 -1.320038)
			(stroke
				(width 0.1)
				(type default)
			)
			(layer "F.Fab")
		)
		(fp_poly
			(pts
				(xy -2.5654 -0.556514) (xy -1.452372 0) (xy -2.5654 0.556514)
			)
			(stroke
				(width 0)
				(type default)
			)
			(fill yes)
			(layer "F.Fab")
		)
		(fp_text user "3"
			(at -1.778 5.13207 90)
			(unlocked yes)
			(layer "F.SilkS")
			(effects
				(font
					(size 0.7874 0.5842)
					(thickness 0.1524)
				)
			)
		)
		(fp_text user "1"
			(at -1.143 0.02667 90)
			(unlocked yes)
			(layer "B.SilkS")
			(effects
				(font
					(size 0.7874 0.5842)
					(thickness 0.1524)
				)
				(justify mirror)
			)
		)
		(fp_text user "3"
			(at -1.1557 5.18287 90)
			(unlocked yes)
			(layer "B.SilkS")
			(effects
				(font
					(size 0.7874 0.5842)
					(thickness 0.1524)
				)
				(justify mirror)
			)
		)
		(fp_text user "1"
			(at -1.143 0.02667 90)
			(unlocked yes)
			(layer "B.Fab")
			(effects
				(font
					(size 0.7874 0.5842)
					(thickness 0.1524)
				)
				(justify mirror)
			)
		)
		(fp_text user "3"
			(at -1.1557 5.18287 90)
			(unlocked yes)
			(layer "B.Fab")
			(effects
				(font
					(size 0.7874 0.5842)
					(thickness 0.1524)
				)
				(justify mirror)
			)
		)
		(fp_text user "3"
			(at -1.778 5.13207 90)
			(unlocked yes)
			(layer "F.Fab")
			(effects
				(font
					(size 0.7874 0.5842)
					(thickness 0.1524)
				)
			)
		)
		(pad "1" thru_hole rect
			(at 0 0 90)
			(size 1.5494 1.5494)
			(drill 1.0414)
			(layers "*.Cu" "*.Mask")
			(remove_unused_layers no)
			(net "PU_JTAG_SW_PU")
			(clearance 0)
			(padstack
				(mode front_inner_back)
				(layer "Inner"
					(shape circle)
					(size 1.5494 1.5494)
					(clearance 0)
				)
				(layer "B.Cu"
					(shape rect)
					(size 1.5494 1.5494)
					(clearance 0)
				)
			)
		)
		(pad "2" thru_hole circle
			(at 0 2.54 90)
			(size 1.5494 1.5494)
			(drill 1.0414)
			(layers "*.Cu" "*.Mask")
			(remove_unused_layers no)
			(net "JTAG_BMC_SW_OE")
			(clearance 0)
		)
		(pad "3" thru_hole circle
			(at 0 5.08 90)
			(size 1.5494 1.5494)
			(drill 1.0414)
			(layers "*.Cu" "*.Mask")
			(remove_unused_layers no)
			(net "GND")
			(clearance 0)
		)
	)
	(footprint ""
		(layer "F.Cu")
		(at 102.84841 -55.277004)
		(property "Reference" "U86"
			(at -2.032 -3.27533 0)
			(unlocked yes)
			(layer "F.SilkS")
			(effects
				(font
					(size 0.7874 0.5842)
					(thickness 0.1524)
				)
				(justify left)
			)
		)
		(property "Value" ""
			(at 0 0 0)
			(layer "F.Fab")
			(effects
				(font
					(size 1.27 1.27)
				)
			)
		)
		(duplicate_pad_numbers_are_jumpers no)
		(fp_line
			(start -2.0066 -2.5527)
			(end -0.5715 -2.5527)
			(stroke
				(width 0.1524)
				(type default)
			)
			(layer "F.SilkS")
		)
		(fp_line
			(start -2.0066 2.5527)
			(end -2.0066 -2.5527)
			(stroke
				(width 0.1524)
				(type default)
			)
			(layer "F.SilkS")
		)
		(fp_line
			(start -0.5715 -2.5527)
			(end 0 -1.9812)
			(stroke
				(width 0.1524)
				(type default)
			)
			(layer "F.SilkS")
		)
		(fp_line
			(start 0 -1.9812)
			(end 0.5715 -2.5527)
			(stroke
				(width 0.1524)
				(type default)
			)
			(layer "F.SilkS")
		)
		(fp_line
			(start 0.5715 -2.5527)
			(end 2.0066 -2.5527)
			(stroke
				(width 0.1524)
				(type default)
			)
			(layer "F.SilkS")
		)
		(fp_line
			(start 2.0066 -2.5527)
			(end 2.0066 2.5527)
			(stroke
				(width 0.1524)
				(type default)
			)
			(layer "F.SilkS")
		)
		(fp_line
			(start 2.0066 2.5527)
			(end -2.0066 2.5527)
			(stroke
				(width 0.1524)
				(type default)
			)
			(layer "F.SilkS")
		)
		(fp_poly
			(pts
				(xy -2.669286 -2.982214) (xy -2.997454 -2.428494) (xy -3.294126 -2.982214)
			)
			(stroke
				(width 0)
				(type default)
			)
			(fill yes)
			(layer "F.SilkS")
		)
		(fp_line
			(start -2.249932 -2.549906)
			(end 2.249932 -2.549906)
			(stroke
				(width 0.1)
				(type default)
			)
			(layer "F.Fab")
		)
		(fp_line
			(start -2.249932 2.549906)
			(end -2.249932 -2.549906)
			(stroke
				(width 0.1)
				(type default)
			)
			(layer "F.Fab")
		)
		(fp_line
			(start 2.249932 -2.549906)
			(end 2.249932 2.549906)
			(stroke
				(width 0.1)
				(type default)
			)
			(layer "F.Fab")
		)
		(fp_line
			(start 2.249932 2.549906)
			(end -2.249932 2.549906)
			(stroke
				(width 0.1)
				(type default)
			)
			(layer "F.Fab")
		)
		(fp_poly
			(pts
				(xy -4.36372 -1.608328) (xy -4.36372 -2.233168) (xy -3.81 -1.905)
			)
			(stroke
				(width 0)
				(type default)
			)
			(fill yes)
			(layer "F.Fab")
		)
		(pad "1" smd rect
			(at -2.921 -1.949958 270)
			(size 0.3556 1.4986)
			(layers "F.Cu" "F.Mask" "F.Paste")
			(net "PD_JTAG_BMC_NTRST_N")
		)
		(pad "2" smd rect
			(at -2.921 -1.299972 270)
			(size 0.3556 1.4986)
			(layers "F.Cu" "F.Mask" "F.Paste")
			(net "FM_BMC_EN_DET")
		)
		(pad "3" smd rect
			(at -2.921 -0.649986 270)
			(size 0.3556 1.4986)
			(layers "F.Cu" "F.Mask" "F.Paste")
			(net "TP_JTAG_BMC_1B")
		)
		(pad "4" smd rect
			(at -2.921 0 270)
			(size 0.3556 1.4986)
			(layers "F.Cu" "F.Mask" "F.Paste")
			(net "JTAG_BMC_CPU_TCK")
		)
		(pad "5" smd rect
			(at -2.921 0.649986 270)
			(size 0.3556 1.4986)
			(layers "F.Cu" "F.Mask" "F.Paste")
			(net "FM_BMC_EN_DET")
		)
		(pad "6" smd rect
			(at -2.921 1.299972 270)
			(size 0.3556 1.4986)
			(layers "F.Cu" "F.Mask" "F.Paste")
			(net "JTAG_DBP_CPU_GTL_TCK_R1")
		)
		(pad "7" smd rect
			(at -2.921 1.949958 270)
			(size 0.3556 1.4986)
			(layers "F.Cu" "F.Mask" "F.Paste")
			(net "GND")
		)
		(pad "8" smd rect
			(at 2.921 1.949958 270)
			(size 0.3556 1.4986)
			(layers "F.Cu" "F.Mask" "F.Paste")
			(net "JTAG_DBP_TCK_PCH_R")
		)
		(pad "9" smd rect
			(at 2.921 1.299972 270)
			(size 0.3556 1.4986)
			(layers "F.Cu" "F.Mask" "F.Paste")
			(net "FM_BMC_EN_DET")
		)
		(pad "10" smd rect
			(at 2.921 0.649986 270)
			(size 0.3556 1.4986)
			(layers "F.Cu" "F.Mask" "F.Paste")
			(net "JTAG_BMC_PCH_TCK")
		)
		(pad "11" smd rect
			(at 2.921 0 270)
			(size 0.3556 1.4986)
			(layers "F.Cu" "F.Mask" "F.Paste")
			(net "TP_JTAG_BMC_4B")
		)
		(pad "12" smd rect
			(at 2.921 -0.649986 270)
			(size 0.3556 1.4986)
			(layers "F.Cu" "F.Mask" "F.Paste")
			(net "FM_BMC_EN_DET")
		)
		(pad "13" smd rect
			(at 2.921 -1.299972 270)
			(size 0.3556 1.4986)
			(layers "F.Cu" "F.Mask" "F.Paste")
			(net "PD_JTAG_BMC_NTRST_N")
		)
		(pad "14" smd rect
			(at 2.921 -1.949958 270)
			(size 0.3556 1.4986)
			(layers "F.Cu" "F.Mask" "F.Paste")
			(net "P3V3_AUX")
		)
	)
	(footprint ""
		(layer "F.Cu")
		(at 130.399028 -341.729822 90)
		(property "Reference" "PR1791"
			(at 0 0 90)
			(layer "F.SilkS")
			(hide yes)
			(effects
				(font
					(size 1.27 1.27)
				)
			)
		)
		(property "Value" ""
			(at 0 0 90)
			(layer "F.Fab")
			(effects
				(font
					(size 1.27 1.27)
				)
			)
		)
		(duplicate_pad_numbers_are_jumpers no)
		(fp_line
			(start 0.7874 -0.4064)
			(end 0.7874 0.4064)
			(stroke
				(width 0.1524)
				(type default)
			)
			(layer "F.SilkS")
		)
		(fp_line
			(start -0.7874 -0.4064)
			(end 0.7874 -0.4064)
			(stroke
				(width 0.1524)
				(type default)
			)
			(layer "F.SilkS")
		)
		(fp_line
			(start 0.7874 0.4064)
			(end -0.7874 0.4064)
			(stroke
				(width 0.1524)
				(type default)
			)
			(layer "F.SilkS")
		)
		(fp_line
			(start -0.7874 0.4064)
			(end -0.7874 -0.4064)
			(stroke
				(width 0.1524)
				(type default)
			)
			(layer "F.SilkS")
		)
		(fp_line
			(start -0.12065 -0.305054)
			(end -0.12065 -0.2794)
			(stroke
				(width 0.1)
				(type default)
			)
			(layer "F.Fab")
		)
		(fp_line
			(start -0.67945 -0.305054)
			(end -0.12065 -0.305054)
			(stroke
				(width 0.1)
				(type default)
			)
			(layer "F.Fab")
		)
		(fp_line
			(start 0.67945 -0.3048)
			(end 0.67945 0.3048)
			(stroke
				(width 0.1)
				(type default)
			)
			(layer "F.Fab")
		)
		(fp_line
			(start 0.12065 -0.3048)
			(end 0.67945 -0.3048)
			(stroke
				(width 0.1)
				(type default)
			)
			(layer "F.Fab")
		)
		(fp_line
			(start 0.12065 -0.2794)
			(end 0.12065 -0.3048)
			(stroke
				(width 0.1)
				(type default)
			)
			(layer "F.Fab")
		)
		(fp_line
			(start -0.12065 -0.2794)
			(end 0.12065 -0.2794)
			(stroke
				(width 0.1)
				(type default)
			)
			(layer "F.Fab")
		)
		(fp_line
			(start 0.120396 0.2794)
			(end -0.12065 0.2794)
			(stroke
				(width 0.1)
				(type default)
			)
			(layer "F.Fab")
		)
		(fp_line
			(start -0.12065 0.2794)
			(end -0.12065 0.3048)
			(stroke
				(width 0.1)
				(type default)
			)
			(layer "F.Fab")
		)
		(fp_line
			(start 0.67945 0.3048)
			(end 0.120396 0.3048)
			(stroke
				(width 0.1)
				(type default)
			)
			(layer "F.Fab")
		)
		(fp_line
			(start 0.120396 0.3048)
			(end 0.120396 0.2794)
			(stroke
				(width 0.1)
				(type default)
			)
			(layer "F.Fab")
		)
		(fp_line
			(start -0.12065 0.3048)
			(end -0.67945 0.3048)
			(stroke
				(width 0.1)
				(type default)
			)
			(layer "F.Fab")
		)
		(fp_line
			(start -0.67945 0.3048)
			(end -0.67945 -0.305054)
			(stroke
				(width 0.1)
				(type default)
			)
			(layer "F.Fab")
		)
		(pad "1" smd circle
			(at -0.40005 0 90)
			(size 0 0)
			(layers "F.Cu" "F.Mask" "F.Paste")
			(net "SW_PVCCIN_CPU1_BOOT5")
		)
		(pad "2" smd circle
			(at 0.40005 0 90)
			(size 0 0)
			(layers "F.Cu" "F.Mask" "F.Paste")
			(net "SW_PVCCIN_CPU1_BOOT5_R")
		)
	)
	(footprint ""
		(layer "F.Cu")
		(at 226.733608 -399.743422 180)
		(property "Reference" "PC2349"
			(at 0 0 180)
			(layer "F.SilkS")
			(hide yes)
			(effects
				(font
					(size 1.27 1.27)
				)
			)
		)
		(property "Value" ""
			(at 0 0 180)
			(layer "F.Fab")
			(effects
				(font
					(size 1.27 1.27)
				)
			)
		)
		(duplicate_pad_numbers_are_jumpers no)
		(fp_line
			(start 0.7874 0.4064)
			(end -0.7874 0.4064)
			(stroke
				(width 0.1524)
				(type default)
			)
			(layer "F.SilkS")
		)
		(fp_line
			(start 0.7874 -0.4064)
			(end 0.7874 0.4064)
			(stroke
				(width 0.1524)
				(type default)
			)
			(layer "F.SilkS")
		)
		(fp_line
			(start -0.7874 0.4064)
			(end -0.7874 -0.4064)
			(stroke
				(width 0.1524)
				(type default)
			)
			(layer "F.SilkS")
		)
		(fp_line
			(start -0.7874 -0.4064)
			(end 0.7874 -0.4064)
			(stroke
				(width 0.1524)
				(type default)
			)
			(layer "F.SilkS")
		)
		(fp_line
			(start 0.67945 0.3048)
			(end 0.120396 0.3048)
			(stroke
				(width 0.1)
				(type default)
			)
			(layer "F.Fab")
		)
		(fp_line
			(start 0.67945 -0.3048)
			(end 0.67945 0.3048)
			(stroke
				(width 0.1)
				(type default)
			)
			(layer "F.Fab")
		)
		(fp_line
			(start 0.12065 -0.2794)
			(end 0.12065 -0.3048)
			(stroke
				(width 0.1)
				(type default)
			)
			(layer "F.Fab")
		)
		(fp_line
			(start 0.12065 -0.3048)
			(end 0.67945 -0.3048)
			(stroke
				(width 0.1)
				(type default)
			)
			(layer "F.Fab")
		)
		(fp_line
			(start 0.120396 0.3048)
			(end 0.120396 0.2794)
			(stroke
				(width 0.1)
				(type default)
			)
			(layer "F.Fab")
		)
		(fp_line
			(start 0.120396 0.2794)
			(end -0.12065 0.2794)
			(stroke
				(width 0.1)
				(type default)
			)
			(layer "F.Fab")
		)
		(fp_line
			(start -0.12065 0.3048)
			(end -0.67945 0.3048)
			(stroke
				(width 0.1)
				(type default)
			)
			(layer "F.Fab")
		)
		(fp_line
			(start -0.12065 0.2794)
			(end -0.12065 0.3048)
			(stroke
				(width 0.1)
				(type default)
			)
			(layer "F.Fab")
		)
		(fp_line
			(start -0.12065 -0.2794)
			(end 0.12065 -0.2794)
			(stroke
				(width 0.1)
				(type default)
			)
			(layer "F.Fab")
		)
		(fp_line
			(start -0.12065 -0.305054)
			(end -0.12065 -0.2794)
			(stroke
				(width 0.1)
				(type default)
			)
			(layer "F.Fab")
		)
		(fp_line
			(start -0.67945 0.3048)
			(end -0.67945 -0.305054)
			(stroke
				(width 0.1)
				(type default)
			)
			(layer "F.Fab")
		)
		(fp_line
			(start -0.67945 -0.305054)
			(end -0.12065 -0.305054)
			(stroke
				(width 0.1)
				(type default)
			)
			(layer "F.Fab")
		)
		(pad "1" smd circle
			(at -0.40005 0 180)
			(size 0 0)
			(layers "F.Cu" "F.Mask" "F.Paste")
			(net "HSC_OCREF")
		)
		(pad "2" smd circle
			(at 0.40005 0 180)
			(size 0 0)
			(layers "F.Cu" "F.Mask" "F.Paste")
			(net "AGND_HSC")
		)
	)
	(footprint ""
		(layer "F.Cu")
		(at 141.572234 -402.371052 -90)
		(property "Reference" "C757"
			(at 0 0 270)
			(layer "F.SilkS")
			(hide yes)
			(effects
				(font
					(size 1.27 1.27)
				)
			)
		)
		(property "Value" ""
			(at 0 0 270)
			(layer "F.Fab")
			(effects
				(font
					(size 1.27 1.27)
				)
			)
		)
		(duplicate_pad_numbers_are_jumpers no)
		(fp_line
			(start -0.299974 0.150114)
			(end -0.299974 -0.150114)
			(stroke
				(width 0.1)
				(type default)
			)
			(layer "F.Fab")
		)
		(fp_line
			(start 0.299974 0.150114)
			(end -0.299974 0.150114)
			(stroke
				(width 0.1)
				(type default)
			)
			(layer "F.Fab")
		)
		(fp_line
			(start -0.299974 -0.150114)
			(end 0.299974 -0.150114)
			(stroke
				(width 0.1)
				(type default)
			)
			(layer "F.Fab")
		)
		(fp_line
			(start 0.299974 -0.150114)
			(end 0.299974 0.150114)
			(stroke
				(width 0.1)
				(type default)
			)
			(layer "F.Fab")
		)
		(pad "1" smd rect
			(at -0.2667 0 270)
			(size 0.3048 0.381)
			(layers "F.Cu" "F.Mask" "F.Paste")
			(net "P5E_CPU1_PE2_TX_C_DP<8>")
		)
		(pad "2" smd rect
			(at 0.2667 0 270)
			(size 0.3048 0.381)
			(layers "F.Cu" "F.Mask" "F.Paste")
			(net "P5E_CPU1_PE2_TX_DP<8>")
		)
	)
	(footprint ""
		(layer "F.Cu")
		(at 420.473632 -178.762914)
		(property "Reference" "PR1775"
			(at 0 0 0)
			(layer "F.SilkS")
			(hide yes)
			(effects
				(font
					(size 1.27 1.27)
				)
			)
		)
		(property "Value" ""
			(at 0 0 0)
			(layer "F.Fab")
			(effects
				(font
					(size 1.27 1.27)
				)
			)
		)
		(duplicate_pad_numbers_are_jumpers no)
		(fp_line
			(start -0.7874 -0.4064)
			(end 0.7874 -0.4064)
			(stroke
				(width 0.1524)
				(type default)
			)
			(layer "F.SilkS")
		)
		(fp_line
			(start -0.7874 0.4064)
			(end -0.7874 -0.4064)
			(stroke
				(width 0.1524)
				(type default)
			)
			(layer "F.SilkS")
		)
		(fp_line
			(start 0.7874 -0.4064)
			(end 0.7874 0.4064)
			(stroke
				(width 0.1524)
				(type default)
			)
			(layer "F.SilkS")
		)
		(fp_line
			(start 0.7874 0.4064)
			(end -0.7874 0.4064)
			(stroke
				(width 0.1524)
				(type default)
			)
			(layer "F.SilkS")
		)
		(fp_line
			(start -0.67945 -0.305054)
			(end -0.12065 -0.305054)
			(stroke
				(width 0.1)
				(type default)
			)
			(layer "F.Fab")
		)
		(fp_line
			(start -0.67945 0.3048)
			(end -0.67945 -0.305054)
			(stroke
				(width 0.1)
				(type default)
			)
			(layer "F.Fab")
		)
		(fp_line
			(start -0.12065 -0.305054)
			(end -0.12065 -0.2794)
			(stroke
				(width 0.1)
				(type default)
			)
			(layer "F.Fab")
		)
		(fp_line
			(start -0.12065 -0.2794)
			(end 0.12065 -0.2794)
			(stroke
				(width 0.1)
				(type default)
			)
			(layer "F.Fab")
		)
		(fp_line
			(start -0.12065 0.2794)
			(end -0.12065 0.3048)
			(stroke
				(width 0.1)
				(type default)
			)
			(layer "F.Fab")
		)
		(fp_line
			(start -0.12065 0.3048)
			(end -0.67945 0.3048)
			(stroke
				(width 0.1)
				(type default)
			)
			(layer "F.Fab")
		)
		(fp_line
			(start 0.120396 0.2794)
			(end -0.12065 0.2794)
			(stroke
				(width 0.1)
				(type default)
			)
			(layer "F.Fab")
		)
		(fp_line
			(start 0.120396 0.3048)
			(end 0.120396 0.2794)
			(stroke
				(width 0.1)
				(type default)
			)
			(layer "F.Fab")
		)
		(fp_line
			(start 0.12065 -0.3048)
			(end 0.67945 -0.3048)
			(stroke
				(width 0.1)
				(type default)
			)
			(layer "F.Fab")
		)
		(fp_line
			(start 0.12065 -0.2794)
			(end 0.12065 -0.3048)
			(stroke
				(width 0.1)
				(type default)
			)
			(layer "F.Fab")
		)
		(fp_line
			(start 0.67945 -0.3048)
			(end 0.67945 0.3048)
			(stroke
				(width 0.1)
				(type default)
			)
			(layer "F.Fab")
		)
		(fp_line
			(start 0.67945 0.3048)
			(end 0.120396 0.3048)
			(stroke
				(width 0.1)
				(type default)
			)
			(layer "F.Fab")
		)
		(pad "1" smd circle
			(at -0.40005 0)
			(size 0 0)
			(layers "F.Cu" "F.Mask" "F.Paste")
			(net "SW_PVCCINFAON_CPU0_BOOT2")
		)
		(pad "2" smd circle
			(at 0.40005 0)
			(size 0 0)
			(layers "F.Cu" "F.Mask" "F.Paste")
			(net "SW_PVCCINFAON_CPU0_BOOT2_R")
		)
	)
	(footprint ""
		(layer "F.Cu")
		(at 243.045488 -136.348724)
		(property "Reference" "R4715"
			(at 0 0 0)
			(layer "F.SilkS")
			(hide yes)
			(effects
				(font
					(size 1.27 1.27)
				)
			)
		)
		(property "Value" ""
			(at 0 0 0)
			(layer "F.Fab")
			(effects
				(font
					(size 1.27 1.27)
				)
			)
		)
		(duplicate_pad_numbers_are_jumpers no)
		(fp_line
			(start -0.7874 -0.4064)
			(end 0.7874 -0.4064)
			(stroke
				(width 0.1524)
				(type default)
			)
			(layer "F.SilkS")
		)
		(fp_line
			(start -0.7874 0.4064)
			(end -0.7874 -0.4064)
			(stroke
				(width 0.1524)
				(type default)
			)
			(layer "F.SilkS")
		)
		(fp_line
			(start 0.7874 -0.4064)
			(end 0.7874 0.4064)
			(stroke
				(width 0.1524)
				(type default)
			)
			(layer "F.SilkS")
		)
		(fp_line
			(start 0.7874 0.4064)
			(end -0.7874 0.4064)
			(stroke
				(width 0.1524)
				(type default)
			)
			(layer "F.SilkS")
		)
		(fp_line
			(start -0.67945 -0.305054)
			(end -0.12065 -0.305054)
			(stroke
				(width 0.1)
				(type default)
			)
			(layer "F.Fab")
		)
		(fp_line
			(start -0.67945 0.3048)
			(end -0.67945 -0.305054)
			(stroke
				(width 0.1)
				(type default)
			)
			(layer "F.Fab")
		)
		(fp_line
			(start -0.12065 -0.305054)
			(end -0.12065 -0.2794)
			(stroke
				(width 0.1)
				(type default)
			)
			(layer "F.Fab")
		)
		(fp_line
			(start -0.12065 -0.2794)
			(end 0.12065 -0.2794)
			(stroke
				(width 0.1)
				(type default)
			)
			(layer "F.Fab")
		)
		(fp_line
			(start -0.12065 0.2794)
			(end -0.12065 0.3048)
			(stroke
				(width 0.1)
				(type default)
			)
			(layer "F.Fab")
		)
		(fp_line
			(start -0.12065 0.3048)
			(end -0.67945 0.3048)
			(stroke
				(width 0.1)
				(type default)
			)
			(layer "F.Fab")
		)
		(fp_line
			(start 0.120396 0.2794)
			(end -0.12065 0.2794)
			(stroke
				(width 0.1)
				(type default)
			)
			(layer "F.Fab")
		)
		(fp_line
			(start 0.120396 0.3048)
			(end 0.120396 0.2794)
			(stroke
				(width 0.1)
				(type default)
			)
			(layer "F.Fab")
		)
		(fp_line
			(start 0.12065 -0.3048)
			(end 0.67945 -0.3048)
			(stroke
				(width 0.1)
				(type default)
			)
			(layer "F.Fab")
		)
		(fp_line
			(start 0.12065 -0.2794)
			(end 0.12065 -0.3048)
			(stroke
				(width 0.1)
				(type default)
			)
			(layer "F.Fab")
		)
		(fp_line
			(start 0.67945 -0.3048)
			(end 0.67945 0.3048)
			(stroke
				(width 0.1)
				(type default)
			)
			(layer "F.Fab")
		)
		(fp_line
			(start 0.67945 0.3048)
			(end 0.120396 0.3048)
			(stroke
				(width 0.1)
				(type default)
			)
			(layer "F.Fab")
		)
		(pad "1" smd circle
			(at -0.40005 0)
			(size 0 0)
			(layers "F.Cu" "F.Mask" "F.Paste")
			(net "SMB_HOST_3V3AUX_SCL_R4")
		)
		(pad "2" smd circle
			(at 0.40005 0)
			(size 0 0)
			(layers "F.Cu" "F.Mask" "F.Paste")
			(net "SMB_HOST_3V3AUX_PLD_SCL")
		)
	)
	(footprint ""
		(layer "F.Cu")
		(at 311.970674 -14.69136 180)
		(property "Reference" "U157"
			(at 1.306068 2.358644 0)
			(unlocked yes)
			(layer "F.SilkS")
			(effects
				(font
					(size 0.7874 0.5842)
					(thickness 0.1524)
				)
				(justify left)
			)
		)
		(property "Value" ""
			(at 0 0 180)
			(layer "F.Fab")
			(effects
				(font
					(size 1.27 1.27)
				)
			)
		)
		(duplicate_pad_numbers_are_jumpers no)
		(fp_line
			(start 1.733296 1.549908)
			(end 1.733296 -1.549908)
			(stroke
				(width 0.1524)
				(type default)
			)
			(layer "F.SilkS")
		)
		(fp_line
			(start 1.733296 -1.549908)
			(end 0.660908 -1.549908)
			(stroke
				(width 0.1524)
				(type default)
			)
			(layer "F.SilkS")
		)
		(fp_line
			(start 0.660908 -1.549908)
			(end 0 -0.889)
			(stroke
				(width 0.1524)
				(type default)
			)
			(layer "F.SilkS")
		)
		(fp_line
			(start 0 -0.889)
			(end -0.660908 -1.549908)
			(stroke
				(width 0.1524)
				(type default)
			)
			(layer "F.SilkS")
		)
		(fp_line
			(start -0.660908 -1.549908)
			(end -1.733296 -1.549908)
			(stroke
				(width 0.1524)
				(type default)
			)
			(layer "F.SilkS")
		)
		(fp_line
			(start -1.733296 1.549908)
			(end 1.733296 1.549908)
			(stroke
				(width 0.1524)
				(type default)
			)
			(layer "F.SilkS")
		)
		(fp_line
			(start -1.733296 -1.549908)
			(end -1.733296 1.549908)
			(stroke
				(width 0.1524)
				(type default)
			)
			(layer "F.SilkS")
		)
		(fp_poly
			(pts
				(xy -0.982218 -2.318766) (xy -1.236218 -1.810766) (xy -1.490218 -2.318766)
			)
			(stroke
				(width 0)
				(type default)
			)
			(fill yes)
			(layer "F.SilkS")
		)
		(fp_line
			(start 0.849884 1.549908)
			(end 0.849884 -1.549908)
			(stroke
				(width 0.1)
				(type default)
			)
			(layer "F.Fab")
		)
		(fp_line
			(start 0.849884 -1.549908)
			(end -0.849884 -1.549908)
			(stroke
				(width 0.1)
				(type default)
			)
			(layer "F.Fab")
		)
		(fp_line
			(start -0.849884 1.549908)
			(end 0.849884 1.549908)
			(stroke
				(width 0.1)
				(type default)
			)
			(layer "F.Fab")
		)
		(fp_line
			(start -0.849884 -1.549908)
			(end -0.849884 1.549908)
			(stroke
				(width 0.1)
				(type default)
			)
			(layer "F.Fab")
		)
		(fp_poly
			(pts
				(xy -2.4384 -1.20396) (xy -2.4384 -0.69596) (xy -1.9304 -0.94996)
			)
			(stroke
				(width 0)
				(type default)
			)
			(fill yes)
			(layer "F.Fab")
		)
		(pad "1" smd rect
			(at -1.199896 -0.94996 90)
			(size 0.5588 0.8128)
			(layers "F.Cu" "F.Mask" "F.Paste")
			(net "NC_U157_NC1")
		)
		(pad "2" smd rect
			(at -1.199896 0 90)
			(size 0.5588 0.8128)
			(layers "F.Cu" "F.Mask" "F.Paste")
			(net "OCP_SFF_WAKE_BUFF_R_N")
		)
		(pad "3" smd rect
			(at -1.199896 0.94996 90)
			(size 0.5588 0.8128)
			(layers "F.Cu" "F.Mask" "F.Paste")
			(net "GND")
		)
		(pad "4" smd rect
			(at 1.199896 0.94996 90)
			(size 0.5588 0.8128)
			(layers "F.Cu" "F.Mask" "F.Paste")
			(net "IRQ_LVC3_WAKE_BUF_N")
		)
		(pad "5" smd rect
			(at 1.199896 -0.94996 90)
			(size 0.5588 0.8128)
			(layers "F.Cu" "F.Mask" "F.Paste")
			(net "P3V3_AUX")
		)
	)
	(footprint ""
		(layer "F.Cu")
		(at 136.60628 -26.251408)
		(property "Reference" "R4276"
			(at 0 0 0)
			(layer "F.SilkS")
			(hide yes)
			(effects
				(font
					(size 1.27 1.27)
				)
			)
		)
		(property "Value" ""
			(at 0 0 0)
			(layer "F.Fab")
			(effects
				(font
					(size 1.27 1.27)
				)
			)
		)
		(duplicate_pad_numbers_are_jumpers no)
		(fp_line
			(start -0.7874 -0.4064)
			(end 0.7874 -0.4064)
			(stroke
				(width 0.1524)
				(type default)
			)
			(layer "F.SilkS")
		)
		(fp_line
			(start -0.7874 0.4064)
			(end -0.7874 -0.4064)
			(stroke
				(width 0.1524)
				(type default)
			)
			(layer "F.SilkS")
		)
		(fp_line
			(start 0.7874 -0.4064)
			(end 0.7874 0.4064)
			(stroke
				(width 0.1524)
				(type default)
			)
			(layer "F.SilkS")
		)
		(fp_line
			(start 0.7874 0.4064)
			(end -0.7874 0.4064)
			(stroke
				(width 0.1524)
				(type default)
			)
			(layer "F.SilkS")
		)
		(fp_line
			(start -0.67945 -0.305054)
			(end -0.12065 -0.305054)
			(stroke
				(width 0.1)
				(type default)
			)
			(layer "F.Fab")
		)
		(fp_line
			(start -0.67945 0.3048)
			(end -0.67945 -0.305054)
			(stroke
				(width 0.1)
				(type default)
			)
			(layer "F.Fab")
		)
		(fp_line
			(start -0.12065 -0.305054)
			(end -0.12065 -0.2794)
			(stroke
				(width 0.1)
				(type default)
			)
			(layer "F.Fab")
		)
		(fp_line
			(start -0.12065 -0.2794)
			(end 0.12065 -0.2794)
			(stroke
				(width 0.1)
				(type default)
			)
			(layer "F.Fab")
		)
		(fp_line
			(start -0.12065 0.2794)
			(end -0.12065 0.3048)
			(stroke
				(width 0.1)
				(type default)
			)
			(layer "F.Fab")
		)
		(fp_line
			(start -0.12065 0.3048)
			(end -0.67945 0.3048)
			(stroke
				(width 0.1)
				(type default)
			)
			(layer "F.Fab")
		)
		(fp_line
			(start 0.120396 0.2794)
			(end -0.12065 0.2794)
			(stroke
				(width 0.1)
				(type default)
			)
			(layer "F.Fab")
		)
		(fp_line
			(start 0.120396 0.3048)
			(end 0.120396 0.2794)
			(stroke
				(width 0.1)
				(type default)
			)
			(layer "F.Fab")
		)
		(fp_line
			(start 0.12065 -0.3048)
			(end 0.67945 -0.3048)
			(stroke
				(width 0.1)
				(type default)
			)
			(layer "F.Fab")
		)
		(fp_line
			(start 0.12065 -0.2794)
			(end 0.12065 -0.3048)
			(stroke
				(width 0.1)
				(type default)
			)
			(layer "F.Fab")
		)
		(fp_line
			(start 0.67945 -0.3048)
			(end 0.67945 0.3048)
			(stroke
				(width 0.1)
				(type default)
			)
			(layer "F.Fab")
		)
		(fp_line
			(start 0.67945 0.3048)
			(end 0.120396 0.3048)
			(stroke
				(width 0.1)
				(type default)
			)
			(layer "F.Fab")
		)
		(pad "1" smd circle
			(at -0.40005 0)
			(size 0 0)
			(layers "F.Cu" "F.Mask" "F.Paste")
			(net "FM_USB3_1_EQA")
		)
		(pad "2" smd circle
			(at 0.40005 0)
			(size 0 0)
			(layers "F.Cu" "F.Mask" "F.Paste")
			(net "GND")
		)
	)
	(footprint ""
		(layer "F.Cu")
		(at 280.840688 -15.247112 180)
		(property "Reference" "R3192"
			(at 0 0 180)
			(layer "F.SilkS")
			(hide yes)
			(effects
				(font
					(size 1.27 1.27)
				)
			)
		)
		(property "Value" ""
			(at 0 0 180)
			(layer "F.Fab")
			(effects
				(font
					(size 1.27 1.27)
				)
			)
		)
		(duplicate_pad_numbers_are_jumpers no)
		(fp_line
			(start 0.7874 0.4064)
			(end -0.7874 0.4064)
			(stroke
				(width 0.1524)
				(type default)
			)
			(layer "F.SilkS")
		)
		(fp_line
			(start 0.7874 -0.4064)
			(end 0.7874 0.4064)
			(stroke
				(width 0.1524)
				(type default)
			)
			(layer "F.SilkS")
		)
		(fp_line
			(start -0.7874 0.4064)
			(end -0.7874 -0.4064)
			(stroke
				(width 0.1524)
				(type default)
			)
			(layer "F.SilkS")
		)
		(fp_line
			(start -0.7874 -0.4064)
			(end 0.7874 -0.4064)
			(stroke
				(width 0.1524)
				(type default)
			)
			(layer "F.SilkS")
		)
		(fp_line
			(start 0.67945 0.3048)
			(end 0.120396 0.3048)
			(stroke
				(width 0.1)
				(type default)
			)
			(layer "F.Fab")
		)
		(fp_line
			(start 0.67945 -0.3048)
			(end 0.67945 0.3048)
			(stroke
				(width 0.1)
				(type default)
			)
			(layer "F.Fab")
		)
		(fp_line
			(start 0.12065 -0.2794)
			(end 0.12065 -0.3048)
			(stroke
				(width 0.1)
				(type default)
			)
			(layer "F.Fab")
		)
		(fp_line
			(start 0.12065 -0.3048)
			(end 0.67945 -0.3048)
			(stroke
				(width 0.1)
				(type default)
			)
			(layer "F.Fab")
		)
		(fp_line
			(start 0.120396 0.3048)
			(end 0.120396 0.2794)
			(stroke
				(width 0.1)
				(type default)
			)
			(layer "F.Fab")
		)
		(fp_line
			(start 0.120396 0.2794)
			(end -0.12065 0.2794)
			(stroke
				(width 0.1)
				(type default)
			)
			(layer "F.Fab")
		)
		(fp_line
			(start -0.12065 0.3048)
			(end -0.67945 0.3048)
			(stroke
				(width 0.1)
				(type default)
			)
			(layer "F.Fab")
		)
		(fp_line
			(start -0.12065 0.2794)
			(end -0.12065 0.3048)
			(stroke
				(width 0.1)
				(type default)
			)
			(layer "F.Fab")
		)
		(fp_line
			(start -0.12065 -0.2794)
			(end 0.12065 -0.2794)
			(stroke
				(width 0.1)
				(type default)
			)
			(layer "F.Fab")
		)
		(fp_line
			(start -0.12065 -0.305054)
			(end -0.12065 -0.2794)
			(stroke
				(width 0.1)
				(type default)
			)
			(layer "F.Fab")
		)
		(fp_line
			(start -0.67945 0.3048)
			(end -0.67945 -0.305054)
			(stroke
				(width 0.1)
				(type default)
			)
			(layer "F.Fab")
		)
		(fp_line
			(start -0.67945 -0.305054)
			(end -0.12065 -0.305054)
			(stroke
				(width 0.1)
				(type default)
			)
			(layer "F.Fab")
		)
		(pad "1" smd circle
			(at -0.40005 0 180)
			(size 0 0)
			(layers "F.Cu" "F.Mask" "F.Paste")
			(net "P3V3_AUX")
		)
		(pad "2" smd circle
			(at 0.40005 0 180)
			(size 0 0)
			(layers "F.Cu" "F.Mask" "F.Paste")
			(net "IRQ_LVC3_V3_2_WAKE_BUF_N")
		)
	)
	(footprint ""
		(layer "F.Cu")
		(at 339.298534 -4.696206)
		(property "Reference" "J69"
			(at -4.245864 1.140206 90)
			(unlocked yes)
			(layer "F.SilkS")
			(effects
				(font
					(size 0.7874 0.5842)
					(thickness 0.1524)
				)
				(justify left)
			)
		)
		(property "Value" ""
			(at 0 0 0)
			(layer "F.Fab")
			(effects
				(font
					(size 1.27 1.27)
				)
			)
		)
		(duplicate_pad_numbers_are_jumpers no)
		(fp_line
			(start -1.2192 -2.1082)
			(end 1.2192 -2.1082)
			(stroke
				(width 0.1524)
				(type default)
			)
			(layer "F.SilkS")
		)
		(fp_line
			(start -1.2192 2.1082)
			(end -1.2192 -2.1082)
			(stroke
				(width 0.1524)
				(type default)
			)
			(layer "F.SilkS")
		)
		(fp_line
			(start 1.2192 -2.1082)
			(end 1.2192 2.1082)
			(stroke
				(width 0.1524)
				(type default)
			)
			(layer "F.SilkS")
		)
		(fp_line
			(start 1.2192 2.1082)
			(end -1.2192 2.1082)
			(stroke
				(width 0.1524)
				(type default)
			)
			(layer "F.SilkS")
		)
		(pad "" np_thru_hole circle
			(at -2.8829 -1.27 270)
			(size 1.0414 1.0414)
			(drill 1.0414)
			(layers "*.Cu" "*.Mask")
			(clearance 0.381)
			(thermal_gap 0.381)
		)
		(pad "" np_thru_hole circle
			(at -2.8829 1.27 270)
			(size 1.0414 1.0414)
			(drill 1.0414)
			(layers "*.Cu" "*.Mask")
			(clearance 0.381)
			(thermal_gap 0.381)
		)
		(pad "" np_thru_hole circle
			(at 3.4671 -1.27 270)
			(size 1.0414 1.0414)
			(drill 1.0414)
			(layers "*.Cu" "*.Mask")
			(clearance 0.381)
			(thermal_gap 0.381)
		)
		(pad "" np_thru_hole circle
			(at 3.4671 1.27 270)
			(size 1.0414 1.0414)
			(drill 1.0414)
			(layers "*.Cu" "*.Mask")
			(clearance 0.381)
			(thermal_gap 0.381)
		)
		(pad "1" smd rect
			(at 0.8255 -0.249936 270)
			(size 0.3048 0.508)
			(layers "F.Cu" "F.Mask" "F.Paste")
			(net "DELTA_L_85_5INCH_TOP_DN")
		)
		(pad "2" smd rect
			(at 0.8255 0.249936 270)
			(size 0.3048 0.508)
			(layers "F.Cu" "F.Mask" "F.Paste")
			(net "DELTA_L_85_5INCH_TOP_DP")
		)
		(pad "3" smd circle
			(at 0 0)
			(size 0 0)
			(layers "F.Cu" "F.Mask" "F.Paste")
			(net "DELTA_L_GND_1")
		)
		(zone
			(layer "F.Cu")
			(hatch none 0.5)
			(connect_pads
				(clearance 0)
			)
			(min_thickness 0.25)
			(keepout
				(tracks not_allowed)
				(vias allowed)
				(pads allowed)
				(copperpour not_allowed)
				(footprints allowed)
			)
			(placement
				(enabled no)
				(sheetname "")
			)
			(fill
				(thermal_gap 0.5)
				(thermal_bridge_width 0.5)
				(island_removal_mode 0)
			)
			(polygon
				(pts
					(xy 340.416134 -5.244846) (xy 340.416134 -5.149342) (xy 339.819234 -5.149342) (xy 339.819234 -4.742942)
					(xy 340.416134 -4.742942) (xy 340.416134 -4.64947) (xy 339.819234 -4.64947) (xy 339.819234 -4.24307)
					(xy 340.416134 -4.24307) (xy 340.416134 -4.147566) (xy 339.717634 -4.147566) (xy 339.717634 -5.244846)
				)
			)
		)
		(zone
			(layers "F.Cu" "B.Cu" "In1.Cu" "In2.Cu" "In3.Cu" "In4.Cu" "In5.Cu" "In6.Cu"
				"In7.Cu" "In8.Cu" "In9.Cu" "In10.Cu" "In11.Cu" "In12.Cu" "In13.Cu" "In14.Cu"
				"In15.Cu" "In16.Cu"
			)
			(hatch none 0.5)
			(connect_pads
				(clearance 0)
			)
			(min_thickness 0.25)
			(keepout
				(tracks not_allowed)
				(vias allowed)
				(pads allowed)
				(copperpour not_allowed)
				(footprints allowed)
			)
			(placement
				(enabled no)
				(sheetname "")
			)
			(fill
				(thermal_gap 0.5)
				(thermal_bridge_width 0.5)
				(island_removal_mode 0)
			)
			(polygon
				(pts
					(arc
						(start 337.342734 -5.966206)
						(mid 335.488534 -5.966206)
						(end 337.342734 -5.966206)
					)
				)
			)
		)
		(zone
			(layers "F.Cu" "B.Cu" "In1.Cu" "In2.Cu" "In3.Cu" "In4.Cu" "In5.Cu" "In6.Cu"
				"In7.Cu" "In8.Cu" "In9.Cu" "In10.Cu" "In11.Cu" "In12.Cu" "In13.Cu" "In14.Cu"
				"In15.Cu" "In16.Cu"
			)
			(hatch none 0.5)
			(connect_pads
				(clearance 0)
			)
			(min_thickness 0.25)
			(keepout
				(tracks not_allowed)
				(vias allowed)
				(pads allowed)
				(copperpour not_allowed)
				(footprints allowed)
			)
			(placement
				(enabled no)
				(sheetname "")
			)
			(fill
				(thermal_gap 0.5)
				(thermal_bridge_width 0.5)
				(island_removal_mode 0)
			)
			(polygon
				(pts
					(arc
						(start 337.342734 -3.426206)
						(mid 335.488534 -3.426206)
						(end 337.342734 -3.426206)
					)
				)
			)
		)
		(zone
			(layers "F.Cu" "B.Cu" "In1.Cu" "In2.Cu" "In3.Cu" "In4.Cu" "In5.Cu" "In6.Cu"
				"In7.Cu" "In8.Cu" "In9.Cu" "In10.Cu" "In11.Cu" "In12.Cu" "In13.Cu" "In14.Cu"
				"In15.Cu" "In16.Cu"
			)
			(hatch none 0.5)
			(connect_pads
				(clearance 0)
			)
			(min_thickness 0.25)
			(keepout
				(tracks not_allowed)
				(vias allowed)
				(pads allowed)
				(copperpour not_allowed)
				(footprints allowed)
			)
			(placement
				(enabled no)
				(sheetname "")
			)
			(fill
				(thermal_gap 0.5)
				(thermal_bridge_width 0.5)
				(island_removal_mode 0)
			)
			(polygon
				(pts
					(arc
						(start 343.692734 -5.966206)
						(mid 341.838534 -5.966206)
						(end 343.692734 -5.966206)
					)
				)
			)
		)
		(zone
			(layers "F.Cu" "B.Cu" "In1.Cu" "In2.Cu" "In3.Cu" "In4.Cu" "In5.Cu" "In6.Cu"
				"In7.Cu" "In8.Cu" "In9.Cu" "In10.Cu" "In11.Cu" "In12.Cu" "In13.Cu" "In14.Cu"
				"In15.Cu" "In16.Cu"
			)
			(hatch none 0.5)
			(connect_pads
				(clearance 0)
			)
			(min_thickness 0.25)
			(keepout
				(tracks not_allowed)
				(vias allowed)
				(pads allowed)
				(copperpour not_allowed)
				(footprints allowed)
			)
			(placement
				(enabled no)
				(sheetname "")
			)
			(fill
				(thermal_gap 0.5)
				(thermal_bridge_width 0.5)
				(island_removal_mode 0)
			)
			(polygon
				(pts
					(arc
						(start 343.692734 -3.426206)
						(mid 341.838534 -3.426206)
						(end 343.692734 -3.426206)
					)
				)
			)
		)
	)
	(footprint ""
		(layer "F.Cu")
		(at 354.270818 -244.03177 90)
		(property "Reference" "C1003"
			(at 0 0 90)
			(layer "F.SilkS")
			(hide yes)
			(effects
				(font
					(size 1.27 1.27)
				)
			)
		)
		(property "Value" ""
			(at 0 0 90)
			(layer "F.Fab")
			(effects
				(font
					(size 1.27 1.27)
				)
			)
		)
		(duplicate_pad_numbers_are_jumpers no)
		(fp_line
			(start 0.7874 -0.4064)
			(end 0.7874 0.4064)
			(stroke
				(width 0.1524)
				(type default)
			)
			(layer "F.SilkS")
		)
		(fp_line
			(start -0.7874 -0.4064)
			(end 0.7874 -0.4064)
			(stroke
				(width 0.1524)
				(type default)
			)
			(layer "F.SilkS")
		)
		(fp_line
			(start 0.7874 0.4064)
			(end -0.7874 0.4064)
			(stroke
				(width 0.1524)
				(type default)
			)
			(layer "F.SilkS")
		)
		(fp_line
			(start -0.7874 0.4064)
			(end -0.7874 -0.4064)
			(stroke
				(width 0.1524)
				(type default)
			)
			(layer "F.SilkS")
		)
		(fp_line
			(start -0.12065 -0.305054)
			(end -0.12065 -0.2794)
			(stroke
				(width 0.1)
				(type default)
			)
			(layer "F.Fab")
		)
		(fp_line
			(start -0.67945 -0.305054)
			(end -0.12065 -0.305054)
			(stroke
				(width 0.1)
				(type default)
			)
			(layer "F.Fab")
		)
		(fp_line
			(start 0.67945 -0.3048)
			(end 0.67945 0.3048)
			(stroke
				(width 0.1)
				(type default)
			)
			(layer "F.Fab")
		)
		(fp_line
			(start 0.12065 -0.3048)
			(end 0.67945 -0.3048)
			(stroke
				(width 0.1)
				(type default)
			)
			(layer "F.Fab")
		)
		(fp_line
			(start 0.12065 -0.2794)
			(end 0.12065 -0.3048)
			(stroke
				(width 0.1)
				(type default)
			)
			(layer "F.Fab")
		)
		(fp_line
			(start -0.12065 -0.2794)
			(end 0.12065 -0.2794)
			(stroke
				(width 0.1)
				(type default)
			)
			(layer "F.Fab")
		)
		(fp_line
			(start 0.120396 0.2794)
			(end -0.12065 0.2794)
			(stroke
				(width 0.1)
				(type default)
			)
			(layer "F.Fab")
		)
		(fp_line
			(start -0.12065 0.2794)
			(end -0.12065 0.3048)
			(stroke
				(width 0.1)
				(type default)
			)
			(layer "F.Fab")
		)
		(fp_line
			(start 0.67945 0.3048)
			(end 0.120396 0.3048)
			(stroke
				(width 0.1)
				(type default)
			)
			(layer "F.Fab")
		)
		(fp_line
			(start 0.120396 0.3048)
			(end 0.120396 0.2794)
			(stroke
				(width 0.1)
				(type default)
			)
			(layer "F.Fab")
		)
		(fp_line
			(start -0.12065 0.3048)
			(end -0.67945 0.3048)
			(stroke
				(width 0.1)
				(type default)
			)
			(layer "F.Fab")
		)
		(fp_line
			(start -0.67945 0.3048)
			(end -0.67945 -0.305054)
			(stroke
				(width 0.1)
				(type default)
			)
			(layer "F.Fab")
		)
		(pad "1" smd circle
			(at -0.40005 0 90)
			(size 0 0)
			(layers "F.Cu" "F.Mask" "F.Paste")
			(net "PVCCIN_CPU0")
		)
		(pad "2" smd circle
			(at 0.40005 0 90)
			(size 0 0)
			(layers "F.Cu" "F.Mask" "F.Paste")
			(net "GND")
		)
	)
	(footprint ""
		(layer "F.Cu")
		(at 79.666084 -347.930978)
		(property "Reference" "PR286"
			(at 0 0 0)
			(layer "F.SilkS")
			(hide yes)
			(effects
				(font
					(size 1.27 1.27)
				)
			)
		)
		(property "Value" ""
			(at 0 0 0)
			(layer "F.Fab")
			(effects
				(font
					(size 1.27 1.27)
				)
			)
		)
		(duplicate_pad_numbers_are_jumpers no)
		(fp_line
			(start -0.7874 -0.4064)
			(end 0.7874 -0.4064)
			(stroke
				(width 0.1524)
				(type default)
			)
			(layer "F.SilkS")
		)
		(fp_line
			(start -0.7874 0.4064)
			(end -0.7874 -0.4064)
			(stroke
				(width 0.1524)
				(type default)
			)
			(layer "F.SilkS")
		)
		(fp_line
			(start 0.7874 -0.4064)
			(end 0.7874 0.4064)
			(stroke
				(width 0.1524)
				(type default)
			)
			(layer "F.SilkS")
		)
		(fp_line
			(start 0.7874 0.4064)
			(end -0.7874 0.4064)
			(stroke
				(width 0.1524)
				(type default)
			)
			(layer "F.SilkS")
		)
		(fp_line
			(start -0.67945 -0.305054)
			(end -0.12065 -0.305054)
			(stroke
				(width 0.1)
				(type default)
			)
			(layer "F.Fab")
		)
		(fp_line
			(start -0.67945 0.3048)
			(end -0.67945 -0.305054)
			(stroke
				(width 0.1)
				(type default)
			)
			(layer "F.Fab")
		)
		(fp_line
			(start -0.12065 -0.305054)
			(end -0.12065 -0.2794)
			(stroke
				(width 0.1)
				(type default)
			)
			(layer "F.Fab")
		)
		(fp_line
			(start -0.12065 -0.2794)
			(end 0.12065 -0.2794)
			(stroke
				(width 0.1)
				(type default)
			)
			(layer "F.Fab")
		)
		(fp_line
			(start -0.12065 0.2794)
			(end -0.12065 0.3048)
			(stroke
				(width 0.1)
				(type default)
			)
			(layer "F.Fab")
		)
		(fp_line
			(start -0.12065 0.3048)
			(end -0.67945 0.3048)
			(stroke
				(width 0.1)
				(type default)
			)
			(layer "F.Fab")
		)
		(fp_line
			(start 0.120396 0.2794)
			(end -0.12065 0.2794)
			(stroke
				(width 0.1)
				(type default)
			)
			(layer "F.Fab")
		)
		(fp_line
			(start 0.120396 0.3048)
			(end 0.120396 0.2794)
			(stroke
				(width 0.1)
				(type default)
			)
			(layer "F.Fab")
		)
		(fp_line
			(start 0.12065 -0.3048)
			(end 0.67945 -0.3048)
			(stroke
				(width 0.1)
				(type default)
			)
			(layer "F.Fab")
		)
		(fp_line
			(start 0.12065 -0.2794)
			(end 0.12065 -0.3048)
			(stroke
				(width 0.1)
				(type default)
			)
			(layer "F.Fab")
		)
		(fp_line
			(start 0.67945 -0.3048)
			(end 0.67945 0.3048)
			(stroke
				(width 0.1)
				(type default)
			)
			(layer "F.Fab")
		)
		(fp_line
			(start 0.67945 0.3048)
			(end 0.120396 0.3048)
			(stroke
				(width 0.1)
				(type default)
			)
			(layer "F.Fab")
		)
		(pad "1" smd circle
			(at -0.40005 0)
			(size 0 0)
			(layers "F.Cu" "F.Mask" "F.Paste")
			(net "PVCCIN_CPU1_LSET7")
		)
		(pad "2" smd circle
			(at 0.40005 0)
			(size 0 0)
			(layers "F.Cu" "F.Mask" "F.Paste")
			(net "GND")
		)
	)
	(footprint ""
		(layer "F.Cu")
		(at 189.28588 -126.964948 90)
		(property "Reference" "R1833"
			(at 0 0 90)
			(layer "F.SilkS")
			(hide yes)
			(effects
				(font
					(size 1.27 1.27)
				)
			)
		)
		(property "Value" ""
			(at 0 0 90)
			(layer "F.Fab")
			(effects
				(font
					(size 1.27 1.27)
				)
			)
		)
		(duplicate_pad_numbers_are_jumpers no)
		(fp_line
			(start 0.7874 -0.4064)
			(end 0.7874 0.4064)
			(stroke
				(width 0.1524)
				(type default)
			)
			(layer "F.SilkS")
		)
		(fp_line
			(start -0.7874 -0.4064)
			(end 0.7874 -0.4064)
			(stroke
				(width 0.1524)
				(type default)
			)
			(layer "F.SilkS")
		)
		(fp_line
			(start 0.7874 0.4064)
			(end -0.7874 0.4064)
			(stroke
				(width 0.1524)
				(type default)
			)
			(layer "F.SilkS")
		)
		(fp_line
			(start -0.7874 0.4064)
			(end -0.7874 -0.4064)
			(stroke
				(width 0.1524)
				(type default)
			)
			(layer "F.SilkS")
		)
		(fp_line
			(start -0.12065 -0.305054)
			(end -0.12065 -0.2794)
			(stroke
				(width 0.1)
				(type default)
			)
			(layer "F.Fab")
		)
		(fp_line
			(start -0.67945 -0.305054)
			(end -0.12065 -0.305054)
			(stroke
				(width 0.1)
				(type default)
			)
			(layer "F.Fab")
		)
		(fp_line
			(start 0.67945 -0.3048)
			(end 0.67945 0.3048)
			(stroke
				(width 0.1)
				(type default)
			)
			(layer "F.Fab")
		)
		(fp_line
			(start 0.12065 -0.3048)
			(end 0.67945 -0.3048)
			(stroke
				(width 0.1)
				(type default)
			)
			(layer "F.Fab")
		)
		(fp_line
			(start 0.12065 -0.2794)
			(end 0.12065 -0.3048)
			(stroke
				(width 0.1)
				(type default)
			)
			(layer "F.Fab")
		)
		(fp_line
			(start -0.12065 -0.2794)
			(end 0.12065 -0.2794)
			(stroke
				(width 0.1)
				(type default)
			)
			(layer "F.Fab")
		)
		(fp_line
			(start 0.120396 0.2794)
			(end -0.12065 0.2794)
			(stroke
				(width 0.1)
				(type default)
			)
			(layer "F.Fab")
		)
		(fp_line
			(start -0.12065 0.2794)
			(end -0.12065 0.3048)
			(stroke
				(width 0.1)
				(type default)
			)
			(layer "F.Fab")
		)
		(fp_line
			(start 0.67945 0.3048)
			(end 0.120396 0.3048)
			(stroke
				(width 0.1)
				(type default)
			)
			(layer "F.Fab")
		)
		(fp_line
			(start 0.120396 0.3048)
			(end 0.120396 0.2794)
			(stroke
				(width 0.1)
				(type default)
			)
			(layer "F.Fab")
		)
		(fp_line
			(start -0.12065 0.3048)
			(end -0.67945 0.3048)
			(stroke
				(width 0.1)
				(type default)
			)
			(layer "F.Fab")
		)
		(fp_line
			(start -0.67945 0.3048)
			(end -0.67945 -0.305054)
			(stroke
				(width 0.1)
				(type default)
			)
			(layer "F.Fab")
		)
		(pad "1" smd circle
			(at -0.40005 0 90)
			(size 0 0)
			(layers "F.Cu" "F.Mask" "F.Paste")
			(net "FM_JTAG_BMC_MUX_SEL_R")
		)
		(pad "2" smd circle
			(at 0.40005 0 90)
			(size 0 0)
			(layers "F.Cu" "F.Mask" "F.Paste")
			(net "FM_JTAG_BMC_MUX_SEL")
		)
	)
	(footprint ""
		(layer "F.Cu")
		(at 52.15128 -170.576748 -90)
		(property "Reference" "PC428"
			(at 0 0 270)
			(layer "F.SilkS")
			(hide yes)
			(effects
				(font
					(size 1.27 1.27)
				)
			)
		)
		(property "Value" ""
			(at 0 0 270)
			(layer "F.Fab")
			(effects
				(font
					(size 1.27 1.27)
				)
			)
		)
		(duplicate_pad_numbers_are_jumpers no)
		(fp_line
			(start -0.7874 0.4064)
			(end -0.7874 -0.4064)
			(stroke
				(width 0.1524)
				(type default)
			)
			(layer "F.SilkS")
		)
		(fp_line
			(start 0.7874 0.4064)
			(end -0.7874 0.4064)
			(stroke
				(width 0.1524)
				(type default)
			)
			(layer "F.SilkS")
		)
		(fp_line
			(start -0.7874 -0.4064)
			(end 0.7874 -0.4064)
			(stroke
				(width 0.1524)
				(type default)
			)
			(layer "F.SilkS")
		)
		(fp_line
			(start 0.7874 -0.4064)
			(end 0.7874 0.4064)
			(stroke
				(width 0.1524)
				(type default)
			)
			(layer "F.SilkS")
		)
		(fp_line
			(start -0.67945 0.3048)
			(end -0.67945 -0.305054)
			(stroke
				(width 0.1)
				(type default)
			)
			(layer "F.Fab")
		)
		(fp_line
			(start -0.12065 0.3048)
			(end -0.67945 0.3048)
			(stroke
				(width 0.1)
				(type default)
			)
			(layer "F.Fab")
		)
		(fp_line
			(start 0.120396 0.3048)
			(end 0.120396 0.2794)
			(stroke
				(width 0.1)
				(type default)
			)
			(layer "F.Fab")
		)
		(fp_line
			(start 0.67945 0.3048)
			(end 0.120396 0.3048)
			(stroke
				(width 0.1)
				(type default)
			)
			(layer "F.Fab")
		)
		(fp_line
			(start -0.12065 0.2794)
			(end -0.12065 0.3048)
			(stroke
				(width 0.1)
				(type default)
			)
			(layer "F.Fab")
		)
		(fp_line
			(start 0.120396 0.2794)
			(end -0.12065 0.2794)
			(stroke
				(width 0.1)
				(type default)
			)
			(layer "F.Fab")
		)
		(fp_line
			(start -0.12065 -0.2794)
			(end 0.12065 -0.2794)
			(stroke
				(width 0.1)
				(type default)
			)
			(layer "F.Fab")
		)
		(fp_line
			(start 0.12065 -0.2794)
			(end 0.12065 -0.3048)
			(stroke
				(width 0.1)
				(type default)
			)
			(layer "F.Fab")
		)
		(fp_line
			(start 0.12065 -0.3048)
			(end 0.67945 -0.3048)
			(stroke
				(width 0.1)
				(type default)
			)
			(layer "F.Fab")
		)
		(fp_line
			(start 0.67945 -0.3048)
			(end 0.67945 0.3048)
			(stroke
				(width 0.1)
				(type default)
			)
			(layer "F.Fab")
		)
		(fp_line
			(start -0.67945 -0.305054)
			(end -0.12065 -0.305054)
			(stroke
				(width 0.1)
				(type default)
			)
			(layer "F.Fab")
		)
		(fp_line
			(start -0.12065 -0.305054)
			(end -0.12065 -0.2794)
			(stroke
				(width 0.1)
				(type default)
			)
			(layer "F.Fab")
		)
		(pad "1" smd circle
			(at -0.40005 0 270)
			(size 0 0)
			(layers "F.Cu" "F.Mask" "F.Paste")
			(net "PVCCFA_EHV_CPU1_VDD1")
		)
		(pad "2" smd circle
			(at 0.40005 0 270)
			(size 0 0)
			(layers "F.Cu" "F.Mask" "F.Paste")
			(net "GND")
		)
	)
	(footprint ""
		(layer "F.Cu")
		(at 28.578048 -77.783944)
		(property "Reference" "R3143"
			(at 0 0 0)
			(layer "F.SilkS")
			(hide yes)
			(effects
				(font
					(size 1.27 1.27)
				)
			)
		)
		(property "Value" ""
			(at 0 0 0)
			(layer "F.Fab")
			(effects
				(font
					(size 1.27 1.27)
				)
			)
		)
		(duplicate_pad_numbers_are_jumpers no)
		(fp_line
			(start -0.7874 -0.4064)
			(end 0.7874 -0.4064)
			(stroke
				(width 0.1524)
				(type default)
			)
			(layer "F.SilkS")
		)
		(fp_line
			(start -0.7874 0.4064)
			(end -0.7874 -0.4064)
			(stroke
				(width 0.1524)
				(type default)
			)
			(layer "F.SilkS")
		)
		(fp_line
			(start 0.7874 -0.4064)
			(end 0.7874 0.4064)
			(stroke
				(width 0.1524)
				(type default)
			)
			(layer "F.SilkS")
		)
		(fp_line
			(start 0.7874 0.4064)
			(end -0.7874 0.4064)
			(stroke
				(width 0.1524)
				(type default)
			)
			(layer "F.SilkS")
		)
		(fp_line
			(start -0.67945 -0.305054)
			(end -0.12065 -0.305054)
			(stroke
				(width 0.1)
				(type default)
			)
			(layer "F.Fab")
		)
		(fp_line
			(start -0.67945 0.3048)
			(end -0.67945 -0.305054)
			(stroke
				(width 0.1)
				(type default)
			)
			(layer "F.Fab")
		)
		(fp_line
			(start -0.12065 -0.305054)
			(end -0.12065 -0.2794)
			(stroke
				(width 0.1)
				(type default)
			)
			(layer "F.Fab")
		)
		(fp_line
			(start -0.12065 -0.2794)
			(end 0.12065 -0.2794)
			(stroke
				(width 0.1)
				(type default)
			)
			(layer "F.Fab")
		)
		(fp_line
			(start -0.12065 0.2794)
			(end -0.12065 0.3048)
			(stroke
				(width 0.1)
				(type default)
			)
			(layer "F.Fab")
		)
		(fp_line
			(start -0.12065 0.3048)
			(end -0.67945 0.3048)
			(stroke
				(width 0.1)
				(type default)
			)
			(layer "F.Fab")
		)
		(fp_line
			(start 0.120396 0.2794)
			(end -0.12065 0.2794)
			(stroke
				(width 0.1)
				(type default)
			)
			(layer "F.Fab")
		)
		(fp_line
			(start 0.120396 0.3048)
			(end 0.120396 0.2794)
			(stroke
				(width 0.1)
				(type default)
			)
			(layer "F.Fab")
		)
		(fp_line
			(start 0.12065 -0.3048)
			(end 0.67945 -0.3048)
			(stroke
				(width 0.1)
				(type default)
			)
			(layer "F.Fab")
		)
		(fp_line
			(start 0.12065 -0.2794)
			(end 0.12065 -0.3048)
			(stroke
				(width 0.1)
				(type default)
			)
			(layer "F.Fab")
		)
		(fp_line
			(start 0.67945 -0.3048)
			(end 0.67945 0.3048)
			(stroke
				(width 0.1)
				(type default)
			)
			(layer "F.Fab")
		)
		(fp_line
			(start 0.67945 0.3048)
			(end 0.120396 0.3048)
			(stroke
				(width 0.1)
				(type default)
			)
			(layer "F.Fab")
		)
		(pad "1" smd circle
			(at -0.40005 0)
			(size 0 0)
			(layers "F.Cu" "F.Mask" "F.Paste")
			(net "HP_LVC3_OCP_V3_2_PRSNT2_N_R")
		)
		(pad "2" smd circle
			(at 0.40005 0)
			(size 0 0)
			(layers "F.Cu" "F.Mask" "F.Paste")
			(net "HP_LVC3_OCP_V3_2_ATTN_OUT_SW_N")
		)
	)
	(footprint ""
		(layer "F.Cu")
		(at 226.733608 -405.839422 180)
		(property "Reference" "PC2227"
			(at 0 0 180)
			(layer "F.SilkS")
			(hide yes)
			(effects
				(font
					(size 1.27 1.27)
				)
			)
		)
		(property "Value" ""
			(at 0 0 180)
			(layer "F.Fab")
			(effects
				(font
					(size 1.27 1.27)
				)
			)
		)
		(duplicate_pad_numbers_are_jumpers no)
		(fp_line
			(start 0.7874 0.4064)
			(end -0.7874 0.4064)
			(stroke
				(width 0.1524)
				(type default)
			)
			(layer "F.SilkS")
		)
		(fp_line
			(start 0.7874 -0.4064)
			(end 0.7874 0.4064)
			(stroke
				(width 0.1524)
				(type default)
			)
			(layer "F.SilkS")
		)
		(fp_line
			(start -0.7874 0.4064)
			(end -0.7874 -0.4064)
			(stroke
				(width 0.1524)
				(type default)
			)
			(layer "F.SilkS")
		)
		(fp_line
			(start -0.7874 -0.4064)
			(end 0.7874 -0.4064)
			(stroke
				(width 0.1524)
				(type default)
			)
			(layer "F.SilkS")
		)
		(fp_line
			(start 0.67945 0.3048)
			(end 0.120396 0.3048)
			(stroke
				(width 0.1)
				(type default)
			)
			(layer "F.Fab")
		)
		(fp_line
			(start 0.67945 -0.3048)
			(end 0.67945 0.3048)
			(stroke
				(width 0.1)
				(type default)
			)
			(layer "F.Fab")
		)
		(fp_line
			(start 0.12065 -0.2794)
			(end 0.12065 -0.3048)
			(stroke
				(width 0.1)
				(type default)
			)
			(layer "F.Fab")
		)
		(fp_line
			(start 0.12065 -0.3048)
			(end 0.67945 -0.3048)
			(stroke
				(width 0.1)
				(type default)
			)
			(layer "F.Fab")
		)
		(fp_line
			(start 0.120396 0.3048)
			(end 0.120396 0.2794)
			(stroke
				(width 0.1)
				(type default)
			)
			(layer "F.Fab")
		)
		(fp_line
			(start 0.120396 0.2794)
			(end -0.12065 0.2794)
			(stroke
				(width 0.1)
				(type default)
			)
			(layer "F.Fab")
		)
		(fp_line
			(start -0.12065 0.3048)
			(end -0.67945 0.3048)
			(stroke
				(width 0.1)
				(type default)
			)
			(layer "F.Fab")
		)
		(fp_line
			(start -0.12065 0.2794)
			(end -0.12065 0.3048)
			(stroke
				(width 0.1)
				(type default)
			)
			(layer "F.Fab")
		)
		(fp_line
			(start -0.12065 -0.2794)
			(end 0.12065 -0.2794)
			(stroke
				(width 0.1)
				(type default)
			)
			(layer "F.Fab")
		)
		(fp_line
			(start -0.12065 -0.305054)
			(end -0.12065 -0.2794)
			(stroke
				(width 0.1)
				(type default)
			)
			(layer "F.Fab")
		)
		(fp_line
			(start -0.67945 0.3048)
			(end -0.67945 -0.305054)
			(stroke
				(width 0.1)
				(type default)
			)
			(layer "F.Fab")
		)
		(fp_line
			(start -0.67945 -0.305054)
			(end -0.12065 -0.305054)
			(stroke
				(width 0.1)
				(type default)
			)
			(layer "F.Fab")
		)
		(pad "1" smd circle
			(at -0.40005 0 180)
			(size 0 0)
			(layers "F.Cu" "F.Mask" "F.Paste")
			(net "HSC_SS")
		)
		(pad "2" smd circle
			(at 0.40005 0 180)
			(size 0 0)
			(layers "F.Cu" "F.Mask" "F.Paste")
			(net "AGND_HSC")
		)
	)
	(footprint ""
		(layer "F.Cu")
		(at 106.990896 -338.180172 -90)
		(property "Reference" "PC564"
			(at 0 0 270)
			(layer "F.SilkS")
			(hide yes)
			(effects
				(font
					(size 1.27 1.27)
				)
			)
		)
		(property "Value" ""
			(at 0 0 270)
			(layer "F.Fab")
			(effects
				(font
					(size 1.27 1.27)
				)
			)
		)
		(duplicate_pad_numbers_are_jumpers no)
		(fp_line
			(start -0.7874 0.4064)
			(end -0.7874 -0.4064)
			(stroke
				(width 0.1524)
				(type default)
			)
			(layer "F.SilkS")
		)
		(fp_line
			(start 0.7874 0.4064)
			(end -0.7874 0.4064)
			(stroke
				(width 0.1524)
				(type default)
			)
			(layer "F.SilkS")
		)
		(fp_line
			(start -0.7874 -0.4064)
			(end 0.7874 -0.4064)
			(stroke
				(width 0.1524)
				(type default)
			)
			(layer "F.SilkS")
		)
		(fp_line
			(start 0.7874 -0.4064)
			(end 0.7874 0.4064)
			(stroke
				(width 0.1524)
				(type default)
			)
			(layer "F.SilkS")
		)
		(fp_line
			(start -0.67945 0.3048)
			(end -0.67945 -0.305054)
			(stroke
				(width 0.1)
				(type default)
			)
			(layer "F.Fab")
		)
		(fp_line
			(start -0.12065 0.3048)
			(end -0.67945 0.3048)
			(stroke
				(width 0.1)
				(type default)
			)
			(layer "F.Fab")
		)
		(fp_line
			(start 0.120396 0.3048)
			(end 0.120396 0.2794)
			(stroke
				(width 0.1)
				(type default)
			)
			(layer "F.Fab")
		)
		(fp_line
			(start 0.67945 0.3048)
			(end 0.120396 0.3048)
			(stroke
				(width 0.1)
				(type default)
			)
			(layer "F.Fab")
		)
		(fp_line
			(start -0.12065 0.2794)
			(end -0.12065 0.3048)
			(stroke
				(width 0.1)
				(type default)
			)
			(layer "F.Fab")
		)
		(fp_line
			(start 0.120396 0.2794)
			(end -0.12065 0.2794)
			(stroke
				(width 0.1)
				(type default)
			)
			(layer "F.Fab")
		)
		(fp_line
			(start -0.12065 -0.2794)
			(end 0.12065 -0.2794)
			(stroke
				(width 0.1)
				(type default)
			)
			(layer "F.Fab")
		)
		(fp_line
			(start 0.12065 -0.2794)
			(end 0.12065 -0.3048)
			(stroke
				(width 0.1)
				(type default)
			)
			(layer "F.Fab")
		)
		(fp_line
			(start 0.12065 -0.3048)
			(end 0.67945 -0.3048)
			(stroke
				(width 0.1)
				(type default)
			)
			(layer "F.Fab")
		)
		(fp_line
			(start 0.67945 -0.3048)
			(end 0.67945 0.3048)
			(stroke
				(width 0.1)
				(type default)
			)
			(layer "F.Fab")
		)
		(fp_line
			(start -0.67945 -0.305054)
			(end -0.12065 -0.305054)
			(stroke
				(width 0.1)
				(type default)
			)
			(layer "F.Fab")
		)
		(fp_line
			(start -0.12065 -0.305054)
			(end -0.12065 -0.2794)
			(stroke
				(width 0.1)
				(type default)
			)
			(layer "F.Fab")
		)
		(pad "1" smd circle
			(at -0.40005 0 270)
			(size 0 0)
			(layers "F.Cu" "F.Mask" "F.Paste")
			(net "SW_PVCCIN_CPU1_BOOT2_R")
		)
		(pad "2" smd circle
			(at 0.40005 0 270)
			(size 0 0)
			(layers "F.Cu" "F.Mask" "F.Paste")
			(net "SW_PVCCIN_CPU1_BOOTR2")
		)
	)
	(footprint ""
		(layer "F.Cu")
		(at 101.833934 -397.46174 180)
		(property "Reference" "R3496"
			(at 0 0 180)
			(layer "F.SilkS")
			(hide yes)
			(effects
				(font
					(size 1.27 1.27)
				)
			)
		)
		(property "Value" ""
			(at 0 0 180)
			(layer "F.Fab")
			(effects
				(font
					(size 1.27 1.27)
				)
			)
		)
		(duplicate_pad_numbers_are_jumpers no)
		(fp_line
			(start 0.7874 0.4064)
			(end -0.7874 0.4064)
			(stroke
				(width 0.1524)
				(type default)
			)
			(layer "F.SilkS")
		)
		(fp_line
			(start 0.7874 -0.4064)
			(end 0.7874 0.4064)
			(stroke
				(width 0.1524)
				(type default)
			)
			(layer "F.SilkS")
		)
		(fp_line
			(start -0.7874 0.4064)
			(end -0.7874 -0.4064)
			(stroke
				(width 0.1524)
				(type default)
			)
			(layer "F.SilkS")
		)
		(fp_line
			(start -0.7874 -0.4064)
			(end 0.7874 -0.4064)
			(stroke
				(width 0.1524)
				(type default)
			)
			(layer "F.SilkS")
		)
		(fp_line
			(start 0.67945 0.3048)
			(end 0.120396 0.3048)
			(stroke
				(width 0.1)
				(type default)
			)
			(layer "F.Fab")
		)
		(fp_line
			(start 0.67945 -0.3048)
			(end 0.67945 0.3048)
			(stroke
				(width 0.1)
				(type default)
			)
			(layer "F.Fab")
		)
		(fp_line
			(start 0.12065 -0.2794)
			(end 0.12065 -0.3048)
			(stroke
				(width 0.1)
				(type default)
			)
			(layer "F.Fab")
		)
		(fp_line
			(start 0.12065 -0.3048)
			(end 0.67945 -0.3048)
			(stroke
				(width 0.1)
				(type default)
			)
			(layer "F.Fab")
		)
		(fp_line
			(start 0.120396 0.3048)
			(end 0.120396 0.2794)
			(stroke
				(width 0.1)
				(type default)
			)
			(layer "F.Fab")
		)
		(fp_line
			(start 0.120396 0.2794)
			(end -0.12065 0.2794)
			(stroke
				(width 0.1)
				(type default)
			)
			(layer "F.Fab")
		)
		(fp_line
			(start -0.12065 0.3048)
			(end -0.67945 0.3048)
			(stroke
				(width 0.1)
				(type default)
			)
			(layer "F.Fab")
		)
		(fp_line
			(start -0.12065 0.2794)
			(end -0.12065 0.3048)
			(stroke
				(width 0.1)
				(type default)
			)
			(layer "F.Fab")
		)
		(fp_line
			(start -0.12065 -0.2794)
			(end 0.12065 -0.2794)
			(stroke
				(width 0.1)
				(type default)
			)
			(layer "F.Fab")
		)
		(fp_line
			(start -0.12065 -0.305054)
			(end -0.12065 -0.2794)
			(stroke
				(width 0.1)
				(type default)
			)
			(layer "F.Fab")
		)
		(fp_line
			(start -0.67945 0.3048)
			(end -0.67945 -0.305054)
			(stroke
				(width 0.1)
				(type default)
			)
			(layer "F.Fab")
		)
		(fp_line
			(start -0.67945 -0.305054)
			(end -0.12065 -0.305054)
			(stroke
				(width 0.1)
				(type default)
			)
			(layer "F.Fab")
		)
		(pad "1" smd circle
			(at -0.40005 0 180)
			(size 0 0)
			(layers "F.Cu" "F.Mask" "F.Paste")
			(net "GPU_FPGA_EROT_RST_BUF_R_N")
		)
		(pad "2" smd circle
			(at 0.40005 0 180)
			(size 0 0)
			(layers "F.Cu" "F.Mask" "F.Paste")
			(net "GPU_FPGA_EROT_RST_BUF_N")
		)
	)
	(footprint ""
		(layer "F.Cu")
		(at 87.947246 -57.279286 90)
		(property "Reference" "PC2140"
			(at 0 0 90)
			(layer "F.SilkS")
			(hide yes)
			(effects
				(font
					(size 1.27 1.27)
				)
			)
		)
		(property "Value" ""
			(at 0 0 90)
			(layer "F.Fab")
			(effects
				(font
					(size 1.27 1.27)
				)
			)
		)
		(duplicate_pad_numbers_are_jumpers no)
		(fp_line
			(start 0.7874 -0.4064)
			(end 0.7874 0.4064)
			(stroke
				(width 0.1524)
				(type default)
			)
			(layer "F.SilkS")
		)
		(fp_line
			(start -0.7874 -0.4064)
			(end 0.7874 -0.4064)
			(stroke
				(width 0.1524)
				(type default)
			)
			(layer "F.SilkS")
		)
		(fp_line
			(start 0.7874 0.4064)
			(end -0.7874 0.4064)
			(stroke
				(width 0.1524)
				(type default)
			)
			(layer "F.SilkS")
		)
		(fp_line
			(start -0.7874 0.4064)
			(end -0.7874 -0.4064)
			(stroke
				(width 0.1524)
				(type default)
			)
			(layer "F.SilkS")
		)
		(fp_line
			(start -0.12065 -0.305054)
			(end -0.12065 -0.2794)
			(stroke
				(width 0.1)
				(type default)
			)
			(layer "F.Fab")
		)
		(fp_line
			(start -0.67945 -0.305054)
			(end -0.12065 -0.305054)
			(stroke
				(width 0.1)
				(type default)
			)
			(layer "F.Fab")
		)
		(fp_line
			(start 0.67945 -0.3048)
			(end 0.67945 0.3048)
			(stroke
				(width 0.1)
				(type default)
			)
			(layer "F.Fab")
		)
		(fp_line
			(start 0.12065 -0.3048)
			(end 0.67945 -0.3048)
			(stroke
				(width 0.1)
				(type default)
			)
			(layer "F.Fab")
		)
		(fp_line
			(start 0.12065 -0.2794)
			(end 0.12065 -0.3048)
			(stroke
				(width 0.1)
				(type default)
			)
			(layer "F.Fab")
		)
		(fp_line
			(start -0.12065 -0.2794)
			(end 0.12065 -0.2794)
			(stroke
				(width 0.1)
				(type default)
			)
			(layer "F.Fab")
		)
		(fp_line
			(start 0.120396 0.2794)
			(end -0.12065 0.2794)
			(stroke
				(width 0.1)
				(type default)
			)
			(layer "F.Fab")
		)
		(fp_line
			(start -0.12065 0.2794)
			(end -0.12065 0.3048)
			(stroke
				(width 0.1)
				(type default)
			)
			(layer "F.Fab")
		)
		(fp_line
			(start 0.67945 0.3048)
			(end 0.120396 0.3048)
			(stroke
				(width 0.1)
				(type default)
			)
			(layer "F.Fab")
		)
		(fp_line
			(start 0.120396 0.3048)
			(end 0.120396 0.2794)
			(stroke
				(width 0.1)
				(type default)
			)
			(layer "F.Fab")
		)
		(fp_line
			(start -0.12065 0.3048)
			(end -0.67945 0.3048)
			(stroke
				(width 0.1)
				(type default)
			)
			(layer "F.Fab")
		)
		(fp_line
			(start -0.67945 0.3048)
			(end -0.67945 -0.305054)
			(stroke
				(width 0.1)
				(type default)
			)
			(layer "F.Fab")
		)
		(pad "1" smd circle
			(at -0.40005 0 90)
			(size 0 0)
			(layers "F.Cu" "F.Mask" "F.Paste")
			(net "P3V3_AUX")
		)
		(pad "2" smd circle
			(at 0.40005 0 90)
			(size 0 0)
			(layers "F.Cu" "F.Mask" "F.Paste")
			(net "GND")
		)
	)
	(footprint ""
		(layer "F.Cu")
		(at 36.884102 -122.380502 90)
		(property "Reference" "R2449"
			(at 0 0 90)
			(layer "F.SilkS")
			(hide yes)
			(effects
				(font
					(size 1.27 1.27)
				)
			)
		)
		(property "Value" ""
			(at 0 0 90)
			(layer "F.Fab")
			(effects
				(font
					(size 1.27 1.27)
				)
			)
		)
		(duplicate_pad_numbers_are_jumpers no)
		(fp_line
			(start 0.7874 -0.4064)
			(end 0.7874 0.4064)
			(stroke
				(width 0.1524)
				(type default)
			)
			(layer "F.SilkS")
		)
		(fp_line
			(start -0.7874 -0.4064)
			(end 0.7874 -0.4064)
			(stroke
				(width 0.1524)
				(type default)
			)
			(layer "F.SilkS")
		)
		(fp_line
			(start 0.7874 0.4064)
			(end -0.7874 0.4064)
			(stroke
				(width 0.1524)
				(type default)
			)
			(layer "F.SilkS")
		)
		(fp_line
			(start -0.7874 0.4064)
			(end -0.7874 -0.4064)
			(stroke
				(width 0.1524)
				(type default)
			)
			(layer "F.SilkS")
		)
		(fp_line
			(start -0.12065 -0.305054)
			(end -0.12065 -0.2794)
			(stroke
				(width 0.1)
				(type default)
			)
			(layer "F.Fab")
		)
		(fp_line
			(start -0.67945 -0.305054)
			(end -0.12065 -0.305054)
			(stroke
				(width 0.1)
				(type default)
			)
			(layer "F.Fab")
		)
		(fp_line
			(start 0.67945 -0.3048)
			(end 0.67945 0.3048)
			(stroke
				(width 0.1)
				(type default)
			)
			(layer "F.Fab")
		)
		(fp_line
			(start 0.12065 -0.3048)
			(end 0.67945 -0.3048)
			(stroke
				(width 0.1)
				(type default)
			)
			(layer "F.Fab")
		)
		(fp_line
			(start 0.12065 -0.2794)
			(end 0.12065 -0.3048)
			(stroke
				(width 0.1)
				(type default)
			)
			(layer "F.Fab")
		)
		(fp_line
			(start -0.12065 -0.2794)
			(end 0.12065 -0.2794)
			(stroke
				(width 0.1)
				(type default)
			)
			(layer "F.Fab")
		)
		(fp_line
			(start 0.120396 0.2794)
			(end -0.12065 0.2794)
			(stroke
				(width 0.1)
				(type default)
			)
			(layer "F.Fab")
		)
		(fp_line
			(start -0.12065 0.2794)
			(end -0.12065 0.3048)
			(stroke
				(width 0.1)
				(type default)
			)
			(layer "F.Fab")
		)
		(fp_line
			(start 0.67945 0.3048)
			(end 0.120396 0.3048)
			(stroke
				(width 0.1)
				(type default)
			)
			(layer "F.Fab")
		)
		(fp_line
			(start 0.120396 0.3048)
			(end 0.120396 0.2794)
			(stroke
				(width 0.1)
				(type default)
			)
			(layer "F.Fab")
		)
		(fp_line
			(start -0.12065 0.3048)
			(end -0.67945 0.3048)
			(stroke
				(width 0.1)
				(type default)
			)
			(layer "F.Fab")
		)
		(fp_line
			(start -0.67945 0.3048)
			(end -0.67945 -0.305054)
			(stroke
				(width 0.1)
				(type default)
			)
			(layer "F.Fab")
		)
		(pad "1" smd circle
			(at -0.40005 0 90)
			(size 0 0)
			(layers "F.Cu" "F.Mask" "F.Paste")
			(net "SMB_VR_3V3AUX_SCL")
		)
		(pad "2" smd circle
			(at 0.40005 0 90)
			(size 0 0)
			(layers "F.Cu" "F.Mask" "F.Paste")
			(net "SMB_VR_3V3AUX_SCL_R1")
		)
	)
	(footprint ""
		(layer "F.Cu")
		(at 138.55954 -347.520514 90)
		(property "Reference" "PR1792"
			(at 0 0 90)
			(layer "F.SilkS")
			(hide yes)
			(effects
				(font
					(size 1.27 1.27)
				)
			)
		)
		(property "Value" ""
			(at 0 0 90)
			(layer "F.Fab")
			(effects
				(font
					(size 1.27 1.27)
				)
			)
		)
		(duplicate_pad_numbers_are_jumpers no)
		(fp_line
			(start 0.7874 -0.4064)
			(end 0.7874 0.4064)
			(stroke
				(width 0.1524)
				(type default)
			)
			(layer "F.SilkS")
		)
		(fp_line
			(start -0.7874 -0.4064)
			(end 0.7874 -0.4064)
			(stroke
				(width 0.1524)
				(type default)
			)
			(layer "F.SilkS")
		)
		(fp_line
			(start 0.7874 0.4064)
			(end -0.7874 0.4064)
			(stroke
				(width 0.1524)
				(type default)
			)
			(layer "F.SilkS")
		)
		(fp_line
			(start -0.7874 0.4064)
			(end -0.7874 -0.4064)
			(stroke
				(width 0.1524)
				(type default)
			)
			(layer "F.SilkS")
		)
		(fp_line
			(start -0.12065 -0.305054)
			(end -0.12065 -0.2794)
			(stroke
				(width 0.1)
				(type default)
			)
			(layer "F.Fab")
		)
		(fp_line
			(start -0.67945 -0.305054)
			(end -0.12065 -0.305054)
			(stroke
				(width 0.1)
				(type default)
			)
			(layer "F.Fab")
		)
		(fp_line
			(start 0.67945 -0.3048)
			(end 0.67945 0.3048)
			(stroke
				(width 0.1)
				(type default)
			)
			(layer "F.Fab")
		)
		(fp_line
			(start 0.12065 -0.3048)
			(end 0.67945 -0.3048)
			(stroke
				(width 0.1)
				(type default)
			)
			(layer "F.Fab")
		)
		(fp_line
			(start 0.12065 -0.2794)
			(end 0.12065 -0.3048)
			(stroke
				(width 0.1)
				(type default)
			)
			(layer "F.Fab")
		)
		(fp_line
			(start -0.12065 -0.2794)
			(end 0.12065 -0.2794)
			(stroke
				(width 0.1)
				(type default)
			)
			(layer "F.Fab")
		)
		(fp_line
			(start 0.120396 0.2794)
			(end -0.12065 0.2794)
			(stroke
				(width 0.1)
				(type default)
			)
			(layer "F.Fab")
		)
		(fp_line
			(start -0.12065 0.2794)
			(end -0.12065 0.3048)
			(stroke
				(width 0.1)
				(type default)
			)
			(layer "F.Fab")
		)
		(fp_line
			(start 0.67945 0.3048)
			(end 0.120396 0.3048)
			(stroke
				(width 0.1)
				(type default)
			)
			(layer "F.Fab")
		)
		(fp_line
			(start 0.120396 0.3048)
			(end 0.120396 0.2794)
			(stroke
				(width 0.1)
				(type default)
			)
			(layer "F.Fab")
		)
		(fp_line
			(start -0.12065 0.3048)
			(end -0.67945 0.3048)
			(stroke
				(width 0.1)
				(type default)
			)
			(layer "F.Fab")
		)
		(fp_line
			(start -0.67945 0.3048)
			(end -0.67945 -0.305054)
			(stroke
				(width 0.1)
				(type default)
			)
			(layer "F.Fab")
		)
		(pad "1" smd circle
			(at -0.40005 0 90)
			(size 0 0)
			(layers "F.Cu" "F.Mask" "F.Paste")
			(net "SW_PVCCIN_CPU1_BOOT8")
		)
		(pad "2" smd circle
			(at 0.40005 0 90)
			(size 0 0)
			(layers "F.Cu" "F.Mask" "F.Paste")
			(net "SW_PVCCIN_CPU1_BOOT8_R")
		)
	)
	(footprint ""
		(layer "F.Cu")
		(at 352.089974 -354.495862 -90)
		(property "Reference" "C3268"
			(at 0 0 270)
			(layer "F.SilkS")
			(hide yes)
			(effects
				(font
					(size 1.27 1.27)
				)
			)
		)
		(property "Value" ""
			(at 0 0 270)
			(layer "F.Fab")
			(effects
				(font
					(size 1.27 1.27)
				)
			)
		)
		(duplicate_pad_numbers_are_jumpers no)
		(fp_line
			(start -0.7874 0.4064)
			(end -0.7874 -0.4064)
			(stroke
				(width 0.1524)
				(type default)
			)
			(layer "F.SilkS")
		)
		(fp_line
			(start 0.7874 0.4064)
			(end -0.7874 0.4064)
			(stroke
				(width 0.1524)
				(type default)
			)
			(layer "F.SilkS")
		)
		(fp_line
			(start -0.7874 -0.4064)
			(end 0.7874 -0.4064)
			(stroke
				(width 0.1524)
				(type default)
			)
			(layer "F.SilkS")
		)
		(fp_line
			(start 0.7874 -0.4064)
			(end 0.7874 0.4064)
			(stroke
				(width 0.1524)
				(type default)
			)
			(layer "F.SilkS")
		)
		(fp_line
			(start -0.67945 0.3048)
			(end -0.67945 -0.305054)
			(stroke
				(width 0.1)
				(type default)
			)
			(layer "F.Fab")
		)
		(fp_line
			(start -0.12065 0.3048)
			(end -0.67945 0.3048)
			(stroke
				(width 0.1)
				(type default)
			)
			(layer "F.Fab")
		)
		(fp_line
			(start 0.120396 0.3048)
			(end 0.120396 0.2794)
			(stroke
				(width 0.1)
				(type default)
			)
			(layer "F.Fab")
		)
		(fp_line
			(start 0.67945 0.3048)
			(end 0.120396 0.3048)
			(stroke
				(width 0.1)
				(type default)
			)
			(layer "F.Fab")
		)
		(fp_line
			(start -0.12065 0.2794)
			(end -0.12065 0.3048)
			(stroke
				(width 0.1)
				(type default)
			)
			(layer "F.Fab")
		)
		(fp_line
			(start 0.120396 0.2794)
			(end -0.12065 0.2794)
			(stroke
				(width 0.1)
				(type default)
			)
			(layer "F.Fab")
		)
		(fp_line
			(start -0.12065 -0.2794)
			(end 0.12065 -0.2794)
			(stroke
				(width 0.1)
				(type default)
			)
			(layer "F.Fab")
		)
		(fp_line
			(start 0.12065 -0.2794)
			(end 0.12065 -0.3048)
			(stroke
				(width 0.1)
				(type default)
			)
			(layer "F.Fab")
		)
		(fp_line
			(start 0.12065 -0.3048)
			(end 0.67945 -0.3048)
			(stroke
				(width 0.1)
				(type default)
			)
			(layer "F.Fab")
		)
		(fp_line
			(start 0.67945 -0.3048)
			(end 0.67945 0.3048)
			(stroke
				(width 0.1)
				(type default)
			)
			(layer "F.Fab")
		)
		(fp_line
			(start -0.67945 -0.305054)
			(end -0.12065 -0.305054)
			(stroke
				(width 0.1)
				(type default)
			)
			(layer "F.Fab")
		)
		(fp_line
			(start -0.12065 -0.305054)
			(end -0.12065 -0.2794)
			(stroke
				(width 0.1)
				(type default)
			)
			(layer "F.Fab")
		)
		(pad "1" smd circle
			(at -0.40005 0 270)
			(size 0 0)
			(layers "F.Cu" "F.Mask" "F.Paste")
			(net "PVCCFA_EHV_FIVRA_CPU0_EN_R")
		)
		(pad "2" smd circle
			(at 0.40005 0 270)
			(size 0 0)
			(layers "F.Cu" "F.Mask" "F.Paste")
			(net "GND")
		)
	)
	(footprint ""
		(layer "F.Cu")
		(at 428.62373 -119.349012 180)
		(property "Reference" "PC632"
			(at 0 0 180)
			(layer "F.SilkS")
			(hide yes)
			(effects
				(font
					(size 1.27 1.27)
				)
			)
		)
		(property "Value" ""
			(at 0 0 180)
			(layer "F.Fab")
			(effects
				(font
					(size 1.27 1.27)
				)
			)
		)
		(duplicate_pad_numbers_are_jumpers no)
		(fp_line
			(start 0.7874 0.4064)
			(end -0.7874 0.4064)
			(stroke
				(width 0.1524)
				(type default)
			)
			(layer "F.SilkS")
		)
		(fp_line
			(start 0.7874 -0.4064)
			(end 0.7874 0.4064)
			(stroke
				(width 0.1524)
				(type default)
			)
			(layer "F.SilkS")
		)
		(fp_line
			(start -0.7874 0.4064)
			(end -0.7874 -0.4064)
			(stroke
				(width 0.1524)
				(type default)
			)
			(layer "F.SilkS")
		)
		(fp_line
			(start -0.7874 -0.4064)
			(end 0.7874 -0.4064)
			(stroke
				(width 0.1524)
				(type default)
			)
			(layer "F.SilkS")
		)
		(fp_line
			(start 0.67945 0.3048)
			(end 0.120396 0.3048)
			(stroke
				(width 0.1)
				(type default)
			)
			(layer "F.Fab")
		)
		(fp_line
			(start 0.67945 -0.3048)
			(end 0.67945 0.3048)
			(stroke
				(width 0.1)
				(type default)
			)
			(layer "F.Fab")
		)
		(fp_line
			(start 0.12065 -0.2794)
			(end 0.12065 -0.3048)
			(stroke
				(width 0.1)
				(type default)
			)
			(layer "F.Fab")
		)
		(fp_line
			(start 0.12065 -0.3048)
			(end 0.67945 -0.3048)
			(stroke
				(width 0.1)
				(type default)
			)
			(layer "F.Fab")
		)
		(fp_line
			(start 0.120396 0.3048)
			(end 0.120396 0.2794)
			(stroke
				(width 0.1)
				(type default)
			)
			(layer "F.Fab")
		)
		(fp_line
			(start 0.120396 0.2794)
			(end -0.12065 0.2794)
			(stroke
				(width 0.1)
				(type default)
			)
			(layer "F.Fab")
		)
		(fp_line
			(start -0.12065 0.3048)
			(end -0.67945 0.3048)
			(stroke
				(width 0.1)
				(type default)
			)
			(layer "F.Fab")
		)
		(fp_line
			(start -0.12065 0.2794)
			(end -0.12065 0.3048)
			(stroke
				(width 0.1)
				(type default)
			)
			(layer "F.Fab")
		)
		(fp_line
			(start -0.12065 -0.2794)
			(end 0.12065 -0.2794)
			(stroke
				(width 0.1)
				(type default)
			)
			(layer "F.Fab")
		)
		(fp_line
			(start -0.12065 -0.305054)
			(end -0.12065 -0.2794)
			(stroke
				(width 0.1)
				(type default)
			)
			(layer "F.Fab")
		)
		(fp_line
			(start -0.67945 0.3048)
			(end -0.67945 -0.305054)
			(stroke
				(width 0.1)
				(type default)
			)
			(layer "F.Fab")
		)
		(fp_line
			(start -0.67945 -0.305054)
			(end -0.12065 -0.305054)
			(stroke
				(width 0.1)
				(type default)
			)
			(layer "F.Fab")
		)
		(pad "1" smd circle
			(at -0.40005 0 180)
			(size 0 0)
			(layers "F.Cu" "F.Mask" "F.Paste")
			(net "PVCCD_HV_CPU0_VCC")
		)
		(pad "2" smd circle
			(at 0.40005 0 180)
			(size 0 0)
			(layers "F.Cu" "F.Mask" "F.Paste")
			(net "GND")
		)
	)
	(footprint ""
		(layer "F.Cu")
		(at 377.300998 -75.74788 180)
		(property "Reference" "PL170"
			(at 8.649208 2.006092 0)
			(unlocked yes)
			(layer "F.SilkS")
			(effects
				(font
					(size 0.7874 0.5842)
					(thickness 0.1524)
				)
				(justify left)
			)
		)
		(property "Value" ""
			(at 0 0 180)
			(layer "F.Fab")
			(effects
				(font
					(size 1.27 1.27)
				)
			)
		)
		(duplicate_pad_numbers_are_jumpers no)
		(fp_line
			(start 3.64998 3.350006)
			(end -3.64998 3.350006)
			(stroke
				(width 0.1524)
				(type default)
			)
			(layer "F.SilkS")
		)
		(fp_line
			(start 3.64998 1.8034)
			(end 3.64998 3.350006)
			(stroke
				(width 0.1524)
				(type default)
			)
			(layer "F.SilkS")
		)
		(fp_line
			(start 3.64998 -3.350006)
			(end 3.64998 -1.8034)
			(stroke
				(width 0.1524)
				(type default)
			)
			(layer "F.SilkS")
		)
		(fp_line
			(start -3.64998 3.350006)
			(end -3.64998 1.8288)
			(stroke
				(width 0.1524)
				(type default)
			)
			(layer "F.SilkS")
		)
		(fp_line
			(start -3.64998 -1.8034)
			(end -3.64998 -3.350006)
			(stroke
				(width 0.1524)
				(type default)
			)
			(layer "F.SilkS")
		)
		(fp_line
			(start -3.6576 -3.350006)
			(end 3.64998 -3.350006)
			(stroke
				(width 0.1524)
				(type default)
			)
			(layer "F.SilkS")
		)
		(fp_line
			(start 3.64998 3.350006)
			(end -3.64998 3.350006)
			(stroke
				(width 0.1)
				(type default)
			)
			(layer "F.Fab")
		)
		(fp_line
			(start 3.64998 -3.350006)
			(end 3.64998 3.350006)
			(stroke
				(width 0.1)
				(type default)
			)
			(layer "F.Fab")
		)
		(fp_line
			(start -3.64998 3.350006)
			(end -3.64998 -3.350006)
			(stroke
				(width 0.1)
				(type default)
			)
			(layer "F.Fab")
		)
		(fp_line
			(start -3.64998 -3.350006)
			(end 3.64998 -3.350006)
			(stroke
				(width 0.1)
				(type default)
			)
			(layer "F.Fab")
		)
		(pad "1" smd rect
			(at -2.92481 0 180)
			(size 2.15392 3.302)
			(layers "F.Cu" "F.Mask" "F.Paste")
			(net "SW_P1V8_PCH_AUX_SW")
		)
		(pad "2" smd rect
			(at 2.92481 0 180)
			(size 2.15392 3.302)
			(layers "F.Cu" "F.Mask" "F.Paste")
			(net "P1V8_PCH_AUX")
		)
	)
	(footprint ""
		(layer "F.Cu")
		(at 102.844346 -357.562658)
		(property "Reference" "R310"
			(at 0 0 0)
			(layer "F.SilkS")
			(hide yes)
			(effects
				(font
					(size 1.27 1.27)
				)
			)
		)
		(property "Value" ""
			(at 0 0 0)
			(layer "F.Fab")
			(effects
				(font
					(size 1.27 1.27)
				)
			)
		)
		(duplicate_pad_numbers_are_jumpers no)
		(fp_line
			(start -0.7874 -0.4064)
			(end 0.7874 -0.4064)
			(stroke
				(width 0.1524)
				(type default)
			)
			(layer "F.SilkS")
		)
		(fp_line
			(start -0.7874 0.4064)
			(end -0.7874 -0.4064)
			(stroke
				(width 0.1524)
				(type default)
			)
			(layer "F.SilkS")
		)
		(fp_line
			(start 0.7874 -0.4064)
			(end 0.7874 0.4064)
			(stroke
				(width 0.1524)
				(type default)
			)
			(layer "F.SilkS")
		)
		(fp_line
			(start 0.7874 0.4064)
			(end -0.7874 0.4064)
			(stroke
				(width 0.1524)
				(type default)
			)
			(layer "F.SilkS")
		)
		(fp_line
			(start -0.67945 -0.305054)
			(end -0.12065 -0.305054)
			(stroke
				(width 0.1)
				(type default)
			)
			(layer "F.Fab")
		)
		(fp_line
			(start -0.67945 0.3048)
			(end -0.67945 -0.305054)
			(stroke
				(width 0.1)
				(type default)
			)
			(layer "F.Fab")
		)
		(fp_line
			(start -0.12065 -0.305054)
			(end -0.12065 -0.2794)
			(stroke
				(width 0.1)
				(type default)
			)
			(layer "F.Fab")
		)
		(fp_line
			(start -0.12065 -0.2794)
			(end 0.12065 -0.2794)
			(stroke
				(width 0.1)
				(type default)
			)
			(layer "F.Fab")
		)
		(fp_line
			(start -0.12065 0.2794)
			(end -0.12065 0.3048)
			(stroke
				(width 0.1)
				(type default)
			)
			(layer "F.Fab")
		)
		(fp_line
			(start -0.12065 0.3048)
			(end -0.67945 0.3048)
			(stroke
				(width 0.1)
				(type default)
			)
			(layer "F.Fab")
		)
		(fp_line
			(start 0.120396 0.2794)
			(end -0.12065 0.2794)
			(stroke
				(width 0.1)
				(type default)
			)
			(layer "F.Fab")
		)
		(fp_line
			(start 0.120396 0.3048)
			(end 0.120396 0.2794)
			(stroke
				(width 0.1)
				(type default)
			)
			(layer "F.Fab")
		)
		(fp_line
			(start 0.12065 -0.3048)
			(end 0.67945 -0.3048)
			(stroke
				(width 0.1)
				(type default)
			)
			(layer "F.Fab")
		)
		(fp_line
			(start 0.12065 -0.2794)
			(end 0.12065 -0.3048)
			(stroke
				(width 0.1)
				(type default)
			)
			(layer "F.Fab")
		)
		(fp_line
			(start 0.67945 -0.3048)
			(end 0.67945 0.3048)
			(stroke
				(width 0.1)
				(type default)
			)
			(layer "F.Fab")
		)
		(fp_line
			(start 0.67945 0.3048)
			(end 0.120396 0.3048)
			(stroke
				(width 0.1)
				(type default)
			)
			(layer "F.Fab")
		)
		(pad "1" smd circle
			(at -0.40005 0)
			(size 0 0)
			(layers "F.Cu" "F.Mask" "F.Paste")
			(net "SVID_CLK0_CPU1_R")
		)
		(pad "2" smd circle
			(at 0.40005 0)
			(size 0 0)
			(layers "F.Cu" "F.Mask" "F.Paste")
			(net "SVID_CLK_PVCCIN_CPU1_R")
		)
	)
	(footprint ""
		(layer "F.Cu")
		(at 434.808122 -32.573468 180)
		(property "Reference" "R3870"
			(at 0 0 180)
			(layer "F.SilkS")
			(hide yes)
			(effects
				(font
					(size 1.27 1.27)
				)
			)
		)
		(property "Value" ""
			(at 0 0 180)
			(layer "F.Fab")
			(effects
				(font
					(size 1.27 1.27)
				)
			)
		)
		(duplicate_pad_numbers_are_jumpers no)
		(fp_line
			(start 0.7874 0.4064)
			(end -0.7874 0.4064)
			(stroke
				(width 0.1524)
				(type default)
			)
			(layer "F.SilkS")
		)
		(fp_line
			(start 0.7874 -0.4064)
			(end 0.7874 0.4064)
			(stroke
				(width 0.1524)
				(type default)
			)
			(layer "F.SilkS")
		)
		(fp_line
			(start -0.7874 0.4064)
			(end -0.7874 -0.4064)
			(stroke
				(width 0.1524)
				(type default)
			)
			(layer "F.SilkS")
		)
		(fp_line
			(start -0.7874 -0.4064)
			(end 0.7874 -0.4064)
			(stroke
				(width 0.1524)
				(type default)
			)
			(layer "F.SilkS")
		)
		(fp_line
			(start 0.67945 0.3048)
			(end 0.120396 0.3048)
			(stroke
				(width 0.1)
				(type default)
			)
			(layer "F.Fab")
		)
		(fp_line
			(start 0.67945 -0.3048)
			(end 0.67945 0.3048)
			(stroke
				(width 0.1)
				(type default)
			)
			(layer "F.Fab")
		)
		(fp_line
			(start 0.12065 -0.2794)
			(end 0.12065 -0.3048)
			(stroke
				(width 0.1)
				(type default)
			)
			(layer "F.Fab")
		)
		(fp_line
			(start 0.12065 -0.3048)
			(end 0.67945 -0.3048)
			(stroke
				(width 0.1)
				(type default)
			)
			(layer "F.Fab")
		)
		(fp_line
			(start 0.120396 0.3048)
			(end 0.120396 0.2794)
			(stroke
				(width 0.1)
				(type default)
			)
			(layer "F.Fab")
		)
		(fp_line
			(start 0.120396 0.2794)
			(end -0.12065 0.2794)
			(stroke
				(width 0.1)
				(type default)
			)
			(layer "F.Fab")
		)
		(fp_line
			(start -0.12065 0.3048)
			(end -0.67945 0.3048)
			(stroke
				(width 0.1)
				(type default)
			)
			(layer "F.Fab")
		)
		(fp_line
			(start -0.12065 0.2794)
			(end -0.12065 0.3048)
			(stroke
				(width 0.1)
				(type default)
			)
			(layer "F.Fab")
		)
		(fp_line
			(start -0.12065 -0.2794)
			(end 0.12065 -0.2794)
			(stroke
				(width 0.1)
				(type default)
			)
			(layer "F.Fab")
		)
		(fp_line
			(start -0.12065 -0.305054)
			(end -0.12065 -0.2794)
			(stroke
				(width 0.1)
				(type default)
			)
			(layer "F.Fab")
		)
		(fp_line
			(start -0.67945 0.3048)
			(end -0.67945 -0.305054)
			(stroke
				(width 0.1)
				(type default)
			)
			(layer "F.Fab")
		)
		(fp_line
			(start -0.67945 -0.305054)
			(end -0.12065 -0.305054)
			(stroke
				(width 0.1)
				(type default)
			)
			(layer "F.Fab")
		)
		(pad "1" smd rect
			(at -0.40005 0)
			(size 0.4572 0.508)
			(layers "F.Cu" "F.Mask" "F.Paste")
			(net "P12V_OCP_SENSE_1")
		)
		(pad "2" smd rect
			(at 0.40005 0)
			(size 0.4572 0.508)
			(layers "F.Cu" "F.Mask" "F.Paste")
			(net "P12V_OCP_SFF_ISENSE_MAM_TIC")
		)
	)
	(footprint ""
		(layer "F.Cu")
		(at 283.826712 -363.881416)
		(property "Reference" "PR447"
			(at 0 0 0)
			(layer "F.SilkS")
			(hide yes)
			(effects
				(font
					(size 1.27 1.27)
				)
			)
		)
		(property "Value" ""
			(at 0 0 0)
			(layer "F.Fab")
			(effects
				(font
					(size 1.27 1.27)
				)
			)
		)
		(duplicate_pad_numbers_are_jumpers no)
		(fp_line
			(start -0.7874 -0.4064)
			(end 0.7874 -0.4064)
			(stroke
				(width 0.1524)
				(type default)
			)
			(layer "F.SilkS")
		)
		(fp_line
			(start -0.7874 0.4064)
			(end -0.7874 -0.4064)
			(stroke
				(width 0.1524)
				(type default)
			)
			(layer "F.SilkS")
		)
		(fp_line
			(start 0.7874 -0.4064)
			(end 0.7874 0.4064)
			(stroke
				(width 0.1524)
				(type default)
			)
			(layer "F.SilkS")
		)
		(fp_line
			(start 0.7874 0.4064)
			(end -0.7874 0.4064)
			(stroke
				(width 0.1524)
				(type default)
			)
			(layer "F.SilkS")
		)
		(fp_line
			(start -0.67945 -0.305054)
			(end -0.12065 -0.305054)
			(stroke
				(width 0.1)
				(type default)
			)
			(layer "F.Fab")
		)
		(fp_line
			(start -0.67945 0.3048)
			(end -0.67945 -0.305054)
			(stroke
				(width 0.1)
				(type default)
			)
			(layer "F.Fab")
		)
		(fp_line
			(start -0.12065 -0.305054)
			(end -0.12065 -0.2794)
			(stroke
				(width 0.1)
				(type default)
			)
			(layer "F.Fab")
		)
		(fp_line
			(start -0.12065 -0.2794)
			(end 0.12065 -0.2794)
			(stroke
				(width 0.1)
				(type default)
			)
			(layer "F.Fab")
		)
		(fp_line
			(start -0.12065 0.2794)
			(end -0.12065 0.3048)
			(stroke
				(width 0.1)
				(type default)
			)
			(layer "F.Fab")
		)
		(fp_line
			(start -0.12065 0.3048)
			(end -0.67945 0.3048)
			(stroke
				(width 0.1)
				(type default)
			)
			(layer "F.Fab")
		)
		(fp_line
			(start 0.120396 0.2794)
			(end -0.12065 0.2794)
			(stroke
				(width 0.1)
				(type default)
			)
			(layer "F.Fab")
		)
		(fp_line
			(start 0.120396 0.3048)
			(end 0.120396 0.2794)
			(stroke
				(width 0.1)
				(type default)
			)
			(layer "F.Fab")
		)
		(fp_line
			(start 0.12065 -0.3048)
			(end 0.67945 -0.3048)
			(stroke
				(width 0.1)
				(type default)
			)
			(layer "F.Fab")
		)
		(fp_line
			(start 0.12065 -0.2794)
			(end 0.12065 -0.3048)
			(stroke
				(width 0.1)
				(type default)
			)
			(layer "F.Fab")
		)
		(fp_line
			(start 0.67945 -0.3048)
			(end 0.67945 0.3048)
			(stroke
				(width 0.1)
				(type default)
			)
			(layer "F.Fab")
		)
		(fp_line
			(start 0.67945 0.3048)
			(end 0.120396 0.3048)
			(stroke
				(width 0.1)
				(type default)
			)
			(layer "F.Fab")
		)
		(pad "1" smd circle
			(at -0.40005 0)
			(size 0 0)
			(layers "F.Cu" "F.Mask" "F.Paste")
			(net "P5V")
		)
		(pad "2" smd circle
			(at 0.40005 0)
			(size 0 0)
			(layers "F.Cu" "F.Mask" "F.Paste")
			(net "PVCCFA_EHV_FIVRA_CPU0_PVCC2")
		)
	)
	(footprint ""
		(layer "F.Cu")
		(at 336.947256 -66.424556)
		(property "Reference" "C104"
			(at 0 0 0)
			(layer "F.SilkS")
			(hide yes)
			(effects
				(font
					(size 1.27 1.27)
				)
			)
		)
		(property "Value" ""
			(at 0 0 0)
			(layer "F.Fab")
			(effects
				(font
					(size 1.27 1.27)
				)
			)
		)
		(duplicate_pad_numbers_are_jumpers no)
		(fp_line
			(start -0.7874 -0.4064)
			(end 0.7874 -0.4064)
			(stroke
				(width 0.1524)
				(type default)
			)
			(layer "F.SilkS")
		)
		(fp_line
			(start -0.7874 0.4064)
			(end -0.7874 -0.4064)
			(stroke
				(width 0.1524)
				(type default)
			)
			(layer "F.SilkS")
		)
		(fp_line
			(start 0.7874 -0.4064)
			(end 0.7874 0.4064)
			(stroke
				(width 0.1524)
				(type default)
			)
			(layer "F.SilkS")
		)
		(fp_line
			(start 0.7874 0.4064)
			(end -0.7874 0.4064)
			(stroke
				(width 0.1524)
				(type default)
			)
			(layer "F.SilkS")
		)
		(fp_line
			(start -0.67945 -0.305054)
			(end -0.12065 -0.305054)
			(stroke
				(width 0.1)
				(type default)
			)
			(layer "F.Fab")
		)
		(fp_line
			(start -0.67945 0.3048)
			(end -0.67945 -0.305054)
			(stroke
				(width 0.1)
				(type default)
			)
			(layer "F.Fab")
		)
		(fp_line
			(start -0.12065 -0.305054)
			(end -0.12065 -0.2794)
			(stroke
				(width 0.1)
				(type default)
			)
			(layer "F.Fab")
		)
		(fp_line
			(start -0.12065 -0.2794)
			(end 0.12065 -0.2794)
			(stroke
				(width 0.1)
				(type default)
			)
			(layer "F.Fab")
		)
		(fp_line
			(start -0.12065 0.2794)
			(end -0.12065 0.3048)
			(stroke
				(width 0.1)
				(type default)
			)
			(layer "F.Fab")
		)
		(fp_line
			(start -0.12065 0.3048)
			(end -0.67945 0.3048)
			(stroke
				(width 0.1)
				(type default)
			)
			(layer "F.Fab")
		)
		(fp_line
			(start 0.120396 0.2794)
			(end -0.12065 0.2794)
			(stroke
				(width 0.1)
				(type default)
			)
			(layer "F.Fab")
		)
		(fp_line
			(start 0.120396 0.3048)
			(end 0.120396 0.2794)
			(stroke
				(width 0.1)
				(type default)
			)
			(layer "F.Fab")
		)
		(fp_line
			(start 0.12065 -0.3048)
			(end 0.67945 -0.3048)
			(stroke
				(width 0.1)
				(type default)
			)
			(layer "F.Fab")
		)
		(fp_line
			(start 0.12065 -0.2794)
			(end 0.12065 -0.3048)
			(stroke
				(width 0.1)
				(type default)
			)
			(layer "F.Fab")
		)
		(fp_line
			(start 0.67945 -0.3048)
			(end 0.67945 0.3048)
			(stroke
				(width 0.1)
				(type default)
			)
			(layer "F.Fab")
		)
		(fp_line
			(start 0.67945 0.3048)
			(end 0.120396 0.3048)
			(stroke
				(width 0.1)
				(type default)
			)
			(layer "F.Fab")
		)
		(pad "1" smd circle
			(at -0.40005 0)
			(size 0 0)
			(layers "F.Cu" "F.Mask" "F.Paste")
			(net "XTAL_PCH_25M_OUT")
		)
		(pad "2" smd circle
			(at 0.40005 0)
			(size 0 0)
			(layers "F.Cu" "F.Mask" "F.Paste")
			(net "GND")
		)
	)
	(footprint ""
		(layer "F.Cu")
		(at 324.9168 -34.178748 135)
		(property "Reference" "C1508"
			(at 0 0 135)
			(layer "F.SilkS")
			(hide yes)
			(effects
				(font
					(size 1.27 1.27)
				)
			)
		)
		(property "Value" ""
			(at 0 0 135)
			(layer "F.Fab")
			(effects
				(font
					(size 1.27 1.27)
				)
			)
		)
		(duplicate_pad_numbers_are_jumpers no)
		(fp_line
			(start 0.787389 -0.406267)
			(end 0.787389 0.406267)
			(stroke
				(width 0.1524)
				(type default)
			)
			(layer "F.SilkS")
		)
		(fp_line
			(start 0.787389 0.406267)
			(end -0.787389 0.406267)
			(stroke
				(width 0.1524)
				(type default)
			)
			(layer "F.SilkS")
		)
		(fp_line
			(start -0.787389 -0.406267)
			(end 0.787389 -0.406267)
			(stroke
				(width 0.1524)
				(type default)
			)
			(layer "F.SilkS")
		)
		(fp_line
			(start -0.787389 0.406267)
			(end -0.787389 -0.406267)
			(stroke
				(width 0.1524)
				(type default)
			)
			(layer "F.SilkS")
		)
		(fp_line
			(start 0.679446 -0.30479)
			(end 0.679446 0.30479)
			(stroke
				(width 0.1)
				(type default)
			)
			(layer "F.Fab")
		)
		(fp_line
			(start 0.120515 -0.30479)
			(end 0.679446 -0.30479)
			(stroke
				(width 0.1)
				(type default)
			)
			(layer "F.Fab")
		)
		(fp_line
			(start 0.120695 -0.279466)
			(end 0.120515 -0.30479)
			(stroke
				(width 0.1)
				(type default)
			)
			(layer "F.Fab")
		)
		(fp_line
			(start 0.679446 0.30479)
			(end 0.120515 0.30479)
			(stroke
				(width 0.1)
				(type default)
			)
			(layer "F.Fab")
		)
		(fp_line
			(start -0.120695 -0.304969)
			(end -0.120695 -0.279466)
			(stroke
				(width 0.1)
				(type default)
			)
			(layer "F.Fab")
		)
		(fp_line
			(start -0.120695 -0.279466)
			(end 0.120695 -0.279466)
			(stroke
				(width 0.1)
				(type default)
			)
			(layer "F.Fab")
		)
		(fp_line
			(start 0.120335 0.279466)
			(end -0.120695 0.279466)
			(stroke
				(width 0.1)
				(type default)
			)
			(layer "F.Fab")
		)
		(fp_line
			(start 0.120515 0.30479)
			(end 0.120335 0.279466)
			(stroke
				(width 0.1)
				(type default)
			)
			(layer "F.Fab")
		)
		(fp_line
			(start -0.679446 -0.305149)
			(end -0.120695 -0.304969)
			(stroke
				(width 0.1)
				(type default)
			)
			(layer "F.Fab")
		)
		(fp_line
			(start -0.120695 0.279466)
			(end -0.120515 0.30479)
			(stroke
				(width 0.1)
				(type default)
			)
			(layer "F.Fab")
		)
		(fp_line
			(start -0.120515 0.30479)
			(end -0.679446 0.30479)
			(stroke
				(width 0.1)
				(type default)
			)
			(layer "F.Fab")
		)
		(fp_line
			(start -0.679446 0.30479)
			(end -0.679446 -0.305149)
			(stroke
				(width 0.1)
				(type default)
			)
			(layer "F.Fab")
		)
		(pad "1" smd circle
			(at -0.40005 0 135)
			(size 0 0)
			(layers "F.Cu" "F.Mask" "F.Paste")
			(net "XTAL_PCH_RTC1")
		)
		(pad "2" smd circle
			(at 0.40005 0 135)
			(size 0 0)
			(layers "F.Cu" "F.Mask" "F.Paste")
			(net "GND")
		)
	)
	(footprint ""
		(layer "F.Cu")
		(at 329.806808 -408.517344 -90)
		(property "Reference" "C918"
			(at 0 0 270)
			(layer "F.SilkS")
			(hide yes)
			(effects
				(font
					(size 1.27 1.27)
				)
			)
		)
		(property "Value" ""
			(at 0 0 270)
			(layer "F.Fab")
			(effects
				(font
					(size 1.27 1.27)
				)
			)
		)
		(duplicate_pad_numbers_are_jumpers no)
		(fp_line
			(start -0.299974 0.150114)
			(end -0.299974 -0.150114)
			(stroke
				(width 0.1)
				(type default)
			)
			(layer "F.Fab")
		)
		(fp_line
			(start 0.299974 0.150114)
			(end -0.299974 0.150114)
			(stroke
				(width 0.1)
				(type default)
			)
			(layer "F.Fab")
		)
		(fp_line
			(start -0.299974 -0.150114)
			(end 0.299974 -0.150114)
			(stroke
				(width 0.1)
				(type default)
			)
			(layer "F.Fab")
		)
		(fp_line
			(start 0.299974 -0.150114)
			(end 0.299974 0.150114)
			(stroke
				(width 0.1)
				(type default)
			)
			(layer "F.Fab")
		)
		(pad "1" smd rect
			(at -0.2667 0 270)
			(size 0.3048 0.381)
			(layers "F.Cu" "F.Mask" "F.Paste")
			(net "P5E_CPU0_PE0_TX_C_DN<7>")
		)
		(pad "2" smd rect
			(at 0.2667 0 270)
			(size 0.3048 0.381)
			(layers "F.Cu" "F.Mask" "F.Paste")
			(net "P5E_CPU0_PE0_TX_DN<7>")
		)
	)
	(footprint ""
		(layer "F.Cu")
		(at 120.975374 -360.043222 90)
		(property "Reference" "PC2002"
			(at 0 0 90)
			(layer "F.SilkS")
			(hide yes)
			(effects
				(font
					(size 1.27 1.27)
				)
			)
		)
		(property "Value" ""
			(at 0 0 90)
			(layer "F.Fab")
			(effects
				(font
					(size 1.27 1.27)
				)
			)
		)
		(duplicate_pad_numbers_are_jumpers no)
		(fp_line
			(start 0.7874 -0.4064)
			(end 0.7874 0.4064)
			(stroke
				(width 0.1524)
				(type default)
			)
			(layer "F.SilkS")
		)
		(fp_line
			(start -0.7874 -0.4064)
			(end 0.7874 -0.4064)
			(stroke
				(width 0.1524)
				(type default)
			)
			(layer "F.SilkS")
		)
		(fp_line
			(start 0.7874 0.4064)
			(end -0.7874 0.4064)
			(stroke
				(width 0.1524)
				(type default)
			)
			(layer "F.SilkS")
		)
		(fp_line
			(start -0.7874 0.4064)
			(end -0.7874 -0.4064)
			(stroke
				(width 0.1524)
				(type default)
			)
			(layer "F.SilkS")
		)
		(fp_line
			(start -0.12065 -0.305054)
			(end -0.12065 -0.2794)
			(stroke
				(width 0.1)
				(type default)
			)
			(layer "F.Fab")
		)
		(fp_line
			(start -0.67945 -0.305054)
			(end -0.12065 -0.305054)
			(stroke
				(width 0.1)
				(type default)
			)
			(layer "F.Fab")
		)
		(fp_line
			(start 0.67945 -0.3048)
			(end 0.67945 0.3048)
			(stroke
				(width 0.1)
				(type default)
			)
			(layer "F.Fab")
		)
		(fp_line
			(start 0.12065 -0.3048)
			(end 0.67945 -0.3048)
			(stroke
				(width 0.1)
				(type default)
			)
			(layer "F.Fab")
		)
		(fp_line
			(start 0.12065 -0.2794)
			(end 0.12065 -0.3048)
			(stroke
				(width 0.1)
				(type default)
			)
			(layer "F.Fab")
		)
		(fp_line
			(start -0.12065 -0.2794)
			(end 0.12065 -0.2794)
			(stroke
				(width 0.1)
				(type default)
			)
			(layer "F.Fab")
		)
		(fp_line
			(start 0.120396 0.2794)
			(end -0.12065 0.2794)
			(stroke
				(width 0.1)
				(type default)
			)
			(layer "F.Fab")
		)
		(fp_line
			(start -0.12065 0.2794)
			(end -0.12065 0.3048)
			(stroke
				(width 0.1)
				(type default)
			)
			(layer "F.Fab")
		)
		(fp_line
			(start 0.67945 0.3048)
			(end 0.120396 0.3048)
			(stroke
				(width 0.1)
				(type default)
			)
			(layer "F.Fab")
		)
		(fp_line
			(start 0.120396 0.3048)
			(end 0.120396 0.2794)
			(stroke
				(width 0.1)
				(type default)
			)
			(layer "F.Fab")
		)
		(fp_line
			(start -0.12065 0.3048)
			(end -0.67945 0.3048)
			(stroke
				(width 0.1)
				(type default)
			)
			(layer "F.Fab")
		)
		(fp_line
			(start -0.67945 0.3048)
			(end -0.67945 -0.305054)
			(stroke
				(width 0.1)
				(type default)
			)
			(layer "F.Fab")
		)
		(pad "1" smd circle
			(at -0.40005 0 90)
			(size 0 0)
			(layers "F.Cu" "F.Mask" "F.Paste")
			(net "PVPP_HBM_CPU1_REF")
		)
		(pad "2" smd circle
			(at 0.40005 0 90)
			(size 0 0)
			(layers "F.Cu" "F.Mask" "F.Paste")
			(net "GND")
		)
	)
	(footprint ""
		(layer "F.Cu")
		(at 357.720392 -400.354038)
		(property "Reference" "R2676"
			(at 0 0 0)
			(layer "F.SilkS")
			(hide yes)
			(effects
				(font
					(size 1.27 1.27)
				)
			)
		)
		(property "Value" ""
			(at 0 0 0)
			(layer "F.Fab")
			(effects
				(font
					(size 1.27 1.27)
				)
			)
		)
		(duplicate_pad_numbers_are_jumpers no)
		(fp_line
			(start -0.7874 -0.4064)
			(end 0.7874 -0.4064)
			(stroke
				(width 0.1524)
				(type default)
			)
			(layer "F.SilkS")
		)
		(fp_line
			(start -0.7874 0.4064)
			(end -0.7874 -0.4064)
			(stroke
				(width 0.1524)
				(type default)
			)
			(layer "F.SilkS")
		)
		(fp_line
			(start 0.7874 -0.4064)
			(end 0.7874 0.4064)
			(stroke
				(width 0.1524)
				(type default)
			)
			(layer "F.SilkS")
		)
		(fp_line
			(start 0.7874 0.4064)
			(end -0.7874 0.4064)
			(stroke
				(width 0.1524)
				(type default)
			)
			(layer "F.SilkS")
		)
		(fp_line
			(start -0.67945 -0.305054)
			(end -0.12065 -0.305054)
			(stroke
				(width 0.1)
				(type default)
			)
			(layer "F.Fab")
		)
		(fp_line
			(start -0.67945 0.3048)
			(end -0.67945 -0.305054)
			(stroke
				(width 0.1)
				(type default)
			)
			(layer "F.Fab")
		)
		(fp_line
			(start -0.12065 -0.305054)
			(end -0.12065 -0.2794)
			(stroke
				(width 0.1)
				(type default)
			)
			(layer "F.Fab")
		)
		(fp_line
			(start -0.12065 -0.2794)
			(end 0.12065 -0.2794)
			(stroke
				(width 0.1)
				(type default)
			)
			(layer "F.Fab")
		)
		(fp_line
			(start -0.12065 0.2794)
			(end -0.12065 0.3048)
			(stroke
				(width 0.1)
				(type default)
			)
			(layer "F.Fab")
		)
		(fp_line
			(start -0.12065 0.3048)
			(end -0.67945 0.3048)
			(stroke
				(width 0.1)
				(type default)
			)
			(layer "F.Fab")
		)
		(fp_line
			(start 0.120396 0.2794)
			(end -0.12065 0.2794)
			(stroke
				(width 0.1)
				(type default)
			)
			(layer "F.Fab")
		)
		(fp_line
			(start 0.120396 0.3048)
			(end 0.120396 0.2794)
			(stroke
				(width 0.1)
				(type default)
			)
			(layer "F.Fab")
		)
		(fp_line
			(start 0.12065 -0.3048)
			(end 0.67945 -0.3048)
			(stroke
				(width 0.1)
				(type default)
			)
			(layer "F.Fab")
		)
		(fp_line
			(start 0.12065 -0.2794)
			(end 0.12065 -0.3048)
			(stroke
				(width 0.1)
				(type default)
			)
			(layer "F.Fab")
		)
		(fp_line
			(start 0.67945 -0.3048)
			(end 0.67945 0.3048)
			(stroke
				(width 0.1)
				(type default)
			)
			(layer "F.Fab")
		)
		(fp_line
			(start 0.67945 0.3048)
			(end 0.120396 0.3048)
			(stroke
				(width 0.1)
				(type default)
			)
			(layer "F.Fab")
		)
		(pad "1" smd circle
			(at -0.40005 0)
			(size 0 0)
			(layers "F.Cu" "F.Mask" "F.Paste")
			(net "SMB_BMC_SWB_EN")
		)
		(pad "2" smd circle
			(at 0.40005 0)
			(size 0 0)
			(layers "F.Cu" "F.Mask" "F.Paste")
			(net "SMB_BMC_SWB_EN_R2")
		)
	)
	(footprint ""
		(layer "F.Cu")
		(at 425.846748 -353.312984 -90)
		(property "Reference" "PL2"
			(at -3.919474 -4.335272 0)
			(unlocked yes)
			(layer "F.SilkS")
			(effects
				(font
					(size 0.7874 0.5842)
					(thickness 0.1524)
				)
				(justify left)
			)
		)
		(property "Value" ""
			(at 0 0 270)
			(layer "F.Fab")
			(effects
				(font
					(size 1.27 1.27)
				)
			)
		)
		(duplicate_pad_numbers_are_jumpers no)
		(fp_line
			(start -4.99999 3.750056)
			(end -4.99999 2.2479)
			(stroke
				(width 0.1524)
				(type default)
			)
			(layer "F.SilkS")
		)
		(fp_line
			(start 0 3.750056)
			(end -4.99999 3.750056)
			(stroke
				(width 0.1524)
				(type default)
			)
			(layer "F.SilkS")
		)
		(fp_line
			(start 4.99999 3.750056)
			(end 0 3.750056)
			(stroke
				(width 0.1524)
				(type default)
			)
			(layer "F.SilkS")
		)
		(fp_line
			(start 4.99999 2.2352)
			(end 4.99999 3.750056)
			(stroke
				(width 0.1524)
				(type default)
			)
			(layer "F.SilkS")
		)
		(fp_line
			(start -4.99999 -2.2479)
			(end -4.99999 -3.750056)
			(stroke
				(width 0.1524)
				(type default)
			)
			(layer "F.SilkS")
		)
		(fp_line
			(start -4.99999 -3.750056)
			(end 4.99999 -3.750056)
			(stroke
				(width 0.1524)
				(type default)
			)
			(layer "F.SilkS")
		)
		(fp_line
			(start 4.99999 -3.750056)
			(end 4.99999 -2.2479)
			(stroke
				(width 0.1524)
				(type default)
			)
			(layer "F.SilkS")
		)
		(fp_line
			(start -4.99999 3.750056)
			(end -4.99999 -3.750056)
			(stroke
				(width 0.1)
				(type default)
			)
			(layer "F.Fab")
		)
		(fp_line
			(start 0 3.750056)
			(end -4.99999 3.750056)
			(stroke
				(width 0.1)
				(type default)
			)
			(layer "F.Fab")
		)
		(fp_line
			(start 4.99999 3.750056)
			(end 0 3.750056)
			(stroke
				(width 0.1)
				(type default)
			)
			(layer "F.Fab")
		)
		(fp_line
			(start -4.99999 -3.750056)
			(end 4.99999 -3.750056)
			(stroke
				(width 0.1)
				(type default)
			)
			(layer "F.Fab")
		)
		(fp_line
			(start 4.99999 -3.750056)
			(end 4.99999 3.750056)
			(stroke
				(width 0.1)
				(type default)
			)
			(layer "F.Fab")
		)
		(pad "1" smd rect
			(at -3.299968 0 270)
			(size 3.302 4.2164)
			(layers "F.Cu" "F.Mask" "F.Paste")
			(net "SW_PVCCFA_EHV_FIVRA_CPU0_SW3")
		)
		(pad "2" smd rect
			(at 3.299968 0 270)
			(size 3.302 4.2164)
			(layers "F.Cu" "F.Mask" "F.Paste")
			(net "PVCCFA_EHV_FIVRA_CPU0")
		)
	)
	(footprint ""
		(layer "F.Cu")
		(at 147.08378 -124.005848 180)
		(property "Reference" "R3153"
			(at 0 0 180)
			(layer "F.SilkS")
			(hide yes)
			(effects
				(font
					(size 1.27 1.27)
				)
			)
		)
		(property "Value" ""
			(at 0 0 180)
			(layer "F.Fab")
			(effects
				(font
					(size 1.27 1.27)
				)
			)
		)
		(duplicate_pad_numbers_are_jumpers no)
		(fp_line
			(start 0.7874 0.4064)
			(end -0.7874 0.4064)
			(stroke
				(width 0.1524)
				(type default)
			)
			(layer "F.SilkS")
		)
		(fp_line
			(start 0.7874 -0.4064)
			(end 0.7874 0.4064)
			(stroke
				(width 0.1524)
				(type default)
			)
			(layer "F.SilkS")
		)
		(fp_line
			(start -0.7874 0.4064)
			(end -0.7874 -0.4064)
			(stroke
				(width 0.1524)
				(type default)
			)
			(layer "F.SilkS")
		)
		(fp_line
			(start -0.7874 -0.4064)
			(end 0.7874 -0.4064)
			(stroke
				(width 0.1524)
				(type default)
			)
			(layer "F.SilkS")
		)
		(fp_line
			(start 0.67945 0.3048)
			(end 0.120396 0.3048)
			(stroke
				(width 0.1)
				(type default)
			)
			(layer "F.Fab")
		)
		(fp_line
			(start 0.67945 -0.3048)
			(end 0.67945 0.3048)
			(stroke
				(width 0.1)
				(type default)
			)
			(layer "F.Fab")
		)
		(fp_line
			(start 0.12065 -0.2794)
			(end 0.12065 -0.3048)
			(stroke
				(width 0.1)
				(type default)
			)
			(layer "F.Fab")
		)
		(fp_line
			(start 0.12065 -0.3048)
			(end 0.67945 -0.3048)
			(stroke
				(width 0.1)
				(type default)
			)
			(layer "F.Fab")
		)
		(fp_line
			(start 0.120396 0.3048)
			(end 0.120396 0.2794)
			(stroke
				(width 0.1)
				(type default)
			)
			(layer "F.Fab")
		)
		(fp_line
			(start 0.120396 0.2794)
			(end -0.12065 0.2794)
			(stroke
				(width 0.1)
				(type default)
			)
			(layer "F.Fab")
		)
		(fp_line
			(start -0.12065 0.3048)
			(end -0.67945 0.3048)
			(stroke
				(width 0.1)
				(type default)
			)
			(layer "F.Fab")
		)
		(fp_line
			(start -0.12065 0.2794)
			(end -0.12065 0.3048)
			(stroke
				(width 0.1)
				(type default)
			)
			(layer "F.Fab")
		)
		(fp_line
			(start -0.12065 -0.2794)
			(end 0.12065 -0.2794)
			(stroke
				(width 0.1)
				(type default)
			)
			(layer "F.Fab")
		)
		(fp_line
			(start -0.12065 -0.305054)
			(end -0.12065 -0.2794)
			(stroke
				(width 0.1)
				(type default)
			)
			(layer "F.Fab")
		)
		(fp_line
			(start -0.67945 0.3048)
			(end -0.67945 -0.305054)
			(stroke
				(width 0.1)
				(type default)
			)
			(layer "F.Fab")
		)
		(fp_line
			(start -0.67945 -0.305054)
			(end -0.12065 -0.305054)
			(stroke
				(width 0.1)
				(type default)
			)
			(layer "F.Fab")
		)
		(pad "1" smd circle
			(at -0.40005 0 180)
			(size 0 0)
			(layers "F.Cu" "F.Mask" "F.Paste")
			(net "P3V3_AUX")
		)
		(pad "2" smd circle
			(at 0.40005 0 180)
			(size 0 0)
			(layers "F.Cu" "F.Mask" "F.Paste")
			(net "PD_SMB_OCP2_HP_ADD0")
		)
	)
	(footprint ""
		(layer "F.Cu")
		(at 63.877698 -26.99004 -90)
		(property "Reference" "PR3854"
			(at 0 0 270)
			(layer "F.SilkS")
			(hide yes)
			(effects
				(font
					(size 1.27 1.27)
				)
			)
		)
		(property "Value" ""
			(at 0 0 270)
			(layer "F.Fab")
			(effects
				(font
					(size 1.27 1.27)
				)
			)
		)
		(duplicate_pad_numbers_are_jumpers no)
		(fp_line
			(start -0.7874 0.4064)
			(end -0.7874 -0.4064)
			(stroke
				(width 0.1524)
				(type default)
			)
			(layer "F.SilkS")
		)
		(fp_line
			(start 0.7874 0.4064)
			(end -0.7874 0.4064)
			(stroke
				(width 0.1524)
				(type default)
			)
			(layer "F.SilkS")
		)
		(fp_line
			(start -0.7874 -0.4064)
			(end 0.7874 -0.4064)
			(stroke
				(width 0.1524)
				(type default)
			)
			(layer "F.SilkS")
		)
		(fp_line
			(start 0.7874 -0.4064)
			(end 0.7874 0.4064)
			(stroke
				(width 0.1524)
				(type default)
			)
			(layer "F.SilkS")
		)
		(fp_line
			(start -0.67945 0.3048)
			(end -0.67945 -0.305054)
			(stroke
				(width 0.1)
				(type default)
			)
			(layer "F.Fab")
		)
		(fp_line
			(start -0.12065 0.3048)
			(end -0.67945 0.3048)
			(stroke
				(width 0.1)
				(type default)
			)
			(layer "F.Fab")
		)
		(fp_line
			(start 0.120396 0.3048)
			(end 0.120396 0.2794)
			(stroke
				(width 0.1)
				(type default)
			)
			(layer "F.Fab")
		)
		(fp_line
			(start 0.67945 0.3048)
			(end 0.120396 0.3048)
			(stroke
				(width 0.1)
				(type default)
			)
			(layer "F.Fab")
		)
		(fp_line
			(start -0.12065 0.2794)
			(end -0.12065 0.3048)
			(stroke
				(width 0.1)
				(type default)
			)
			(layer "F.Fab")
		)
		(fp_line
			(start 0.120396 0.2794)
			(end -0.12065 0.2794)
			(stroke
				(width 0.1)
				(type default)
			)
			(layer "F.Fab")
		)
		(fp_line
			(start -0.12065 -0.2794)
			(end 0.12065 -0.2794)
			(stroke
				(width 0.1)
				(type default)
			)
			(layer "F.Fab")
		)
		(fp_line
			(start 0.12065 -0.2794)
			(end 0.12065 -0.3048)
			(stroke
				(width 0.1)
				(type default)
			)
			(layer "F.Fab")
		)
		(fp_line
			(start 0.12065 -0.3048)
			(end 0.67945 -0.3048)
			(stroke
				(width 0.1)
				(type default)
			)
			(layer "F.Fab")
		)
		(fp_line
			(start 0.67945 -0.3048)
			(end 0.67945 0.3048)
			(stroke
				(width 0.1)
				(type default)
			)
			(layer "F.Fab")
		)
		(fp_line
			(start -0.67945 -0.305054)
			(end -0.12065 -0.305054)
			(stroke
				(width 0.1)
				(type default)
			)
			(layer "F.Fab")
		)
		(fp_line
			(start -0.12065 -0.305054)
			(end -0.12065 -0.2794)
			(stroke
				(width 0.1)
				(type default)
			)
			(layer "F.Fab")
		)
		(pad "1" smd circle
			(at -0.40005 0 270)
			(size 0 0)
			(layers "F.Cu" "F.Mask" "F.Paste")
			(net "P12V_OCP_OV_FB_2")
		)
		(pad "2" smd circle
			(at 0.40005 0 270)
			(size 0 0)
			(layers "F.Cu" "F.Mask" "F.Paste")
			(net "GND")
		)
	)
	(footprint ""
		(layer "F.Cu")
		(at 429.299116 -109.26699 -90)
		(property "Reference" "PR3789"
			(at 0 0 270)
			(layer "F.SilkS")
			(hide yes)
			(effects
				(font
					(size 1.27 1.27)
				)
			)
		)
		(property "Value" ""
			(at 0 0 270)
			(layer "F.Fab")
			(effects
				(font
					(size 1.27 1.27)
				)
			)
		)
		(duplicate_pad_numbers_are_jumpers no)
		(fp_line
			(start -0.7874 0.4064)
			(end -0.7874 -0.4064)
			(stroke
				(width 0.1524)
				(type default)
			)
			(layer "F.SilkS")
		)
		(fp_line
			(start 0.7874 0.4064)
			(end -0.7874 0.4064)
			(stroke
				(width 0.1524)
				(type default)
			)
			(layer "F.SilkS")
		)
		(fp_line
			(start -0.7874 -0.4064)
			(end 0.7874 -0.4064)
			(stroke
				(width 0.1524)
				(type default)
			)
			(layer "F.SilkS")
		)
		(fp_line
			(start 0.7874 -0.4064)
			(end 0.7874 0.4064)
			(stroke
				(width 0.1524)
				(type default)
			)
			(layer "F.SilkS")
		)
		(fp_line
			(start -0.67945 0.3048)
			(end -0.67945 -0.305054)
			(stroke
				(width 0.1)
				(type default)
			)
			(layer "F.Fab")
		)
		(fp_line
			(start -0.12065 0.3048)
			(end -0.67945 0.3048)
			(stroke
				(width 0.1)
				(type default)
			)
			(layer "F.Fab")
		)
		(fp_line
			(start 0.120396 0.3048)
			(end 0.120396 0.2794)
			(stroke
				(width 0.1)
				(type default)
			)
			(layer "F.Fab")
		)
		(fp_line
			(start 0.67945 0.3048)
			(end 0.120396 0.3048)
			(stroke
				(width 0.1)
				(type default)
			)
			(layer "F.Fab")
		)
		(fp_line
			(start -0.12065 0.2794)
			(end -0.12065 0.3048)
			(stroke
				(width 0.1)
				(type default)
			)
			(layer "F.Fab")
		)
		(fp_line
			(start 0.120396 0.2794)
			(end -0.12065 0.2794)
			(stroke
				(width 0.1)
				(type default)
			)
			(layer "F.Fab")
		)
		(fp_line
			(start -0.12065 -0.2794)
			(end 0.12065 -0.2794)
			(stroke
				(width 0.1)
				(type default)
			)
			(layer "F.Fab")
		)
		(fp_line
			(start 0.12065 -0.2794)
			(end 0.12065 -0.3048)
			(stroke
				(width 0.1)
				(type default)
			)
			(layer "F.Fab")
		)
		(fp_line
			(start 0.12065 -0.3048)
			(end 0.67945 -0.3048)
			(stroke
				(width 0.1)
				(type default)
			)
			(layer "F.Fab")
		)
		(fp_line
			(start 0.67945 -0.3048)
			(end 0.67945 0.3048)
			(stroke
				(width 0.1)
				(type default)
			)
			(layer "F.Fab")
		)
		(fp_line
			(start -0.67945 -0.305054)
			(end -0.12065 -0.305054)
			(stroke
				(width 0.1)
				(type default)
			)
			(layer "F.Fab")
		)
		(fp_line
			(start -0.12065 -0.305054)
			(end -0.12065 -0.2794)
			(stroke
				(width 0.1)
				(type default)
			)
			(layer "F.Fab")
		)
		(pad "1" smd circle
			(at -0.40005 0 270)
			(size 0 0)
			(layers "F.Cu" "F.Mask" "F.Paste")
			(net "P3V3_AUX")
		)
		(pad "2" smd circle
			(at 0.40005 0 270)
			(size 0 0)
			(layers "F.Cu" "F.Mask" "F.Paste")
			(net "P3V3_OCP_UV_1")
		)
	)
	(footprint ""
		(layer "F.Cu")
		(at 380.58725 -402.371052 -90)
		(property "Reference" "C941"
			(at 0 0 270)
			(layer "F.SilkS")
			(hide yes)
			(effects
				(font
					(size 1.27 1.27)
				)
			)
		)
		(property "Value" ""
			(at 0 0 270)
			(layer "F.Fab")
			(effects
				(font
					(size 1.27 1.27)
				)
			)
		)
		(duplicate_pad_numbers_are_jumpers no)
		(fp_line
			(start -0.299974 0.150114)
			(end -0.299974 -0.150114)
			(stroke
				(width 0.1)
				(type default)
			)
			(layer "F.Fab")
		)
		(fp_line
			(start 0.299974 0.150114)
			(end -0.299974 0.150114)
			(stroke
				(width 0.1)
				(type default)
			)
			(layer "F.Fab")
		)
		(fp_line
			(start -0.299974 -0.150114)
			(end 0.299974 -0.150114)
			(stroke
				(width 0.1)
				(type default)
			)
			(layer "F.Fab")
		)
		(fp_line
			(start 0.299974 -0.150114)
			(end 0.299974 0.150114)
			(stroke
				(width 0.1)
				(type default)
			)
			(layer "F.Fab")
		)
		(pad "1" smd rect
			(at -0.2667 0 270)
			(size 0.3048 0.381)
			(layers "F.Cu" "F.Mask" "F.Paste")
			(net "P5E_CPU0_PE2_TX_C_DP<12>")
		)
		(pad "2" smd rect
			(at 0.2667 0 270)
			(size 0.3048 0.381)
			(layers "F.Cu" "F.Mask" "F.Paste")
			(net "P5E_CPU0_PE2_TX_DP<12>")
		)
	)
	(footprint ""
		(layer "F.Cu")
		(at 243.045234 -137.344658)
		(property "Reference" "R4714"
			(at 0 0 0)
			(layer "F.SilkS")
			(hide yes)
			(effects
				(font
					(size 1.27 1.27)
				)
			)
		)
		(property "Value" ""
			(at 0 0 0)
			(layer "F.Fab")
			(effects
				(font
					(size 1.27 1.27)
				)
			)
		)
		(duplicate_pad_numbers_are_jumpers no)
		(fp_line
			(start -0.7874 -0.4064)
			(end 0.7874 -0.4064)
			(stroke
				(width 0.1524)
				(type default)
			)
			(layer "F.SilkS")
		)
		(fp_line
			(start -0.7874 0.4064)
			(end -0.7874 -0.4064)
			(stroke
				(width 0.1524)
				(type default)
			)
			(layer "F.SilkS")
		)
		(fp_line
			(start 0.7874 -0.4064)
			(end 0.7874 0.4064)
			(stroke
				(width 0.1524)
				(type default)
			)
			(layer "F.SilkS")
		)
		(fp_line
			(start 0.7874 0.4064)
			(end -0.7874 0.4064)
			(stroke
				(width 0.1524)
				(type default)
			)
			(layer "F.SilkS")
		)
		(fp_line
			(start -0.67945 -0.305054)
			(end -0.12065 -0.305054)
			(stroke
				(width 0.1)
				(type default)
			)
			(layer "F.Fab")
		)
		(fp_line
			(start -0.67945 0.3048)
			(end -0.67945 -0.305054)
			(stroke
				(width 0.1)
				(type default)
			)
			(layer "F.Fab")
		)
		(fp_line
			(start -0.12065 -0.305054)
			(end -0.12065 -0.2794)
			(stroke
				(width 0.1)
				(type default)
			)
			(layer "F.Fab")
		)
		(fp_line
			(start -0.12065 -0.2794)
			(end 0.12065 -0.2794)
			(stroke
				(width 0.1)
				(type default)
			)
			(layer "F.Fab")
		)
		(fp_line
			(start -0.12065 0.2794)
			(end -0.12065 0.3048)
			(stroke
				(width 0.1)
				(type default)
			)
			(layer "F.Fab")
		)
		(fp_line
			(start -0.12065 0.3048)
			(end -0.67945 0.3048)
			(stroke
				(width 0.1)
				(type default)
			)
			(layer "F.Fab")
		)
		(fp_line
			(start 0.120396 0.2794)
			(end -0.12065 0.2794)
			(stroke
				(width 0.1)
				(type default)
			)
			(layer "F.Fab")
		)
		(fp_line
			(start 0.120396 0.3048)
			(end 0.120396 0.2794)
			(stroke
				(width 0.1)
				(type default)
			)
			(layer "F.Fab")
		)
		(fp_line
			(start 0.12065 -0.3048)
			(end 0.67945 -0.3048)
			(stroke
				(width 0.1)
				(type default)
			)
			(layer "F.Fab")
		)
		(fp_line
			(start 0.12065 -0.2794)
			(end 0.12065 -0.3048)
			(stroke
				(width 0.1)
				(type default)
			)
			(layer "F.Fab")
		)
		(fp_line
			(start 0.67945 -0.3048)
			(end 0.67945 0.3048)
			(stroke
				(width 0.1)
				(type default)
			)
			(layer "F.Fab")
		)
		(fp_line
			(start 0.67945 0.3048)
			(end 0.120396 0.3048)
			(stroke
				(width 0.1)
				(type default)
			)
			(layer "F.Fab")
		)
		(pad "1" smd circle
			(at -0.40005 0)
			(size 0 0)
			(layers "F.Cu" "F.Mask" "F.Paste")
			(net "SMB_HOST_3V3AUX_SDA_R4")
		)
		(pad "2" smd circle
			(at 0.40005 0)
			(size 0 0)
			(layers "F.Cu" "F.Mask" "F.Paste")
			(net "SMB_HOST_3V3AUX_PLD_SDA")
		)
	)
	(footprint ""
		(layer "F.Cu")
		(at 100.989384 -337.856068)
		(property "Reference" "PC561_P1_1"
			(at 0 0 0)
			(layer "F.SilkS")
			(hide yes)
			(effects
				(font
					(size 1.27 1.27)
				)
			)
		)
		(property "Value" ""
			(at 0 0 0)
			(layer "F.Fab")
			(effects
				(font
					(size 1.27 1.27)
				)
			)
		)
		(duplicate_pad_numbers_are_jumpers no)
		(fp_line
			(start -0.7874 -0.4064)
			(end 0.7874 -0.4064)
			(stroke
				(width 0.1524)
				(type default)
			)
			(layer "F.SilkS")
		)
		(fp_line
			(start -0.7874 0.4064)
			(end -0.7874 -0.4064)
			(stroke
				(width 0.1524)
				(type default)
			)
			(layer "F.SilkS")
		)
		(fp_line
			(start 0.7874 -0.4064)
			(end 0.7874 0.4064)
			(stroke
				(width 0.1524)
				(type default)
			)
			(layer "F.SilkS")
		)
		(fp_line
			(start 0.7874 0.4064)
			(end -0.7874 0.4064)
			(stroke
				(width 0.1524)
				(type default)
			)
			(layer "F.SilkS")
		)
		(fp_line
			(start -0.67945 -0.305054)
			(end -0.12065 -0.305054)
			(stroke
				(width 0.1)
				(type default)
			)
			(layer "F.Fab")
		)
		(fp_line
			(start -0.67945 0.3048)
			(end -0.67945 -0.305054)
			(stroke
				(width 0.1)
				(type default)
			)
			(layer "F.Fab")
		)
		(fp_line
			(start -0.12065 -0.305054)
			(end -0.12065 -0.2794)
			(stroke
				(width 0.1)
				(type default)
			)
			(layer "F.Fab")
		)
		(fp_line
			(start -0.12065 -0.2794)
			(end 0.12065 -0.2794)
			(stroke
				(width 0.1)
				(type default)
			)
			(layer "F.Fab")
		)
		(fp_line
			(start -0.12065 0.2794)
			(end -0.12065 0.3048)
			(stroke
				(width 0.1)
				(type default)
			)
			(layer "F.Fab")
		)
		(fp_line
			(start -0.12065 0.3048)
			(end -0.67945 0.3048)
			(stroke
				(width 0.1)
				(type default)
			)
			(layer "F.Fab")
		)
		(fp_line
			(start 0.120396 0.2794)
			(end -0.12065 0.2794)
			(stroke
				(width 0.1)
				(type default)
			)
			(layer "F.Fab")
		)
		(fp_line
			(start 0.120396 0.3048)
			(end 0.120396 0.2794)
			(stroke
				(width 0.1)
				(type default)
			)
			(layer "F.Fab")
		)
		(fp_line
			(start 0.12065 -0.3048)
			(end 0.67945 -0.3048)
			(stroke
				(width 0.1)
				(type default)
			)
			(layer "F.Fab")
		)
		(fp_line
			(start 0.12065 -0.2794)
			(end 0.12065 -0.3048)
			(stroke
				(width 0.1)
				(type default)
			)
			(layer "F.Fab")
		)
		(fp_line
			(start 0.67945 -0.3048)
			(end 0.67945 0.3048)
			(stroke
				(width 0.1)
				(type default)
			)
			(layer "F.Fab")
		)
		(fp_line
			(start 0.67945 0.3048)
			(end 0.120396 0.3048)
			(stroke
				(width 0.1)
				(type default)
			)
			(layer "F.Fab")
		)
		(pad "1" smd circle
			(at -0.40005 0)
			(size 0 0)
			(layers "F.Cu" "F.Mask" "F.Paste")
			(net "SW_P12V_PVCCIN_CPU1_FLT")
		)
		(pad "2" smd circle
			(at 0.40005 0)
			(size 0 0)
			(layers "F.Cu" "F.Mask" "F.Paste")
			(net "GND")
		)
	)
	(footprint ""
		(layer "F.Cu")
		(at 159.951674 -402.371052 -90)
		(property "Reference" "C769"
			(at 0 0 270)
			(layer "F.SilkS")
			(hide yes)
			(effects
				(font
					(size 1.27 1.27)
				)
			)
		)
		(property "Value" ""
			(at 0 0 270)
			(layer "F.Fab")
			(effects
				(font
					(size 1.27 1.27)
				)
			)
		)
		(duplicate_pad_numbers_are_jumpers no)
		(fp_line
			(start -0.299974 0.150114)
			(end -0.299974 -0.150114)
			(stroke
				(width 0.1)
				(type default)
			)
			(layer "F.Fab")
		)
		(fp_line
			(start 0.299974 0.150114)
			(end -0.299974 0.150114)
			(stroke
				(width 0.1)
				(type default)
			)
			(layer "F.Fab")
		)
		(fp_line
			(start -0.299974 -0.150114)
			(end 0.299974 -0.150114)
			(stroke
				(width 0.1)
				(type default)
			)
			(layer "F.Fab")
		)
		(fp_line
			(start 0.299974 -0.150114)
			(end 0.299974 0.150114)
			(stroke
				(width 0.1)
				(type default)
			)
			(layer "F.Fab")
		)
		(pad "1" smd rect
			(at -0.2667 0 270)
			(size 0.3048 0.381)
			(layers "F.Cu" "F.Mask" "F.Paste")
			(net "P5E_CPU1_PE2_TX_C_DP<2>")
		)
		(pad "2" smd rect
			(at 0.2667 0 270)
			(size 0.3048 0.381)
			(layers "F.Cu" "F.Mask" "F.Paste")
			(net "P5E_CPU1_PE2_TX_DP<2>")
		)
	)
	(footprint ""
		(layer "F.Cu")
		(at 101.071172 -363.873034)
		(property "Reference" "R2456"
			(at 0 0 0)
			(layer "F.SilkS")
			(hide yes)
			(effects
				(font
					(size 1.27 1.27)
				)
			)
		)
		(property "Value" ""
			(at 0 0 0)
			(layer "F.Fab")
			(effects
				(font
					(size 1.27 1.27)
				)
			)
		)
		(duplicate_pad_numbers_are_jumpers no)
		(fp_line
			(start -0.7874 -0.4064)
			(end 0.7874 -0.4064)
			(stroke
				(width 0.1524)
				(type default)
			)
			(layer "F.SilkS")
		)
		(fp_line
			(start -0.7874 0.4064)
			(end -0.7874 -0.4064)
			(stroke
				(width 0.1524)
				(type default)
			)
			(layer "F.SilkS")
		)
		(fp_line
			(start 0.7874 -0.4064)
			(end 0.7874 0.4064)
			(stroke
				(width 0.1524)
				(type default)
			)
			(layer "F.SilkS")
		)
		(fp_line
			(start 0.7874 0.4064)
			(end -0.7874 0.4064)
			(stroke
				(width 0.1524)
				(type default)
			)
			(layer "F.SilkS")
		)
		(fp_line
			(start -0.67945 -0.305054)
			(end -0.12065 -0.305054)
			(stroke
				(width 0.1)
				(type default)
			)
			(layer "F.Fab")
		)
		(fp_line
			(start -0.67945 0.3048)
			(end -0.67945 -0.305054)
			(stroke
				(width 0.1)
				(type default)
			)
			(layer "F.Fab")
		)
		(fp_line
			(start -0.12065 -0.305054)
			(end -0.12065 -0.2794)
			(stroke
				(width 0.1)
				(type default)
			)
			(layer "F.Fab")
		)
		(fp_line
			(start -0.12065 -0.2794)
			(end 0.12065 -0.2794)
			(stroke
				(width 0.1)
				(type default)
			)
			(layer "F.Fab")
		)
		(fp_line
			(start -0.12065 0.2794)
			(end -0.12065 0.3048)
			(stroke
				(width 0.1)
				(type default)
			)
			(layer "F.Fab")
		)
		(fp_line
			(start -0.12065 0.3048)
			(end -0.67945 0.3048)
			(stroke
				(width 0.1)
				(type default)
			)
			(layer "F.Fab")
		)
		(fp_line
			(start 0.120396 0.2794)
			(end -0.12065 0.2794)
			(stroke
				(width 0.1)
				(type default)
			)
			(layer "F.Fab")
		)
		(fp_line
			(start 0.120396 0.3048)
			(end 0.120396 0.2794)
			(stroke
				(width 0.1)
				(type default)
			)
			(layer "F.Fab")
		)
		(fp_line
			(start 0.12065 -0.3048)
			(end 0.67945 -0.3048)
			(stroke
				(width 0.1)
				(type default)
			)
			(layer "F.Fab")
		)
		(fp_line
			(start 0.12065 -0.2794)
			(end 0.12065 -0.3048)
			(stroke
				(width 0.1)
				(type default)
			)
			(layer "F.Fab")
		)
		(fp_line
			(start 0.67945 -0.3048)
			(end 0.67945 0.3048)
			(stroke
				(width 0.1)
				(type default)
			)
			(layer "F.Fab")
		)
		(fp_line
			(start 0.67945 0.3048)
			(end 0.120396 0.3048)
			(stroke
				(width 0.1)
				(type default)
			)
			(layer "F.Fab")
		)
		(pad "1" smd circle
			(at -0.40005 0)
			(size 0 0)
			(layers "F.Cu" "F.Mask" "F.Paste")
			(net "SMB_VR_3V3AUX_SDA_R")
		)
		(pad "2" smd circle
			(at 0.40005 0)
			(size 0 0)
			(layers "F.Cu" "F.Mask" "F.Paste")
			(net "SMB_VR_3V3AUX_SDA_R3")
		)
	)
	(footprint ""
		(layer "F.Cu")
		(at 296.831258 -372.456202 90)
		(property "Reference" "PC622"
			(at 0 0 90)
			(layer "F.SilkS")
			(hide yes)
			(effects
				(font
					(size 1.27 1.27)
				)
			)
		)
		(property "Value" ""
			(at 0 0 90)
			(layer "F.Fab")
			(effects
				(font
					(size 1.27 1.27)
				)
			)
		)
		(duplicate_pad_numbers_are_jumpers no)
		(fp_line
			(start -3.400044 1.249934)
			(end 3.400044 1.249934)
			(stroke
				(width 0.1524)
				(type default)
			)
			(layer "F.SilkS")
		)
		(fp_circle
			(center 0 1.249934)
			(end 0 4.649978)
			(stroke
				(width 0.1524)
				(type default)
			)
			(fill no)
			(layer "F.SilkS")
		)
		(fp_poly
			(pts
				(arc
					(start -3.400044 1.249934)
					(mid 0 4.649978)
					(end 3.400044 1.249934)
				)
			)
			(stroke
				(width 0)
				(type default)
			)
			(fill yes)
			(layer "F.SilkS")
		)
		(fp_circle
			(center 0 1.249934)
			(end 0 4.649978)
			(stroke
				(width 0.1)
				(type default)
			)
			(fill no)
			(layer "F.Fab")
		)
		(pad "1" thru_hole rect
			(at 0 0 90)
			(size 1.524 1.524)
			(drill 1.016)
			(layers "*.Cu" "*.Mask")
			(remove_unused_layers no)
			(net "SW_P12V_PVCCFA_EHV_FIVRA_CPU0_L")
			(clearance 0)
			(padstack
				(mode front_inner_back)
				(layer "Inner"
					(shape circle)
					(size 1.524 1.524)
					(clearance 0)
				)
				(layer "B.Cu"
					(shape rect)
					(size 1.524 1.524)
					(clearance 0)
				)
			)
		)
		(pad "2" thru_hole circle
			(at 0 2.500122 90)
			(size 1.524 1.524)
			(drill 1.016)
			(layers "*.Cu" "*.Mask")
			(remove_unused_layers no)
			(net "GND")
			(clearance 0)
		)
	)
	(footprint ""
		(layer "F.Cu")
		(at 64.591438 -31.887922 90)
		(property "Reference" "PC2167"
			(at 0 0 90)
			(layer "F.SilkS")
			(hide yes)
			(effects
				(font
					(size 1.27 1.27)
				)
			)
		)
		(property "Value" ""
			(at 0 0 90)
			(layer "F.Fab")
			(effects
				(font
					(size 1.27 1.27)
				)
			)
		)
		(duplicate_pad_numbers_are_jumpers no)
		(fp_line
			(start 0.7874 -0.4064)
			(end 0.7874 0.4064)
			(stroke
				(width 0.1524)
				(type default)
			)
			(layer "F.SilkS")
		)
		(fp_line
			(start -0.7874 -0.4064)
			(end 0.7874 -0.4064)
			(stroke
				(width 0.1524)
				(type default)
			)
			(layer "F.SilkS")
		)
		(fp_line
			(start 0.7874 0.4064)
			(end -0.7874 0.4064)
			(stroke
				(width 0.1524)
				(type default)
			)
			(layer "F.SilkS")
		)
		(fp_line
			(start -0.7874 0.4064)
			(end -0.7874 -0.4064)
			(stroke
				(width 0.1524)
				(type default)
			)
			(layer "F.SilkS")
		)
		(fp_line
			(start -0.12065 -0.305054)
			(end -0.12065 -0.2794)
			(stroke
				(width 0.1)
				(type default)
			)
			(layer "F.Fab")
		)
		(fp_line
			(start -0.67945 -0.305054)
			(end -0.12065 -0.305054)
			(stroke
				(width 0.1)
				(type default)
			)
			(layer "F.Fab")
		)
		(fp_line
			(start 0.67945 -0.3048)
			(end 0.67945 0.3048)
			(stroke
				(width 0.1)
				(type default)
			)
			(layer "F.Fab")
		)
		(fp_line
			(start 0.12065 -0.3048)
			(end 0.67945 -0.3048)
			(stroke
				(width 0.1)
				(type default)
			)
			(layer "F.Fab")
		)
		(fp_line
			(start 0.12065 -0.2794)
			(end 0.12065 -0.3048)
			(stroke
				(width 0.1)
				(type default)
			)
			(layer "F.Fab")
		)
		(fp_line
			(start -0.12065 -0.2794)
			(end 0.12065 -0.2794)
			(stroke
				(width 0.1)
				(type default)
			)
			(layer "F.Fab")
		)
		(fp_line
			(start 0.120396 0.2794)
			(end -0.12065 0.2794)
			(stroke
				(width 0.1)
				(type default)
			)
			(layer "F.Fab")
		)
		(fp_line
			(start -0.12065 0.2794)
			(end -0.12065 0.3048)
			(stroke
				(width 0.1)
				(type default)
			)
			(layer "F.Fab")
		)
		(fp_line
			(start 0.67945 0.3048)
			(end 0.120396 0.3048)
			(stroke
				(width 0.1)
				(type default)
			)
			(layer "F.Fab")
		)
		(fp_line
			(start 0.120396 0.3048)
			(end 0.120396 0.2794)
			(stroke
				(width 0.1)
				(type default)
			)
			(layer "F.Fab")
		)
		(fp_line
			(start -0.12065 0.3048)
			(end -0.67945 0.3048)
			(stroke
				(width 0.1)
				(type default)
			)
			(layer "F.Fab")
		)
		(fp_line
			(start -0.67945 0.3048)
			(end -0.67945 -0.305054)
			(stroke
				(width 0.1)
				(type default)
			)
			(layer "F.Fab")
		)
		(pad "1" smd circle
			(at -0.40005 0 90)
			(size 0 0)
			(layers "F.Cu" "F.Mask" "F.Paste")
			(net "P12V_OCP_IMON_2")
		)
		(pad "2" smd circle
			(at 0.40005 0 90)
			(size 0 0)
			(layers "F.Cu" "F.Mask" "F.Paste")
			(net "GND")
		)
	)
	(footprint ""
		(layer "F.Cu")
		(at 183.85028 -411.20568 -90)
		(property "Reference" "R4793"
			(at 0 0 270)
			(layer "F.SilkS")
			(hide yes)
			(effects
				(font
					(size 1.27 1.27)
				)
			)
		)
		(property "Value" ""
			(at 0 0 270)
			(layer "F.Fab")
			(effects
				(font
					(size 1.27 1.27)
				)
			)
		)
		(duplicate_pad_numbers_are_jumpers no)
		(fp_line
			(start -0.7874 0.4064)
			(end -0.7874 -0.4064)
			(stroke
				(width 0.1524)
				(type default)
			)
			(layer "F.SilkS")
		)
		(fp_line
			(start 0.7874 0.4064)
			(end -0.7874 0.4064)
			(stroke
				(width 0.1524)
				(type default)
			)
			(layer "F.SilkS")
		)
		(fp_line
			(start -0.7874 -0.4064)
			(end 0.7874 -0.4064)
			(stroke
				(width 0.1524)
				(type default)
			)
			(layer "F.SilkS")
		)
		(fp_line
			(start 0.7874 -0.4064)
			(end 0.7874 0.4064)
			(stroke
				(width 0.1524)
				(type default)
			)
			(layer "F.SilkS")
		)
		(fp_line
			(start -0.67945 0.3048)
			(end -0.67945 -0.305054)
			(stroke
				(width 0.1)
				(type default)
			)
			(layer "F.Fab")
		)
		(fp_line
			(start -0.12065 0.3048)
			(end -0.67945 0.3048)
			(stroke
				(width 0.1)
				(type default)
			)
			(layer "F.Fab")
		)
		(fp_line
			(start 0.120396 0.3048)
			(end 0.120396 0.2794)
			(stroke
				(width 0.1)
				(type default)
			)
			(layer "F.Fab")
		)
		(fp_line
			(start 0.67945 0.3048)
			(end 0.120396 0.3048)
			(stroke
				(width 0.1)
				(type default)
			)
			(layer "F.Fab")
		)
		(fp_line
			(start -0.12065 0.2794)
			(end -0.12065 0.3048)
			(stroke
				(width 0.1)
				(type default)
			)
			(layer "F.Fab")
		)
		(fp_line
			(start 0.120396 0.2794)
			(end -0.12065 0.2794)
			(stroke
				(width 0.1)
				(type default)
			)
			(layer "F.Fab")
		)
		(fp_line
			(start -0.12065 -0.2794)
			(end 0.12065 -0.2794)
			(stroke
				(width 0.1)
				(type default)
			)
			(layer "F.Fab")
		)
		(fp_line
			(start 0.12065 -0.2794)
			(end 0.12065 -0.3048)
			(stroke
				(width 0.1)
				(type default)
			)
			(layer "F.Fab")
		)
		(fp_line
			(start 0.12065 -0.3048)
			(end 0.67945 -0.3048)
			(stroke
				(width 0.1)
				(type default)
			)
			(layer "F.Fab")
		)
		(fp_line
			(start 0.67945 -0.3048)
			(end 0.67945 0.3048)
			(stroke
				(width 0.1)
				(type default)
			)
			(layer "F.Fab")
		)
		(fp_line
			(start -0.67945 -0.305054)
			(end -0.12065 -0.305054)
			(stroke
				(width 0.1)
				(type default)
			)
			(layer "F.Fab")
		)
		(fp_line
			(start -0.12065 -0.305054)
			(end -0.12065 -0.2794)
			(stroke
				(width 0.1)
				(type default)
			)
			(layer "F.Fab")
		)
		(pad "1" smd circle
			(at -0.40005 0 270)
			(size 0 0)
			(layers "F.Cu" "F.Mask" "F.Paste")
			(net "HSC_OC_VOL")
		)
		(pad "2" smd circle
			(at 0.40005 0 270)
			(size 0 0)
			(layers "F.Cu" "F.Mask" "F.Paste")
			(net "HSC_D_OC_R2")
		)
	)
	(footprint ""
		(layer "F.Cu")
		(at 114.013742 -338.180172 90)
		(property "Reference" "PR1789"
			(at 0 0 90)
			(layer "F.SilkS")
			(hide yes)
			(effects
				(font
					(size 1.27 1.27)
				)
			)
		)
		(property "Value" ""
			(at 0 0 90)
			(layer "F.Fab")
			(effects
				(font
					(size 1.27 1.27)
				)
			)
		)
		(duplicate_pad_numbers_are_jumpers no)
		(fp_line
			(start 0.7874 -0.4064)
			(end 0.7874 0.4064)
			(stroke
				(width 0.1524)
				(type default)
			)
			(layer "F.SilkS")
		)
		(fp_line
			(start -0.7874 -0.4064)
			(end 0.7874 -0.4064)
			(stroke
				(width 0.1524)
				(type default)
			)
			(layer "F.SilkS")
		)
		(fp_line
			(start 0.7874 0.4064)
			(end -0.7874 0.4064)
			(stroke
				(width 0.1524)
				(type default)
			)
			(layer "F.SilkS")
		)
		(fp_line
			(start -0.7874 0.4064)
			(end -0.7874 -0.4064)
			(stroke
				(width 0.1524)
				(type default)
			)
			(layer "F.SilkS")
		)
		(fp_line
			(start -0.12065 -0.305054)
			(end -0.12065 -0.2794)
			(stroke
				(width 0.1)
				(type default)
			)
			(layer "F.Fab")
		)
		(fp_line
			(start -0.67945 -0.305054)
			(end -0.12065 -0.305054)
			(stroke
				(width 0.1)
				(type default)
			)
			(layer "F.Fab")
		)
		(fp_line
			(start 0.67945 -0.3048)
			(end 0.67945 0.3048)
			(stroke
				(width 0.1)
				(type default)
			)
			(layer "F.Fab")
		)
		(fp_line
			(start 0.12065 -0.3048)
			(end 0.67945 -0.3048)
			(stroke
				(width 0.1)
				(type default)
			)
			(layer "F.Fab")
		)
		(fp_line
			(start 0.12065 -0.2794)
			(end 0.12065 -0.3048)
			(stroke
				(width 0.1)
				(type default)
			)
			(layer "F.Fab")
		)
		(fp_line
			(start -0.12065 -0.2794)
			(end 0.12065 -0.2794)
			(stroke
				(width 0.1)
				(type default)
			)
			(layer "F.Fab")
		)
		(fp_line
			(start 0.120396 0.2794)
			(end -0.12065 0.2794)
			(stroke
				(width 0.1)
				(type default)
			)
			(layer "F.Fab")
		)
		(fp_line
			(start -0.12065 0.2794)
			(end -0.12065 0.3048)
			(stroke
				(width 0.1)
				(type default)
			)
			(layer "F.Fab")
		)
		(fp_line
			(start 0.67945 0.3048)
			(end 0.120396 0.3048)
			(stroke
				(width 0.1)
				(type default)
			)
			(layer "F.Fab")
		)
		(fp_line
			(start 0.120396 0.3048)
			(end 0.120396 0.2794)
			(stroke
				(width 0.1)
				(type default)
			)
			(layer "F.Fab")
		)
		(fp_line
			(start -0.12065 0.3048)
			(end -0.67945 0.3048)
			(stroke
				(width 0.1)
				(type default)
			)
			(layer "F.Fab")
		)
		(fp_line
			(start -0.67945 0.3048)
			(end -0.67945 -0.305054)
			(stroke
				(width 0.1)
				(type default)
			)
			(layer "F.Fab")
		)
		(pad "1" smd circle
			(at -0.40005 0 90)
			(size 0 0)
			(layers "F.Cu" "F.Mask" "F.Paste")
			(net "SW_PVCCIN_CPU1_BOOT3")
		)
		(pad "2" smd circle
			(at 0.40005 0 90)
			(size 0 0)
			(layers "F.Cu" "F.Mask" "F.Paste")
			(net "SW_PVCCIN_CPU1_BOOT3_R")
		)
	)
	(footprint ""
		(layer "F.Cu")
		(at 109.337856 -32.64281)
		(property "Reference" "R3243"
			(at 0 0 0)
			(layer "F.SilkS")
			(hide yes)
			(effects
				(font
					(size 1.27 1.27)
				)
			)
		)
		(property "Value" ""
			(at 0 0 0)
			(layer "F.Fab")
			(effects
				(font
					(size 1.27 1.27)
				)
			)
		)
		(duplicate_pad_numbers_are_jumpers no)
		(fp_line
			(start -0.7874 -0.4064)
			(end 0.7874 -0.4064)
			(stroke
				(width 0.1524)
				(type default)
			)
			(layer "F.SilkS")
		)
		(fp_line
			(start -0.7874 0.4064)
			(end -0.7874 -0.4064)
			(stroke
				(width 0.1524)
				(type default)
			)
			(layer "F.SilkS")
		)
		(fp_line
			(start 0.7874 -0.4064)
			(end 0.7874 0.4064)
			(stroke
				(width 0.1524)
				(type default)
			)
			(layer "F.SilkS")
		)
		(fp_line
			(start 0.7874 0.4064)
			(end -0.7874 0.4064)
			(stroke
				(width 0.1524)
				(type default)
			)
			(layer "F.SilkS")
		)
		(fp_line
			(start -0.67945 -0.305054)
			(end -0.12065 -0.305054)
			(stroke
				(width 0.1)
				(type default)
			)
			(layer "F.Fab")
		)
		(fp_line
			(start -0.67945 0.3048)
			(end -0.67945 -0.305054)
			(stroke
				(width 0.1)
				(type default)
			)
			(layer "F.Fab")
		)
		(fp_line
			(start -0.12065 -0.305054)
			(end -0.12065 -0.2794)
			(stroke
				(width 0.1)
				(type default)
			)
			(layer "F.Fab")
		)
		(fp_line
			(start -0.12065 -0.2794)
			(end 0.12065 -0.2794)
			(stroke
				(width 0.1)
				(type default)
			)
			(layer "F.Fab")
		)
		(fp_line
			(start -0.12065 0.2794)
			(end -0.12065 0.3048)
			(stroke
				(width 0.1)
				(type default)
			)
			(layer "F.Fab")
		)
		(fp_line
			(start -0.12065 0.3048)
			(end -0.67945 0.3048)
			(stroke
				(width 0.1)
				(type default)
			)
			(layer "F.Fab")
		)
		(fp_line
			(start 0.120396 0.2794)
			(end -0.12065 0.2794)
			(stroke
				(width 0.1)
				(type default)
			)
			(layer "F.Fab")
		)
		(fp_line
			(start 0.120396 0.3048)
			(end 0.120396 0.2794)
			(stroke
				(width 0.1)
				(type default)
			)
			(layer "F.Fab")
		)
		(fp_line
			(start 0.12065 -0.3048)
			(end 0.67945 -0.3048)
			(stroke
				(width 0.1)
				(type default)
			)
			(layer "F.Fab")
		)
		(fp_line
			(start 0.12065 -0.2794)
			(end 0.12065 -0.3048)
			(stroke
				(width 0.1)
				(type default)
			)
			(layer "F.Fab")
		)
		(fp_line
			(start 0.67945 -0.3048)
			(end 0.67945 0.3048)
			(stroke
				(width 0.1)
				(type default)
			)
			(layer "F.Fab")
		)
		(fp_line
			(start 0.67945 0.3048)
			(end 0.120396 0.3048)
			(stroke
				(width 0.1)
				(type default)
			)
			(layer "F.Fab")
		)
		(pad "1" smd circle
			(at -0.40005 0)
			(size 0 0)
			(layers "F.Cu" "F.Mask" "F.Paste")
			(net "SMB_OCP_V3_2_3V3AUX_SDA")
		)
		(pad "2" smd circle
			(at 0.40005 0)
			(size 0 0)
			(layers "F.Cu" "F.Mask" "F.Paste")
			(net "P3V3_AUX")
		)
	)
	(footprint ""
		(layer "F.Cu")
		(at 385.91109 -408.517344 -90)
		(property "Reference" "C879"
			(at 0 0 270)
			(layer "F.SilkS")
			(hide yes)
			(effects
				(font
					(size 1.27 1.27)
				)
			)
		)
		(property "Value" ""
			(at 0 0 270)
			(layer "F.Fab")
			(effects
				(font
					(size 1.27 1.27)
				)
			)
		)
		(duplicate_pad_numbers_are_jumpers no)
		(fp_line
			(start -0.299974 0.150114)
			(end -0.299974 -0.150114)
			(stroke
				(width 0.1)
				(type default)
			)
			(layer "F.Fab")
		)
		(fp_line
			(start 0.299974 0.150114)
			(end -0.299974 0.150114)
			(stroke
				(width 0.1)
				(type default)
			)
			(layer "F.Fab")
		)
		(fp_line
			(start -0.299974 -0.150114)
			(end 0.299974 -0.150114)
			(stroke
				(width 0.1)
				(type default)
			)
			(layer "F.Fab")
		)
		(fp_line
			(start 0.299974 -0.150114)
			(end 0.299974 0.150114)
			(stroke
				(width 0.1)
				(type default)
			)
			(layer "F.Fab")
		)
		(pad "1" smd rect
			(at -0.2667 0 270)
			(size 0.3048 0.381)
			(layers "F.Cu" "F.Mask" "F.Paste")
			(net "P5E_CPU0_PE3_TX_C_DP<11>")
		)
		(pad "2" smd rect
			(at 0.2667 0 270)
			(size 0.3048 0.381)
			(layers "F.Cu" "F.Mask" "F.Paste")
			(net "P5E_CPU0_PE3_TX_DP<11>")
		)
	)
	(footprint ""
		(layer "F.Cu")
		(at 262.84809 -75.61834 90)
		(property "Reference" "PC2000"
			(at 0 0 90)
			(layer "F.SilkS")
			(hide yes)
			(effects
				(font
					(size 1.27 1.27)
				)
			)
		)
		(property "Value" ""
			(at 0 0 90)
			(layer "F.Fab")
			(effects
				(font
					(size 1.27 1.27)
				)
			)
		)
		(duplicate_pad_numbers_are_jumpers no)
		(fp_line
			(start 0.7874 -0.4064)
			(end 0.7874 0.4064)
			(stroke
				(width 0.1524)
				(type default)
			)
			(layer "F.SilkS")
		)
		(fp_line
			(start -0.7874 -0.4064)
			(end 0.7874 -0.4064)
			(stroke
				(width 0.1524)
				(type default)
			)
			(layer "F.SilkS")
		)
		(fp_line
			(start 0.7874 0.4064)
			(end -0.7874 0.4064)
			(stroke
				(width 0.1524)
				(type default)
			)
			(layer "F.SilkS")
		)
		(fp_line
			(start -0.7874 0.4064)
			(end -0.7874 -0.4064)
			(stroke
				(width 0.1524)
				(type default)
			)
			(layer "F.SilkS")
		)
		(fp_line
			(start -0.12065 -0.305054)
			(end -0.12065 -0.2794)
			(stroke
				(width 0.1)
				(type default)
			)
			(layer "F.Fab")
		)
		(fp_line
			(start -0.67945 -0.305054)
			(end -0.12065 -0.305054)
			(stroke
				(width 0.1)
				(type default)
			)
			(layer "F.Fab")
		)
		(fp_line
			(start 0.67945 -0.3048)
			(end 0.67945 0.3048)
			(stroke
				(width 0.1)
				(type default)
			)
			(layer "F.Fab")
		)
		(fp_line
			(start 0.12065 -0.3048)
			(end 0.67945 -0.3048)
			(stroke
				(width 0.1)
				(type default)
			)
			(layer "F.Fab")
		)
		(fp_line
			(start 0.12065 -0.2794)
			(end 0.12065 -0.3048)
			(stroke
				(width 0.1)
				(type default)
			)
			(layer "F.Fab")
		)
		(fp_line
			(start -0.12065 -0.2794)
			(end 0.12065 -0.2794)
			(stroke
				(width 0.1)
				(type default)
			)
			(layer "F.Fab")
		)
		(fp_line
			(start 0.120396 0.2794)
			(end -0.12065 0.2794)
			(stroke
				(width 0.1)
				(type default)
			)
			(layer "F.Fab")
		)
		(fp_line
			(start -0.12065 0.2794)
			(end -0.12065 0.3048)
			(stroke
				(width 0.1)
				(type default)
			)
			(layer "F.Fab")
		)
		(fp_line
			(start 0.67945 0.3048)
			(end 0.120396 0.3048)
			(stroke
				(width 0.1)
				(type default)
			)
			(layer "F.Fab")
		)
		(fp_line
			(start 0.120396 0.3048)
			(end 0.120396 0.2794)
			(stroke
				(width 0.1)
				(type default)
			)
			(layer "F.Fab")
		)
		(fp_line
			(start -0.12065 0.3048)
			(end -0.67945 0.3048)
			(stroke
				(width 0.1)
				(type default)
			)
			(layer "F.Fab")
		)
		(fp_line
			(start -0.67945 0.3048)
			(end -0.67945 -0.305054)
			(stroke
				(width 0.1)
				(type default)
			)
			(layer "F.Fab")
		)
		(pad "1" smd circle
			(at -0.40005 0 90)
			(size 0 0)
			(layers "F.Cu" "F.Mask" "F.Paste")
			(net "P1V05_PCH_AUX_REF")
		)
		(pad "2" smd circle
			(at 0.40005 0 90)
			(size 0 0)
			(layers "F.Cu" "F.Mask" "F.Paste")
			(net "GND")
		)
	)
	(footprint ""
		(layer "F.Cu")
		(at 38.02888 -434.939948)
		(property "Reference" "R3523"
			(at 0 0 0)
			(layer "F.SilkS")
			(hide yes)
			(effects
				(font
					(size 1.27 1.27)
				)
			)
		)
		(property "Value" ""
			(at 0 0 0)
			(layer "F.Fab")
			(effects
				(font
					(size 1.27 1.27)
				)
			)
		)
		(duplicate_pad_numbers_are_jumpers no)
		(fp_line
			(start -0.7874 -0.4064)
			(end 0.7874 -0.4064)
			(stroke
				(width 0.1524)
				(type default)
			)
			(layer "F.SilkS")
		)
		(fp_line
			(start -0.7874 0.4064)
			(end -0.7874 -0.4064)
			(stroke
				(width 0.1524)
				(type default)
			)
			(layer "F.SilkS")
		)
		(fp_line
			(start 0.7874 -0.4064)
			(end 0.7874 0.4064)
			(stroke
				(width 0.1524)
				(type default)
			)
			(layer "F.SilkS")
		)
		(fp_line
			(start 0.7874 0.4064)
			(end -0.7874 0.4064)
			(stroke
				(width 0.1524)
				(type default)
			)
			(layer "F.SilkS")
		)
		(fp_line
			(start -0.67945 -0.305054)
			(end -0.12065 -0.305054)
			(stroke
				(width 0.1)
				(type default)
			)
			(layer "F.Fab")
		)
		(fp_line
			(start -0.67945 0.3048)
			(end -0.67945 -0.305054)
			(stroke
				(width 0.1)
				(type default)
			)
			(layer "F.Fab")
		)
		(fp_line
			(start -0.12065 -0.305054)
			(end -0.12065 -0.2794)
			(stroke
				(width 0.1)
				(type default)
			)
			(layer "F.Fab")
		)
		(fp_line
			(start -0.12065 -0.2794)
			(end 0.12065 -0.2794)
			(stroke
				(width 0.1)
				(type default)
			)
			(layer "F.Fab")
		)
		(fp_line
			(start -0.12065 0.2794)
			(end -0.12065 0.3048)
			(stroke
				(width 0.1)
				(type default)
			)
			(layer "F.Fab")
		)
		(fp_line
			(start -0.12065 0.3048)
			(end -0.67945 0.3048)
			(stroke
				(width 0.1)
				(type default)
			)
			(layer "F.Fab")
		)
		(fp_line
			(start 0.120396 0.2794)
			(end -0.12065 0.2794)
			(stroke
				(width 0.1)
				(type default)
			)
			(layer "F.Fab")
		)
		(fp_line
			(start 0.120396 0.3048)
			(end 0.120396 0.2794)
			(stroke
				(width 0.1)
				(type default)
			)
			(layer "F.Fab")
		)
		(fp_line
			(start 0.12065 -0.3048)
			(end 0.67945 -0.3048)
			(stroke
				(width 0.1)
				(type default)
			)
			(layer "F.Fab")
		)
		(fp_line
			(start 0.12065 -0.2794)
			(end 0.12065 -0.3048)
			(stroke
				(width 0.1)
				(type default)
			)
			(layer "F.Fab")
		)
		(fp_line
			(start 0.67945 -0.3048)
			(end 0.67945 0.3048)
			(stroke
				(width 0.1)
				(type default)
			)
			(layer "F.Fab")
		)
		(fp_line
			(start 0.67945 0.3048)
			(end 0.120396 0.3048)
			(stroke
				(width 0.1)
				(type default)
			)
			(layer "F.Fab")
		)
		(pad "1" smd circle
			(at -0.40005 0)
			(size 0 0)
			(layers "F.Cu" "F.Mask" "F.Paste")
			(net "P3V3_AUX")
		)
		(pad "2" smd circle
			(at 0.40005 0)
			(size 0 0)
			(layers "F.Cu" "F.Mask" "F.Paste")
			(net "SMB_1_BMC_GPU_BUF_R_SCL")
		)
	)
	(footprint ""
		(layer "F.Cu")
		(at 215.33739 -104.33304 180)
		(property "Reference" "U205"
			(at 6.09854 -2.351532 0)
			(unlocked yes)
			(layer "F.SilkS")
			(effects
				(font
					(size 0.7874 0.5842)
					(thickness 0.1524)
				)
				(justify left)
			)
		)
		(property "Value" ""
			(at 0 0 180)
			(layer "F.Fab")
			(effects
				(font
					(size 1.27 1.27)
				)
			)
		)
		(duplicate_pad_numbers_are_jumpers no)
		(fp_line
			(start 2.03581 1.525016)
			(end 2.03581 -1.525016)
			(stroke
				(width 0.1524)
				(type default)
			)
			(layer "F.SilkS")
		)
		(fp_line
			(start 2.03581 -1.525016)
			(end 0.82423 -1.525016)
			(stroke
				(width 0.1524)
				(type default)
			)
			(layer "F.SilkS")
		)
		(fp_line
			(start 0.82423 -1.525016)
			(end 0 -0.649986)
			(stroke
				(width 0.1524)
				(type default)
			)
			(layer "F.SilkS")
		)
		(fp_line
			(start 0 -0.649986)
			(end -0.82423 -1.525016)
			(stroke
				(width 0.1524)
				(type default)
			)
			(layer "F.SilkS")
		)
		(fp_line
			(start -0.82423 -1.525016)
			(end -2.03581 -1.525016)
			(stroke
				(width 0.1524)
				(type default)
			)
			(layer "F.SilkS")
		)
		(fp_line
			(start -2.03581 1.525016)
			(end 2.03581 1.525016)
			(stroke
				(width 0.1524)
				(type default)
			)
			(layer "F.SilkS")
		)
		(fp_line
			(start -2.03581 -1.525016)
			(end -2.03581 1.525016)
			(stroke
				(width 0.1524)
				(type default)
			)
			(layer "F.SilkS")
		)
		(fp_poly
			(pts
				(xy -2.335276 -1.224788) (xy -3.151378 -1.497076) (xy -2.60731 -2.041144)
			)
			(stroke
				(width 0)
				(type default)
			)
			(fill yes)
			(layer "F.SilkS")
		)
		(fp_line
			(start 0.87503 1.525016)
			(end 0.87503 -1.525016)
			(stroke
				(width 0.1)
				(type default)
			)
			(layer "F.Fab")
		)
		(fp_line
			(start 0.87503 -1.525016)
			(end -0.87503 -1.525016)
			(stroke
				(width 0.1)
				(type default)
			)
			(layer "F.Fab")
		)
		(fp_line
			(start -0.87503 1.525016)
			(end 0.87503 1.525016)
			(stroke
				(width 0.1)
				(type default)
			)
			(layer "F.Fab")
		)
		(fp_line
			(start -0.87503 -1.525016)
			(end -0.87503 1.525016)
			(stroke
				(width 0.1)
				(type default)
			)
			(layer "F.Fab")
		)
		(fp_poly
			(pts
				(xy -2.12979 -0.943356) (xy -2.89941 -0.5588) (xy -2.89941 -1.328166)
			)
			(stroke
				(width 0)
				(type default)
			)
			(fill yes)
			(layer "F.Fab")
		)
		(pad "1" smd rect
			(at -1.35001 -0.94996 90)
			(size 0.6096 1.1176)
			(layers "F.Cu" "F.Mask" "F.Paste")
			(net "PWRGD_DSW_PWROK_R4")
		)
		(pad "2" smd rect
			(at -1.35001 0 90)
			(size 0.6096 1.1176)
			(layers "F.Cu" "F.Mask" "F.Paste")
			(net "GND")
		)
		(pad "3" smd rect
			(at -1.35001 0.94996 90)
			(size 0.6096 1.1176)
			(layers "F.Cu" "F.Mask" "F.Paste")
			(net "A_HSC_INAP")
		)
		(pad "4" smd rect
			(at 1.35001 0.94996 90)
			(size 0.6096 1.1176)
			(layers "F.Cu" "F.Mask" "F.Paste")
			(net "NC_U205_INB-")
		)
		(pad "5" smd rect
			(at 1.35001 0 90)
			(size 0.6096 1.1176)
			(layers "F.Cu" "F.Mask" "F.Paste")
			(net "U205_VDD")
		)
		(pad "6" smd rect
			(at 1.35001 -0.94996 90)
			(size 0.6096 1.1176)
			(layers "F.Cu" "F.Mask" "F.Paste")
			(net "NC_U205_OUTB")
		)
	)
	(footprint ""
		(layer "F.Cu")
		(at 49.3903 -389.985758 180)
		(property "Reference" "R4645"
			(at 0 0 180)
			(layer "F.SilkS")
			(hide yes)
			(effects
				(font
					(size 1.27 1.27)
				)
			)
		)
		(property "Value" ""
			(at 0 0 180)
			(layer "F.Fab")
			(effects
				(font
					(size 1.27 1.27)
				)
			)
		)
		(duplicate_pad_numbers_are_jumpers no)
		(fp_line
			(start 0.7874 0.4064)
			(end -0.7874 0.4064)
			(stroke
				(width 0.1524)
				(type default)
			)
			(layer "F.SilkS")
		)
		(fp_line
			(start 0.7874 -0.4064)
			(end 0.7874 0.4064)
			(stroke
				(width 0.1524)
				(type default)
			)
			(layer "F.SilkS")
		)
		(fp_line
			(start -0.7874 0.4064)
			(end -0.7874 -0.4064)
			(stroke
				(width 0.1524)
				(type default)
			)
			(layer "F.SilkS")
		)
		(fp_line
			(start -0.7874 -0.4064)
			(end 0.7874 -0.4064)
			(stroke
				(width 0.1524)
				(type default)
			)
			(layer "F.SilkS")
		)
		(fp_line
			(start 0.67945 0.3048)
			(end 0.120396 0.3048)
			(stroke
				(width 0.1)
				(type default)
			)
			(layer "F.Fab")
		)
		(fp_line
			(start 0.67945 -0.3048)
			(end 0.67945 0.3048)
			(stroke
				(width 0.1)
				(type default)
			)
			(layer "F.Fab")
		)
		(fp_line
			(start 0.12065 -0.2794)
			(end 0.12065 -0.3048)
			(stroke
				(width 0.1)
				(type default)
			)
			(layer "F.Fab")
		)
		(fp_line
			(start 0.12065 -0.3048)
			(end 0.67945 -0.3048)
			(stroke
				(width 0.1)
				(type default)
			)
			(layer "F.Fab")
		)
		(fp_line
			(start 0.120396 0.3048)
			(end 0.120396 0.2794)
			(stroke
				(width 0.1)
				(type default)
			)
			(layer "F.Fab")
		)
		(fp_line
			(start 0.120396 0.2794)
			(end -0.12065 0.2794)
			(stroke
				(width 0.1)
				(type default)
			)
			(layer "F.Fab")
		)
		(fp_line
			(start -0.12065 0.3048)
			(end -0.67945 0.3048)
			(stroke
				(width 0.1)
				(type default)
			)
			(layer "F.Fab")
		)
		(fp_line
			(start -0.12065 0.2794)
			(end -0.12065 0.3048)
			(stroke
				(width 0.1)
				(type default)
			)
			(layer "F.Fab")
		)
		(fp_line
			(start -0.12065 -0.2794)
			(end 0.12065 -0.2794)
			(stroke
				(width 0.1)
				(type default)
			)
			(layer "F.Fab")
		)
		(fp_line
			(start -0.12065 -0.305054)
			(end -0.12065 -0.2794)
			(stroke
				(width 0.1)
				(type default)
			)
			(layer "F.Fab")
		)
		(fp_line
			(start -0.67945 0.3048)
			(end -0.67945 -0.305054)
			(stroke
				(width 0.1)
				(type default)
			)
			(layer "F.Fab")
		)
		(fp_line
			(start -0.67945 -0.305054)
			(end -0.12065 -0.305054)
			(stroke
				(width 0.1)
				(type default)
			)
			(layer "F.Fab")
		)
		(pad "1" smd circle
			(at -0.40005 0 180)
			(size 0 0)
			(layers "F.Cu" "F.Mask" "F.Paste")
			(net "P3V3_AUX")
		)
		(pad "2" smd circle
			(at 0.40005 0 180)
			(size 0 0)
			(layers "F.Cu" "F.Mask" "F.Paste")
			(net "FM_P2E_BUF2_EQB0")
		)
	)
	(footprint ""
		(layer "F.Cu")
		(at 24.892 -419.5572 180)
		(property "Reference" "R4736"
			(at 0 0 180)
			(layer "F.SilkS")
			(hide yes)
			(effects
				(font
					(size 1.27 1.27)
				)
			)
		)
		(property "Value" ""
			(at 0 0 180)
			(layer "F.Fab")
			(effects
				(font
					(size 1.27 1.27)
				)
			)
		)
		(duplicate_pad_numbers_are_jumpers no)
		(fp_line
			(start 0.7874 0.4064)
			(end -0.7874 0.4064)
			(stroke
				(width 0.1524)
				(type default)
			)
			(layer "F.SilkS")
		)
		(fp_line
			(start 0.7874 -0.4064)
			(end 0.7874 0.4064)
			(stroke
				(width 0.1524)
				(type default)
			)
			(layer "F.SilkS")
		)
		(fp_line
			(start -0.7874 0.4064)
			(end -0.7874 -0.4064)
			(stroke
				(width 0.1524)
				(type default)
			)
			(layer "F.SilkS")
		)
		(fp_line
			(start -0.7874 -0.4064)
			(end 0.7874 -0.4064)
			(stroke
				(width 0.1524)
				(type default)
			)
			(layer "F.SilkS")
		)
		(fp_line
			(start 0.67945 0.3048)
			(end 0.120396 0.3048)
			(stroke
				(width 0.1)
				(type default)
			)
			(layer "F.Fab")
		)
		(fp_line
			(start 0.67945 -0.3048)
			(end 0.67945 0.3048)
			(stroke
				(width 0.1)
				(type default)
			)
			(layer "F.Fab")
		)
		(fp_line
			(start 0.12065 -0.2794)
			(end 0.12065 -0.3048)
			(stroke
				(width 0.1)
				(type default)
			)
			(layer "F.Fab")
		)
		(fp_line
			(start 0.12065 -0.3048)
			(end 0.67945 -0.3048)
			(stroke
				(width 0.1)
				(type default)
			)
			(layer "F.Fab")
		)
		(fp_line
			(start 0.120396 0.3048)
			(end 0.120396 0.2794)
			(stroke
				(width 0.1)
				(type default)
			)
			(layer "F.Fab")
		)
		(fp_line
			(start 0.120396 0.2794)
			(end -0.12065 0.2794)
			(stroke
				(width 0.1)
				(type default)
			)
			(layer "F.Fab")
		)
		(fp_line
			(start -0.12065 0.3048)
			(end -0.67945 0.3048)
			(stroke
				(width 0.1)
				(type default)
			)
			(layer "F.Fab")
		)
		(fp_line
			(start -0.12065 0.2794)
			(end -0.12065 0.3048)
			(stroke
				(width 0.1)
				(type default)
			)
			(layer "F.Fab")
		)
		(fp_line
			(start -0.12065 -0.2794)
			(end 0.12065 -0.2794)
			(stroke
				(width 0.1)
				(type default)
			)
			(layer "F.Fab")
		)
		(fp_line
			(start -0.12065 -0.305054)
			(end -0.12065 -0.2794)
			(stroke
				(width 0.1)
				(type default)
			)
			(layer "F.Fab")
		)
		(fp_line
			(start -0.67945 0.3048)
			(end -0.67945 -0.305054)
			(stroke
				(width 0.1)
				(type default)
			)
			(layer "F.Fab")
		)
		(fp_line
			(start -0.67945 -0.305054)
			(end -0.12065 -0.305054)
			(stroke
				(width 0.1)
				(type default)
			)
			(layer "F.Fab")
		)
		(pad "1" smd circle
			(at -0.40005 0 180)
			(size 0 0)
			(layers "F.Cu" "F.Mask" "F.Paste")
			(net "PRSNT_CABLE_GPU_A2_ISO_N")
		)
		(pad "2" smd circle
			(at 0.40005 0 180)
			(size 0 0)
			(layers "F.Cu" "F.Mask" "F.Paste")
			(net "PRSNT_CABLE_GPU_A2_ISO_R1_N")
		)
	)
	(footprint ""
		(layer "F.Cu")
		(at 217.583766 -16.381222 -90)
		(property "Reference" "R3181"
			(at 0 0 270)
			(layer "F.SilkS")
			(hide yes)
			(effects
				(font
					(size 1.27 1.27)
				)
			)
		)
		(property "Value" ""
			(at 0 0 270)
			(layer "F.Fab")
			(effects
				(font
					(size 1.27 1.27)
				)
			)
		)
		(duplicate_pad_numbers_are_jumpers no)
		(fp_line
			(start -0.7874 0.4064)
			(end -0.7874 -0.4064)
			(stroke
				(width 0.1524)
				(type default)
			)
			(layer "F.SilkS")
		)
		(fp_line
			(start 0.7874 0.4064)
			(end -0.7874 0.4064)
			(stroke
				(width 0.1524)
				(type default)
			)
			(layer "F.SilkS")
		)
		(fp_line
			(start -0.7874 -0.4064)
			(end 0.7874 -0.4064)
			(stroke
				(width 0.1524)
				(type default)
			)
			(layer "F.SilkS")
		)
		(fp_line
			(start 0.7874 -0.4064)
			(end 0.7874 0.4064)
			(stroke
				(width 0.1524)
				(type default)
			)
			(layer "F.SilkS")
		)
		(fp_line
			(start -0.67945 0.3048)
			(end -0.67945 -0.305054)
			(stroke
				(width 0.1)
				(type default)
			)
			(layer "F.Fab")
		)
		(fp_line
			(start -0.12065 0.3048)
			(end -0.67945 0.3048)
			(stroke
				(width 0.1)
				(type default)
			)
			(layer "F.Fab")
		)
		(fp_line
			(start 0.120396 0.3048)
			(end 0.120396 0.2794)
			(stroke
				(width 0.1)
				(type default)
			)
			(layer "F.Fab")
		)
		(fp_line
			(start 0.67945 0.3048)
			(end 0.120396 0.3048)
			(stroke
				(width 0.1)
				(type default)
			)
			(layer "F.Fab")
		)
		(fp_line
			(start -0.12065 0.2794)
			(end -0.12065 0.3048)
			(stroke
				(width 0.1)
				(type default)
			)
			(layer "F.Fab")
		)
		(fp_line
			(start 0.120396 0.2794)
			(end -0.12065 0.2794)
			(stroke
				(width 0.1)
				(type default)
			)
			(layer "F.Fab")
		)
		(fp_line
			(start -0.12065 -0.2794)
			(end 0.12065 -0.2794)
			(stroke
				(width 0.1)
				(type default)
			)
			(layer "F.Fab")
		)
		(fp_line
			(start 0.12065 -0.2794)
			(end 0.12065 -0.3048)
			(stroke
				(width 0.1)
				(type default)
			)
			(layer "F.Fab")
		)
		(fp_line
			(start 0.12065 -0.3048)
			(end 0.67945 -0.3048)
			(stroke
				(width 0.1)
				(type default)
			)
			(layer "F.Fab")
		)
		(fp_line
			(start 0.67945 -0.3048)
			(end 0.67945 0.3048)
			(stroke
				(width 0.1)
				(type default)
			)
			(layer "F.Fab")
		)
		(fp_line
			(start -0.67945 -0.305054)
			(end -0.12065 -0.305054)
			(stroke
				(width 0.1)
				(type default)
			)
			(layer "F.Fab")
		)
		(fp_line
			(start -0.12065 -0.305054)
			(end -0.12065 -0.2794)
			(stroke
				(width 0.1)
				(type default)
			)
			(layer "F.Fab")
		)
		(pad "1" smd circle
			(at -0.40005 0 270)
			(size 0 0)
			(layers "F.Cu" "F.Mask" "F.Paste")
			(net "CLK_50M_NCSI_OCP_2")
		)
		(pad "2" smd circle
			(at 0.40005 0 270)
			(size 0 0)
			(layers "F.Cu" "F.Mask" "F.Paste")
			(net "CLK_50M_NCSI_OCP_V3_2")
		)
	)
	(footprint ""
		(layer "F.Cu")
		(at 105.158286 -333.716122)
		(property "Reference" "PU30_P1_2"
			(at -2.670048 -6.321298 0)
			(unlocked yes)
			(layer "F.SilkS")
			(effects
				(font
					(size 0.7874 0.5842)
					(thickness 0.1524)
				)
				(justify left)
			)
		)
		(property "Value" ""
			(at 0 0 0)
			(layer "F.Fab")
			(effects
				(font
					(size 1.27 1.27)
				)
			)
		)
		(duplicate_pad_numbers_are_jumpers no)
		(fp_line
			(start -2.500122 -2.999994)
			(end -2.24409 -2.999994)
			(stroke
				(width 0.1524)
				(type default)
			)
			(layer "F.SilkS")
		)
		(fp_line
			(start -2.500122 -2.529078)
			(end -2.500122 -2.999994)
			(stroke
				(width 0.1524)
				(type default)
			)
			(layer "F.SilkS")
		)
		(fp_line
			(start -2.500122 0.6604)
			(end -2.500122 0.229108)
			(stroke
				(width 0.1524)
				(type default)
			)
			(layer "F.SilkS")
		)
		(fp_line
			(start -2.500122 2.999994)
			(end -2.500122 2.339594)
			(stroke
				(width 0.1524)
				(type default)
			)
			(layer "F.SilkS")
		)
		(fp_line
			(start -2.2987 2.999994)
			(end -2.500122 2.999994)
			(stroke
				(width 0.1524)
				(type default)
			)
			(layer "F.SilkS")
		)
		(fp_line
			(start 2.31394 -2.999994)
			(end 2.500122 -2.999994)
			(stroke
				(width 0.1524)
				(type default)
			)
			(layer "F.SilkS")
		)
		(fp_line
			(start 2.500122 -2.999994)
			(end 2.500122 -2.44348)
			(stroke
				(width 0.1524)
				(type default)
			)
			(layer "F.SilkS")
		)
		(fp_line
			(start 2.500122 2.339594)
			(end 2.500122 2.999994)
			(stroke
				(width 0.1524)
				(type default)
			)
			(layer "F.SilkS")
		)
		(fp_line
			(start 2.500122 2.999994)
			(end 2.2987 2.999994)
			(stroke
				(width 0.1524)
				(type default)
			)
			(layer "F.SilkS")
		)
		(fp_poly
			(pts
				(xy -2.156714 -3.626612) (xy -2.664714 -2.610612) (xy -3.172714 -3.626612)
			)
			(stroke
				(width 0)
				(type default)
			)
			(fill yes)
			(layer "F.SilkS")
		)
		(fp_line
			(start -2.500122 -2.999994)
			(end 2.500122 -2.999994)
			(stroke
				(width 0.1)
				(type default)
			)
			(layer "F.Fab")
		)
		(fp_line
			(start -2.500122 2.999994)
			(end -2.500122 -2.999994)
			(stroke
				(width 0.1)
				(type default)
			)
			(layer "F.Fab")
		)
		(fp_line
			(start 2.500122 -2.999994)
			(end 2.500122 2.999994)
			(stroke
				(width 0.1)
				(type default)
			)
			(layer "F.Fab")
		)
		(fp_line
			(start 2.500122 2.999994)
			(end -2.500122 2.999994)
			(stroke
				(width 0.1)
				(type default)
			)
			(layer "F.Fab")
		)
		(fp_poly
			(pts
				(xy -4.218432 -2.783078) (xy -4.218432 -1.767078) (xy -3.202432 -2.275078)
			)
			(stroke
				(width 0)
				(type default)
			)
			(fill yes)
			(layer "F.Fab")
		)
		(pad "1" smd rect
			(at -2.400046 -2.275078 90)
			(size 0.2286 0.6096)
			(layers "F.Cu" "F.Mask" "F.Paste")
			(net "PVCCIN_CPU1_VOS2")
		)
		(pad "2" smd rect
			(at -2.400046 -1.82499 90)
			(size 0.2286 0.6096)
			(layers "F.Cu" "F.Mask" "F.Paste")
			(net "GND")
		)
		(pad "3" smd rect
			(at -2.400046 -1.374902 90)
			(size 0.2286 0.6096)
			(layers "F.Cu" "F.Mask" "F.Paste")
			(net "PVCCIN_CPU1_VDD2")
		)
		(pad "4" smd rect
			(at -2.400046 -0.925068 90)
			(size 0.2286 0.6096)
			(layers "F.Cu" "F.Mask" "F.Paste")
			(net "PVCCIN_CPU1_PVCC")
		)
		(pad "5" smd rect
			(at -2.400046 -0.47498 90)
			(size 0.2286 0.6096)
			(layers "F.Cu" "F.Mask" "F.Paste")
			(net "GND")
		)
		(pad "6" smd rect
			(at -2.400046 -0.024892 90)
			(size 0.2286 0.6096)
			(layers "F.Cu" "F.Mask" "F.Paste")
			(net "Net_8523")
		)
		(pad "7_9-20_24" smd circle
			(at 0 1.150112 90)
			(size 0 0)
			(layers "F.Cu" "F.Mask" "F.Paste")
			(net "GND")
		)
		(pad "10_19" smd rect
			(at 0 2.899918 90)
			(size 0.6096 4.318)
			(layers "F.Cu" "F.Mask" "F.Paste")
			(net "SW_PVCCIN_CPU1_SW2")
		)
		(pad "25_29" smd rect
			(at 1.549908 -1.279906 270)
			(size 2.0574 2.3114)
			(layers "F.Cu" "F.Mask" "F.Paste")
			(net "SW_P12V_PVCCIN_CPU1_FLT")
		)
		(pad "30" smd rect
			(at 2.05994 -2.899918)
			(size 0.2286 0.6096)
			(layers "F.Cu" "F.Mask" "F.Paste")
			(net "SW_P12V_PVCCIN_CPU1_FLT")
		)
		(pad "31" smd rect
			(at 1.610106 -2.899918)
			(size 0.2286 0.6096)
			(layers "F.Cu" "F.Mask" "F.Paste")
			(net "Net_8524")
		)
		(pad "32" smd rect
			(at 1.160018 -2.899918)
			(size 0.2286 0.6096)
			(layers "F.Cu" "F.Mask" "F.Paste")
			(net "SW_PVCCIN_CPU1_BOOTR2")
		)
		(pad "33" smd rect
			(at 0.70993 -2.899918)
			(size 0.2286 0.6096)
			(layers "F.Cu" "F.Mask" "F.Paste")
			(net "SW_PVCCIN_CPU1_BOOT2")
		)
		(pad "34" smd rect
			(at 0.260096 -2.899918)
			(size 0.2286 0.6096)
			(layers "F.Cu" "F.Mask" "F.Paste")
			(net "PVCCIN_CPU1_PWM2")
		)
		(pad "35" smd rect
			(at -0.189992 -2.899918)
			(size 0.2286 0.6096)
			(layers "F.Cu" "F.Mask" "F.Paste")
			(net "PVCCIN_CPU1_VDD2")
		)
		(pad "36" smd rect
			(at -0.64008 -2.899918)
			(size 0.2286 0.6096)
			(layers "F.Cu" "F.Mask" "F.Paste")
			(net "PVCCIN_CPU1_ATSEN")
		)
		(pad "37" smd rect
			(at -1.089914 -2.899918)
			(size 0.2286 0.6096)
			(layers "F.Cu" "F.Mask" "F.Paste")
			(net "PVCCIN_CPU1_LSET2")
		)
		(pad "38" smd rect
			(at -1.540002 -2.899918)
			(size 0.2286 0.6096)
			(layers "F.Cu" "F.Mask" "F.Paste")
			(net "PVCCIN_CPU1_IMON2")
		)
		(pad "39" smd rect
			(at -1.99009 -2.899918)
			(size 0.2286 0.6096)
			(layers "F.Cu" "F.Mask" "F.Paste")
			(net "PVCCIN_CPU1_VREF")
		)
		(pad "40" smd rect
			(at -0.87503 -1.27508)
			(size 1.7526 1.9558)
			(layers "F.Cu" "F.Mask" "F.Paste")
			(net "GND")
		)
		(pad "41" smd rect
			(at -1.525016 0.249936 270)
			(size 0.3048 0.4572)
			(layers "F.Cu" "F.Mask" "F.Paste")
			(net "Net_8522")
		)
		(zone
			(layer "F.Cu")
			(hatch none 0.5)
			(connect_pads
				(clearance 0)
			)
			(min_thickness 0.25)
			(keepout
				(tracks not_allowed)
				(vias allowed)
				(pads allowed)
				(copperpour not_allowed)
				(footprints allowed)
			)
			(placement
				(enabled no)
				(sheetname "")
			)
			(fill
				(thermal_gap 0.5)
				(thermal_bridge_width 0.5)
				(island_removal_mode 0)
			)
			(polygon
				(pts
					(xy 102.658164 -330.716128) (xy 102.658164 -331.465428) (xy 107.658408 -331.465428) (xy 107.658408 -330.716128)
					(xy 107.368086 -330.716128) (xy 107.368086 -331.171804) (xy 102.948486 -331.171804) (xy 102.948486 -330.716128)
				)
			)
		)
		(zone
			(layer "F.Cu")
			(hatch none 0.5)
			(connect_pads
				(clearance 0)
			)
			(min_thickness 0.25)
			(keepout
				(tracks not_allowed)
				(vias allowed)
				(pads allowed)
				(copperpour not_allowed)
				(footprints allowed)
			)
			(placement
				(enabled no)
				(sheetname "")
			)
			(fill
				(thermal_gap 0.5)
				(thermal_bridge_width 0.5)
				(island_removal_mode 0)
			)
			(polygon
				(pts
					(xy 103.11384 -334.040988) (xy 103.356156 -334.040988) (xy 103.356156 -333.962502) (xy 104.13238 -333.962502)
					(xy 104.13238 -333.632048) (xy 104.207564 -333.632048) (xy 104.207564 -332.966822) (xy 102.658164 -332.966822)
					(xy 102.658164 -333.423514) (xy 103.35387 -333.423514) (xy 103.35387 -333.262986) (xy 103.91267 -333.262986)
					(xy 103.91267 -333.669386) (xy 103.35387 -333.669386) (xy 103.35387 -333.448914) (xy 102.658164 -333.448914)
					(xy 102.658164 -333.575914) (xy 103.11384 -333.575914)
				)
			)
		)
	)
	(footprint ""
		(layer "F.Cu")
		(at 58.578496 -70.78599)
		(property "Reference" "D72"
			(at -31.785306 50.178462 90)
			(unlocked yes)
			(layer "F.SilkS")
			(effects
				(font
					(size 0.635 0.4064)
					(thickness 0.1524)
				)
				(justify left)
			)
		)
		(property "Value" ""
			(at 0 0 0)
			(layer "F.Fab")
			(effects
				(font
					(size 1.27 1.27)
				)
			)
		)
		(duplicate_pad_numbers_are_jumpers no)
		(fp_line
			(start -0.90678 0.4826)
			(end -0.90678 -0.4699)
			(stroke
				(width 0.1524)
				(type default)
			)
			(layer "F.SilkS")
		)
		(fp_line
			(start -0.89408 -0.4826)
			(end 0.90678 -0.4826)
			(stroke
				(width 0.1524)
				(type default)
			)
			(layer "F.SilkS")
		)
		(fp_line
			(start -0.79248 -0.4826)
			(end 1.03378 -0.4826)
			(stroke
				(width 0.1524)
				(type default)
			)
			(layer "F.SilkS")
		)
		(fp_line
			(start -0.64008 -0.4826)
			(end 1.16078 -0.4826)
			(stroke
				(width 0.1524)
				(type default)
			)
			(layer "F.SilkS")
		)
		(fp_line
			(start 0.90678 -0.4826)
			(end 0.90678 0.4826)
			(stroke
				(width 0.1524)
				(type default)
			)
			(layer "F.SilkS")
		)
		(fp_line
			(start 0.90678 0.4826)
			(end -0.90678 0.4826)
			(stroke
				(width 0.1524)
				(type default)
			)
			(layer "F.SilkS")
		)
		(fp_line
			(start 1.03378 -0.4826)
			(end 1.03378 0.4826)
			(stroke
				(width 0.1524)
				(type default)
			)
			(layer "F.SilkS")
		)
		(fp_line
			(start 1.03378 0.4826)
			(end -0.79248 0.4826)
			(stroke
				(width 0.1524)
				(type default)
			)
			(layer "F.SilkS")
		)
		(fp_line
			(start 1.16078 -0.4826)
			(end 1.16078 0.4826)
			(stroke
				(width 0.1524)
				(type default)
			)
			(layer "F.SilkS")
		)
		(fp_line
			(start 1.16078 0.4826)
			(end -0.64008 0.4826)
			(stroke
				(width 0.1524)
				(type default)
			)
			(layer "F.SilkS")
		)
		(fp_line
			(start -0.499872 -0.249936)
			(end 0.499872 -0.249936)
			(stroke
				(width 0.1)
				(type default)
			)
			(layer "F.Fab")
		)
		(fp_line
			(start -0.499872 0.249936)
			(end -0.499872 -0.249936)
			(stroke
				(width 0.1)
				(type default)
			)
			(layer "F.Fab")
		)
		(fp_line
			(start 0.499872 -0.249936)
			(end 0.499872 0.249936)
			(stroke
				(width 0.1)
				(type default)
			)
			(layer "F.Fab")
		)
		(fp_line
			(start 0.499872 0.249936)
			(end -0.499872 0.249936)
			(stroke
				(width 0.1)
				(type default)
			)
			(layer "F.Fab")
		)
		(pad "A" smd rect
			(at -0.47498 0)
			(size 0.6096 0.7112)
			(layers "F.Cu" "F.Mask" "F.Paste")
			(net "LED_RST_PLD_CPU1_DRAM_GH_N")
		)
		(pad "C" smd rect
			(at 0.47498 0)
			(size 0.6096 0.7112)
			(layers "F.Cu" "F.Mask" "F.Paste")
			(net "LED_RST_PLD_CPU1_DRAM_GH_N_D")
		)
	)
	(footprint ""
		(layer "F.Cu")
		(at 121.984008 -360.043222 90)
		(property "Reference" "PR1339"
			(at 0 0 90)
			(layer "F.SilkS")
			(hide yes)
			(effects
				(font
					(size 1.27 1.27)
				)
			)
		)
		(property "Value" ""
			(at 0 0 90)
			(layer "F.Fab")
			(effects
				(font
					(size 1.27 1.27)
				)
			)
		)
		(duplicate_pad_numbers_are_jumpers no)
		(fp_line
			(start 0.7874 -0.4064)
			(end 0.7874 0.4064)
			(stroke
				(width 0.1524)
				(type default)
			)
			(layer "F.SilkS")
		)
		(fp_line
			(start -0.7874 -0.4064)
			(end 0.7874 -0.4064)
			(stroke
				(width 0.1524)
				(type default)
			)
			(layer "F.SilkS")
		)
		(fp_line
			(start 0.7874 0.4064)
			(end -0.7874 0.4064)
			(stroke
				(width 0.1524)
				(type default)
			)
			(layer "F.SilkS")
		)
		(fp_line
			(start -0.7874 0.4064)
			(end -0.7874 -0.4064)
			(stroke
				(width 0.1524)
				(type default)
			)
			(layer "F.SilkS")
		)
		(fp_line
			(start -0.12065 -0.305054)
			(end -0.12065 -0.2794)
			(stroke
				(width 0.1)
				(type default)
			)
			(layer "F.Fab")
		)
		(fp_line
			(start -0.67945 -0.305054)
			(end -0.12065 -0.305054)
			(stroke
				(width 0.1)
				(type default)
			)
			(layer "F.Fab")
		)
		(fp_line
			(start 0.67945 -0.3048)
			(end 0.67945 0.3048)
			(stroke
				(width 0.1)
				(type default)
			)
			(layer "F.Fab")
		)
		(fp_line
			(start 0.12065 -0.3048)
			(end 0.67945 -0.3048)
			(stroke
				(width 0.1)
				(type default)
			)
			(layer "F.Fab")
		)
		(fp_line
			(start 0.12065 -0.2794)
			(end 0.12065 -0.3048)
			(stroke
				(width 0.1)
				(type default)
			)
			(layer "F.Fab")
		)
		(fp_line
			(start -0.12065 -0.2794)
			(end 0.12065 -0.2794)
			(stroke
				(width 0.1)
				(type default)
			)
			(layer "F.Fab")
		)
		(fp_line
			(start 0.120396 0.2794)
			(end -0.12065 0.2794)
			(stroke
				(width 0.1)
				(type default)
			)
			(layer "F.Fab")
		)
		(fp_line
			(start -0.12065 0.2794)
			(end -0.12065 0.3048)
			(stroke
				(width 0.1)
				(type default)
			)
			(layer "F.Fab")
		)
		(fp_line
			(start 0.67945 0.3048)
			(end 0.120396 0.3048)
			(stroke
				(width 0.1)
				(type default)
			)
			(layer "F.Fab")
		)
		(fp_line
			(start 0.120396 0.3048)
			(end 0.120396 0.2794)
			(stroke
				(width 0.1)
				(type default)
			)
			(layer "F.Fab")
		)
		(fp_line
			(start -0.12065 0.3048)
			(end -0.67945 0.3048)
			(stroke
				(width 0.1)
				(type default)
			)
			(layer "F.Fab")
		)
		(fp_line
			(start -0.67945 0.3048)
			(end -0.67945 -0.305054)
			(stroke
				(width 0.1)
				(type default)
			)
			(layer "F.Fab")
		)
		(pad "1" smd circle
			(at -0.40005 0 90)
			(size 0 0)
			(layers "F.Cu" "F.Mask" "F.Paste")
			(net "PVPP_HBM_CPU1_CS")
		)
		(pad "2" smd circle
			(at 0.40005 0 90)
			(size 0 0)
			(layers "F.Cu" "F.Mask" "F.Paste")
			(net "GND")
		)
	)
	(footprint ""
		(layer "F.Cu")
		(at 62.994032 -143.757904 180)
		(property "Reference" "PC452_P1_1"
			(at 0 0 180)
			(layer "F.SilkS")
			(hide yes)
			(effects
				(font
					(size 1.27 1.27)
				)
			)
		)
		(property "Value" ""
			(at 0 0 180)
			(layer "F.Fab")
			(effects
				(font
					(size 1.27 1.27)
				)
			)
		)
		(duplicate_pad_numbers_are_jumpers no)
		(fp_line
			(start 0.7874 0.4064)
			(end -0.7874 0.4064)
			(stroke
				(width 0.1524)
				(type default)
			)
			(layer "F.SilkS")
		)
		(fp_line
			(start 0.7874 -0.4064)
			(end 0.7874 0.4064)
			(stroke
				(width 0.1524)
				(type default)
			)
			(layer "F.SilkS")
		)
		(fp_line
			(start -0.7874 0.4064)
			(end -0.7874 -0.4064)
			(stroke
				(width 0.1524)
				(type default)
			)
			(layer "F.SilkS")
		)
		(fp_line
			(start -0.7874 -0.4064)
			(end 0.7874 -0.4064)
			(stroke
				(width 0.1524)
				(type default)
			)
			(layer "F.SilkS")
		)
		(fp_line
			(start 0.67945 0.3048)
			(end 0.120396 0.3048)
			(stroke
				(width 0.1)
				(type default)
			)
			(layer "F.Fab")
		)
		(fp_line
			(start 0.67945 -0.3048)
			(end 0.67945 0.3048)
			(stroke
				(width 0.1)
				(type default)
			)
			(layer "F.Fab")
		)
		(fp_line
			(start 0.12065 -0.2794)
			(end 0.12065 -0.3048)
			(stroke
				(width 0.1)
				(type default)
			)
			(layer "F.Fab")
		)
		(fp_line
			(start 0.12065 -0.3048)
			(end 0.67945 -0.3048)
			(stroke
				(width 0.1)
				(type default)
			)
			(layer "F.Fab")
		)
		(fp_line
			(start 0.120396 0.3048)
			(end 0.120396 0.2794)
			(stroke
				(width 0.1)
				(type default)
			)
			(layer "F.Fab")
		)
		(fp_line
			(start 0.120396 0.2794)
			(end -0.12065 0.2794)
			(stroke
				(width 0.1)
				(type default)
			)
			(layer "F.Fab")
		)
		(fp_line
			(start -0.12065 0.3048)
			(end -0.67945 0.3048)
			(stroke
				(width 0.1)
				(type default)
			)
			(layer "F.Fab")
		)
		(fp_line
			(start -0.12065 0.2794)
			(end -0.12065 0.3048)
			(stroke
				(width 0.1)
				(type default)
			)
			(layer "F.Fab")
		)
		(fp_line
			(start -0.12065 -0.2794)
			(end 0.12065 -0.2794)
			(stroke
				(width 0.1)
				(type default)
			)
			(layer "F.Fab")
		)
		(fp_line
			(start -0.12065 -0.305054)
			(end -0.12065 -0.2794)
			(stroke
				(width 0.1)
				(type default)
			)
			(layer "F.Fab")
		)
		(fp_line
			(start -0.67945 0.3048)
			(end -0.67945 -0.305054)
			(stroke
				(width 0.1)
				(type default)
			)
			(layer "F.Fab")
		)
		(fp_line
			(start -0.67945 -0.305054)
			(end -0.12065 -0.305054)
			(stroke
				(width 0.1)
				(type default)
			)
			(layer "F.Fab")
		)
		(pad "1" smd circle
			(at -0.40005 0 180)
			(size 0 0)
			(layers "F.Cu" "F.Mask" "F.Paste")
			(net "PVCCINFAON_CPU1")
		)
		(pad "2" smd circle
			(at 0.40005 0 180)
			(size 0 0)
			(layers "F.Cu" "F.Mask" "F.Paste")
			(net "GND")
		)
	)
	(footprint ""
		(layer "F.Cu")
		(at 317.396622 -61.331348 180)
		(property "Reference" "R1476"
			(at 0 0 180)
			(layer "F.SilkS")
			(hide yes)
			(effects
				(font
					(size 1.27 1.27)
				)
			)
		)
		(property "Value" ""
			(at 0 0 180)
			(layer "F.Fab")
			(effects
				(font
					(size 1.27 1.27)
				)
			)
		)
		(duplicate_pad_numbers_are_jumpers no)
		(fp_line
			(start 0.7874 0.4064)
			(end -0.7874 0.4064)
			(stroke
				(width 0.1524)
				(type default)
			)
			(layer "F.SilkS")
		)
		(fp_line
			(start 0.7874 -0.4064)
			(end 0.7874 0.4064)
			(stroke
				(width 0.1524)
				(type default)
			)
			(layer "F.SilkS")
		)
		(fp_line
			(start -0.7874 0.4064)
			(end -0.7874 -0.4064)
			(stroke
				(width 0.1524)
				(type default)
			)
			(layer "F.SilkS")
		)
		(fp_line
			(start -0.7874 -0.4064)
			(end 0.7874 -0.4064)
			(stroke
				(width 0.1524)
				(type default)
			)
			(layer "F.SilkS")
		)
		(fp_line
			(start 0.67945 0.3048)
			(end 0.120396 0.3048)
			(stroke
				(width 0.1)
				(type default)
			)
			(layer "F.Fab")
		)
		(fp_line
			(start 0.67945 -0.3048)
			(end 0.67945 0.3048)
			(stroke
				(width 0.1)
				(type default)
			)
			(layer "F.Fab")
		)
		(fp_line
			(start 0.12065 -0.2794)
			(end 0.12065 -0.3048)
			(stroke
				(width 0.1)
				(type default)
			)
			(layer "F.Fab")
		)
		(fp_line
			(start 0.12065 -0.3048)
			(end 0.67945 -0.3048)
			(stroke
				(width 0.1)
				(type default)
			)
			(layer "F.Fab")
		)
		(fp_line
			(start 0.120396 0.3048)
			(end 0.120396 0.2794)
			(stroke
				(width 0.1)
				(type default)
			)
			(layer "F.Fab")
		)
		(fp_line
			(start 0.120396 0.2794)
			(end -0.12065 0.2794)
			(stroke
				(width 0.1)
				(type default)
			)
			(layer "F.Fab")
		)
		(fp_line
			(start -0.12065 0.3048)
			(end -0.67945 0.3048)
			(stroke
				(width 0.1)
				(type default)
			)
			(layer "F.Fab")
		)
		(fp_line
			(start -0.12065 0.2794)
			(end -0.12065 0.3048)
			(stroke
				(width 0.1)
				(type default)
			)
			(layer "F.Fab")
		)
		(fp_line
			(start -0.12065 -0.2794)
			(end 0.12065 -0.2794)
			(stroke
				(width 0.1)
				(type default)
			)
			(layer "F.Fab")
		)
		(fp_line
			(start -0.12065 -0.305054)
			(end -0.12065 -0.2794)
			(stroke
				(width 0.1)
				(type default)
			)
			(layer "F.Fab")
		)
		(fp_line
			(start -0.67945 0.3048)
			(end -0.67945 -0.305054)
			(stroke
				(width 0.1)
				(type default)
			)
			(layer "F.Fab")
		)
		(fp_line
			(start -0.67945 -0.305054)
			(end -0.12065 -0.305054)
			(stroke
				(width 0.1)
				(type default)
			)
			(layer "F.Fab")
		)
		(pad "1" smd circle
			(at -0.40005 0 180)
			(size 0 0)
			(layers "F.Cu" "F.Mask" "F.Paste")
			(net "FM_PCH_RING_OSC_BYPASS_MGPIO_TE")
		)
		(pad "2" smd circle
			(at 0.40005 0 180)
			(size 0 0)
			(layers "F.Cu" "F.Mask" "F.Paste")
			(net "GND")
		)
	)
	(footprint ""
		(layer "F.Cu")
		(at 265.674348 -258.091686)
		(property "Reference" "J8"
			(at -3.683 -81.702148 0)
			(unlocked yes)
			(layer "F.SilkS")
			(effects
				(font
					(size 0.7874 0.5842)
					(thickness 0.1524)
				)
				(justify left)
			)
		)
		(property "Value" ""
			(at 0 0 0)
			(layer "F.Fab")
			(effects
				(font
					(size 1.27 1.27)
				)
			)
		)
		(duplicate_pad_numbers_are_jumpers no)
		(fp_line
			(start -3.24993 -81.000092)
			(end -3.24993 72.041258)
			(stroke
				(width 0.1524)
				(type default)
			)
			(layer "F.SilkS")
		)
		(fp_line
			(start -3.24993 77.697838)
			(end -3.24993 81.000092)
			(stroke
				(width 0.1524)
				(type default)
			)
			(layer "F.SilkS")
		)
		(fp_line
			(start -3.24993 81.000092)
			(end 3.24993 81.000092)
			(stroke
				(width 0.1524)
				(type default)
			)
			(layer "F.SilkS")
		)
		(fp_line
			(start 3.24993 -81.000092)
			(end -3.24993 -81.000092)
			(stroke
				(width 0.1524)
				(type default)
			)
			(layer "F.SilkS")
		)
		(fp_line
			(start 3.24993 -72.00011)
			(end -3.24993 -72.00011)
			(stroke
				(width 0.1524)
				(type default)
			)
			(layer "F.SilkS")
		)
		(fp_line
			(start 3.24993 72.00011)
			(end -3.24993 72.00011)
			(stroke
				(width 0.1524)
				(type default)
			)
			(layer "F.SilkS")
		)
		(fp_line
			(start 3.24993 75.201018)
			(end 3.24993 -81.000092)
			(stroke
				(width 0.1524)
				(type default)
			)
			(layer "F.SilkS")
		)
		(fp_line
			(start 3.24993 81.000092)
			(end 3.24993 80.357218)
			(stroke
				(width 0.1524)
				(type default)
			)
			(layer "F.SilkS")
		)
		(fp_poly
			(pts
				(xy -4.184396 -63.831978) (xy -3.295396 -63.387478) (xy -4.184396 -62.942978)
			)
			(stroke
				(width 0)
				(type default)
			)
			(fill yes)
			(layer "F.SilkS")
		)
		(fp_line
			(start -3.24993 -81.000092)
			(end -3.24993 81.000092)
			(stroke
				(width 0.1)
				(type default)
			)
			(layer "F.Fab")
		)
		(fp_line
			(start -3.24993 81.000092)
			(end 3.24993 81.000092)
			(stroke
				(width 0.1)
				(type default)
			)
			(layer "F.Fab")
		)
		(fp_line
			(start 3.24993 -81.000092)
			(end -3.24993 -81.000092)
			(stroke
				(width 0.1)
				(type default)
			)
			(layer "F.Fab")
		)
		(fp_line
			(start 3.24993 -72.00011)
			(end -3.24993 -72.00011)
			(stroke
				(width 0.1)
				(type default)
			)
			(layer "F.Fab")
		)
		(fp_line
			(start 3.24993 -71.000112)
			(end -3.24993 -71.000112)
			(stroke
				(width 0.1)
				(type default)
			)
			(layer "F.Fab")
		)
		(fp_line
			(start 3.24993 71.000112)
			(end -3.24993 71.000112)
			(stroke
				(width 0.1)
				(type default)
			)
			(layer "F.Fab")
		)
		(fp_line
			(start 3.24993 72.00011)
			(end -3.24993 72.00011)
			(stroke
				(width 0.1)
				(type default)
			)
			(layer "F.Fab")
		)
		(fp_line
			(start 3.24993 81.000092)
			(end 3.24993 -81.000092)
			(stroke
				(width 0.1)
				(type default)
			)
			(layer "F.Fab")
		)
		(fp_poly
			(pts
				(xy -4.445 -63.832994) (xy -4.445 -62.816994) (xy -3.429 -63.324994)
			)
			(stroke
				(width 0)
				(type default)
			)
			(fill yes)
			(layer "F.Fab")
		)
		(pad "1" smd rect
			(at -2.050034 -63.324994 270)
			(size 0.519938 1.4986)
			(layers "F.Cu" "F.Mask" "F.Paste")
			(net "P12V_S3_AUX_CPU0_NVDIMM")
		)
		(pad "2" smd rect
			(at -2.050034 -62.47511 270)
			(size 0.519938 1.4986)
			(layers "F.Cu" "F.Mask" "F.Paste")
			(net "TP_CHD_CPU0_DIMM2_FRU_0")
		)
		(pad "3" smd rect
			(at -2.050034 -61.624972 270)
			(size 0.519938 1.4986)
			(layers "F.Cu" "F.Mask" "F.Paste")
			(net "P3V3_AUX")
		)
		(pad "4" smd rect
			(at -2.050034 -60.775088 270)
			(size 0.519938 1.4986)
			(layers "F.Cu" "F.Mask" "F.Paste")
			(net "I3C_SPD_DDRABCD_CPU0_LVC1_SCL_7")
		)
		(pad "5" smd rect
			(at -2.050034 -59.92495 270)
			(size 0.519938 1.4986)
			(layers "F.Cu" "F.Mask" "F.Paste")
			(net "I3C_SPD_DDRABCD_CPU0_LVC1_SDA")
		)
		(pad "6" smd rect
			(at -2.050034 -59.075066 270)
			(size 0.519938 1.4986)
			(layers "F.Cu" "F.Mask" "F.Paste")
			(net "GND")
		)
		(pad "7" smd rect
			(at -2.050034 -58.224928 270)
			(size 0.519938 1.4986)
			(layers "F.Cu" "F.Mask" "F.Paste")
			(net "M_D_CPU0_SA_DQ<0>")
		)
		(pad "8" smd rect
			(at -2.050034 -57.375044 270)
			(size 0.519938 1.4986)
			(layers "F.Cu" "F.Mask" "F.Paste")
			(net "GND")
		)
		(pad "9" smd rect
			(at -2.050034 -56.524906 270)
			(size 0.519938 1.4986)
			(layers "F.Cu" "F.Mask" "F.Paste")
			(net "M_D_CPU0_SA_DQ<1>")
		)
		(pad "10" smd rect
			(at -2.050034 -55.675022 270)
			(size 0.519938 1.4986)
			(layers "F.Cu" "F.Mask" "F.Paste")
			(net "GND")
		)
		(pad "11" smd rect
			(at -2.050034 -54.824884 270)
			(size 0.519938 1.4986)
			(layers "F.Cu" "F.Mask" "F.Paste")
			(net "M_D_CPU0_SA_DQS_DP<0>")
		)
		(pad "12" smd rect
			(at -2.050034 -53.975 270)
			(size 0.519938 1.4986)
			(layers "F.Cu" "F.Mask" "F.Paste")
			(net "M_D_CPU0_SA_DQS_DN<0>")
		)
		(pad "13" smd rect
			(at -2.050034 -53.125116 270)
			(size 0.519938 1.4986)
			(layers "F.Cu" "F.Mask" "F.Paste")
			(net "GND")
		)
		(pad "14" smd rect
			(at -2.050034 -52.274978 270)
			(size 0.519938 1.4986)
			(layers "F.Cu" "F.Mask" "F.Paste")
			(net "M_D_CPU0_SA_DQ<4>")
		)
		(pad "15" smd rect
			(at -2.050034 -51.425094 270)
			(size 0.519938 1.4986)
			(layers "F.Cu" "F.Mask" "F.Paste")
			(net "GND")
		)
		(pad "16" smd rect
			(at -2.050034 -50.574956 270)
			(size 0.519938 1.4986)
			(layers "F.Cu" "F.Mask" "F.Paste")
			(net "M_D_CPU0_SA_DQ<5>")
		)
		(pad "17" smd rect
			(at -2.050034 -49.725072 270)
			(size 0.519938 1.4986)
			(layers "F.Cu" "F.Mask" "F.Paste")
			(net "GND")
		)
		(pad "18" smd rect
			(at -2.050034 -48.874934 270)
			(size 0.519938 1.4986)
			(layers "F.Cu" "F.Mask" "F.Paste")
			(net "M_D_CPU0_SA_DQ<8>")
		)
		(pad "19" smd rect
			(at -2.050034 -48.02505 270)
			(size 0.519938 1.4986)
			(layers "F.Cu" "F.Mask" "F.Paste")
			(net "GND")
		)
		(pad "20" smd rect
			(at -2.050034 -47.174912 270)
			(size 0.519938 1.4986)
			(layers "F.Cu" "F.Mask" "F.Paste")
			(net "M_D_CPU0_SA_DQ<9>")
		)
		(pad "21" smd rect
			(at -2.050034 -46.325028 270)
			(size 0.519938 1.4986)
			(layers "F.Cu" "F.Mask" "F.Paste")
			(net "GND")
		)
		(pad "22" smd rect
			(at -2.050034 -45.47489 270)
			(size 0.519938 1.4986)
			(layers "F.Cu" "F.Mask" "F.Paste")
			(net "M_D_CPU0_SA_DQS_DP<1>")
		)
		(pad "23" smd rect
			(at -2.050034 -44.625006 270)
			(size 0.519938 1.4986)
			(layers "F.Cu" "F.Mask" "F.Paste")
			(net "M_D_CPU0_SA_DQS_DN<1>")
		)
		(pad "24" smd rect
			(at -2.050034 -43.775122 270)
			(size 0.519938 1.4986)
			(layers "F.Cu" "F.Mask" "F.Paste")
			(net "GND")
		)
		(pad "25" smd rect
			(at -2.050034 -42.924984 270)
			(size 0.519938 1.4986)
			(layers "F.Cu" "F.Mask" "F.Paste")
			(net "M_D_CPU0_SA_DQ<12>")
		)
		(pad "26" smd rect
			(at -2.050034 -42.0751 270)
			(size 0.519938 1.4986)
			(layers "F.Cu" "F.Mask" "F.Paste")
			(net "GND")
		)
		(pad "27" smd rect
			(at -2.050034 -41.224962 270)
			(size 0.519938 1.4986)
			(layers "F.Cu" "F.Mask" "F.Paste")
			(net "M_D_CPU0_SA_DQ<13>")
		)
		(pad "28" smd rect
			(at -2.050034 -40.375078 270)
			(size 0.519938 1.4986)
			(layers "F.Cu" "F.Mask" "F.Paste")
			(net "GND")
		)
		(pad "29" smd rect
			(at -2.050034 -39.52494 270)
			(size 0.519938 1.4986)
			(layers "F.Cu" "F.Mask" "F.Paste")
			(net "M_D_CPU0_SA_DQ<16>")
		)
		(pad "30" smd rect
			(at -2.050034 -38.675056 270)
			(size 0.519938 1.4986)
			(layers "F.Cu" "F.Mask" "F.Paste")
			(net "GND")
		)
		(pad "31" smd rect
			(at -2.050034 -37.824918 270)
			(size 0.519938 1.4986)
			(layers "F.Cu" "F.Mask" "F.Paste")
			(net "M_D_CPU0_SA_DQ<17>")
		)
		(pad "32" smd rect
			(at -2.050034 -36.975034 270)
			(size 0.519938 1.4986)
			(layers "F.Cu" "F.Mask" "F.Paste")
			(net "GND")
		)
		(pad "33" smd rect
			(at -2.050034 -36.124896 270)
			(size 0.519938 1.4986)
			(layers "F.Cu" "F.Mask" "F.Paste")
			(net "M_D_CPU0_SA_DQS_DP<2>")
		)
		(pad "34" smd rect
			(at -2.050034 -35.275012 270)
			(size 0.519938 1.4986)
			(layers "F.Cu" "F.Mask" "F.Paste")
			(net "M_D_CPU0_SA_DQS_DN<2>")
		)
		(pad "35" smd rect
			(at -2.050034 -34.425128 270)
			(size 0.519938 1.4986)
			(layers "F.Cu" "F.Mask" "F.Paste")
			(net "GND")
		)
		(pad "36" smd rect
			(at -2.050034 -33.57499 270)
			(size 0.519938 1.4986)
			(layers "F.Cu" "F.Mask" "F.Paste")
			(net "M_D_CPU0_SA_DQ<20>")
		)
		(pad "37" smd rect
			(at -2.050034 -32.725106 270)
			(size 0.519938 1.4986)
			(layers "F.Cu" "F.Mask" "F.Paste")
			(net "GND")
		)
		(pad "38" smd rect
			(at -2.050034 -31.874968 270)
			(size 0.519938 1.4986)
			(layers "F.Cu" "F.Mask" "F.Paste")
			(net "M_D_CPU0_SA_DQ<21>")
		)
		(pad "39" smd rect
			(at -2.050034 -31.025084 270)
			(size 0.519938 1.4986)
			(layers "F.Cu" "F.Mask" "F.Paste")
			(net "GND")
		)
		(pad "40" smd rect
			(at -2.050034 -30.174946 270)
			(size 0.519938 1.4986)
			(layers "F.Cu" "F.Mask" "F.Paste")
			(net "M_D_CPU0_SA_DQ<24>")
		)
		(pad "41" smd rect
			(at -2.050034 -29.325062 270)
			(size 0.519938 1.4986)
			(layers "F.Cu" "F.Mask" "F.Paste")
			(net "GND")
		)
		(pad "42" smd rect
			(at -2.050034 -28.474924 270)
			(size 0.519938 1.4986)
			(layers "F.Cu" "F.Mask" "F.Paste")
			(net "M_D_CPU0_SA_DQ<25>")
		)
		(pad "43" smd rect
			(at -2.050034 -27.62504 270)
			(size 0.519938 1.4986)
			(layers "F.Cu" "F.Mask" "F.Paste")
			(net "GND")
		)
		(pad "44" smd rect
			(at -2.050034 -26.774902 270)
			(size 0.519938 1.4986)
			(layers "F.Cu" "F.Mask" "F.Paste")
			(net "M_D_CPU0_SA_DQS_DP<3>")
		)
		(pad "45" smd rect
			(at -2.050034 -25.925018 270)
			(size 0.519938 1.4986)
			(layers "F.Cu" "F.Mask" "F.Paste")
			(net "M_D_CPU0_SA_DQS_DN<3>")
		)
		(pad "46" smd rect
			(at -2.050034 -25.07488 270)
			(size 0.519938 1.4986)
			(layers "F.Cu" "F.Mask" "F.Paste")
			(net "GND")
		)
		(pad "47" smd rect
			(at -2.050034 -24.224996 270)
			(size 0.519938 1.4986)
			(layers "F.Cu" "F.Mask" "F.Paste")
			(net "M_D_CPU0_SA_DQ<28>")
		)
		(pad "48" smd rect
			(at -2.050034 -23.375112 270)
			(size 0.519938 1.4986)
			(layers "F.Cu" "F.Mask" "F.Paste")
			(net "GND")
		)
		(pad "49" smd rect
			(at -2.050034 -22.524974 270)
			(size 0.519938 1.4986)
			(layers "F.Cu" "F.Mask" "F.Paste")
			(net "M_D_CPU0_SA_DQ<29>")
		)
		(pad "50" smd rect
			(at -2.050034 -21.67509 270)
			(size 0.519938 1.4986)
			(layers "F.Cu" "F.Mask" "F.Paste")
			(net "GND")
		)
		(pad "51" smd rect
			(at -2.050034 -20.824952 270)
			(size 0.519938 1.4986)
			(layers "F.Cu" "F.Mask" "F.Paste")
			(net "M_D_CPU0_SA_CB<0>")
		)
		(pad "52" smd rect
			(at -2.050034 -19.975068 270)
			(size 0.519938 1.4986)
			(layers "F.Cu" "F.Mask" "F.Paste")
			(net "GND")
		)
		(pad "53" smd rect
			(at -2.050034 -19.12493 270)
			(size 0.519938 1.4986)
			(layers "F.Cu" "F.Mask" "F.Paste")
			(net "M_D_CPU0_SA_CB<1>")
		)
		(pad "54" smd rect
			(at -2.050034 -18.275046 270)
			(size 0.519938 1.4986)
			(layers "F.Cu" "F.Mask" "F.Paste")
			(net "GND")
		)
		(pad "55" smd rect
			(at -2.050034 -17.424908 270)
			(size 0.519938 1.4986)
			(layers "F.Cu" "F.Mask" "F.Paste")
			(net "M_D_CPU0_SA_DQS_DP<4>")
		)
		(pad "56" smd rect
			(at -2.050034 -16.575024 270)
			(size 0.519938 1.4986)
			(layers "F.Cu" "F.Mask" "F.Paste")
			(net "M_D_CPU0_SA_DQS_DN<4>")
		)
		(pad "57" smd rect
			(at -2.050034 -15.724886 270)
			(size 0.519938 1.4986)
			(layers "F.Cu" "F.Mask" "F.Paste")
			(net "GND")
		)
		(pad "58" smd rect
			(at -2.050034 -14.875002 270)
			(size 0.519938 1.4986)
			(layers "F.Cu" "F.Mask" "F.Paste")
			(net "M_D_CPU0_SA_CB<4>")
		)
		(pad "59" smd rect
			(at -2.050034 -14.025118 270)
			(size 0.519938 1.4986)
			(layers "F.Cu" "F.Mask" "F.Paste")
			(net "GND")
		)
		(pad "60" smd rect
			(at -2.050034 -13.17498 270)
			(size 0.519938 1.4986)
			(layers "F.Cu" "F.Mask" "F.Paste")
			(net "M_D_CPU0_SA_CB<5>")
		)
		(pad "61" smd rect
			(at -2.050034 -12.325096 270)
			(size 0.519938 1.4986)
			(layers "F.Cu" "F.Mask" "F.Paste")
			(net "GND")
		)
		(pad "62" smd rect
			(at -2.050034 -11.474958 270)
			(size 0.519938 1.4986)
			(layers "F.Cu" "F.Mask" "F.Paste")
			(net "M_D_CPU0_ALERT_N")
		)
		(pad "63" smd rect
			(at -2.050034 -10.625074 270)
			(size 0.519938 1.4986)
			(layers "F.Cu" "F.Mask" "F.Paste")
			(net "GND")
		)
		(pad "64" smd rect
			(at -2.050034 -9.774936 270)
			(size 0.519938 1.4986)
			(layers "F.Cu" "F.Mask" "F.Paste")
			(net "M_D_CPU0_SA_CS_N<2>")
		)
		(pad "65" smd rect
			(at -2.050034 -8.925052 270)
			(size 0.519938 1.4986)
			(layers "F.Cu" "F.Mask" "F.Paste")
			(net "GND")
		)
		(pad "66" smd rect
			(at -2.050034 -8.074914 270)
			(size 0.519938 1.4986)
			(layers "F.Cu" "F.Mask" "F.Paste")
			(net "M_D_CPU0_SA_CA<0>")
		)
		(pad "67" smd rect
			(at -2.050034 -7.22503 270)
			(size 0.519938 1.4986)
			(layers "F.Cu" "F.Mask" "F.Paste")
			(net "GND")
		)
		(pad "68" smd rect
			(at -2.050034 -6.374892 270)
			(size 0.519938 1.4986)
			(layers "F.Cu" "F.Mask" "F.Paste")
			(net "M_D_CPU0_SA_CA<2>")
		)
		(pad "69" smd rect
			(at -2.050034 -5.525008 270)
			(size 0.519938 1.4986)
			(layers "F.Cu" "F.Mask" "F.Paste")
			(net "GND")
		)
		(pad "70" smd rect
			(at -2.050034 -4.675124 270)
			(size 0.519938 1.4986)
			(layers "F.Cu" "F.Mask" "F.Paste")
			(net "M_D_CPU0_SA_CA<4>")
		)
		(pad "71" smd rect
			(at -2.050034 -3.824986 270)
			(size 0.519938 1.4986)
			(layers "F.Cu" "F.Mask" "F.Paste")
			(net "GND")
		)
		(pad "72" smd rect
			(at -2.050034 -2.975102 270)
			(size 0.519938 1.4986)
			(layers "F.Cu" "F.Mask" "F.Paste")
			(net "M_D_CPU0_SA_CA<6>")
		)
		(pad "73" smd rect
			(at -2.050034 -2.124964 270)
			(size 0.519938 1.4986)
			(layers "F.Cu" "F.Mask" "F.Paste")
			(net "GND")
		)
		(pad "74" smd rect
			(at -2.050034 -1.27508 270)
			(size 0.519938 1.4986)
			(layers "F.Cu" "F.Mask" "F.Paste")
			(net "M_D_CPU0_SA_PAR")
		)
		(pad "75" smd rect
			(at -2.050034 -0.424942 270)
			(size 0.519938 1.4986)
			(layers "F.Cu" "F.Mask" "F.Paste")
			(net "GND")
		)
		(pad "76" smd rect
			(at -2.050034 5.525008 270)
			(size 0.519938 1.4986)
			(layers "F.Cu" "F.Mask" "F.Paste")
			(net "M_D_CPU0_SB_CA<0>")
		)
		(pad "77" smd rect
			(at -2.050034 6.374892 270)
			(size 0.519938 1.4986)
			(layers "F.Cu" "F.Mask" "F.Paste")
			(net "GND")
		)
		(pad "78" smd rect
			(at -2.050034 7.22503 270)
			(size 0.519938 1.4986)
			(layers "F.Cu" "F.Mask" "F.Paste")
			(net "M_D_CPU0_SB_CA<2>")
		)
		(pad "79" smd rect
			(at -2.050034 8.074914 270)
			(size 0.519938 1.4986)
			(layers "F.Cu" "F.Mask" "F.Paste")
			(net "GND")
		)
		(pad "80" smd rect
			(at -2.050034 8.925052 270)
			(size 0.519938 1.4986)
			(layers "F.Cu" "F.Mask" "F.Paste")
			(net "M_D_CPU0_SB_CA<4>")
		)
		(pad "81" smd rect
			(at -2.050034 9.774936 270)
			(size 0.519938 1.4986)
			(layers "F.Cu" "F.Mask" "F.Paste")
			(net "GND")
		)
		(pad "82" smd rect
			(at -2.050034 10.625074 270)
			(size 0.519938 1.4986)
			(layers "F.Cu" "F.Mask" "F.Paste")
			(net "M_D_CPU0_SB_CA<6>")
		)
		(pad "83" smd rect
			(at -2.050034 11.474958 270)
			(size 0.519938 1.4986)
			(layers "F.Cu" "F.Mask" "F.Paste")
			(net "GND")
		)
		(pad "84" smd rect
			(at -2.050034 12.325096 270)
			(size 0.519938 1.4986)
			(layers "F.Cu" "F.Mask" "F.Paste")
			(net "M_D_CPU0_SB_CS_N<2>")
		)
		(pad "85" smd rect
			(at -2.050034 13.17498 270)
			(size 0.519938 1.4986)
			(layers "F.Cu" "F.Mask" "F.Paste")
			(net "GND")
		)
		(pad "86" smd rect
			(at -2.050034 14.025118 270)
			(size 0.519938 1.4986)
			(layers "F.Cu" "F.Mask" "F.Paste")
			(net "M_D_CPU0_SA_RSP<1>")
		)
		(pad "87" smd rect
			(at -2.050034 14.875002 270)
			(size 0.519938 1.4986)
			(layers "F.Cu" "F.Mask" "F.Paste")
			(net "M_D_CPU0_SB_RSP<1>")
		)
		(pad "88" smd rect
			(at -2.050034 15.724886 270)
			(size 0.519938 1.4986)
			(layers "F.Cu" "F.Mask" "F.Paste")
			(net "GND")
		)
		(pad "89" smd rect
			(at -2.050034 16.575024 270)
			(size 0.519938 1.4986)
			(layers "F.Cu" "F.Mask" "F.Paste")
			(net "M_D_CPU0_SB_CB<4>")
		)
		(pad "90" smd rect
			(at -2.050034 17.424908 270)
			(size 0.519938 1.4986)
			(layers "F.Cu" "F.Mask" "F.Paste")
			(net "GND")
		)
		(pad "91" smd rect
			(at -2.050034 18.275046 270)
			(size 0.519938 1.4986)
			(layers "F.Cu" "F.Mask" "F.Paste")
			(net "M_D_CPU0_SB_CB<5>")
		)
		(pad "92" smd rect
			(at -2.050034 19.12493 270)
			(size 0.519938 1.4986)
			(layers "F.Cu" "F.Mask" "F.Paste")
			(net "GND")
		)
		(pad "93" smd rect
			(at -2.050034 19.975068 270)
			(size 0.519938 1.4986)
			(layers "F.Cu" "F.Mask" "F.Paste")
			(net "M_D_CPU0_SB_DQS_DP<9>")
		)
		(pad "94" smd rect
			(at -2.050034 20.824952 270)
			(size 0.519938 1.4986)
			(layers "F.Cu" "F.Mask" "F.Paste")
			(net "M_D_CPU0_SB_DQS_DN<9>")
		)
		(pad "95" smd rect
			(at -2.050034 21.67509 270)
			(size 0.519938 1.4986)
			(layers "F.Cu" "F.Mask" "F.Paste")
			(net "GND")
		)
		(pad "96" smd rect
			(at -2.050034 22.524974 270)
			(size 0.519938 1.4986)
			(layers "F.Cu" "F.Mask" "F.Paste")
			(net "M_D_CPU0_SB_CB<0>")
		)
		(pad "97" smd rect
			(at -2.050034 23.375112 270)
			(size 0.519938 1.4986)
			(layers "F.Cu" "F.Mask" "F.Paste")
			(net "GND")
		)
		(pad "98" smd rect
			(at -2.050034 24.224996 270)
			(size 0.519938 1.4986)
			(layers "F.Cu" "F.Mask" "F.Paste")
			(net "M_D_CPU0_SB_CB<1>")
		)
		(pad "99" smd rect
			(at -2.050034 25.07488 270)
			(size 0.519938 1.4986)
			(layers "F.Cu" "F.Mask" "F.Paste")
			(net "GND")
		)
		(pad "100" smd rect
			(at -2.050034 25.925018 270)
			(size 0.519938 1.4986)
			(layers "F.Cu" "F.Mask" "F.Paste")
			(net "M_D_CPU0_SB_DQ<0>")
		)
		(pad "101" smd rect
			(at -2.050034 26.774902 270)
			(size 0.519938 1.4986)
			(layers "F.Cu" "F.Mask" "F.Paste")
			(net "GND")
		)
		(pad "102" smd rect
			(at -2.050034 27.62504 270)
			(size 0.519938 1.4986)
			(layers "F.Cu" "F.Mask" "F.Paste")
			(net "M_D_CPU0_SB_DQ<1>")
		)
		(pad "103" smd rect
			(at -2.050034 28.474924 270)
			(size 0.519938 1.4986)
			(layers "F.Cu" "F.Mask" "F.Paste")
			(net "GND")
		)
		(pad "104" smd rect
			(at -2.050034 29.325062 270)
			(size 0.519938 1.4986)
			(layers "F.Cu" "F.Mask" "F.Paste")
			(net "M_D_CPU0_SB_DQS_DP<0>")
		)
		(pad "105" smd rect
			(at -2.050034 30.174946 270)
			(size 0.519938 1.4986)
			(layers "F.Cu" "F.Mask" "F.Paste")
			(net "M_D_CPU0_SB_DQS_DN<0>")
		)
		(pad "106" smd rect
			(at -2.050034 31.025084 270)
			(size 0.519938 1.4986)
			(layers "F.Cu" "F.Mask" "F.Paste")
			(net "GND")
		)
		(pad "107" smd rect
			(at -2.050034 31.874968 270)
			(size 0.519938 1.4986)
			(layers "F.Cu" "F.Mask" "F.Paste")
			(net "M_D_CPU0_SB_DQ<4>")
		)
		(pad "108" smd rect
			(at -2.050034 32.725106 270)
			(size 0.519938 1.4986)
			(layers "F.Cu" "F.Mask" "F.Paste")
			(net "GND")
		)
		(pad "109" smd rect
			(at -2.050034 33.57499 270)
			(size 0.519938 1.4986)
			(layers "F.Cu" "F.Mask" "F.Paste")
			(net "M_D_CPU0_SB_DQ<5>")
		)
		(pad "110" smd rect
			(at -2.050034 34.425128 270)
			(size 0.519938 1.4986)
			(layers "F.Cu" "F.Mask" "F.Paste")
			(net "GND")
		)
		(pad "111" smd rect
			(at -2.050034 35.275012 270)
			(size 0.519938 1.4986)
			(layers "F.Cu" "F.Mask" "F.Paste")
			(net "M_D_CPU0_SB_DQ<8>")
		)
		(pad "112" smd rect
			(at -2.050034 36.124896 270)
			(size 0.519938 1.4986)
			(layers "F.Cu" "F.Mask" "F.Paste")
			(net "GND")
		)
		(pad "113" smd rect
			(at -2.050034 36.975034 270)
			(size 0.519938 1.4986)
			(layers "F.Cu" "F.Mask" "F.Paste")
			(net "M_D_CPU0_SB_DQ<9>")
		)
		(pad "114" smd rect
			(at -2.050034 37.824918 270)
			(size 0.519938 1.4986)
			(layers "F.Cu" "F.Mask" "F.Paste")
			(net "GND")
		)
		(pad "115" smd rect
			(at -2.050034 38.675056 270)
			(size 0.519938 1.4986)
			(layers "F.Cu" "F.Mask" "F.Paste")
			(net "M_D_CPU0_SB_DQS_DP<1>")
		)
		(pad "116" smd rect
			(at -2.050034 39.52494 270)
			(size 0.519938 1.4986)
			(layers "F.Cu" "F.Mask" "F.Paste")
			(net "M_D_CPU0_SB_DQS_DN<1>")
		)
		(pad "117" smd rect
			(at -2.050034 40.375078 270)
			(size 0.519938 1.4986)
			(layers "F.Cu" "F.Mask" "F.Paste")
			(net "GND")
		)
		(pad "118" smd rect
			(at -2.050034 41.224962 270)
			(size 0.519938 1.4986)
			(layers "F.Cu" "F.Mask" "F.Paste")
			(net "M_D_CPU0_SB_DQ<12>")
		)
		(pad "119" smd rect
			(at -2.050034 42.0751 270)
			(size 0.519938 1.4986)
			(layers "F.Cu" "F.Mask" "F.Paste")
			(net "GND")
		)
		(pad "120" smd rect
			(at -2.050034 42.924984 270)
			(size 0.519938 1.4986)
			(layers "F.Cu" "F.Mask" "F.Paste")
			(net "M_D_CPU0_SB_DQ<13>")
		)
		(pad "121" smd rect
			(at -2.050034 43.775122 270)
			(size 0.519938 1.4986)
			(layers "F.Cu" "F.Mask" "F.Paste")
			(net "GND")
		)
		(pad "122" smd rect
			(at -2.050034 44.625006 270)
			(size 0.519938 1.4986)
			(layers "F.Cu" "F.Mask" "F.Paste")
			(net "M_D_CPU0_SB_DQ<16>")
		)
		(pad "123" smd rect
			(at -2.050034 45.47489 270)
			(size 0.519938 1.4986)
			(layers "F.Cu" "F.Mask" "F.Paste")
			(net "GND")
		)
		(pad "124" smd rect
			(at -2.050034 46.325028 270)
			(size 0.519938 1.4986)
			(layers "F.Cu" "F.Mask" "F.Paste")
			(net "M_D_CPU0_SB_DQ<17>")
		)
		(pad "125" smd rect
			(at -2.050034 47.174912 270)
			(size 0.519938 1.4986)
			(layers "F.Cu" "F.Mask" "F.Paste")
			(net "GND")
		)
		(pad "126" smd rect
			(at -2.050034 48.02505 270)
			(size 0.519938 1.4986)
			(layers "F.Cu" "F.Mask" "F.Paste")
			(net "M_D_CPU0_SB_DQS_DP<2>")
		)
		(pad "127" smd rect
			(at -2.050034 48.874934 270)
			(size 0.519938 1.4986)
			(layers "F.Cu" "F.Mask" "F.Paste")
			(net "M_D_CPU0_SB_DQS_DN<2>")
		)
		(pad "128" smd rect
			(at -2.050034 49.725072 270)
			(size 0.519938 1.4986)
			(layers "F.Cu" "F.Mask" "F.Paste")
			(net "GND")
		)
		(pad "129" smd rect
			(at -2.050034 50.574956 270)
			(size 0.519938 1.4986)
			(layers "F.Cu" "F.Mask" "F.Paste")
			(net "M_D_CPU0_SB_DQ<20>")
		)
		(pad "130" smd rect
			(at -2.050034 51.425094 270)
			(size 0.519938 1.4986)
			(layers "F.Cu" "F.Mask" "F.Paste")
			(net "GND")
		)
		(pad "131" smd rect
			(at -2.050034 52.274978 270)
			(size 0.519938 1.4986)
			(layers "F.Cu" "F.Mask" "F.Paste")
			(net "M_D_CPU0_SB_DQ<21>")
		)
		(pad "132" smd rect
			(at -2.050034 53.125116 270)
			(size 0.519938 1.4986)
			(layers "F.Cu" "F.Mask" "F.Paste")
			(net "GND")
		)
		(pad "133" smd rect
			(at -2.050034 53.975 270)
			(size 0.519938 1.4986)
			(layers "F.Cu" "F.Mask" "F.Paste")
			(net "M_D_CPU0_SB_DQ<24>")
		)
		(pad "134" smd rect
			(at -2.050034 54.824884 270)
			(size 0.519938 1.4986)
			(layers "F.Cu" "F.Mask" "F.Paste")
			(net "GND")
		)
		(pad "135" smd rect
			(at -2.050034 55.675022 270)
			(size 0.519938 1.4986)
			(layers "F.Cu" "F.Mask" "F.Paste")
			(net "M_D_CPU0_SB_DQ<25>")
		)
		(pad "136" smd rect
			(at -2.050034 56.524906 270)
			(size 0.519938 1.4986)
			(layers "F.Cu" "F.Mask" "F.Paste")
			(net "GND")
		)
		(pad "137" smd rect
			(at -2.050034 57.375044 270)
			(size 0.519938 1.4986)
			(layers "F.Cu" "F.Mask" "F.Paste")
			(net "M_D_CPU0_SB_DQS_DP<3>")
		)
		(pad "138" smd rect
			(at -2.050034 58.224928 270)
			(size 0.519938 1.4986)
			(layers "F.Cu" "F.Mask" "F.Paste")
			(net "M_D_CPU0_SB_DQS_DN<3>")
		)
		(pad "139" smd rect
			(at -2.050034 59.075066 270)
			(size 0.519938 1.4986)
			(layers "F.Cu" "F.Mask" "F.Paste")
			(net "GND")
		)
		(pad "140" smd rect
			(at -2.050034 59.92495 270)
			(size 0.519938 1.4986)
			(layers "F.Cu" "F.Mask" "F.Paste")
			(net "M_D_CPU0_SB_DQ<28>")
		)
		(pad "141" smd rect
			(at -2.050034 60.775088 270)
			(size 0.519938 1.4986)
			(layers "F.Cu" "F.Mask" "F.Paste")
			(net "GND")
		)
		(pad "142" smd rect
			(at -2.050034 61.624972 270)
			(size 0.519938 1.4986)
			(layers "F.Cu" "F.Mask" "F.Paste")
			(net "M_D_CPU0_SB_DQ<29>")
		)
		(pad "143" smd rect
			(at -2.050034 62.47511 270)
			(size 0.519938 1.4986)
			(layers "F.Cu" "F.Mask" "F.Paste")
			(net "GND")
		)
		(pad "144" smd rect
			(at -2.050034 63.324994 270)
			(size 0.519938 1.4986)
			(layers "F.Cu" "F.Mask" "F.Paste")
			(net "TP_CHD_CPU0_DIMM2_FRU_1")
		)
		(pad "145" smd rect
			(at 2.050034 -63.324994 270)
			(size 0.519938 1.4986)
			(layers "F.Cu" "F.Mask" "F.Paste")
			(net "P12V_S3_AUX_CPU0_NVDIMM")
		)
		(pad "146" smd rect
			(at 2.050034 -62.47511 270)
			(size 0.519938 1.4986)
			(layers "F.Cu" "F.Mask" "F.Paste")
			(net "P12V_S3_AUX_CPU0_NVDIMM")
		)
		(pad "147" smd rect
			(at 2.050034 -61.624972 270)
			(size 0.519938 1.4986)
			(layers "F.Cu" "F.Mask" "F.Paste")
			(net "PWRGD_CHD_CPU0_DIMM2")
		)
		(pad "148" smd rect
			(at 2.050034 -60.775088 270)
			(size 0.519938 1.4986)
			(layers "F.Cu" "F.Mask" "F.Paste")
			(net "PD_CHD_CPU0_DIMM2_SAA")
		)
		(pad "149" smd rect
			(at 2.050034 -59.92495 270)
			(size 0.519938 1.4986)
			(layers "F.Cu" "F.Mask" "F.Paste")
			(net "TP_CHD_CPU0_DIMM2_FRU_2")
		)
		(pad "150" smd rect
			(at 2.050034 -59.075066 270)
			(size 0.519938 1.4986)
			(layers "F.Cu" "F.Mask" "F.Paste")
			(net "TP_CHD_CPU0_DIMM2_FRU_3")
		)
		(pad "151" smd rect
			(at 2.050034 -58.224928 270)
			(size 0.519938 1.4986)
			(layers "F.Cu" "F.Mask" "F.Paste")
			(net "GND")
		)
		(pad "152" smd rect
			(at 2.050034 -57.375044 270)
			(size 0.519938 1.4986)
			(layers "F.Cu" "F.Mask" "F.Paste")
			(net "M_D_CPU0_SA_DQ<2>")
		)
		(pad "153" smd rect
			(at 2.050034 -56.524906 270)
			(size 0.519938 1.4986)
			(layers "F.Cu" "F.Mask" "F.Paste")
			(net "GND")
		)
		(pad "154" smd rect
			(at 2.050034 -55.675022 270)
			(size 0.519938 1.4986)
			(layers "F.Cu" "F.Mask" "F.Paste")
			(net "M_D_CPU0_SA_DQ<3>")
		)
		(pad "155" smd rect
			(at 2.050034 -54.824884 270)
			(size 0.519938 1.4986)
			(layers "F.Cu" "F.Mask" "F.Paste")
			(net "GND")
		)
		(pad "156" smd rect
			(at 2.050034 -53.975 270)
			(size 0.519938 1.4986)
			(layers "F.Cu" "F.Mask" "F.Paste")
			(net "M_D_CPU0_SA_DQS_DN<5>")
		)
		(pad "157" smd rect
			(at 2.050034 -53.125116 270)
			(size 0.519938 1.4986)
			(layers "F.Cu" "F.Mask" "F.Paste")
			(net "M_D_CPU0_SA_DQS_DP<5>")
		)
		(pad "158" smd rect
			(at 2.050034 -52.274978 270)
			(size 0.519938 1.4986)
			(layers "F.Cu" "F.Mask" "F.Paste")
			(net "GND")
		)
		(pad "159" smd rect
			(at 2.050034 -51.425094 270)
			(size 0.519938 1.4986)
			(layers "F.Cu" "F.Mask" "F.Paste")
			(net "M_D_CPU0_SA_DQ<6>")
		)
		(pad "160" smd rect
			(at 2.050034 -50.574956 270)
			(size 0.519938 1.4986)
			(layers "F.Cu" "F.Mask" "F.Paste")
			(net "GND")
		)
		(pad "161" smd rect
			(at 2.050034 -49.725072 270)
			(size 0.519938 1.4986)
			(layers "F.Cu" "F.Mask" "F.Paste")
			(net "M_D_CPU0_SA_DQ<7>")
		)
		(pad "162" smd rect
			(at 2.050034 -48.874934 270)
			(size 0.519938 1.4986)
			(layers "F.Cu" "F.Mask" "F.Paste")
			(net "GND")
		)
		(pad "163" smd rect
			(at 2.050034 -48.02505 270)
			(size 0.519938 1.4986)
			(layers "F.Cu" "F.Mask" "F.Paste")
			(net "M_D_CPU0_SA_DQ<10>")
		)
		(pad "164" smd rect
			(at 2.050034 -47.174912 270)
			(size 0.519938 1.4986)
			(layers "F.Cu" "F.Mask" "F.Paste")
			(net "GND")
		)
		(pad "165" smd rect
			(at 2.050034 -46.325028 270)
			(size 0.519938 1.4986)
			(layers "F.Cu" "F.Mask" "F.Paste")
			(net "M_D_CPU0_SA_DQ<11>")
		)
		(pad "166" smd rect
			(at 2.050034 -45.47489 270)
			(size 0.519938 1.4986)
			(layers "F.Cu" "F.Mask" "F.Paste")
			(net "GND")
		)
		(pad "167" smd rect
			(at 2.050034 -44.625006 270)
			(size 0.519938 1.4986)
			(layers "F.Cu" "F.Mask" "F.Paste")
			(net "M_D_CPU0_SA_DQS_DN<6>")
		)
		(pad "168" smd rect
			(at 2.050034 -43.775122 270)
			(size 0.519938 1.4986)
			(layers "F.Cu" "F.Mask" "F.Paste")
			(net "M_D_CPU0_SA_DQS_DP<6>")
		)
		(pad "169" smd rect
			(at 2.050034 -42.924984 270)
			(size 0.519938 1.4986)
			(layers "F.Cu" "F.Mask" "F.Paste")
			(net "GND")
		)
		(pad "170" smd rect
			(at 2.050034 -42.0751 270)
			(size 0.519938 1.4986)
			(layers "F.Cu" "F.Mask" "F.Paste")
			(net "M_D_CPU0_SA_DQ<14>")
		)
		(pad "171" smd rect
			(at 2.050034 -41.224962 270)
			(size 0.519938 1.4986)
			(layers "F.Cu" "F.Mask" "F.Paste")
			(net "GND")
		)
		(pad "172" smd rect
			(at 2.050034 -40.375078 270)
			(size 0.519938 1.4986)
			(layers "F.Cu" "F.Mask" "F.Paste")
			(net "M_D_CPU0_SA_DQ<15>")
		)
		(pad "173" smd rect
			(at 2.050034 -39.52494 270)
			(size 0.519938 1.4986)
			(layers "F.Cu" "F.Mask" "F.Paste")
			(net "GND")
		)
		(pad "174" smd rect
			(at 2.050034 -38.675056 270)
			(size 0.519938 1.4986)
			(layers "F.Cu" "F.Mask" "F.Paste")
			(net "M_D_CPU0_SA_DQ<18>")
		)
		(pad "175" smd rect
			(at 2.050034 -37.824918 270)
			(size 0.519938 1.4986)
			(layers "F.Cu" "F.Mask" "F.Paste")
			(net "GND")
		)
		(pad "176" smd rect
			(at 2.050034 -36.975034 270)
			(size 0.519938 1.4986)
			(layers "F.Cu" "F.Mask" "F.Paste")
			(net "M_D_CPU0_SA_DQ<19>")
		)
		(pad "177" smd rect
			(at 2.050034 -36.124896 270)
			(size 0.519938 1.4986)
			(layers "F.Cu" "F.Mask" "F.Paste")
			(net "GND")
		)
		(pad "178" smd rect
			(at 2.050034 -35.275012 270)
			(size 0.519938 1.4986)
			(layers "F.Cu" "F.Mask" "F.Paste")
			(net "M_D_CPU0_SA_DQS_DN<7>")
		)
		(pad "179" smd rect
			(at 2.050034 -34.425128 270)
			(size 0.519938 1.4986)
			(layers "F.Cu" "F.Mask" "F.Paste")
			(net "M_D_CPU0_SA_DQS_DP<7>")
		)
		(pad "180" smd rect
			(at 2.050034 -33.57499 270)
			(size 0.519938 1.4986)
			(layers "F.Cu" "F.Mask" "F.Paste")
			(net "GND")
		)
		(pad "181" smd rect
			(at 2.050034 -32.725106 270)
			(size 0.519938 1.4986)
			(layers "F.Cu" "F.Mask" "F.Paste")
			(net "M_D_CPU0_SA_DQ<22>")
		)
		(pad "182" smd rect
			(at 2.050034 -31.874968 270)
			(size 0.519938 1.4986)
			(layers "F.Cu" "F.Mask" "F.Paste")
			(net "GND")
		)
		(pad "183" smd rect
			(at 2.050034 -31.025084 270)
			(size 0.519938 1.4986)
			(layers "F.Cu" "F.Mask" "F.Paste")
			(net "M_D_CPU0_SA_DQ<23>")
		)
		(pad "184" smd rect
			(at 2.050034 -30.174946 270)
			(size 0.519938 1.4986)
			(layers "F.Cu" "F.Mask" "F.Paste")
			(net "GND")
		)
		(pad "185" smd rect
			(at 2.050034 -29.325062 270)
			(size 0.519938 1.4986)
			(layers "F.Cu" "F.Mask" "F.Paste")
			(net "M_D_CPU0_SA_DQ<26>")
		)
		(pad "186" smd rect
			(at 2.050034 -28.474924 270)
			(size 0.519938 1.4986)
			(layers "F.Cu" "F.Mask" "F.Paste")
			(net "GND")
		)
		(pad "187" smd rect
			(at 2.050034 -27.62504 270)
			(size 0.519938 1.4986)
			(layers "F.Cu" "F.Mask" "F.Paste")
			(net "M_D_CPU0_SA_DQ<27>")
		)
		(pad "188" smd rect
			(at 2.050034 -26.774902 270)
			(size 0.519938 1.4986)
			(layers "F.Cu" "F.Mask" "F.Paste")
			(net "GND")
		)
		(pad "189" smd rect
			(at 2.050034 -25.925018 270)
			(size 0.519938 1.4986)
			(layers "F.Cu" "F.Mask" "F.Paste")
			(net "M_D_CPU0_SA_DQS_DN<8>")
		)
		(pad "190" smd rect
			(at 2.050034 -25.07488 270)
			(size 0.519938 1.4986)
			(layers "F.Cu" "F.Mask" "F.Paste")
			(net "M_D_CPU0_SA_DQS_DP<8>")
		)
		(pad "191" smd rect
			(at 2.050034 -24.224996 270)
			(size 0.519938 1.4986)
			(layers "F.Cu" "F.Mask" "F.Paste")
			(net "GND")
		)
		(pad "192" smd rect
			(at 2.050034 -23.375112 270)
			(size 0.519938 1.4986)
			(layers "F.Cu" "F.Mask" "F.Paste")
			(net "M_D_CPU0_SA_DQ<30>")
		)
		(pad "193" smd rect
			(at 2.050034 -22.524974 270)
			(size 0.519938 1.4986)
			(layers "F.Cu" "F.Mask" "F.Paste")
			(net "GND")
		)
		(pad "194" smd rect
			(at 2.050034 -21.67509 270)
			(size 0.519938 1.4986)
			(layers "F.Cu" "F.Mask" "F.Paste")
			(net "M_D_CPU0_SA_DQ<31>")
		)
		(pad "195" smd rect
			(at 2.050034 -20.824952 270)
			(size 0.519938 1.4986)
			(layers "F.Cu" "F.Mask" "F.Paste")
			(net "GND")
		)
		(pad "196" smd rect
			(at 2.050034 -19.975068 270)
			(size 0.519938 1.4986)
			(layers "F.Cu" "F.Mask" "F.Paste")
			(net "M_D_CPU0_SA_CB<2>")
		)
		(pad "197" smd rect
			(at 2.050034 -19.12493 270)
			(size 0.519938 1.4986)
			(layers "F.Cu" "F.Mask" "F.Paste")
			(net "GND")
		)
		(pad "198" smd rect
			(at 2.050034 -18.275046 270)
			(size 0.519938 1.4986)
			(layers "F.Cu" "F.Mask" "F.Paste")
			(net "M_D_CPU0_SA_CB<3>")
		)
		(pad "199" smd rect
			(at 2.050034 -17.424908 270)
			(size 0.519938 1.4986)
			(layers "F.Cu" "F.Mask" "F.Paste")
			(net "GND")
		)
		(pad "200" smd rect
			(at 2.050034 -16.575024 270)
			(size 0.519938 1.4986)
			(layers "F.Cu" "F.Mask" "F.Paste")
			(net "M_D_CPU0_SA_DQS_DN<9>")
		)
		(pad "201" smd rect
			(at 2.050034 -15.724886 270)
			(size 0.519938 1.4986)
			(layers "F.Cu" "F.Mask" "F.Paste")
			(net "M_D_CPU0_SA_DQS_DP<9>")
		)
		(pad "202" smd rect
			(at 2.050034 -14.875002 270)
			(size 0.519938 1.4986)
			(layers "F.Cu" "F.Mask" "F.Paste")
			(net "GND")
		)
		(pad "203" smd rect
			(at 2.050034 -14.025118 270)
			(size 0.519938 1.4986)
			(layers "F.Cu" "F.Mask" "F.Paste")
			(net "M_D_CPU0_SA_CB<6>")
		)
		(pad "204" smd rect
			(at 2.050034 -13.17498 270)
			(size 0.519938 1.4986)
			(layers "F.Cu" "F.Mask" "F.Paste")
			(net "GND")
		)
		(pad "205" smd rect
			(at 2.050034 -12.325096 270)
			(size 0.519938 1.4986)
			(layers "F.Cu" "F.Mask" "F.Paste")
			(net "M_D_CPU0_SA_CB<7>")
		)
		(pad "206" smd rect
			(at 2.050034 -11.474958 270)
			(size 0.519938 1.4986)
			(layers "F.Cu" "F.Mask" "F.Paste")
			(net "GND")
		)
		(pad "207" smd rect
			(at 2.050034 -10.625074 270)
			(size 0.519938 1.4986)
			(layers "F.Cu" "F.Mask" "F.Paste")
			(net "RST_M_CD_CPU0_FPGA_N")
		)
		(pad "208" smd rect
			(at 2.050034 -9.774936 270)
			(size 0.519938 1.4986)
			(layers "F.Cu" "F.Mask" "F.Paste")
			(net "GND")
		)
		(pad "209" smd rect
			(at 2.050034 -8.925052 270)
			(size 0.519938 1.4986)
			(layers "F.Cu" "F.Mask" "F.Paste")
			(net "M_D_CPU0_SA_CS_N<3>")
		)
		(pad "210" smd rect
			(at 2.050034 -8.074914 270)
			(size 0.519938 1.4986)
			(layers "F.Cu" "F.Mask" "F.Paste")
			(net "GND")
		)
		(pad "211" smd rect
			(at 2.050034 -7.22503 270)
			(size 0.519938 1.4986)
			(layers "F.Cu" "F.Mask" "F.Paste")
			(net "M_D_CPU0_SA_CA<1>")
		)
		(pad "212" smd rect
			(at 2.050034 -6.374892 270)
			(size 0.519938 1.4986)
			(layers "F.Cu" "F.Mask" "F.Paste")
			(net "GND")
		)
		(pad "213" smd rect
			(at 2.050034 -5.525008 270)
			(size 0.519938 1.4986)
			(layers "F.Cu" "F.Mask" "F.Paste")
			(net "M_D_CPU0_SA_CA<3>")
		)
		(pad "214" smd rect
			(at 2.050034 -4.675124 270)
			(size 0.519938 1.4986)
			(layers "F.Cu" "F.Mask" "F.Paste")
			(net "GND")
		)
		(pad "215" smd rect
			(at 2.050034 -3.824986 270)
			(size 0.519938 1.4986)
			(layers "F.Cu" "F.Mask" "F.Paste")
			(net "M_D_CPU0_SA_CA<5>")
		)
		(pad "216" smd rect
			(at 2.050034 -2.975102 270)
			(size 0.519938 1.4986)
			(layers "F.Cu" "F.Mask" "F.Paste")
			(net "GND")
		)
		(pad "217" smd rect
			(at 2.050034 -2.124964 270)
			(size 0.519938 1.4986)
			(layers "F.Cu" "F.Mask" "F.Paste")
			(net "M_D_CPU0_CLK_DP<1>")
		)
		(pad "218" smd rect
			(at 2.050034 -1.27508 270)
			(size 0.519938 1.4986)
			(layers "F.Cu" "F.Mask" "F.Paste")
			(net "M_D_CPU0_CLK_DN<1>")
		)
		(pad "219" smd rect
			(at 2.050034 -0.424942 270)
			(size 0.519938 1.4986)
			(layers "F.Cu" "F.Mask" "F.Paste")
			(net "GND")
		)
		(pad "220" smd rect
			(at 2.050034 5.525008 270)
			(size 0.519938 1.4986)
			(layers "F.Cu" "F.Mask" "F.Paste")
			(net "TP_CHD_CPU0_DIMM2_FRU_4")
		)
		(pad "221" smd rect
			(at 2.050034 6.374892 270)
			(size 0.519938 1.4986)
			(layers "F.Cu" "F.Mask" "F.Paste")
			(net "M_D_CPU0_SB_CA<1>")
		)
		(pad "222" smd rect
			(at 2.050034 7.22503 270)
			(size 0.519938 1.4986)
			(layers "F.Cu" "F.Mask" "F.Paste")
			(net "GND")
		)
		(pad "223" smd rect
			(at 2.050034 8.074914 270)
			(size 0.519938 1.4986)
			(layers "F.Cu" "F.Mask" "F.Paste")
			(net "M_D_CPU0_SB_CA<3>")
		)
		(pad "224" smd rect
			(at 2.050034 8.925052 270)
			(size 0.519938 1.4986)
			(layers "F.Cu" "F.Mask" "F.Paste")
			(net "GND")
		)
		(pad "225" smd rect
			(at 2.050034 9.774936 270)
			(size 0.519938 1.4986)
			(layers "F.Cu" "F.Mask" "F.Paste")
			(net "M_D_CPU0_SB_CA<5>")
		)
		(pad "226" smd rect
			(at 2.050034 10.625074 270)
			(size 0.519938 1.4986)
			(layers "F.Cu" "F.Mask" "F.Paste")
			(net "GND")
		)
		(pad "227" smd rect
			(at 2.050034 11.474958 270)
			(size 0.519938 1.4986)
			(layers "F.Cu" "F.Mask" "F.Paste")
			(net "M_D_CPU0_SB_PAR")
		)
		(pad "228" smd rect
			(at 2.050034 12.325096 270)
			(size 0.519938 1.4986)
			(layers "F.Cu" "F.Mask" "F.Paste")
			(net "GND")
		)
		(pad "229" smd rect
			(at 2.050034 13.17498 270)
			(size 0.519938 1.4986)
			(layers "F.Cu" "F.Mask" "F.Paste")
			(net "M_D_CPU0_SB_CS_N<3>")
		)
		(pad "230" smd rect
			(at 2.050034 14.025118 270)
			(size 0.519938 1.4986)
			(layers "F.Cu" "F.Mask" "F.Paste")
			(net "GND")
		)
		(pad "231" smd rect
			(at 2.050034 14.875002 270)
			(size 0.519938 1.4986)
			(layers "F.Cu" "F.Mask" "F.Paste")
			(net "TP_CHD_CPU0_DIMM2_FRU_5")
		)
		(pad "232" smd rect
			(at 2.050034 15.724886 270)
			(size 0.519938 1.4986)
			(layers "F.Cu" "F.Mask" "F.Paste")
			(net "TP_CHD_CPU0_DIMM2_FRU_6")
		)
		(pad "233" smd rect
			(at 2.050034 16.575024 270)
			(size 0.519938 1.4986)
			(layers "F.Cu" "F.Mask" "F.Paste")
			(net "GND")
		)
		(pad "234" smd rect
			(at 2.050034 17.424908 270)
			(size 0.519938 1.4986)
			(layers "F.Cu" "F.Mask" "F.Paste")
			(net "M_D_CPU0_SB_CB<6>")
		)
		(pad "235" smd rect
			(at 2.050034 18.275046 270)
			(size 0.519938 1.4986)
			(layers "F.Cu" "F.Mask" "F.Paste")
			(net "GND")
		)
		(pad "236" smd rect
			(at 2.050034 19.12493 270)
			(size 0.519938 1.4986)
			(layers "F.Cu" "F.Mask" "F.Paste")
			(net "M_D_CPU0_SB_CB<7>")
		)
		(pad "237" smd rect
			(at 2.050034 19.975068 270)
			(size 0.519938 1.4986)
			(layers "F.Cu" "F.Mask" "F.Paste")
			(net "GND")
		)
		(pad "238" smd rect
			(at 2.050034 20.824952 270)
			(size 0.519938 1.4986)
			(layers "F.Cu" "F.Mask" "F.Paste")
			(net "M_D_CPU0_SB_DQS_DN<4>")
		)
		(pad "239" smd rect
			(at 2.050034 21.67509 270)
			(size 0.519938 1.4986)
			(layers "F.Cu" "F.Mask" "F.Paste")
			(net "M_D_CPU0_SB_DQS_DP<4>")
		)
		(pad "240" smd rect
			(at 2.050034 22.524974 270)
			(size 0.519938 1.4986)
			(layers "F.Cu" "F.Mask" "F.Paste")
			(net "GND")
		)
		(pad "241" smd rect
			(at 2.050034 23.375112 270)
			(size 0.519938 1.4986)
			(layers "F.Cu" "F.Mask" "F.Paste")
			(net "M_D_CPU0_SB_CB<2>")
		)
		(pad "242" smd rect
			(at 2.050034 24.224996 270)
			(size 0.519938 1.4986)
			(layers "F.Cu" "F.Mask" "F.Paste")
			(net "GND")
		)
		(pad "243" smd rect
			(at 2.050034 25.07488 270)
			(size 0.519938 1.4986)
			(layers "F.Cu" "F.Mask" "F.Paste")
			(net "M_D_CPU0_SB_CB<3>")
		)
		(pad "244" smd rect
			(at 2.050034 25.925018 270)
			(size 0.519938 1.4986)
			(layers "F.Cu" "F.Mask" "F.Paste")
			(net "GND")
		)
		(pad "245" smd rect
			(at 2.050034 26.774902 270)
			(size 0.519938 1.4986)
			(layers "F.Cu" "F.Mask" "F.Paste")
			(net "M_D_CPU0_SB_DQ<2>")
		)
		(pad "246" smd rect
			(at 2.050034 27.62504 270)
			(size 0.519938 1.4986)
			(layers "F.Cu" "F.Mask" "F.Paste")
			(net "GND")
		)
		(pad "247" smd rect
			(at 2.050034 28.474924 270)
			(size 0.519938 1.4986)
			(layers "F.Cu" "F.Mask" "F.Paste")
			(net "M_D_CPU0_SB_DQ<3>")
		)
		(pad "248" smd rect
			(at 2.050034 29.325062 270)
			(size 0.519938 1.4986)
			(layers "F.Cu" "F.Mask" "F.Paste")
			(net "GND")
		)
		(pad "249" smd rect
			(at 2.050034 30.174946 270)
			(size 0.519938 1.4986)
			(layers "F.Cu" "F.Mask" "F.Paste")
			(net "M_D_CPU0_SB_DQS_DN<5>")
		)
		(pad "250" smd rect
			(at 2.050034 31.025084 270)
			(size 0.519938 1.4986)
			(layers "F.Cu" "F.Mask" "F.Paste")
			(net "M_D_CPU0_SB_DQS_DP<5>")
		)
		(pad "251" smd rect
			(at 2.050034 31.874968 270)
			(size 0.519938 1.4986)
			(layers "F.Cu" "F.Mask" "F.Paste")
			(net "GND")
		)
		(pad "252" smd rect
			(at 2.050034 32.725106 270)
			(size 0.519938 1.4986)
			(layers "F.Cu" "F.Mask" "F.Paste")
			(net "M_D_CPU0_SB_DQ<6>")
		)
		(pad "253" smd rect
			(at 2.050034 33.57499 270)
			(size 0.519938 1.4986)
			(layers "F.Cu" "F.Mask" "F.Paste")
			(net "GND")
		)
		(pad "254" smd rect
			(at 2.050034 34.425128 270)
			(size 0.519938 1.4986)
			(layers "F.Cu" "F.Mask" "F.Paste")
			(net "M_D_CPU0_SB_DQ<7>")
		)
		(pad "255" smd rect
			(at 2.050034 35.275012 270)
			(size 0.519938 1.4986)
			(layers "F.Cu" "F.Mask" "F.Paste")
			(net "GND")
		)
		(pad "256" smd rect
			(at 2.050034 36.124896 270)
			(size 0.519938 1.4986)
			(layers "F.Cu" "F.Mask" "F.Paste")
			(net "M_D_CPU0_SB_DQ<10>")
		)
		(pad "257" smd rect
			(at 2.050034 36.975034 270)
			(size 0.519938 1.4986)
			(layers "F.Cu" "F.Mask" "F.Paste")
			(net "GND")
		)
		(pad "258" smd rect
			(at 2.050034 37.824918 270)
			(size 0.519938 1.4986)
			(layers "F.Cu" "F.Mask" "F.Paste")
			(net "M_D_CPU0_SB_DQ<11>")
		)
		(pad "259" smd rect
			(at 2.050034 38.675056 270)
			(size 0.519938 1.4986)
			(layers "F.Cu" "F.Mask" "F.Paste")
			(net "GND")
		)
		(pad "260" smd rect
			(at 2.050034 39.52494 270)
			(size 0.519938 1.4986)
			(layers "F.Cu" "F.Mask" "F.Paste")
			(net "M_D_CPU0_SB_DQS_DN<6>")
		)
		(pad "261" smd rect
			(at 2.050034 40.375078 270)
			(size 0.519938 1.4986)
			(layers "F.Cu" "F.Mask" "F.Paste")
			(net "M_D_CPU0_SB_DQS_DP<6>")
		)
		(pad "262" smd rect
			(at 2.050034 41.224962 270)
			(size 0.519938 1.4986)
			(layers "F.Cu" "F.Mask" "F.Paste")
			(net "GND")
		)
		(pad "263" smd rect
			(at 2.050034 42.0751 270)
			(size 0.519938 1.4986)
			(layers "F.Cu" "F.Mask" "F.Paste")
			(net "M_D_CPU0_SB_DQ<14>")
		)
		(pad "264" smd rect
			(at 2.050034 42.924984 270)
			(size 0.519938 1.4986)
			(layers "F.Cu" "F.Mask" "F.Paste")
			(net "GND")
		)
		(pad "265" smd rect
			(at 2.050034 43.775122 270)
			(size 0.519938 1.4986)
			(layers "F.Cu" "F.Mask" "F.Paste")
			(net "M_D_CPU0_SB_DQ<15>")
		)
		(pad "266" smd rect
			(at 2.050034 44.625006 270)
			(size 0.519938 1.4986)
			(layers "F.Cu" "F.Mask" "F.Paste")
			(net "GND")
		)
		(pad "267" smd rect
			(at 2.050034 45.47489 270)
			(size 0.519938 1.4986)
			(layers "F.Cu" "F.Mask" "F.Paste")
			(net "M_D_CPU0_SB_DQ<18>")
		)
		(pad "268" smd rect
			(at 2.050034 46.325028 270)
			(size 0.519938 1.4986)
			(layers "F.Cu" "F.Mask" "F.Paste")
			(net "GND")
		)
		(pad "269" smd rect
			(at 2.050034 47.174912 270)
			(size 0.519938 1.4986)
			(layers "F.Cu" "F.Mask" "F.Paste")
			(net "M_D_CPU0_SB_DQ<19>")
		)
		(pad "270" smd rect
			(at 2.050034 48.02505 270)
			(size 0.519938 1.4986)
			(layers "F.Cu" "F.Mask" "F.Paste")
			(net "GND")
		)
		(pad "271" smd rect
			(at 2.050034 48.874934 270)
			(size 0.519938 1.4986)
			(layers "F.Cu" "F.Mask" "F.Paste")
			(net "M_D_CPU0_SB_DQS_DN<7>")
		)
		(pad "272" smd rect
			(at 2.050034 49.725072 270)
			(size 0.519938 1.4986)
			(layers "F.Cu" "F.Mask" "F.Paste")
			(net "M_D_CPU0_SB_DQS_DP<7>")
		)
		(pad "273" smd rect
			(at 2.050034 50.574956 270)
			(size 0.519938 1.4986)
			(layers "F.Cu" "F.Mask" "F.Paste")
			(net "GND")
		)
		(pad "274" smd rect
			(at 2.050034 51.425094 270)
			(size 0.519938 1.4986)
			(layers "F.Cu" "F.Mask" "F.Paste")
			(net "M_D_CPU0_SB_DQ<22>")
		)
		(pad "275" smd rect
			(at 2.050034 52.274978 270)
			(size 0.519938 1.4986)
			(layers "F.Cu" "F.Mask" "F.Paste")
			(net "GND")
		)
		(pad "276" smd rect
			(at 2.050034 53.125116 270)
			(size 0.519938 1.4986)
			(layers "F.Cu" "F.Mask" "F.Paste")
			(net "M_D_CPU0_SB_DQ<23>")
		)
		(pad "277" smd rect
			(at 2.050034 53.975 270)
			(size 0.519938 1.4986)
			(layers "F.Cu" "F.Mask" "F.Paste")
			(net "GND")
		)
		(pad "278" smd rect
			(at 2.050034 54.824884 270)
			(size 0.519938 1.4986)
			(layers "F.Cu" "F.Mask" "F.Paste")
			(net "M_D_CPU0_SB_DQ<26>")
		)
		(pad "279" smd rect
			(at 2.050034 55.675022 270)
			(size 0.519938 1.4986)
			(layers "F.Cu" "F.Mask" "F.Paste")
			(net "GND")
		)
		(pad "280" smd rect
			(at 2.050034 56.524906 270)
			(size 0.519938 1.4986)
			(layers "F.Cu" "F.Mask" "F.Paste")
			(net "M_D_CPU0_SB_DQ<27>")
		)
		(pad "281" smd rect
			(at 2.050034 57.375044 270)
			(size 0.519938 1.4986)
			(layers "F.Cu" "F.Mask" "F.Paste")
			(net "GND")
		)
		(pad "282" smd rect
			(at 2.050034 58.224928 270)
			(size 0.519938 1.4986)
			(layers "F.Cu" "F.Mask" "F.Paste")
			(net "M_D_CPU0_SB_DQS_DN<8>")
		)
		(pad "283" smd rect
			(at 2.050034 59.075066 270)
			(size 0.519938 1.4986)
			(layers "F.Cu" "F.Mask" "F.Paste")
			(net "M_D_CPU0_SB_DQS_DP<8>")
		)
		(pad "284" smd rect
			(at 2.050034 59.92495 270)
			(size 0.519938 1.4986)
			(layers "F.Cu" "F.Mask" "F.Paste")
			(net "GND")
		)
		(pad "285" smd rect
			(at 2.050034 60.775088 270)
			(size 0.519938 1.4986)
			(layers "F.Cu" "F.Mask" "F.Paste")
			(net "M_D_CPU0_SB_DQ<30>")
		)
		(pad "286" smd rect
			(at 2.050034 61.624972 270)
			(size 0.519938 1.4986)
			(layers "F.Cu" "F.Mask" "F.Paste")
			(net "GND")
		)
		(pad "287" smd rect
			(at 2.050034 62.47511 270)
			(size 0.519938 1.4986)
			(layers "F.Cu" "F.Mask" "F.Paste")
			(net "M_D_CPU0_SB_DQ<31>")
		)
		(pad "288" smd rect
			(at 2.050034 63.324994 270)
			(size 0.519938 1.4986)
			(layers "F.Cu" "F.Mask" "F.Paste")
			(net "GND")
		)
		(pad "G1" thru_hole oval
			(at 0 -68.97497)
			(size 2.8194 1.5748)
			(drill oval 2.4384 1.1938)
			(layers "*.Cu" "*.Mask")
			(remove_unused_layers no)
			(net "GND")
			(clearance 0.127)
			(thermal_gap 0.127)
		)
		(pad "G2" thru_hole oval
			(at 0 3.875024)
			(size 2.8194 1.5748)
			(drill oval 2.4384 1.1938)
			(layers "*.Cu" "*.Mask")
			(remove_unused_layers no)
			(net "GND")
			(clearance 0.127)
			(thermal_gap 0.127)
		)
		(pad "G3" thru_hole oval
			(at 0 68.97497)
			(size 2.8194 1.5748)
			(drill oval 2.4384 1.1938)
			(layers "*.Cu" "*.Mask")
			(remove_unused_layers no)
			(net "GND")
			(clearance 0.127)
			(thermal_gap 0.127)
		)
	)
	(footprint ""
		(layer "F.Cu")
		(at 428.283116 -109.26699 90)
		(property "Reference" "PR3791"
			(at 0 0 90)
			(layer "F.SilkS")
			(hide yes)
			(effects
				(font
					(size 1.27 1.27)
				)
			)
		)
		(property "Value" ""
			(at 0 0 90)
			(layer "F.Fab")
			(effects
				(font
					(size 1.27 1.27)
				)
			)
		)
		(duplicate_pad_numbers_are_jumpers no)
		(fp_line
			(start 0.7874 -0.4064)
			(end 0.7874 0.4064)
			(stroke
				(width 0.1524)
				(type default)
			)
			(layer "F.SilkS")
		)
		(fp_line
			(start -0.7874 -0.4064)
			(end 0.7874 -0.4064)
			(stroke
				(width 0.1524)
				(type default)
			)
			(layer "F.SilkS")
		)
		(fp_line
			(start 0.7874 0.4064)
			(end -0.7874 0.4064)
			(stroke
				(width 0.1524)
				(type default)
			)
			(layer "F.SilkS")
		)
		(fp_line
			(start -0.7874 0.4064)
			(end -0.7874 -0.4064)
			(stroke
				(width 0.1524)
				(type default)
			)
			(layer "F.SilkS")
		)
		(fp_line
			(start -0.12065 -0.305054)
			(end -0.12065 -0.2794)
			(stroke
				(width 0.1)
				(type default)
			)
			(layer "F.Fab")
		)
		(fp_line
			(start -0.67945 -0.305054)
			(end -0.12065 -0.305054)
			(stroke
				(width 0.1)
				(type default)
			)
			(layer "F.Fab")
		)
		(fp_line
			(start 0.67945 -0.3048)
			(end 0.67945 0.3048)
			(stroke
				(width 0.1)
				(type default)
			)
			(layer "F.Fab")
		)
		(fp_line
			(start 0.12065 -0.3048)
			(end 0.67945 -0.3048)
			(stroke
				(width 0.1)
				(type default)
			)
			(layer "F.Fab")
		)
		(fp_line
			(start 0.12065 -0.2794)
			(end 0.12065 -0.3048)
			(stroke
				(width 0.1)
				(type default)
			)
			(layer "F.Fab")
		)
		(fp_line
			(start -0.12065 -0.2794)
			(end 0.12065 -0.2794)
			(stroke
				(width 0.1)
				(type default)
			)
			(layer "F.Fab")
		)
		(fp_line
			(start 0.120396 0.2794)
			(end -0.12065 0.2794)
			(stroke
				(width 0.1)
				(type default)
			)
			(layer "F.Fab")
		)
		(fp_line
			(start -0.12065 0.2794)
			(end -0.12065 0.3048)
			(stroke
				(width 0.1)
				(type default)
			)
			(layer "F.Fab")
		)
		(fp_line
			(start 0.67945 0.3048)
			(end 0.120396 0.3048)
			(stroke
				(width 0.1)
				(type default)
			)
			(layer "F.Fab")
		)
		(fp_line
			(start 0.120396 0.3048)
			(end 0.120396 0.2794)
			(stroke
				(width 0.1)
				(type default)
			)
			(layer "F.Fab")
		)
		(fp_line
			(start -0.12065 0.3048)
			(end -0.67945 0.3048)
			(stroke
				(width 0.1)
				(type default)
			)
			(layer "F.Fab")
		)
		(fp_line
			(start -0.67945 0.3048)
			(end -0.67945 -0.305054)
			(stroke
				(width 0.1)
				(type default)
			)
			(layer "F.Fab")
		)
		(pad "1" smd circle
			(at -0.40005 0 90)
			(size 0 0)
			(layers "F.Cu" "F.Mask" "F.Paste")
			(net "P3V3_OCP_OV_1")
		)
		(pad "2" smd circle
			(at 0.40005 0 90)
			(size 0 0)
			(layers "F.Cu" "F.Mask" "F.Paste")
			(net "GND")
		)
	)
	(footprint ""
		(layer "F.Cu")
		(at 160.866074 -402.371052 -90)
		(property "Reference" "C768"
			(at 0 0 270)
			(layer "F.SilkS")
			(hide yes)
			(effects
				(font
					(size 1.27 1.27)
				)
			)
		)
		(property "Value" ""
			(at 0 0 270)
			(layer "F.Fab")
			(effects
				(font
					(size 1.27 1.27)
				)
			)
		)
		(duplicate_pad_numbers_are_jumpers no)
		(fp_line
			(start -0.299974 0.150114)
			(end -0.299974 -0.150114)
			(stroke
				(width 0.1)
				(type default)
			)
			(layer "F.Fab")
		)
		(fp_line
			(start 0.299974 0.150114)
			(end -0.299974 0.150114)
			(stroke
				(width 0.1)
				(type default)
			)
			(layer "F.Fab")
		)
		(fp_line
			(start -0.299974 -0.150114)
			(end 0.299974 -0.150114)
			(stroke
				(width 0.1)
				(type default)
			)
			(layer "F.Fab")
		)
		(fp_line
			(start 0.299974 -0.150114)
			(end 0.299974 0.150114)
			(stroke
				(width 0.1)
				(type default)
			)
			(layer "F.Fab")
		)
		(pad "1" smd rect
			(at -0.2667 0 270)
			(size 0.3048 0.381)
			(layers "F.Cu" "F.Mask" "F.Paste")
			(net "P5E_CPU1_PE2_TX_C_DN<2>")
		)
		(pad "2" smd rect
			(at 0.2667 0 270)
			(size 0.3048 0.381)
			(layers "F.Cu" "F.Mask" "F.Paste")
			(net "P5E_CPU1_PE2_TX_DN<2>")
		)
	)
	(footprint ""
		(layer "F.Cu")
		(at 142.918434 -408.517344 -90)
		(property "Reference" "C1530"
			(at 0 0 270)
			(layer "F.SilkS")
			(hide yes)
			(effects
				(font
					(size 1.27 1.27)
				)
			)
		)
		(property "Value" ""
			(at 0 0 270)
			(layer "F.Fab")
			(effects
				(font
					(size 1.27 1.27)
				)
			)
		)
		(duplicate_pad_numbers_are_jumpers no)
		(fp_line
			(start -0.299974 0.150114)
			(end -0.299974 -0.150114)
			(stroke
				(width 0.1)
				(type default)
			)
			(layer "F.Fab")
		)
		(fp_line
			(start 0.299974 0.150114)
			(end -0.299974 0.150114)
			(stroke
				(width 0.1)
				(type default)
			)
			(layer "F.Fab")
		)
		(fp_line
			(start -0.299974 -0.150114)
			(end 0.299974 -0.150114)
			(stroke
				(width 0.1)
				(type default)
			)
			(layer "F.Fab")
		)
		(fp_line
			(start 0.299974 -0.150114)
			(end 0.299974 0.150114)
			(stroke
				(width 0.1)
				(type default)
			)
			(layer "F.Fab")
		)
		(pad "1" smd rect
			(at -0.2667 0 270)
			(size 0.3048 0.381)
			(layers "F.Cu" "F.Mask" "F.Paste")
			(net "P5E_CPU1_PE3_TX_C_DN<8>")
		)
		(pad "2" smd rect
			(at 0.2667 0 270)
			(size 0.3048 0.381)
			(layers "F.Cu" "F.Mask" "F.Paste")
			(net "P5E_CPU1_PE3_TX_DN<8>")
		)
	)
	(footprint ""
		(layer "F.Cu")
		(at 204.93736 -120.614948)
		(property "Reference" "R4174"
			(at 0 0 0)
			(layer "F.SilkS")
			(hide yes)
			(effects
				(font
					(size 1.27 1.27)
				)
			)
		)
		(property "Value" ""
			(at 0 0 0)
			(layer "F.Fab")
			(effects
				(font
					(size 1.27 1.27)
				)
			)
		)
		(duplicate_pad_numbers_are_jumpers no)
		(fp_line
			(start -0.7874 -0.4064)
			(end 0.7874 -0.4064)
			(stroke
				(width 0.1524)
				(type default)
			)
			(layer "F.SilkS")
		)
		(fp_line
			(start -0.7874 0.4064)
			(end -0.7874 -0.4064)
			(stroke
				(width 0.1524)
				(type default)
			)
			(layer "F.SilkS")
		)
		(fp_line
			(start 0.7874 -0.4064)
			(end 0.7874 0.4064)
			(stroke
				(width 0.1524)
				(type default)
			)
			(layer "F.SilkS")
		)
		(fp_line
			(start 0.7874 0.4064)
			(end -0.7874 0.4064)
			(stroke
				(width 0.1524)
				(type default)
			)
			(layer "F.SilkS")
		)
		(fp_line
			(start -0.67945 -0.305054)
			(end -0.12065 -0.305054)
			(stroke
				(width 0.1)
				(type default)
			)
			(layer "F.Fab")
		)
		(fp_line
			(start -0.67945 0.3048)
			(end -0.67945 -0.305054)
			(stroke
				(width 0.1)
				(type default)
			)
			(layer "F.Fab")
		)
		(fp_line
			(start -0.12065 -0.305054)
			(end -0.12065 -0.2794)
			(stroke
				(width 0.1)
				(type default)
			)
			(layer "F.Fab")
		)
		(fp_line
			(start -0.12065 -0.2794)
			(end 0.12065 -0.2794)
			(stroke
				(width 0.1)
				(type default)
			)
			(layer "F.Fab")
		)
		(fp_line
			(start -0.12065 0.2794)
			(end -0.12065 0.3048)
			(stroke
				(width 0.1)
				(type default)
			)
			(layer "F.Fab")
		)
		(fp_line
			(start -0.12065 0.3048)
			(end -0.67945 0.3048)
			(stroke
				(width 0.1)
				(type default)
			)
			(layer "F.Fab")
		)
		(fp_line
			(start 0.120396 0.2794)
			(end -0.12065 0.2794)
			(stroke
				(width 0.1)
				(type default)
			)
			(layer "F.Fab")
		)
		(fp_line
			(start 0.120396 0.3048)
			(end 0.120396 0.2794)
			(stroke
				(width 0.1)
				(type default)
			)
			(layer "F.Fab")
		)
		(fp_line
			(start 0.12065 -0.3048)
			(end 0.67945 -0.3048)
			(stroke
				(width 0.1)
				(type default)
			)
			(layer "F.Fab")
		)
		(fp_line
			(start 0.12065 -0.2794)
			(end 0.12065 -0.3048)
			(stroke
				(width 0.1)
				(type default)
			)
			(layer "F.Fab")
		)
		(fp_line
			(start 0.67945 -0.3048)
			(end 0.67945 0.3048)
			(stroke
				(width 0.1)
				(type default)
			)
			(layer "F.Fab")
		)
		(fp_line
			(start 0.67945 0.3048)
			(end 0.120396 0.3048)
			(stroke
				(width 0.1)
				(type default)
			)
			(layer "F.Fab")
		)
		(pad "1" smd circle
			(at -0.40005 0)
			(size 0 0)
			(layers "F.Cu" "F.Mask" "F.Paste")
			(net "RST_PCIE_PCH_DEV_PERST_N")
		)
		(pad "2" smd circle
			(at 0.40005 0)
			(size 0 0)
			(layers "F.Cu" "F.Mask" "F.Paste")
			(net "RST_PCIE_PCH_DEV_PERST_E1S_R_N")
		)
	)
	(footprint ""
		(layer "F.Cu")
		(at 66.150744 -14.26464 180)
		(property "Reference" "PC2152"
			(at 0 0 180)
			(layer "F.SilkS")
			(hide yes)
			(effects
				(font
					(size 1.27 1.27)
				)
			)
		)
		(property "Value" ""
			(at 0 0 180)
			(layer "F.Fab")
			(effects
				(font
					(size 1.27 1.27)
				)
			)
		)
		(duplicate_pad_numbers_are_jumpers no)
		(fp_line
			(start 0.7874 0.4064)
			(end -0.7874 0.4064)
			(stroke
				(width 0.1524)
				(type default)
			)
			(layer "F.SilkS")
		)
		(fp_line
			(start 0.7874 -0.4064)
			(end 0.7874 0.4064)
			(stroke
				(width 0.1524)
				(type default)
			)
			(layer "F.SilkS")
		)
		(fp_line
			(start -0.7874 0.4064)
			(end -0.7874 -0.4064)
			(stroke
				(width 0.1524)
				(type default)
			)
			(layer "F.SilkS")
		)
		(fp_line
			(start -0.7874 -0.4064)
			(end 0.7874 -0.4064)
			(stroke
				(width 0.1524)
				(type default)
			)
			(layer "F.SilkS")
		)
		(fp_line
			(start 0.67945 0.3048)
			(end 0.120396 0.3048)
			(stroke
				(width 0.1)
				(type default)
			)
			(layer "F.Fab")
		)
		(fp_line
			(start 0.67945 -0.3048)
			(end 0.67945 0.3048)
			(stroke
				(width 0.1)
				(type default)
			)
			(layer "F.Fab")
		)
		(fp_line
			(start 0.12065 -0.2794)
			(end 0.12065 -0.3048)
			(stroke
				(width 0.1)
				(type default)
			)
			(layer "F.Fab")
		)
		(fp_line
			(start 0.12065 -0.3048)
			(end 0.67945 -0.3048)
			(stroke
				(width 0.1)
				(type default)
			)
			(layer "F.Fab")
		)
		(fp_line
			(start 0.120396 0.3048)
			(end 0.120396 0.2794)
			(stroke
				(width 0.1)
				(type default)
			)
			(layer "F.Fab")
		)
		(fp_line
			(start 0.120396 0.2794)
			(end -0.12065 0.2794)
			(stroke
				(width 0.1)
				(type default)
			)
			(layer "F.Fab")
		)
		(fp_line
			(start -0.12065 0.3048)
			(end -0.67945 0.3048)
			(stroke
				(width 0.1)
				(type default)
			)
			(layer "F.Fab")
		)
		(fp_line
			(start -0.12065 0.2794)
			(end -0.12065 0.3048)
			(stroke
				(width 0.1)
				(type default)
			)
			(layer "F.Fab")
		)
		(fp_line
			(start -0.12065 -0.2794)
			(end 0.12065 -0.2794)
			(stroke
				(width 0.1)
				(type default)
			)
			(layer "F.Fab")
		)
		(fp_line
			(start -0.12065 -0.305054)
			(end -0.12065 -0.2794)
			(stroke
				(width 0.1)
				(type default)
			)
			(layer "F.Fab")
		)
		(fp_line
			(start -0.67945 0.3048)
			(end -0.67945 -0.305054)
			(stroke
				(width 0.1)
				(type default)
			)
			(layer "F.Fab")
		)
		(fp_line
			(start -0.67945 -0.305054)
			(end -0.12065 -0.305054)
			(stroke
				(width 0.1)
				(type default)
			)
			(layer "F.Fab")
		)
		(pad "1" smd circle
			(at -0.40005 0 180)
			(size 0 0)
			(layers "F.Cu" "F.Mask" "F.Paste")
			(net "P12V_OCP_V3_2")
		)
		(pad "2" smd circle
			(at 0.40005 0 180)
			(size 0 0)
			(layers "F.Cu" "F.Mask" "F.Paste")
			(net "GND")
		)
	)
	(footprint ""
		(layer "F.Cu")
		(at 428.62373 -120.365012 180)
		(property "Reference" "PC629"
			(at 0 0 180)
			(layer "F.SilkS")
			(hide yes)
			(effects
				(font
					(size 1.27 1.27)
				)
			)
		)
		(property "Value" ""
			(at 0 0 180)
			(layer "F.Fab")
			(effects
				(font
					(size 1.27 1.27)
				)
			)
		)
		(duplicate_pad_numbers_are_jumpers no)
		(fp_line
			(start 0.7874 0.4064)
			(end -0.7874 0.4064)
			(stroke
				(width 0.1524)
				(type default)
			)
			(layer "F.SilkS")
		)
		(fp_line
			(start 0.7874 -0.4064)
			(end 0.7874 0.4064)
			(stroke
				(width 0.1524)
				(type default)
			)
			(layer "F.SilkS")
		)
		(fp_line
			(start -0.7874 0.4064)
			(end -0.7874 -0.4064)
			(stroke
				(width 0.1524)
				(type default)
			)
			(layer "F.SilkS")
		)
		(fp_line
			(start -0.7874 -0.4064)
			(end 0.7874 -0.4064)
			(stroke
				(width 0.1524)
				(type default)
			)
			(layer "F.SilkS")
		)
		(fp_line
			(start 0.67945 0.3048)
			(end 0.120396 0.3048)
			(stroke
				(width 0.1)
				(type default)
			)
			(layer "F.Fab")
		)
		(fp_line
			(start 0.67945 -0.3048)
			(end 0.67945 0.3048)
			(stroke
				(width 0.1)
				(type default)
			)
			(layer "F.Fab")
		)
		(fp_line
			(start 0.12065 -0.2794)
			(end 0.12065 -0.3048)
			(stroke
				(width 0.1)
				(type default)
			)
			(layer "F.Fab")
		)
		(fp_line
			(start 0.12065 -0.3048)
			(end 0.67945 -0.3048)
			(stroke
				(width 0.1)
				(type default)
			)
			(layer "F.Fab")
		)
		(fp_line
			(start 0.120396 0.3048)
			(end 0.120396 0.2794)
			(stroke
				(width 0.1)
				(type default)
			)
			(layer "F.Fab")
		)
		(fp_line
			(start 0.120396 0.2794)
			(end -0.12065 0.2794)
			(stroke
				(width 0.1)
				(type default)
			)
			(layer "F.Fab")
		)
		(fp_line
			(start -0.12065 0.3048)
			(end -0.67945 0.3048)
			(stroke
				(width 0.1)
				(type default)
			)
			(layer "F.Fab")
		)
		(fp_line
			(start -0.12065 0.2794)
			(end -0.12065 0.3048)
			(stroke
				(width 0.1)
				(type default)
			)
			(layer "F.Fab")
		)
		(fp_line
			(start -0.12065 -0.2794)
			(end 0.12065 -0.2794)
			(stroke
				(width 0.1)
				(type default)
			)
			(layer "F.Fab")
		)
		(fp_line
			(start -0.12065 -0.305054)
			(end -0.12065 -0.2794)
			(stroke
				(width 0.1)
				(type default)
			)
			(layer "F.Fab")
		)
		(fp_line
			(start -0.67945 0.3048)
			(end -0.67945 -0.305054)
			(stroke
				(width 0.1)
				(type default)
			)
			(layer "F.Fab")
		)
		(fp_line
			(start -0.67945 -0.305054)
			(end -0.12065 -0.305054)
			(stroke
				(width 0.1)
				(type default)
			)
			(layer "F.Fab")
		)
		(pad "1" smd circle
			(at -0.40005 0 180)
			(size 0 0)
			(layers "F.Cu" "F.Mask" "F.Paste")
			(net "PVCCD_HV_CPU0_VCC")
		)
		(pad "2" smd circle
			(at 0.40005 0 180)
			(size 0 0)
			(layers "F.Cu" "F.Mask" "F.Paste")
			(net "GND")
		)
	)
	(footprint ""
		(layer "F.Cu")
		(at 101.833934 -392.63574 180)
		(property "Reference" "R3462"
			(at 0 0 180)
			(layer "F.SilkS")
			(hide yes)
			(effects
				(font
					(size 1.27 1.27)
				)
			)
		)
		(property "Value" ""
			(at 0 0 180)
			(layer "F.Fab")
			(effects
				(font
					(size 1.27 1.27)
				)
			)
		)
		(duplicate_pad_numbers_are_jumpers no)
		(fp_line
			(start 0.7874 0.4064)
			(end -0.7874 0.4064)
			(stroke
				(width 0.1524)
				(type default)
			)
			(layer "F.SilkS")
		)
		(fp_line
			(start 0.7874 -0.4064)
			(end 0.7874 0.4064)
			(stroke
				(width 0.1524)
				(type default)
			)
			(layer "F.SilkS")
		)
		(fp_line
			(start -0.7874 0.4064)
			(end -0.7874 -0.4064)
			(stroke
				(width 0.1524)
				(type default)
			)
			(layer "F.SilkS")
		)
		(fp_line
			(start -0.7874 -0.4064)
			(end 0.7874 -0.4064)
			(stroke
				(width 0.1524)
				(type default)
			)
			(layer "F.SilkS")
		)
		(fp_line
			(start 0.67945 0.3048)
			(end 0.120396 0.3048)
			(stroke
				(width 0.1)
				(type default)
			)
			(layer "F.Fab")
		)
		(fp_line
			(start 0.67945 -0.3048)
			(end 0.67945 0.3048)
			(stroke
				(width 0.1)
				(type default)
			)
			(layer "F.Fab")
		)
		(fp_line
			(start 0.12065 -0.2794)
			(end 0.12065 -0.3048)
			(stroke
				(width 0.1)
				(type default)
			)
			(layer "F.Fab")
		)
		(fp_line
			(start 0.12065 -0.3048)
			(end 0.67945 -0.3048)
			(stroke
				(width 0.1)
				(type default)
			)
			(layer "F.Fab")
		)
		(fp_line
			(start 0.120396 0.3048)
			(end 0.120396 0.2794)
			(stroke
				(width 0.1)
				(type default)
			)
			(layer "F.Fab")
		)
		(fp_line
			(start 0.120396 0.2794)
			(end -0.12065 0.2794)
			(stroke
				(width 0.1)
				(type default)
			)
			(layer "F.Fab")
		)
		(fp_line
			(start -0.12065 0.3048)
			(end -0.67945 0.3048)
			(stroke
				(width 0.1)
				(type default)
			)
			(layer "F.Fab")
		)
		(fp_line
			(start -0.12065 0.2794)
			(end -0.12065 0.3048)
			(stroke
				(width 0.1)
				(type default)
			)
			(layer "F.Fab")
		)
		(fp_line
			(start -0.12065 -0.2794)
			(end 0.12065 -0.2794)
			(stroke
				(width 0.1)
				(type default)
			)
			(layer "F.Fab")
		)
		(fp_line
			(start -0.12065 -0.305054)
			(end -0.12065 -0.2794)
			(stroke
				(width 0.1)
				(type default)
			)
			(layer "F.Fab")
		)
		(fp_line
			(start -0.67945 0.3048)
			(end -0.67945 -0.305054)
			(stroke
				(width 0.1)
				(type default)
			)
			(layer "F.Fab")
		)
		(fp_line
			(start -0.67945 -0.305054)
			(end -0.12065 -0.305054)
			(stroke
				(width 0.1)
				(type default)
			)
			(layer "F.Fab")
		)
		(pad "1" smd circle
			(at -0.40005 0 180)
			(size 0 0)
			(layers "F.Cu" "F.Mask" "F.Paste")
			(net "GPU_NVS_PWR_BRAKE_N_R")
		)
		(pad "2" smd circle
			(at 0.40005 0 180)
			(size 0 0)
			(layers "F.Cu" "F.Mask" "F.Paste")
			(net "GND")
		)
	)
	(footprint ""
		(layer "F.Cu")
		(at 284.599888 -411.29204 -90)
		(property "Reference" "C2342"
			(at 0 0 270)
			(layer "F.SilkS")
			(hide yes)
			(effects
				(font
					(size 1.27 1.27)
				)
			)
		)
		(property "Value" ""
			(at 0 0 270)
			(layer "F.Fab")
			(effects
				(font
					(size 1.27 1.27)
				)
			)
		)
		(duplicate_pad_numbers_are_jumpers no)
		(fp_line
			(start -0.7874 0.4064)
			(end -0.7874 -0.4064)
			(stroke
				(width 0.1524)
				(type default)
			)
			(layer "F.SilkS")
		)
		(fp_line
			(start 0.7874 0.4064)
			(end -0.7874 0.4064)
			(stroke
				(width 0.1524)
				(type default)
			)
			(layer "F.SilkS")
		)
		(fp_line
			(start -0.7874 -0.4064)
			(end 0.7874 -0.4064)
			(stroke
				(width 0.1524)
				(type default)
			)
			(layer "F.SilkS")
		)
		(fp_line
			(start 0.7874 -0.4064)
			(end 0.7874 0.4064)
			(stroke
				(width 0.1524)
				(type default)
			)
			(layer "F.SilkS")
		)
		(fp_line
			(start -0.67945 0.3048)
			(end -0.67945 -0.305054)
			(stroke
				(width 0.1)
				(type default)
			)
			(layer "F.Fab")
		)
		(fp_line
			(start -0.12065 0.3048)
			(end -0.67945 0.3048)
			(stroke
				(width 0.1)
				(type default)
			)
			(layer "F.Fab")
		)
		(fp_line
			(start 0.120396 0.3048)
			(end 0.120396 0.2794)
			(stroke
				(width 0.1)
				(type default)
			)
			(layer "F.Fab")
		)
		(fp_line
			(start 0.67945 0.3048)
			(end 0.120396 0.3048)
			(stroke
				(width 0.1)
				(type default)
			)
			(layer "F.Fab")
		)
		(fp_line
			(start -0.12065 0.2794)
			(end -0.12065 0.3048)
			(stroke
				(width 0.1)
				(type default)
			)
			(layer "F.Fab")
		)
		(fp_line
			(start 0.120396 0.2794)
			(end -0.12065 0.2794)
			(stroke
				(width 0.1)
				(type default)
			)
			(layer "F.Fab")
		)
		(fp_line
			(start -0.12065 -0.2794)
			(end 0.12065 -0.2794)
			(stroke
				(width 0.1)
				(type default)
			)
			(layer "F.Fab")
		)
		(fp_line
			(start 0.12065 -0.2794)
			(end 0.12065 -0.3048)
			(stroke
				(width 0.1)
				(type default)
			)
			(layer "F.Fab")
		)
		(fp_line
			(start 0.12065 -0.3048)
			(end 0.67945 -0.3048)
			(stroke
				(width 0.1)
				(type default)
			)
			(layer "F.Fab")
		)
		(fp_line
			(start 0.67945 -0.3048)
			(end 0.67945 0.3048)
			(stroke
				(width 0.1)
				(type default)
			)
			(layer "F.Fab")
		)
		(fp_line
			(start -0.67945 -0.305054)
			(end -0.12065 -0.305054)
			(stroke
				(width 0.1)
				(type default)
			)
			(layer "F.Fab")
		)
		(fp_line
			(start -0.12065 -0.305054)
			(end -0.12065 -0.2794)
			(stroke
				(width 0.1)
				(type default)
			)
			(layer "F.Fab")
		)
		(pad "1" smd circle
			(at -0.40005 0 270)
			(size 0 0)
			(layers "F.Cu" "F.Mask" "F.Paste")
			(net "HPDB_HSC_PWRGD_ISO")
		)
		(pad "2" smd circle
			(at 0.40005 0 270)
			(size 0 0)
			(layers "F.Cu" "F.Mask" "F.Paste")
			(net "GND")
		)
	)
	(footprint ""
		(layer "F.Cu")
		(at 353.0727 -324.445376)
		(property "Reference" "PL13"
			(at -12.45616 6.763258 0)
			(unlocked yes)
			(layer "F.SilkS")
			(effects
				(font
					(size 0.7874 0.5842)
					(thickness 0.1524)
				)
				(justify left)
			)
		)
		(property "Value" ""
			(at 0 0 0)
			(layer "F.Fab")
			(effects
				(font
					(size 1.27 1.27)
				)
			)
		)
		(duplicate_pad_numbers_are_jumpers no)
		(fp_line
			(start -3.750056 -5.500116)
			(end -2.393442 -5.500116)
			(stroke
				(width 0.1524)
				(type default)
			)
			(layer "F.SilkS")
		)
		(fp_line
			(start -3.750056 5.500116)
			(end -3.750056 -5.500116)
			(stroke
				(width 0.1524)
				(type default)
			)
			(layer "F.SilkS")
		)
		(fp_line
			(start -2.393442 5.500116)
			(end -3.750056 5.500116)
			(stroke
				(width 0.1524)
				(type default)
			)
			(layer "F.SilkS")
		)
		(fp_line
			(start 2.393442 5.500116)
			(end 3.750056 5.500116)
			(stroke
				(width 0.1524)
				(type default)
			)
			(layer "F.SilkS")
		)
		(fp_line
			(start 3.750056 -5.500116)
			(end 2.393442 -5.500116)
			(stroke
				(width 0.1524)
				(type default)
			)
			(layer "F.SilkS")
		)
		(fp_line
			(start 3.750056 -4.449572)
			(end 3.750056 -5.500116)
			(stroke
				(width 0.1524)
				(type default)
			)
			(layer "F.SilkS")
		)
		(fp_line
			(start 3.750056 5.500116)
			(end 3.750056 -3.560572)
			(stroke
				(width 0.1524)
				(type default)
			)
			(layer "F.SilkS")
		)
		(fp_poly
			(pts
				(xy -3.434334 -7.043674) (xy -3.074924 -5.965952) (xy -4.152646 -6.325108)
			)
			(stroke
				(width 0)
				(type default)
			)
			(fill yes)
			(layer "F.SilkS")
		)
		(fp_line
			(start -3.750056 -5.500116)
			(end -3.750056 5.500116)
			(stroke
				(width 0.1)
				(type default)
			)
			(layer "F.Fab")
		)
		(fp_line
			(start -3.750056 5.500116)
			(end 3.750056 5.500116)
			(stroke
				(width 0.1)
				(type default)
			)
			(layer "F.Fab")
		)
		(fp_line
			(start 3.750056 -5.500116)
			(end -3.750056 -5.500116)
			(stroke
				(width 0.1)
				(type default)
			)
			(layer "F.Fab")
		)
		(fp_line
			(start 3.750056 5.500116)
			(end 3.750056 -5.500116)
			(stroke
				(width 0.1)
				(type default)
			)
			(layer "F.Fab")
		)
		(fp_poly
			(pts
				(xy -4.9276 -4.757928) (xy -4.9276 -3.741928) (xy -3.9116 -4.249928)
			)
			(stroke
				(width 0)
				(type default)
			)
			(fill yes)
			(layer "F.Fab")
		)
		(pad "1" smd rect
			(at 0 -4.249928 270)
			(size 2.413 4.5212)
			(layers "F.Cu" "F.Mask" "F.Paste")
			(net "SW_PVCCIN_CPU0_SW2")
		)
		(pad "2" smd rect
			(at 0 -1.175004 270)
			(size 1.3716 4.5212)
			(layers "F.Cu" "F.Mask" "F.Paste")
			(net "IND_P0_CPL2")
		)
		(pad "3" smd rect
			(at 0 1.175004 270)
			(size 1.3716 4.5212)
			(layers "F.Cu" "F.Mask" "F.Paste")
			(net "IND_P0_CPL3")
		)
		(pad "4" smd rect
			(at 0 4.249928 270)
			(size 2.413 4.5212)
			(layers "F.Cu" "F.Mask" "F.Paste")
			(net "PVCCIN_CPU0")
		)
	)
	(footprint ""
		(layer "F.Cu")
		(at 466.24748 -53.449728)
		(property "Reference" ""
			(at 0 0 0)
			(layer "F.SilkS")
			(hide yes)
			(effects
				(font
					(size 1.27 1.27)
				)
			)
		)
		(property "Value" ""
			(at 0 0 0)
			(layer "F.Fab")
			(effects
				(font
					(size 1.27 1.27)
				)
			)
		)
		(duplicate_pad_numbers_are_jumpers no)
		(pad "1" smd circle
			(at 0 0)
			(size 0.9906 0.9906)
			(layers "F.Cu" "F.Mask" "F.Paste")
			(net "Net_295")
		)
		(zone
			(layer "F.Cu")
			(hatch none 0.5)
			(connect_pads
				(clearance 0)
			)
			(min_thickness 0.25)
			(keepout
				(tracks not_allowed)
				(vias allowed)
				(pads allowed)
				(copperpour not_allowed)
				(footprints allowed)
			)
			(placement
				(enabled no)
				(sheetname "")
			)
			(fill
				(thermal_gap 0.5)
				(thermal_bridge_width 0.5)
				(island_removal_mode 0)
			)
			(polygon
				(pts
					(arc
						(start 467.87308 -53.449728)
						(mid 464.62188 -53.449728)
						(end 467.87308 -53.449728)
					)
				)
			)
		)
	)
	(footprint ""
		(layer "F.Cu")
		(at 25.27808 -258.091686)
		(property "Reference" "J21"
			(at -0.325882 -81.821274 0)
			(unlocked yes)
			(layer "F.SilkS")
			(effects
				(font
					(size 0.7874 0.5842)
					(thickness 0.1524)
				)
				(justify left)
			)
		)
		(property "Value" ""
			(at 0 0 0)
			(layer "F.Fab")
			(effects
				(font
					(size 1.27 1.27)
				)
			)
		)
		(duplicate_pad_numbers_are_jumpers no)
		(fp_line
			(start -3.24993 -79.573374)
			(end -3.24993 -76.342494)
			(stroke
				(width 0.1524)
				(type default)
			)
			(layer "F.SilkS")
		)
		(fp_line
			(start -3.24993 -72.583294)
			(end -3.24993 74.487786)
			(stroke
				(width 0.1524)
				(type default)
			)
			(layer "F.SilkS")
		)
		(fp_line
			(start -3.24993 80.035146)
			(end -3.24993 81.000092)
			(stroke
				(width 0.1524)
				(type default)
			)
			(layer "F.SilkS")
		)
		(fp_line
			(start -3.24993 81.000092)
			(end -2.5019 81.000092)
			(stroke
				(width 0.1524)
				(type default)
			)
			(layer "F.SilkS")
		)
		(fp_line
			(start 0.508 81.000092)
			(end 1.20396 81.000092)
			(stroke
				(width 0.1524)
				(type default)
			)
			(layer "F.SilkS")
		)
		(fp_line
			(start 3.24993 -81.000092)
			(end -1.43256 -81.000092)
			(stroke
				(width 0.1524)
				(type default)
			)
			(layer "F.SilkS")
		)
		(fp_line
			(start 3.24993 -72.00011)
			(end -3.24993 -72.00011)
			(stroke
				(width 0.1524)
				(type default)
			)
			(layer "F.SilkS")
		)
		(fp_line
			(start 3.24993 72.00011)
			(end -3.24993 72.00011)
			(stroke
				(width 0.1524)
				(type default)
			)
			(layer "F.SilkS")
		)
		(fp_line
			(start 3.24993 74.340466)
			(end 3.24993 -81.000092)
			(stroke
				(width 0.1524)
				(type default)
			)
			(layer "F.SilkS")
		)
		(fp_poly
			(pts
				(xy -4.268216 -62.905386) (xy -3.429 -63.324994) (xy -4.25196 -63.736474)
			)
			(stroke
				(width 0)
				(type default)
			)
			(fill yes)
			(layer "F.SilkS")
		)
		(fp_line
			(start -3.24993 -81.000092)
			(end -3.24993 81.000092)
			(stroke
				(width 0.1)
				(type default)
			)
			(layer "F.Fab")
		)
		(fp_line
			(start -3.24993 81.000092)
			(end 3.24993 81.000092)
			(stroke
				(width 0.1)
				(type default)
			)
			(layer "F.Fab")
		)
		(fp_line
			(start 3.24993 -81.000092)
			(end -3.24993 -81.000092)
			(stroke
				(width 0.1)
				(type default)
			)
			(layer "F.Fab")
		)
		(fp_line
			(start 3.24993 -72.00011)
			(end -3.24993 -72.00011)
			(stroke
				(width 0.1)
				(type default)
			)
			(layer "F.Fab")
		)
		(fp_line
			(start 3.24993 -71.000112)
			(end -3.24993 -71.000112)
			(stroke
				(width 0.1)
				(type default)
			)
			(layer "F.Fab")
		)
		(fp_line
			(start 3.24993 71.000112)
			(end -3.24993 71.000112)
			(stroke
				(width 0.1)
				(type default)
			)
			(layer "F.Fab")
		)
		(fp_line
			(start 3.24993 72.00011)
			(end -3.24993 72.00011)
			(stroke
				(width 0.1)
				(type default)
			)
			(layer "F.Fab")
		)
		(fp_line
			(start 3.24993 81.000092)
			(end 3.24993 -81.000092)
			(stroke
				(width 0.1)
				(type default)
			)
			(layer "F.Fab")
		)
		(fp_poly
			(pts
				(xy -4.445 -63.832994) (xy -4.445 -62.816994) (xy -3.429 -63.324994)
			)
			(stroke
				(width 0)
				(type default)
			)
			(fill yes)
			(layer "F.Fab")
		)
		(pad "1" smd rect
			(at -2.050034 -63.324994 270)
			(size 0.519938 1.4986)
			(layers "F.Cu" "F.Mask" "F.Paste")
			(net "P12V_S3_AUX_CPU1_NVDIMM")
		)
		(pad "2" smd rect
			(at -2.050034 -62.47511 270)
			(size 0.519938 1.4986)
			(layers "F.Cu" "F.Mask" "F.Paste")
			(net "TP_CHC_CPU1_DIMM1_FRU_0")
		)
		(pad "3" smd rect
			(at -2.050034 -61.624972 270)
			(size 0.519938 1.4986)
			(layers "F.Cu" "F.Mask" "F.Paste")
			(net "P3V3_AUX")
		)
		(pad "4" smd rect
			(at -2.050034 -60.775088 270)
			(size 0.519938 1.4986)
			(layers "F.Cu" "F.Mask" "F.Paste")
			(net "I3C_SPD_DDRABCD_CPU1_LVC1_SCL_4")
		)
		(pad "5" smd rect
			(at -2.050034 -59.92495 270)
			(size 0.519938 1.4986)
			(layers "F.Cu" "F.Mask" "F.Paste")
			(net "I3C_SPD_DDRABCD_CPU1_LVC1_SDA")
		)
		(pad "6" smd rect
			(at -2.050034 -59.075066 270)
			(size 0.519938 1.4986)
			(layers "F.Cu" "F.Mask" "F.Paste")
			(net "GND")
		)
		(pad "7" smd rect
			(at -2.050034 -58.224928 270)
			(size 0.519938 1.4986)
			(layers "F.Cu" "F.Mask" "F.Paste")
			(net "M_C_CPU1_SA_DQ<0>")
		)
		(pad "8" smd rect
			(at -2.050034 -57.375044 270)
			(size 0.519938 1.4986)
			(layers "F.Cu" "F.Mask" "F.Paste")
			(net "GND")
		)
		(pad "9" smd rect
			(at -2.050034 -56.524906 270)
			(size 0.519938 1.4986)
			(layers "F.Cu" "F.Mask" "F.Paste")
			(net "M_C_CPU1_SA_DQ<1>")
		)
		(pad "10" smd rect
			(at -2.050034 -55.675022 270)
			(size 0.519938 1.4986)
			(layers "F.Cu" "F.Mask" "F.Paste")
			(net "GND")
		)
		(pad "11" smd rect
			(at -2.050034 -54.824884 270)
			(size 0.519938 1.4986)
			(layers "F.Cu" "F.Mask" "F.Paste")
			(net "M_C_CPU1_SA_DQS_DP<0>")
		)
		(pad "12" smd rect
			(at -2.050034 -53.975 270)
			(size 0.519938 1.4986)
			(layers "F.Cu" "F.Mask" "F.Paste")
			(net "M_C_CPU1_SA_DQS_DN<0>")
		)
		(pad "13" smd rect
			(at -2.050034 -53.125116 270)
			(size 0.519938 1.4986)
			(layers "F.Cu" "F.Mask" "F.Paste")
			(net "GND")
		)
		(pad "14" smd rect
			(at -2.050034 -52.274978 270)
			(size 0.519938 1.4986)
			(layers "F.Cu" "F.Mask" "F.Paste")
			(net "M_C_CPU1_SA_DQ<4>")
		)
		(pad "15" smd rect
			(at -2.050034 -51.425094 270)
			(size 0.519938 1.4986)
			(layers "F.Cu" "F.Mask" "F.Paste")
			(net "GND")
		)
		(pad "16" smd rect
			(at -2.050034 -50.574956 270)
			(size 0.519938 1.4986)
			(layers "F.Cu" "F.Mask" "F.Paste")
			(net "M_C_CPU1_SA_DQ<5>")
		)
		(pad "17" smd rect
			(at -2.050034 -49.725072 270)
			(size 0.519938 1.4986)
			(layers "F.Cu" "F.Mask" "F.Paste")
			(net "GND")
		)
		(pad "18" smd rect
			(at -2.050034 -48.874934 270)
			(size 0.519938 1.4986)
			(layers "F.Cu" "F.Mask" "F.Paste")
			(net "M_C_CPU1_SA_DQ<8>")
		)
		(pad "19" smd rect
			(at -2.050034 -48.02505 270)
			(size 0.519938 1.4986)
			(layers "F.Cu" "F.Mask" "F.Paste")
			(net "GND")
		)
		(pad "20" smd rect
			(at -2.050034 -47.174912 270)
			(size 0.519938 1.4986)
			(layers "F.Cu" "F.Mask" "F.Paste")
			(net "M_C_CPU1_SA_DQ<9>")
		)
		(pad "21" smd rect
			(at -2.050034 -46.325028 270)
			(size 0.519938 1.4986)
			(layers "F.Cu" "F.Mask" "F.Paste")
			(net "GND")
		)
		(pad "22" smd rect
			(at -2.050034 -45.47489 270)
			(size 0.519938 1.4986)
			(layers "F.Cu" "F.Mask" "F.Paste")
			(net "M_C_CPU1_SA_DQS_DP<1>")
		)
		(pad "23" smd rect
			(at -2.050034 -44.625006 270)
			(size 0.519938 1.4986)
			(layers "F.Cu" "F.Mask" "F.Paste")
			(net "M_C_CPU1_SA_DQS_DN<1>")
		)
		(pad "24" smd rect
			(at -2.050034 -43.775122 270)
			(size 0.519938 1.4986)
			(layers "F.Cu" "F.Mask" "F.Paste")
			(net "GND")
		)
		(pad "25" smd rect
			(at -2.050034 -42.924984 270)
			(size 0.519938 1.4986)
			(layers "F.Cu" "F.Mask" "F.Paste")
			(net "M_C_CPU1_SA_DQ<12>")
		)
		(pad "26" smd rect
			(at -2.050034 -42.0751 270)
			(size 0.519938 1.4986)
			(layers "F.Cu" "F.Mask" "F.Paste")
			(net "GND")
		)
		(pad "27" smd rect
			(at -2.050034 -41.224962 270)
			(size 0.519938 1.4986)
			(layers "F.Cu" "F.Mask" "F.Paste")
			(net "M_C_CPU1_SA_DQ<13>")
		)
		(pad "28" smd rect
			(at -2.050034 -40.375078 270)
			(size 0.519938 1.4986)
			(layers "F.Cu" "F.Mask" "F.Paste")
			(net "GND")
		)
		(pad "29" smd rect
			(at -2.050034 -39.52494 270)
			(size 0.519938 1.4986)
			(layers "F.Cu" "F.Mask" "F.Paste")
			(net "M_C_CPU1_SA_DQ<16>")
		)
		(pad "30" smd rect
			(at -2.050034 -38.675056 270)
			(size 0.519938 1.4986)
			(layers "F.Cu" "F.Mask" "F.Paste")
			(net "GND")
		)
		(pad "31" smd rect
			(at -2.050034 -37.824918 270)
			(size 0.519938 1.4986)
			(layers "F.Cu" "F.Mask" "F.Paste")
			(net "M_C_CPU1_SA_DQ<17>")
		)
		(pad "32" smd rect
			(at -2.050034 -36.975034 270)
			(size 0.519938 1.4986)
			(layers "F.Cu" "F.Mask" "F.Paste")
			(net "GND")
		)
		(pad "33" smd rect
			(at -2.050034 -36.124896 270)
			(size 0.519938 1.4986)
			(layers "F.Cu" "F.Mask" "F.Paste")
			(net "M_C_CPU1_SA_DQS_DP<2>")
		)
		(pad "34" smd rect
			(at -2.050034 -35.275012 270)
			(size 0.519938 1.4986)
			(layers "F.Cu" "F.Mask" "F.Paste")
			(net "M_C_CPU1_SA_DQS_DN<2>")
		)
		(pad "35" smd rect
			(at -2.050034 -34.425128 270)
			(size 0.519938 1.4986)
			(layers "F.Cu" "F.Mask" "F.Paste")
			(net "GND")
		)
		(pad "36" smd rect
			(at -2.050034 -33.57499 270)
			(size 0.519938 1.4986)
			(layers "F.Cu" "F.Mask" "F.Paste")
			(net "M_C_CPU1_SA_DQ<20>")
		)
		(pad "37" smd rect
			(at -2.050034 -32.725106 270)
			(size 0.519938 1.4986)
			(layers "F.Cu" "F.Mask" "F.Paste")
			(net "GND")
		)
		(pad "38" smd rect
			(at -2.050034 -31.874968 270)
			(size 0.519938 1.4986)
			(layers "F.Cu" "F.Mask" "F.Paste")
			(net "M_C_CPU1_SA_DQ<21>")
		)
		(pad "39" smd rect
			(at -2.050034 -31.025084 270)
			(size 0.519938 1.4986)
			(layers "F.Cu" "F.Mask" "F.Paste")
			(net "GND")
		)
		(pad "40" smd rect
			(at -2.050034 -30.174946 270)
			(size 0.519938 1.4986)
			(layers "F.Cu" "F.Mask" "F.Paste")
			(net "M_C_CPU1_SA_DQ<24>")
		)
		(pad "41" smd rect
			(at -2.050034 -29.325062 270)
			(size 0.519938 1.4986)
			(layers "F.Cu" "F.Mask" "F.Paste")
			(net "GND")
		)
		(pad "42" smd rect
			(at -2.050034 -28.474924 270)
			(size 0.519938 1.4986)
			(layers "F.Cu" "F.Mask" "F.Paste")
			(net "M_C_CPU1_SA_DQ<25>")
		)
		(pad "43" smd rect
			(at -2.050034 -27.62504 270)
			(size 0.519938 1.4986)
			(layers "F.Cu" "F.Mask" "F.Paste")
			(net "GND")
		)
		(pad "44" smd rect
			(at -2.050034 -26.774902 270)
			(size 0.519938 1.4986)
			(layers "F.Cu" "F.Mask" "F.Paste")
			(net "M_C_CPU1_SA_DQS_DP<3>")
		)
		(pad "45" smd rect
			(at -2.050034 -25.925018 270)
			(size 0.519938 1.4986)
			(layers "F.Cu" "F.Mask" "F.Paste")
			(net "M_C_CPU1_SA_DQS_DN<3>")
		)
		(pad "46" smd rect
			(at -2.050034 -25.07488 270)
			(size 0.519938 1.4986)
			(layers "F.Cu" "F.Mask" "F.Paste")
			(net "GND")
		)
		(pad "47" smd rect
			(at -2.050034 -24.224996 270)
			(size 0.519938 1.4986)
			(layers "F.Cu" "F.Mask" "F.Paste")
			(net "M_C_CPU1_SA_DQ<28>")
		)
		(pad "48" smd rect
			(at -2.050034 -23.375112 270)
			(size 0.519938 1.4986)
			(layers "F.Cu" "F.Mask" "F.Paste")
			(net "GND")
		)
		(pad "49" smd rect
			(at -2.050034 -22.524974 270)
			(size 0.519938 1.4986)
			(layers "F.Cu" "F.Mask" "F.Paste")
			(net "M_C_CPU1_SA_DQ<29>")
		)
		(pad "50" smd rect
			(at -2.050034 -21.67509 270)
			(size 0.519938 1.4986)
			(layers "F.Cu" "F.Mask" "F.Paste")
			(net "GND")
		)
		(pad "51" smd rect
			(at -2.050034 -20.824952 270)
			(size 0.519938 1.4986)
			(layers "F.Cu" "F.Mask" "F.Paste")
			(net "M_C_CPU1_SA_CB<0>")
		)
		(pad "52" smd rect
			(at -2.050034 -19.975068 270)
			(size 0.519938 1.4986)
			(layers "F.Cu" "F.Mask" "F.Paste")
			(net "GND")
		)
		(pad "53" smd rect
			(at -2.050034 -19.12493 270)
			(size 0.519938 1.4986)
			(layers "F.Cu" "F.Mask" "F.Paste")
			(net "M_C_CPU1_SA_CB<1>")
		)
		(pad "54" smd rect
			(at -2.050034 -18.275046 270)
			(size 0.519938 1.4986)
			(layers "F.Cu" "F.Mask" "F.Paste")
			(net "GND")
		)
		(pad "55" smd rect
			(at -2.050034 -17.424908 270)
			(size 0.519938 1.4986)
			(layers "F.Cu" "F.Mask" "F.Paste")
			(net "M_C_CPU1_SA_DQS_DP<4>")
		)
		(pad "56" smd rect
			(at -2.050034 -16.575024 270)
			(size 0.519938 1.4986)
			(layers "F.Cu" "F.Mask" "F.Paste")
			(net "M_C_CPU1_SA_DQS_DN<4>")
		)
		(pad "57" smd rect
			(at -2.050034 -15.724886 270)
			(size 0.519938 1.4986)
			(layers "F.Cu" "F.Mask" "F.Paste")
			(net "GND")
		)
		(pad "58" smd rect
			(at -2.050034 -14.875002 270)
			(size 0.519938 1.4986)
			(layers "F.Cu" "F.Mask" "F.Paste")
			(net "M_C_CPU1_SA_CB<4>")
		)
		(pad "59" smd rect
			(at -2.050034 -14.025118 270)
			(size 0.519938 1.4986)
			(layers "F.Cu" "F.Mask" "F.Paste")
			(net "GND")
		)
		(pad "60" smd rect
			(at -2.050034 -13.17498 270)
			(size 0.519938 1.4986)
			(layers "F.Cu" "F.Mask" "F.Paste")
			(net "M_C_CPU1_SA_CB<5>")
		)
		(pad "61" smd rect
			(at -2.050034 -12.325096 270)
			(size 0.519938 1.4986)
			(layers "F.Cu" "F.Mask" "F.Paste")
			(net "GND")
		)
		(pad "62" smd rect
			(at -2.050034 -11.474958 270)
			(size 0.519938 1.4986)
			(layers "F.Cu" "F.Mask" "F.Paste")
			(net "M_C_CPU1_ALERT_N")
		)
		(pad "63" smd rect
			(at -2.050034 -10.625074 270)
			(size 0.519938 1.4986)
			(layers "F.Cu" "F.Mask" "F.Paste")
			(net "GND")
		)
		(pad "64" smd rect
			(at -2.050034 -9.774936 270)
			(size 0.519938 1.4986)
			(layers "F.Cu" "F.Mask" "F.Paste")
			(net "M_C_CPU1_SA_CS_N<0>")
		)
		(pad "65" smd rect
			(at -2.050034 -8.925052 270)
			(size 0.519938 1.4986)
			(layers "F.Cu" "F.Mask" "F.Paste")
			(net "GND")
		)
		(pad "66" smd rect
			(at -2.050034 -8.074914 270)
			(size 0.519938 1.4986)
			(layers "F.Cu" "F.Mask" "F.Paste")
			(net "M_C_CPU1_SA_CA<0>")
		)
		(pad "67" smd rect
			(at -2.050034 -7.22503 270)
			(size 0.519938 1.4986)
			(layers "F.Cu" "F.Mask" "F.Paste")
			(net "GND")
		)
		(pad "68" smd rect
			(at -2.050034 -6.374892 270)
			(size 0.519938 1.4986)
			(layers "F.Cu" "F.Mask" "F.Paste")
			(net "M_C_CPU1_SA_CA<2>")
		)
		(pad "69" smd rect
			(at -2.050034 -5.525008 270)
			(size 0.519938 1.4986)
			(layers "F.Cu" "F.Mask" "F.Paste")
			(net "GND")
		)
		(pad "70" smd rect
			(at -2.050034 -4.675124 270)
			(size 0.519938 1.4986)
			(layers "F.Cu" "F.Mask" "F.Paste")
			(net "M_C_CPU1_SA_CA<4>")
		)
		(pad "71" smd rect
			(at -2.050034 -3.824986 270)
			(size 0.519938 1.4986)
			(layers "F.Cu" "F.Mask" "F.Paste")
			(net "GND")
		)
		(pad "72" smd rect
			(at -2.050034 -2.975102 270)
			(size 0.519938 1.4986)
			(layers "F.Cu" "F.Mask" "F.Paste")
			(net "M_C_CPU1_SA_CA<6>")
		)
		(pad "73" smd rect
			(at -2.050034 -2.124964 270)
			(size 0.519938 1.4986)
			(layers "F.Cu" "F.Mask" "F.Paste")
			(net "GND")
		)
		(pad "74" smd rect
			(at -2.050034 -1.27508 270)
			(size 0.519938 1.4986)
			(layers "F.Cu" "F.Mask" "F.Paste")
			(net "M_C_CPU1_SA_PAR")
		)
		(pad "75" smd rect
			(at -2.050034 -0.424942 270)
			(size 0.519938 1.4986)
			(layers "F.Cu" "F.Mask" "F.Paste")
			(net "GND")
		)
		(pad "76" smd rect
			(at -2.050034 5.525008 270)
			(size 0.519938 1.4986)
			(layers "F.Cu" "F.Mask" "F.Paste")
			(net "M_C_CPU1_SB_CA<0>")
		)
		(pad "77" smd rect
			(at -2.050034 6.374892 270)
			(size 0.519938 1.4986)
			(layers "F.Cu" "F.Mask" "F.Paste")
			(net "GND")
		)
		(pad "78" smd rect
			(at -2.050034 7.22503 270)
			(size 0.519938 1.4986)
			(layers "F.Cu" "F.Mask" "F.Paste")
			(net "M_C_CPU1_SB_CA<2>")
		)
		(pad "79" smd rect
			(at -2.050034 8.074914 270)
			(size 0.519938 1.4986)
			(layers "F.Cu" "F.Mask" "F.Paste")
			(net "GND")
		)
		(pad "80" smd rect
			(at -2.050034 8.925052 270)
			(size 0.519938 1.4986)
			(layers "F.Cu" "F.Mask" "F.Paste")
			(net "M_C_CPU1_SB_CA<4>")
		)
		(pad "81" smd rect
			(at -2.050034 9.774936 270)
			(size 0.519938 1.4986)
			(layers "F.Cu" "F.Mask" "F.Paste")
			(net "GND")
		)
		(pad "82" smd rect
			(at -2.050034 10.625074 270)
			(size 0.519938 1.4986)
			(layers "F.Cu" "F.Mask" "F.Paste")
			(net "M_C_CPU1_SB_CA<6>")
		)
		(pad "83" smd rect
			(at -2.050034 11.474958 270)
			(size 0.519938 1.4986)
			(layers "F.Cu" "F.Mask" "F.Paste")
			(net "GND")
		)
		(pad "84" smd rect
			(at -2.050034 12.325096 270)
			(size 0.519938 1.4986)
			(layers "F.Cu" "F.Mask" "F.Paste")
			(net "M_C_CPU1_SB_CS_N<0>")
		)
		(pad "85" smd rect
			(at -2.050034 13.17498 270)
			(size 0.519938 1.4986)
			(layers "F.Cu" "F.Mask" "F.Paste")
			(net "GND")
		)
		(pad "86" smd rect
			(at -2.050034 14.025118 270)
			(size 0.519938 1.4986)
			(layers "F.Cu" "F.Mask" "F.Paste")
			(net "M_C_CPU1_SA_RSP<0>")
		)
		(pad "87" smd rect
			(at -2.050034 14.875002 270)
			(size 0.519938 1.4986)
			(layers "F.Cu" "F.Mask" "F.Paste")
			(net "M_C_CPU1_SB_RSP<0>")
		)
		(pad "88" smd rect
			(at -2.050034 15.724886 270)
			(size 0.519938 1.4986)
			(layers "F.Cu" "F.Mask" "F.Paste")
			(net "GND")
		)
		(pad "89" smd rect
			(at -2.050034 16.575024 270)
			(size 0.519938 1.4986)
			(layers "F.Cu" "F.Mask" "F.Paste")
			(net "M_C_CPU1_SB_CB<4>")
		)
		(pad "90" smd rect
			(at -2.050034 17.424908 270)
			(size 0.519938 1.4986)
			(layers "F.Cu" "F.Mask" "F.Paste")
			(net "GND")
		)
		(pad "91" smd rect
			(at -2.050034 18.275046 270)
			(size 0.519938 1.4986)
			(layers "F.Cu" "F.Mask" "F.Paste")
			(net "M_C_CPU1_SB_CB<5>")
		)
		(pad "92" smd rect
			(at -2.050034 19.12493 270)
			(size 0.519938 1.4986)
			(layers "F.Cu" "F.Mask" "F.Paste")
			(net "GND")
		)
		(pad "93" smd rect
			(at -2.050034 19.975068 270)
			(size 0.519938 1.4986)
			(layers "F.Cu" "F.Mask" "F.Paste")
			(net "M_C_CPU1_SB_DQS_DP<9>")
		)
		(pad "94" smd rect
			(at -2.050034 20.824952 270)
			(size 0.519938 1.4986)
			(layers "F.Cu" "F.Mask" "F.Paste")
			(net "M_C_CPU1_SB_DQS_DN<9>")
		)
		(pad "95" smd rect
			(at -2.050034 21.67509 270)
			(size 0.519938 1.4986)
			(layers "F.Cu" "F.Mask" "F.Paste")
			(net "GND")
		)
		(pad "96" smd rect
			(at -2.050034 22.524974 270)
			(size 0.519938 1.4986)
			(layers "F.Cu" "F.Mask" "F.Paste")
			(net "M_C_CPU1_SB_CB<0>")
		)
		(pad "97" smd rect
			(at -2.050034 23.375112 270)
			(size 0.519938 1.4986)
			(layers "F.Cu" "F.Mask" "F.Paste")
			(net "GND")
		)
		(pad "98" smd rect
			(at -2.050034 24.224996 270)
			(size 0.519938 1.4986)
			(layers "F.Cu" "F.Mask" "F.Paste")
			(net "M_C_CPU1_SB_CB<1>")
		)
		(pad "99" smd rect
			(at -2.050034 25.07488 270)
			(size 0.519938 1.4986)
			(layers "F.Cu" "F.Mask" "F.Paste")
			(net "GND")
		)
		(pad "100" smd rect
			(at -2.050034 25.925018 270)
			(size 0.519938 1.4986)
			(layers "F.Cu" "F.Mask" "F.Paste")
			(net "M_C_CPU1_SB_DQ<0>")
		)
		(pad "101" smd rect
			(at -2.050034 26.774902 270)
			(size 0.519938 1.4986)
			(layers "F.Cu" "F.Mask" "F.Paste")
			(net "GND")
		)
		(pad "102" smd rect
			(at -2.050034 27.62504 270)
			(size 0.519938 1.4986)
			(layers "F.Cu" "F.Mask" "F.Paste")
			(net "M_C_CPU1_SB_DQ<1>")
		)
		(pad "103" smd rect
			(at -2.050034 28.474924 270)
			(size 0.519938 1.4986)
			(layers "F.Cu" "F.Mask" "F.Paste")
			(net "GND")
		)
		(pad "104" smd rect
			(at -2.050034 29.325062 270)
			(size 0.519938 1.4986)
			(layers "F.Cu" "F.Mask" "F.Paste")
			(net "M_C_CPU1_SB_DQS_DP<0>")
		)
		(pad "105" smd rect
			(at -2.050034 30.174946 270)
			(size 0.519938 1.4986)
			(layers "F.Cu" "F.Mask" "F.Paste")
			(net "M_C_CPU1_SB_DQS_DN<0>")
		)
		(pad "106" smd rect
			(at -2.050034 31.025084 270)
			(size 0.519938 1.4986)
			(layers "F.Cu" "F.Mask" "F.Paste")
			(net "GND")
		)
		(pad "107" smd rect
			(at -2.050034 31.874968 270)
			(size 0.519938 1.4986)
			(layers "F.Cu" "F.Mask" "F.Paste")
			(net "M_C_CPU1_SB_DQ<4>")
		)
		(pad "108" smd rect
			(at -2.050034 32.725106 270)
			(size 0.519938 1.4986)
			(layers "F.Cu" "F.Mask" "F.Paste")
			(net "GND")
		)
		(pad "109" smd rect
			(at -2.050034 33.57499 270)
			(size 0.519938 1.4986)
			(layers "F.Cu" "F.Mask" "F.Paste")
			(net "M_C_CPU1_SB_DQ<5>")
		)
		(pad "110" smd rect
			(at -2.050034 34.425128 270)
			(size 0.519938 1.4986)
			(layers "F.Cu" "F.Mask" "F.Paste")
			(net "GND")
		)
		(pad "111" smd rect
			(at -2.050034 35.275012 270)
			(size 0.519938 1.4986)
			(layers "F.Cu" "F.Mask" "F.Paste")
			(net "M_C_CPU1_SB_DQ<8>")
		)
		(pad "112" smd rect
			(at -2.050034 36.124896 270)
			(size 0.519938 1.4986)
			(layers "F.Cu" "F.Mask" "F.Paste")
			(net "GND")
		)
		(pad "113" smd rect
			(at -2.050034 36.975034 270)
			(size 0.519938 1.4986)
			(layers "F.Cu" "F.Mask" "F.Paste")
			(net "M_C_CPU1_SB_DQ<9>")
		)
		(pad "114" smd rect
			(at -2.050034 37.824918 270)
			(size 0.519938 1.4986)
			(layers "F.Cu" "F.Mask" "F.Paste")
			(net "GND")
		)
		(pad "115" smd rect
			(at -2.050034 38.675056 270)
			(size 0.519938 1.4986)
			(layers "F.Cu" "F.Mask" "F.Paste")
			(net "M_C_CPU1_SB_DQS_DP<1>")
		)
		(pad "116" smd rect
			(at -2.050034 39.52494 270)
			(size 0.519938 1.4986)
			(layers "F.Cu" "F.Mask" "F.Paste")
			(net "M_C_CPU1_SB_DQS_DN<1>")
		)
		(pad "117" smd rect
			(at -2.050034 40.375078 270)
			(size 0.519938 1.4986)
			(layers "F.Cu" "F.Mask" "F.Paste")
			(net "GND")
		)
		(pad "118" smd rect
			(at -2.050034 41.224962 270)
			(size 0.519938 1.4986)
			(layers "F.Cu" "F.Mask" "F.Paste")
			(net "M_C_CPU1_SB_DQ<12>")
		)
		(pad "119" smd rect
			(at -2.050034 42.0751 270)
			(size 0.519938 1.4986)
			(layers "F.Cu" "F.Mask" "F.Paste")
			(net "GND")
		)
		(pad "120" smd rect
			(at -2.050034 42.924984 270)
			(size 0.519938 1.4986)
			(layers "F.Cu" "F.Mask" "F.Paste")
			(net "M_C_CPU1_SB_DQ<13>")
		)
		(pad "121" smd rect
			(at -2.050034 43.775122 270)
			(size 0.519938 1.4986)
			(layers "F.Cu" "F.Mask" "F.Paste")
			(net "GND")
		)
		(pad "122" smd rect
			(at -2.050034 44.625006 270)
			(size 0.519938 1.4986)
			(layers "F.Cu" "F.Mask" "F.Paste")
			(net "M_C_CPU1_SB_DQ<16>")
		)
		(pad "123" smd rect
			(at -2.050034 45.47489 270)
			(size 0.519938 1.4986)
			(layers "F.Cu" "F.Mask" "F.Paste")
			(net "GND")
		)
		(pad "124" smd rect
			(at -2.050034 46.325028 270)
			(size 0.519938 1.4986)
			(layers "F.Cu" "F.Mask" "F.Paste")
			(net "M_C_CPU1_SB_DQ<17>")
		)
		(pad "125" smd rect
			(at -2.050034 47.174912 270)
			(size 0.519938 1.4986)
			(layers "F.Cu" "F.Mask" "F.Paste")
			(net "GND")
		)
		(pad "126" smd rect
			(at -2.050034 48.02505 270)
			(size 0.519938 1.4986)
			(layers "F.Cu" "F.Mask" "F.Paste")
			(net "M_C_CPU1_SB_DQS_DP<2>")
		)
		(pad "127" smd rect
			(at -2.050034 48.874934 270)
			(size 0.519938 1.4986)
			(layers "F.Cu" "F.Mask" "F.Paste")
			(net "M_C_CPU1_SB_DQS_DN<2>")
		)
		(pad "128" smd rect
			(at -2.050034 49.725072 270)
			(size 0.519938 1.4986)
			(layers "F.Cu" "F.Mask" "F.Paste")
			(net "GND")
		)
		(pad "129" smd rect
			(at -2.050034 50.574956 270)
			(size 0.519938 1.4986)
			(layers "F.Cu" "F.Mask" "F.Paste")
			(net "M_C_CPU1_SB_DQ<20>")
		)
		(pad "130" smd rect
			(at -2.050034 51.425094 270)
			(size 0.519938 1.4986)
			(layers "F.Cu" "F.Mask" "F.Paste")
			(net "GND")
		)
		(pad "131" smd rect
			(at -2.050034 52.274978 270)
			(size 0.519938 1.4986)
			(layers "F.Cu" "F.Mask" "F.Paste")
			(net "M_C_CPU1_SB_DQ<21>")
		)
		(pad "132" smd rect
			(at -2.050034 53.125116 270)
			(size 0.519938 1.4986)
			(layers "F.Cu" "F.Mask" "F.Paste")
			(net "GND")
		)
		(pad "133" smd rect
			(at -2.050034 53.975 270)
			(size 0.519938 1.4986)
			(layers "F.Cu" "F.Mask" "F.Paste")
			(net "M_C_CPU1_SB_DQ<24>")
		)
		(pad "134" smd rect
			(at -2.050034 54.824884 270)
			(size 0.519938 1.4986)
			(layers "F.Cu" "F.Mask" "F.Paste")
			(net "GND")
		)
		(pad "135" smd rect
			(at -2.050034 55.675022 270)
			(size 0.519938 1.4986)
			(layers "F.Cu" "F.Mask" "F.Paste")
			(net "M_C_CPU1_SB_DQ<25>")
		)
		(pad "136" smd rect
			(at -2.050034 56.524906 270)
			(size 0.519938 1.4986)
			(layers "F.Cu" "F.Mask" "F.Paste")
			(net "GND")
		)
		(pad "137" smd rect
			(at -2.050034 57.375044 270)
			(size 0.519938 1.4986)
			(layers "F.Cu" "F.Mask" "F.Paste")
			(net "M_C_CPU1_SB_DQS_DP<3>")
		)
		(pad "138" smd rect
			(at -2.050034 58.224928 270)
			(size 0.519938 1.4986)
			(layers "F.Cu" "F.Mask" "F.Paste")
			(net "M_C_CPU1_SB_DQS_DN<3>")
		)
		(pad "139" smd rect
			(at -2.050034 59.075066 270)
			(size 0.519938 1.4986)
			(layers "F.Cu" "F.Mask" "F.Paste")
			(net "GND")
		)
		(pad "140" smd rect
			(at -2.050034 59.92495 270)
			(size 0.519938 1.4986)
			(layers "F.Cu" "F.Mask" "F.Paste")
			(net "M_C_CPU1_SB_DQ<28>")
		)
		(pad "141" smd rect
			(at -2.050034 60.775088 270)
			(size 0.519938 1.4986)
			(layers "F.Cu" "F.Mask" "F.Paste")
			(net "GND")
		)
		(pad "142" smd rect
			(at -2.050034 61.624972 270)
			(size 0.519938 1.4986)
			(layers "F.Cu" "F.Mask" "F.Paste")
			(net "M_C_CPU1_SB_DQ<29>")
		)
		(pad "143" smd rect
			(at -2.050034 62.47511 270)
			(size 0.519938 1.4986)
			(layers "F.Cu" "F.Mask" "F.Paste")
			(net "GND")
		)
		(pad "144" smd rect
			(at -2.050034 63.324994 270)
			(size 0.519938 1.4986)
			(layers "F.Cu" "F.Mask" "F.Paste")
			(net "TP_CHC_CPU1_DIMM1_FRU_1")
		)
		(pad "145" smd rect
			(at 2.050034 -63.324994 270)
			(size 0.519938 1.4986)
			(layers "F.Cu" "F.Mask" "F.Paste")
			(net "P12V_S3_AUX_CPU1_NVDIMM")
		)
		(pad "146" smd rect
			(at 2.050034 -62.47511 270)
			(size 0.519938 1.4986)
			(layers "F.Cu" "F.Mask" "F.Paste")
			(net "P12V_S3_AUX_CPU1_NVDIMM")
		)
		(pad "147" smd rect
			(at 2.050034 -61.624972 270)
			(size 0.519938 1.4986)
			(layers "F.Cu" "F.Mask" "F.Paste")
			(net "PWRGD_CHC_CPU1_DIMM1")
		)
		(pad "148" smd rect
			(at 2.050034 -60.775088 270)
			(size 0.519938 1.4986)
			(layers "F.Cu" "F.Mask" "F.Paste")
			(net "PD_CHC_CPU1_DIMM1_SAA")
		)
		(pad "149" smd rect
			(at 2.050034 -59.92495 270)
			(size 0.519938 1.4986)
			(layers "F.Cu" "F.Mask" "F.Paste")
			(net "TP_CHC_CPU1_DIMM1_FRU_2")
		)
		(pad "150" smd rect
			(at 2.050034 -59.075066 270)
			(size 0.519938 1.4986)
			(layers "F.Cu" "F.Mask" "F.Paste")
			(net "TP_CHC_CPU1_DIMM1_FRU_3")
		)
		(pad "151" smd rect
			(at 2.050034 -58.224928 270)
			(size 0.519938 1.4986)
			(layers "F.Cu" "F.Mask" "F.Paste")
			(net "GND")
		)
		(pad "152" smd rect
			(at 2.050034 -57.375044 270)
			(size 0.519938 1.4986)
			(layers "F.Cu" "F.Mask" "F.Paste")
			(net "M_C_CPU1_SA_DQ<2>")
		)
		(pad "153" smd rect
			(at 2.050034 -56.524906 270)
			(size 0.519938 1.4986)
			(layers "F.Cu" "F.Mask" "F.Paste")
			(net "GND")
		)
		(pad "154" smd rect
			(at 2.050034 -55.675022 270)
			(size 0.519938 1.4986)
			(layers "F.Cu" "F.Mask" "F.Paste")
			(net "M_C_CPU1_SA_DQ<3>")
		)
		(pad "155" smd rect
			(at 2.050034 -54.824884 270)
			(size 0.519938 1.4986)
			(layers "F.Cu" "F.Mask" "F.Paste")
			(net "GND")
		)
		(pad "156" smd rect
			(at 2.050034 -53.975 270)
			(size 0.519938 1.4986)
			(layers "F.Cu" "F.Mask" "F.Paste")
			(net "M_C_CPU1_SA_DQS_DN<5>")
		)
		(pad "157" smd rect
			(at 2.050034 -53.125116 270)
			(size 0.519938 1.4986)
			(layers "F.Cu" "F.Mask" "F.Paste")
			(net "M_C_CPU1_SA_DQS_DP<5>")
		)
		(pad "158" smd rect
			(at 2.050034 -52.274978 270)
			(size 0.519938 1.4986)
			(layers "F.Cu" "F.Mask" "F.Paste")
			(net "GND")
		)
		(pad "159" smd rect
			(at 2.050034 -51.425094 270)
			(size 0.519938 1.4986)
			(layers "F.Cu" "F.Mask" "F.Paste")
			(net "M_C_CPU1_SA_DQ<6>")
		)
		(pad "160" smd rect
			(at 2.050034 -50.574956 270)
			(size 0.519938 1.4986)
			(layers "F.Cu" "F.Mask" "F.Paste")
			(net "GND")
		)
		(pad "161" smd rect
			(at 2.050034 -49.725072 270)
			(size 0.519938 1.4986)
			(layers "F.Cu" "F.Mask" "F.Paste")
			(net "M_C_CPU1_SA_DQ<7>")
		)
		(pad "162" smd rect
			(at 2.050034 -48.874934 270)
			(size 0.519938 1.4986)
			(layers "F.Cu" "F.Mask" "F.Paste")
			(net "GND")
		)
		(pad "163" smd rect
			(at 2.050034 -48.02505 270)
			(size 0.519938 1.4986)
			(layers "F.Cu" "F.Mask" "F.Paste")
			(net "M_C_CPU1_SA_DQ<10>")
		)
		(pad "164" smd rect
			(at 2.050034 -47.174912 270)
			(size 0.519938 1.4986)
			(layers "F.Cu" "F.Mask" "F.Paste")
			(net "GND")
		)
		(pad "165" smd rect
			(at 2.050034 -46.325028 270)
			(size 0.519938 1.4986)
			(layers "F.Cu" "F.Mask" "F.Paste")
			(net "M_C_CPU1_SA_DQ<11>")
		)
		(pad "166" smd rect
			(at 2.050034 -45.47489 270)
			(size 0.519938 1.4986)
			(layers "F.Cu" "F.Mask" "F.Paste")
			(net "GND")
		)
		(pad "167" smd rect
			(at 2.050034 -44.625006 270)
			(size 0.519938 1.4986)
			(layers "F.Cu" "F.Mask" "F.Paste")
			(net "M_C_CPU1_SA_DQS_DN<6>")
		)
		(pad "168" smd rect
			(at 2.050034 -43.775122 270)
			(size 0.519938 1.4986)
			(layers "F.Cu" "F.Mask" "F.Paste")
			(net "M_C_CPU1_SA_DQS_DP<6>")
		)
		(pad "169" smd rect
			(at 2.050034 -42.924984 270)
			(size 0.519938 1.4986)
			(layers "F.Cu" "F.Mask" "F.Paste")
			(net "GND")
		)
		(pad "170" smd rect
			(at 2.050034 -42.0751 270)
			(size 0.519938 1.4986)
			(layers "F.Cu" "F.Mask" "F.Paste")
			(net "M_C_CPU1_SA_DQ<14>")
		)
		(pad "171" smd rect
			(at 2.050034 -41.224962 270)
			(size 0.519938 1.4986)
			(layers "F.Cu" "F.Mask" "F.Paste")
			(net "GND")
		)
		(pad "172" smd rect
			(at 2.050034 -40.375078 270)
			(size 0.519938 1.4986)
			(layers "F.Cu" "F.Mask" "F.Paste")
			(net "M_C_CPU1_SA_DQ<15>")
		)
		(pad "173" smd rect
			(at 2.050034 -39.52494 270)
			(size 0.519938 1.4986)
			(layers "F.Cu" "F.Mask" "F.Paste")
			(net "GND")
		)
		(pad "174" smd rect
			(at 2.050034 -38.675056 270)
			(size 0.519938 1.4986)
			(layers "F.Cu" "F.Mask" "F.Paste")
			(net "M_C_CPU1_SA_DQ<18>")
		)
		(pad "175" smd rect
			(at 2.050034 -37.824918 270)
			(size 0.519938 1.4986)
			(layers "F.Cu" "F.Mask" "F.Paste")
			(net "GND")
		)
		(pad "176" smd rect
			(at 2.050034 -36.975034 270)
			(size 0.519938 1.4986)
			(layers "F.Cu" "F.Mask" "F.Paste")
			(net "M_C_CPU1_SA_DQ<19>")
		)
		(pad "177" smd rect
			(at 2.050034 -36.124896 270)
			(size 0.519938 1.4986)
			(layers "F.Cu" "F.Mask" "F.Paste")
			(net "GND")
		)
		(pad "178" smd rect
			(at 2.050034 -35.275012 270)
			(size 0.519938 1.4986)
			(layers "F.Cu" "F.Mask" "F.Paste")
			(net "M_C_CPU1_SA_DQS_DN<7>")
		)
		(pad "179" smd rect
			(at 2.050034 -34.425128 270)
			(size 0.519938 1.4986)
			(layers "F.Cu" "F.Mask" "F.Paste")
			(net "M_C_CPU1_SA_DQS_DP<7>")
		)
		(pad "180" smd rect
			(at 2.050034 -33.57499 270)
			(size 0.519938 1.4986)
			(layers "F.Cu" "F.Mask" "F.Paste")
			(net "GND")
		)
		(pad "181" smd rect
			(at 2.050034 -32.725106 270)
			(size 0.519938 1.4986)
			(layers "F.Cu" "F.Mask" "F.Paste")
			(net "M_C_CPU1_SA_DQ<22>")
		)
		(pad "182" smd rect
			(at 2.050034 -31.874968 270)
			(size 0.519938 1.4986)
			(layers "F.Cu" "F.Mask" "F.Paste")
			(net "GND")
		)
		(pad "183" smd rect
			(at 2.050034 -31.025084 270)
			(size 0.519938 1.4986)
			(layers "F.Cu" "F.Mask" "F.Paste")
			(net "M_C_CPU1_SA_DQ<23>")
		)
		(pad "184" smd rect
			(at 2.050034 -30.174946 270)
			(size 0.519938 1.4986)
			(layers "F.Cu" "F.Mask" "F.Paste")
			(net "GND")
		)
		(pad "185" smd rect
			(at 2.050034 -29.325062 270)
			(size 0.519938 1.4986)
			(layers "F.Cu" "F.Mask" "F.Paste")
			(net "M_C_CPU1_SA_DQ<26>")
		)
		(pad "186" smd rect
			(at 2.050034 -28.474924 270)
			(size 0.519938 1.4986)
			(layers "F.Cu" "F.Mask" "F.Paste")
			(net "GND")
		)
		(pad "187" smd rect
			(at 2.050034 -27.62504 270)
			(size 0.519938 1.4986)
			(layers "F.Cu" "F.Mask" "F.Paste")
			(net "M_C_CPU1_SA_DQ<27>")
		)
		(pad "188" smd rect
			(at 2.050034 -26.774902 270)
			(size 0.519938 1.4986)
			(layers "F.Cu" "F.Mask" "F.Paste")
			(net "GND")
		)
		(pad "189" smd rect
			(at 2.050034 -25.925018 270)
			(size 0.519938 1.4986)
			(layers "F.Cu" "F.Mask" "F.Paste")
			(net "M_C_CPU1_SA_DQS_DN<8>")
		)
		(pad "190" smd rect
			(at 2.050034 -25.07488 270)
			(size 0.519938 1.4986)
			(layers "F.Cu" "F.Mask" "F.Paste")
			(net "M_C_CPU1_SA_DQS_DP<8>")
		)
		(pad "191" smd rect
			(at 2.050034 -24.224996 270)
			(size 0.519938 1.4986)
			(layers "F.Cu" "F.Mask" "F.Paste")
			(net "GND")
		)
		(pad "192" smd rect
			(at 2.050034 -23.375112 270)
			(size 0.519938 1.4986)
			(layers "F.Cu" "F.Mask" "F.Paste")
			(net "M_C_CPU1_SA_DQ<30>")
		)
		(pad "193" smd rect
			(at 2.050034 -22.524974 270)
			(size 0.519938 1.4986)
			(layers "F.Cu" "F.Mask" "F.Paste")
			(net "GND")
		)
		(pad "194" smd rect
			(at 2.050034 -21.67509 270)
			(size 0.519938 1.4986)
			(layers "F.Cu" "F.Mask" "F.Paste")
			(net "M_C_CPU1_SA_DQ<31>")
		)
		(pad "195" smd rect
			(at 2.050034 -20.824952 270)
			(size 0.519938 1.4986)
			(layers "F.Cu" "F.Mask" "F.Paste")
			(net "GND")
		)
		(pad "196" smd rect
			(at 2.050034 -19.975068 270)
			(size 0.519938 1.4986)
			(layers "F.Cu" "F.Mask" "F.Paste")
			(net "M_C_CPU1_SA_CB<2>")
		)
		(pad "197" smd rect
			(at 2.050034 -19.12493 270)
			(size 0.519938 1.4986)
			(layers "F.Cu" "F.Mask" "F.Paste")
			(net "GND")
		)
		(pad "198" smd rect
			(at 2.050034 -18.275046 270)
			(size 0.519938 1.4986)
			(layers "F.Cu" "F.Mask" "F.Paste")
			(net "M_C_CPU1_SA_CB<3>")
		)
		(pad "199" smd rect
			(at 2.050034 -17.424908 270)
			(size 0.519938 1.4986)
			(layers "F.Cu" "F.Mask" "F.Paste")
			(net "GND")
		)
		(pad "200" smd rect
			(at 2.050034 -16.575024 270)
			(size 0.519938 1.4986)
			(layers "F.Cu" "F.Mask" "F.Paste")
			(net "M_C_CPU1_SA_DQS_DN<9>")
		)
		(pad "201" smd rect
			(at 2.050034 -15.724886 270)
			(size 0.519938 1.4986)
			(layers "F.Cu" "F.Mask" "F.Paste")
			(net "M_C_CPU1_SA_DQS_DP<9>")
		)
		(pad "202" smd rect
			(at 2.050034 -14.875002 270)
			(size 0.519938 1.4986)
			(layers "F.Cu" "F.Mask" "F.Paste")
			(net "GND")
		)
		(pad "203" smd rect
			(at 2.050034 -14.025118 270)
			(size 0.519938 1.4986)
			(layers "F.Cu" "F.Mask" "F.Paste")
			(net "M_C_CPU1_SA_CB<6>")
		)
		(pad "204" smd rect
			(at 2.050034 -13.17498 270)
			(size 0.519938 1.4986)
			(layers "F.Cu" "F.Mask" "F.Paste")
			(net "GND")
		)
		(pad "205" smd rect
			(at 2.050034 -12.325096 270)
			(size 0.519938 1.4986)
			(layers "F.Cu" "F.Mask" "F.Paste")
			(net "M_C_CPU1_SA_CB<7>")
		)
		(pad "206" smd rect
			(at 2.050034 -11.474958 270)
			(size 0.519938 1.4986)
			(layers "F.Cu" "F.Mask" "F.Paste")
			(net "GND")
		)
		(pad "207" smd rect
			(at 2.050034 -10.625074 270)
			(size 0.519938 1.4986)
			(layers "F.Cu" "F.Mask" "F.Paste")
			(net "RST_M_CD_CPU1_FPGA_N")
		)
		(pad "208" smd rect
			(at 2.050034 -9.774936 270)
			(size 0.519938 1.4986)
			(layers "F.Cu" "F.Mask" "F.Paste")
			(net "GND")
		)
		(pad "209" smd rect
			(at 2.050034 -8.925052 270)
			(size 0.519938 1.4986)
			(layers "F.Cu" "F.Mask" "F.Paste")
			(net "M_C_CPU1_SA_CS_N<1>")
		)
		(pad "210" smd rect
			(at 2.050034 -8.074914 270)
			(size 0.519938 1.4986)
			(layers "F.Cu" "F.Mask" "F.Paste")
			(net "GND")
		)
		(pad "211" smd rect
			(at 2.050034 -7.22503 270)
			(size 0.519938 1.4986)
			(layers "F.Cu" "F.Mask" "F.Paste")
			(net "M_C_CPU1_SA_CA<1>")
		)
		(pad "212" smd rect
			(at 2.050034 -6.374892 270)
			(size 0.519938 1.4986)
			(layers "F.Cu" "F.Mask" "F.Paste")
			(net "GND")
		)
		(pad "213" smd rect
			(at 2.050034 -5.525008 270)
			(size 0.519938 1.4986)
			(layers "F.Cu" "F.Mask" "F.Paste")
			(net "M_C_CPU1_SA_CA<3>")
		)
		(pad "214" smd rect
			(at 2.050034 -4.675124 270)
			(size 0.519938 1.4986)
			(layers "F.Cu" "F.Mask" "F.Paste")
			(net "GND")
		)
		(pad "215" smd rect
			(at 2.050034 -3.824986 270)
			(size 0.519938 1.4986)
			(layers "F.Cu" "F.Mask" "F.Paste")
			(net "M_C_CPU1_SA_CA<5>")
		)
		(pad "216" smd rect
			(at 2.050034 -2.975102 270)
			(size 0.519938 1.4986)
			(layers "F.Cu" "F.Mask" "F.Paste")
			(net "GND")
		)
		(pad "217" smd rect
			(at 2.050034 -2.124964 270)
			(size 0.519938 1.4986)
			(layers "F.Cu" "F.Mask" "F.Paste")
			(net "M_C_CPU1_CLK_DP<0>")
		)
		(pad "218" smd rect
			(at 2.050034 -1.27508 270)
			(size 0.519938 1.4986)
			(layers "F.Cu" "F.Mask" "F.Paste")
			(net "M_C_CPU1_CLK_DN<0>")
		)
		(pad "219" smd rect
			(at 2.050034 -0.424942 270)
			(size 0.519938 1.4986)
			(layers "F.Cu" "F.Mask" "F.Paste")
			(net "GND")
		)
		(pad "220" smd rect
			(at 2.050034 5.525008 270)
			(size 0.519938 1.4986)
			(layers "F.Cu" "F.Mask" "F.Paste")
			(net "TP_CHC_CPU1_DIMM1_FRU_4")
		)
		(pad "221" smd rect
			(at 2.050034 6.374892 270)
			(size 0.519938 1.4986)
			(layers "F.Cu" "F.Mask" "F.Paste")
			(net "M_C_CPU1_SB_CA<1>")
		)
		(pad "222" smd rect
			(at 2.050034 7.22503 270)
			(size 0.519938 1.4986)
			(layers "F.Cu" "F.Mask" "F.Paste")
			(net "GND")
		)
		(pad "223" smd rect
			(at 2.050034 8.074914 270)
			(size 0.519938 1.4986)
			(layers "F.Cu" "F.Mask" "F.Paste")
			(net "M_C_CPU1_SB_CA<3>")
		)
		(pad "224" smd rect
			(at 2.050034 8.925052 270)
			(size 0.519938 1.4986)
			(layers "F.Cu" "F.Mask" "F.Paste")
			(net "GND")
		)
		(pad "225" smd rect
			(at 2.050034 9.774936 270)
			(size 0.519938 1.4986)
			(layers "F.Cu" "F.Mask" "F.Paste")
			(net "M_C_CPU1_SB_CA<5>")
		)
		(pad "226" smd rect
			(at 2.050034 10.625074 270)
			(size 0.519938 1.4986)
			(layers "F.Cu" "F.Mask" "F.Paste")
			(net "GND")
		)
		(pad "227" smd rect
			(at 2.050034 11.474958 270)
			(size 0.519938 1.4986)
			(layers "F.Cu" "F.Mask" "F.Paste")
			(net "M_C_CPU1_SB_PAR")
		)
		(pad "228" smd rect
			(at 2.050034 12.325096 270)
			(size 0.519938 1.4986)
			(layers "F.Cu" "F.Mask" "F.Paste")
			(net "GND")
		)
		(pad "229" smd rect
			(at 2.050034 13.17498 270)
			(size 0.519938 1.4986)
			(layers "F.Cu" "F.Mask" "F.Paste")
			(net "M_C_CPU1_SB_CS_N<1>")
		)
		(pad "230" smd rect
			(at 2.050034 14.025118 270)
			(size 0.519938 1.4986)
			(layers "F.Cu" "F.Mask" "F.Paste")
			(net "GND")
		)
		(pad "231" smd rect
			(at 2.050034 14.875002 270)
			(size 0.519938 1.4986)
			(layers "F.Cu" "F.Mask" "F.Paste")
			(net "TP_CHC_CPU1_DIMM1_FRU_5")
		)
		(pad "232" smd rect
			(at 2.050034 15.724886 270)
			(size 0.519938 1.4986)
			(layers "F.Cu" "F.Mask" "F.Paste")
			(net "TP_CHC_CPU1_DIMM1_FRU_6")
		)
		(pad "233" smd rect
			(at 2.050034 16.575024 270)
			(size 0.519938 1.4986)
			(layers "F.Cu" "F.Mask" "F.Paste")
			(net "GND")
		)
		(pad "234" smd rect
			(at 2.050034 17.424908 270)
			(size 0.519938 1.4986)
			(layers "F.Cu" "F.Mask" "F.Paste")
			(net "M_C_CPU1_SB_CB<6>")
		)
		(pad "235" smd rect
			(at 2.050034 18.275046 270)
			(size 0.519938 1.4986)
			(layers "F.Cu" "F.Mask" "F.Paste")
			(net "GND")
		)
		(pad "236" smd rect
			(at 2.050034 19.12493 270)
			(size 0.519938 1.4986)
			(layers "F.Cu" "F.Mask" "F.Paste")
			(net "M_C_CPU1_SB_CB<7>")
		)
		(pad "237" smd rect
			(at 2.050034 19.975068 270)
			(size 0.519938 1.4986)
			(layers "F.Cu" "F.Mask" "F.Paste")
			(net "GND")
		)
		(pad "238" smd rect
			(at 2.050034 20.824952 270)
			(size 0.519938 1.4986)
			(layers "F.Cu" "F.Mask" "F.Paste")
			(net "M_C_CPU1_SB_DQS_DN<4>")
		)
		(pad "239" smd rect
			(at 2.050034 21.67509 270)
			(size 0.519938 1.4986)
			(layers "F.Cu" "F.Mask" "F.Paste")
			(net "M_C_CPU1_SB_DQS_DP<4>")
		)
		(pad "240" smd rect
			(at 2.050034 22.524974 270)
			(size 0.519938 1.4986)
			(layers "F.Cu" "F.Mask" "F.Paste")
			(net "GND")
		)
		(pad "241" smd rect
			(at 2.050034 23.375112 270)
			(size 0.519938 1.4986)
			(layers "F.Cu" "F.Mask" "F.Paste")
			(net "M_C_CPU1_SB_CB<2>")
		)
		(pad "242" smd rect
			(at 2.050034 24.224996 270)
			(size 0.519938 1.4986)
			(layers "F.Cu" "F.Mask" "F.Paste")
			(net "GND")
		)
		(pad "243" smd rect
			(at 2.050034 25.07488 270)
			(size 0.519938 1.4986)
			(layers "F.Cu" "F.Mask" "F.Paste")
			(net "M_C_CPU1_SB_CB<3>")
		)
		(pad "244" smd rect
			(at 2.050034 25.925018 270)
			(size 0.519938 1.4986)
			(layers "F.Cu" "F.Mask" "F.Paste")
			(net "GND")
		)
		(pad "245" smd rect
			(at 2.050034 26.774902 270)
			(size 0.519938 1.4986)
			(layers "F.Cu" "F.Mask" "F.Paste")
			(net "M_C_CPU1_SB_DQ<2>")
		)
		(pad "246" smd rect
			(at 2.050034 27.62504 270)
			(size 0.519938 1.4986)
			(layers "F.Cu" "F.Mask" "F.Paste")
			(net "GND")
		)
		(pad "247" smd rect
			(at 2.050034 28.474924 270)
			(size 0.519938 1.4986)
			(layers "F.Cu" "F.Mask" "F.Paste")
			(net "M_C_CPU1_SB_DQ<3>")
		)
		(pad "248" smd rect
			(at 2.050034 29.325062 270)
			(size 0.519938 1.4986)
			(layers "F.Cu" "F.Mask" "F.Paste")
			(net "GND")
		)
		(pad "249" smd rect
			(at 2.050034 30.174946 270)
			(size 0.519938 1.4986)
			(layers "F.Cu" "F.Mask" "F.Paste")
			(net "M_C_CPU1_SB_DQS_DN<5>")
		)
		(pad "250" smd rect
			(at 2.050034 31.025084 270)
			(size 0.519938 1.4986)
			(layers "F.Cu" "F.Mask" "F.Paste")
			(net "M_C_CPU1_SB_DQS_DP<5>")
		)
		(pad "251" smd rect
			(at 2.050034 31.874968 270)
			(size 0.519938 1.4986)
			(layers "F.Cu" "F.Mask" "F.Paste")
			(net "GND")
		)
		(pad "252" smd rect
			(at 2.050034 32.725106 270)
			(size 0.519938 1.4986)
			(layers "F.Cu" "F.Mask" "F.Paste")
			(net "M_C_CPU1_SB_DQ<6>")
		)
		(pad "253" smd rect
			(at 2.050034 33.57499 270)
			(size 0.519938 1.4986)
			(layers "F.Cu" "F.Mask" "F.Paste")
			(net "GND")
		)
		(pad "254" smd rect
			(at 2.050034 34.425128 270)
			(size 0.519938 1.4986)
			(layers "F.Cu" "F.Mask" "F.Paste")
			(net "M_C_CPU1_SB_DQ<7>")
		)
		(pad "255" smd rect
			(at 2.050034 35.275012 270)
			(size 0.519938 1.4986)
			(layers "F.Cu" "F.Mask" "F.Paste")
			(net "GND")
		)
		(pad "256" smd rect
			(at 2.050034 36.124896 270)
			(size 0.519938 1.4986)
			(layers "F.Cu" "F.Mask" "F.Paste")
			(net "M_C_CPU1_SB_DQ<10>")
		)
		(pad "257" smd rect
			(at 2.050034 36.975034 270)
			(size 0.519938 1.4986)
			(layers "F.Cu" "F.Mask" "F.Paste")
			(net "GND")
		)
		(pad "258" smd rect
			(at 2.050034 37.824918 270)
			(size 0.519938 1.4986)
			(layers "F.Cu" "F.Mask" "F.Paste")
			(net "M_C_CPU1_SB_DQ<11>")
		)
		(pad "259" smd rect
			(at 2.050034 38.675056 270)
			(size 0.519938 1.4986)
			(layers "F.Cu" "F.Mask" "F.Paste")
			(net "GND")
		)
		(pad "260" smd rect
			(at 2.050034 39.52494 270)
			(size 0.519938 1.4986)
			(layers "F.Cu" "F.Mask" "F.Paste")
			(net "M_C_CPU1_SB_DQS_DN<6>")
		)
		(pad "261" smd rect
			(at 2.050034 40.375078 270)
			(size 0.519938 1.4986)
			(layers "F.Cu" "F.Mask" "F.Paste")
			(net "M_C_CPU1_SB_DQS_DP<6>")
		)
		(pad "262" smd rect
			(at 2.050034 41.224962 270)
			(size 0.519938 1.4986)
			(layers "F.Cu" "F.Mask" "F.Paste")
			(net "GND")
		)
		(pad "263" smd rect
			(at 2.050034 42.0751 270)
			(size 0.519938 1.4986)
			(layers "F.Cu" "F.Mask" "F.Paste")
			(net "M_C_CPU1_SB_DQ<14>")
		)
		(pad "264" smd rect
			(at 2.050034 42.924984 270)
			(size 0.519938 1.4986)
			(layers "F.Cu" "F.Mask" "F.Paste")
			(net "GND")
		)
		(pad "265" smd rect
			(at 2.050034 43.775122 270)
			(size 0.519938 1.4986)
			(layers "F.Cu" "F.Mask" "F.Paste")
			(net "M_C_CPU1_SB_DQ<15>")
		)
		(pad "266" smd rect
			(at 2.050034 44.625006 270)
			(size 0.519938 1.4986)
			(layers "F.Cu" "F.Mask" "F.Paste")
			(net "GND")
		)
		(pad "267" smd rect
			(at 2.050034 45.47489 270)
			(size 0.519938 1.4986)
			(layers "F.Cu" "F.Mask" "F.Paste")
			(net "M_C_CPU1_SB_DQ<18>")
		)
		(pad "268" smd rect
			(at 2.050034 46.325028 270)
			(size 0.519938 1.4986)
			(layers "F.Cu" "F.Mask" "F.Paste")
			(net "GND")
		)
		(pad "269" smd rect
			(at 2.050034 47.174912 270)
			(size 0.519938 1.4986)
			(layers "F.Cu" "F.Mask" "F.Paste")
			(net "M_C_CPU1_SB_DQ<19>")
		)
		(pad "270" smd rect
			(at 2.050034 48.02505 270)
			(size 0.519938 1.4986)
			(layers "F.Cu" "F.Mask" "F.Paste")
			(net "GND")
		)
		(pad "271" smd rect
			(at 2.050034 48.874934 270)
			(size 0.519938 1.4986)
			(layers "F.Cu" "F.Mask" "F.Paste")
			(net "M_C_CPU1_SB_DQS_DN<7>")
		)
		(pad "272" smd rect
			(at 2.050034 49.725072 270)
			(size 0.519938 1.4986)
			(layers "F.Cu" "F.Mask" "F.Paste")
			(net "M_C_CPU1_SB_DQS_DP<7>")
		)
		(pad "273" smd rect
			(at 2.050034 50.574956 270)
			(size 0.519938 1.4986)
			(layers "F.Cu" "F.Mask" "F.Paste")
			(net "GND")
		)
		(pad "274" smd rect
			(at 2.050034 51.425094 270)
			(size 0.519938 1.4986)
			(layers "F.Cu" "F.Mask" "F.Paste")
			(net "M_C_CPU1_SB_DQ<22>")
		)
		(pad "275" smd rect
			(at 2.050034 52.274978 270)
			(size 0.519938 1.4986)
			(layers "F.Cu" "F.Mask" "F.Paste")
			(net "GND")
		)
		(pad "276" smd rect
			(at 2.050034 53.125116 270)
			(size 0.519938 1.4986)
			(layers "F.Cu" "F.Mask" "F.Paste")
			(net "M_C_CPU1_SB_DQ<23>")
		)
		(pad "277" smd rect
			(at 2.050034 53.975 270)
			(size 0.519938 1.4986)
			(layers "F.Cu" "F.Mask" "F.Paste")
			(net "GND")
		)
		(pad "278" smd rect
			(at 2.050034 54.824884 270)
			(size 0.519938 1.4986)
			(layers "F.Cu" "F.Mask" "F.Paste")
			(net "M_C_CPU1_SB_DQ<26>")
		)
		(pad "279" smd rect
			(at 2.050034 55.675022 270)
			(size 0.519938 1.4986)
			(layers "F.Cu" "F.Mask" "F.Paste")
			(net "GND")
		)
		(pad "280" smd rect
			(at 2.050034 56.524906 270)
			(size 0.519938 1.4986)
			(layers "F.Cu" "F.Mask" "F.Paste")
			(net "M_C_CPU1_SB_DQ<27>")
		)
		(pad "281" smd rect
			(at 2.050034 57.375044 270)
			(size 0.519938 1.4986)
			(layers "F.Cu" "F.Mask" "F.Paste")
			(net "GND")
		)
		(pad "282" smd rect
			(at 2.050034 58.224928 270)
			(size 0.519938 1.4986)
			(layers "F.Cu" "F.Mask" "F.Paste")
			(net "M_C_CPU1_SB_DQS_DN<8>")
		)
		(pad "283" smd rect
			(at 2.050034 59.075066 270)
			(size 0.519938 1.4986)
			(layers "F.Cu" "F.Mask" "F.Paste")
			(net "M_C_CPU1_SB_DQS_DP<8>")
		)
		(pad "284" smd rect
			(at 2.050034 59.92495 270)
			(size 0.519938 1.4986)
			(layers "F.Cu" "F.Mask" "F.Paste")
			(net "GND")
		)
		(pad "285" smd rect
			(at 2.050034 60.775088 270)
			(size 0.519938 1.4986)
			(layers "F.Cu" "F.Mask" "F.Paste")
			(net "M_C_CPU1_SB_DQ<30>")
		)
		(pad "286" smd rect
			(at 2.050034 61.624972 270)
			(size 0.519938 1.4986)
			(layers "F.Cu" "F.Mask" "F.Paste")
			(net "GND")
		)
		(pad "287" smd rect
			(at 2.050034 62.47511 270)
			(size 0.519938 1.4986)
			(layers "F.Cu" "F.Mask" "F.Paste")
			(net "M_C_CPU1_SB_DQ<31>")
		)
		(pad "288" smd rect
			(at 2.050034 63.324994 270)
			(size 0.519938 1.4986)
			(layers "F.Cu" "F.Mask" "F.Paste")
			(net "GND")
		)
		(pad "G1" thru_hole oval
			(at 0 -68.97497)
			(size 2.8194 1.5748)
			(drill oval 2.4384 1.1938)
			(layers "*.Cu" "*.Mask")
			(remove_unused_layers no)
			(net "GND")
			(clearance 0.127)
			(thermal_gap 0.127)
		)
		(pad "G2" thru_hole oval
			(at 0 3.875024)
			(size 2.8194 1.5748)
			(drill oval 2.4384 1.1938)
			(layers "*.Cu" "*.Mask")
			(remove_unused_layers no)
			(net "GND")
			(clearance 0.127)
			(thermal_gap 0.127)
		)
		(pad "G3" thru_hole oval
			(at 0 68.97497)
			(size 2.8194 1.5748)
			(drill oval 2.4384 1.1938)
			(layers "*.Cu" "*.Mask")
			(remove_unused_layers no)
			(net "GND")
			(clearance 0.127)
			(thermal_gap 0.127)
		)
	)
	(footprint ""
		(layer "F.Cu")
		(at 152.70988 -125.313948 90)
		(property "Reference" "U286"
			(at 2.012442 -5.37718 0)
			(unlocked yes)
			(layer "F.SilkS")
			(effects
				(font
					(size 0.7874 0.5842)
					(thickness 0.1524)
				)
				(justify left)
			)
		)
		(property "Value" ""
			(at 0 0 90)
			(layer "F.Fab")
			(effects
				(font
					(size 1.27 1.27)
				)
			)
		)
		(duplicate_pad_numbers_are_jumpers no)
		(fp_line
			(start 1.400048 -1.100074)
			(end -1.400048 -1.100074)
			(stroke
				(width 0.1524)
				(type default)
			)
			(layer "F.SilkS")
		)
		(fp_line
			(start 1.400048 -1.100074)
			(end 1.400048 1.100074)
			(stroke
				(width 0.1524)
				(type default)
			)
			(layer "F.SilkS")
		)
		(fp_line
			(start 1.400048 1.100074)
			(end -1.400048 1.100074)
			(stroke
				(width 0.1524)
				(type default)
			)
			(layer "F.SilkS")
		)
		(fp_line
			(start -1.400048 1.100074)
			(end -1.400048 -1.100074)
			(stroke
				(width 0.1524)
				(type default)
			)
			(layer "F.SilkS")
		)
		(fp_poly
			(pts
				(xy -0.686308 -1.26873) (xy -0.327152 -2.346452) (xy 0.39116 -1.627886)
			)
			(stroke
				(width 0)
				(type default)
			)
			(fill yes)
			(layer "F.SilkS")
		)
		(fp_line
			(start 0.674878 -1.100074)
			(end 0.674878 1.100074)
			(stroke
				(width 0.1)
				(type default)
			)
			(layer "F.Fab")
		)
		(fp_line
			(start -0.674878 -1.100074)
			(end 0.674878 -1.100074)
			(stroke
				(width 0.1)
				(type default)
			)
			(layer "F.Fab")
		)
		(fp_line
			(start 0.674878 1.100074)
			(end -0.674878 1.100074)
			(stroke
				(width 0.1)
				(type default)
			)
			(layer "F.Fab")
		)
		(fp_line
			(start -0.674878 1.100074)
			(end -0.674878 -1.100074)
			(stroke
				(width 0.1)
				(type default)
			)
			(layer "F.Fab")
		)
		(fp_poly
			(pts
				(xy -1.590548 -0.649986) (xy -2.606548 -1.157986) (xy -2.606548 -0.141986)
			)
			(stroke
				(width 0)
				(type default)
			)
			(fill yes)
			(layer "F.Fab")
		)
		(pad "1" smd rect
			(at -0.94996 -0.649986)
			(size 0.4318 0.6096)
			(layers "F.Cu" "F.Mask" "F.Paste")
			(net "OCP_V3_2_AUX_PWR_EN_R1")
		)
		(pad "2" smd rect
			(at -0.94996 0)
			(size 0.4318 0.6096)
			(layers "F.Cu" "F.Mask" "F.Paste")
			(net "FM_OCP_V3_2_PWR_GOOD")
		)
		(pad "3" smd rect
			(at -0.94996 0.649986)
			(size 0.4318 0.6096)
			(layers "F.Cu" "F.Mask" "F.Paste")
			(net "GND")
		)
		(pad "4" smd rect
			(at 0.94996 0.649986)
			(size 0.4318 0.6096)
			(layers "F.Cu" "F.Mask" "F.Paste")
			(net "FB_BMC_ISOLATE_R2")
		)
		(pad "5" smd rect
			(at 0.94996 -0.649986)
			(size 0.4318 0.6096)
			(layers "F.Cu" "F.Mask" "F.Paste")
			(net "P3V3_AUX")
		)
	)
	(footprint ""
		(layer "F.Cu")
		(at 9.277096 -100.017834 90)
		(property "Reference" "C2029"
			(at 0 0 90)
			(layer "F.SilkS")
			(hide yes)
			(effects
				(font
					(size 1.27 1.27)
				)
			)
		)
		(property "Value" ""
			(at 0 0 90)
			(layer "F.Fab")
			(effects
				(font
					(size 1.27 1.27)
				)
			)
		)
		(duplicate_pad_numbers_are_jumpers no)
		(fp_line
			(start 0.7874 -0.4064)
			(end 0.7874 0.4064)
			(stroke
				(width 0.1524)
				(type default)
			)
			(layer "F.SilkS")
		)
		(fp_line
			(start -0.7874 -0.4064)
			(end 0.7874 -0.4064)
			(stroke
				(width 0.1524)
				(type default)
			)
			(layer "F.SilkS")
		)
		(fp_line
			(start 0.7874 0.4064)
			(end -0.7874 0.4064)
			(stroke
				(width 0.1524)
				(type default)
			)
			(layer "F.SilkS")
		)
		(fp_line
			(start -0.7874 0.4064)
			(end -0.7874 -0.4064)
			(stroke
				(width 0.1524)
				(type default)
			)
			(layer "F.SilkS")
		)
		(fp_line
			(start -0.12065 -0.305054)
			(end -0.12065 -0.2794)
			(stroke
				(width 0.1)
				(type default)
			)
			(layer "F.Fab")
		)
		(fp_line
			(start -0.67945 -0.305054)
			(end -0.12065 -0.305054)
			(stroke
				(width 0.1)
				(type default)
			)
			(layer "F.Fab")
		)
		(fp_line
			(start 0.67945 -0.3048)
			(end 0.67945 0.3048)
			(stroke
				(width 0.1)
				(type default)
			)
			(layer "F.Fab")
		)
		(fp_line
			(start 0.12065 -0.3048)
			(end 0.67945 -0.3048)
			(stroke
				(width 0.1)
				(type default)
			)
			(layer "F.Fab")
		)
		(fp_line
			(start 0.12065 -0.2794)
			(end 0.12065 -0.3048)
			(stroke
				(width 0.1)
				(type default)
			)
			(layer "F.Fab")
		)
		(fp_line
			(start -0.12065 -0.2794)
			(end 0.12065 -0.2794)
			(stroke
				(width 0.1)
				(type default)
			)
			(layer "F.Fab")
		)
		(fp_line
			(start 0.120396 0.2794)
			(end -0.12065 0.2794)
			(stroke
				(width 0.1)
				(type default)
			)
			(layer "F.Fab")
		)
		(fp_line
			(start -0.12065 0.2794)
			(end -0.12065 0.3048)
			(stroke
				(width 0.1)
				(type default)
			)
			(layer "F.Fab")
		)
		(fp_line
			(start 0.67945 0.3048)
			(end 0.120396 0.3048)
			(stroke
				(width 0.1)
				(type default)
			)
			(layer "F.Fab")
		)
		(fp_line
			(start 0.120396 0.3048)
			(end 0.120396 0.2794)
			(stroke
				(width 0.1)
				(type default)
			)
			(layer "F.Fab")
		)
		(fp_line
			(start -0.12065 0.3048)
			(end -0.67945 0.3048)
			(stroke
				(width 0.1)
				(type default)
			)
			(layer "F.Fab")
		)
		(fp_line
			(start -0.67945 0.3048)
			(end -0.67945 -0.305054)
			(stroke
				(width 0.1)
				(type default)
			)
			(layer "F.Fab")
		)
		(pad "1" smd circle
			(at -0.40005 0 90)
			(size 0 0)
			(layers "F.Cu" "F.Mask" "F.Paste")
			(net "USB_HUB_XTAL_IN")
		)
		(pad "2" smd circle
			(at 0.40005 0 90)
			(size 0 0)
			(layers "F.Cu" "F.Mask" "F.Paste")
			(net "GND")
		)
	)
	(footprint ""
		(layer "F.Cu")
		(at 461.593946 -106.027728 180)
		(property "Reference" "R4752"
			(at 0 0 180)
			(layer "F.SilkS")
			(hide yes)
			(effects
				(font
					(size 1.27 1.27)
				)
			)
		)
		(property "Value" ""
			(at 0 0 180)
			(layer "F.Fab")
			(effects
				(font
					(size 1.27 1.27)
				)
			)
		)
		(duplicate_pad_numbers_are_jumpers no)
		(fp_line
			(start 0.7874 0.4064)
			(end -0.7874 0.4064)
			(stroke
				(width 0.1524)
				(type default)
			)
			(layer "F.SilkS")
		)
		(fp_line
			(start 0.7874 -0.4064)
			(end 0.7874 0.4064)
			(stroke
				(width 0.1524)
				(type default)
			)
			(layer "F.SilkS")
		)
		(fp_line
			(start -0.7874 0.4064)
			(end -0.7874 -0.4064)
			(stroke
				(width 0.1524)
				(type default)
			)
			(layer "F.SilkS")
		)
		(fp_line
			(start -0.7874 -0.4064)
			(end 0.7874 -0.4064)
			(stroke
				(width 0.1524)
				(type default)
			)
			(layer "F.SilkS")
		)
		(fp_line
			(start 0.67945 0.3048)
			(end 0.120396 0.3048)
			(stroke
				(width 0.1)
				(type default)
			)
			(layer "F.Fab")
		)
		(fp_line
			(start 0.67945 -0.3048)
			(end 0.67945 0.3048)
			(stroke
				(width 0.1)
				(type default)
			)
			(layer "F.Fab")
		)
		(fp_line
			(start 0.12065 -0.2794)
			(end 0.12065 -0.3048)
			(stroke
				(width 0.1)
				(type default)
			)
			(layer "F.Fab")
		)
		(fp_line
			(start 0.12065 -0.3048)
			(end 0.67945 -0.3048)
			(stroke
				(width 0.1)
				(type default)
			)
			(layer "F.Fab")
		)
		(fp_line
			(start 0.120396 0.3048)
			(end 0.120396 0.2794)
			(stroke
				(width 0.1)
				(type default)
			)
			(layer "F.Fab")
		)
		(fp_line
			(start 0.120396 0.2794)
			(end -0.12065 0.2794)
			(stroke
				(width 0.1)
				(type default)
			)
			(layer "F.Fab")
		)
		(fp_line
			(start -0.12065 0.3048)
			(end -0.67945 0.3048)
			(stroke
				(width 0.1)
				(type default)
			)
			(layer "F.Fab")
		)
		(fp_line
			(start -0.12065 0.2794)
			(end -0.12065 0.3048)
			(stroke
				(width 0.1)
				(type default)
			)
			(layer "F.Fab")
		)
		(fp_line
			(start -0.12065 -0.2794)
			(end 0.12065 -0.2794)
			(stroke
				(width 0.1)
				(type default)
			)
			(layer "F.Fab")
		)
		(fp_line
			(start -0.12065 -0.305054)
			(end -0.12065 -0.2794)
			(stroke
				(width 0.1)
				(type default)
			)
			(layer "F.Fab")
		)
		(fp_line
			(start -0.67945 0.3048)
			(end -0.67945 -0.305054)
			(stroke
				(width 0.1)
				(type default)
			)
			(layer "F.Fab")
		)
		(fp_line
			(start -0.67945 -0.305054)
			(end -0.12065 -0.305054)
			(stroke
				(width 0.1)
				(type default)
			)
			(layer "F.Fab")
		)
		(pad "1" smd circle
			(at -0.40005 0 180)
			(size 0 0)
			(layers "F.Cu" "F.Mask" "F.Paste")
			(net "HP_LVC3_OCP_V3_1_PRSNT2_N_R")
		)
		(pad "2" smd circle
			(at 0.40005 0 180)
			(size 0 0)
			(layers "F.Cu" "F.Mask" "F.Paste")
			(net "HP_LVC3_OCP_V3_1_PRSNT2_PLD_N")
		)
	)
	(footprint ""
		(layer "F.Cu")
		(at 215.95588 -32.857948 180)
		(property "Reference" "R3593"
			(at 0 0 180)
			(layer "F.SilkS")
			(hide yes)
			(effects
				(font
					(size 1.27 1.27)
				)
			)
		)
		(property "Value" ""
			(at 0 0 180)
			(layer "F.Fab")
			(effects
				(font
					(size 1.27 1.27)
				)
			)
		)
		(duplicate_pad_numbers_are_jumpers no)
		(fp_line
			(start 0.7874 0.4064)
			(end -0.7874 0.4064)
			(stroke
				(width 0.1524)
				(type default)
			)
			(layer "F.SilkS")
		)
		(fp_line
			(start 0.7874 -0.4064)
			(end 0.7874 0.4064)
			(stroke
				(width 0.1524)
				(type default)
			)
			(layer "F.SilkS")
		)
		(fp_line
			(start -0.7874 0.4064)
			(end -0.7874 -0.4064)
			(stroke
				(width 0.1524)
				(type default)
			)
			(layer "F.SilkS")
		)
		(fp_line
			(start -0.7874 -0.4064)
			(end 0.7874 -0.4064)
			(stroke
				(width 0.1524)
				(type default)
			)
			(layer "F.SilkS")
		)
		(fp_line
			(start 0.67945 0.3048)
			(end 0.120396 0.3048)
			(stroke
				(width 0.1)
				(type default)
			)
			(layer "F.Fab")
		)
		(fp_line
			(start 0.67945 -0.3048)
			(end 0.67945 0.3048)
			(stroke
				(width 0.1)
				(type default)
			)
			(layer "F.Fab")
		)
		(fp_line
			(start 0.12065 -0.2794)
			(end 0.12065 -0.3048)
			(stroke
				(width 0.1)
				(type default)
			)
			(layer "F.Fab")
		)
		(fp_line
			(start 0.12065 -0.3048)
			(end 0.67945 -0.3048)
			(stroke
				(width 0.1)
				(type default)
			)
			(layer "F.Fab")
		)
		(fp_line
			(start 0.120396 0.3048)
			(end 0.120396 0.2794)
			(stroke
				(width 0.1)
				(type default)
			)
			(layer "F.Fab")
		)
		(fp_line
			(start 0.120396 0.2794)
			(end -0.12065 0.2794)
			(stroke
				(width 0.1)
				(type default)
			)
			(layer "F.Fab")
		)
		(fp_line
			(start -0.12065 0.3048)
			(end -0.67945 0.3048)
			(stroke
				(width 0.1)
				(type default)
			)
			(layer "F.Fab")
		)
		(fp_line
			(start -0.12065 0.2794)
			(end -0.12065 0.3048)
			(stroke
				(width 0.1)
				(type default)
			)
			(layer "F.Fab")
		)
		(fp_line
			(start -0.12065 -0.2794)
			(end 0.12065 -0.2794)
			(stroke
				(width 0.1)
				(type default)
			)
			(layer "F.Fab")
		)
		(fp_line
			(start -0.12065 -0.305054)
			(end -0.12065 -0.2794)
			(stroke
				(width 0.1)
				(type default)
			)
			(layer "F.Fab")
		)
		(fp_line
			(start -0.67945 0.3048)
			(end -0.67945 -0.305054)
			(stroke
				(width 0.1)
				(type default)
			)
			(layer "F.Fab")
		)
		(fp_line
			(start -0.67945 -0.305054)
			(end -0.12065 -0.305054)
			(stroke
				(width 0.1)
				(type default)
			)
			(layer "F.Fab")
		)
		(pad "1" smd circle
			(at -0.40005 0 180)
			(size 0 0)
			(layers "F.Cu" "F.Mask" "F.Paste")
			(net "SMB_INA230_3V3AUX_SDA")
		)
		(pad "2" smd circle
			(at 0.40005 0 180)
			(size 0 0)
			(layers "F.Cu" "F.Mask" "F.Paste")
			(net "SMB_INA230_5_3V3AUX_SDA_R")
		)
	)
	(footprint ""
		(layer "F.Cu")
		(at 317.396622 -60.315348 180)
		(property "Reference" "R1478"
			(at 0 0 180)
			(layer "F.SilkS")
			(hide yes)
			(effects
				(font
					(size 1.27 1.27)
				)
			)
		)
		(property "Value" ""
			(at 0 0 180)
			(layer "F.Fab")
			(effects
				(font
					(size 1.27 1.27)
				)
			)
		)
		(duplicate_pad_numbers_are_jumpers no)
		(fp_line
			(start 0.7874 0.4064)
			(end -0.7874 0.4064)
			(stroke
				(width 0.1524)
				(type default)
			)
			(layer "F.SilkS")
		)
		(fp_line
			(start 0.7874 -0.4064)
			(end 0.7874 0.4064)
			(stroke
				(width 0.1524)
				(type default)
			)
			(layer "F.SilkS")
		)
		(fp_line
			(start -0.7874 0.4064)
			(end -0.7874 -0.4064)
			(stroke
				(width 0.1524)
				(type default)
			)
			(layer "F.SilkS")
		)
		(fp_line
			(start -0.7874 -0.4064)
			(end 0.7874 -0.4064)
			(stroke
				(width 0.1524)
				(type default)
			)
			(layer "F.SilkS")
		)
		(fp_line
			(start 0.67945 0.3048)
			(end 0.120396 0.3048)
			(stroke
				(width 0.1)
				(type default)
			)
			(layer "F.Fab")
		)
		(fp_line
			(start 0.67945 -0.3048)
			(end 0.67945 0.3048)
			(stroke
				(width 0.1)
				(type default)
			)
			(layer "F.Fab")
		)
		(fp_line
			(start 0.12065 -0.2794)
			(end 0.12065 -0.3048)
			(stroke
				(width 0.1)
				(type default)
			)
			(layer "F.Fab")
		)
		(fp_line
			(start 0.12065 -0.3048)
			(end 0.67945 -0.3048)
			(stroke
				(width 0.1)
				(type default)
			)
			(layer "F.Fab")
		)
		(fp_line
			(start 0.120396 0.3048)
			(end 0.120396 0.2794)
			(stroke
				(width 0.1)
				(type default)
			)
			(layer "F.Fab")
		)
		(fp_line
			(start 0.120396 0.2794)
			(end -0.12065 0.2794)
			(stroke
				(width 0.1)
				(type default)
			)
			(layer "F.Fab")
		)
		(fp_line
			(start -0.12065 0.3048)
			(end -0.67945 0.3048)
			(stroke
				(width 0.1)
				(type default)
			)
			(layer "F.Fab")
		)
		(fp_line
			(start -0.12065 0.2794)
			(end -0.12065 0.3048)
			(stroke
				(width 0.1)
				(type default)
			)
			(layer "F.Fab")
		)
		(fp_line
			(start -0.12065 -0.2794)
			(end 0.12065 -0.2794)
			(stroke
				(width 0.1)
				(type default)
			)
			(layer "F.Fab")
		)
		(fp_line
			(start -0.12065 -0.305054)
			(end -0.12065 -0.2794)
			(stroke
				(width 0.1)
				(type default)
			)
			(layer "F.Fab")
		)
		(fp_line
			(start -0.67945 0.3048)
			(end -0.67945 -0.305054)
			(stroke
				(width 0.1)
				(type default)
			)
			(layer "F.Fab")
		)
		(fp_line
			(start -0.67945 -0.305054)
			(end -0.12065 -0.305054)
			(stroke
				(width 0.1)
				(type default)
			)
			(layer "F.Fab")
		)
		(pad "1" smd circle
			(at -0.40005 0 180)
			(size 0 0)
			(layers "F.Cu" "F.Mask" "F.Paste")
			(net "FM_PCH_XTAL_INPUT_MODE_MGPIO_TE")
		)
		(pad "2" smd circle
			(at 0.40005 0 180)
			(size 0 0)
			(layers "F.Cu" "F.Mask" "F.Paste")
			(net "GND")
		)
	)
	(footprint ""
		(layer "F.Cu")
		(at 186.733942 -133.689598 -90)
		(property "Reference" "R4057"
			(at 0 0 270)
			(layer "F.SilkS")
			(hide yes)
			(effects
				(font
					(size 1.27 1.27)
				)
			)
		)
		(property "Value" ""
			(at 0 0 270)
			(layer "F.Fab")
			(effects
				(font
					(size 1.27 1.27)
				)
			)
		)
		(duplicate_pad_numbers_are_jumpers no)
		(fp_line
			(start -0.7874 0.4064)
			(end -0.7874 -0.4064)
			(stroke
				(width 0.1524)
				(type default)
			)
			(layer "F.SilkS")
		)
		(fp_line
			(start 0.7874 0.4064)
			(end -0.7874 0.4064)
			(stroke
				(width 0.1524)
				(type default)
			)
			(layer "F.SilkS")
		)
		(fp_line
			(start -0.7874 -0.4064)
			(end 0.7874 -0.4064)
			(stroke
				(width 0.1524)
				(type default)
			)
			(layer "F.SilkS")
		)
		(fp_line
			(start 0.7874 -0.4064)
			(end 0.7874 0.4064)
			(stroke
				(width 0.1524)
				(type default)
			)
			(layer "F.SilkS")
		)
		(fp_line
			(start -0.67945 0.3048)
			(end -0.67945 -0.305054)
			(stroke
				(width 0.1)
				(type default)
			)
			(layer "F.Fab")
		)
		(fp_line
			(start -0.12065 0.3048)
			(end -0.67945 0.3048)
			(stroke
				(width 0.1)
				(type default)
			)
			(layer "F.Fab")
		)
		(fp_line
			(start 0.120396 0.3048)
			(end 0.120396 0.2794)
			(stroke
				(width 0.1)
				(type default)
			)
			(layer "F.Fab")
		)
		(fp_line
			(start 0.67945 0.3048)
			(end 0.120396 0.3048)
			(stroke
				(width 0.1)
				(type default)
			)
			(layer "F.Fab")
		)
		(fp_line
			(start -0.12065 0.2794)
			(end -0.12065 0.3048)
			(stroke
				(width 0.1)
				(type default)
			)
			(layer "F.Fab")
		)
		(fp_line
			(start 0.120396 0.2794)
			(end -0.12065 0.2794)
			(stroke
				(width 0.1)
				(type default)
			)
			(layer "F.Fab")
		)
		(fp_line
			(start -0.12065 -0.2794)
			(end 0.12065 -0.2794)
			(stroke
				(width 0.1)
				(type default)
			)
			(layer "F.Fab")
		)
		(fp_line
			(start 0.12065 -0.2794)
			(end 0.12065 -0.3048)
			(stroke
				(width 0.1)
				(type default)
			)
			(layer "F.Fab")
		)
		(fp_line
			(start 0.12065 -0.3048)
			(end 0.67945 -0.3048)
			(stroke
				(width 0.1)
				(type default)
			)
			(layer "F.Fab")
		)
		(fp_line
			(start 0.67945 -0.3048)
			(end 0.67945 0.3048)
			(stroke
				(width 0.1)
				(type default)
			)
			(layer "F.Fab")
		)
		(fp_line
			(start -0.67945 -0.305054)
			(end -0.12065 -0.305054)
			(stroke
				(width 0.1)
				(type default)
			)
			(layer "F.Fab")
		)
		(fp_line
			(start -0.12065 -0.305054)
			(end -0.12065 -0.2794)
			(stroke
				(width 0.1)
				(type default)
			)
			(layer "F.Fab")
		)
		(pad "1" smd circle
			(at -0.40005 0 270)
			(size 0 0)
			(layers "F.Cu" "F.Mask" "F.Paste")
			(net "PRSNT_SWB_ISO_N")
		)
		(pad "2" smd circle
			(at 0.40005 0 270)
			(size 0 0)
			(layers "F.Cu" "F.Mask" "F.Paste")
			(net "PRSNT_SWB_ISO_R_N")
		)
	)
	(footprint ""
		(layer "F.Cu")
		(at 327.636378 -347.990922)
		(property "Reference" "PR133"
			(at 0 0 0)
			(layer "F.SilkS")
			(hide yes)
			(effects
				(font
					(size 1.27 1.27)
				)
			)
		)
		(property "Value" ""
			(at 0 0 0)
			(layer "F.Fab")
			(effects
				(font
					(size 1.27 1.27)
				)
			)
		)
		(duplicate_pad_numbers_are_jumpers no)
		(fp_line
			(start -0.7874 -0.4064)
			(end 0.7874 -0.4064)
			(stroke
				(width 0.1524)
				(type default)
			)
			(layer "F.SilkS")
		)
		(fp_line
			(start -0.7874 0.4064)
			(end -0.7874 -0.4064)
			(stroke
				(width 0.1524)
				(type default)
			)
			(layer "F.SilkS")
		)
		(fp_line
			(start 0.7874 -0.4064)
			(end 0.7874 0.4064)
			(stroke
				(width 0.1524)
				(type default)
			)
			(layer "F.SilkS")
		)
		(fp_line
			(start 0.7874 0.4064)
			(end -0.7874 0.4064)
			(stroke
				(width 0.1524)
				(type default)
			)
			(layer "F.SilkS")
		)
		(fp_line
			(start -0.67945 -0.305054)
			(end -0.12065 -0.305054)
			(stroke
				(width 0.1)
				(type default)
			)
			(layer "F.Fab")
		)
		(fp_line
			(start -0.67945 0.3048)
			(end -0.67945 -0.305054)
			(stroke
				(width 0.1)
				(type default)
			)
			(layer "F.Fab")
		)
		(fp_line
			(start -0.12065 -0.305054)
			(end -0.12065 -0.2794)
			(stroke
				(width 0.1)
				(type default)
			)
			(layer "F.Fab")
		)
		(fp_line
			(start -0.12065 -0.2794)
			(end 0.12065 -0.2794)
			(stroke
				(width 0.1)
				(type default)
			)
			(layer "F.Fab")
		)
		(fp_line
			(start -0.12065 0.2794)
			(end -0.12065 0.3048)
			(stroke
				(width 0.1)
				(type default)
			)
			(layer "F.Fab")
		)
		(fp_line
			(start -0.12065 0.3048)
			(end -0.67945 0.3048)
			(stroke
				(width 0.1)
				(type default)
			)
			(layer "F.Fab")
		)
		(fp_line
			(start 0.120396 0.2794)
			(end -0.12065 0.2794)
			(stroke
				(width 0.1)
				(type default)
			)
			(layer "F.Fab")
		)
		(fp_line
			(start 0.120396 0.3048)
			(end 0.120396 0.2794)
			(stroke
				(width 0.1)
				(type default)
			)
			(layer "F.Fab")
		)
		(fp_line
			(start 0.12065 -0.3048)
			(end 0.67945 -0.3048)
			(stroke
				(width 0.1)
				(type default)
			)
			(layer "F.Fab")
		)
		(fp_line
			(start 0.12065 -0.2794)
			(end 0.12065 -0.3048)
			(stroke
				(width 0.1)
				(type default)
			)
			(layer "F.Fab")
		)
		(fp_line
			(start 0.67945 -0.3048)
			(end 0.67945 0.3048)
			(stroke
				(width 0.1)
				(type default)
			)
			(layer "F.Fab")
		)
		(fp_line
			(start 0.67945 0.3048)
			(end 0.120396 0.3048)
			(stroke
				(width 0.1)
				(type default)
			)
			(layer "F.Fab")
		)
		(pad "1" smd circle
			(at -0.40005 0)
			(size 0 0)
			(layers "F.Cu" "F.Mask" "F.Paste")
			(net "PVCCIN_CPU0_LSET7")
		)
		(pad "2" smd circle
			(at 0.40005 0)
			(size 0 0)
			(layers "F.Cu" "F.Mask" "F.Paste")
			(net "GND")
		)
	)
	(footprint ""
		(layer "F.Cu")
		(at 20.11426 -164.737796)
		(property "Reference" "C1336"
			(at 0 0 0)
			(layer "F.SilkS")
			(hide yes)
			(effects
				(font
					(size 1.27 1.27)
				)
			)
		)
		(property "Value" ""
			(at 0 0 0)
			(layer "F.Fab")
			(effects
				(font
					(size 1.27 1.27)
				)
			)
		)
		(duplicate_pad_numbers_are_jumpers no)
		(fp_line
			(start -0.7874 -0.4064)
			(end 0.7874 -0.4064)
			(stroke
				(width 0.1524)
				(type default)
			)
			(layer "F.SilkS")
		)
		(fp_line
			(start -0.7874 0.4064)
			(end -0.7874 -0.4064)
			(stroke
				(width 0.1524)
				(type default)
			)
			(layer "F.SilkS")
		)
		(fp_line
			(start 0.7874 -0.4064)
			(end 0.7874 0.4064)
			(stroke
				(width 0.1524)
				(type default)
			)
			(layer "F.SilkS")
		)
		(fp_line
			(start 0.7874 0.4064)
			(end -0.7874 0.4064)
			(stroke
				(width 0.1524)
				(type default)
			)
			(layer "F.SilkS")
		)
		(fp_line
			(start -0.67945 -0.305054)
			(end -0.12065 -0.305054)
			(stroke
				(width 0.1)
				(type default)
			)
			(layer "F.Fab")
		)
		(fp_line
			(start -0.67945 0.3048)
			(end -0.67945 -0.305054)
			(stroke
				(width 0.1)
				(type default)
			)
			(layer "F.Fab")
		)
		(fp_line
			(start -0.12065 -0.305054)
			(end -0.12065 -0.2794)
			(stroke
				(width 0.1)
				(type default)
			)
			(layer "F.Fab")
		)
		(fp_line
			(start -0.12065 -0.2794)
			(end 0.12065 -0.2794)
			(stroke
				(width 0.1)
				(type default)
			)
			(layer "F.Fab")
		)
		(fp_line
			(start -0.12065 0.2794)
			(end -0.12065 0.3048)
			(stroke
				(width 0.1)
				(type default)
			)
			(layer "F.Fab")
		)
		(fp_line
			(start -0.12065 0.3048)
			(end -0.67945 0.3048)
			(stroke
				(width 0.1)
				(type default)
			)
			(layer "F.Fab")
		)
		(fp_line
			(start 0.120396 0.2794)
			(end -0.12065 0.2794)
			(stroke
				(width 0.1)
				(type default)
			)
			(layer "F.Fab")
		)
		(fp_line
			(start 0.120396 0.3048)
			(end 0.120396 0.2794)
			(stroke
				(width 0.1)
				(type default)
			)
			(layer "F.Fab")
		)
		(fp_line
			(start 0.12065 -0.3048)
			(end 0.67945 -0.3048)
			(stroke
				(width 0.1)
				(type default)
			)
			(layer "F.Fab")
		)
		(fp_line
			(start 0.12065 -0.2794)
			(end 0.12065 -0.3048)
			(stroke
				(width 0.1)
				(type default)
			)
			(layer "F.Fab")
		)
		(fp_line
			(start 0.67945 -0.3048)
			(end 0.67945 0.3048)
			(stroke
				(width 0.1)
				(type default)
			)
			(layer "F.Fab")
		)
		(fp_line
			(start 0.67945 0.3048)
			(end 0.120396 0.3048)
			(stroke
				(width 0.1)
				(type default)
			)
			(layer "F.Fab")
		)
		(pad "1" smd circle
			(at -0.40005 0)
			(size 0 0)
			(layers "F.Cu" "F.Mask" "F.Paste")
			(net "PVNN_TERM_CPU1")
		)
		(pad "2" smd circle
			(at 0.40005 0)
			(size 0 0)
			(layers "F.Cu" "F.Mask" "F.Paste")
			(net "GND")
		)
	)
	(footprint ""
		(layer "F.Cu")
		(at 189.738762 -25.643332)
		(property "Reference" "PU300"
			(at -6.880352 -3.665982 0)
			(unlocked yes)
			(layer "F.SilkS")
			(effects
				(font
					(size 0.7874 0.5842)
					(thickness 0.1524)
				)
				(justify left)
			)
		)
		(property "Value" ""
			(at 0 0 0)
			(layer "F.Fab")
			(effects
				(font
					(size 1.27 1.27)
				)
			)
		)
		(duplicate_pad_numbers_are_jumpers no)
		(fp_line
			(start -1.774952 -1.039876)
			(end -1.774952 1.039876)
			(stroke
				(width 0.1524)
				(type default)
			)
			(layer "F.SilkS")
		)
		(fp_line
			(start -1.774952 1.039876)
			(end 1.774952 1.039876)
			(stroke
				(width 0.1524)
				(type default)
			)
			(layer "F.SilkS")
		)
		(fp_line
			(start 1.774952 -1.039876)
			(end -1.774952 -1.039876)
			(stroke
				(width 0.1524)
				(type default)
			)
			(layer "F.SilkS")
		)
		(fp_line
			(start 1.774952 1.039876)
			(end 1.774952 -1.039876)
			(stroke
				(width 0.1524)
				(type default)
			)
			(layer "F.SilkS")
		)
		(fp_poly
			(pts
				(xy -1.769872 -1.039876) (xy -1.769872 -0.249936) (xy -2.531872 -0.249936) (xy -2.531872 -1.801876)
				(xy -0.999998 -1.801876) (xy -0.999998 -1.039876)
			)
			(stroke
				(width 0)
				(type default)
			)
			(fill yes)
			(layer "F.SilkS")
		)
		(fp_line
			(start -1.769872 -1.039876)
			(end -1.769872 1.039876)
			(stroke
				(width 0.1)
				(type default)
			)
			(layer "F.Fab")
		)
		(fp_line
			(start -1.769872 1.039876)
			(end 1.769872 1.039876)
			(stroke
				(width 0.1)
				(type default)
			)
			(layer "F.Fab")
		)
		(fp_line
			(start 1.769872 -1.039876)
			(end -1.769872 -1.039876)
			(stroke
				(width 0.1)
				(type default)
			)
			(layer "F.Fab")
		)
		(fp_line
			(start 1.769872 1.039876)
			(end 1.769872 -1.039876)
			(stroke
				(width 0.1)
				(type default)
			)
			(layer "F.Fab")
		)
		(fp_poly
			(pts
				(xy -1.769872 -1.039876) (xy -0.999998 -1.039876) (xy -0.999998 -1.801876) (xy -2.531872 -1.801876)
				(xy -2.531872 -0.249936) (xy -1.769872 -0.249936)
			)
			(stroke
				(width 0)
				(type default)
			)
			(fill yes)
			(layer "F.Fab")
		)
		(pad "A1" smd circle
			(at -1.500124 -0.750062)
			(size 0.2286 0.2286)
			(layers "F.Cu" "F.Mask" "F.Paste")
			(net "P12V_SCM_SENSE")
		)
		(pad "A2" smd circle
			(at -0.999998 -0.750062)
			(size 0.2286 0.2286)
			(layers "F.Cu" "F.Mask" "F.Paste")
			(net "P12V_SCM_VCC")
		)
		(pad "A3" smd circle
			(at -0.499872 -0.750062)
			(size 0.2286 0.2286)
			(layers "F.Cu" "F.Mask" "F.Paste")
			(net "P12V_AUX")
		)
		(pad "A4" smd circle
			(at 0 -0.750062)
			(size 0.2286 0.2286)
			(layers "F.Cu" "F.Mask" "F.Paste")
			(net "P12V_SCM_R")
		)
		(pad "A5" smd circle
			(at 0.499872 -0.750062)
			(size 0.2286 0.2286)
			(layers "F.Cu" "F.Mask" "F.Paste")
			(net "P12V_AUX")
		)
		(pad "A6" smd circle
			(at 0.999998 -0.750062)
			(size 0.2286 0.2286)
			(layers "F.Cu" "F.Mask" "F.Paste")
			(net "P12V_SCM_GATE")
		)
		(pad "A7" smd circle
			(at 1.500124 -0.750062)
			(size 0.2286 0.2286)
			(layers "F.Cu" "F.Mask" "F.Paste")
			(net "GND")
		)
		(pad "B1" smd circle
			(at -1.500124 -0.249936)
			(size 0.2286 0.2286)
			(layers "F.Cu" "F.Mask" "F.Paste")
			(net "P12V_SCM_CB")
		)
		(pad "B2" smd circle
			(at -0.999998 -0.249936)
			(size 0.2286 0.2286)
			(layers "F.Cu" "F.Mask" "F.Paste")
			(net "GND")
		)
		(pad "B3" smd circle
			(at -0.499872 -0.249936)
			(size 0.2286 0.2286)
			(layers "F.Cu" "F.Mask" "F.Paste")
			(net "P12V_AUX")
		)
		(pad "B4" smd circle
			(at 0 -0.249936)
			(size 0.2286 0.2286)
			(layers "F.Cu" "F.Mask" "F.Paste")
			(net "P12V_SCM_R")
		)
		(pad "B5" smd circle
			(at 0.499872 -0.249936)
			(size 0.2286 0.2286)
			(layers "F.Cu" "F.Mask" "F.Paste")
			(net "P12V_AUX")
		)
		(pad "B6" smd circle
			(at 0.999998 -0.249936)
			(size 0.2286 0.2286)
			(layers "F.Cu" "F.Mask" "F.Paste")
			(net "P12V_SCM_R")
		)
		(pad "B7" smd circle
			(at 1.500124 -0.249936)
			(size 0.2286 0.2286)
			(layers "F.Cu" "F.Mask" "F.Paste")
			(net "GND")
		)
		(pad "C1" smd circle
			(at -1.500124 0.249936)
			(size 0.2286 0.2286)
			(layers "F.Cu" "F.Mask" "F.Paste")
			(net "GND")
		)
		(pad "C2" smd circle
			(at -0.999998 0.249936)
			(size 0.2286 0.2286)
			(layers "F.Cu" "F.Mask" "F.Paste")
			(net "GND")
		)
		(pad "C3" smd circle
			(at -0.499872 0.249936)
			(size 0.2286 0.2286)
			(layers "F.Cu" "F.Mask" "F.Paste")
			(net "P12V_AUX")
		)
		(pad "C4" smd circle
			(at 0 0.249936)
			(size 0.2286 0.2286)
			(layers "F.Cu" "F.Mask" "F.Paste")
			(net "P12V_SCM_R")
		)
		(pad "C5" smd circle
			(at 0.499872 0.249936)
			(size 0.2286 0.2286)
			(layers "F.Cu" "F.Mask" "F.Paste")
			(net "P12V_AUX")
		)
		(pad "C6" smd circle
			(at 0.999998 0.249936)
			(size 0.2286 0.2286)
			(layers "F.Cu" "F.Mask" "F.Paste")
			(net "P12V_SCM_R")
		)
		(pad "C7" smd circle
			(at 1.500124 0.249936)
			(size 0.2286 0.2286)
			(layers "F.Cu" "F.Mask" "F.Paste")
			(net "P12V_SCM_FAULT_N")
		)
		(pad "D1" smd circle
			(at -1.500124 0.750062)
			(size 0.2286 0.2286)
			(layers "F.Cu" "F.Mask" "F.Paste")
			(net "P12V_SCM_REG")
		)
		(pad "D2" smd circle
			(at -0.999998 0.750062)
			(size 0.2286 0.2286)
			(layers "F.Cu" "F.Mask" "F.Paste")
			(net "P12V_SCM_UV")
		)
		(pad "D3" smd circle
			(at -0.499872 0.750062)
			(size 0.2286 0.2286)
			(layers "F.Cu" "F.Mask" "F.Paste")
			(net "P12V_SCM_OV")
		)
		(pad "D4" smd circle
			(at 0 0.750062)
			(size 0.2286 0.2286)
			(layers "F.Cu" "F.Mask" "F.Paste")
			(net "P12V_SCM_R")
		)
		(pad "D5" smd circle
			(at 0.499872 0.750062)
			(size 0.2286 0.2286)
			(layers "F.Cu" "F.Mask" "F.Paste")
			(net "P12V_AUX")
		)
		(pad "D6" smd circle
			(at 0.999998 0.750062)
			(size 0.2286 0.2286)
			(layers "F.Cu" "F.Mask" "F.Paste")
			(net "P12V_SCM_R")
		)
		(pad "D7" smd circle
			(at 1.500124 0.750062)
			(size 0.2286 0.2286)
			(layers "F.Cu" "F.Mask" "F.Paste")
			(net "P12V_SCM_PWRGD")
		)
	)
	(footprint ""
		(layer "F.Cu")
		(at 193.38036 -118.074948)
		(property "Reference" "R1420"
			(at 0 0 0)
			(layer "F.SilkS")
			(hide yes)
			(effects
				(font
					(size 1.27 1.27)
				)
			)
		)
		(property "Value" ""
			(at 0 0 0)
			(layer "F.Fab")
			(effects
				(font
					(size 1.27 1.27)
				)
			)
		)
		(duplicate_pad_numbers_are_jumpers no)
		(fp_line
			(start -0.7874 -0.4064)
			(end 0.7874 -0.4064)
			(stroke
				(width 0.1524)
				(type default)
			)
			(layer "F.SilkS")
		)
		(fp_line
			(start -0.7874 0.4064)
			(end -0.7874 -0.4064)
			(stroke
				(width 0.1524)
				(type default)
			)
			(layer "F.SilkS")
		)
		(fp_line
			(start 0.7874 -0.4064)
			(end 0.7874 0.4064)
			(stroke
				(width 0.1524)
				(type default)
			)
			(layer "F.SilkS")
		)
		(fp_line
			(start 0.7874 0.4064)
			(end -0.7874 0.4064)
			(stroke
				(width 0.1524)
				(type default)
			)
			(layer "F.SilkS")
		)
		(fp_line
			(start -0.67945 -0.305054)
			(end -0.12065 -0.305054)
			(stroke
				(width 0.1)
				(type default)
			)
			(layer "F.Fab")
		)
		(fp_line
			(start -0.67945 0.3048)
			(end -0.67945 -0.305054)
			(stroke
				(width 0.1)
				(type default)
			)
			(layer "F.Fab")
		)
		(fp_line
			(start -0.12065 -0.305054)
			(end -0.12065 -0.2794)
			(stroke
				(width 0.1)
				(type default)
			)
			(layer "F.Fab")
		)
		(fp_line
			(start -0.12065 -0.2794)
			(end 0.12065 -0.2794)
			(stroke
				(width 0.1)
				(type default)
			)
			(layer "F.Fab")
		)
		(fp_line
			(start -0.12065 0.2794)
			(end -0.12065 0.3048)
			(stroke
				(width 0.1)
				(type default)
			)
			(layer "F.Fab")
		)
		(fp_line
			(start -0.12065 0.3048)
			(end -0.67945 0.3048)
			(stroke
				(width 0.1)
				(type default)
			)
			(layer "F.Fab")
		)
		(fp_line
			(start 0.120396 0.2794)
			(end -0.12065 0.2794)
			(stroke
				(width 0.1)
				(type default)
			)
			(layer "F.Fab")
		)
		(fp_line
			(start 0.120396 0.3048)
			(end 0.120396 0.2794)
			(stroke
				(width 0.1)
				(type default)
			)
			(layer "F.Fab")
		)
		(fp_line
			(start 0.12065 -0.3048)
			(end 0.67945 -0.3048)
			(stroke
				(width 0.1)
				(type default)
			)
			(layer "F.Fab")
		)
		(fp_line
			(start 0.12065 -0.2794)
			(end 0.12065 -0.3048)
			(stroke
				(width 0.1)
				(type default)
			)
			(layer "F.Fab")
		)
		(fp_line
			(start 0.67945 -0.3048)
			(end 0.67945 0.3048)
			(stroke
				(width 0.1)
				(type default)
			)
			(layer "F.Fab")
		)
		(fp_line
			(start 0.67945 0.3048)
			(end 0.120396 0.3048)
			(stroke
				(width 0.1)
				(type default)
			)
			(layer "F.Fab")
		)
		(pad "1" smd circle
			(at -0.40005 0)
			(size 0 0)
			(layers "F.Cu" "F.Mask" "F.Paste")
			(net "RST_PLTRST_PLD_B_N")
		)
		(pad "2" smd circle
			(at 0.40005 0)
			(size 0 0)
			(layers "F.Cu" "F.Mask" "F.Paste")
			(net "GND")
		)
	)
	(footprint ""
		(layer "F.Cu")
		(at 217.881962 -68.340478)
		(property "Reference" "PR3963"
			(at 0 0 0)
			(layer "F.SilkS")
			(hide yes)
			(effects
				(font
					(size 1.27 1.27)
				)
			)
		)
		(property "Value" ""
			(at 0 0 0)
			(layer "F.Fab")
			(effects
				(font
					(size 1.27 1.27)
				)
			)
		)
		(duplicate_pad_numbers_are_jumpers no)
		(fp_line
			(start -0.7874 -0.4064)
			(end 0.7874 -0.4064)
			(stroke
				(width 0.1524)
				(type default)
			)
			(layer "F.SilkS")
		)
		(fp_line
			(start -0.7874 0.4064)
			(end -0.7874 -0.4064)
			(stroke
				(width 0.1524)
				(type default)
			)
			(layer "F.SilkS")
		)
		(fp_line
			(start 0.7874 -0.4064)
			(end 0.7874 0.4064)
			(stroke
				(width 0.1524)
				(type default)
			)
			(layer "F.SilkS")
		)
		(fp_line
			(start 0.7874 0.4064)
			(end -0.7874 0.4064)
			(stroke
				(width 0.1524)
				(type default)
			)
			(layer "F.SilkS")
		)
		(fp_line
			(start -0.67945 -0.305054)
			(end -0.12065 -0.305054)
			(stroke
				(width 0.1)
				(type default)
			)
			(layer "F.Fab")
		)
		(fp_line
			(start -0.67945 0.3048)
			(end -0.67945 -0.305054)
			(stroke
				(width 0.1)
				(type default)
			)
			(layer "F.Fab")
		)
		(fp_line
			(start -0.12065 -0.305054)
			(end -0.12065 -0.2794)
			(stroke
				(width 0.1)
				(type default)
			)
			(layer "F.Fab")
		)
		(fp_line
			(start -0.12065 -0.2794)
			(end 0.12065 -0.2794)
			(stroke
				(width 0.1)
				(type default)
			)
			(layer "F.Fab")
		)
		(fp_line
			(start -0.12065 0.2794)
			(end -0.12065 0.3048)
			(stroke
				(width 0.1)
				(type default)
			)
			(layer "F.Fab")
		)
		(fp_line
			(start -0.12065 0.3048)
			(end -0.67945 0.3048)
			(stroke
				(width 0.1)
				(type default)
			)
			(layer "F.Fab")
		)
		(fp_line
			(start 0.120396 0.2794)
			(end -0.12065 0.2794)
			(stroke
				(width 0.1)
				(type default)
			)
			(layer "F.Fab")
		)
		(fp_line
			(start 0.120396 0.3048)
			(end 0.120396 0.2794)
			(stroke
				(width 0.1)
				(type default)
			)
			(layer "F.Fab")
		)
		(fp_line
			(start 0.12065 -0.3048)
			(end 0.67945 -0.3048)
			(stroke
				(width 0.1)
				(type default)
			)
			(layer "F.Fab")
		)
		(fp_line
			(start 0.12065 -0.2794)
			(end 0.12065 -0.3048)
			(stroke
				(width 0.1)
				(type default)
			)
			(layer "F.Fab")
		)
		(fp_line
			(start 0.67945 -0.3048)
			(end 0.67945 0.3048)
			(stroke
				(width 0.1)
				(type default)
			)
			(layer "F.Fab")
		)
		(fp_line
			(start 0.67945 0.3048)
			(end 0.120396 0.3048)
			(stroke
				(width 0.1)
				(type default)
			)
			(layer "F.Fab")
		)
		(pad "1" smd circle
			(at -0.40005 0)
			(size 0 0)
			(layers "F.Cu" "F.Mask" "F.Paste")
			(net "P3V3_AUX")
		)
		(pad "2" smd circle
			(at 0.40005 0)
			(size 0 0)
			(layers "F.Cu" "F.Mask" "F.Paste")
			(net "P3V3_E1S_UV_0")
		)
	)
	(footprint ""
		(layer "F.Cu")
		(at 351.6757 -64.440562)
		(property "Reference" "C143"
			(at 0 0 0)
			(layer "F.SilkS")
			(hide yes)
			(effects
				(font
					(size 1.27 1.27)
				)
			)
		)
		(property "Value" ""
			(at 0 0 0)
			(layer "F.Fab")
			(effects
				(font
					(size 1.27 1.27)
				)
			)
		)
		(duplicate_pad_numbers_are_jumpers no)
		(fp_line
			(start -0.299974 -0.150114)
			(end 0.299974 -0.150114)
			(stroke
				(width 0.1)
				(type default)
			)
			(layer "F.Fab")
		)
		(fp_line
			(start -0.299974 0.150114)
			(end -0.299974 -0.150114)
			(stroke
				(width 0.1)
				(type default)
			)
			(layer "F.Fab")
		)
		(fp_line
			(start 0.299974 -0.150114)
			(end 0.299974 0.150114)
			(stroke
				(width 0.1)
				(type default)
			)
			(layer "F.Fab")
		)
		(fp_line
			(start 0.299974 0.150114)
			(end -0.299974 0.150114)
			(stroke
				(width 0.1)
				(type default)
			)
			(layer "F.Fab")
		)
		(pad "1" smd rect
			(at -0.2667 0)
			(size 0.3048 0.381)
			(layers "F.Cu" "F.Mask" "F.Paste")
			(net "DMI_CPU0_PCH_TX_C_DN<5>")
		)
		(pad "2" smd rect
			(at 0.2667 0)
			(size 0.3048 0.381)
			(layers "F.Cu" "F.Mask" "F.Paste")
			(net "DMI_CPU0_PCH_TX_DN<5>")
		)
		(zone
			(layer "In1.Cu")
			(hatch none 0.5)
			(connect_pads
				(clearance 0)
			)
			(min_thickness 0.25)
			(keepout
				(tracks not_allowed)
				(vias allowed)
				(pads allowed)
				(copperpour not_allowed)
				(footprints allowed)
			)
			(placement
				(enabled no)
				(sheetname "")
			)
			(fill
				(thermal_gap 0.5)
				(thermal_bridge_width 0.5)
				(island_removal_mode 0)
			)
			(polygon
				(pts
					(arc
						(start 351.282 -64.199262)
						(mid 351.228118 -64.22158)
						(end 351.2058 -64.275462)
					)
					(arc
						(start 351.2058 -64.605662)
						(mid 351.228118 -64.659544)
						(end 351.282 -64.681862)
					)
					(arc
						(start 351.536 -64.681862)
						(mid 351.589882 -64.659544)
						(end 351.6122 -64.605662)
					)
					(arc
						(start 351.6122 -64.275462)
						(mid 351.589882 -64.22158)
						(end 351.536 -64.199262)
					)
				)
			)
		)
		(zone
			(layer "In1.Cu")
			(hatch none 0.5)
			(connect_pads
				(clearance 0)
			)
			(min_thickness 0.25)
			(keepout
				(tracks not_allowed)
				(vias allowed)
				(pads allowed)
				(copperpour not_allowed)
				(footprints allowed)
			)
			(placement
				(enabled no)
				(sheetname "")
			)
			(fill
				(thermal_gap 0.5)
				(thermal_bridge_width 0.5)
				(island_removal_mode 0)
			)
			(polygon
				(pts
					(arc
						(start 351.8154 -64.199262)
						(mid 351.761518 -64.22158)
						(end 351.7392 -64.275462)
					)
					(arc
						(start 351.7392 -64.605662)
						(mid 351.761518 -64.659544)
						(end 351.8154 -64.681862)
					)
					(arc
						(start 352.0694 -64.681862)
						(mid 352.123282 -64.659544)
						(end 352.1456 -64.605662)
					)
					(arc
						(start 352.1456 -64.275462)
						(mid 352.123282 -64.22158)
						(end 352.0694 -64.199262)
					)
				)
			)
		)
	)
	(footprint ""
		(layer "F.Cu")
		(at 420.682166 -137.178034 180)
		(property "Reference" "PC222"
			(at 0 0 180)
			(layer "F.SilkS")
			(hide yes)
			(effects
				(font
					(size 1.27 1.27)
				)
			)
		)
		(property "Value" ""
			(at 0 0 180)
			(layer "F.Fab")
			(effects
				(font
					(size 1.27 1.27)
				)
			)
		)
		(duplicate_pad_numbers_are_jumpers no)
		(fp_line
			(start 0.7874 0.4064)
			(end -0.7874 0.4064)
			(stroke
				(width 0.1524)
				(type default)
			)
			(layer "F.SilkS")
		)
		(fp_line
			(start 0.7874 -0.4064)
			(end 0.7874 0.4064)
			(stroke
				(width 0.1524)
				(type default)
			)
			(layer "F.SilkS")
		)
		(fp_line
			(start -0.7874 0.4064)
			(end -0.7874 -0.4064)
			(stroke
				(width 0.1524)
				(type default)
			)
			(layer "F.SilkS")
		)
		(fp_line
			(start -0.7874 -0.4064)
			(end 0.7874 -0.4064)
			(stroke
				(width 0.1524)
				(type default)
			)
			(layer "F.SilkS")
		)
		(fp_line
			(start 0.67945 0.3048)
			(end 0.120396 0.3048)
			(stroke
				(width 0.1)
				(type default)
			)
			(layer "F.Fab")
		)
		(fp_line
			(start 0.67945 -0.3048)
			(end 0.67945 0.3048)
			(stroke
				(width 0.1)
				(type default)
			)
			(layer "F.Fab")
		)
		(fp_line
			(start 0.12065 -0.2794)
			(end 0.12065 -0.3048)
			(stroke
				(width 0.1)
				(type default)
			)
			(layer "F.Fab")
		)
		(fp_line
			(start 0.12065 -0.3048)
			(end 0.67945 -0.3048)
			(stroke
				(width 0.1)
				(type default)
			)
			(layer "F.Fab")
		)
		(fp_line
			(start 0.120396 0.3048)
			(end 0.120396 0.2794)
			(stroke
				(width 0.1)
				(type default)
			)
			(layer "F.Fab")
		)
		(fp_line
			(start 0.120396 0.2794)
			(end -0.12065 0.2794)
			(stroke
				(width 0.1)
				(type default)
			)
			(layer "F.Fab")
		)
		(fp_line
			(start -0.12065 0.3048)
			(end -0.67945 0.3048)
			(stroke
				(width 0.1)
				(type default)
			)
			(layer "F.Fab")
		)
		(fp_line
			(start -0.12065 0.2794)
			(end -0.12065 0.3048)
			(stroke
				(width 0.1)
				(type default)
			)
			(layer "F.Fab")
		)
		(fp_line
			(start -0.12065 -0.2794)
			(end 0.12065 -0.2794)
			(stroke
				(width 0.1)
				(type default)
			)
			(layer "F.Fab")
		)
		(fp_line
			(start -0.12065 -0.305054)
			(end -0.12065 -0.2794)
			(stroke
				(width 0.1)
				(type default)
			)
			(layer "F.Fab")
		)
		(fp_line
			(start -0.67945 0.3048)
			(end -0.67945 -0.305054)
			(stroke
				(width 0.1)
				(type default)
			)
			(layer "F.Fab")
		)
		(fp_line
			(start -0.67945 -0.305054)
			(end -0.12065 -0.305054)
			(stroke
				(width 0.1)
				(type default)
			)
			(layer "F.Fab")
		)
		(pad "1" smd circle
			(at -0.40005 0 180)
			(size 0 0)
			(layers "F.Cu" "F.Mask" "F.Paste")
			(net "PVCCINFAON_CPU0_ATSEN")
		)
		(pad "2" smd circle
			(at 0.40005 0 180)
			(size 0 0)
			(layers "F.Cu" "F.Mask" "F.Paste")
			(net "GND")
		)
	)
	(footprint ""
		(layer "F.Cu")
		(at 449.52666 -51.976528)
		(property "Reference" "PC1866"
			(at 0 0 0)
			(layer "F.SilkS")
			(hide yes)
			(effects
				(font
					(size 1.27 1.27)
				)
			)
		)
		(property "Value" ""
			(at 0 0 0)
			(layer "F.Fab")
			(effects
				(font
					(size 1.27 1.27)
				)
			)
		)
		(duplicate_pad_numbers_are_jumpers no)
		(fp_line
			(start -3.400044 1.249934)
			(end 3.400044 1.249934)
			(stroke
				(width 0.1524)
				(type default)
			)
			(layer "F.SilkS")
		)
		(fp_circle
			(center 0 1.249934)
			(end 3.400044 1.249934)
			(stroke
				(width 0.1524)
				(type default)
			)
			(fill no)
			(layer "F.SilkS")
		)
		(fp_poly
			(pts
				(arc
					(start 3.400044 1.249934)
					(mid 0 4.649978)
					(end -3.400044 1.249934)
				)
			)
			(stroke
				(width 0)
				(type default)
			)
			(fill yes)
			(layer "F.SilkS")
		)
		(fp_circle
			(center 0 1.249934)
			(end 3.400044 1.249934)
			(stroke
				(width 0.1)
				(type default)
			)
			(fill no)
			(layer "F.Fab")
		)
		(pad "1" thru_hole rect
			(at 0 0)
			(size 1.524 1.524)
			(drill 1.016)
			(layers "*.Cu" "*.Mask")
			(remove_unused_layers no)
			(net "P3V3_AUX")
			(clearance 0)
			(padstack
				(mode front_inner_back)
				(layer "Inner"
					(shape circle)
					(size 1.524 1.524)
					(clearance 0)
				)
				(layer "B.Cu"
					(shape rect)
					(size 1.524 1.524)
					(clearance 0)
				)
			)
		)
		(pad "2" thru_hole circle
			(at 0 2.500122)
			(size 1.524 1.524)
			(drill 1.016)
			(layers "*.Cu" "*.Mask")
			(remove_unused_layers no)
			(net "GND")
			(clearance 0)
		)
	)
	(footprint ""
		(layer "F.Cu")
		(at 136.791954 -408.517344 -90)
		(property "Reference" "C1526"
			(at 0 0 270)
			(layer "F.SilkS")
			(hide yes)
			(effects
				(font
					(size 1.27 1.27)
				)
			)
		)
		(property "Value" ""
			(at 0 0 270)
			(layer "F.Fab")
			(effects
				(font
					(size 1.27 1.27)
				)
			)
		)
		(duplicate_pad_numbers_are_jumpers no)
		(fp_line
			(start -0.299974 0.150114)
			(end -0.299974 -0.150114)
			(stroke
				(width 0.1)
				(type default)
			)
			(layer "F.Fab")
		)
		(fp_line
			(start 0.299974 0.150114)
			(end -0.299974 0.150114)
			(stroke
				(width 0.1)
				(type default)
			)
			(layer "F.Fab")
		)
		(fp_line
			(start -0.299974 -0.150114)
			(end 0.299974 -0.150114)
			(stroke
				(width 0.1)
				(type default)
			)
			(layer "F.Fab")
		)
		(fp_line
			(start 0.299974 -0.150114)
			(end 0.299974 0.150114)
			(stroke
				(width 0.1)
				(type default)
			)
			(layer "F.Fab")
		)
		(pad "1" smd rect
			(at -0.2667 0 270)
			(size 0.3048 0.381)
			(layers "F.Cu" "F.Mask" "F.Paste")
			(net "P5E_CPU1_PE3_TX_C_DN<10>")
		)
		(pad "2" smd rect
			(at 0.2667 0 270)
			(size 0.3048 0.381)
			(layers "F.Cu" "F.Mask" "F.Paste")
			(net "P5E_CPU1_PE3_TX_DN<10>")
		)
	)
	(footprint ""
		(layer "F.Cu")
		(at 310.081168 -402.371052 -90)
		(property "Reference" "C1574"
			(at 0 0 270)
			(layer "F.SilkS")
			(hide yes)
			(effects
				(font
					(size 1.27 1.27)
				)
			)
		)
		(property "Value" ""
			(at 0 0 270)
			(layer "F.Fab")
			(effects
				(font
					(size 1.27 1.27)
				)
			)
		)
		(duplicate_pad_numbers_are_jumpers no)
		(fp_line
			(start -0.299974 0.150114)
			(end -0.299974 -0.150114)
			(stroke
				(width 0.1)
				(type default)
			)
			(layer "F.Fab")
		)
		(fp_line
			(start 0.299974 0.150114)
			(end -0.299974 0.150114)
			(stroke
				(width 0.1)
				(type default)
			)
			(layer "F.Fab")
		)
		(fp_line
			(start -0.299974 -0.150114)
			(end 0.299974 -0.150114)
			(stroke
				(width 0.1)
				(type default)
			)
			(layer "F.Fab")
		)
		(fp_line
			(start 0.299974 -0.150114)
			(end 0.299974 0.150114)
			(stroke
				(width 0.1)
				(type default)
			)
			(layer "F.Fab")
		)
		(pad "1" smd rect
			(at -0.2667 0 270)
			(size 0.3048 0.381)
			(layers "F.Cu" "F.Mask" "F.Paste")
			(net "P5E_CPU0_PE4_TX_C_DN<2>")
		)
		(pad "2" smd rect
			(at 0.2667 0 270)
			(size 0.3048 0.381)
			(layers "F.Cu" "F.Mask" "F.Paste")
			(net "P5E_CPU0_PE4_TX_DN<2>")
		)
	)
	(footprint ""
		(layer "F.Cu")
		(at 332.26756 -343.005156 -90)
		(property "Reference" "PC233_P0_7"
			(at 0 0 270)
			(layer "F.SilkS")
			(hide yes)
			(effects
				(font
					(size 1.27 1.27)
				)
			)
		)
		(property "Value" ""
			(at 0 0 270)
			(layer "F.Fab")
			(effects
				(font
					(size 1.27 1.27)
				)
			)
		)
		(duplicate_pad_numbers_are_jumpers no)
		(fp_line
			(start -0.7874 0.4064)
			(end -0.7874 -0.4064)
			(stroke
				(width 0.1524)
				(type default)
			)
			(layer "F.SilkS")
		)
		(fp_line
			(start 0.7874 0.4064)
			(end -0.7874 0.4064)
			(stroke
				(width 0.1524)
				(type default)
			)
			(layer "F.SilkS")
		)
		(fp_line
			(start -0.7874 -0.4064)
			(end 0.7874 -0.4064)
			(stroke
				(width 0.1524)
				(type default)
			)
			(layer "F.SilkS")
		)
		(fp_line
			(start 0.7874 -0.4064)
			(end 0.7874 0.4064)
			(stroke
				(width 0.1524)
				(type default)
			)
			(layer "F.SilkS")
		)
		(fp_line
			(start -0.67945 0.3048)
			(end -0.67945 -0.305054)
			(stroke
				(width 0.1)
				(type default)
			)
			(layer "F.Fab")
		)
		(fp_line
			(start -0.12065 0.3048)
			(end -0.67945 0.3048)
			(stroke
				(width 0.1)
				(type default)
			)
			(layer "F.Fab")
		)
		(fp_line
			(start 0.120396 0.3048)
			(end 0.120396 0.2794)
			(stroke
				(width 0.1)
				(type default)
			)
			(layer "F.Fab")
		)
		(fp_line
			(start 0.67945 0.3048)
			(end 0.120396 0.3048)
			(stroke
				(width 0.1)
				(type default)
			)
			(layer "F.Fab")
		)
		(fp_line
			(start -0.12065 0.2794)
			(end -0.12065 0.3048)
			(stroke
				(width 0.1)
				(type default)
			)
			(layer "F.Fab")
		)
		(fp_line
			(start 0.120396 0.2794)
			(end -0.12065 0.2794)
			(stroke
				(width 0.1)
				(type default)
			)
			(layer "F.Fab")
		)
		(fp_line
			(start -0.12065 -0.2794)
			(end 0.12065 -0.2794)
			(stroke
				(width 0.1)
				(type default)
			)
			(layer "F.Fab")
		)
		(fp_line
			(start 0.12065 -0.2794)
			(end 0.12065 -0.3048)
			(stroke
				(width 0.1)
				(type default)
			)
			(layer "F.Fab")
		)
		(fp_line
			(start 0.12065 -0.3048)
			(end 0.67945 -0.3048)
			(stroke
				(width 0.1)
				(type default)
			)
			(layer "F.Fab")
		)
		(fp_line
			(start 0.67945 -0.3048)
			(end 0.67945 0.3048)
			(stroke
				(width 0.1)
				(type default)
			)
			(layer "F.Fab")
		)
		(fp_line
			(start -0.67945 -0.305054)
			(end -0.12065 -0.305054)
			(stroke
				(width 0.1)
				(type default)
			)
			(layer "F.Fab")
		)
		(fp_line
			(start -0.12065 -0.305054)
			(end -0.12065 -0.2794)
			(stroke
				(width 0.1)
				(type default)
			)
			(layer "F.Fab")
		)
		(pad "1" smd circle
			(at -0.40005 0 270)
			(size 0 0)
			(layers "F.Cu" "F.Mask" "F.Paste")
			(net "SW_P12V_PVCCIN_CPU0_FLT")
		)
		(pad "2" smd circle
			(at 0.40005 0 270)
			(size 0 0)
			(layers "F.Cu" "F.Mask" "F.Paste")
			(net "GND")
		)
	)
	(footprint ""
		(layer "F.Cu")
		(at 332.115668 -76.153518 90)
		(property "Reference" "R4306"
			(at 0 0 90)
			(layer "F.SilkS")
			(hide yes)
			(effects
				(font
					(size 1.27 1.27)
				)
			)
		)
		(property "Value" ""
			(at 0 0 90)
			(layer "F.Fab")
			(effects
				(font
					(size 1.27 1.27)
				)
			)
		)
		(duplicate_pad_numbers_are_jumpers no)
		(fp_line
			(start 0.7874 -0.4064)
			(end 0.7874 0.4064)
			(stroke
				(width 0.1524)
				(type default)
			)
			(layer "F.SilkS")
		)
		(fp_line
			(start -0.7874 -0.4064)
			(end 0.7874 -0.4064)
			(stroke
				(width 0.1524)
				(type default)
			)
			(layer "F.SilkS")
		)
		(fp_line
			(start 0.7874 0.4064)
			(end -0.7874 0.4064)
			(stroke
				(width 0.1524)
				(type default)
			)
			(layer "F.SilkS")
		)
		(fp_line
			(start -0.7874 0.4064)
			(end -0.7874 -0.4064)
			(stroke
				(width 0.1524)
				(type default)
			)
			(layer "F.SilkS")
		)
		(fp_line
			(start -0.12065 -0.305054)
			(end -0.12065 -0.2794)
			(stroke
				(width 0.1)
				(type default)
			)
			(layer "F.Fab")
		)
		(fp_line
			(start -0.67945 -0.305054)
			(end -0.12065 -0.305054)
			(stroke
				(width 0.1)
				(type default)
			)
			(layer "F.Fab")
		)
		(fp_line
			(start 0.67945 -0.3048)
			(end 0.67945 0.3048)
			(stroke
				(width 0.1)
				(type default)
			)
			(layer "F.Fab")
		)
		(fp_line
			(start 0.12065 -0.3048)
			(end 0.67945 -0.3048)
			(stroke
				(width 0.1)
				(type default)
			)
			(layer "F.Fab")
		)
		(fp_line
			(start 0.12065 -0.2794)
			(end 0.12065 -0.3048)
			(stroke
				(width 0.1)
				(type default)
			)
			(layer "F.Fab")
		)
		(fp_line
			(start -0.12065 -0.2794)
			(end 0.12065 -0.2794)
			(stroke
				(width 0.1)
				(type default)
			)
			(layer "F.Fab")
		)
		(fp_line
			(start 0.120396 0.2794)
			(end -0.12065 0.2794)
			(stroke
				(width 0.1)
				(type default)
			)
			(layer "F.Fab")
		)
		(fp_line
			(start -0.12065 0.2794)
			(end -0.12065 0.3048)
			(stroke
				(width 0.1)
				(type default)
			)
			(layer "F.Fab")
		)
		(fp_line
			(start 0.67945 0.3048)
			(end 0.120396 0.3048)
			(stroke
				(width 0.1)
				(type default)
			)
			(layer "F.Fab")
		)
		(fp_line
			(start 0.120396 0.3048)
			(end 0.120396 0.2794)
			(stroke
				(width 0.1)
				(type default)
			)
			(layer "F.Fab")
		)
		(fp_line
			(start -0.12065 0.3048)
			(end -0.67945 0.3048)
			(stroke
				(width 0.1)
				(type default)
			)
			(layer "F.Fab")
		)
		(fp_line
			(start -0.67945 0.3048)
			(end -0.67945 -0.305054)
			(stroke
				(width 0.1)
				(type default)
			)
			(layer "F.Fab")
		)
		(pad "1" smd circle
			(at -0.40005 0 90)
			(size 0 0)
			(layers "F.Cu" "F.Mask" "F.Paste")
			(net "CLK_100M_PE_M2_0_R_DN")
		)
		(pad "2" smd circle
			(at 0.40005 0 90)
			(size 0 0)
			(layers "F.Cu" "F.Mask" "F.Paste")
			(net "CLK_100M_PE_M2_0_DN")
		)
	)
	(footprint ""
		(layer "F.Cu")
		(at 163.50615 -430.706276)
		(property "Reference" "R2705"
			(at 0 0 0)
			(layer "F.SilkS")
			(hide yes)
			(effects
				(font
					(size 1.27 1.27)
				)
			)
		)
		(property "Value" ""
			(at 0 0 0)
			(layer "F.Fab")
			(effects
				(font
					(size 1.27 1.27)
				)
			)
		)
		(duplicate_pad_numbers_are_jumpers no)
		(fp_line
			(start -0.7874 -0.4064)
			(end 0.7874 -0.4064)
			(stroke
				(width 0.1524)
				(type default)
			)
			(layer "F.SilkS")
		)
		(fp_line
			(start -0.7874 0.4064)
			(end -0.7874 -0.4064)
			(stroke
				(width 0.1524)
				(type default)
			)
			(layer "F.SilkS")
		)
		(fp_line
			(start 0.7874 -0.4064)
			(end 0.7874 0.4064)
			(stroke
				(width 0.1524)
				(type default)
			)
			(layer "F.SilkS")
		)
		(fp_line
			(start 0.7874 0.4064)
			(end -0.7874 0.4064)
			(stroke
				(width 0.1524)
				(type default)
			)
			(layer "F.SilkS")
		)
		(fp_line
			(start -0.67945 -0.305054)
			(end -0.12065 -0.305054)
			(stroke
				(width 0.1)
				(type default)
			)
			(layer "F.Fab")
		)
		(fp_line
			(start -0.67945 0.3048)
			(end -0.67945 -0.305054)
			(stroke
				(width 0.1)
				(type default)
			)
			(layer "F.Fab")
		)
		(fp_line
			(start -0.12065 -0.305054)
			(end -0.12065 -0.2794)
			(stroke
				(width 0.1)
				(type default)
			)
			(layer "F.Fab")
		)
		(fp_line
			(start -0.12065 -0.2794)
			(end 0.12065 -0.2794)
			(stroke
				(width 0.1)
				(type default)
			)
			(layer "F.Fab")
		)
		(fp_line
			(start -0.12065 0.2794)
			(end -0.12065 0.3048)
			(stroke
				(width 0.1)
				(type default)
			)
			(layer "F.Fab")
		)
		(fp_line
			(start -0.12065 0.3048)
			(end -0.67945 0.3048)
			(stroke
				(width 0.1)
				(type default)
			)
			(layer "F.Fab")
		)
		(fp_line
			(start 0.120396 0.2794)
			(end -0.12065 0.2794)
			(stroke
				(width 0.1)
				(type default)
			)
			(layer "F.Fab")
		)
		(fp_line
			(start 0.120396 0.3048)
			(end 0.120396 0.2794)
			(stroke
				(width 0.1)
				(type default)
			)
			(layer "F.Fab")
		)
		(fp_line
			(start 0.12065 -0.3048)
			(end 0.67945 -0.3048)
			(stroke
				(width 0.1)
				(type default)
			)
			(layer "F.Fab")
		)
		(fp_line
			(start 0.12065 -0.2794)
			(end 0.12065 -0.3048)
			(stroke
				(width 0.1)
				(type default)
			)
			(layer "F.Fab")
		)
		(fp_line
			(start 0.67945 -0.3048)
			(end 0.67945 0.3048)
			(stroke
				(width 0.1)
				(type default)
			)
			(layer "F.Fab")
		)
		(fp_line
			(start 0.67945 0.3048)
			(end 0.120396 0.3048)
			(stroke
				(width 0.1)
				(type default)
			)
			(layer "F.Fab")
		)
		(pad "1" smd circle
			(at -0.40005 0)
			(size 0 0)
			(layers "F.Cu" "F.Mask" "F.Paste")
			(net "SMB_BMC_SWB_R_SCL")
		)
		(pad "2" smd circle
			(at 0.40005 0)
			(size 0 0)
			(layers "F.Cu" "F.Mask" "F.Paste")
			(net "SMB_BMC_SWB_BUF_R_SCL")
		)
	)
	(footprint ""
		(layer "F.Cu")
		(at 399.312384 -17.612614 90)
		(property "Reference" "C845"
			(at 0 0 90)
			(layer "F.SilkS")
			(hide yes)
			(effects
				(font
					(size 1.27 1.27)
				)
			)
		)
		(property "Value" ""
			(at 0 0 90)
			(layer "F.Fab")
			(effects
				(font
					(size 1.27 1.27)
				)
			)
		)
		(duplicate_pad_numbers_are_jumpers no)
		(fp_line
			(start 0.299974 -0.150114)
			(end 0.299974 0.150114)
			(stroke
				(width 0.1)
				(type default)
			)
			(layer "F.Fab")
		)
		(fp_line
			(start -0.299974 -0.150114)
			(end 0.299974 -0.150114)
			(stroke
				(width 0.1)
				(type default)
			)
			(layer "F.Fab")
		)
		(fp_line
			(start 0.299974 0.150114)
			(end -0.299974 0.150114)
			(stroke
				(width 0.1)
				(type default)
			)
			(layer "F.Fab")
		)
		(fp_line
			(start -0.299974 0.150114)
			(end -0.299974 -0.150114)
			(stroke
				(width 0.1)
				(type default)
			)
			(layer "F.Fab")
		)
		(pad "1" smd rect
			(at -0.2667 0 90)
			(size 0.3048 0.381)
			(layers "F.Cu" "F.Mask" "F.Paste")
			(net "P5E_CPU0_PE1_TX_C_DP<12>")
		)
		(pad "2" smd rect
			(at 0.2667 0 90)
			(size 0.3048 0.381)
			(layers "F.Cu" "F.Mask" "F.Paste")
			(net "P5E_CPU0_PE1_TX_DP<12>")
		)
	)
	(footprint ""
		(layer "F.Cu")
		(at 430.991518 -366.65027)
		(property "Reference" "PC722_P0_3"
			(at 0 0 0)
			(layer "F.SilkS")
			(hide yes)
			(effects
				(font
					(size 1.27 1.27)
				)
			)
		)
		(property "Value" ""
			(at 0 0 0)
			(layer "F.Fab")
			(effects
				(font
					(size 1.27 1.27)
				)
			)
		)
		(duplicate_pad_numbers_are_jumpers no)
		(fp_line
			(start -1.524 -0.762)
			(end 1.524 -0.762)
			(stroke
				(width 0.1524)
				(type default)
			)
			(layer "F.SilkS")
		)
		(fp_line
			(start -1.524 0.762)
			(end -1.524 -0.762)
			(stroke
				(width 0.1524)
				(type default)
			)
			(layer "F.SilkS")
		)
		(fp_line
			(start 1.524 -0.762)
			(end 1.524 0.762)
			(stroke
				(width 0.1524)
				(type default)
			)
			(layer "F.SilkS")
		)
		(fp_line
			(start 1.524 0.762)
			(end -1.524 0.762)
			(stroke
				(width 0.1524)
				(type default)
			)
			(layer "F.SilkS")
		)
		(fp_line
			(start -1.1049 -0.724916)
			(end -1.1049 0.724916)
			(stroke
				(width 0.1)
				(type default)
			)
			(layer "F.Fab")
		)
		(fp_line
			(start -1.1049 0.724916)
			(end 1.1049 0.724916)
			(stroke
				(width 0.1)
				(type default)
			)
			(layer "F.Fab")
		)
		(fp_line
			(start 1.1049 -0.724916)
			(end -1.1049 -0.724916)
			(stroke
				(width 0.1)
				(type default)
			)
			(layer "F.Fab")
		)
		(fp_line
			(start 1.1049 0.724916)
			(end 1.1049 -0.724916)
			(stroke
				(width 0.1)
				(type default)
			)
			(layer "F.Fab")
		)
		(pad "1" smd rect
			(at -0.889 0 180)
			(size 1.016 1.27)
			(layers "F.Cu" "F.Mask" "F.Paste")
			(net "SW_P12V_PVCCFA_EHV_FIVRA_CPU0_R")
		)
		(pad "2" smd rect
			(at 0.889 0 180)
			(size 1.016 1.27)
			(layers "F.Cu" "F.Mask" "F.Paste")
			(net "GND")
		)
	)
	(footprint ""
		(layer "F.Cu")
		(at 162.23488 -58.511948)
		(property "Reference" "R2476"
			(at 0 0 0)
			(layer "F.SilkS")
			(hide yes)
			(effects
				(font
					(size 1.27 1.27)
				)
			)
		)
		(property "Value" ""
			(at 0 0 0)
			(layer "F.Fab")
			(effects
				(font
					(size 1.27 1.27)
				)
			)
		)
		(duplicate_pad_numbers_are_jumpers no)
		(fp_line
			(start -0.7874 -0.4064)
			(end 0.7874 -0.4064)
			(stroke
				(width 0.1524)
				(type default)
			)
			(layer "F.SilkS")
		)
		(fp_line
			(start -0.7874 0.4064)
			(end -0.7874 -0.4064)
			(stroke
				(width 0.1524)
				(type default)
			)
			(layer "F.SilkS")
		)
		(fp_line
			(start 0.7874 -0.4064)
			(end 0.7874 0.4064)
			(stroke
				(width 0.1524)
				(type default)
			)
			(layer "F.SilkS")
		)
		(fp_line
			(start 0.7874 0.4064)
			(end -0.7874 0.4064)
			(stroke
				(width 0.1524)
				(type default)
			)
			(layer "F.SilkS")
		)
		(fp_line
			(start -0.67945 -0.305054)
			(end -0.12065 -0.305054)
			(stroke
				(width 0.1)
				(type default)
			)
			(layer "F.Fab")
		)
		(fp_line
			(start -0.67945 0.3048)
			(end -0.67945 -0.305054)
			(stroke
				(width 0.1)
				(type default)
			)
			(layer "F.Fab")
		)
		(fp_line
			(start -0.12065 -0.305054)
			(end -0.12065 -0.2794)
			(stroke
				(width 0.1)
				(type default)
			)
			(layer "F.Fab")
		)
		(fp_line
			(start -0.12065 -0.2794)
			(end 0.12065 -0.2794)
			(stroke
				(width 0.1)
				(type default)
			)
			(layer "F.Fab")
		)
		(fp_line
			(start -0.12065 0.2794)
			(end -0.12065 0.3048)
			(stroke
				(width 0.1)
				(type default)
			)
			(layer "F.Fab")
		)
		(fp_line
			(start -0.12065 0.3048)
			(end -0.67945 0.3048)
			(stroke
				(width 0.1)
				(type default)
			)
			(layer "F.Fab")
		)
		(fp_line
			(start 0.120396 0.2794)
			(end -0.12065 0.2794)
			(stroke
				(width 0.1)
				(type default)
			)
			(layer "F.Fab")
		)
		(fp_line
			(start 0.120396 0.3048)
			(end 0.120396 0.2794)
			(stroke
				(width 0.1)
				(type default)
			)
			(layer "F.Fab")
		)
		(fp_line
			(start 0.12065 -0.3048)
			(end 0.67945 -0.3048)
			(stroke
				(width 0.1)
				(type default)
			)
			(layer "F.Fab")
		)
		(fp_line
			(start 0.12065 -0.2794)
			(end 0.12065 -0.3048)
			(stroke
				(width 0.1)
				(type default)
			)
			(layer "F.Fab")
		)
		(fp_line
			(start 0.67945 -0.3048)
			(end 0.67945 0.3048)
			(stroke
				(width 0.1)
				(type default)
			)
			(layer "F.Fab")
		)
		(fp_line
			(start 0.67945 0.3048)
			(end 0.120396 0.3048)
			(stroke
				(width 0.1)
				(type default)
			)
			(layer "F.Fab")
		)
		(pad "1" smd circle
			(at -0.40005 0)
			(size 0 0)
			(layers "F.Cu" "F.Mask" "F.Paste")
			(net "SMB_PCIE_M2_0_EN")
		)
		(pad "2" smd circle
			(at 0.40005 0)
			(size 0 0)
			(layers "F.Cu" "F.Mask" "F.Paste")
			(net "PWRGD_P1V8_PCH_AUX")
		)
	)
	(footprint ""
		(layer "F.Cu")
		(at 140.70838 -33.466024)
		(property "Reference" "C1879"
			(at 0 0 0)
			(layer "F.SilkS")
			(hide yes)
			(effects
				(font
					(size 1.27 1.27)
				)
			)
		)
		(property "Value" ""
			(at 0 0 0)
			(layer "F.Fab")
			(effects
				(font
					(size 1.27 1.27)
				)
			)
		)
		(duplicate_pad_numbers_are_jumpers no)
		(fp_line
			(start -0.7874 -0.4064)
			(end 0.7874 -0.4064)
			(stroke
				(width 0.1524)
				(type default)
			)
			(layer "F.SilkS")
		)
		(fp_line
			(start -0.7874 0.4064)
			(end -0.7874 -0.4064)
			(stroke
				(width 0.1524)
				(type default)
			)
			(layer "F.SilkS")
		)
		(fp_line
			(start 0.7874 -0.4064)
			(end 0.7874 0.4064)
			(stroke
				(width 0.1524)
				(type default)
			)
			(layer "F.SilkS")
		)
		(fp_line
			(start 0.7874 0.4064)
			(end -0.7874 0.4064)
			(stroke
				(width 0.1524)
				(type default)
			)
			(layer "F.SilkS")
		)
		(fp_line
			(start -0.67945 -0.305054)
			(end -0.12065 -0.305054)
			(stroke
				(width 0.1)
				(type default)
			)
			(layer "F.Fab")
		)
		(fp_line
			(start -0.67945 0.3048)
			(end -0.67945 -0.305054)
			(stroke
				(width 0.1)
				(type default)
			)
			(layer "F.Fab")
		)
		(fp_line
			(start -0.12065 -0.305054)
			(end -0.12065 -0.2794)
			(stroke
				(width 0.1)
				(type default)
			)
			(layer "F.Fab")
		)
		(fp_line
			(start -0.12065 -0.2794)
			(end 0.12065 -0.2794)
			(stroke
				(width 0.1)
				(type default)
			)
			(layer "F.Fab")
		)
		(fp_line
			(start -0.12065 0.2794)
			(end -0.12065 0.3048)
			(stroke
				(width 0.1)
				(type default)
			)
			(layer "F.Fab")
		)
		(fp_line
			(start -0.12065 0.3048)
			(end -0.67945 0.3048)
			(stroke
				(width 0.1)
				(type default)
			)
			(layer "F.Fab")
		)
		(fp_line
			(start 0.120396 0.2794)
			(end -0.12065 0.2794)
			(stroke
				(width 0.1)
				(type default)
			)
			(layer "F.Fab")
		)
		(fp_line
			(start 0.120396 0.3048)
			(end 0.120396 0.2794)
			(stroke
				(width 0.1)
				(type default)
			)
			(layer "F.Fab")
		)
		(fp_line
			(start 0.12065 -0.3048)
			(end 0.67945 -0.3048)
			(stroke
				(width 0.1)
				(type default)
			)
			(layer "F.Fab")
		)
		(fp_line
			(start 0.12065 -0.2794)
			(end 0.12065 -0.3048)
			(stroke
				(width 0.1)
				(type default)
			)
			(layer "F.Fab")
		)
		(fp_line
			(start 0.67945 -0.3048)
			(end 0.67945 0.3048)
			(stroke
				(width 0.1)
				(type default)
			)
			(layer "F.Fab")
		)
		(fp_line
			(start 0.67945 0.3048)
			(end 0.120396 0.3048)
			(stroke
				(width 0.1)
				(type default)
			)
			(layer "F.Fab")
		)
		(pad "1" smd circle
			(at -0.40005 0)
			(size 0 0)
			(layers "F.Cu" "F.Mask" "F.Paste")
			(net "P3V3_AUX")
		)
		(pad "2" smd circle
			(at 0.40005 0)
			(size 0 0)
			(layers "F.Cu" "F.Mask" "F.Paste")
			(net "GND")
		)
	)
	(footprint ""
		(layer "F.Cu")
		(at 385.716272 -59.719464)
		(property "Reference" "R768"
			(at 0 0 0)
			(layer "F.SilkS")
			(hide yes)
			(effects
				(font
					(size 1.27 1.27)
				)
			)
		)
		(property "Value" ""
			(at 0 0 0)
			(layer "F.Fab")
			(effects
				(font
					(size 1.27 1.27)
				)
			)
		)
		(duplicate_pad_numbers_are_jumpers no)
		(fp_line
			(start -0.7874 -0.4064)
			(end 0.7874 -0.4064)
			(stroke
				(width 0.1524)
				(type default)
			)
			(layer "F.SilkS")
		)
		(fp_line
			(start -0.7874 0.4064)
			(end -0.7874 -0.4064)
			(stroke
				(width 0.1524)
				(type default)
			)
			(layer "F.SilkS")
		)
		(fp_line
			(start 0.7874 -0.4064)
			(end 0.7874 0.4064)
			(stroke
				(width 0.1524)
				(type default)
			)
			(layer "F.SilkS")
		)
		(fp_line
			(start 0.7874 0.4064)
			(end -0.7874 0.4064)
			(stroke
				(width 0.1524)
				(type default)
			)
			(layer "F.SilkS")
		)
		(fp_line
			(start -0.67945 -0.305054)
			(end -0.12065 -0.305054)
			(stroke
				(width 0.1)
				(type default)
			)
			(layer "F.Fab")
		)
		(fp_line
			(start -0.67945 0.3048)
			(end -0.67945 -0.305054)
			(stroke
				(width 0.1)
				(type default)
			)
			(layer "F.Fab")
		)
		(fp_line
			(start -0.12065 -0.305054)
			(end -0.12065 -0.2794)
			(stroke
				(width 0.1)
				(type default)
			)
			(layer "F.Fab")
		)
		(fp_line
			(start -0.12065 -0.2794)
			(end 0.12065 -0.2794)
			(stroke
				(width 0.1)
				(type default)
			)
			(layer "F.Fab")
		)
		(fp_line
			(start -0.12065 0.2794)
			(end -0.12065 0.3048)
			(stroke
				(width 0.1)
				(type default)
			)
			(layer "F.Fab")
		)
		(fp_line
			(start -0.12065 0.3048)
			(end -0.67945 0.3048)
			(stroke
				(width 0.1)
				(type default)
			)
			(layer "F.Fab")
		)
		(fp_line
			(start 0.120396 0.2794)
			(end -0.12065 0.2794)
			(stroke
				(width 0.1)
				(type default)
			)
			(layer "F.Fab")
		)
		(fp_line
			(start 0.120396 0.3048)
			(end 0.120396 0.2794)
			(stroke
				(width 0.1)
				(type default)
			)
			(layer "F.Fab")
		)
		(fp_line
			(start 0.12065 -0.3048)
			(end 0.67945 -0.3048)
			(stroke
				(width 0.1)
				(type default)
			)
			(layer "F.Fab")
		)
		(fp_line
			(start 0.12065 -0.2794)
			(end 0.12065 -0.3048)
			(stroke
				(width 0.1)
				(type default)
			)
			(layer "F.Fab")
		)
		(fp_line
			(start 0.67945 -0.3048)
			(end 0.67945 0.3048)
			(stroke
				(width 0.1)
				(type default)
			)
			(layer "F.Fab")
		)
		(fp_line
			(start 0.67945 0.3048)
			(end 0.120396 0.3048)
			(stroke
				(width 0.1)
				(type default)
			)
			(layer "F.Fab")
		)
		(pad "1" smd circle
			(at -0.40005 0)
			(size 0 0)
			(layers "F.Cu" "F.Mask" "F.Paste")
			(net "P3V3_AUX")
		)
		(pad "2" smd circle
			(at 0.40005 0)
			(size 0 0)
			(layers "F.Cu" "F.Mask" "F.Paste")
			(net "JTAG_DBP_PRESENT_R_N")
		)
	)
	(footprint ""
		(layer "F.Cu")
		(at 307.14188 -48.097948)
		(property "Reference" "R7"
			(at 0 0 0)
			(layer "F.SilkS")
			(hide yes)
			(effects
				(font
					(size 1.27 1.27)
				)
			)
		)
		(property "Value" ""
			(at 0 0 0)
			(layer "F.Fab")
			(effects
				(font
					(size 1.27 1.27)
				)
			)
		)
		(duplicate_pad_numbers_are_jumpers no)
		(fp_line
			(start -0.7874 -0.4064)
			(end 0.7874 -0.4064)
			(stroke
				(width 0.1524)
				(type default)
			)
			(layer "F.SilkS")
		)
		(fp_line
			(start -0.7874 0.4064)
			(end -0.7874 -0.4064)
			(stroke
				(width 0.1524)
				(type default)
			)
			(layer "F.SilkS")
		)
		(fp_line
			(start 0.7874 -0.4064)
			(end 0.7874 0.4064)
			(stroke
				(width 0.1524)
				(type default)
			)
			(layer "F.SilkS")
		)
		(fp_line
			(start 0.7874 0.4064)
			(end -0.7874 0.4064)
			(stroke
				(width 0.1524)
				(type default)
			)
			(layer "F.SilkS")
		)
		(fp_line
			(start -0.67945 -0.305054)
			(end -0.12065 -0.305054)
			(stroke
				(width 0.1)
				(type default)
			)
			(layer "F.Fab")
		)
		(fp_line
			(start -0.67945 0.3048)
			(end -0.67945 -0.305054)
			(stroke
				(width 0.1)
				(type default)
			)
			(layer "F.Fab")
		)
		(fp_line
			(start -0.12065 -0.305054)
			(end -0.12065 -0.2794)
			(stroke
				(width 0.1)
				(type default)
			)
			(layer "F.Fab")
		)
		(fp_line
			(start -0.12065 -0.2794)
			(end 0.12065 -0.2794)
			(stroke
				(width 0.1)
				(type default)
			)
			(layer "F.Fab")
		)
		(fp_line
			(start -0.12065 0.2794)
			(end -0.12065 0.3048)
			(stroke
				(width 0.1)
				(type default)
			)
			(layer "F.Fab")
		)
		(fp_line
			(start -0.12065 0.3048)
			(end -0.67945 0.3048)
			(stroke
				(width 0.1)
				(type default)
			)
			(layer "F.Fab")
		)
		(fp_line
			(start 0.120396 0.2794)
			(end -0.12065 0.2794)
			(stroke
				(width 0.1)
				(type default)
			)
			(layer "F.Fab")
		)
		(fp_line
			(start 0.120396 0.3048)
			(end 0.120396 0.2794)
			(stroke
				(width 0.1)
				(type default)
			)
			(layer "F.Fab")
		)
		(fp_line
			(start 0.12065 -0.3048)
			(end 0.67945 -0.3048)
			(stroke
				(width 0.1)
				(type default)
			)
			(layer "F.Fab")
		)
		(fp_line
			(start 0.12065 -0.2794)
			(end 0.12065 -0.3048)
			(stroke
				(width 0.1)
				(type default)
			)
			(layer "F.Fab")
		)
		(fp_line
			(start 0.67945 -0.3048)
			(end 0.67945 0.3048)
			(stroke
				(width 0.1)
				(type default)
			)
			(layer "F.Fab")
		)
		(fp_line
			(start 0.67945 0.3048)
			(end 0.120396 0.3048)
			(stroke
				(width 0.1)
				(type default)
			)
			(layer "F.Fab")
		)
		(pad "1" smd circle
			(at -0.40005 0)
			(size 0 0)
			(layers "F.Cu" "F.Mask" "F.Paste")
			(net "H_CPU0_PMDOWN_PCH_R")
		)
		(pad "2" smd circle
			(at 0.40005 0)
			(size 0 0)
			(layers "F.Cu" "F.Mask" "F.Paste")
			(net "H_CPU0_PMDOWN_PCH")
		)
	)
	(footprint ""
		(layer "F.Cu")
		(at 63.582804 -47.049944 90)
		(property "Reference" "H75"
			(at 4.323137 -0.070988 358.089)
			(unlocked yes)
			(layer "F.SilkS")
			(effects
				(font
					(size 0.7874 0.5842)
					(thickness 0.1524)
				)
			)
		)
		(property "Value" ""
			(at 0 0 90)
			(layer "F.Fab")
			(effects
				(font
					(size 1.27 1.27)
				)
			)
		)
		(duplicate_pad_numbers_are_jumpers no)
		(pad "" np_thru_hole circle
			(at 0 0 90)
			(size 0 0)
			(drill oval 3.2004 4.8006)
			(layers "*.Cu" "*.Mask")
			(clearance -1.2192)
			(thermal_gap 0.381)
			(padstack
				(mode front_inner_back)
				(layer "Inner"
					(shape oval)
					(size 3.2004 4.8006)
					(clearance 0.381)
				)
				(layer "B.Cu"
					(shape circle)
					(size 0 0)
					(clearance -1.2192)
				)
			)
		)
		(zone
			(layers "F.Cu" "B.Cu" "In1.Cu" "In2.Cu" "In3.Cu" "In4.Cu" "In5.Cu" "In6.Cu"
				"In7.Cu" "In8.Cu" "In9.Cu" "In10.Cu" "In11.Cu" "In12.Cu" "In13.Cu" "In14.Cu"
				"In15.Cu" "In16.Cu"
			)
			(hatch none 0.5)
			(connect_pads
				(clearance 0)
			)
			(min_thickness 0.25)
			(keepout
				(tracks not_allowed)
				(vias allowed)
				(pads allowed)
				(copperpour not_allowed)
				(footprints allowed)
			)
			(placement
				(enabled no)
				(sheetname "")
			)
			(fill
				(thermal_gap 0.5)
				(thermal_bridge_width 0.5)
				(island_removal_mode 0)
			)
			(polygon
				(pts
					(arc
						(start 64.38265 -49.158144)
						(mid 66.49085 -47.049944)
						(end 64.38265 -44.941744)
					)
					(arc
						(start 62.782958 -44.941744)
						(mid 60.674758 -47.049944)
						(end 62.782958 -49.158144)
					)
				)
			)
		)
		(zone
			(layers "F.Cu" "B.Cu" "In1.Cu" "In2.Cu" "In3.Cu" "In4.Cu" "In5.Cu" "In6.Cu"
				"In7.Cu" "In8.Cu" "In9.Cu" "In10.Cu" "In11.Cu" "In12.Cu" "In13.Cu" "In14.Cu"
				"In15.Cu" "In16.Cu"
			)
			(hatch none 0.5)
			(connect_pads
				(clearance 0)
			)
			(min_thickness 0.25)
			(keepout
				(tracks not_allowed)
				(vias allowed)
				(pads allowed)
				(copperpour not_allowed)
				(footprints allowed)
			)
			(placement
				(enabled no)
				(sheetname "")
			)
			(fill
				(thermal_gap 0.5)
				(thermal_bridge_width 0.5)
				(island_removal_mode 0)
			)
			(polygon
				(pts
					(arc
						(start 64.382904 -50.050192)
						(mid 67.383152 -47.050071)
						(end 64.383158 -44.049696)
					)
					(arc
						(start 62.782704 -44.049696)
						(mid 59.782456 -47.049817)
						(end 62.78245 -50.050192)
					)
				)
			)
		)
	)
	(footprint ""
		(layer "F.Cu")
		(at 235.899706 -81.699862 180)
		(property "Reference" "H115"
			(at -3.231388 -9.86282 0)
			(unlocked yes)
			(layer "F.SilkS")
			(effects
				(font
					(size 0.7874 0.5842)
					(thickness 0.1524)
				)
				(justify left)
			)
		)
		(property "Value" ""
			(at 0 0 180)
			(layer "F.Fab")
			(effects
				(font
					(size 1.27 1.27)
				)
			)
		)
		(duplicate_pad_numbers_are_jumpers no)
		(fp_circle
			(center 0 0)
			(end -7.999984 0)
			(stroke
				(width 0.1524)
				(type default)
			)
			(fill no)
			(layer "F.SilkS")
		)
		(fp_arc
			(start 1.378458 7.88035)
			(mid -5.146459 6.124845)
			(end -7.999984 0)
			(stroke
				(width 0.1524)
				(type default)
			)
			(layer "B.SilkS")
		)
		(fp_arc
			(start -0.846328 -7.955026)
			(mid 6.678862 -4.403794)
			(end 6.978396 3.911854)
			(stroke
				(width 0.1524)
				(type default)
			)
			(layer "B.SilkS")
		)
		(fp_arc
			(start -7.999984 0)
			(mid -7.68431 -2.225377)
			(end -6.761988 -4.275074)
			(stroke
				(width 0.1524)
				(type default)
			)
			(layer "B.SilkS")
		)
		(fp_circle
			(center 0 0)
			(end -7.999984 0)
			(stroke
				(width 0.1)
				(type default)
			)
			(fill no)
			(layer "B.Fab")
		)
		(fp_circle
			(center 0 0)
			(end -7.999984 0)
			(stroke
				(width 0.1)
				(type default)
			)
			(fill no)
			(layer "F.Fab")
		)
		(pad "" np_thru_hole oval
			(at 0 0 90)
			(size 5.08 6.477)
			(drill oval 5.08 6.477)
			(layers "*.Cu" "*.Mask")
			(clearance 0.381)
			(thermal_gap 0.381)
		)
		(pad "2" thru_hole circle
			(at 4.38023 0 180)
			(size 0.762 0.762)
			(drill 0.5588)
			(layers "*.Cu" "*.Mask")
			(remove_unused_layers no)
			(net "GND")
			(clearance 0.1524)
			(thermal_gap 0.1524)
		)
		(pad "3" thru_hole circle
			(at 3.097276 -3.097276 180)
			(size 0.762 0.762)
			(drill 0.5588)
			(layers "*.Cu" "*.Mask")
			(remove_unused_layers no)
			(net "GND")
			(clearance 0.1524)
			(thermal_gap 0.1524)
		)
		(pad "4" thru_hole circle
			(at 0 -4.38023 180)
			(size 0.762 0.762)
			(drill 0.5588)
			(layers "*.Cu" "*.Mask")
			(remove_unused_layers no)
			(net "GND")
			(clearance 0.1524)
			(thermal_gap 0.1524)
		)
		(pad "5" thru_hole circle
			(at -3.097276 -3.097276 180)
			(size 0.762 0.762)
			(drill 0.5588)
			(layers "*.Cu" "*.Mask")
			(remove_unused_layers no)
			(net "GND")
			(clearance 0.1524)
			(thermal_gap 0.1524)
		)
		(pad "6" thru_hole circle
			(at -4.38023 0 180)
			(size 0.762 0.762)
			(drill 0.5588)
			(layers "*.Cu" "*.Mask")
			(remove_unused_layers no)
			(net "GND")
			(clearance 0.1524)
			(thermal_gap 0.1524)
		)
		(pad "7" thru_hole circle
			(at -3.097276 3.097276 180)
			(size 0.762 0.762)
			(drill 0.5588)
			(layers "*.Cu" "*.Mask")
			(remove_unused_layers no)
			(net "GND")
			(clearance 0.1524)
			(thermal_gap 0.1524)
		)
		(pad "8" thru_hole circle
			(at 0 4.38023 180)
			(size 0.762 0.762)
			(drill 0.5588)
			(layers "*.Cu" "*.Mask")
			(remove_unused_layers no)
			(net "GND")
			(clearance 0.1524)
			(thermal_gap 0.1524)
		)
		(pad "9" thru_hole circle
			(at 3.097276 3.097276 180)
			(size 0.762 0.762)
			(drill 0.5588)
			(layers "*.Cu" "*.Mask")
			(remove_unused_layers no)
			(net "GND")
			(clearance 0.1524)
			(thermal_gap 0.1524)
		)
		(zone
			(layer "F.Cu")
			(hatch none 0.5)
			(connect_pads
				(clearance 0)
			)
			(min_thickness 0.25)
			(keepout
				(tracks not_allowed)
				(vias allowed)
				(pads allowed)
				(copperpour not_allowed)
				(footprints allowed)
			)
			(placement
				(enabled no)
				(sheetname "")
			)
			(fill
				(thermal_gap 0.5)
				(thermal_bridge_width 0.5)
				(island_removal_mode 0)
			)
			(polygon
				(pts
					(arc
						(start 230.391716 -81.699862)
						(mid 232.004969 -85.594599)
						(end 235.899706 -87.207852)
					)
					(arc
						(start 235.899706 -86.725252)
						(mid 230.874316 -81.699862)
						(end 235.899706 -76.674472)
					)
					(arc
						(start 235.899706 -76.191872)
						(mid 232.004969 -77.805125)
						(end 230.391716 -81.699862)
					)
				)
			)
		)
		(zone
			(layer "F.Cu")
			(hatch none 0.5)
			(connect_pads
				(clearance 0)
			)
			(min_thickness 0.25)
			(keepout
				(tracks not_allowed)
				(vias allowed)
				(pads allowed)
				(copperpour not_allowed)
				(footprints allowed)
			)
			(placement
				(enabled no)
				(sheetname "")
			)
			(fill
				(thermal_gap 0.5)
				(thermal_bridge_width 0.5)
				(island_removal_mode 0)
			)
			(polygon
				(pts
					(arc
						(start 241.407696 -81.699862)
						(mid 239.794443 -85.594599)
						(end 235.899706 -87.207852)
					)
					(arc
						(start 235.899706 -86.725252)
						(mid 240.925096 -81.699862)
						(end 235.899706 -76.674472)
					)
					(arc
						(start 235.899706 -76.191872)
						(mid 239.794443 -77.805125)
						(end 241.407696 -81.699862)
					)
				)
			)
		)
		(zone
			(layers "F.Cu" "B.Cu" "In1.Cu" "In2.Cu" "In3.Cu" "In4.Cu" "In5.Cu" "In6.Cu"
				"In7.Cu" "In8.Cu" "In9.Cu" "In10.Cu" "In11.Cu" "In12.Cu" "In13.Cu" "In14.Cu"
				"In15.Cu" "In16.Cu"
			)
			(hatch none 0.5)
			(connect_pads
				(clearance 0)
			)
			(min_thickness 0.25)
			(keepout
				(tracks not_allowed)
				(vias allowed)
				(pads allowed)
				(copperpour not_allowed)
				(footprints allowed)
			)
			(placement
				(enabled no)
				(sheetname "")
			)
			(fill
				(thermal_gap 0.5)
				(thermal_bridge_width 0.5)
				(island_removal_mode 0)
			)
			(polygon
				(pts
					(arc
						(start 233.715306 -78.641956)
						(mid 235.899706 -85.457839)
						(end 238.084106 -78.641956)
					)
				)
			)
		)
		(zone
			(layer "B.Cu")
			(hatch none 0.5)
			(connect_pads
				(clearance 0)
			)
			(min_thickness 0.25)
			(keepout
				(tracks not_allowed)
				(vias allowed)
				(pads allowed)
				(copperpour not_allowed)
				(footprints allowed)
			)
			(placement
				(enabled no)
				(sheetname "")
			)
			(fill
				(thermal_gap 0.5)
				(thermal_bridge_width 0.5)
				(island_removal_mode 0)
			)
			(polygon
				(pts
					(arc
						(start 235.899706 -89.699846)
						(mid 227.899722 -81.699862)
						(end 235.899706 -73.699878)
					)
					(arc
						(start 235.899706 -76.445872)
						(mid 232.184574 -77.98473)
						(end 230.645716 -81.699862)
					)
					(arc
						(start 230.645716 -81.699862)
						(mid 232.184574 -85.414994)
						(end 235.899706 -86.953852)
					)
				)
			)
		)
		(zone
			(layer "B.Cu")
			(hatch none 0.5)
			(connect_pads
				(clearance 0)
			)
			(min_thickness 0.25)
			(keepout
				(tracks not_allowed)
				(vias allowed)
				(pads allowed)
				(copperpour not_allowed)
				(footprints allowed)
			)
			(placement
				(enabled no)
				(sheetname "")
			)
			(fill
				(thermal_gap 0.5)
				(thermal_bridge_width 0.5)
				(island_removal_mode 0)
			)
			(polygon
				(pts
					(arc
						(start 235.899706 -89.699846)
						(mid 243.89969 -81.699862)
						(end 235.899706 -73.699878)
					)
					(arc
						(start 235.899706 -76.445872)
						(mid 239.614838 -77.98473)
						(end 241.153696 -81.699862)
					)
					(arc
						(start 241.153696 -81.699862)
						(mid 239.614838 -85.414994)
						(end 235.899706 -86.953852)
					)
				)
			)
		)
	)
	(footprint ""
		(layer "F.Cu")
		(at 430.827434 -98.175064 180)
		(property "Reference" "R3645"
			(at 0 0 180)
			(layer "F.SilkS")
			(hide yes)
			(effects
				(font
					(size 1.27 1.27)
				)
			)
		)
		(property "Value" ""
			(at 0 0 180)
			(layer "F.Fab")
			(effects
				(font
					(size 1.27 1.27)
				)
			)
		)
		(duplicate_pad_numbers_are_jumpers no)
		(fp_line
			(start 4.0386 1.7526)
			(end -4.0386 1.7526)
			(stroke
				(width 0.1524)
				(type default)
			)
			(layer "F.SilkS")
		)
		(fp_line
			(start 4.0386 -1.7526)
			(end 4.0386 1.7526)
			(stroke
				(width 0.1524)
				(type default)
			)
			(layer "F.SilkS")
		)
		(fp_line
			(start -4.0386 1.7526)
			(end -4.0386 -1.7526)
			(stroke
				(width 0.1524)
				(type default)
			)
			(layer "F.SilkS")
		)
		(fp_line
			(start -4.0386 -1.7526)
			(end 4.0386 -1.7526)
			(stroke
				(width 0.1524)
				(type default)
			)
			(layer "F.SilkS")
		)
		(fp_line
			(start 4.0386 1.7526)
			(end -4.0386 1.7526)
			(stroke
				(width 0.1)
				(type default)
			)
			(layer "F.Fab")
		)
		(fp_line
			(start 4.0386 -1.7526)
			(end 4.0386 1.7526)
			(stroke
				(width 0.1)
				(type default)
			)
			(layer "F.Fab")
		)
		(fp_line
			(start -4.0386 1.7526)
			(end -4.0386 -1.7526)
			(stroke
				(width 0.1)
				(type default)
			)
			(layer "F.Fab")
		)
		(fp_line
			(start -4.0386 -1.7526)
			(end 4.0386 -1.7526)
			(stroke
				(width 0.1)
				(type default)
			)
			(layer "F.Fab")
		)
		(pad "1" smd rect
			(at -3.1115 0 180)
			(size 1.524 3.2004)
			(layers "F.Cu" "F.Mask" "F.Paste")
			(net "P3V3_OCP_SFF")
		)
		(pad "2" smd rect
			(at 3.1115 0 180)
			(size 1.524 3.2004)
			(layers "F.Cu" "F.Mask" "F.Paste")
			(net "P3V3_OCP_SFF_R")
		)
	)
	(footprint ""
		(layer "F.Cu")
		(at 69.923406 -166.634922)
		(property "Reference" "PC385"
			(at 0 0 0)
			(layer "F.SilkS")
			(hide yes)
			(effects
				(font
					(size 1.27 1.27)
				)
			)
		)
		(property "Value" ""
			(at 0 0 0)
			(layer "F.Fab")
			(effects
				(font
					(size 1.27 1.27)
				)
			)
		)
		(duplicate_pad_numbers_are_jumpers no)
		(fp_line
			(start 2.750058 0.999998)
			(end -2.750058 0.999998)
			(stroke
				(width 0.1524)
				(type default)
			)
			(layer "F.SilkS")
		)
		(fp_circle
			(center 0 0.999998)
			(end 2.750058 0.999998)
			(stroke
				(width 0.1524)
				(type default)
			)
			(fill no)
			(layer "F.SilkS")
		)
		(fp_poly
			(pts
				(arc
					(start 2.750058 0.999998)
					(mid 0 3.750056)
					(end -2.750058 0.999998)
				)
			)
			(stroke
				(width 0)
				(type default)
			)
			(fill yes)
			(layer "F.SilkS")
		)
		(fp_circle
			(center 0 0.999998)
			(end 2.750058 0.999998)
			(stroke
				(width 0.1)
				(type default)
			)
			(fill no)
			(layer "F.Fab")
		)
		(pad "1" thru_hole rect
			(at 0 0)
			(size 1.5748 1.5748)
			(drill 1.0668)
			(layers "*.Cu" "*.Mask")
			(remove_unused_layers no)
			(net "PVCCD_HV_CPU1")
			(clearance 0)
			(padstack
				(mode front_inner_back)
				(layer "Inner"
					(shape circle)
					(size 1.5748 1.5748)
					(clearance 0)
				)
				(layer "B.Cu"
					(shape rect)
					(size 1.5748 1.5748)
					(clearance 0)
				)
			)
		)
		(pad "2" thru_hole circle
			(at 0 1.999996)
			(size 1.5748 1.5748)
			(drill 1.0668)
			(layers "*.Cu" "*.Mask")
			(remove_unused_layers no)
			(net "GND")
			(clearance 0)
		)
	)
	(footprint ""
		(layer "F.Cu")
		(at 426.6819 -109.644688 90)
		(property "Reference" "PC2081"
			(at 0 0 90)
			(layer "F.SilkS")
			(hide yes)
			(effects
				(font
					(size 1.27 1.27)
				)
			)
		)
		(property "Value" ""
			(at 0 0 90)
			(layer "F.Fab")
			(effects
				(font
					(size 1.27 1.27)
				)
			)
		)
		(duplicate_pad_numbers_are_jumpers no)
		(fp_line
			(start 1.524 -0.762)
			(end 1.524 0.762)
			(stroke
				(width 0.1524)
				(type default)
			)
			(layer "F.SilkS")
		)
		(fp_line
			(start -1.524 -0.762)
			(end 1.524 -0.762)
			(stroke
				(width 0.1524)
				(type default)
			)
			(layer "F.SilkS")
		)
		(fp_line
			(start 1.524 0.762)
			(end -1.524 0.762)
			(stroke
				(width 0.1524)
				(type default)
			)
			(layer "F.SilkS")
		)
		(fp_line
			(start -1.524 0.762)
			(end -1.524 -0.762)
			(stroke
				(width 0.1524)
				(type default)
			)
			(layer "F.SilkS")
		)
		(fp_line
			(start 1.1049 -0.724916)
			(end -1.1049 -0.724916)
			(stroke
				(width 0.1)
				(type default)
			)
			(layer "F.Fab")
		)
		(fp_line
			(start -1.1049 -0.724916)
			(end -1.1049 0.724916)
			(stroke
				(width 0.1)
				(type default)
			)
			(layer "F.Fab")
		)
		(fp_line
			(start 1.1049 0.724916)
			(end 1.1049 -0.724916)
			(stroke
				(width 0.1)
				(type default)
			)
			(layer "F.Fab")
		)
		(fp_line
			(start -1.1049 0.724916)
			(end 1.1049 0.724916)
			(stroke
				(width 0.1)
				(type default)
			)
			(layer "F.Fab")
		)
		(pad "1" smd rect
			(at -0.889 0 270)
			(size 1.016 1.27)
			(layers "F.Cu" "F.Mask" "F.Paste")
			(net "P3V3_OCP_SFF_R")
		)
		(pad "2" smd rect
			(at 0.889 0 270)
			(size 1.016 1.27)
			(layers "F.Cu" "F.Mask" "F.Paste")
			(net "GND")
		)
	)
	(footprint ""
		(layer "F.Cu")
		(at 105.2957 -255.0541 90)
		(property "Reference" "C246"
			(at 0 0 90)
			(layer "F.SilkS")
			(hide yes)
			(effects
				(font
					(size 1.27 1.27)
				)
			)
		)
		(property "Value" ""
			(at 0 0 90)
			(layer "F.Fab")
			(effects
				(font
					(size 1.27 1.27)
				)
			)
		)
		(duplicate_pad_numbers_are_jumpers no)
		(fp_line
			(start 0.7874 -0.4064)
			(end 0.7874 0.4064)
			(stroke
				(width 0.1524)
				(type default)
			)
			(layer "F.SilkS")
		)
		(fp_line
			(start -0.7874 -0.4064)
			(end 0.7874 -0.4064)
			(stroke
				(width 0.1524)
				(type default)
			)
			(layer "F.SilkS")
		)
		(fp_line
			(start 0.7874 0.4064)
			(end -0.7874 0.4064)
			(stroke
				(width 0.1524)
				(type default)
			)
			(layer "F.SilkS")
		)
		(fp_line
			(start -0.7874 0.4064)
			(end -0.7874 -0.4064)
			(stroke
				(width 0.1524)
				(type default)
			)
			(layer "F.SilkS")
		)
		(fp_line
			(start -0.12065 -0.305054)
			(end -0.12065 -0.2794)
			(stroke
				(width 0.1)
				(type default)
			)
			(layer "F.Fab")
		)
		(fp_line
			(start -0.67945 -0.305054)
			(end -0.12065 -0.305054)
			(stroke
				(width 0.1)
				(type default)
			)
			(layer "F.Fab")
		)
		(fp_line
			(start 0.67945 -0.3048)
			(end 0.67945 0.3048)
			(stroke
				(width 0.1)
				(type default)
			)
			(layer "F.Fab")
		)
		(fp_line
			(start 0.12065 -0.3048)
			(end 0.67945 -0.3048)
			(stroke
				(width 0.1)
				(type default)
			)
			(layer "F.Fab")
		)
		(fp_line
			(start 0.12065 -0.2794)
			(end 0.12065 -0.3048)
			(stroke
				(width 0.1)
				(type default)
			)
			(layer "F.Fab")
		)
		(fp_line
			(start -0.12065 -0.2794)
			(end 0.12065 -0.2794)
			(stroke
				(width 0.1)
				(type default)
			)
			(layer "F.Fab")
		)
		(fp_line
			(start 0.120396 0.2794)
			(end -0.12065 0.2794)
			(stroke
				(width 0.1)
				(type default)
			)
			(layer "F.Fab")
		)
		(fp_line
			(start -0.12065 0.2794)
			(end -0.12065 0.3048)
			(stroke
				(width 0.1)
				(type default)
			)
			(layer "F.Fab")
		)
		(fp_line
			(start 0.67945 0.3048)
			(end 0.120396 0.3048)
			(stroke
				(width 0.1)
				(type default)
			)
			(layer "F.Fab")
		)
		(fp_line
			(start 0.120396 0.3048)
			(end 0.120396 0.2794)
			(stroke
				(width 0.1)
				(type default)
			)
			(layer "F.Fab")
		)
		(fp_line
			(start -0.12065 0.3048)
			(end -0.67945 0.3048)
			(stroke
				(width 0.1)
				(type default)
			)
			(layer "F.Fab")
		)
		(fp_line
			(start -0.67945 0.3048)
			(end -0.67945 -0.305054)
			(stroke
				(width 0.1)
				(type default)
			)
			(layer "F.Fab")
		)
		(pad "1" smd circle
			(at -0.40005 0 90)
			(size 0 0)
			(layers "F.Cu" "F.Mask" "F.Paste")
			(net "PVCCIN_CPU1")
		)
		(pad "2" smd circle
			(at 0.40005 0 90)
			(size 0 0)
			(layers "F.Cu" "F.Mask" "F.Paste")
			(net "GND")
		)
	)
	(footprint ""
		(layer "F.Cu")
		(at 128.9685 -74.824082 -90)
		(property "Reference" "R1345"
			(at 0 0 270)
			(layer "F.SilkS")
			(hide yes)
			(effects
				(font
					(size 1.27 1.27)
				)
			)
		)
		(property "Value" ""
			(at 0 0 270)
			(layer "F.Fab")
			(effects
				(font
					(size 1.27 1.27)
				)
			)
		)
		(duplicate_pad_numbers_are_jumpers no)
		(fp_line
			(start -0.7874 0.4064)
			(end -0.7874 -0.4064)
			(stroke
				(width 0.1524)
				(type default)
			)
			(layer "F.SilkS")
		)
		(fp_line
			(start 0.7874 0.4064)
			(end -0.7874 0.4064)
			(stroke
				(width 0.1524)
				(type default)
			)
			(layer "F.SilkS")
		)
		(fp_line
			(start -0.7874 -0.4064)
			(end 0.7874 -0.4064)
			(stroke
				(width 0.1524)
				(type default)
			)
			(layer "F.SilkS")
		)
		(fp_line
			(start 0.7874 -0.4064)
			(end 0.7874 0.4064)
			(stroke
				(width 0.1524)
				(type default)
			)
			(layer "F.SilkS")
		)
		(fp_line
			(start -0.67945 0.3048)
			(end -0.67945 -0.305054)
			(stroke
				(width 0.1)
				(type default)
			)
			(layer "F.Fab")
		)
		(fp_line
			(start -0.12065 0.3048)
			(end -0.67945 0.3048)
			(stroke
				(width 0.1)
				(type default)
			)
			(layer "F.Fab")
		)
		(fp_line
			(start 0.120396 0.3048)
			(end 0.120396 0.2794)
			(stroke
				(width 0.1)
				(type default)
			)
			(layer "F.Fab")
		)
		(fp_line
			(start 0.67945 0.3048)
			(end 0.120396 0.3048)
			(stroke
				(width 0.1)
				(type default)
			)
			(layer "F.Fab")
		)
		(fp_line
			(start -0.12065 0.2794)
			(end -0.12065 0.3048)
			(stroke
				(width 0.1)
				(type default)
			)
			(layer "F.Fab")
		)
		(fp_line
			(start 0.120396 0.2794)
			(end -0.12065 0.2794)
			(stroke
				(width 0.1)
				(type default)
			)
			(layer "F.Fab")
		)
		(fp_line
			(start -0.12065 -0.2794)
			(end 0.12065 -0.2794)
			(stroke
				(width 0.1)
				(type default)
			)
			(layer "F.Fab")
		)
		(fp_line
			(start 0.12065 -0.2794)
			(end 0.12065 -0.3048)
			(stroke
				(width 0.1)
				(type default)
			)
			(layer "F.Fab")
		)
		(fp_line
			(start 0.12065 -0.3048)
			(end 0.67945 -0.3048)
			(stroke
				(width 0.1)
				(type default)
			)
			(layer "F.Fab")
		)
		(fp_line
			(start 0.67945 -0.3048)
			(end 0.67945 0.3048)
			(stroke
				(width 0.1)
				(type default)
			)
			(layer "F.Fab")
		)
		(fp_line
			(start -0.67945 -0.305054)
			(end -0.12065 -0.305054)
			(stroke
				(width 0.1)
				(type default)
			)
			(layer "F.Fab")
		)
		(fp_line
			(start -0.12065 -0.305054)
			(end -0.12065 -0.2794)
			(stroke
				(width 0.1)
				(type default)
			)
			(layer "F.Fab")
		)
		(pad "1" smd circle
			(at -0.40005 0 270)
			(size 0 0)
			(layers "F.Cu" "F.Mask" "F.Paste")
			(net "JTAG_BMC_DBP_TDI_R")
		)
		(pad "2" smd circle
			(at 0.40005 0 270)
			(size 0 0)
			(layers "F.Cu" "F.Mask" "F.Paste")
			(net "JTAG_BMC_DBP_TDI")
		)
	)
	(footprint ""
		(layer "F.Cu")
		(at 162.848036 -66.091308 180)
		(property "Reference" "R3773"
			(at 0 0 180)
			(layer "F.SilkS")
			(hide yes)
			(effects
				(font
					(size 1.27 1.27)
				)
			)
		)
		(property "Value" ""
			(at 0 0 180)
			(layer "F.Fab")
			(effects
				(font
					(size 1.27 1.27)
				)
			)
		)
		(duplicate_pad_numbers_are_jumpers no)
		(fp_line
			(start 0.7874 0.4064)
			(end -0.7874 0.4064)
			(stroke
				(width 0.1524)
				(type default)
			)
			(layer "F.SilkS")
		)
		(fp_line
			(start 0.7874 -0.4064)
			(end 0.7874 0.4064)
			(stroke
				(width 0.1524)
				(type default)
			)
			(layer "F.SilkS")
		)
		(fp_line
			(start -0.7874 0.4064)
			(end -0.7874 -0.4064)
			(stroke
				(width 0.1524)
				(type default)
			)
			(layer "F.SilkS")
		)
		(fp_line
			(start -0.7874 -0.4064)
			(end 0.7874 -0.4064)
			(stroke
				(width 0.1524)
				(type default)
			)
			(layer "F.SilkS")
		)
		(fp_line
			(start 0.67945 0.3048)
			(end 0.120396 0.3048)
			(stroke
				(width 0.1)
				(type default)
			)
			(layer "F.Fab")
		)
		(fp_line
			(start 0.67945 -0.3048)
			(end 0.67945 0.3048)
			(stroke
				(width 0.1)
				(type default)
			)
			(layer "F.Fab")
		)
		(fp_line
			(start 0.12065 -0.2794)
			(end 0.12065 -0.3048)
			(stroke
				(width 0.1)
				(type default)
			)
			(layer "F.Fab")
		)
		(fp_line
			(start 0.12065 -0.3048)
			(end 0.67945 -0.3048)
			(stroke
				(width 0.1)
				(type default)
			)
			(layer "F.Fab")
		)
		(fp_line
			(start 0.120396 0.3048)
			(end 0.120396 0.2794)
			(stroke
				(width 0.1)
				(type default)
			)
			(layer "F.Fab")
		)
		(fp_line
			(start 0.120396 0.2794)
			(end -0.12065 0.2794)
			(stroke
				(width 0.1)
				(type default)
			)
			(layer "F.Fab")
		)
		(fp_line
			(start -0.12065 0.3048)
			(end -0.67945 0.3048)
			(stroke
				(width 0.1)
				(type default)
			)
			(layer "F.Fab")
		)
		(fp_line
			(start -0.12065 0.2794)
			(end -0.12065 0.3048)
			(stroke
				(width 0.1)
				(type default)
			)
			(layer "F.Fab")
		)
		(fp_line
			(start -0.12065 -0.2794)
			(end 0.12065 -0.2794)
			(stroke
				(width 0.1)
				(type default)
			)
			(layer "F.Fab")
		)
		(fp_line
			(start -0.12065 -0.305054)
			(end -0.12065 -0.2794)
			(stroke
				(width 0.1)
				(type default)
			)
			(layer "F.Fab")
		)
		(fp_line
			(start -0.67945 0.3048)
			(end -0.67945 -0.305054)
			(stroke
				(width 0.1)
				(type default)
			)
			(layer "F.Fab")
		)
		(fp_line
			(start -0.67945 -0.305054)
			(end -0.12065 -0.305054)
			(stroke
				(width 0.1)
				(type default)
			)
			(layer "F.Fab")
		)
		(pad "1" smd circle
			(at -0.40005 0 180)
			(size 0 0)
			(layers "F.Cu" "F.Mask" "F.Paste")
			(net "P3V3_AUX")
		)
		(pad "2" smd circle
			(at 0.40005 0 180)
			(size 0 0)
			(layers "F.Cu" "F.Mask" "F.Paste")
			(net "RST_SMB_E1S_0_N")
		)
	)
	(footprint ""
		(layer "F.Cu")
		(at 96.57588 -55.209948 180)
		(property "Reference" "C1293"
			(at 0 0 180)
			(layer "F.SilkS")
			(hide yes)
			(effects
				(font
					(size 1.27 1.27)
				)
			)
		)
		(property "Value" ""
			(at 0 0 180)
			(layer "F.Fab")
			(effects
				(font
					(size 1.27 1.27)
				)
			)
		)
		(duplicate_pad_numbers_are_jumpers no)
		(fp_line
			(start 0.7874 0.4064)
			(end -0.7874 0.4064)
			(stroke
				(width 0.1524)
				(type default)
			)
			(layer "F.SilkS")
		)
		(fp_line
			(start 0.7874 -0.4064)
			(end 0.7874 0.4064)
			(stroke
				(width 0.1524)
				(type default)
			)
			(layer "F.SilkS")
		)
		(fp_line
			(start -0.7874 0.4064)
			(end -0.7874 -0.4064)
			(stroke
				(width 0.1524)
				(type default)
			)
			(layer "F.SilkS")
		)
		(fp_line
			(start -0.7874 -0.4064)
			(end 0.7874 -0.4064)
			(stroke
				(width 0.1524)
				(type default)
			)
			(layer "F.SilkS")
		)
		(fp_line
			(start 0.67945 0.3048)
			(end 0.120396 0.3048)
			(stroke
				(width 0.1)
				(type default)
			)
			(layer "F.Fab")
		)
		(fp_line
			(start 0.67945 -0.3048)
			(end 0.67945 0.3048)
			(stroke
				(width 0.1)
				(type default)
			)
			(layer "F.Fab")
		)
		(fp_line
			(start 0.12065 -0.2794)
			(end 0.12065 -0.3048)
			(stroke
				(width 0.1)
				(type default)
			)
			(layer "F.Fab")
		)
		(fp_line
			(start 0.12065 -0.3048)
			(end 0.67945 -0.3048)
			(stroke
				(width 0.1)
				(type default)
			)
			(layer "F.Fab")
		)
		(fp_line
			(start 0.120396 0.3048)
			(end 0.120396 0.2794)
			(stroke
				(width 0.1)
				(type default)
			)
			(layer "F.Fab")
		)
		(fp_line
			(start 0.120396 0.2794)
			(end -0.12065 0.2794)
			(stroke
				(width 0.1)
				(type default)
			)
			(layer "F.Fab")
		)
		(fp_line
			(start -0.12065 0.3048)
			(end -0.67945 0.3048)
			(stroke
				(width 0.1)
				(type default)
			)
			(layer "F.Fab")
		)
		(fp_line
			(start -0.12065 0.2794)
			(end -0.12065 0.3048)
			(stroke
				(width 0.1)
				(type default)
			)
			(layer "F.Fab")
		)
		(fp_line
			(start -0.12065 -0.2794)
			(end 0.12065 -0.2794)
			(stroke
				(width 0.1)
				(type default)
			)
			(layer "F.Fab")
		)
		(fp_line
			(start -0.12065 -0.305054)
			(end -0.12065 -0.2794)
			(stroke
				(width 0.1)
				(type default)
			)
			(layer "F.Fab")
		)
		(fp_line
			(start -0.67945 0.3048)
			(end -0.67945 -0.305054)
			(stroke
				(width 0.1)
				(type default)
			)
			(layer "F.Fab")
		)
		(fp_line
			(start -0.67945 -0.305054)
			(end -0.12065 -0.305054)
			(stroke
				(width 0.1)
				(type default)
			)
			(layer "F.Fab")
		)
		(pad "1" smd circle
			(at -0.40005 0 180)
			(size 0 0)
			(layers "F.Cu" "F.Mask" "F.Paste")
			(net "FM_BMC_EN_DET")
		)
		(pad "2" smd circle
			(at 0.40005 0 180)
			(size 0 0)
			(layers "F.Cu" "F.Mask" "F.Paste")
			(net "GND")
		)
	)
	(footprint ""
		(layer "F.Cu")
		(at 409.07081 -402.371052 -90)
		(property "Reference" "C958"
			(at 0 0 270)
			(layer "F.SilkS")
			(hide yes)
			(effects
				(font
					(size 1.27 1.27)
				)
			)
		)
		(property "Value" ""
			(at 0 0 270)
			(layer "F.Fab")
			(effects
				(font
					(size 1.27 1.27)
				)
			)
		)
		(duplicate_pad_numbers_are_jumpers no)
		(fp_line
			(start -0.299974 0.150114)
			(end -0.299974 -0.150114)
			(stroke
				(width 0.1)
				(type default)
			)
			(layer "F.Fab")
		)
		(fp_line
			(start 0.299974 0.150114)
			(end -0.299974 0.150114)
			(stroke
				(width 0.1)
				(type default)
			)
			(layer "F.Fab")
		)
		(fp_line
			(start -0.299974 -0.150114)
			(end 0.299974 -0.150114)
			(stroke
				(width 0.1)
				(type default)
			)
			(layer "F.Fab")
		)
		(fp_line
			(start 0.299974 -0.150114)
			(end 0.299974 0.150114)
			(stroke
				(width 0.1)
				(type default)
			)
			(layer "F.Fab")
		)
		(pad "1" smd rect
			(at -0.2667 0 270)
			(size 0.3048 0.381)
			(layers "F.Cu" "F.Mask" "F.Paste")
			(net "P5E_CPU0_PE2_TX_C_DN<3>")
		)
		(pad "2" smd rect
			(at 0.2667 0 270)
			(size 0.3048 0.381)
			(layers "F.Cu" "F.Mask" "F.Paste")
			(net "P5E_CPU0_PE2_TX_DN<3>")
		)
	)
	(footprint ""
		(layer "F.Cu")
		(at 133.725412 -368.24793)
		(property "Reference" "PC1771"
			(at 0 0 0)
			(layer "F.SilkS")
			(hide yes)
			(effects
				(font
					(size 1.27 1.27)
				)
			)
		)
		(property "Value" ""
			(at 0 0 0)
			(layer "F.Fab")
			(effects
				(font
					(size 1.27 1.27)
				)
			)
		)
		(duplicate_pad_numbers_are_jumpers no)
		(fp_line
			(start -3.400044 1.249934)
			(end 3.400044 1.249934)
			(stroke
				(width 0.1524)
				(type default)
			)
			(layer "F.SilkS")
		)
		(fp_circle
			(center 0 1.249934)
			(end 3.400044 1.249934)
			(stroke
				(width 0.1524)
				(type default)
			)
			(fill no)
			(layer "F.SilkS")
		)
		(fp_poly
			(pts
				(arc
					(start 3.400044 1.249934)
					(mid 0 4.649978)
					(end -3.400044 1.249934)
				)
			)
			(stroke
				(width 0)
				(type default)
			)
			(fill yes)
			(layer "F.SilkS")
		)
		(fp_circle
			(center 0 1.249934)
			(end 3.400044 1.249934)
			(stroke
				(width 0.1)
				(type default)
			)
			(fill no)
			(layer "F.Fab")
		)
		(pad "1" thru_hole rect
			(at 0 0)
			(size 1.524 1.524)
			(drill 1.016)
			(layers "*.Cu" "*.Mask")
			(remove_unused_layers no)
			(net "PVPP_HBM_CPU1")
			(clearance 0)
			(padstack
				(mode front_inner_back)
				(layer "Inner"
					(shape circle)
					(size 1.524 1.524)
					(clearance 0)
				)
				(layer "B.Cu"
					(shape rect)
					(size 1.524 1.524)
					(clearance 0)
				)
			)
		)
		(pad "2" thru_hole circle
			(at 0 2.500122)
			(size 1.524 1.524)
			(drill 1.016)
			(layers "*.Cu" "*.Mask")
			(remove_unused_layers no)
			(net "GND")
			(clearance 0)
		)
	)
	(footprint ""
		(layer "F.Cu")
		(at 90.440002 -297.514772)
		(property "Reference" "H22"
			(at -3.582162 -6.911086 0)
			(unlocked yes)
			(layer "F.SilkS")
			(effects
				(font
					(size 0.7874 0.5842)
					(thickness 0.1524)
				)
				(justify left)
			)
		)
		(property "Value" ""
			(at 0 0 0)
			(layer "F.Fab")
			(effects
				(font
					(size 1.27 1.27)
				)
			)
		)
		(duplicate_pad_numbers_are_jumpers no)
		(fp_circle
			(center 0 0)
			(end 2.5273 0)
			(stroke
				(width 0.1524)
				(type default)
			)
			(fill no)
			(layer "F.SilkS")
		)
		(fp_circle
			(center 0 0)
			(end 2.5273 0)
			(stroke
				(width 0.1524)
				(type default)
			)
			(fill no)
			(layer "B.SilkS")
		)
		(fp_circle
			(center 0 0)
			(end 2.5273 0)
			(stroke
				(width 0.1)
				(type default)
			)
			(fill no)
			(layer "B.Fab")
		)
		(fp_circle
			(center 0 0)
			(end 2.5273 0)
			(stroke
				(width 0.1)
				(type default)
			)
			(fill no)
			(layer "F.Fab")
		)
		(pad "" np_thru_hole circle
			(at 0 0)
			(size 3.429 3.429)
			(drill 3.429)
			(layers "*.Cu" "*.Mask")
			(clearance 0.381)
			(thermal_gap 0.381)
		)
	)
	(footprint ""
		(layer "F.Cu")
		(at 73.81748 -162.003486)
		(property "Reference" "PC379"
			(at 0 0 0)
			(layer "F.SilkS")
			(hide yes)
			(effects
				(font
					(size 1.27 1.27)
				)
			)
		)
		(property "Value" ""
			(at 0 0 0)
			(layer "F.Fab")
			(effects
				(font
					(size 1.27 1.27)
				)
			)
		)
		(duplicate_pad_numbers_are_jumpers no)
		(fp_line
			(start -0.7874 -0.4064)
			(end 0.7874 -0.4064)
			(stroke
				(width 0.1524)
				(type default)
			)
			(layer "F.SilkS")
		)
		(fp_line
			(start -0.7874 0.4064)
			(end -0.7874 -0.4064)
			(stroke
				(width 0.1524)
				(type default)
			)
			(layer "F.SilkS")
		)
		(fp_line
			(start 0.7874 -0.4064)
			(end 0.7874 0.4064)
			(stroke
				(width 0.1524)
				(type default)
			)
			(layer "F.SilkS")
		)
		(fp_line
			(start 0.7874 0.4064)
			(end -0.7874 0.4064)
			(stroke
				(width 0.1524)
				(type default)
			)
			(layer "F.SilkS")
		)
		(fp_line
			(start -0.67945 -0.305054)
			(end -0.12065 -0.305054)
			(stroke
				(width 0.1)
				(type default)
			)
			(layer "F.Fab")
		)
		(fp_line
			(start -0.67945 0.3048)
			(end -0.67945 -0.305054)
			(stroke
				(width 0.1)
				(type default)
			)
			(layer "F.Fab")
		)
		(fp_line
			(start -0.12065 -0.305054)
			(end -0.12065 -0.2794)
			(stroke
				(width 0.1)
				(type default)
			)
			(layer "F.Fab")
		)
		(fp_line
			(start -0.12065 -0.2794)
			(end 0.12065 -0.2794)
			(stroke
				(width 0.1)
				(type default)
			)
			(layer "F.Fab")
		)
		(fp_line
			(start -0.12065 0.2794)
			(end -0.12065 0.3048)
			(stroke
				(width 0.1)
				(type default)
			)
			(layer "F.Fab")
		)
		(fp_line
			(start -0.12065 0.3048)
			(end -0.67945 0.3048)
			(stroke
				(width 0.1)
				(type default)
			)
			(layer "F.Fab")
		)
		(fp_line
			(start 0.120396 0.2794)
			(end -0.12065 0.2794)
			(stroke
				(width 0.1)
				(type default)
			)
			(layer "F.Fab")
		)
		(fp_line
			(start 0.120396 0.3048)
			(end 0.120396 0.2794)
			(stroke
				(width 0.1)
				(type default)
			)
			(layer "F.Fab")
		)
		(fp_line
			(start 0.12065 -0.3048)
			(end 0.67945 -0.3048)
			(stroke
				(width 0.1)
				(type default)
			)
			(layer "F.Fab")
		)
		(fp_line
			(start 0.12065 -0.2794)
			(end 0.12065 -0.3048)
			(stroke
				(width 0.1)
				(type default)
			)
			(layer "F.Fab")
		)
		(fp_line
			(start 0.67945 -0.3048)
			(end 0.67945 0.3048)
			(stroke
				(width 0.1)
				(type default)
			)
			(layer "F.Fab")
		)
		(fp_line
			(start 0.67945 0.3048)
			(end 0.120396 0.3048)
			(stroke
				(width 0.1)
				(type default)
			)
			(layer "F.Fab")
		)
		(pad "1" smd circle
			(at -0.40005 0)
			(size 0 0)
			(layers "F.Cu" "F.Mask" "F.Paste")
			(net "PVCCD_HV_CPU1")
		)
		(pad "2" smd circle
			(at 0.40005 0)
			(size 0 0)
			(layers "F.Cu" "F.Mask" "F.Paste")
			(net "GND")
		)
	)
	(footprint ""
		(layer "F.Cu")
		(at 306.63388 -53.050948 90)
		(property "Reference" "R146"
			(at 0 0 90)
			(layer "F.SilkS")
			(hide yes)
			(effects
				(font
					(size 1.27 1.27)
				)
			)
		)
		(property "Value" ""
			(at 0 0 90)
			(layer "F.Fab")
			(effects
				(font
					(size 1.27 1.27)
				)
			)
		)
		(duplicate_pad_numbers_are_jumpers no)
		(fp_line
			(start 0.7874 -0.4064)
			(end 0.7874 0.4064)
			(stroke
				(width 0.1524)
				(type default)
			)
			(layer "F.SilkS")
		)
		(fp_line
			(start -0.7874 -0.4064)
			(end 0.7874 -0.4064)
			(stroke
				(width 0.1524)
				(type default)
			)
			(layer "F.SilkS")
		)
		(fp_line
			(start 0.7874 0.4064)
			(end -0.7874 0.4064)
			(stroke
				(width 0.1524)
				(type default)
			)
			(layer "F.SilkS")
		)
		(fp_line
			(start -0.7874 0.4064)
			(end -0.7874 -0.4064)
			(stroke
				(width 0.1524)
				(type default)
			)
			(layer "F.SilkS")
		)
		(fp_line
			(start -0.12065 -0.305054)
			(end -0.12065 -0.2794)
			(stroke
				(width 0.1)
				(type default)
			)
			(layer "F.Fab")
		)
		(fp_line
			(start -0.67945 -0.305054)
			(end -0.12065 -0.305054)
			(stroke
				(width 0.1)
				(type default)
			)
			(layer "F.Fab")
		)
		(fp_line
			(start 0.67945 -0.3048)
			(end 0.67945 0.3048)
			(stroke
				(width 0.1)
				(type default)
			)
			(layer "F.Fab")
		)
		(fp_line
			(start 0.12065 -0.3048)
			(end 0.67945 -0.3048)
			(stroke
				(width 0.1)
				(type default)
			)
			(layer "F.Fab")
		)
		(fp_line
			(start 0.12065 -0.2794)
			(end 0.12065 -0.3048)
			(stroke
				(width 0.1)
				(type default)
			)
			(layer "F.Fab")
		)
		(fp_line
			(start -0.12065 -0.2794)
			(end 0.12065 -0.2794)
			(stroke
				(width 0.1)
				(type default)
			)
			(layer "F.Fab")
		)
		(fp_line
			(start 0.120396 0.2794)
			(end -0.12065 0.2794)
			(stroke
				(width 0.1)
				(type default)
			)
			(layer "F.Fab")
		)
		(fp_line
			(start -0.12065 0.2794)
			(end -0.12065 0.3048)
			(stroke
				(width 0.1)
				(type default)
			)
			(layer "F.Fab")
		)
		(fp_line
			(start 0.67945 0.3048)
			(end 0.120396 0.3048)
			(stroke
				(width 0.1)
				(type default)
			)
			(layer "F.Fab")
		)
		(fp_line
			(start 0.120396 0.3048)
			(end 0.120396 0.2794)
			(stroke
				(width 0.1)
				(type default)
			)
			(layer "F.Fab")
		)
		(fp_line
			(start -0.12065 0.3048)
			(end -0.67945 0.3048)
			(stroke
				(width 0.1)
				(type default)
			)
			(layer "F.Fab")
		)
		(fp_line
			(start -0.67945 0.3048)
			(end -0.67945 -0.305054)
			(stroke
				(width 0.1)
				(type default)
			)
			(layer "F.Fab")
		)
		(pad "1" smd circle
			(at -0.40005 0 90)
			(size 0 0)
			(layers "F.Cu" "F.Mask" "F.Paste")
			(net "PVNN_TERM_CPU0")
		)
		(pad "2" smd circle
			(at 0.40005 0 90)
			(size 0 0)
			(layers "F.Cu" "F.Mask" "F.Paste")
			(net "PECI_BMC_R")
		)
	)
	(footprint ""
		(layer "F.Cu")
		(at 209.74558 -129.814828 180)
		(property "Reference" "R1950"
			(at 0 0 180)
			(layer "F.SilkS")
			(hide yes)
			(effects
				(font
					(size 1.27 1.27)
				)
			)
		)
		(property "Value" ""
			(at 0 0 180)
			(layer "F.Fab")
			(effects
				(font
					(size 1.27 1.27)
				)
			)
		)
		(duplicate_pad_numbers_are_jumpers no)
		(fp_line
			(start 0.7874 0.4064)
			(end -0.7874 0.4064)
			(stroke
				(width 0.1524)
				(type default)
			)
			(layer "F.SilkS")
		)
		(fp_line
			(start 0.7874 -0.4064)
			(end 0.7874 0.4064)
			(stroke
				(width 0.1524)
				(type default)
			)
			(layer "F.SilkS")
		)
		(fp_line
			(start -0.7874 0.4064)
			(end -0.7874 -0.4064)
			(stroke
				(width 0.1524)
				(type default)
			)
			(layer "F.SilkS")
		)
		(fp_line
			(start -0.7874 -0.4064)
			(end 0.7874 -0.4064)
			(stroke
				(width 0.1524)
				(type default)
			)
			(layer "F.SilkS")
		)
		(fp_line
			(start 0.67945 0.3048)
			(end 0.120396 0.3048)
			(stroke
				(width 0.1)
				(type default)
			)
			(layer "F.Fab")
		)
		(fp_line
			(start 0.67945 -0.3048)
			(end 0.67945 0.3048)
			(stroke
				(width 0.1)
				(type default)
			)
			(layer "F.Fab")
		)
		(fp_line
			(start 0.12065 -0.2794)
			(end 0.12065 -0.3048)
			(stroke
				(width 0.1)
				(type default)
			)
			(layer "F.Fab")
		)
		(fp_line
			(start 0.12065 -0.3048)
			(end 0.67945 -0.3048)
			(stroke
				(width 0.1)
				(type default)
			)
			(layer "F.Fab")
		)
		(fp_line
			(start 0.120396 0.3048)
			(end 0.120396 0.2794)
			(stroke
				(width 0.1)
				(type default)
			)
			(layer "F.Fab")
		)
		(fp_line
			(start 0.120396 0.2794)
			(end -0.12065 0.2794)
			(stroke
				(width 0.1)
				(type default)
			)
			(layer "F.Fab")
		)
		(fp_line
			(start -0.12065 0.3048)
			(end -0.67945 0.3048)
			(stroke
				(width 0.1)
				(type default)
			)
			(layer "F.Fab")
		)
		(fp_line
			(start -0.12065 0.2794)
			(end -0.12065 0.3048)
			(stroke
				(width 0.1)
				(type default)
			)
			(layer "F.Fab")
		)
		(fp_line
			(start -0.12065 -0.2794)
			(end 0.12065 -0.2794)
			(stroke
				(width 0.1)
				(type default)
			)
			(layer "F.Fab")
		)
		(fp_line
			(start -0.12065 -0.305054)
			(end -0.12065 -0.2794)
			(stroke
				(width 0.1)
				(type default)
			)
			(layer "F.Fab")
		)
		(fp_line
			(start -0.67945 0.3048)
			(end -0.67945 -0.305054)
			(stroke
				(width 0.1)
				(type default)
			)
			(layer "F.Fab")
		)
		(fp_line
			(start -0.67945 -0.305054)
			(end -0.12065 -0.305054)
			(stroke
				(width 0.1)
				(type default)
			)
			(layer "F.Fab")
		)
		(pad "1" smd circle
			(at -0.40005 0 180)
			(size 0 0)
			(layers "F.Cu" "F.Mask" "F.Paste")
			(net "FM_COMP_P3V3_AUX_VIN")
		)
		(pad "2" smd circle
			(at 0.40005 0 180)
			(size 0 0)
			(layers "F.Cu" "F.Mask" "F.Paste")
			(net "FM_COMP_P3V3_AUX_VIN_R")
		)
	)
	(footprint ""
		(layer "F.Cu")
		(at 147.5359 -40.051736 180)
		(property "Reference" "R3303"
			(at 0 0 180)
			(layer "F.SilkS")
			(hide yes)
			(effects
				(font
					(size 1.27 1.27)
				)
			)
		)
		(property "Value" ""
			(at 0 0 180)
			(layer "F.Fab")
			(effects
				(font
					(size 1.27 1.27)
				)
			)
		)
		(duplicate_pad_numbers_are_jumpers no)
		(fp_line
			(start 0.7874 0.4064)
			(end -0.7874 0.4064)
			(stroke
				(width 0.1524)
				(type default)
			)
			(layer "F.SilkS")
		)
		(fp_line
			(start 0.7874 -0.4064)
			(end 0.7874 0.4064)
			(stroke
				(width 0.1524)
				(type default)
			)
			(layer "F.SilkS")
		)
		(fp_line
			(start -0.7874 0.4064)
			(end -0.7874 -0.4064)
			(stroke
				(width 0.1524)
				(type default)
			)
			(layer "F.SilkS")
		)
		(fp_line
			(start -0.7874 -0.4064)
			(end 0.7874 -0.4064)
			(stroke
				(width 0.1524)
				(type default)
			)
			(layer "F.SilkS")
		)
		(fp_line
			(start 0.67945 0.3048)
			(end 0.120396 0.3048)
			(stroke
				(width 0.1)
				(type default)
			)
			(layer "F.Fab")
		)
		(fp_line
			(start 0.67945 -0.3048)
			(end 0.67945 0.3048)
			(stroke
				(width 0.1)
				(type default)
			)
			(layer "F.Fab")
		)
		(fp_line
			(start 0.12065 -0.2794)
			(end 0.12065 -0.3048)
			(stroke
				(width 0.1)
				(type default)
			)
			(layer "F.Fab")
		)
		(fp_line
			(start 0.12065 -0.3048)
			(end 0.67945 -0.3048)
			(stroke
				(width 0.1)
				(type default)
			)
			(layer "F.Fab")
		)
		(fp_line
			(start 0.120396 0.3048)
			(end 0.120396 0.2794)
			(stroke
				(width 0.1)
				(type default)
			)
			(layer "F.Fab")
		)
		(fp_line
			(start 0.120396 0.2794)
			(end -0.12065 0.2794)
			(stroke
				(width 0.1)
				(type default)
			)
			(layer "F.Fab")
		)
		(fp_line
			(start -0.12065 0.3048)
			(end -0.67945 0.3048)
			(stroke
				(width 0.1)
				(type default)
			)
			(layer "F.Fab")
		)
		(fp_line
			(start -0.12065 0.2794)
			(end -0.12065 0.3048)
			(stroke
				(width 0.1)
				(type default)
			)
			(layer "F.Fab")
		)
		(fp_line
			(start -0.12065 -0.2794)
			(end 0.12065 -0.2794)
			(stroke
				(width 0.1)
				(type default)
			)
			(layer "F.Fab")
		)
		(fp_line
			(start -0.12065 -0.305054)
			(end -0.12065 -0.2794)
			(stroke
				(width 0.1)
				(type default)
			)
			(layer "F.Fab")
		)
		(fp_line
			(start -0.67945 0.3048)
			(end -0.67945 -0.305054)
			(stroke
				(width 0.1)
				(type default)
			)
			(layer "F.Fab")
		)
		(fp_line
			(start -0.67945 -0.305054)
			(end -0.12065 -0.305054)
			(stroke
				(width 0.1)
				(type default)
			)
			(layer "F.Fab")
		)
		(pad "1" smd circle
			(at -0.40005 0 180)
			(size 0 0)
			(layers "F.Cu" "F.Mask" "F.Paste")
			(net "OCP_SFF_PRSNT_ALL_R_N")
		)
		(pad "2" smd circle
			(at 0.40005 0 180)
			(size 0 0)
			(layers "F.Cu" "F.Mask" "F.Paste")
			(net "OCP_SFF_PRSNT_ALL_R1_N")
		)
	)
	(footprint ""
		(layer "F.Cu")
		(at 159.274256 -64.694308 90)
		(property "Reference" "C1592"
			(at 0 0 90)
			(layer "F.SilkS")
			(hide yes)
			(effects
				(font
					(size 1.27 1.27)
				)
			)
		)
		(property "Value" ""
			(at 0 0 90)
			(layer "F.Fab")
			(effects
				(font
					(size 1.27 1.27)
				)
			)
		)
		(duplicate_pad_numbers_are_jumpers no)
		(fp_line
			(start 0.7874 -0.4064)
			(end 0.7874 0.4064)
			(stroke
				(width 0.1524)
				(type default)
			)
			(layer "F.SilkS")
		)
		(fp_line
			(start -0.7874 -0.4064)
			(end 0.7874 -0.4064)
			(stroke
				(width 0.1524)
				(type default)
			)
			(layer "F.SilkS")
		)
		(fp_line
			(start 0.7874 0.4064)
			(end -0.7874 0.4064)
			(stroke
				(width 0.1524)
				(type default)
			)
			(layer "F.SilkS")
		)
		(fp_line
			(start -0.7874 0.4064)
			(end -0.7874 -0.4064)
			(stroke
				(width 0.1524)
				(type default)
			)
			(layer "F.SilkS")
		)
		(fp_line
			(start -0.12065 -0.305054)
			(end -0.12065 -0.2794)
			(stroke
				(width 0.1)
				(type default)
			)
			(layer "F.Fab")
		)
		(fp_line
			(start -0.67945 -0.305054)
			(end -0.12065 -0.305054)
			(stroke
				(width 0.1)
				(type default)
			)
			(layer "F.Fab")
		)
		(fp_line
			(start 0.67945 -0.3048)
			(end 0.67945 0.3048)
			(stroke
				(width 0.1)
				(type default)
			)
			(layer "F.Fab")
		)
		(fp_line
			(start 0.12065 -0.3048)
			(end 0.67945 -0.3048)
			(stroke
				(width 0.1)
				(type default)
			)
			(layer "F.Fab")
		)
		(fp_line
			(start 0.12065 -0.2794)
			(end 0.12065 -0.3048)
			(stroke
				(width 0.1)
				(type default)
			)
			(layer "F.Fab")
		)
		(fp_line
			(start -0.12065 -0.2794)
			(end 0.12065 -0.2794)
			(stroke
				(width 0.1)
				(type default)
			)
			(layer "F.Fab")
		)
		(fp_line
			(start 0.120396 0.2794)
			(end -0.12065 0.2794)
			(stroke
				(width 0.1)
				(type default)
			)
			(layer "F.Fab")
		)
		(fp_line
			(start -0.12065 0.2794)
			(end -0.12065 0.3048)
			(stroke
				(width 0.1)
				(type default)
			)
			(layer "F.Fab")
		)
		(fp_line
			(start 0.67945 0.3048)
			(end 0.120396 0.3048)
			(stroke
				(width 0.1)
				(type default)
			)
			(layer "F.Fab")
		)
		(fp_line
			(start 0.120396 0.3048)
			(end 0.120396 0.2794)
			(stroke
				(width 0.1)
				(type default)
			)
			(layer "F.Fab")
		)
		(fp_line
			(start -0.12065 0.3048)
			(end -0.67945 0.3048)
			(stroke
				(width 0.1)
				(type default)
			)
			(layer "F.Fab")
		)
		(fp_line
			(start -0.67945 0.3048)
			(end -0.67945 -0.305054)
			(stroke
				(width 0.1)
				(type default)
			)
			(layer "F.Fab")
		)
		(pad "1" smd circle
			(at -0.40005 0 90)
			(size 0 0)
			(layers "F.Cu" "F.Mask" "F.Paste")
			(net "P3V3_AUX")
		)
		(pad "2" smd circle
			(at 0.40005 0 90)
			(size 0 0)
			(layers "F.Cu" "F.Mask" "F.Paste")
			(net "GND")
		)
	)
	(footprint ""
		(layer "F.Cu")
		(at 271.225772 -71.4756)
		(property "Reference" "PL150"
			(at -4.800092 -4.062222 0)
			(unlocked yes)
			(layer "F.SilkS")
			(effects
				(font
					(size 0.7874 0.5842)
					(thickness 0.1524)
				)
				(justify left)
			)
		)
		(property "Value" ""
			(at 0 0 0)
			(layer "F.Fab")
			(effects
				(font
					(size 1.27 1.27)
				)
			)
		)
		(duplicate_pad_numbers_are_jumpers no)
		(fp_line
			(start -4.800092 -3.199892)
			(end 4.800092 -3.199892)
			(stroke
				(width 0.1524)
				(type default)
			)
			(layer "F.SilkS")
		)
		(fp_line
			(start -4.800092 -1.6891)
			(end -4.800092 -3.199892)
			(stroke
				(width 0.1524)
				(type default)
			)
			(layer "F.SilkS")
		)
		(fp_line
			(start -4.800092 3.199892)
			(end -4.800092 1.6891)
			(stroke
				(width 0.1524)
				(type default)
			)
			(layer "F.SilkS")
		)
		(fp_line
			(start 4.800092 -3.199892)
			(end 4.800092 -1.6891)
			(stroke
				(width 0.1524)
				(type default)
			)
			(layer "F.SilkS")
		)
		(fp_line
			(start 4.800092 1.6891)
			(end 4.800092 3.199892)
			(stroke
				(width 0.1524)
				(type default)
			)
			(layer "F.SilkS")
		)
		(fp_line
			(start 4.800092 3.199892)
			(end -4.800092 3.199892)
			(stroke
				(width 0.1524)
				(type default)
			)
			(layer "F.SilkS")
		)
		(fp_line
			(start -4.800092 -3.199892)
			(end 4.800092 -3.199892)
			(stroke
				(width 0.1)
				(type default)
			)
			(layer "F.Fab")
		)
		(fp_line
			(start -4.800092 3.199892)
			(end -4.800092 -3.199892)
			(stroke
				(width 0.1)
				(type default)
			)
			(layer "F.Fab")
		)
		(fp_line
			(start 4.800092 -3.199892)
			(end 4.800092 3.199892)
			(stroke
				(width 0.1)
				(type default)
			)
			(layer "F.Fab")
		)
		(fp_line
			(start 4.800092 3.199892)
			(end -4.800092 3.199892)
			(stroke
				(width 0.1)
				(type default)
			)
			(layer "F.Fab")
		)
		(pad "1" smd rect
			(at -3.350006 0 90)
			(size 3.0988 3.2004)
			(layers "F.Cu" "F.Mask" "F.Paste")
			(net "SW_P1V05_PCH_AUX_SW")
		)
		(pad "2" smd rect
			(at 3.350006 0 90)
			(size 3.0988 3.2004)
			(layers "F.Cu" "F.Mask" "F.Paste")
			(net "P1V05_PCH_AUX")
		)
	)
	(footprint ""
		(layer "F.Cu")
		(at 178.044602 -32.950912 90)
		(property "Reference" "PR3999"
			(at 0 0 90)
			(layer "F.SilkS")
			(hide yes)
			(effects
				(font
					(size 1.27 1.27)
				)
			)
		)
		(property "Value" ""
			(at 0 0 90)
			(layer "F.Fab")
			(effects
				(font
					(size 1.27 1.27)
				)
			)
		)
		(duplicate_pad_numbers_are_jumpers no)
		(fp_line
			(start 0.7874 -0.4064)
			(end 0.7874 0.4064)
			(stroke
				(width 0.1524)
				(type default)
			)
			(layer "F.SilkS")
		)
		(fp_line
			(start -0.7874 -0.4064)
			(end 0.7874 -0.4064)
			(stroke
				(width 0.1524)
				(type default)
			)
			(layer "F.SilkS")
		)
		(fp_line
			(start 0.7874 0.4064)
			(end -0.7874 0.4064)
			(stroke
				(width 0.1524)
				(type default)
			)
			(layer "F.SilkS")
		)
		(fp_line
			(start -0.7874 0.4064)
			(end -0.7874 -0.4064)
			(stroke
				(width 0.1524)
				(type default)
			)
			(layer "F.SilkS")
		)
		(fp_line
			(start -0.12065 -0.305054)
			(end -0.12065 -0.2794)
			(stroke
				(width 0.1)
				(type default)
			)
			(layer "F.Fab")
		)
		(fp_line
			(start -0.67945 -0.305054)
			(end -0.12065 -0.305054)
			(stroke
				(width 0.1)
				(type default)
			)
			(layer "F.Fab")
		)
		(fp_line
			(start 0.67945 -0.3048)
			(end 0.67945 0.3048)
			(stroke
				(width 0.1)
				(type default)
			)
			(layer "F.Fab")
		)
		(fp_line
			(start 0.12065 -0.3048)
			(end 0.67945 -0.3048)
			(stroke
				(width 0.1)
				(type default)
			)
			(layer "F.Fab")
		)
		(fp_line
			(start 0.12065 -0.2794)
			(end 0.12065 -0.3048)
			(stroke
				(width 0.1)
				(type default)
			)
			(layer "F.Fab")
		)
		(fp_line
			(start -0.12065 -0.2794)
			(end 0.12065 -0.2794)
			(stroke
				(width 0.1)
				(type default)
			)
			(layer "F.Fab")
		)
		(fp_line
			(start 0.120396 0.2794)
			(end -0.12065 0.2794)
			(stroke
				(width 0.1)
				(type default)
			)
			(layer "F.Fab")
		)
		(fp_line
			(start -0.12065 0.2794)
			(end -0.12065 0.3048)
			(stroke
				(width 0.1)
				(type default)
			)
			(layer "F.Fab")
		)
		(fp_line
			(start 0.67945 0.3048)
			(end 0.120396 0.3048)
			(stroke
				(width 0.1)
				(type default)
			)
			(layer "F.Fab")
		)
		(fp_line
			(start 0.120396 0.3048)
			(end 0.120396 0.2794)
			(stroke
				(width 0.1)
				(type default)
			)
			(layer "F.Fab")
		)
		(fp_line
			(start -0.12065 0.3048)
			(end -0.67945 0.3048)
			(stroke
				(width 0.1)
				(type default)
			)
			(layer "F.Fab")
		)
		(fp_line
			(start -0.67945 0.3048)
			(end -0.67945 -0.305054)
			(stroke
				(width 0.1)
				(type default)
			)
			(layer "F.Fab")
		)
		(pad "1" smd circle
			(at -0.40005 0 90)
			(size 0 0)
			(layers "F.Cu" "F.Mask" "F.Paste")
			(net "P12V_SCM_ISET")
		)
		(pad "2" smd circle
			(at 0.40005 0 90)
			(size 0 0)
			(layers "F.Cu" "F.Mask" "F.Paste")
			(net "GND")
		)
	)
	(footprint ""
		(layer "F.Cu")
		(at 181.135782 -426.8216 180)
		(property "Reference" "R2796"
			(at 0 0 180)
			(layer "F.SilkS")
			(hide yes)
			(effects
				(font
					(size 1.27 1.27)
				)
			)
		)
		(property "Value" ""
			(at 0 0 180)
			(layer "F.Fab")
			(effects
				(font
					(size 1.27 1.27)
				)
			)
		)
		(duplicate_pad_numbers_are_jumpers no)
		(fp_line
			(start 0.7874 0.4064)
			(end -0.7874 0.4064)
			(stroke
				(width 0.1524)
				(type default)
			)
			(layer "F.SilkS")
		)
		(fp_line
			(start 0.7874 -0.4064)
			(end 0.7874 0.4064)
			(stroke
				(width 0.1524)
				(type default)
			)
			(layer "F.SilkS")
		)
		(fp_line
			(start -0.7874 0.4064)
			(end -0.7874 -0.4064)
			(stroke
				(width 0.1524)
				(type default)
			)
			(layer "F.SilkS")
		)
		(fp_line
			(start -0.7874 -0.4064)
			(end 0.7874 -0.4064)
			(stroke
				(width 0.1524)
				(type default)
			)
			(layer "F.SilkS")
		)
		(fp_line
			(start 0.67945 0.3048)
			(end 0.120396 0.3048)
			(stroke
				(width 0.1)
				(type default)
			)
			(layer "F.Fab")
		)
		(fp_line
			(start 0.67945 -0.3048)
			(end 0.67945 0.3048)
			(stroke
				(width 0.1)
				(type default)
			)
			(layer "F.Fab")
		)
		(fp_line
			(start 0.12065 -0.2794)
			(end 0.12065 -0.3048)
			(stroke
				(width 0.1)
				(type default)
			)
			(layer "F.Fab")
		)
		(fp_line
			(start 0.12065 -0.3048)
			(end 0.67945 -0.3048)
			(stroke
				(width 0.1)
				(type default)
			)
			(layer "F.Fab")
		)
		(fp_line
			(start 0.120396 0.3048)
			(end 0.120396 0.2794)
			(stroke
				(width 0.1)
				(type default)
			)
			(layer "F.Fab")
		)
		(fp_line
			(start 0.120396 0.2794)
			(end -0.12065 0.2794)
			(stroke
				(width 0.1)
				(type default)
			)
			(layer "F.Fab")
		)
		(fp_line
			(start -0.12065 0.3048)
			(end -0.67945 0.3048)
			(stroke
				(width 0.1)
				(type default)
			)
			(layer "F.Fab")
		)
		(fp_line
			(start -0.12065 0.2794)
			(end -0.12065 0.3048)
			(stroke
				(width 0.1)
				(type default)
			)
			(layer "F.Fab")
		)
		(fp_line
			(start -0.12065 -0.2794)
			(end 0.12065 -0.2794)
			(stroke
				(width 0.1)
				(type default)
			)
			(layer "F.Fab")
		)
		(fp_line
			(start -0.12065 -0.305054)
			(end -0.12065 -0.2794)
			(stroke
				(width 0.1)
				(type default)
			)
			(layer "F.Fab")
		)
		(fp_line
			(start -0.67945 0.3048)
			(end -0.67945 -0.305054)
			(stroke
				(width 0.1)
				(type default)
			)
			(layer "F.Fab")
		)
		(fp_line
			(start -0.67945 -0.305054)
			(end -0.12065 -0.305054)
			(stroke
				(width 0.1)
				(type default)
			)
			(layer "F.Fab")
		)
		(pad "1" smd circle
			(at -0.40005 0 180)
			(size 0 0)
			(layers "F.Cu" "F.Mask" "F.Paste")
			(net "FM_PDB_BUF_EN_R")
		)
		(pad "2" smd circle
			(at 0.40005 0 180)
			(size 0 0)
			(layers "F.Cu" "F.Mask" "F.Paste")
			(net "FM_MB_PDB_SMB9_R_EN")
		)
	)
	(footprint ""
		(layer "F.Cu")
		(at 353.254818 -245.634002 -90)
		(property "Reference" "C983"
			(at 0 0 270)
			(layer "F.SilkS")
			(hide yes)
			(effects
				(font
					(size 1.27 1.27)
				)
			)
		)
		(property "Value" ""
			(at 0 0 270)
			(layer "F.Fab")
			(effects
				(font
					(size 1.27 1.27)
				)
			)
		)
		(duplicate_pad_numbers_are_jumpers no)
		(fp_line
			(start -0.7874 0.4064)
			(end -0.7874 -0.4064)
			(stroke
				(width 0.1524)
				(type default)
			)
			(layer "F.SilkS")
		)
		(fp_line
			(start 0.7874 0.4064)
			(end -0.7874 0.4064)
			(stroke
				(width 0.1524)
				(type default)
			)
			(layer "F.SilkS")
		)
		(fp_line
			(start -0.7874 -0.4064)
			(end 0.7874 -0.4064)
			(stroke
				(width 0.1524)
				(type default)
			)
			(layer "F.SilkS")
		)
		(fp_line
			(start 0.7874 -0.4064)
			(end 0.7874 0.4064)
			(stroke
				(width 0.1524)
				(type default)
			)
			(layer "F.SilkS")
		)
		(fp_line
			(start -0.67945 0.3048)
			(end -0.67945 -0.305054)
			(stroke
				(width 0.1)
				(type default)
			)
			(layer "F.Fab")
		)
		(fp_line
			(start -0.12065 0.3048)
			(end -0.67945 0.3048)
			(stroke
				(width 0.1)
				(type default)
			)
			(layer "F.Fab")
		)
		(fp_line
			(start 0.120396 0.3048)
			(end 0.120396 0.2794)
			(stroke
				(width 0.1)
				(type default)
			)
			(layer "F.Fab")
		)
		(fp_line
			(start 0.67945 0.3048)
			(end 0.120396 0.3048)
			(stroke
				(width 0.1)
				(type default)
			)
			(layer "F.Fab")
		)
		(fp_line
			(start -0.12065 0.2794)
			(end -0.12065 0.3048)
			(stroke
				(width 0.1)
				(type default)
			)
			(layer "F.Fab")
		)
		(fp_line
			(start 0.120396 0.2794)
			(end -0.12065 0.2794)
			(stroke
				(width 0.1)
				(type default)
			)
			(layer "F.Fab")
		)
		(fp_line
			(start -0.12065 -0.2794)
			(end 0.12065 -0.2794)
			(stroke
				(width 0.1)
				(type default)
			)
			(layer "F.Fab")
		)
		(fp_line
			(start 0.12065 -0.2794)
			(end 0.12065 -0.3048)
			(stroke
				(width 0.1)
				(type default)
			)
			(layer "F.Fab")
		)
		(fp_line
			(start 0.12065 -0.3048)
			(end 0.67945 -0.3048)
			(stroke
				(width 0.1)
				(type default)
			)
			(layer "F.Fab")
		)
		(fp_line
			(start 0.67945 -0.3048)
			(end 0.67945 0.3048)
			(stroke
				(width 0.1)
				(type default)
			)
			(layer "F.Fab")
		)
		(fp_line
			(start -0.67945 -0.305054)
			(end -0.12065 -0.305054)
			(stroke
				(width 0.1)
				(type default)
			)
			(layer "F.Fab")
		)
		(fp_line
			(start -0.12065 -0.305054)
			(end -0.12065 -0.2794)
			(stroke
				(width 0.1)
				(type default)
			)
			(layer "F.Fab")
		)
		(pad "1" smd circle
			(at -0.40005 0 270)
			(size 0 0)
			(layers "F.Cu" "F.Mask" "F.Paste")
			(net "PVCCIN_CPU0")
		)
		(pad "2" smd circle
			(at 0.40005 0 270)
			(size 0 0)
			(layers "F.Cu" "F.Mask" "F.Paste")
			(net "GND")
		)
	)
	(footprint ""
		(layer "F.Cu")
		(at 56.618378 -81.345024 90)
		(property "Reference" "R3092"
			(at 0 0 90)
			(layer "F.SilkS")
			(hide yes)
			(effects
				(font
					(size 1.27 1.27)
				)
			)
		)
		(property "Value" ""
			(at 0 0 90)
			(layer "F.Fab")
			(effects
				(font
					(size 1.27 1.27)
				)
			)
		)
		(duplicate_pad_numbers_are_jumpers no)
		(fp_line
			(start 0.7874 -0.4064)
			(end 0.7874 0.4064)
			(stroke
				(width 0.1524)
				(type default)
			)
			(layer "F.SilkS")
		)
		(fp_line
			(start -0.7874 -0.4064)
			(end 0.7874 -0.4064)
			(stroke
				(width 0.1524)
				(type default)
			)
			(layer "F.SilkS")
		)
		(fp_line
			(start 0.7874 0.4064)
			(end -0.7874 0.4064)
			(stroke
				(width 0.1524)
				(type default)
			)
			(layer "F.SilkS")
		)
		(fp_line
			(start -0.7874 0.4064)
			(end -0.7874 -0.4064)
			(stroke
				(width 0.1524)
				(type default)
			)
			(layer "F.SilkS")
		)
		(fp_line
			(start -0.12065 -0.305054)
			(end -0.12065 -0.2794)
			(stroke
				(width 0.1)
				(type default)
			)
			(layer "F.Fab")
		)
		(fp_line
			(start -0.67945 -0.305054)
			(end -0.12065 -0.305054)
			(stroke
				(width 0.1)
				(type default)
			)
			(layer "F.Fab")
		)
		(fp_line
			(start 0.67945 -0.3048)
			(end 0.67945 0.3048)
			(stroke
				(width 0.1)
				(type default)
			)
			(layer "F.Fab")
		)
		(fp_line
			(start 0.12065 -0.3048)
			(end 0.67945 -0.3048)
			(stroke
				(width 0.1)
				(type default)
			)
			(layer "F.Fab")
		)
		(fp_line
			(start 0.12065 -0.2794)
			(end 0.12065 -0.3048)
			(stroke
				(width 0.1)
				(type default)
			)
			(layer "F.Fab")
		)
		(fp_line
			(start -0.12065 -0.2794)
			(end 0.12065 -0.2794)
			(stroke
				(width 0.1)
				(type default)
			)
			(layer "F.Fab")
		)
		(fp_line
			(start 0.120396 0.2794)
			(end -0.12065 0.2794)
			(stroke
				(width 0.1)
				(type default)
			)
			(layer "F.Fab")
		)
		(fp_line
			(start -0.12065 0.2794)
			(end -0.12065 0.3048)
			(stroke
				(width 0.1)
				(type default)
			)
			(layer "F.Fab")
		)
		(fp_line
			(start 0.67945 0.3048)
			(end 0.120396 0.3048)
			(stroke
				(width 0.1)
				(type default)
			)
			(layer "F.Fab")
		)
		(fp_line
			(start 0.120396 0.3048)
			(end 0.120396 0.2794)
			(stroke
				(width 0.1)
				(type default)
			)
			(layer "F.Fab")
		)
		(fp_line
			(start -0.12065 0.3048)
			(end -0.67945 0.3048)
			(stroke
				(width 0.1)
				(type default)
			)
			(layer "F.Fab")
		)
		(fp_line
			(start -0.67945 0.3048)
			(end -0.67945 -0.305054)
			(stroke
				(width 0.1)
				(type default)
			)
			(layer "F.Fab")
		)
		(pad "1" smd circle
			(at -0.40005 0 90)
			(size 0 0)
			(layers "F.Cu" "F.Mask" "F.Paste")
			(net "LED_PWRGD_PVCCINFAON_CPU0")
		)
		(pad "2" smd circle
			(at 0.40005 0 90)
			(size 0 0)
			(layers "F.Cu" "F.Mask" "F.Paste")
			(net "P3V3_AUX")
		)
	)
	(footprint ""
		(layer "F.Cu")
		(at 350.78416 -357.562658)
		(property "Reference" "R2368"
			(at 0 0 0)
			(layer "F.SilkS")
			(hide yes)
			(effects
				(font
					(size 1.27 1.27)
				)
			)
		)
		(property "Value" ""
			(at 0 0 0)
			(layer "F.Fab")
			(effects
				(font
					(size 1.27 1.27)
				)
			)
		)
		(duplicate_pad_numbers_are_jumpers no)
		(fp_line
			(start -0.7874 -0.4064)
			(end 0.7874 -0.4064)
			(stroke
				(width 0.1524)
				(type default)
			)
			(layer "F.SilkS")
		)
		(fp_line
			(start -0.7874 0.4064)
			(end -0.7874 -0.4064)
			(stroke
				(width 0.1524)
				(type default)
			)
			(layer "F.SilkS")
		)
		(fp_line
			(start 0.7874 -0.4064)
			(end 0.7874 0.4064)
			(stroke
				(width 0.1524)
				(type default)
			)
			(layer "F.SilkS")
		)
		(fp_line
			(start 0.7874 0.4064)
			(end -0.7874 0.4064)
			(stroke
				(width 0.1524)
				(type default)
			)
			(layer "F.SilkS")
		)
		(fp_line
			(start -0.67945 -0.305054)
			(end -0.12065 -0.305054)
			(stroke
				(width 0.1)
				(type default)
			)
			(layer "F.Fab")
		)
		(fp_line
			(start -0.67945 0.3048)
			(end -0.67945 -0.305054)
			(stroke
				(width 0.1)
				(type default)
			)
			(layer "F.Fab")
		)
		(fp_line
			(start -0.12065 -0.305054)
			(end -0.12065 -0.2794)
			(stroke
				(width 0.1)
				(type default)
			)
			(layer "F.Fab")
		)
		(fp_line
			(start -0.12065 -0.2794)
			(end 0.12065 -0.2794)
			(stroke
				(width 0.1)
				(type default)
			)
			(layer "F.Fab")
		)
		(fp_line
			(start -0.12065 0.2794)
			(end -0.12065 0.3048)
			(stroke
				(width 0.1)
				(type default)
			)
			(layer "F.Fab")
		)
		(fp_line
			(start -0.12065 0.3048)
			(end -0.67945 0.3048)
			(stroke
				(width 0.1)
				(type default)
			)
			(layer "F.Fab")
		)
		(fp_line
			(start 0.120396 0.2794)
			(end -0.12065 0.2794)
			(stroke
				(width 0.1)
				(type default)
			)
			(layer "F.Fab")
		)
		(fp_line
			(start 0.120396 0.3048)
			(end 0.120396 0.2794)
			(stroke
				(width 0.1)
				(type default)
			)
			(layer "F.Fab")
		)
		(fp_line
			(start 0.12065 -0.3048)
			(end 0.67945 -0.3048)
			(stroke
				(width 0.1)
				(type default)
			)
			(layer "F.Fab")
		)
		(fp_line
			(start 0.12065 -0.2794)
			(end 0.12065 -0.3048)
			(stroke
				(width 0.1)
				(type default)
			)
			(layer "F.Fab")
		)
		(fp_line
			(start 0.67945 -0.3048)
			(end 0.67945 0.3048)
			(stroke
				(width 0.1)
				(type default)
			)
			(layer "F.Fab")
		)
		(fp_line
			(start 0.67945 0.3048)
			(end 0.120396 0.3048)
			(stroke
				(width 0.1)
				(type default)
			)
			(layer "F.Fab")
		)
		(pad "1" smd circle
			(at -0.40005 0)
			(size 0 0)
			(layers "F.Cu" "F.Mask" "F.Paste")
			(net "SVID_CLK0_CPU0_R")
		)
		(pad "2" smd circle
			(at 0.40005 0)
			(size 0 0)
			(layers "F.Cu" "F.Mask" "F.Paste")
			(net "SVID_CLK_PVCCIN_CPU0_R")
		)
	)
	(footprint ""
		(layer "F.Cu")
		(at 134.92988 -74.259948 90)
		(property "Reference" "C563"
			(at 0 0 90)
			(layer "F.SilkS")
			(hide yes)
			(effects
				(font
					(size 1.27 1.27)
				)
			)
		)
		(property "Value" ""
			(at 0 0 90)
			(layer "F.Fab")
			(effects
				(font
					(size 1.27 1.27)
				)
			)
		)
		(duplicate_pad_numbers_are_jumpers no)
		(fp_line
			(start 1.524 -0.762)
			(end 1.524 0.762)
			(stroke
				(width 0.1524)
				(type default)
			)
			(layer "F.SilkS")
		)
		(fp_line
			(start -1.524 -0.762)
			(end 1.524 -0.762)
			(stroke
				(width 0.1524)
				(type default)
			)
			(layer "F.SilkS")
		)
		(fp_line
			(start 1.524 0.762)
			(end -1.524 0.762)
			(stroke
				(width 0.1524)
				(type default)
			)
			(layer "F.SilkS")
		)
		(fp_line
			(start -1.524 0.762)
			(end -1.524 -0.762)
			(stroke
				(width 0.1524)
				(type default)
			)
			(layer "F.SilkS")
		)
		(fp_line
			(start 1.1049 -0.724916)
			(end -1.1049 -0.724916)
			(stroke
				(width 0.1)
				(type default)
			)
			(layer "F.Fab")
		)
		(fp_line
			(start -1.1049 -0.724916)
			(end -1.1049 0.724916)
			(stroke
				(width 0.1)
				(type default)
			)
			(layer "F.Fab")
		)
		(fp_line
			(start 1.1049 0.724916)
			(end 1.1049 -0.724916)
			(stroke
				(width 0.1)
				(type default)
			)
			(layer "F.Fab")
		)
		(fp_line
			(start -1.1049 0.724916)
			(end 1.1049 0.724916)
			(stroke
				(width 0.1)
				(type default)
			)
			(layer "F.Fab")
		)
		(pad "1" smd rect
			(at -0.889 0 270)
			(size 1.016 1.27)
			(layers "F.Cu" "F.Mask" "F.Paste")
			(net "P3V3_AUX_BMC_D")
		)
		(pad "2" smd rect
			(at 0.889 0 270)
			(size 1.016 1.27)
			(layers "F.Cu" "F.Mask" "F.Paste")
			(net "GND")
		)
	)
	(footprint ""
		(layer "F.Cu")
		(at 438.256172 -32.173418 90)
		(property "Reference" "PR3837"
			(at 0 0 90)
			(layer "F.SilkS")
			(hide yes)
			(effects
				(font
					(size 1.27 1.27)
				)
			)
		)
		(property "Value" ""
			(at 0 0 90)
			(layer "F.Fab")
			(effects
				(font
					(size 1.27 1.27)
				)
			)
		)
		(duplicate_pad_numbers_are_jumpers no)
		(fp_line
			(start 0.7874 -0.4064)
			(end 0.7874 0.4064)
			(stroke
				(width 0.1524)
				(type default)
			)
			(layer "F.SilkS")
		)
		(fp_line
			(start -0.7874 -0.4064)
			(end 0.7874 -0.4064)
			(stroke
				(width 0.1524)
				(type default)
			)
			(layer "F.SilkS")
		)
		(fp_line
			(start 0.7874 0.4064)
			(end -0.7874 0.4064)
			(stroke
				(width 0.1524)
				(type default)
			)
			(layer "F.SilkS")
		)
		(fp_line
			(start -0.7874 0.4064)
			(end -0.7874 -0.4064)
			(stroke
				(width 0.1524)
				(type default)
			)
			(layer "F.SilkS")
		)
		(fp_line
			(start -0.12065 -0.305054)
			(end -0.12065 -0.2794)
			(stroke
				(width 0.1)
				(type default)
			)
			(layer "F.Fab")
		)
		(fp_line
			(start -0.67945 -0.305054)
			(end -0.12065 -0.305054)
			(stroke
				(width 0.1)
				(type default)
			)
			(layer "F.Fab")
		)
		(fp_line
			(start 0.67945 -0.3048)
			(end 0.67945 0.3048)
			(stroke
				(width 0.1)
				(type default)
			)
			(layer "F.Fab")
		)
		(fp_line
			(start 0.12065 -0.3048)
			(end 0.67945 -0.3048)
			(stroke
				(width 0.1)
				(type default)
			)
			(layer "F.Fab")
		)
		(fp_line
			(start 0.12065 -0.2794)
			(end 0.12065 -0.3048)
			(stroke
				(width 0.1)
				(type default)
			)
			(layer "F.Fab")
		)
		(fp_line
			(start -0.12065 -0.2794)
			(end 0.12065 -0.2794)
			(stroke
				(width 0.1)
				(type default)
			)
			(layer "F.Fab")
		)
		(fp_line
			(start 0.120396 0.2794)
			(end -0.12065 0.2794)
			(stroke
				(width 0.1)
				(type default)
			)
			(layer "F.Fab")
		)
		(fp_line
			(start -0.12065 0.2794)
			(end -0.12065 0.3048)
			(stroke
				(width 0.1)
				(type default)
			)
			(layer "F.Fab")
		)
		(fp_line
			(start 0.67945 0.3048)
			(end 0.120396 0.3048)
			(stroke
				(width 0.1)
				(type default)
			)
			(layer "F.Fab")
		)
		(fp_line
			(start 0.120396 0.3048)
			(end 0.120396 0.2794)
			(stroke
				(width 0.1)
				(type default)
			)
			(layer "F.Fab")
		)
		(fp_line
			(start -0.12065 0.3048)
			(end -0.67945 0.3048)
			(stroke
				(width 0.1)
				(type default)
			)
			(layer "F.Fab")
		)
		(fp_line
			(start -0.67945 0.3048)
			(end -0.67945 -0.305054)
			(stroke
				(width 0.1)
				(type default)
			)
			(layer "F.Fab")
		)
		(pad "1" smd circle
			(at -0.40005 0 90)
			(size 0 0)
			(layers "F.Cu" "F.Mask" "F.Paste")
			(net "P12V_OCP_IMON_1")
		)
		(pad "2" smd circle
			(at 0.40005 0 90)
			(size 0 0)
			(layers "F.Cu" "F.Mask" "F.Paste")
			(net "GND")
		)
	)
	(footprint ""
		(layer "F.Cu")
		(at 36.956238 -129.74574 180)
		(property "Reference" "R2559"
			(at 0 0 180)
			(layer "F.SilkS")
			(hide yes)
			(effects
				(font
					(size 1.27 1.27)
				)
			)
		)
		(property "Value" ""
			(at 0 0 180)
			(layer "F.Fab")
			(effects
				(font
					(size 1.27 1.27)
				)
			)
		)
		(duplicate_pad_numbers_are_jumpers no)
		(fp_line
			(start 0.7874 0.4064)
			(end -0.7874 0.4064)
			(stroke
				(width 0.1524)
				(type default)
			)
			(layer "F.SilkS")
		)
		(fp_line
			(start 0.7874 -0.4064)
			(end 0.7874 0.4064)
			(stroke
				(width 0.1524)
				(type default)
			)
			(layer "F.SilkS")
		)
		(fp_line
			(start -0.7874 0.4064)
			(end -0.7874 -0.4064)
			(stroke
				(width 0.1524)
				(type default)
			)
			(layer "F.SilkS")
		)
		(fp_line
			(start -0.7874 -0.4064)
			(end 0.7874 -0.4064)
			(stroke
				(width 0.1524)
				(type default)
			)
			(layer "F.SilkS")
		)
		(fp_line
			(start 0.67945 0.3048)
			(end 0.120396 0.3048)
			(stroke
				(width 0.1)
				(type default)
			)
			(layer "F.Fab")
		)
		(fp_line
			(start 0.67945 -0.3048)
			(end 0.67945 0.3048)
			(stroke
				(width 0.1)
				(type default)
			)
			(layer "F.Fab")
		)
		(fp_line
			(start 0.12065 -0.2794)
			(end 0.12065 -0.3048)
			(stroke
				(width 0.1)
				(type default)
			)
			(layer "F.Fab")
		)
		(fp_line
			(start 0.12065 -0.3048)
			(end 0.67945 -0.3048)
			(stroke
				(width 0.1)
				(type default)
			)
			(layer "F.Fab")
		)
		(fp_line
			(start 0.120396 0.3048)
			(end 0.120396 0.2794)
			(stroke
				(width 0.1)
				(type default)
			)
			(layer "F.Fab")
		)
		(fp_line
			(start 0.120396 0.2794)
			(end -0.12065 0.2794)
			(stroke
				(width 0.1)
				(type default)
			)
			(layer "F.Fab")
		)
		(fp_line
			(start -0.12065 0.3048)
			(end -0.67945 0.3048)
			(stroke
				(width 0.1)
				(type default)
			)
			(layer "F.Fab")
		)
		(fp_line
			(start -0.12065 0.2794)
			(end -0.12065 0.3048)
			(stroke
				(width 0.1)
				(type default)
			)
			(layer "F.Fab")
		)
		(fp_line
			(start -0.12065 -0.2794)
			(end 0.12065 -0.2794)
			(stroke
				(width 0.1)
				(type default)
			)
			(layer "F.Fab")
		)
		(fp_line
			(start -0.12065 -0.305054)
			(end -0.12065 -0.2794)
			(stroke
				(width 0.1)
				(type default)
			)
			(layer "F.Fab")
		)
		(fp_line
			(start -0.67945 0.3048)
			(end -0.67945 -0.305054)
			(stroke
				(width 0.1)
				(type default)
			)
			(layer "F.Fab")
		)
		(fp_line
			(start -0.67945 -0.305054)
			(end -0.12065 -0.305054)
			(stroke
				(width 0.1)
				(type default)
			)
			(layer "F.Fab")
		)
		(pad "1" smd circle
			(at -0.40005 0 180)
			(size 0 0)
			(layers "F.Cu" "F.Mask" "F.Paste")
			(net "SVID_CLK0_CPU1_R")
		)
		(pad "2" smd circle
			(at 0.40005 0 180)
			(size 0 0)
			(layers "F.Cu" "F.Mask" "F.Paste")
			(net "SVID_CLK_PVCCINFAON_CPU1_R")
		)
	)
	(footprint ""
		(layer "F.Cu")
		(at 430.600104 -139.574778)
		(property "Reference" "C3275"
			(at 0 0 0)
			(layer "F.SilkS")
			(hide yes)
			(effects
				(font
					(size 1.27 1.27)
				)
			)
		)
		(property "Value" ""
			(at 0 0 0)
			(layer "F.Fab")
			(effects
				(font
					(size 1.27 1.27)
				)
			)
		)
		(duplicate_pad_numbers_are_jumpers no)
		(fp_line
			(start -0.7874 -0.4064)
			(end 0.7874 -0.4064)
			(stroke
				(width 0.1524)
				(type default)
			)
			(layer "F.SilkS")
		)
		(fp_line
			(start -0.7874 0.4064)
			(end -0.7874 -0.4064)
			(stroke
				(width 0.1524)
				(type default)
			)
			(layer "F.SilkS")
		)
		(fp_line
			(start 0.7874 -0.4064)
			(end 0.7874 0.4064)
			(stroke
				(width 0.1524)
				(type default)
			)
			(layer "F.SilkS")
		)
		(fp_line
			(start 0.7874 0.4064)
			(end -0.7874 0.4064)
			(stroke
				(width 0.1524)
				(type default)
			)
			(layer "F.SilkS")
		)
		(fp_line
			(start -0.67945 -0.305054)
			(end -0.12065 -0.305054)
			(stroke
				(width 0.1)
				(type default)
			)
			(layer "F.Fab")
		)
		(fp_line
			(start -0.67945 0.3048)
			(end -0.67945 -0.305054)
			(stroke
				(width 0.1)
				(type default)
			)
			(layer "F.Fab")
		)
		(fp_line
			(start -0.12065 -0.305054)
			(end -0.12065 -0.2794)
			(stroke
				(width 0.1)
				(type default)
			)
			(layer "F.Fab")
		)
		(fp_line
			(start -0.12065 -0.2794)
			(end 0.12065 -0.2794)
			(stroke
				(width 0.1)
				(type default)
			)
			(layer "F.Fab")
		)
		(fp_line
			(start -0.12065 0.2794)
			(end -0.12065 0.3048)
			(stroke
				(width 0.1)
				(type default)
			)
			(layer "F.Fab")
		)
		(fp_line
			(start -0.12065 0.3048)
			(end -0.67945 0.3048)
			(stroke
				(width 0.1)
				(type default)
			)
			(layer "F.Fab")
		)
		(fp_line
			(start 0.120396 0.2794)
			(end -0.12065 0.2794)
			(stroke
				(width 0.1)
				(type default)
			)
			(layer "F.Fab")
		)
		(fp_line
			(start 0.120396 0.3048)
			(end 0.120396 0.2794)
			(stroke
				(width 0.1)
				(type default)
			)
			(layer "F.Fab")
		)
		(fp_line
			(start 0.12065 -0.3048)
			(end 0.67945 -0.3048)
			(stroke
				(width 0.1)
				(type default)
			)
			(layer "F.Fab")
		)
		(fp_line
			(start 0.12065 -0.2794)
			(end 0.12065 -0.3048)
			(stroke
				(width 0.1)
				(type default)
			)
			(layer "F.Fab")
		)
		(fp_line
			(start 0.67945 -0.3048)
			(end 0.67945 0.3048)
			(stroke
				(width 0.1)
				(type default)
			)
			(layer "F.Fab")
		)
		(fp_line
			(start 0.67945 0.3048)
			(end 0.120396 0.3048)
			(stroke
				(width 0.1)
				(type default)
			)
			(layer "F.Fab")
		)
		(pad "1" smd circle
			(at -0.40005 0)
			(size 0 0)
			(layers "F.Cu" "F.Mask" "F.Paste")
			(net "PVCCFA_EHV_CPU0_EN_R")
		)
		(pad "2" smd circle
			(at 0.40005 0)
			(size 0 0)
			(layers "F.Cu" "F.Mask" "F.Paste")
			(net "GND")
		)
	)
	(footprint ""
		(layer "F.Cu")
		(at 448.31254 -41.747948)
		(property "Reference" "C1874"
			(at 0 0 0)
			(layer "F.SilkS")
			(hide yes)
			(effects
				(font
					(size 1.27 1.27)
				)
			)
		)
		(property "Value" ""
			(at 0 0 0)
			(layer "F.Fab")
			(effects
				(font
					(size 1.27 1.27)
				)
			)
		)
		(duplicate_pad_numbers_are_jumpers no)
		(fp_line
			(start -0.7874 -0.4064)
			(end 0.7874 -0.4064)
			(stroke
				(width 0.1524)
				(type default)
			)
			(layer "F.SilkS")
		)
		(fp_line
			(start -0.7874 0.4064)
			(end -0.7874 -0.4064)
			(stroke
				(width 0.1524)
				(type default)
			)
			(layer "F.SilkS")
		)
		(fp_line
			(start 0.7874 -0.4064)
			(end 0.7874 0.4064)
			(stroke
				(width 0.1524)
				(type default)
			)
			(layer "F.SilkS")
		)
		(fp_line
			(start 0.7874 0.4064)
			(end -0.7874 0.4064)
			(stroke
				(width 0.1524)
				(type default)
			)
			(layer "F.SilkS")
		)
		(fp_line
			(start -0.67945 -0.305054)
			(end -0.12065 -0.305054)
			(stroke
				(width 0.1)
				(type default)
			)
			(layer "F.Fab")
		)
		(fp_line
			(start -0.67945 0.3048)
			(end -0.67945 -0.305054)
			(stroke
				(width 0.1)
				(type default)
			)
			(layer "F.Fab")
		)
		(fp_line
			(start -0.12065 -0.305054)
			(end -0.12065 -0.2794)
			(stroke
				(width 0.1)
				(type default)
			)
			(layer "F.Fab")
		)
		(fp_line
			(start -0.12065 -0.2794)
			(end 0.12065 -0.2794)
			(stroke
				(width 0.1)
				(type default)
			)
			(layer "F.Fab")
		)
		(fp_line
			(start -0.12065 0.2794)
			(end -0.12065 0.3048)
			(stroke
				(width 0.1)
				(type default)
			)
			(layer "F.Fab")
		)
		(fp_line
			(start -0.12065 0.3048)
			(end -0.67945 0.3048)
			(stroke
				(width 0.1)
				(type default)
			)
			(layer "F.Fab")
		)
		(fp_line
			(start 0.120396 0.2794)
			(end -0.12065 0.2794)
			(stroke
				(width 0.1)
				(type default)
			)
			(layer "F.Fab")
		)
		(fp_line
			(start 0.120396 0.3048)
			(end 0.120396 0.2794)
			(stroke
				(width 0.1)
				(type default)
			)
			(layer "F.Fab")
		)
		(fp_line
			(start 0.12065 -0.3048)
			(end 0.67945 -0.3048)
			(stroke
				(width 0.1)
				(type default)
			)
			(layer "F.Fab")
		)
		(fp_line
			(start 0.12065 -0.2794)
			(end 0.12065 -0.3048)
			(stroke
				(width 0.1)
				(type default)
			)
			(layer "F.Fab")
		)
		(fp_line
			(start 0.67945 -0.3048)
			(end 0.67945 0.3048)
			(stroke
				(width 0.1)
				(type default)
			)
			(layer "F.Fab")
		)
		(fp_line
			(start 0.67945 0.3048)
			(end 0.120396 0.3048)
			(stroke
				(width 0.1)
				(type default)
			)
			(layer "F.Fab")
		)
		(pad "1" smd circle
			(at -0.40005 0)
			(size 0 0)
			(layers "F.Cu" "F.Mask" "F.Paste")
			(net "P3V3_AUX")
		)
		(pad "2" smd circle
			(at 0.40005 0)
			(size 0 0)
			(layers "F.Cu" "F.Mask" "F.Paste")
			(net "GND")
		)
	)
	(footprint ""
		(layer "F.Cu")
		(at 217.742008 -402.994622 90)
		(property "Reference" "PC3272"
			(at 0 0 90)
			(layer "F.SilkS")
			(hide yes)
			(effects
				(font
					(size 1.27 1.27)
				)
			)
		)
		(property "Value" ""
			(at 0 0 90)
			(layer "F.Fab")
			(effects
				(font
					(size 1.27 1.27)
				)
			)
		)
		(duplicate_pad_numbers_are_jumpers no)
		(fp_line
			(start 0.7874 -0.4064)
			(end 0.7874 0.4064)
			(stroke
				(width 0.1524)
				(type default)
			)
			(layer "F.SilkS")
		)
		(fp_line
			(start -0.7874 -0.4064)
			(end 0.7874 -0.4064)
			(stroke
				(width 0.1524)
				(type default)
			)
			(layer "F.SilkS")
		)
		(fp_line
			(start 0.7874 0.4064)
			(end -0.7874 0.4064)
			(stroke
				(width 0.1524)
				(type default)
			)
			(layer "F.SilkS")
		)
		(fp_line
			(start -0.7874 0.4064)
			(end -0.7874 -0.4064)
			(stroke
				(width 0.1524)
				(type default)
			)
			(layer "F.SilkS")
		)
		(fp_line
			(start -0.12065 -0.305054)
			(end -0.12065 -0.2794)
			(stroke
				(width 0.1)
				(type default)
			)
			(layer "F.Fab")
		)
		(fp_line
			(start -0.67945 -0.305054)
			(end -0.12065 -0.305054)
			(stroke
				(width 0.1)
				(type default)
			)
			(layer "F.Fab")
		)
		(fp_line
			(start 0.67945 -0.3048)
			(end 0.67945 0.3048)
			(stroke
				(width 0.1)
				(type default)
			)
			(layer "F.Fab")
		)
		(fp_line
			(start 0.12065 -0.3048)
			(end 0.67945 -0.3048)
			(stroke
				(width 0.1)
				(type default)
			)
			(layer "F.Fab")
		)
		(fp_line
			(start 0.12065 -0.2794)
			(end 0.12065 -0.3048)
			(stroke
				(width 0.1)
				(type default)
			)
			(layer "F.Fab")
		)
		(fp_line
			(start -0.12065 -0.2794)
			(end 0.12065 -0.2794)
			(stroke
				(width 0.1)
				(type default)
			)
			(layer "F.Fab")
		)
		(fp_line
			(start 0.120396 0.2794)
			(end -0.12065 0.2794)
			(stroke
				(width 0.1)
				(type default)
			)
			(layer "F.Fab")
		)
		(fp_line
			(start -0.12065 0.2794)
			(end -0.12065 0.3048)
			(stroke
				(width 0.1)
				(type default)
			)
			(layer "F.Fab")
		)
		(fp_line
			(start 0.67945 0.3048)
			(end 0.120396 0.3048)
			(stroke
				(width 0.1)
				(type default)
			)
			(layer "F.Fab")
		)
		(fp_line
			(start 0.120396 0.3048)
			(end 0.120396 0.2794)
			(stroke
				(width 0.1)
				(type default)
			)
			(layer "F.Fab")
		)
		(fp_line
			(start -0.12065 0.3048)
			(end -0.67945 0.3048)
			(stroke
				(width 0.1)
				(type default)
			)
			(layer "F.Fab")
		)
		(fp_line
			(start -0.67945 0.3048)
			(end -0.67945 -0.305054)
			(stroke
				(width 0.1)
				(type default)
			)
			(layer "F.Fab")
		)
		(pad "1" smd circle
			(at -0.40005 0 90)
			(size 0 0)
			(layers "F.Cu" "F.Mask" "F.Paste")
			(net "HSC_VDD_R_3")
		)
		(pad "2" smd circle
			(at 0.40005 0 90)
			(size 0 0)
			(layers "F.Cu" "F.Mask" "F.Paste")
			(net "AGND_HSC")
		)
	)
	(footprint ""
		(layer "F.Cu")
		(at 193.60261 -431.424334 180)
		(property "Reference" "C1775"
			(at 0 0 180)
			(layer "F.SilkS")
			(hide yes)
			(effects
				(font
					(size 1.27 1.27)
				)
			)
		)
		(property "Value" ""
			(at 0 0 180)
			(layer "F.Fab")
			(effects
				(font
					(size 1.27 1.27)
				)
			)
		)
		(duplicate_pad_numbers_are_jumpers no)
		(fp_line
			(start 0.7874 0.4064)
			(end -0.7874 0.4064)
			(stroke
				(width 0.1524)
				(type default)
			)
			(layer "F.SilkS")
		)
		(fp_line
			(start 0.7874 -0.4064)
			(end 0.7874 0.4064)
			(stroke
				(width 0.1524)
				(type default)
			)
			(layer "F.SilkS")
		)
		(fp_line
			(start -0.7874 0.4064)
			(end -0.7874 -0.4064)
			(stroke
				(width 0.1524)
				(type default)
			)
			(layer "F.SilkS")
		)
		(fp_line
			(start -0.7874 -0.4064)
			(end 0.7874 -0.4064)
			(stroke
				(width 0.1524)
				(type default)
			)
			(layer "F.SilkS")
		)
		(fp_line
			(start 0.67945 0.3048)
			(end 0.120396 0.3048)
			(stroke
				(width 0.1)
				(type default)
			)
			(layer "F.Fab")
		)
		(fp_line
			(start 0.67945 -0.3048)
			(end 0.67945 0.3048)
			(stroke
				(width 0.1)
				(type default)
			)
			(layer "F.Fab")
		)
		(fp_line
			(start 0.12065 -0.2794)
			(end 0.12065 -0.3048)
			(stroke
				(width 0.1)
				(type default)
			)
			(layer "F.Fab")
		)
		(fp_line
			(start 0.12065 -0.3048)
			(end 0.67945 -0.3048)
			(stroke
				(width 0.1)
				(type default)
			)
			(layer "F.Fab")
		)
		(fp_line
			(start 0.120396 0.3048)
			(end 0.120396 0.2794)
			(stroke
				(width 0.1)
				(type default)
			)
			(layer "F.Fab")
		)
		(fp_line
			(start 0.120396 0.2794)
			(end -0.12065 0.2794)
			(stroke
				(width 0.1)
				(type default)
			)
			(layer "F.Fab")
		)
		(fp_line
			(start -0.12065 0.3048)
			(end -0.67945 0.3048)
			(stroke
				(width 0.1)
				(type default)
			)
			(layer "F.Fab")
		)
		(fp_line
			(start -0.12065 0.2794)
			(end -0.12065 0.3048)
			(stroke
				(width 0.1)
				(type default)
			)
			(layer "F.Fab")
		)
		(fp_line
			(start -0.12065 -0.2794)
			(end 0.12065 -0.2794)
			(stroke
				(width 0.1)
				(type default)
			)
			(layer "F.Fab")
		)
		(fp_line
			(start -0.12065 -0.305054)
			(end -0.12065 -0.2794)
			(stroke
				(width 0.1)
				(type default)
			)
			(layer "F.Fab")
		)
		(fp_line
			(start -0.67945 0.3048)
			(end -0.67945 -0.305054)
			(stroke
				(width 0.1)
				(type default)
			)
			(layer "F.Fab")
		)
		(fp_line
			(start -0.67945 -0.305054)
			(end -0.12065 -0.305054)
			(stroke
				(width 0.1)
				(type default)
			)
			(layer "F.Fab")
		)
		(pad "1" smd circle
			(at -0.40005 0 180)
			(size 0 0)
			(layers "F.Cu" "F.Mask" "F.Paste")
			(net "P3V3_AUX")
		)
		(pad "2" smd circle
			(at 0.40005 0 180)
			(size 0 0)
			(layers "F.Cu" "F.Mask" "F.Paste")
			(net "GND")
		)
	)
	(footprint ""
		(layer "F.Cu")
		(at 225.171762 -69.318378 -90)
		(property "Reference" "R3979"
			(at 0 0 270)
			(layer "F.SilkS")
			(hide yes)
			(effects
				(font
					(size 1.27 1.27)
				)
			)
		)
		(property "Value" ""
			(at 0 0 270)
			(layer "F.Fab")
			(effects
				(font
					(size 1.27 1.27)
				)
			)
		)
		(duplicate_pad_numbers_are_jumpers no)
		(fp_line
			(start -0.7874 0.4064)
			(end -0.7874 -0.4064)
			(stroke
				(width 0.1524)
				(type default)
			)
			(layer "F.SilkS")
		)
		(fp_line
			(start 0.7874 0.4064)
			(end -0.7874 0.4064)
			(stroke
				(width 0.1524)
				(type default)
			)
			(layer "F.SilkS")
		)
		(fp_line
			(start -0.7874 -0.4064)
			(end 0.7874 -0.4064)
			(stroke
				(width 0.1524)
				(type default)
			)
			(layer "F.SilkS")
		)
		(fp_line
			(start 0.7874 -0.4064)
			(end 0.7874 0.4064)
			(stroke
				(width 0.1524)
				(type default)
			)
			(layer "F.SilkS")
		)
		(fp_line
			(start -0.67945 0.3048)
			(end -0.67945 -0.305054)
			(stroke
				(width 0.1)
				(type default)
			)
			(layer "F.Fab")
		)
		(fp_line
			(start -0.12065 0.3048)
			(end -0.67945 0.3048)
			(stroke
				(width 0.1)
				(type default)
			)
			(layer "F.Fab")
		)
		(fp_line
			(start 0.120396 0.3048)
			(end 0.120396 0.2794)
			(stroke
				(width 0.1)
				(type default)
			)
			(layer "F.Fab")
		)
		(fp_line
			(start 0.67945 0.3048)
			(end 0.120396 0.3048)
			(stroke
				(width 0.1)
				(type default)
			)
			(layer "F.Fab")
		)
		(fp_line
			(start -0.12065 0.2794)
			(end -0.12065 0.3048)
			(stroke
				(width 0.1)
				(type default)
			)
			(layer "F.Fab")
		)
		(fp_line
			(start 0.120396 0.2794)
			(end -0.12065 0.2794)
			(stroke
				(width 0.1)
				(type default)
			)
			(layer "F.Fab")
		)
		(fp_line
			(start -0.12065 -0.2794)
			(end 0.12065 -0.2794)
			(stroke
				(width 0.1)
				(type default)
			)
			(layer "F.Fab")
		)
		(fp_line
			(start 0.12065 -0.2794)
			(end 0.12065 -0.3048)
			(stroke
				(width 0.1)
				(type default)
			)
			(layer "F.Fab")
		)
		(fp_line
			(start 0.12065 -0.3048)
			(end 0.67945 -0.3048)
			(stroke
				(width 0.1)
				(type default)
			)
			(layer "F.Fab")
		)
		(fp_line
			(start 0.67945 -0.3048)
			(end 0.67945 0.3048)
			(stroke
				(width 0.1)
				(type default)
			)
			(layer "F.Fab")
		)
		(fp_line
			(start -0.67945 -0.305054)
			(end -0.12065 -0.305054)
			(stroke
				(width 0.1)
				(type default)
			)
			(layer "F.Fab")
		)
		(fp_line
			(start -0.12065 -0.305054)
			(end -0.12065 -0.2794)
			(stroke
				(width 0.1)
				(type default)
			)
			(layer "F.Fab")
		)
		(pad "1" smd circle
			(at -0.40005 0 270)
			(size 0 0)
			(layers "F.Cu" "F.Mask" "F.Paste")
			(net "P3V3_AUX")
		)
		(pad "2" smd circle
			(at 0.40005 0 270)
			(size 0 0)
			(layers "F.Cu" "F.Mask" "F.Paste")
			(net "TP_P3V3_E1S_PWRGD_0")
		)
	)
	(footprint ""
		(layer "F.Cu")
		(at 430.642522 -181.57063 90)
		(property "Reference" "PC1274"
			(at 0 0 90)
			(layer "F.SilkS")
			(hide yes)
			(effects
				(font
					(size 1.27 1.27)
				)
			)
		)
		(property "Value" ""
			(at 0 0 90)
			(layer "F.Fab")
			(effects
				(font
					(size 1.27 1.27)
				)
			)
		)
		(duplicate_pad_numbers_are_jumpers no)
		(fp_line
			(start 0.7874 -0.4064)
			(end 0.7874 0.4064)
			(stroke
				(width 0.1524)
				(type default)
			)
			(layer "F.SilkS")
		)
		(fp_line
			(start -0.7874 -0.4064)
			(end 0.7874 -0.4064)
			(stroke
				(width 0.1524)
				(type default)
			)
			(layer "F.SilkS")
		)
		(fp_line
			(start 0.7874 0.4064)
			(end -0.7874 0.4064)
			(stroke
				(width 0.1524)
				(type default)
			)
			(layer "F.SilkS")
		)
		(fp_line
			(start -0.7874 0.4064)
			(end -0.7874 -0.4064)
			(stroke
				(width 0.1524)
				(type default)
			)
			(layer "F.SilkS")
		)
		(fp_line
			(start -0.12065 -0.305054)
			(end -0.12065 -0.2794)
			(stroke
				(width 0.1)
				(type default)
			)
			(layer "F.Fab")
		)
		(fp_line
			(start -0.67945 -0.305054)
			(end -0.12065 -0.305054)
			(stroke
				(width 0.1)
				(type default)
			)
			(layer "F.Fab")
		)
		(fp_line
			(start 0.67945 -0.3048)
			(end 0.67945 0.3048)
			(stroke
				(width 0.1)
				(type default)
			)
			(layer "F.Fab")
		)
		(fp_line
			(start 0.12065 -0.3048)
			(end 0.67945 -0.3048)
			(stroke
				(width 0.1)
				(type default)
			)
			(layer "F.Fab")
		)
		(fp_line
			(start 0.12065 -0.2794)
			(end 0.12065 -0.3048)
			(stroke
				(width 0.1)
				(type default)
			)
			(layer "F.Fab")
		)
		(fp_line
			(start -0.12065 -0.2794)
			(end 0.12065 -0.2794)
			(stroke
				(width 0.1)
				(type default)
			)
			(layer "F.Fab")
		)
		(fp_line
			(start 0.120396 0.2794)
			(end -0.12065 0.2794)
			(stroke
				(width 0.1)
				(type default)
			)
			(layer "F.Fab")
		)
		(fp_line
			(start -0.12065 0.2794)
			(end -0.12065 0.3048)
			(stroke
				(width 0.1)
				(type default)
			)
			(layer "F.Fab")
		)
		(fp_line
			(start 0.67945 0.3048)
			(end 0.120396 0.3048)
			(stroke
				(width 0.1)
				(type default)
			)
			(layer "F.Fab")
		)
		(fp_line
			(start 0.120396 0.3048)
			(end 0.120396 0.2794)
			(stroke
				(width 0.1)
				(type default)
			)
			(layer "F.Fab")
		)
		(fp_line
			(start -0.12065 0.3048)
			(end -0.67945 0.3048)
			(stroke
				(width 0.1)
				(type default)
			)
			(layer "F.Fab")
		)
		(fp_line
			(start -0.67945 0.3048)
			(end -0.67945 -0.305054)
			(stroke
				(width 0.1)
				(type default)
			)
			(layer "F.Fab")
		)
		(pad "1" smd circle
			(at -0.40005 0 90)
			(size 0 0)
			(layers "F.Cu" "F.Mask" "F.Paste")
			(net "SW_P12V_PVCCINFAON_CPU0_FLT")
		)
		(pad "2" smd circle
			(at 0.40005 0 90)
			(size 0 0)
			(layers "F.Cu" "F.Mask" "F.Paste")
			(net "GND")
		)
	)
	(footprint ""
		(layer "F.Cu")
		(at 299.23359 -367.378996 90)
		(property "Reference" "PR1781"
			(at 0 0 90)
			(layer "F.SilkS")
			(hide yes)
			(effects
				(font
					(size 1.27 1.27)
				)
			)
		)
		(property "Value" ""
			(at 0 0 90)
			(layer "F.Fab")
			(effects
				(font
					(size 1.27 1.27)
				)
			)
		)
		(duplicate_pad_numbers_are_jumpers no)
		(fp_line
			(start 0.7874 -0.4064)
			(end 0.7874 0.4064)
			(stroke
				(width 0.1524)
				(type default)
			)
			(layer "F.SilkS")
		)
		(fp_line
			(start -0.7874 -0.4064)
			(end 0.7874 -0.4064)
			(stroke
				(width 0.1524)
				(type default)
			)
			(layer "F.SilkS")
		)
		(fp_line
			(start 0.7874 0.4064)
			(end -0.7874 0.4064)
			(stroke
				(width 0.1524)
				(type default)
			)
			(layer "F.SilkS")
		)
		(fp_line
			(start -0.7874 0.4064)
			(end -0.7874 -0.4064)
			(stroke
				(width 0.1524)
				(type default)
			)
			(layer "F.SilkS")
		)
		(fp_line
			(start -0.12065 -0.305054)
			(end -0.12065 -0.2794)
			(stroke
				(width 0.1)
				(type default)
			)
			(layer "F.Fab")
		)
		(fp_line
			(start -0.67945 -0.305054)
			(end -0.12065 -0.305054)
			(stroke
				(width 0.1)
				(type default)
			)
			(layer "F.Fab")
		)
		(fp_line
			(start 0.67945 -0.3048)
			(end 0.67945 0.3048)
			(stroke
				(width 0.1)
				(type default)
			)
			(layer "F.Fab")
		)
		(fp_line
			(start 0.12065 -0.3048)
			(end 0.67945 -0.3048)
			(stroke
				(width 0.1)
				(type default)
			)
			(layer "F.Fab")
		)
		(fp_line
			(start 0.12065 -0.2794)
			(end 0.12065 -0.3048)
			(stroke
				(width 0.1)
				(type default)
			)
			(layer "F.Fab")
		)
		(fp_line
			(start -0.12065 -0.2794)
			(end 0.12065 -0.2794)
			(stroke
				(width 0.1)
				(type default)
			)
			(layer "F.Fab")
		)
		(fp_line
			(start 0.120396 0.2794)
			(end -0.12065 0.2794)
			(stroke
				(width 0.1)
				(type default)
			)
			(layer "F.Fab")
		)
		(fp_line
			(start -0.12065 0.2794)
			(end -0.12065 0.3048)
			(stroke
				(width 0.1)
				(type default)
			)
			(layer "F.Fab")
		)
		(fp_line
			(start 0.67945 0.3048)
			(end 0.120396 0.3048)
			(stroke
				(width 0.1)
				(type default)
			)
			(layer "F.Fab")
		)
		(fp_line
			(start 0.120396 0.3048)
			(end 0.120396 0.2794)
			(stroke
				(width 0.1)
				(type default)
			)
			(layer "F.Fab")
		)
		(fp_line
			(start -0.12065 0.3048)
			(end -0.67945 0.3048)
			(stroke
				(width 0.1)
				(type default)
			)
			(layer "F.Fab")
		)
		(fp_line
			(start -0.67945 0.3048)
			(end -0.67945 -0.305054)
			(stroke
				(width 0.1)
				(type default)
			)
			(layer "F.Fab")
		)
		(pad "1" smd circle
			(at -0.40005 0 90)
			(size 0 0)
			(layers "F.Cu" "F.Mask" "F.Paste")
			(net "SW_PVCCFA_EHV_FIVRA_CPU0_BOOT2")
		)
		(pad "2" smd circle
			(at 0.40005 0 90)
			(size 0 0)
			(layers "F.Cu" "F.Mask" "F.Paste")
			(net "SW_PVCCFA_EHV_FIVRA_CPU0_BOOT2_")
		)
	)
	(footprint ""
		(layer "F.Cu")
		(at 54.242716 -109.91469 180)
		(property "Reference" "R3718"
			(at 0 0 180)
			(layer "F.SilkS")
			(hide yes)
			(effects
				(font
					(size 1.27 1.27)
				)
			)
		)
		(property "Value" ""
			(at 0 0 180)
			(layer "F.Fab")
			(effects
				(font
					(size 1.27 1.27)
				)
			)
		)
		(duplicate_pad_numbers_are_jumpers no)
		(fp_line
			(start 0.7874 0.4064)
			(end -0.7874 0.4064)
			(stroke
				(width 0.1524)
				(type default)
			)
			(layer "F.SilkS")
		)
		(fp_line
			(start 0.7874 -0.4064)
			(end 0.7874 0.4064)
			(stroke
				(width 0.1524)
				(type default)
			)
			(layer "F.SilkS")
		)
		(fp_line
			(start -0.7874 0.4064)
			(end -0.7874 -0.4064)
			(stroke
				(width 0.1524)
				(type default)
			)
			(layer "F.SilkS")
		)
		(fp_line
			(start -0.7874 -0.4064)
			(end 0.7874 -0.4064)
			(stroke
				(width 0.1524)
				(type default)
			)
			(layer "F.SilkS")
		)
		(fp_line
			(start 0.67945 0.3048)
			(end 0.120396 0.3048)
			(stroke
				(width 0.1)
				(type default)
			)
			(layer "F.Fab")
		)
		(fp_line
			(start 0.67945 -0.3048)
			(end 0.67945 0.3048)
			(stroke
				(width 0.1)
				(type default)
			)
			(layer "F.Fab")
		)
		(fp_line
			(start 0.12065 -0.2794)
			(end 0.12065 -0.3048)
			(stroke
				(width 0.1)
				(type default)
			)
			(layer "F.Fab")
		)
		(fp_line
			(start 0.12065 -0.3048)
			(end 0.67945 -0.3048)
			(stroke
				(width 0.1)
				(type default)
			)
			(layer "F.Fab")
		)
		(fp_line
			(start 0.120396 0.3048)
			(end 0.120396 0.2794)
			(stroke
				(width 0.1)
				(type default)
			)
			(layer "F.Fab")
		)
		(fp_line
			(start 0.120396 0.2794)
			(end -0.12065 0.2794)
			(stroke
				(width 0.1)
				(type default)
			)
			(layer "F.Fab")
		)
		(fp_line
			(start -0.12065 0.3048)
			(end -0.67945 0.3048)
			(stroke
				(width 0.1)
				(type default)
			)
			(layer "F.Fab")
		)
		(fp_line
			(start -0.12065 0.2794)
			(end -0.12065 0.3048)
			(stroke
				(width 0.1)
				(type default)
			)
			(layer "F.Fab")
		)
		(fp_line
			(start -0.12065 -0.2794)
			(end 0.12065 -0.2794)
			(stroke
				(width 0.1)
				(type default)
			)
			(layer "F.Fab")
		)
		(fp_line
			(start -0.12065 -0.305054)
			(end -0.12065 -0.2794)
			(stroke
				(width 0.1)
				(type default)
			)
			(layer "F.Fab")
		)
		(fp_line
			(start -0.67945 0.3048)
			(end -0.67945 -0.305054)
			(stroke
				(width 0.1)
				(type default)
			)
			(layer "F.Fab")
		)
		(fp_line
			(start -0.67945 -0.305054)
			(end -0.12065 -0.305054)
			(stroke
				(width 0.1)
				(type default)
			)
			(layer "F.Fab")
		)
		(pad "1" smd circle
			(at -0.40005 0 180)
			(size 0 0)
			(layers "F.Cu" "F.Mask" "F.Paste")
			(net "SMB_LM75_1_3V3AUX_SDA_R")
		)
		(pad "2" smd circle
			(at 0.40005 0 180)
			(size 0 0)
			(layers "F.Cu" "F.Mask" "F.Paste")
			(net "SMB_LM75_1_3V3AUX_SDA")
		)
	)
	(footprint ""
		(layer "F.Cu")
		(at 51.593496 -118.93677)
		(property "Reference" "R3708"
			(at 0 0 0)
			(layer "F.SilkS")
			(hide yes)
			(effects
				(font
					(size 1.27 1.27)
				)
			)
		)
		(property "Value" ""
			(at 0 0 0)
			(layer "F.Fab")
			(effects
				(font
					(size 1.27 1.27)
				)
			)
		)
		(duplicate_pad_numbers_are_jumpers no)
		(fp_line
			(start -0.7874 -0.4064)
			(end 0.7874 -0.4064)
			(stroke
				(width 0.1524)
				(type default)
			)
			(layer "F.SilkS")
		)
		(fp_line
			(start -0.7874 0.4064)
			(end -0.7874 -0.4064)
			(stroke
				(width 0.1524)
				(type default)
			)
			(layer "F.SilkS")
		)
		(fp_line
			(start 0.7874 -0.4064)
			(end 0.7874 0.4064)
			(stroke
				(width 0.1524)
				(type default)
			)
			(layer "F.SilkS")
		)
		(fp_line
			(start 0.7874 0.4064)
			(end -0.7874 0.4064)
			(stroke
				(width 0.1524)
				(type default)
			)
			(layer "F.SilkS")
		)
		(fp_line
			(start -0.67945 -0.305054)
			(end -0.12065 -0.305054)
			(stroke
				(width 0.1)
				(type default)
			)
			(layer "F.Fab")
		)
		(fp_line
			(start -0.67945 0.3048)
			(end -0.67945 -0.305054)
			(stroke
				(width 0.1)
				(type default)
			)
			(layer "F.Fab")
		)
		(fp_line
			(start -0.12065 -0.305054)
			(end -0.12065 -0.2794)
			(stroke
				(width 0.1)
				(type default)
			)
			(layer "F.Fab")
		)
		(fp_line
			(start -0.12065 -0.2794)
			(end 0.12065 -0.2794)
			(stroke
				(width 0.1)
				(type default)
			)
			(layer "F.Fab")
		)
		(fp_line
			(start -0.12065 0.2794)
			(end -0.12065 0.3048)
			(stroke
				(width 0.1)
				(type default)
			)
			(layer "F.Fab")
		)
		(fp_line
			(start -0.12065 0.3048)
			(end -0.67945 0.3048)
			(stroke
				(width 0.1)
				(type default)
			)
			(layer "F.Fab")
		)
		(fp_line
			(start 0.120396 0.2794)
			(end -0.12065 0.2794)
			(stroke
				(width 0.1)
				(type default)
			)
			(layer "F.Fab")
		)
		(fp_line
			(start 0.120396 0.3048)
			(end 0.120396 0.2794)
			(stroke
				(width 0.1)
				(type default)
			)
			(layer "F.Fab")
		)
		(fp_line
			(start 0.12065 -0.3048)
			(end 0.67945 -0.3048)
			(stroke
				(width 0.1)
				(type default)
			)
			(layer "F.Fab")
		)
		(fp_line
			(start 0.12065 -0.2794)
			(end 0.12065 -0.3048)
			(stroke
				(width 0.1)
				(type default)
			)
			(layer "F.Fab")
		)
		(fp_line
			(start 0.67945 -0.3048)
			(end 0.67945 0.3048)
			(stroke
				(width 0.1)
				(type default)
			)
			(layer "F.Fab")
		)
		(fp_line
			(start 0.67945 0.3048)
			(end 0.120396 0.3048)
			(stroke
				(width 0.1)
				(type default)
			)
			(layer "F.Fab")
		)
		(pad "1" smd circle
			(at -0.40005 0)
			(size 0 0)
			(layers "F.Cu" "F.Mask" "F.Paste")
			(net "P3V3_AUX")
		)
		(pad "2" smd circle
			(at 0.40005 0)
			(size 0 0)
			(layers "F.Cu" "F.Mask" "F.Paste")
			(net "PCA9548_PCIE0_ADDR0")
		)
	)
	(footprint ""
		(layer "F.Cu")
		(at 362.65358 -363.5121)
		(property "Reference" "PC2361"
			(at 0 0 0)
			(layer "F.SilkS")
			(hide yes)
			(effects
				(font
					(size 1.27 1.27)
				)
			)
		)
		(property "Value" ""
			(at 0 0 0)
			(layer "F.Fab")
			(effects
				(font
					(size 1.27 1.27)
				)
			)
		)
		(duplicate_pad_numbers_are_jumpers no)
		(fp_line
			(start -0.7874 -0.4064)
			(end 0.7874 -0.4064)
			(stroke
				(width 0.1524)
				(type default)
			)
			(layer "F.SilkS")
		)
		(fp_line
			(start -0.7874 0.4064)
			(end -0.7874 -0.4064)
			(stroke
				(width 0.1524)
				(type default)
			)
			(layer "F.SilkS")
		)
		(fp_line
			(start 0.7874 -0.4064)
			(end 0.7874 0.4064)
			(stroke
				(width 0.1524)
				(type default)
			)
			(layer "F.SilkS")
		)
		(fp_line
			(start 0.7874 0.4064)
			(end -0.7874 0.4064)
			(stroke
				(width 0.1524)
				(type default)
			)
			(layer "F.SilkS")
		)
		(fp_line
			(start -0.67945 -0.305054)
			(end -0.12065 -0.305054)
			(stroke
				(width 0.1)
				(type default)
			)
			(layer "F.Fab")
		)
		(fp_line
			(start -0.67945 0.3048)
			(end -0.67945 -0.305054)
			(stroke
				(width 0.1)
				(type default)
			)
			(layer "F.Fab")
		)
		(fp_line
			(start -0.12065 -0.305054)
			(end -0.12065 -0.2794)
			(stroke
				(width 0.1)
				(type default)
			)
			(layer "F.Fab")
		)
		(fp_line
			(start -0.12065 -0.2794)
			(end 0.12065 -0.2794)
			(stroke
				(width 0.1)
				(type default)
			)
			(layer "F.Fab")
		)
		(fp_line
			(start -0.12065 0.2794)
			(end -0.12065 0.3048)
			(stroke
				(width 0.1)
				(type default)
			)
			(layer "F.Fab")
		)
		(fp_line
			(start -0.12065 0.3048)
			(end -0.67945 0.3048)
			(stroke
				(width 0.1)
				(type default)
			)
			(layer "F.Fab")
		)
		(fp_line
			(start 0.120396 0.2794)
			(end -0.12065 0.2794)
			(stroke
				(width 0.1)
				(type default)
			)
			(layer "F.Fab")
		)
		(fp_line
			(start 0.120396 0.3048)
			(end 0.120396 0.2794)
			(stroke
				(width 0.1)
				(type default)
			)
			(layer "F.Fab")
		)
		(fp_line
			(start 0.12065 -0.3048)
			(end 0.67945 -0.3048)
			(stroke
				(width 0.1)
				(type default)
			)
			(layer "F.Fab")
		)
		(fp_line
			(start 0.12065 -0.2794)
			(end 0.12065 -0.3048)
			(stroke
				(width 0.1)
				(type default)
			)
			(layer "F.Fab")
		)
		(fp_line
			(start 0.67945 -0.3048)
			(end 0.67945 0.3048)
			(stroke
				(width 0.1)
				(type default)
			)
			(layer "F.Fab")
		)
		(fp_line
			(start 0.67945 0.3048)
			(end 0.120396 0.3048)
			(stroke
				(width 0.1)
				(type default)
			)
			(layer "F.Fab")
		)
		(pad "1" smd circle
			(at -0.40005 0)
			(size 0 0)
			(layers "F.Cu" "F.Mask" "F.Paste")
			(net "PVCCIN_CPU0_VCC")
		)
		(pad "2" smd circle
			(at 0.40005 0)
			(size 0 0)
			(layers "F.Cu" "F.Mask" "F.Paste")
			(net "GND")
		)
	)
	(footprint ""
		(layer "F.Cu")
		(at 213.41588 -125.821948)
		(property "Reference" "C1317"
			(at 0 0 0)
			(layer "F.SilkS")
			(hide yes)
			(effects
				(font
					(size 1.27 1.27)
				)
			)
		)
		(property "Value" ""
			(at 0 0 0)
			(layer "F.Fab")
			(effects
				(font
					(size 1.27 1.27)
				)
			)
		)
		(duplicate_pad_numbers_are_jumpers no)
		(fp_line
			(start -0.7874 -0.4064)
			(end 0.7874 -0.4064)
			(stroke
				(width 0.1524)
				(type default)
			)
			(layer "F.SilkS")
		)
		(fp_line
			(start -0.7874 0.4064)
			(end -0.7874 -0.4064)
			(stroke
				(width 0.1524)
				(type default)
			)
			(layer "F.SilkS")
		)
		(fp_line
			(start 0.7874 -0.4064)
			(end 0.7874 0.4064)
			(stroke
				(width 0.1524)
				(type default)
			)
			(layer "F.SilkS")
		)
		(fp_line
			(start 0.7874 0.4064)
			(end -0.7874 0.4064)
			(stroke
				(width 0.1524)
				(type default)
			)
			(layer "F.SilkS")
		)
		(fp_line
			(start -0.67945 -0.305054)
			(end -0.12065 -0.305054)
			(stroke
				(width 0.1)
				(type default)
			)
			(layer "F.Fab")
		)
		(fp_line
			(start -0.67945 0.3048)
			(end -0.67945 -0.305054)
			(stroke
				(width 0.1)
				(type default)
			)
			(layer "F.Fab")
		)
		(fp_line
			(start -0.12065 -0.305054)
			(end -0.12065 -0.2794)
			(stroke
				(width 0.1)
				(type default)
			)
			(layer "F.Fab")
		)
		(fp_line
			(start -0.12065 -0.2794)
			(end 0.12065 -0.2794)
			(stroke
				(width 0.1)
				(type default)
			)
			(layer "F.Fab")
		)
		(fp_line
			(start -0.12065 0.2794)
			(end -0.12065 0.3048)
			(stroke
				(width 0.1)
				(type default)
			)
			(layer "F.Fab")
		)
		(fp_line
			(start -0.12065 0.3048)
			(end -0.67945 0.3048)
			(stroke
				(width 0.1)
				(type default)
			)
			(layer "F.Fab")
		)
		(fp_line
			(start 0.120396 0.2794)
			(end -0.12065 0.2794)
			(stroke
				(width 0.1)
				(type default)
			)
			(layer "F.Fab")
		)
		(fp_line
			(start 0.120396 0.3048)
			(end 0.120396 0.2794)
			(stroke
				(width 0.1)
				(type default)
			)
			(layer "F.Fab")
		)
		(fp_line
			(start 0.12065 -0.3048)
			(end 0.67945 -0.3048)
			(stroke
				(width 0.1)
				(type default)
			)
			(layer "F.Fab")
		)
		(fp_line
			(start 0.12065 -0.2794)
			(end 0.12065 -0.3048)
			(stroke
				(width 0.1)
				(type default)
			)
			(layer "F.Fab")
		)
		(fp_line
			(start 0.67945 -0.3048)
			(end 0.67945 0.3048)
			(stroke
				(width 0.1)
				(type default)
			)
			(layer "F.Fab")
		)
		(fp_line
			(start 0.67945 0.3048)
			(end 0.120396 0.3048)
			(stroke
				(width 0.1)
				(type default)
			)
			(layer "F.Fab")
		)
		(pad "1" smd circle
			(at -0.40005 0)
			(size 0 0)
			(layers "F.Cu" "F.Mask" "F.Paste")
			(net "P3V3_AUX")
		)
		(pad "2" smd circle
			(at 0.40005 0)
			(size 0 0)
			(layers "F.Cu" "F.Mask" "F.Paste")
			(net "GND")
		)
	)
	(footprint ""
		(layer "F.Cu")
		(at 381.229616 -97.604072 -90)
		(property "Reference" "C1290"
			(at 0 0 270)
			(layer "F.SilkS")
			(hide yes)
			(effects
				(font
					(size 1.27 1.27)
				)
			)
		)
		(property "Value" ""
			(at 0 0 270)
			(layer "F.Fab")
			(effects
				(font
					(size 1.27 1.27)
				)
			)
		)
		(duplicate_pad_numbers_are_jumpers no)
		(fp_line
			(start -0.7874 0.4064)
			(end -0.7874 -0.4064)
			(stroke
				(width 0.1524)
				(type default)
			)
			(layer "F.SilkS")
		)
		(fp_line
			(start 0.7874 0.4064)
			(end -0.7874 0.4064)
			(stroke
				(width 0.1524)
				(type default)
			)
			(layer "F.SilkS")
		)
		(fp_line
			(start -0.7874 -0.4064)
			(end 0.7874 -0.4064)
			(stroke
				(width 0.1524)
				(type default)
			)
			(layer "F.SilkS")
		)
		(fp_line
			(start 0.7874 -0.4064)
			(end 0.7874 0.4064)
			(stroke
				(width 0.1524)
				(type default)
			)
			(layer "F.SilkS")
		)
		(fp_line
			(start -0.67945 0.3048)
			(end -0.67945 -0.305054)
			(stroke
				(width 0.1)
				(type default)
			)
			(layer "F.Fab")
		)
		(fp_line
			(start -0.12065 0.3048)
			(end -0.67945 0.3048)
			(stroke
				(width 0.1)
				(type default)
			)
			(layer "F.Fab")
		)
		(fp_line
			(start 0.120396 0.3048)
			(end 0.120396 0.2794)
			(stroke
				(width 0.1)
				(type default)
			)
			(layer "F.Fab")
		)
		(fp_line
			(start 0.67945 0.3048)
			(end 0.120396 0.3048)
			(stroke
				(width 0.1)
				(type default)
			)
			(layer "F.Fab")
		)
		(fp_line
			(start -0.12065 0.2794)
			(end -0.12065 0.3048)
			(stroke
				(width 0.1)
				(type default)
			)
			(layer "F.Fab")
		)
		(fp_line
			(start 0.120396 0.2794)
			(end -0.12065 0.2794)
			(stroke
				(width 0.1)
				(type default)
			)
			(layer "F.Fab")
		)
		(fp_line
			(start -0.12065 -0.2794)
			(end 0.12065 -0.2794)
			(stroke
				(width 0.1)
				(type default)
			)
			(layer "F.Fab")
		)
		(fp_line
			(start 0.12065 -0.2794)
			(end 0.12065 -0.3048)
			(stroke
				(width 0.1)
				(type default)
			)
			(layer "F.Fab")
		)
		(fp_line
			(start 0.12065 -0.3048)
			(end 0.67945 -0.3048)
			(stroke
				(width 0.1)
				(type default)
			)
			(layer "F.Fab")
		)
		(fp_line
			(start 0.67945 -0.3048)
			(end 0.67945 0.3048)
			(stroke
				(width 0.1)
				(type default)
			)
			(layer "F.Fab")
		)
		(fp_line
			(start -0.67945 -0.305054)
			(end -0.12065 -0.305054)
			(stroke
				(width 0.1)
				(type default)
			)
			(layer "F.Fab")
		)
		(fp_line
			(start -0.12065 -0.305054)
			(end -0.12065 -0.2794)
			(stroke
				(width 0.1)
				(type default)
			)
			(layer "F.Fab")
		)
		(pad "1" smd circle
			(at -0.40005 0 270)
			(size 0 0)
			(layers "F.Cu" "F.Mask" "F.Paste")
			(net "P3V3_AUX")
		)
		(pad "2" smd circle
			(at 0.40005 0 270)
			(size 0 0)
			(layers "F.Cu" "F.Mask" "F.Paste")
			(net "GND")
		)
	)
	(footprint ""
		(layer "F.Cu")
		(at 419.60673 -408.517344 -90)
		(property "Reference" "C900"
			(at 0 0 270)
			(layer "F.SilkS")
			(hide yes)
			(effects
				(font
					(size 1.27 1.27)
				)
			)
		)
		(property "Value" ""
			(at 0 0 270)
			(layer "F.Fab")
			(effects
				(font
					(size 1.27 1.27)
				)
			)
		)
		(duplicate_pad_numbers_are_jumpers no)
		(fp_line
			(start -0.299974 0.150114)
			(end -0.299974 -0.150114)
			(stroke
				(width 0.1)
				(type default)
			)
			(layer "F.Fab")
		)
		(fp_line
			(start 0.299974 0.150114)
			(end -0.299974 0.150114)
			(stroke
				(width 0.1)
				(type default)
			)
			(layer "F.Fab")
		)
		(fp_line
			(start -0.299974 -0.150114)
			(end 0.299974 -0.150114)
			(stroke
				(width 0.1)
				(type default)
			)
			(layer "F.Fab")
		)
		(fp_line
			(start 0.299974 -0.150114)
			(end 0.299974 0.150114)
			(stroke
				(width 0.1)
				(type default)
			)
			(layer "F.Fab")
		)
		(pad "1" smd rect
			(at -0.2667 0 270)
			(size 0.3048 0.381)
			(layers "F.Cu" "F.Mask" "F.Paste")
			(net "P5E_CPU0_PE3_TX_C_DN<0>")
		)
		(pad "2" smd rect
			(at 0.2667 0 270)
			(size 0.3048 0.381)
			(layers "F.Cu" "F.Mask" "F.Paste")
			(net "P5E_CPU0_PE3_TX_DN<0>")
		)
	)
	(footprint ""
		(layer "F.Cu")
		(at 17.658842 -105.537762 90)
		(property "Reference" "R4420"
			(at 0 0 90)
			(layer "F.SilkS")
			(hide yes)
			(effects
				(font
					(size 1.27 1.27)
				)
			)
		)
		(property "Value" ""
			(at 0 0 90)
			(layer "F.Fab")
			(effects
				(font
					(size 1.27 1.27)
				)
			)
		)
		(duplicate_pad_numbers_are_jumpers no)
		(fp_line
			(start 0.7874 -0.4064)
			(end 0.7874 0.4064)
			(stroke
				(width 0.1524)
				(type default)
			)
			(layer "F.SilkS")
		)
		(fp_line
			(start -0.026162 -0.4064)
			(end 0.7874 -0.4064)
			(stroke
				(width 0.1524)
				(type default)
			)
			(layer "F.SilkS")
		)
		(fp_line
			(start 0.7874 0.4064)
			(end -0.7874 0.4064)
			(stroke
				(width 0.1524)
				(type default)
			)
			(layer "F.SilkS")
		)
		(fp_line
			(start -0.7874 0.4064)
			(end -0.7874 -0.4064)
			(stroke
				(width 0.1524)
				(type default)
			)
			(layer "F.SilkS")
		)
		(fp_line
			(start -0.12065 -0.305054)
			(end -0.12065 -0.2794)
			(stroke
				(width 0.1)
				(type default)
			)
			(layer "F.Fab")
		)
		(fp_line
			(start -0.67945 -0.305054)
			(end -0.12065 -0.305054)
			(stroke
				(width 0.1)
				(type default)
			)
			(layer "F.Fab")
		)
		(fp_line
			(start 0.67945 -0.3048)
			(end 0.67945 0.3048)
			(stroke
				(width 0.1)
				(type default)
			)
			(layer "F.Fab")
		)
		(fp_line
			(start 0.12065 -0.3048)
			(end 0.67945 -0.3048)
			(stroke
				(width 0.1)
				(type default)
			)
			(layer "F.Fab")
		)
		(fp_line
			(start 0.12065 -0.2794)
			(end 0.12065 -0.3048)
			(stroke
				(width 0.1)
				(type default)
			)
			(layer "F.Fab")
		)
		(fp_line
			(start -0.12065 -0.2794)
			(end 0.12065 -0.2794)
			(stroke
				(width 0.1)
				(type default)
			)
			(layer "F.Fab")
		)
		(fp_line
			(start 0.120396 0.2794)
			(end -0.12065 0.2794)
			(stroke
				(width 0.1)
				(type default)
			)
			(layer "F.Fab")
		)
		(fp_line
			(start -0.12065 0.2794)
			(end -0.12065 0.3048)
			(stroke
				(width 0.1)
				(type default)
			)
			(layer "F.Fab")
		)
		(fp_line
			(start 0.67945 0.3048)
			(end 0.120396 0.3048)
			(stroke
				(width 0.1)
				(type default)
			)
			(layer "F.Fab")
		)
		(fp_line
			(start 0.120396 0.3048)
			(end 0.120396 0.2794)
			(stroke
				(width 0.1)
				(type default)
			)
			(layer "F.Fab")
		)
		(fp_line
			(start -0.12065 0.3048)
			(end -0.67945 0.3048)
			(stroke
				(width 0.1)
				(type default)
			)
			(layer "F.Fab")
		)
		(fp_line
			(start -0.67945 0.3048)
			(end -0.67945 -0.305054)
			(stroke
				(width 0.1)
				(type default)
			)
			(layer "F.Fab")
		)
		(pad "1" smd circle
			(at -0.40005 0 90)
			(size 0 0)
			(layers "F.Cu" "F.Mask" "F.Paste")
			(net "USB2_HOST_BMC_B_DN")
		)
		(pad "2" smd circle
			(at 0.40005 0 90)
			(size 0 0)
			(layers "F.Cu" "F.Mask" "F.Paste")
			(net "GND")
		)
	)
	(footprint ""
		(layer "F.Cu")
		(at 31.29788 -424.271948)
		(property "Reference" "R3455"
			(at 0 0 0)
			(layer "F.SilkS")
			(hide yes)
			(effects
				(font
					(size 1.27 1.27)
				)
			)
		)
		(property "Value" ""
			(at 0 0 0)
			(layer "F.Fab")
			(effects
				(font
					(size 1.27 1.27)
				)
			)
		)
		(duplicate_pad_numbers_are_jumpers no)
		(fp_line
			(start -0.7874 -0.4064)
			(end 0.7874 -0.4064)
			(stroke
				(width 0.1524)
				(type default)
			)
			(layer "F.SilkS")
		)
		(fp_line
			(start -0.7874 0.4064)
			(end -0.7874 -0.4064)
			(stroke
				(width 0.1524)
				(type default)
			)
			(layer "F.SilkS")
		)
		(fp_line
			(start 0.7874 -0.4064)
			(end 0.7874 0.4064)
			(stroke
				(width 0.1524)
				(type default)
			)
			(layer "F.SilkS")
		)
		(fp_line
			(start 0.7874 0.4064)
			(end -0.7874 0.4064)
			(stroke
				(width 0.1524)
				(type default)
			)
			(layer "F.SilkS")
		)
		(fp_line
			(start -0.67945 -0.305054)
			(end -0.12065 -0.305054)
			(stroke
				(width 0.1)
				(type default)
			)
			(layer "F.Fab")
		)
		(fp_line
			(start -0.67945 0.3048)
			(end -0.67945 -0.305054)
			(stroke
				(width 0.1)
				(type default)
			)
			(layer "F.Fab")
		)
		(fp_line
			(start -0.12065 -0.305054)
			(end -0.12065 -0.2794)
			(stroke
				(width 0.1)
				(type default)
			)
			(layer "F.Fab")
		)
		(fp_line
			(start -0.12065 -0.2794)
			(end 0.12065 -0.2794)
			(stroke
				(width 0.1)
				(type default)
			)
			(layer "F.Fab")
		)
		(fp_line
			(start -0.12065 0.2794)
			(end -0.12065 0.3048)
			(stroke
				(width 0.1)
				(type default)
			)
			(layer "F.Fab")
		)
		(fp_line
			(start -0.12065 0.3048)
			(end -0.67945 0.3048)
			(stroke
				(width 0.1)
				(type default)
			)
			(layer "F.Fab")
		)
		(fp_line
			(start 0.120396 0.2794)
			(end -0.12065 0.2794)
			(stroke
				(width 0.1)
				(type default)
			)
			(layer "F.Fab")
		)
		(fp_line
			(start 0.120396 0.3048)
			(end 0.120396 0.2794)
			(stroke
				(width 0.1)
				(type default)
			)
			(layer "F.Fab")
		)
		(fp_line
			(start 0.12065 -0.3048)
			(end 0.67945 -0.3048)
			(stroke
				(width 0.1)
				(type default)
			)
			(layer "F.Fab")
		)
		(fp_line
			(start 0.12065 -0.2794)
			(end 0.12065 -0.3048)
			(stroke
				(width 0.1)
				(type default)
			)
			(layer "F.Fab")
		)
		(fp_line
			(start 0.67945 -0.3048)
			(end 0.67945 0.3048)
			(stroke
				(width 0.1)
				(type default)
			)
			(layer "F.Fab")
		)
		(fp_line
			(start 0.67945 0.3048)
			(end 0.120396 0.3048)
			(stroke
				(width 0.1)
				(type default)
			)
			(layer "F.Fab")
		)
		(pad "1" smd circle
			(at -0.40005 0)
			(size 0 0)
			(layers "F.Cu" "F.Mask" "F.Paste")
			(net "RST_PERST_1_SWB_BUF_R_N")
		)
		(pad "2" smd circle
			(at 0.40005 0)
			(size 0 0)
			(layers "F.Cu" "F.Mask" "F.Paste")
			(net "GND")
		)
	)
	(footprint ""
		(layer "F.Cu")
		(at 424.205654 -371.76837 90)
		(property "Reference" "PC1189"
			(at 0 0 90)
			(layer "F.SilkS")
			(hide yes)
			(effects
				(font
					(size 1.27 1.27)
				)
			)
		)
		(property "Value" ""
			(at 0 0 90)
			(layer "F.Fab")
			(effects
				(font
					(size 1.27 1.27)
				)
			)
		)
		(duplicate_pad_numbers_are_jumpers no)
		(fp_line
			(start -3.400044 1.249934)
			(end 3.400044 1.249934)
			(stroke
				(width 0.1524)
				(type default)
			)
			(layer "F.SilkS")
		)
		(fp_circle
			(center 0 1.249934)
			(end 0 4.649978)
			(stroke
				(width 0.1524)
				(type default)
			)
			(fill no)
			(layer "F.SilkS")
		)
		(fp_poly
			(pts
				(arc
					(start -3.400044 1.249934)
					(mid 0 4.649978)
					(end 3.400044 1.249934)
				)
			)
			(stroke
				(width 0)
				(type default)
			)
			(fill yes)
			(layer "F.SilkS")
		)
		(fp_circle
			(center 0 1.249934)
			(end 0 4.649978)
			(stroke
				(width 0.1)
				(type default)
			)
			(fill no)
			(layer "F.Fab")
		)
		(pad "1" thru_hole rect
			(at 0 0 90)
			(size 1.524 1.524)
			(drill 1.016)
			(layers "*.Cu" "*.Mask")
			(remove_unused_layers no)
			(net "SW_P12V_PVCCFA_EHV_FIVRA_CPU0_R")
			(clearance 0)
			(padstack
				(mode front_inner_back)
				(layer "Inner"
					(shape circle)
					(size 1.524 1.524)
					(clearance 0)
				)
				(layer "B.Cu"
					(shape rect)
					(size 1.524 1.524)
					(clearance 0)
				)
			)
		)
		(pad "2" thru_hole circle
			(at 0 2.500122 90)
			(size 1.524 1.524)
			(drill 1.016)
			(layers "*.Cu" "*.Mask")
			(remove_unused_layers no)
			(net "GND")
			(clearance 0)
		)
	)
	(footprint ""
		(layer "F.Cu")
		(at 68.010786 -65.082674 -90)
		(property "Reference" "R3085"
			(at 0 0 270)
			(layer "F.SilkS")
			(hide yes)
			(effects
				(font
					(size 1.27 1.27)
				)
			)
		)
		(property "Value" ""
			(at 0 0 270)
			(layer "F.Fab")
			(effects
				(font
					(size 1.27 1.27)
				)
			)
		)
		(duplicate_pad_numbers_are_jumpers no)
		(fp_line
			(start -0.7874 0.4064)
			(end -0.7874 -0.4064)
			(stroke
				(width 0.1524)
				(type default)
			)
			(layer "F.SilkS")
		)
		(fp_line
			(start 0.7874 0.4064)
			(end -0.7874 0.4064)
			(stroke
				(width 0.1524)
				(type default)
			)
			(layer "F.SilkS")
		)
		(fp_line
			(start -0.7874 -0.4064)
			(end 0.7874 -0.4064)
			(stroke
				(width 0.1524)
				(type default)
			)
			(layer "F.SilkS")
		)
		(fp_line
			(start 0.7874 -0.4064)
			(end 0.7874 0.4064)
			(stroke
				(width 0.1524)
				(type default)
			)
			(layer "F.SilkS")
		)
		(fp_line
			(start -0.67945 0.3048)
			(end -0.67945 -0.305054)
			(stroke
				(width 0.1)
				(type default)
			)
			(layer "F.Fab")
		)
		(fp_line
			(start -0.12065 0.3048)
			(end -0.67945 0.3048)
			(stroke
				(width 0.1)
				(type default)
			)
			(layer "F.Fab")
		)
		(fp_line
			(start 0.120396 0.3048)
			(end 0.120396 0.2794)
			(stroke
				(width 0.1)
				(type default)
			)
			(layer "F.Fab")
		)
		(fp_line
			(start 0.67945 0.3048)
			(end 0.120396 0.3048)
			(stroke
				(width 0.1)
				(type default)
			)
			(layer "F.Fab")
		)
		(fp_line
			(start -0.12065 0.2794)
			(end -0.12065 0.3048)
			(stroke
				(width 0.1)
				(type default)
			)
			(layer "F.Fab")
		)
		(fp_line
			(start 0.120396 0.2794)
			(end -0.12065 0.2794)
			(stroke
				(width 0.1)
				(type default)
			)
			(layer "F.Fab")
		)
		(fp_line
			(start -0.12065 -0.2794)
			(end 0.12065 -0.2794)
			(stroke
				(width 0.1)
				(type default)
			)
			(layer "F.Fab")
		)
		(fp_line
			(start 0.12065 -0.2794)
			(end 0.12065 -0.3048)
			(stroke
				(width 0.1)
				(type default)
			)
			(layer "F.Fab")
		)
		(fp_line
			(start 0.12065 -0.3048)
			(end 0.67945 -0.3048)
			(stroke
				(width 0.1)
				(type default)
			)
			(layer "F.Fab")
		)
		(fp_line
			(start 0.67945 -0.3048)
			(end 0.67945 0.3048)
			(stroke
				(width 0.1)
				(type default)
			)
			(layer "F.Fab")
		)
		(fp_line
			(start -0.67945 -0.305054)
			(end -0.12065 -0.305054)
			(stroke
				(width 0.1)
				(type default)
			)
			(layer "F.Fab")
		)
		(fp_line
			(start -0.12065 -0.305054)
			(end -0.12065 -0.2794)
			(stroke
				(width 0.1)
				(type default)
			)
			(layer "F.Fab")
		)
		(pad "1" smd circle
			(at -0.40005 0 270)
			(size 0 0)
			(layers "F.Cu" "F.Mask" "F.Paste")
			(net "LED_RST_PLD_CPU1_DRAM_GH_N")
		)
		(pad "2" smd circle
			(at 0.40005 0 270)
			(size 0 0)
			(layers "F.Cu" "F.Mask" "F.Paste")
			(net "P3V3_AUX")
		)
	)
	(footprint ""
		(layer "F.Cu")
		(at 172.8724 -93.538548 90)
		(property "Reference" "R4580"
			(at 0 0 90)
			(layer "F.SilkS")
			(hide yes)
			(effects
				(font
					(size 1.27 1.27)
				)
			)
		)
		(property "Value" ""
			(at 0 0 90)
			(layer "F.Fab")
			(effects
				(font
					(size 1.27 1.27)
				)
			)
		)
		(duplicate_pad_numbers_are_jumpers no)
		(fp_line
			(start 0.7874 -0.4064)
			(end 0.7874 0.4064)
			(stroke
				(width 0.1524)
				(type default)
			)
			(layer "F.SilkS")
		)
		(fp_line
			(start -0.7874 -0.4064)
			(end 0.7874 -0.4064)
			(stroke
				(width 0.1524)
				(type default)
			)
			(layer "F.SilkS")
		)
		(fp_line
			(start 0.7874 0.4064)
			(end -0.7874 0.4064)
			(stroke
				(width 0.1524)
				(type default)
			)
			(layer "F.SilkS")
		)
		(fp_line
			(start -0.7874 0.4064)
			(end -0.7874 -0.4064)
			(stroke
				(width 0.1524)
				(type default)
			)
			(layer "F.SilkS")
		)
		(fp_line
			(start -0.12065 -0.305054)
			(end -0.12065 -0.2794)
			(stroke
				(width 0.1)
				(type default)
			)
			(layer "F.Fab")
		)
		(fp_line
			(start -0.67945 -0.305054)
			(end -0.12065 -0.305054)
			(stroke
				(width 0.1)
				(type default)
			)
			(layer "F.Fab")
		)
		(fp_line
			(start 0.67945 -0.3048)
			(end 0.67945 0.3048)
			(stroke
				(width 0.1)
				(type default)
			)
			(layer "F.Fab")
		)
		(fp_line
			(start 0.12065 -0.3048)
			(end 0.67945 -0.3048)
			(stroke
				(width 0.1)
				(type default)
			)
			(layer "F.Fab")
		)
		(fp_line
			(start 0.12065 -0.2794)
			(end 0.12065 -0.3048)
			(stroke
				(width 0.1)
				(type default)
			)
			(layer "F.Fab")
		)
		(fp_line
			(start -0.12065 -0.2794)
			(end 0.12065 -0.2794)
			(stroke
				(width 0.1)
				(type default)
			)
			(layer "F.Fab")
		)
		(fp_line
			(start 0.120396 0.2794)
			(end -0.12065 0.2794)
			(stroke
				(width 0.1)
				(type default)
			)
			(layer "F.Fab")
		)
		(fp_line
			(start -0.12065 0.2794)
			(end -0.12065 0.3048)
			(stroke
				(width 0.1)
				(type default)
			)
			(layer "F.Fab")
		)
		(fp_line
			(start 0.67945 0.3048)
			(end 0.120396 0.3048)
			(stroke
				(width 0.1)
				(type default)
			)
			(layer "F.Fab")
		)
		(fp_line
			(start 0.120396 0.3048)
			(end 0.120396 0.2794)
			(stroke
				(width 0.1)
				(type default)
			)
			(layer "F.Fab")
		)
		(fp_line
			(start -0.12065 0.3048)
			(end -0.67945 0.3048)
			(stroke
				(width 0.1)
				(type default)
			)
			(layer "F.Fab")
		)
		(fp_line
			(start -0.67945 0.3048)
			(end -0.67945 -0.305054)
			(stroke
				(width 0.1)
				(type default)
			)
			(layer "F.Fab")
		)
		(pad "1" smd rect
			(at -0.40005 0 270)
			(size 0.4572 0.508)
			(layers "F.Cu" "F.Mask" "F.Paste")
			(net "P3V3_AUX")
		)
		(pad "2" smd rect
			(at 0.40005 0 270)
			(size 0.4572 0.508)
			(layers "F.Cu" "F.Mask" "F.Paste")
			(net "FM_BOARD_BMC_SKU_ID4")
		)
	)
	(footprint ""
		(layer "F.Cu")
		(at 367.63452 -65.771268)
		(property "Reference" "U18"
			(at -2.032 -3.27533 0)
			(unlocked yes)
			(layer "F.SilkS")
			(effects
				(font
					(size 0.7874 0.5842)
					(thickness 0.1524)
				)
				(justify left)
			)
		)
		(property "Value" ""
			(at 0 0 0)
			(layer "F.Fab")
			(effects
				(font
					(size 1.27 1.27)
				)
			)
		)
		(duplicate_pad_numbers_are_jumpers no)
		(fp_line
			(start -2.0066 -2.5527)
			(end -0.5715 -2.5527)
			(stroke
				(width 0.1524)
				(type default)
			)
			(layer "F.SilkS")
		)
		(fp_line
			(start -2.0066 2.5527)
			(end -2.0066 -2.5527)
			(stroke
				(width 0.1524)
				(type default)
			)
			(layer "F.SilkS")
		)
		(fp_line
			(start -0.5715 -2.5527)
			(end 0 -1.9812)
			(stroke
				(width 0.1524)
				(type default)
			)
			(layer "F.SilkS")
		)
		(fp_line
			(start 0 -1.9812)
			(end 0.5715 -2.5527)
			(stroke
				(width 0.1524)
				(type default)
			)
			(layer "F.SilkS")
		)
		(fp_line
			(start 0.5715 -2.5527)
			(end 2.0066 -2.5527)
			(stroke
				(width 0.1524)
				(type default)
			)
			(layer "F.SilkS")
		)
		(fp_line
			(start 2.0066 -2.5527)
			(end 2.0066 2.5527)
			(stroke
				(width 0.1524)
				(type default)
			)
			(layer "F.SilkS")
		)
		(fp_line
			(start 2.0066 2.5527)
			(end -2.0066 2.5527)
			(stroke
				(width 0.1524)
				(type default)
			)
			(layer "F.SilkS")
		)
		(fp_poly
			(pts
				(xy -4.36372 -2.233168) (xy -3.81 -1.905) (xy -4.36372 -1.608328)
			)
			(stroke
				(width 0)
				(type default)
			)
			(fill yes)
			(layer "F.SilkS")
		)
		(fp_line
			(start -2.249932 -2.549906)
			(end 2.249932 -2.549906)
			(stroke
				(width 0.1)
				(type default)
			)
			(layer "F.Fab")
		)
		(fp_line
			(start -2.249932 2.549906)
			(end -2.249932 -2.549906)
			(stroke
				(width 0.1)
				(type default)
			)
			(layer "F.Fab")
		)
		(fp_line
			(start 2.249932 -2.549906)
			(end 2.249932 2.549906)
			(stroke
				(width 0.1)
				(type default)
			)
			(layer "F.Fab")
		)
		(fp_line
			(start 2.249932 2.549906)
			(end -2.249932 2.549906)
			(stroke
				(width 0.1)
				(type default)
			)
			(layer "F.Fab")
		)
		(fp_poly
			(pts
				(xy -4.36372 -1.608328) (xy -4.36372 -2.233168) (xy -3.81 -1.905)
			)
			(stroke
				(width 0)
				(type default)
			)
			(fill yes)
			(layer "F.Fab")
		)
		(pad "1" smd rect
			(at -2.921 -1.949958 270)
			(size 0.3556 1.4986)
			(layers "F.Cu" "F.Mask" "F.Paste")
			(net "PWRGD_PVNN_MAIN_CPU0")
		)
		(pad "2" smd rect
			(at -2.921 -1.299972 270)
			(size 0.3556 1.4986)
			(layers "F.Cu" "F.Mask" "F.Paste")
			(net "JTAG_DBP_CPU_HOOK9_MBP3_GTL_N")
		)
		(pad "3" smd rect
			(at -2.921 -0.649986 270)
			(size 0.3556 1.4986)
			(layers "F.Cu" "F.Mask" "F.Paste")
			(net "DBP_CPU_HOOK9_MBP3_GTL_QS_N")
		)
		(pad "4" smd rect
			(at -2.921 0 270)
			(size 0.3556 1.4986)
			(layers "F.Cu" "F.Mask" "F.Paste")
			(net "PWRGD_PVNN_MAIN_CPU0")
		)
		(pad "5" smd rect
			(at -2.921 0.649986 270)
			(size 0.3556 1.4986)
			(layers "F.Cu" "F.Mask" "F.Paste")
			(net "JTAG_DBP_CPU_HOOK8_MBP2_GTL_N")
		)
		(pad "6" smd rect
			(at -2.921 1.299972 270)
			(size 0.3556 1.4986)
			(layers "F.Cu" "F.Mask" "F.Paste")
			(net "DBP_CPU_HOOK8_MBP2_GTL_QS_N")
		)
		(pad "7" smd rect
			(at -2.921 1.949958 270)
			(size 0.3556 1.4986)
			(layers "F.Cu" "F.Mask" "F.Paste")
			(net "GND")
		)
		(pad "8" smd rect
			(at 2.921 1.949958 270)
			(size 0.3556 1.4986)
			(layers "F.Cu" "F.Mask" "F.Paste")
			(net "H_CPU_PRDY_QS_GTL_N")
		)
		(pad "9" smd rect
			(at 2.921 1.299972 270)
			(size 0.3556 1.4986)
			(layers "F.Cu" "F.Mask" "F.Paste")
			(net "JTAG_DBP_PRDY_N")
		)
		(pad "10" smd rect
			(at 2.921 0.649986 270)
			(size 0.3556 1.4986)
			(layers "F.Cu" "F.Mask" "F.Paste")
			(net "PWRGD_PVNN_MAIN_CPU0")
		)
		(pad "11" smd rect
			(at 2.921 0 270)
			(size 0.3556 1.4986)
			(layers "F.Cu" "F.Mask" "F.Paste")
			(net "H_CPU_PREQ_QS_GTL_N")
		)
		(pad "12" smd rect
			(at 2.921 -0.649986 270)
			(size 0.3556 1.4986)
			(layers "F.Cu" "F.Mask" "F.Paste")
			(net "JTAG_DBP_PREQ_N")
		)
		(pad "13" smd rect
			(at 2.921 -1.299972 270)
			(size 0.3556 1.4986)
			(layers "F.Cu" "F.Mask" "F.Paste")
			(net "PWRGD_PVNN_MAIN_CPU0")
		)
		(pad "14" smd rect
			(at 2.921 -1.949958 270)
			(size 0.3556 1.4986)
			(layers "F.Cu" "F.Mask" "F.Paste")
			(net "P3V3_AUX")
		)
	)
	(footprint ""
		(layer "F.Cu")
		(at 28.961334 -169.000678 90)
		(property "Reference" "PC1289"
			(at 0 0 90)
			(layer "F.SilkS")
			(hide yes)
			(effects
				(font
					(size 1.27 1.27)
				)
			)
		)
		(property "Value" ""
			(at 0 0 90)
			(layer "F.Fab")
			(effects
				(font
					(size 1.27 1.27)
				)
			)
		)
		(duplicate_pad_numbers_are_jumpers no)
		(fp_line
			(start 0.7874 -0.4064)
			(end 0.7874 0.4064)
			(stroke
				(width 0.1524)
				(type default)
			)
			(layer "F.SilkS")
		)
		(fp_line
			(start -0.7874 -0.4064)
			(end 0.7874 -0.4064)
			(stroke
				(width 0.1524)
				(type default)
			)
			(layer "F.SilkS")
		)
		(fp_line
			(start 0.7874 0.4064)
			(end -0.7874 0.4064)
			(stroke
				(width 0.1524)
				(type default)
			)
			(layer "F.SilkS")
		)
		(fp_line
			(start -0.7874 0.4064)
			(end -0.7874 -0.4064)
			(stroke
				(width 0.1524)
				(type default)
			)
			(layer "F.SilkS")
		)
		(fp_line
			(start -0.12065 -0.305054)
			(end -0.12065 -0.2794)
			(stroke
				(width 0.1)
				(type default)
			)
			(layer "F.Fab")
		)
		(fp_line
			(start -0.67945 -0.305054)
			(end -0.12065 -0.305054)
			(stroke
				(width 0.1)
				(type default)
			)
			(layer "F.Fab")
		)
		(fp_line
			(start 0.67945 -0.3048)
			(end 0.67945 0.3048)
			(stroke
				(width 0.1)
				(type default)
			)
			(layer "F.Fab")
		)
		(fp_line
			(start 0.12065 -0.3048)
			(end 0.67945 -0.3048)
			(stroke
				(width 0.1)
				(type default)
			)
			(layer "F.Fab")
		)
		(fp_line
			(start 0.12065 -0.2794)
			(end 0.12065 -0.3048)
			(stroke
				(width 0.1)
				(type default)
			)
			(layer "F.Fab")
		)
		(fp_line
			(start -0.12065 -0.2794)
			(end 0.12065 -0.2794)
			(stroke
				(width 0.1)
				(type default)
			)
			(layer "F.Fab")
		)
		(fp_line
			(start 0.120396 0.2794)
			(end -0.12065 0.2794)
			(stroke
				(width 0.1)
				(type default)
			)
			(layer "F.Fab")
		)
		(fp_line
			(start -0.12065 0.2794)
			(end -0.12065 0.3048)
			(stroke
				(width 0.1)
				(type default)
			)
			(layer "F.Fab")
		)
		(fp_line
			(start 0.67945 0.3048)
			(end 0.120396 0.3048)
			(stroke
				(width 0.1)
				(type default)
			)
			(layer "F.Fab")
		)
		(fp_line
			(start 0.120396 0.3048)
			(end 0.120396 0.2794)
			(stroke
				(width 0.1)
				(type default)
			)
			(layer "F.Fab")
		)
		(fp_line
			(start -0.12065 0.3048)
			(end -0.67945 0.3048)
			(stroke
				(width 0.1)
				(type default)
			)
			(layer "F.Fab")
		)
		(fp_line
			(start -0.67945 0.3048)
			(end -0.67945 -0.305054)
			(stroke
				(width 0.1)
				(type default)
			)
			(layer "F.Fab")
		)
		(pad "1" smd circle
			(at -0.40005 0 90)
			(size 0 0)
			(layers "F.Cu" "F.Mask" "F.Paste")
			(net "PVCCD_HV_CPU1_VREF")
		)
		(pad "2" smd circle
			(at 0.40005 0 90)
			(size 0 0)
			(layers "F.Cu" "F.Mask" "F.Paste")
			(net "GND")
		)
	)
	(footprint ""
		(layer "F.Cu")
		(at 54.242716 -117.40769 180)
		(property "Reference" "R3709"
			(at 0 0 180)
			(layer "F.SilkS")
			(hide yes)
			(effects
				(font
					(size 1.27 1.27)
				)
			)
		)
		(property "Value" ""
			(at 0 0 180)
			(layer "F.Fab")
			(effects
				(font
					(size 1.27 1.27)
				)
			)
		)
		(duplicate_pad_numbers_are_jumpers no)
		(fp_line
			(start 0.7874 0.4064)
			(end -0.7874 0.4064)
			(stroke
				(width 0.1524)
				(type default)
			)
			(layer "F.SilkS")
		)
		(fp_line
			(start 0.7874 -0.4064)
			(end 0.7874 0.4064)
			(stroke
				(width 0.1524)
				(type default)
			)
			(layer "F.SilkS")
		)
		(fp_line
			(start -0.7874 0.4064)
			(end -0.7874 -0.4064)
			(stroke
				(width 0.1524)
				(type default)
			)
			(layer "F.SilkS")
		)
		(fp_line
			(start -0.7874 -0.4064)
			(end 0.7874 -0.4064)
			(stroke
				(width 0.1524)
				(type default)
			)
			(layer "F.SilkS")
		)
		(fp_line
			(start 0.67945 0.3048)
			(end 0.120396 0.3048)
			(stroke
				(width 0.1)
				(type default)
			)
			(layer "F.Fab")
		)
		(fp_line
			(start 0.67945 -0.3048)
			(end 0.67945 0.3048)
			(stroke
				(width 0.1)
				(type default)
			)
			(layer "F.Fab")
		)
		(fp_line
			(start 0.12065 -0.2794)
			(end 0.12065 -0.3048)
			(stroke
				(width 0.1)
				(type default)
			)
			(layer "F.Fab")
		)
		(fp_line
			(start 0.12065 -0.3048)
			(end 0.67945 -0.3048)
			(stroke
				(width 0.1)
				(type default)
			)
			(layer "F.Fab")
		)
		(fp_line
			(start 0.120396 0.3048)
			(end 0.120396 0.2794)
			(stroke
				(width 0.1)
				(type default)
			)
			(layer "F.Fab")
		)
		(fp_line
			(start 0.120396 0.2794)
			(end -0.12065 0.2794)
			(stroke
				(width 0.1)
				(type default)
			)
			(layer "F.Fab")
		)
		(fp_line
			(start -0.12065 0.3048)
			(end -0.67945 0.3048)
			(stroke
				(width 0.1)
				(type default)
			)
			(layer "F.Fab")
		)
		(fp_line
			(start -0.12065 0.2794)
			(end -0.12065 0.3048)
			(stroke
				(width 0.1)
				(type default)
			)
			(layer "F.Fab")
		)
		(fp_line
			(start -0.12065 -0.2794)
			(end 0.12065 -0.2794)
			(stroke
				(width 0.1)
				(type default)
			)
			(layer "F.Fab")
		)
		(fp_line
			(start -0.12065 -0.305054)
			(end -0.12065 -0.2794)
			(stroke
				(width 0.1)
				(type default)
			)
			(layer "F.Fab")
		)
		(fp_line
			(start -0.67945 0.3048)
			(end -0.67945 -0.305054)
			(stroke
				(width 0.1)
				(type default)
			)
			(layer "F.Fab")
		)
		(fp_line
			(start -0.67945 -0.305054)
			(end -0.12065 -0.305054)
			(stroke
				(width 0.1)
				(type default)
			)
			(layer "F.Fab")
		)
		(pad "1" smd circle
			(at -0.40005 0 180)
			(size 0 0)
			(layers "F.Cu" "F.Mask" "F.Paste")
			(net "PCA9548_PCIE0_ADDR0")
		)
		(pad "2" smd circle
			(at 0.40005 0 180)
			(size 0 0)
			(layers "F.Cu" "F.Mask" "F.Paste")
			(net "GND")
		)
	)
	(footprint ""
		(layer "F.Cu")
		(at 302.045624 -362.843826 -90)
		(property "Reference" "PC603_P0_2"
			(at 0 0 270)
			(layer "F.SilkS")
			(hide yes)
			(effects
				(font
					(size 1.27 1.27)
				)
			)
		)
		(property "Value" ""
			(at 0 0 270)
			(layer "F.Fab")
			(effects
				(font
					(size 1.27 1.27)
				)
			)
		)
		(duplicate_pad_numbers_are_jumpers no)
		(fp_line
			(start -0.7874 0.4064)
			(end -0.7874 -0.4064)
			(stroke
				(width 0.1524)
				(type default)
			)
			(layer "F.SilkS")
		)
		(fp_line
			(start 0.7874 0.4064)
			(end -0.7874 0.4064)
			(stroke
				(width 0.1524)
				(type default)
			)
			(layer "F.SilkS")
		)
		(fp_line
			(start -0.7874 -0.4064)
			(end 0.7874 -0.4064)
			(stroke
				(width 0.1524)
				(type default)
			)
			(layer "F.SilkS")
		)
		(fp_line
			(start 0.7874 -0.4064)
			(end 0.7874 0.4064)
			(stroke
				(width 0.1524)
				(type default)
			)
			(layer "F.SilkS")
		)
		(fp_line
			(start -0.67945 0.3048)
			(end -0.67945 -0.305054)
			(stroke
				(width 0.1)
				(type default)
			)
			(layer "F.Fab")
		)
		(fp_line
			(start -0.12065 0.3048)
			(end -0.67945 0.3048)
			(stroke
				(width 0.1)
				(type default)
			)
			(layer "F.Fab")
		)
		(fp_line
			(start 0.120396 0.3048)
			(end 0.120396 0.2794)
			(stroke
				(width 0.1)
				(type default)
			)
			(layer "F.Fab")
		)
		(fp_line
			(start 0.67945 0.3048)
			(end 0.120396 0.3048)
			(stroke
				(width 0.1)
				(type default)
			)
			(layer "F.Fab")
		)
		(fp_line
			(start -0.12065 0.2794)
			(end -0.12065 0.3048)
			(stroke
				(width 0.1)
				(type default)
			)
			(layer "F.Fab")
		)
		(fp_line
			(start 0.120396 0.2794)
			(end -0.12065 0.2794)
			(stroke
				(width 0.1)
				(type default)
			)
			(layer "F.Fab")
		)
		(fp_line
			(start -0.12065 -0.2794)
			(end 0.12065 -0.2794)
			(stroke
				(width 0.1)
				(type default)
			)
			(layer "F.Fab")
		)
		(fp_line
			(start 0.12065 -0.2794)
			(end 0.12065 -0.3048)
			(stroke
				(width 0.1)
				(type default)
			)
			(layer "F.Fab")
		)
		(fp_line
			(start 0.12065 -0.3048)
			(end 0.67945 -0.3048)
			(stroke
				(width 0.1)
				(type default)
			)
			(layer "F.Fab")
		)
		(fp_line
			(start 0.67945 -0.3048)
			(end 0.67945 0.3048)
			(stroke
				(width 0.1)
				(type default)
			)
			(layer "F.Fab")
		)
		(fp_line
			(start -0.67945 -0.305054)
			(end -0.12065 -0.305054)
			(stroke
				(width 0.1)
				(type default)
			)
			(layer "F.Fab")
		)
		(fp_line
			(start -0.12065 -0.305054)
			(end -0.12065 -0.2794)
			(stroke
				(width 0.1)
				(type default)
			)
			(layer "F.Fab")
		)
		(pad "1" smd circle
			(at -0.40005 0 270)
			(size 0 0)
			(layers "F.Cu" "F.Mask" "F.Paste")
			(net "SW_P12V_PVCCFA_EHV_FIVRA_CPU0_L")
		)
		(pad "2" smd circle
			(at 0.40005 0 270)
			(size 0 0)
			(layers "F.Cu" "F.Mask" "F.Paste")
			(net "GND")
		)
	)
	(footprint ""
		(layer "F.Cu")
		(at 46.085506 -394.429996)
		(property "Reference" "R4653"
			(at 0 0 0)
			(layer "F.SilkS")
			(hide yes)
			(effects
				(font
					(size 1.27 1.27)
				)
			)
		)
		(property "Value" ""
			(at 0 0 0)
			(layer "F.Fab")
			(effects
				(font
					(size 1.27 1.27)
				)
			)
		)
		(duplicate_pad_numbers_are_jumpers no)
		(fp_line
			(start -0.7874 -0.4064)
			(end 0.7874 -0.4064)
			(stroke
				(width 0.1524)
				(type default)
			)
			(layer "F.SilkS")
		)
		(fp_line
			(start -0.7874 0.4064)
			(end -0.7874 -0.4064)
			(stroke
				(width 0.1524)
				(type default)
			)
			(layer "F.SilkS")
		)
		(fp_line
			(start 0.7874 -0.4064)
			(end 0.7874 0.4064)
			(stroke
				(width 0.1524)
				(type default)
			)
			(layer "F.SilkS")
		)
		(fp_line
			(start 0.7874 0.4064)
			(end -0.7874 0.4064)
			(stroke
				(width 0.1524)
				(type default)
			)
			(layer "F.SilkS")
		)
		(fp_line
			(start -0.67945 -0.305054)
			(end -0.12065 -0.305054)
			(stroke
				(width 0.1)
				(type default)
			)
			(layer "F.Fab")
		)
		(fp_line
			(start -0.67945 0.3048)
			(end -0.67945 -0.305054)
			(stroke
				(width 0.1)
				(type default)
			)
			(layer "F.Fab")
		)
		(fp_line
			(start -0.12065 -0.305054)
			(end -0.12065 -0.2794)
			(stroke
				(width 0.1)
				(type default)
			)
			(layer "F.Fab")
		)
		(fp_line
			(start -0.12065 -0.2794)
			(end 0.12065 -0.2794)
			(stroke
				(width 0.1)
				(type default)
			)
			(layer "F.Fab")
		)
		(fp_line
			(start -0.12065 0.2794)
			(end -0.12065 0.3048)
			(stroke
				(width 0.1)
				(type default)
			)
			(layer "F.Fab")
		)
		(fp_line
			(start -0.12065 0.3048)
			(end -0.67945 0.3048)
			(stroke
				(width 0.1)
				(type default)
			)
			(layer "F.Fab")
		)
		(fp_line
			(start 0.120396 0.2794)
			(end -0.12065 0.2794)
			(stroke
				(width 0.1)
				(type default)
			)
			(layer "F.Fab")
		)
		(fp_line
			(start 0.120396 0.3048)
			(end 0.120396 0.2794)
			(stroke
				(width 0.1)
				(type default)
			)
			(layer "F.Fab")
		)
		(fp_line
			(start 0.12065 -0.3048)
			(end 0.67945 -0.3048)
			(stroke
				(width 0.1)
				(type default)
			)
			(layer "F.Fab")
		)
		(fp_line
			(start 0.12065 -0.2794)
			(end 0.12065 -0.3048)
			(stroke
				(width 0.1)
				(type default)
			)
			(layer "F.Fab")
		)
		(fp_line
			(start 0.67945 -0.3048)
			(end 0.67945 0.3048)
			(stroke
				(width 0.1)
				(type default)
			)
			(layer "F.Fab")
		)
		(fp_line
			(start 0.67945 0.3048)
			(end 0.120396 0.3048)
			(stroke
				(width 0.1)
				(type default)
			)
			(layer "F.Fab")
		)
		(pad "1" smd circle
			(at -0.40005 0)
			(size 0 0)
			(layers "F.Cu" "F.Mask" "F.Paste")
			(net "FM_P2E_BUF2_VODB_DB")
		)
		(pad "2" smd circle
			(at 0.40005 0)
			(size 0 0)
			(layers "F.Cu" "F.Mask" "F.Paste")
			(net "GND")
		)
	)
	(footprint ""
		(layer "F.Cu")
		(at 214.692738 -68.846446 180)
		(property "Reference" "C641"
			(at 0 0 180)
			(layer "F.SilkS")
			(hide yes)
			(effects
				(font
					(size 1.27 1.27)
				)
			)
		)
		(property "Value" ""
			(at 0 0 180)
			(layer "F.Fab")
			(effects
				(font
					(size 1.27 1.27)
				)
			)
		)
		(duplicate_pad_numbers_are_jumpers no)
		(fp_line
			(start 0.7874 0.4064)
			(end -0.7874 0.4064)
			(stroke
				(width 0.1524)
				(type default)
			)
			(layer "F.SilkS")
		)
		(fp_line
			(start 0.7874 -0.4064)
			(end 0.7874 0.4064)
			(stroke
				(width 0.1524)
				(type default)
			)
			(layer "F.SilkS")
		)
		(fp_line
			(start -0.7874 0.4064)
			(end -0.7874 -0.4064)
			(stroke
				(width 0.1524)
				(type default)
			)
			(layer "F.SilkS")
		)
		(fp_line
			(start -0.7874 -0.4064)
			(end 0.7874 -0.4064)
			(stroke
				(width 0.1524)
				(type default)
			)
			(layer "F.SilkS")
		)
		(fp_line
			(start 0.67945 0.3048)
			(end 0.120396 0.3048)
			(stroke
				(width 0.1)
				(type default)
			)
			(layer "F.Fab")
		)
		(fp_line
			(start 0.67945 -0.3048)
			(end 0.67945 0.3048)
			(stroke
				(width 0.1)
				(type default)
			)
			(layer "F.Fab")
		)
		(fp_line
			(start 0.12065 -0.2794)
			(end 0.12065 -0.3048)
			(stroke
				(width 0.1)
				(type default)
			)
			(layer "F.Fab")
		)
		(fp_line
			(start 0.12065 -0.3048)
			(end 0.67945 -0.3048)
			(stroke
				(width 0.1)
				(type default)
			)
			(layer "F.Fab")
		)
		(fp_line
			(start 0.120396 0.3048)
			(end 0.120396 0.2794)
			(stroke
				(width 0.1)
				(type default)
			)
			(layer "F.Fab")
		)
		(fp_line
			(start 0.120396 0.2794)
			(end -0.12065 0.2794)
			(stroke
				(width 0.1)
				(type default)
			)
			(layer "F.Fab")
		)
		(fp_line
			(start -0.12065 0.3048)
			(end -0.67945 0.3048)
			(stroke
				(width 0.1)
				(type default)
			)
			(layer "F.Fab")
		)
		(fp_line
			(start -0.12065 0.2794)
			(end -0.12065 0.3048)
			(stroke
				(width 0.1)
				(type default)
			)
			(layer "F.Fab")
		)
		(fp_line
			(start -0.12065 -0.2794)
			(end 0.12065 -0.2794)
			(stroke
				(width 0.1)
				(type default)
			)
			(layer "F.Fab")
		)
		(fp_line
			(start -0.12065 -0.305054)
			(end -0.12065 -0.2794)
			(stroke
				(width 0.1)
				(type default)
			)
			(layer "F.Fab")
		)
		(fp_line
			(start -0.67945 0.3048)
			(end -0.67945 -0.305054)
			(stroke
				(width 0.1)
				(type default)
			)
			(layer "F.Fab")
		)
		(fp_line
			(start -0.67945 -0.305054)
			(end -0.12065 -0.305054)
			(stroke
				(width 0.1)
				(type default)
			)
			(layer "F.Fab")
		)
		(pad "1" smd circle
			(at -0.40005 0 180)
			(size 0 0)
			(layers "F.Cu" "F.Mask" "F.Paste")
			(net "P3V3_AUX")
		)
		(pad "2" smd circle
			(at 0.40005 0 180)
			(size 0 0)
			(layers "F.Cu" "F.Mask" "F.Paste")
			(net "GND")
		)
	)
	(footprint ""
		(layer "F.Cu")
		(at 166.17315 -421.435276 -90)
		(property "Reference" "C1707"
			(at 0 0 270)
			(layer "F.SilkS")
			(hide yes)
			(effects
				(font
					(size 1.27 1.27)
				)
			)
		)
		(property "Value" ""
			(at 0 0 270)
			(layer "F.Fab")
			(effects
				(font
					(size 1.27 1.27)
				)
			)
		)
		(duplicate_pad_numbers_are_jumpers no)
		(fp_line
			(start -0.7874 0.4064)
			(end -0.7874 -0.4064)
			(stroke
				(width 0.1524)
				(type default)
			)
			(layer "F.SilkS")
		)
		(fp_line
			(start 0.7874 0.4064)
			(end -0.7874 0.4064)
			(stroke
				(width 0.1524)
				(type default)
			)
			(layer "F.SilkS")
		)
		(fp_line
			(start -0.7874 -0.4064)
			(end 0.7874 -0.4064)
			(stroke
				(width 0.1524)
				(type default)
			)
			(layer "F.SilkS")
		)
		(fp_line
			(start 0.7874 -0.4064)
			(end 0.7874 0.4064)
			(stroke
				(width 0.1524)
				(type default)
			)
			(layer "F.SilkS")
		)
		(fp_line
			(start -0.67945 0.3048)
			(end -0.67945 -0.305054)
			(stroke
				(width 0.1)
				(type default)
			)
			(layer "F.Fab")
		)
		(fp_line
			(start -0.12065 0.3048)
			(end -0.67945 0.3048)
			(stroke
				(width 0.1)
				(type default)
			)
			(layer "F.Fab")
		)
		(fp_line
			(start 0.120396 0.3048)
			(end 0.120396 0.2794)
			(stroke
				(width 0.1)
				(type default)
			)
			(layer "F.Fab")
		)
		(fp_line
			(start 0.67945 0.3048)
			(end 0.120396 0.3048)
			(stroke
				(width 0.1)
				(type default)
			)
			(layer "F.Fab")
		)
		(fp_line
			(start -0.12065 0.2794)
			(end -0.12065 0.3048)
			(stroke
				(width 0.1)
				(type default)
			)
			(layer "F.Fab")
		)
		(fp_line
			(start 0.120396 0.2794)
			(end -0.12065 0.2794)
			(stroke
				(width 0.1)
				(type default)
			)
			(layer "F.Fab")
		)
		(fp_line
			(start -0.12065 -0.2794)
			(end 0.12065 -0.2794)
			(stroke
				(width 0.1)
				(type default)
			)
			(layer "F.Fab")
		)
		(fp_line
			(start 0.12065 -0.2794)
			(end 0.12065 -0.3048)
			(stroke
				(width 0.1)
				(type default)
			)
			(layer "F.Fab")
		)
		(fp_line
			(start 0.12065 -0.3048)
			(end 0.67945 -0.3048)
			(stroke
				(width 0.1)
				(type default)
			)
			(layer "F.Fab")
		)
		(fp_line
			(start 0.67945 -0.3048)
			(end 0.67945 0.3048)
			(stroke
				(width 0.1)
				(type default)
			)
			(layer "F.Fab")
		)
		(fp_line
			(start -0.67945 -0.305054)
			(end -0.12065 -0.305054)
			(stroke
				(width 0.1)
				(type default)
			)
			(layer "F.Fab")
		)
		(fp_line
			(start -0.12065 -0.305054)
			(end -0.12065 -0.2794)
			(stroke
				(width 0.1)
				(type default)
			)
			(layer "F.Fab")
		)
		(pad "1" smd circle
			(at -0.40005 0 270)
			(size 0 0)
			(layers "F.Cu" "F.Mask" "F.Paste")
			(net "P3V3_AUX")
		)
		(pad "2" smd circle
			(at 0.40005 0 270)
			(size 0 0)
			(layers "F.Cu" "F.Mask" "F.Paste")
			(net "GND")
		)
	)
	(footprint ""
		(layer "F.Cu")
		(at 322.263516 -24.579072)
		(property "Reference" "R1809"
			(at 0 0 0)
			(layer "F.SilkS")
			(hide yes)
			(effects
				(font
					(size 1.27 1.27)
				)
			)
		)
		(property "Value" ""
			(at 0 0 0)
			(layer "F.Fab")
			(effects
				(font
					(size 1.27 1.27)
				)
			)
		)
		(duplicate_pad_numbers_are_jumpers no)
		(fp_line
			(start -0.7874 -0.4064)
			(end 0.7874 -0.4064)
			(stroke
				(width 0.1524)
				(type default)
			)
			(layer "F.SilkS")
		)
		(fp_line
			(start -0.7874 0.4064)
			(end -0.7874 -0.4064)
			(stroke
				(width 0.1524)
				(type default)
			)
			(layer "F.SilkS")
		)
		(fp_line
			(start 0.7874 -0.4064)
			(end 0.7874 0.4064)
			(stroke
				(width 0.1524)
				(type default)
			)
			(layer "F.SilkS")
		)
		(fp_line
			(start 0.7874 0.4064)
			(end -0.7874 0.4064)
			(stroke
				(width 0.1524)
				(type default)
			)
			(layer "F.SilkS")
		)
		(fp_line
			(start -0.67945 -0.305054)
			(end -0.12065 -0.305054)
			(stroke
				(width 0.1)
				(type default)
			)
			(layer "F.Fab")
		)
		(fp_line
			(start -0.67945 0.3048)
			(end -0.67945 -0.305054)
			(stroke
				(width 0.1)
				(type default)
			)
			(layer "F.Fab")
		)
		(fp_line
			(start -0.12065 -0.305054)
			(end -0.12065 -0.2794)
			(stroke
				(width 0.1)
				(type default)
			)
			(layer "F.Fab")
		)
		(fp_line
			(start -0.12065 -0.2794)
			(end 0.12065 -0.2794)
			(stroke
				(width 0.1)
				(type default)
			)
			(layer "F.Fab")
		)
		(fp_line
			(start -0.12065 0.2794)
			(end -0.12065 0.3048)
			(stroke
				(width 0.1)
				(type default)
			)
			(layer "F.Fab")
		)
		(fp_line
			(start -0.12065 0.3048)
			(end -0.67945 0.3048)
			(stroke
				(width 0.1)
				(type default)
			)
			(layer "F.Fab")
		)
		(fp_line
			(start 0.120396 0.2794)
			(end -0.12065 0.2794)
			(stroke
				(width 0.1)
				(type default)
			)
			(layer "F.Fab")
		)
		(fp_line
			(start 0.120396 0.3048)
			(end 0.120396 0.2794)
			(stroke
				(width 0.1)
				(type default)
			)
			(layer "F.Fab")
		)
		(fp_line
			(start 0.12065 -0.3048)
			(end 0.67945 -0.3048)
			(stroke
				(width 0.1)
				(type default)
			)
			(layer "F.Fab")
		)
		(fp_line
			(start 0.12065 -0.2794)
			(end 0.12065 -0.3048)
			(stroke
				(width 0.1)
				(type default)
			)
			(layer "F.Fab")
		)
		(fp_line
			(start 0.67945 -0.3048)
			(end 0.67945 0.3048)
			(stroke
				(width 0.1)
				(type default)
			)
			(layer "F.Fab")
		)
		(fp_line
			(start 0.67945 0.3048)
			(end 0.120396 0.3048)
			(stroke
				(width 0.1)
				(type default)
			)
			(layer "F.Fab")
		)
		(pad "1" smd circle
			(at -0.40005 0)
			(size 0 0)
			(layers "F.Cu" "F.Mask" "F.Paste")
			(net "P3V3_AUX")
		)
		(pad "2" smd circle
			(at 0.40005 0)
			(size 0 0)
			(layers "F.Cu" "F.Mask" "F.Paste")
			(net "FM_ADR_MODE0")
		)
	)
	(footprint ""
		(layer "F.Cu")
		(at 113.494312 -133.472682 180)
		(property "Reference" "R3394"
			(at 0 0 180)
			(layer "F.SilkS")
			(hide yes)
			(effects
				(font
					(size 1.27 1.27)
				)
			)
		)
		(property "Value" ""
			(at 0 0 180)
			(layer "F.Fab")
			(effects
				(font
					(size 1.27 1.27)
				)
			)
		)
		(duplicate_pad_numbers_are_jumpers no)
		(fp_line
			(start 0.7874 0.4064)
			(end -0.7874 0.4064)
			(stroke
				(width 0.1524)
				(type default)
			)
			(layer "F.SilkS")
		)
		(fp_line
			(start 0.7874 -0.4064)
			(end 0.7874 0.4064)
			(stroke
				(width 0.1524)
				(type default)
			)
			(layer "F.SilkS")
		)
		(fp_line
			(start -0.7874 0.4064)
			(end -0.7874 -0.4064)
			(stroke
				(width 0.1524)
				(type default)
			)
			(layer "F.SilkS")
		)
		(fp_line
			(start -0.7874 -0.4064)
			(end 0.7874 -0.4064)
			(stroke
				(width 0.1524)
				(type default)
			)
			(layer "F.SilkS")
		)
		(fp_line
			(start 0.67945 0.3048)
			(end 0.120396 0.3048)
			(stroke
				(width 0.1)
				(type default)
			)
			(layer "F.Fab")
		)
		(fp_line
			(start 0.67945 -0.3048)
			(end 0.67945 0.3048)
			(stroke
				(width 0.1)
				(type default)
			)
			(layer "F.Fab")
		)
		(fp_line
			(start 0.12065 -0.2794)
			(end 0.12065 -0.3048)
			(stroke
				(width 0.1)
				(type default)
			)
			(layer "F.Fab")
		)
		(fp_line
			(start 0.12065 -0.3048)
			(end 0.67945 -0.3048)
			(stroke
				(width 0.1)
				(type default)
			)
			(layer "F.Fab")
		)
		(fp_line
			(start 0.120396 0.3048)
			(end 0.120396 0.2794)
			(stroke
				(width 0.1)
				(type default)
			)
			(layer "F.Fab")
		)
		(fp_line
			(start 0.120396 0.2794)
			(end -0.12065 0.2794)
			(stroke
				(width 0.1)
				(type default)
			)
			(layer "F.Fab")
		)
		(fp_line
			(start -0.12065 0.3048)
			(end -0.67945 0.3048)
			(stroke
				(width 0.1)
				(type default)
			)
			(layer "F.Fab")
		)
		(fp_line
			(start -0.12065 0.2794)
			(end -0.12065 0.3048)
			(stroke
				(width 0.1)
				(type default)
			)
			(layer "F.Fab")
		)
		(fp_line
			(start -0.12065 -0.2794)
			(end 0.12065 -0.2794)
			(stroke
				(width 0.1)
				(type default)
			)
			(layer "F.Fab")
		)
		(fp_line
			(start -0.12065 -0.305054)
			(end -0.12065 -0.2794)
			(stroke
				(width 0.1)
				(type default)
			)
			(layer "F.Fab")
		)
		(fp_line
			(start -0.67945 0.3048)
			(end -0.67945 -0.305054)
			(stroke
				(width 0.1)
				(type default)
			)
			(layer "F.Fab")
		)
		(fp_line
			(start -0.67945 -0.305054)
			(end -0.12065 -0.305054)
			(stroke
				(width 0.1)
				(type default)
			)
			(layer "F.Fab")
		)
		(pad "1" smd circle
			(at -0.40005 0 180)
			(size 0 0)
			(layers "F.Cu" "F.Mask" "F.Paste")
			(net "SMB_IOEXP_3V3AUX_SDA_R")
		)
		(pad "2" smd circle
			(at 0.40005 0 180)
			(size 0 0)
			(layers "F.Cu" "F.Mask" "F.Paste")
			(net "SMB_IOEXP_3V3AUX_SDA")
		)
	)
	(footprint ""
		(layer "F.Cu")
		(at 143.3322 -104.116378 -90)
		(property "Reference" "R346"
			(at 0 0 270)
			(layer "F.SilkS")
			(hide yes)
			(effects
				(font
					(size 1.27 1.27)
				)
			)
		)
		(property "Value" ""
			(at 0 0 270)
			(layer "F.Fab")
			(effects
				(font
					(size 1.27 1.27)
				)
			)
		)
		(duplicate_pad_numbers_are_jumpers no)
		(fp_line
			(start -0.7874 0.4064)
			(end -0.7874 -0.4064)
			(stroke
				(width 0.1524)
				(type default)
			)
			(layer "F.SilkS")
		)
		(fp_line
			(start 0.7874 0.4064)
			(end -0.7874 0.4064)
			(stroke
				(width 0.1524)
				(type default)
			)
			(layer "F.SilkS")
		)
		(fp_line
			(start -0.7874 -0.4064)
			(end 0.7874 -0.4064)
			(stroke
				(width 0.1524)
				(type default)
			)
			(layer "F.SilkS")
		)
		(fp_line
			(start 0.7874 -0.4064)
			(end 0.7874 0.4064)
			(stroke
				(width 0.1524)
				(type default)
			)
			(layer "F.SilkS")
		)
		(fp_line
			(start -0.67945 0.3048)
			(end -0.67945 -0.305054)
			(stroke
				(width 0.1)
				(type default)
			)
			(layer "F.Fab")
		)
		(fp_line
			(start -0.12065 0.3048)
			(end -0.67945 0.3048)
			(stroke
				(width 0.1)
				(type default)
			)
			(layer "F.Fab")
		)
		(fp_line
			(start 0.120396 0.3048)
			(end 0.120396 0.2794)
			(stroke
				(width 0.1)
				(type default)
			)
			(layer "F.Fab")
		)
		(fp_line
			(start 0.67945 0.3048)
			(end 0.120396 0.3048)
			(stroke
				(width 0.1)
				(type default)
			)
			(layer "F.Fab")
		)
		(fp_line
			(start -0.12065 0.2794)
			(end -0.12065 0.3048)
			(stroke
				(width 0.1)
				(type default)
			)
			(layer "F.Fab")
		)
		(fp_line
			(start 0.120396 0.2794)
			(end -0.12065 0.2794)
			(stroke
				(width 0.1)
				(type default)
			)
			(layer "F.Fab")
		)
		(fp_line
			(start -0.12065 -0.2794)
			(end 0.12065 -0.2794)
			(stroke
				(width 0.1)
				(type default)
			)
			(layer "F.Fab")
		)
		(fp_line
			(start 0.12065 -0.2794)
			(end 0.12065 -0.3048)
			(stroke
				(width 0.1)
				(type default)
			)
			(layer "F.Fab")
		)
		(fp_line
			(start 0.12065 -0.3048)
			(end 0.67945 -0.3048)
			(stroke
				(width 0.1)
				(type default)
			)
			(layer "F.Fab")
		)
		(fp_line
			(start 0.67945 -0.3048)
			(end 0.67945 0.3048)
			(stroke
				(width 0.1)
				(type default)
			)
			(layer "F.Fab")
		)
		(fp_line
			(start -0.67945 -0.305054)
			(end -0.12065 -0.305054)
			(stroke
				(width 0.1)
				(type default)
			)
			(layer "F.Fab")
		)
		(fp_line
			(start -0.12065 -0.305054)
			(end -0.12065 -0.2794)
			(stroke
				(width 0.1)
				(type default)
			)
			(layer "F.Fab")
		)
		(pad "1" smd circle
			(at -0.40005 0 270)
			(size 0 0)
			(layers "F.Cu" "F.Mask" "F.Paste")
			(net "H_CPU_ERR2_LVC1_R_N")
		)
		(pad "2" smd circle
			(at 0.40005 0 270)
			(size 0 0)
			(layers "F.Cu" "F.Mask" "F.Paste")
			(net "H_CPU_ERR2_LVC1_N")
		)
	)
	(footprint ""
		(layer "F.Cu")
		(at 80.981296 -70.78599)
		(property "Reference" "D65"
			(at -41.742106 50.178462 90)
			(unlocked yes)
			(layer "F.SilkS")
			(effects
				(font
					(size 0.635 0.4064)
					(thickness 0.1524)
				)
				(justify left)
			)
		)
		(property "Value" ""
			(at 0 0 0)
			(layer "F.Fab")
			(effects
				(font
					(size 1.27 1.27)
				)
			)
		)
		(duplicate_pad_numbers_are_jumpers no)
		(fp_line
			(start -0.90678 0.4826)
			(end -0.90678 -0.4699)
			(stroke
				(width 0.1524)
				(type default)
			)
			(layer "F.SilkS")
		)
		(fp_line
			(start -0.89408 -0.4826)
			(end 0.90678 -0.4826)
			(stroke
				(width 0.1524)
				(type default)
			)
			(layer "F.SilkS")
		)
		(fp_line
			(start -0.79248 -0.4826)
			(end 1.03378 -0.4826)
			(stroke
				(width 0.1524)
				(type default)
			)
			(layer "F.SilkS")
		)
		(fp_line
			(start -0.64008 -0.4826)
			(end 1.16078 -0.4826)
			(stroke
				(width 0.1524)
				(type default)
			)
			(layer "F.SilkS")
		)
		(fp_line
			(start 0.90678 -0.4826)
			(end 0.90678 0.4826)
			(stroke
				(width 0.1524)
				(type default)
			)
			(layer "F.SilkS")
		)
		(fp_line
			(start 0.90678 0.4826)
			(end -0.90678 0.4826)
			(stroke
				(width 0.1524)
				(type default)
			)
			(layer "F.SilkS")
		)
		(fp_line
			(start 1.03378 -0.4826)
			(end 1.03378 0.4826)
			(stroke
				(width 0.1524)
				(type default)
			)
			(layer "F.SilkS")
		)
		(fp_line
			(start 1.03378 0.4826)
			(end -0.79248 0.4826)
			(stroke
				(width 0.1524)
				(type default)
			)
			(layer "F.SilkS")
		)
		(fp_line
			(start 1.16078 -0.4826)
			(end 1.16078 0.4826)
			(stroke
				(width 0.1524)
				(type default)
			)
			(layer "F.SilkS")
		)
		(fp_line
			(start 1.16078 0.4826)
			(end -0.64008 0.4826)
			(stroke
				(width 0.1524)
				(type default)
			)
			(layer "F.SilkS")
		)
		(fp_line
			(start -0.499872 -0.249936)
			(end 0.499872 -0.249936)
			(stroke
				(width 0.1)
				(type default)
			)
			(layer "F.Fab")
		)
		(fp_line
			(start -0.499872 0.249936)
			(end -0.499872 -0.249936)
			(stroke
				(width 0.1)
				(type default)
			)
			(layer "F.Fab")
		)
		(fp_line
			(start 0.499872 -0.249936)
			(end 0.499872 0.249936)
			(stroke
				(width 0.1)
				(type default)
			)
			(layer "F.Fab")
		)
		(fp_line
			(start 0.499872 0.249936)
			(end -0.499872 0.249936)
			(stroke
				(width 0.1)
				(type default)
			)
			(layer "F.Fab")
		)
		(pad "A" smd rect
			(at -0.47498 0)
			(size 0.6096 0.7112)
			(layers "F.Cu" "F.Mask" "F.Paste")
			(net "LED_RST_PLD_CPU0_DRAM_AB_N")
		)
		(pad "C" smd rect
			(at 0.47498 0)
			(size 0.6096 0.7112)
			(layers "F.Cu" "F.Mask" "F.Paste")
			(net "LED_RST_PLD_CPU0_DRAM_AB_N_D")
		)
	)
	(footprint ""
		(layer "F.Cu")
		(at 280.786078 -424.5483 90)
		(property "Reference" "R4670"
			(at 0 0 90)
			(layer "F.SilkS")
			(hide yes)
			(effects
				(font
					(size 1.27 1.27)
				)
			)
		)
		(property "Value" ""
			(at 0 0 90)
			(layer "F.Fab")
			(effects
				(font
					(size 1.27 1.27)
				)
			)
		)
		(duplicate_pad_numbers_are_jumpers no)
		(fp_line
			(start 0.7874 -0.4064)
			(end 0.7874 0.4064)
			(stroke
				(width 0.1524)
				(type default)
			)
			(layer "F.SilkS")
		)
		(fp_line
			(start -0.7874 -0.4064)
			(end 0.7874 -0.4064)
			(stroke
				(width 0.1524)
				(type default)
			)
			(layer "F.SilkS")
		)
		(fp_line
			(start 0.7874 0.4064)
			(end -0.7874 0.4064)
			(stroke
				(width 0.1524)
				(type default)
			)
			(layer "F.SilkS")
		)
		(fp_line
			(start -0.7874 0.4064)
			(end -0.7874 -0.4064)
			(stroke
				(width 0.1524)
				(type default)
			)
			(layer "F.SilkS")
		)
		(fp_line
			(start -0.12065 -0.305054)
			(end -0.12065 -0.2794)
			(stroke
				(width 0.1)
				(type default)
			)
			(layer "F.Fab")
		)
		(fp_line
			(start -0.67945 -0.305054)
			(end -0.12065 -0.305054)
			(stroke
				(width 0.1)
				(type default)
			)
			(layer "F.Fab")
		)
		(fp_line
			(start 0.67945 -0.3048)
			(end 0.67945 0.3048)
			(stroke
				(width 0.1)
				(type default)
			)
			(layer "F.Fab")
		)
		(fp_line
			(start 0.12065 -0.3048)
			(end 0.67945 -0.3048)
			(stroke
				(width 0.1)
				(type default)
			)
			(layer "F.Fab")
		)
		(fp_line
			(start 0.12065 -0.2794)
			(end 0.12065 -0.3048)
			(stroke
				(width 0.1)
				(type default)
			)
			(layer "F.Fab")
		)
		(fp_line
			(start -0.12065 -0.2794)
			(end 0.12065 -0.2794)
			(stroke
				(width 0.1)
				(type default)
			)
			(layer "F.Fab")
		)
		(fp_line
			(start 0.120396 0.2794)
			(end -0.12065 0.2794)
			(stroke
				(width 0.1)
				(type default)
			)
			(layer "F.Fab")
		)
		(fp_line
			(start -0.12065 0.2794)
			(end -0.12065 0.3048)
			(stroke
				(width 0.1)
				(type default)
			)
			(layer "F.Fab")
		)
		(fp_line
			(start 0.67945 0.3048)
			(end 0.120396 0.3048)
			(stroke
				(width 0.1)
				(type default)
			)
			(layer "F.Fab")
		)
		(fp_line
			(start 0.120396 0.3048)
			(end 0.120396 0.2794)
			(stroke
				(width 0.1)
				(type default)
			)
			(layer "F.Fab")
		)
		(fp_line
			(start -0.12065 0.3048)
			(end -0.67945 0.3048)
			(stroke
				(width 0.1)
				(type default)
			)
			(layer "F.Fab")
		)
		(fp_line
			(start -0.67945 0.3048)
			(end -0.67945 -0.305054)
			(stroke
				(width 0.1)
				(type default)
			)
			(layer "F.Fab")
		)
		(pad "1" smd circle
			(at -0.40005 0 90)
			(size 0 0)
			(layers "F.Cu" "F.Mask" "F.Paste")
			(net "A_HSC_HIGH")
		)
		(pad "2" smd circle
			(at 0.40005 0 90)
			(size 0 0)
			(layers "F.Cu" "F.Mask" "F.Paste")
			(net "GND")
		)
	)
	(footprint ""
		(layer "F.Cu")
		(at 84.44611 -59.242706 90)
		(property "Reference" "PR3824"
			(at 0 0 90)
			(layer "F.SilkS")
			(hide yes)
			(effects
				(font
					(size 1.27 1.27)
				)
			)
		)
		(property "Value" ""
			(at 0 0 90)
			(layer "F.Fab")
			(effects
				(font
					(size 1.27 1.27)
				)
			)
		)
		(duplicate_pad_numbers_are_jumpers no)
		(fp_line
			(start 0.7874 -0.4064)
			(end 0.7874 0.4064)
			(stroke
				(width 0.1524)
				(type default)
			)
			(layer "F.SilkS")
		)
		(fp_line
			(start -0.7874 -0.4064)
			(end 0.7874 -0.4064)
			(stroke
				(width 0.1524)
				(type default)
			)
			(layer "F.SilkS")
		)
		(fp_line
			(start 0.7874 0.4064)
			(end -0.7874 0.4064)
			(stroke
				(width 0.1524)
				(type default)
			)
			(layer "F.SilkS")
		)
		(fp_line
			(start -0.7874 0.4064)
			(end -0.7874 -0.4064)
			(stroke
				(width 0.1524)
				(type default)
			)
			(layer "F.SilkS")
		)
		(fp_line
			(start -0.12065 -0.305054)
			(end -0.12065 -0.2794)
			(stroke
				(width 0.1)
				(type default)
			)
			(layer "F.Fab")
		)
		(fp_line
			(start -0.67945 -0.305054)
			(end -0.12065 -0.305054)
			(stroke
				(width 0.1)
				(type default)
			)
			(layer "F.Fab")
		)
		(fp_line
			(start 0.67945 -0.3048)
			(end 0.67945 0.3048)
			(stroke
				(width 0.1)
				(type default)
			)
			(layer "F.Fab")
		)
		(fp_line
			(start 0.12065 -0.3048)
			(end 0.67945 -0.3048)
			(stroke
				(width 0.1)
				(type default)
			)
			(layer "F.Fab")
		)
		(fp_line
			(start 0.12065 -0.2794)
			(end 0.12065 -0.3048)
			(stroke
				(width 0.1)
				(type default)
			)
			(layer "F.Fab")
		)
		(fp_line
			(start -0.12065 -0.2794)
			(end 0.12065 -0.2794)
			(stroke
				(width 0.1)
				(type default)
			)
			(layer "F.Fab")
		)
		(fp_line
			(start 0.120396 0.2794)
			(end -0.12065 0.2794)
			(stroke
				(width 0.1)
				(type default)
			)
			(layer "F.Fab")
		)
		(fp_line
			(start -0.12065 0.2794)
			(end -0.12065 0.3048)
			(stroke
				(width 0.1)
				(type default)
			)
			(layer "F.Fab")
		)
		(fp_line
			(start 0.67945 0.3048)
			(end 0.120396 0.3048)
			(stroke
				(width 0.1)
				(type default)
			)
			(layer "F.Fab")
		)
		(fp_line
			(start 0.120396 0.3048)
			(end 0.120396 0.2794)
			(stroke
				(width 0.1)
				(type default)
			)
			(layer "F.Fab")
		)
		(fp_line
			(start -0.12065 0.3048)
			(end -0.67945 0.3048)
			(stroke
				(width 0.1)
				(type default)
			)
			(layer "F.Fab")
		)
		(fp_line
			(start -0.67945 0.3048)
			(end -0.67945 -0.305054)
			(stroke
				(width 0.1)
				(type default)
			)
			(layer "F.Fab")
		)
		(pad "1" smd circle
			(at -0.40005 0 90)
			(size 0 0)
			(layers "F.Cu" "F.Mask" "F.Paste")
			(net "P3V3_OCP_SENSE_2")
		)
		(pad "2" smd circle
			(at 0.40005 0 90)
			(size 0 0)
			(layers "F.Cu" "F.Mask" "F.Paste")
			(net "GND")
		)
	)
	(footprint ""
		(layer "F.Cu")
		(at 357.548942 -390.43737 180)
		(property "Reference" "R4163"
			(at 0 0 180)
			(layer "F.SilkS")
			(hide yes)
			(effects
				(font
					(size 1.27 1.27)
				)
			)
		)
		(property "Value" ""
			(at 0 0 180)
			(layer "F.Fab")
			(effects
				(font
					(size 1.27 1.27)
				)
			)
		)
		(duplicate_pad_numbers_are_jumpers no)
		(fp_line
			(start 0.7874 0.4064)
			(end -0.7874 0.4064)
			(stroke
				(width 0.1524)
				(type default)
			)
			(layer "F.SilkS")
		)
		(fp_line
			(start 0.7874 -0.4064)
			(end 0.7874 0.4064)
			(stroke
				(width 0.1524)
				(type default)
			)
			(layer "F.SilkS")
		)
		(fp_line
			(start -0.7874 0.4064)
			(end -0.7874 -0.4064)
			(stroke
				(width 0.1524)
				(type default)
			)
			(layer "F.SilkS")
		)
		(fp_line
			(start -0.7874 -0.4064)
			(end 0.7874 -0.4064)
			(stroke
				(width 0.1524)
				(type default)
			)
			(layer "F.SilkS")
		)
		(fp_line
			(start 0.67945 0.3048)
			(end 0.120396 0.3048)
			(stroke
				(width 0.1)
				(type default)
			)
			(layer "F.Fab")
		)
		(fp_line
			(start 0.67945 -0.3048)
			(end 0.67945 0.3048)
			(stroke
				(width 0.1)
				(type default)
			)
			(layer "F.Fab")
		)
		(fp_line
			(start 0.12065 -0.2794)
			(end 0.12065 -0.3048)
			(stroke
				(width 0.1)
				(type default)
			)
			(layer "F.Fab")
		)
		(fp_line
			(start 0.12065 -0.3048)
			(end 0.67945 -0.3048)
			(stroke
				(width 0.1)
				(type default)
			)
			(layer "F.Fab")
		)
		(fp_line
			(start 0.120396 0.3048)
			(end 0.120396 0.2794)
			(stroke
				(width 0.1)
				(type default)
			)
			(layer "F.Fab")
		)
		(fp_line
			(start 0.120396 0.2794)
			(end -0.12065 0.2794)
			(stroke
				(width 0.1)
				(type default)
			)
			(layer "F.Fab")
		)
		(fp_line
			(start -0.12065 0.3048)
			(end -0.67945 0.3048)
			(stroke
				(width 0.1)
				(type default)
			)
			(layer "F.Fab")
		)
		(fp_line
			(start -0.12065 0.2794)
			(end -0.12065 0.3048)
			(stroke
				(width 0.1)
				(type default)
			)
			(layer "F.Fab")
		)
		(fp_line
			(start -0.12065 -0.2794)
			(end 0.12065 -0.2794)
			(stroke
				(width 0.1)
				(type default)
			)
			(layer "F.Fab")
		)
		(fp_line
			(start -0.12065 -0.305054)
			(end -0.12065 -0.2794)
			(stroke
				(width 0.1)
				(type default)
			)
			(layer "F.Fab")
		)
		(fp_line
			(start -0.67945 0.3048)
			(end -0.67945 -0.305054)
			(stroke
				(width 0.1)
				(type default)
			)
			(layer "F.Fab")
		)
		(fp_line
			(start -0.67945 -0.305054)
			(end -0.12065 -0.305054)
			(stroke
				(width 0.1)
				(type default)
			)
			(layer "F.Fab")
		)
		(pad "1" smd circle
			(at -0.40005 0 180)
			(size 0 0)
			(layers "F.Cu" "F.Mask" "F.Paste")
			(net "GPU_3V3IO_RSVD3")
		)
		(pad "2" smd circle
			(at 0.40005 0 180)
			(size 0 0)
			(layers "F.Cu" "F.Mask" "F.Paste")
			(net "GND")
		)
	)
	(footprint ""
		(layer "F.Cu")
		(at 125.205744 -66.867278 90)
		(property "Reference" "R803"
			(at 0 0 90)
			(layer "F.SilkS")
			(hide yes)
			(effects
				(font
					(size 1.27 1.27)
				)
			)
		)
		(property "Value" ""
			(at 0 0 90)
			(layer "F.Fab")
			(effects
				(font
					(size 1.27 1.27)
				)
			)
		)
		(duplicate_pad_numbers_are_jumpers no)
		(fp_line
			(start 0.7874 -0.4064)
			(end 0.7874 0.4064)
			(stroke
				(width 0.1524)
				(type default)
			)
			(layer "F.SilkS")
		)
		(fp_line
			(start -0.7874 -0.4064)
			(end 0.7874 -0.4064)
			(stroke
				(width 0.1524)
				(type default)
			)
			(layer "F.SilkS")
		)
		(fp_line
			(start 0.7874 0.4064)
			(end -0.7874 0.4064)
			(stroke
				(width 0.1524)
				(type default)
			)
			(layer "F.SilkS")
		)
		(fp_line
			(start -0.7874 0.4064)
			(end -0.7874 -0.4064)
			(stroke
				(width 0.1524)
				(type default)
			)
			(layer "F.SilkS")
		)
		(fp_line
			(start -0.12065 -0.305054)
			(end -0.12065 -0.2794)
			(stroke
				(width 0.1)
				(type default)
			)
			(layer "F.Fab")
		)
		(fp_line
			(start -0.67945 -0.305054)
			(end -0.12065 -0.305054)
			(stroke
				(width 0.1)
				(type default)
			)
			(layer "F.Fab")
		)
		(fp_line
			(start 0.67945 -0.3048)
			(end 0.67945 0.3048)
			(stroke
				(width 0.1)
				(type default)
			)
			(layer "F.Fab")
		)
		(fp_line
			(start 0.12065 -0.3048)
			(end 0.67945 -0.3048)
			(stroke
				(width 0.1)
				(type default)
			)
			(layer "F.Fab")
		)
		(fp_line
			(start 0.12065 -0.2794)
			(end 0.12065 -0.3048)
			(stroke
				(width 0.1)
				(type default)
			)
			(layer "F.Fab")
		)
		(fp_line
			(start -0.12065 -0.2794)
			(end 0.12065 -0.2794)
			(stroke
				(width 0.1)
				(type default)
			)
			(layer "F.Fab")
		)
		(fp_line
			(start 0.120396 0.2794)
			(end -0.12065 0.2794)
			(stroke
				(width 0.1)
				(type default)
			)
			(layer "F.Fab")
		)
		(fp_line
			(start -0.12065 0.2794)
			(end -0.12065 0.3048)
			(stroke
				(width 0.1)
				(type default)
			)
			(layer "F.Fab")
		)
		(fp_line
			(start 0.67945 0.3048)
			(end 0.120396 0.3048)
			(stroke
				(width 0.1)
				(type default)
			)
			(layer "F.Fab")
		)
		(fp_line
			(start 0.120396 0.3048)
			(end 0.120396 0.2794)
			(stroke
				(width 0.1)
				(type default)
			)
			(layer "F.Fab")
		)
		(fp_line
			(start -0.12065 0.3048)
			(end -0.67945 0.3048)
			(stroke
				(width 0.1)
				(type default)
			)
			(layer "F.Fab")
		)
		(fp_line
			(start -0.67945 0.3048)
			(end -0.67945 -0.305054)
			(stroke
				(width 0.1)
				(type default)
			)
			(layer "F.Fab")
		)
		(pad "1" smd circle
			(at -0.40005 0 90)
			(size 0 0)
			(layers "F.Cu" "F.Mask" "F.Paste")
			(net "JTAG_PLD_TDI_R")
		)
		(pad "2" smd circle
			(at 0.40005 0 90)
			(size 0 0)
			(layers "F.Cu" "F.Mask" "F.Paste")
			(net "JTAG_BMC_PLD_TDI")
		)
	)
	(footprint ""
		(layer "F.Cu")
		(at 299.02023 -53.384196 180)
		(property "Reference" "R2977"
			(at 0 0 180)
			(layer "F.SilkS")
			(hide yes)
			(effects
				(font
					(size 1.27 1.27)
				)
			)
		)
		(property "Value" ""
			(at 0 0 180)
			(layer "F.Fab")
			(effects
				(font
					(size 1.27 1.27)
				)
			)
		)
		(duplicate_pad_numbers_are_jumpers no)
		(fp_line
			(start 0.7874 0.4064)
			(end -0.7874 0.4064)
			(stroke
				(width 0.1524)
				(type default)
			)
			(layer "F.SilkS")
		)
		(fp_line
			(start 0.7874 -0.4064)
			(end 0.7874 0.4064)
			(stroke
				(width 0.1524)
				(type default)
			)
			(layer "F.SilkS")
		)
		(fp_line
			(start -0.7874 0.4064)
			(end -0.7874 -0.4064)
			(stroke
				(width 0.1524)
				(type default)
			)
			(layer "F.SilkS")
		)
		(fp_line
			(start -0.7874 -0.4064)
			(end 0.7874 -0.4064)
			(stroke
				(width 0.1524)
				(type default)
			)
			(layer "F.SilkS")
		)
		(fp_line
			(start 0.67945 0.3048)
			(end 0.120396 0.3048)
			(stroke
				(width 0.1)
				(type default)
			)
			(layer "F.Fab")
		)
		(fp_line
			(start 0.67945 -0.3048)
			(end 0.67945 0.3048)
			(stroke
				(width 0.1)
				(type default)
			)
			(layer "F.Fab")
		)
		(fp_line
			(start 0.12065 -0.2794)
			(end 0.12065 -0.3048)
			(stroke
				(width 0.1)
				(type default)
			)
			(layer "F.Fab")
		)
		(fp_line
			(start 0.12065 -0.3048)
			(end 0.67945 -0.3048)
			(stroke
				(width 0.1)
				(type default)
			)
			(layer "F.Fab")
		)
		(fp_line
			(start 0.120396 0.3048)
			(end 0.120396 0.2794)
			(stroke
				(width 0.1)
				(type default)
			)
			(layer "F.Fab")
		)
		(fp_line
			(start 0.120396 0.2794)
			(end -0.12065 0.2794)
			(stroke
				(width 0.1)
				(type default)
			)
			(layer "F.Fab")
		)
		(fp_line
			(start -0.12065 0.3048)
			(end -0.67945 0.3048)
			(stroke
				(width 0.1)
				(type default)
			)
			(layer "F.Fab")
		)
		(fp_line
			(start -0.12065 0.2794)
			(end -0.12065 0.3048)
			(stroke
				(width 0.1)
				(type default)
			)
			(layer "F.Fab")
		)
		(fp_line
			(start -0.12065 -0.2794)
			(end 0.12065 -0.2794)
			(stroke
				(width 0.1)
				(type default)
			)
			(layer "F.Fab")
		)
		(fp_line
			(start -0.12065 -0.305054)
			(end -0.12065 -0.2794)
			(stroke
				(width 0.1)
				(type default)
			)
			(layer "F.Fab")
		)
		(fp_line
			(start -0.67945 0.3048)
			(end -0.67945 -0.305054)
			(stroke
				(width 0.1)
				(type default)
			)
			(layer "F.Fab")
		)
		(fp_line
			(start -0.67945 -0.305054)
			(end -0.12065 -0.305054)
			(stroke
				(width 0.1)
				(type default)
			)
			(layer "F.Fab")
		)
		(pad "1" smd circle
			(at -0.40005 0 180)
			(size 0 0)
			(layers "F.Cu" "F.Mask" "F.Paste")
			(net "FM_BOARD_SKU_ID3")
		)
		(pad "2" smd circle
			(at 0.40005 0 180)
			(size 0 0)
			(layers "F.Cu" "F.Mask" "F.Paste")
			(net "GND")
		)
	)
	(footprint ""
		(layer "F.Cu")
		(at 233.869738 -119.183658 -90)
		(property "Reference" "R3194"
			(at 0 0 270)
			(layer "F.SilkS")
			(hide yes)
			(effects
				(font
					(size 1.27 1.27)
				)
			)
		)
		(property "Value" ""
			(at 0 0 270)
			(layer "F.Fab")
			(effects
				(font
					(size 1.27 1.27)
				)
			)
		)
		(duplicate_pad_numbers_are_jumpers no)
		(fp_line
			(start -0.7874 0.4064)
			(end -0.7874 -0.109982)
			(stroke
				(width 0.1524)
				(type default)
			)
			(layer "F.SilkS")
		)
		(fp_line
			(start 0.7874 0.4064)
			(end -0.7874 0.4064)
			(stroke
				(width 0.1524)
				(type default)
			)
			(layer "F.SilkS")
		)
		(fp_line
			(start 0.7874 -0.089662)
			(end 0.7874 0.4064)
			(stroke
				(width 0.1524)
				(type default)
			)
			(layer "F.SilkS")
		)
		(fp_line
			(start -0.363982 -0.4064)
			(end 0.410718 -0.4064)
			(stroke
				(width 0.1524)
				(type default)
			)
			(layer "F.SilkS")
		)
		(fp_line
			(start -0.67945 0.3048)
			(end -0.67945 -0.305054)
			(stroke
				(width 0.1)
				(type default)
			)
			(layer "F.Fab")
		)
		(fp_line
			(start -0.12065 0.3048)
			(end -0.67945 0.3048)
			(stroke
				(width 0.1)
				(type default)
			)
			(layer "F.Fab")
		)
		(fp_line
			(start 0.120396 0.3048)
			(end 0.120396 0.2794)
			(stroke
				(width 0.1)
				(type default)
			)
			(layer "F.Fab")
		)
		(fp_line
			(start 0.67945 0.3048)
			(end 0.120396 0.3048)
			(stroke
				(width 0.1)
				(type default)
			)
			(layer "F.Fab")
		)
		(fp_line
			(start -0.12065 0.2794)
			(end -0.12065 0.3048)
			(stroke
				(width 0.1)
				(type default)
			)
			(layer "F.Fab")
		)
		(fp_line
			(start 0.120396 0.2794)
			(end -0.12065 0.2794)
			(stroke
				(width 0.1)
				(type default)
			)
			(layer "F.Fab")
		)
		(fp_line
			(start -0.12065 -0.2794)
			(end 0.12065 -0.2794)
			(stroke
				(width 0.1)
				(type default)
			)
			(layer "F.Fab")
		)
		(fp_line
			(start 0.12065 -0.2794)
			(end 0.12065 -0.3048)
			(stroke
				(width 0.1)
				(type default)
			)
			(layer "F.Fab")
		)
		(fp_line
			(start 0.12065 -0.3048)
			(end 0.67945 -0.3048)
			(stroke
				(width 0.1)
				(type default)
			)
			(layer "F.Fab")
		)
		(fp_line
			(start 0.67945 -0.3048)
			(end 0.67945 0.3048)
			(stroke
				(width 0.1)
				(type default)
			)
			(layer "F.Fab")
		)
		(fp_line
			(start -0.67945 -0.305054)
			(end -0.12065 -0.305054)
			(stroke
				(width 0.1)
				(type default)
			)
			(layer "F.Fab")
		)
		(fp_line
			(start -0.12065 -0.305054)
			(end -0.12065 -0.2794)
			(stroke
				(width 0.1)
				(type default)
			)
			(layer "F.Fab")
		)
		(pad "1" smd circle
			(at -0.40005 0 270)
			(size 0 0)
			(layers "F.Cu" "F.Mask" "F.Paste")
			(net "CLK_100M_OCP_V3_2_A_R_DP")
		)
		(pad "2" smd circle
			(at 0.40005 0 270)
			(size 0 0)
			(layers "F.Cu" "F.Mask" "F.Paste")
			(net "CLK_100M_OCP_V3_2_A_DP")
		)
	)
	(footprint ""
		(layer "F.Cu")
		(at 194.020186 -429.41113 -90)
		(property "Reference" "R2944"
			(at 0 0 270)
			(layer "F.SilkS")
			(hide yes)
			(effects
				(font
					(size 1.27 1.27)
				)
			)
		)
		(property "Value" ""
			(at 0 0 270)
			(layer "F.Fab")
			(effects
				(font
					(size 1.27 1.27)
				)
			)
		)
		(duplicate_pad_numbers_are_jumpers no)
		(fp_line
			(start -0.7874 0.4064)
			(end -0.7874 -0.4064)
			(stroke
				(width 0.1524)
				(type default)
			)
			(layer "F.SilkS")
		)
		(fp_line
			(start 0.7874 0.4064)
			(end -0.7874 0.4064)
			(stroke
				(width 0.1524)
				(type default)
			)
			(layer "F.SilkS")
		)
		(fp_line
			(start -0.7874 -0.4064)
			(end 0.7874 -0.4064)
			(stroke
				(width 0.1524)
				(type default)
			)
			(layer "F.SilkS")
		)
		(fp_line
			(start 0.7874 -0.4064)
			(end 0.7874 0.4064)
			(stroke
				(width 0.1524)
				(type default)
			)
			(layer "F.SilkS")
		)
		(fp_line
			(start -0.67945 0.3048)
			(end -0.67945 -0.305054)
			(stroke
				(width 0.1)
				(type default)
			)
			(layer "F.Fab")
		)
		(fp_line
			(start -0.12065 0.3048)
			(end -0.67945 0.3048)
			(stroke
				(width 0.1)
				(type default)
			)
			(layer "F.Fab")
		)
		(fp_line
			(start 0.120396 0.3048)
			(end 0.120396 0.2794)
			(stroke
				(width 0.1)
				(type default)
			)
			(layer "F.Fab")
		)
		(fp_line
			(start 0.67945 0.3048)
			(end 0.120396 0.3048)
			(stroke
				(width 0.1)
				(type default)
			)
			(layer "F.Fab")
		)
		(fp_line
			(start -0.12065 0.2794)
			(end -0.12065 0.3048)
			(stroke
				(width 0.1)
				(type default)
			)
			(layer "F.Fab")
		)
		(fp_line
			(start 0.120396 0.2794)
			(end -0.12065 0.2794)
			(stroke
				(width 0.1)
				(type default)
			)
			(layer "F.Fab")
		)
		(fp_line
			(start -0.12065 -0.2794)
			(end 0.12065 -0.2794)
			(stroke
				(width 0.1)
				(type default)
			)
			(layer "F.Fab")
		)
		(fp_line
			(start 0.12065 -0.2794)
			(end 0.12065 -0.3048)
			(stroke
				(width 0.1)
				(type default)
			)
			(layer "F.Fab")
		)
		(fp_line
			(start 0.12065 -0.3048)
			(end 0.67945 -0.3048)
			(stroke
				(width 0.1)
				(type default)
			)
			(layer "F.Fab")
		)
		(fp_line
			(start 0.67945 -0.3048)
			(end 0.67945 0.3048)
			(stroke
				(width 0.1)
				(type default)
			)
			(layer "F.Fab")
		)
		(fp_line
			(start -0.67945 -0.305054)
			(end -0.12065 -0.305054)
			(stroke
				(width 0.1)
				(type default)
			)
			(layer "F.Fab")
		)
		(fp_line
			(start -0.12065 -0.305054)
			(end -0.12065 -0.2794)
			(stroke
				(width 0.1)
				(type default)
			)
			(layer "F.Fab")
		)
		(pad "1" smd circle
			(at -0.40005 0 270)
			(size 0 0)
			(layers "F.Cu" "F.Mask" "F.Paste")
			(net "FM_GPU_HSC_EN_BUF_R")
		)
		(pad "2" smd circle
			(at 0.40005 0 270)
			(size 0 0)
			(layers "F.Cu" "F.Mask" "F.Paste")
			(net "FM_GPU_HSC_EN_BUF")
		)
	)
	(footprint ""
		(layer "F.Cu")
		(at 257.85953 -53.447442)
		(property "Reference" "PC2202"
			(at 0 0 0)
			(layer "F.SilkS")
			(hide yes)
			(effects
				(font
					(size 1.27 1.27)
				)
			)
		)
		(property "Value" ""
			(at 0 0 0)
			(layer "F.Fab")
			(effects
				(font
					(size 1.27 1.27)
				)
			)
		)
		(duplicate_pad_numbers_are_jumpers no)
		(fp_line
			(start -0.7874 -0.4064)
			(end 0.7874 -0.4064)
			(stroke
				(width 0.1524)
				(type default)
			)
			(layer "F.SilkS")
		)
		(fp_line
			(start -0.7874 0.4064)
			(end -0.7874 -0.4064)
			(stroke
				(width 0.1524)
				(type default)
			)
			(layer "F.SilkS")
		)
		(fp_line
			(start 0.7874 -0.4064)
			(end 0.7874 0.4064)
			(stroke
				(width 0.1524)
				(type default)
			)
			(layer "F.SilkS")
		)
		(fp_line
			(start 0.7874 0.4064)
			(end -0.7874 0.4064)
			(stroke
				(width 0.1524)
				(type default)
			)
			(layer "F.SilkS")
		)
		(fp_line
			(start -0.67945 -0.305054)
			(end -0.12065 -0.305054)
			(stroke
				(width 0.1)
				(type default)
			)
			(layer "F.Fab")
		)
		(fp_line
			(start -0.67945 0.3048)
			(end -0.67945 -0.305054)
			(stroke
				(width 0.1)
				(type default)
			)
			(layer "F.Fab")
		)
		(fp_line
			(start -0.12065 -0.305054)
			(end -0.12065 -0.2794)
			(stroke
				(width 0.1)
				(type default)
			)
			(layer "F.Fab")
		)
		(fp_line
			(start -0.12065 -0.2794)
			(end 0.12065 -0.2794)
			(stroke
				(width 0.1)
				(type default)
			)
			(layer "F.Fab")
		)
		(fp_line
			(start -0.12065 0.2794)
			(end -0.12065 0.3048)
			(stroke
				(width 0.1)
				(type default)
			)
			(layer "F.Fab")
		)
		(fp_line
			(start -0.12065 0.3048)
			(end -0.67945 0.3048)
			(stroke
				(width 0.1)
				(type default)
			)
			(layer "F.Fab")
		)
		(fp_line
			(start 0.120396 0.2794)
			(end -0.12065 0.2794)
			(stroke
				(width 0.1)
				(type default)
			)
			(layer "F.Fab")
		)
		(fp_line
			(start 0.120396 0.3048)
			(end 0.120396 0.2794)
			(stroke
				(width 0.1)
				(type default)
			)
			(layer "F.Fab")
		)
		(fp_line
			(start 0.12065 -0.3048)
			(end 0.67945 -0.3048)
			(stroke
				(width 0.1)
				(type default)
			)
			(layer "F.Fab")
		)
		(fp_line
			(start 0.12065 -0.2794)
			(end 0.12065 -0.3048)
			(stroke
				(width 0.1)
				(type default)
			)
			(layer "F.Fab")
		)
		(fp_line
			(start 0.67945 -0.3048)
			(end 0.67945 0.3048)
			(stroke
				(width 0.1)
				(type default)
			)
			(layer "F.Fab")
		)
		(fp_line
			(start 0.67945 0.3048)
			(end 0.120396 0.3048)
			(stroke
				(width 0.1)
				(type default)
			)
			(layer "F.Fab")
		)
		(pad "1" smd circle
			(at -0.40005 0)
			(size 0 0)
			(layers "F.Cu" "F.Mask" "F.Paste")
			(net "P12V_E1S_IMON_0")
		)
		(pad "2" smd circle
			(at 0.40005 0)
			(size 0 0)
			(layers "F.Cu" "F.Mask" "F.Paste")
			(net "GND")
		)
	)
	(footprint ""
		(layer "F.Cu")
		(at 152.96388 -128.742948 180)
		(property "Reference" "R3205"
			(at 0 0 180)
			(layer "F.SilkS")
			(hide yes)
			(effects
				(font
					(size 1.27 1.27)
				)
			)
		)
		(property "Value" ""
			(at 0 0 180)
			(layer "F.Fab")
			(effects
				(font
					(size 1.27 1.27)
				)
			)
		)
		(duplicate_pad_numbers_are_jumpers no)
		(fp_line
			(start 0.7874 0.4064)
			(end -0.7874 0.4064)
			(stroke
				(width 0.1524)
				(type default)
			)
			(layer "F.SilkS")
		)
		(fp_line
			(start 0.7874 -0.4064)
			(end 0.7874 0.4064)
			(stroke
				(width 0.1524)
				(type default)
			)
			(layer "F.SilkS")
		)
		(fp_line
			(start -0.7874 0.4064)
			(end -0.7874 -0.4064)
			(stroke
				(width 0.1524)
				(type default)
			)
			(layer "F.SilkS")
		)
		(fp_line
			(start -0.7874 -0.4064)
			(end 0.7874 -0.4064)
			(stroke
				(width 0.1524)
				(type default)
			)
			(layer "F.SilkS")
		)
		(fp_line
			(start 0.67945 0.3048)
			(end 0.120396 0.3048)
			(stroke
				(width 0.1)
				(type default)
			)
			(layer "F.Fab")
		)
		(fp_line
			(start 0.67945 -0.3048)
			(end 0.67945 0.3048)
			(stroke
				(width 0.1)
				(type default)
			)
			(layer "F.Fab")
		)
		(fp_line
			(start 0.12065 -0.2794)
			(end 0.12065 -0.3048)
			(stroke
				(width 0.1)
				(type default)
			)
			(layer "F.Fab")
		)
		(fp_line
			(start 0.12065 -0.3048)
			(end 0.67945 -0.3048)
			(stroke
				(width 0.1)
				(type default)
			)
			(layer "F.Fab")
		)
		(fp_line
			(start 0.120396 0.3048)
			(end 0.120396 0.2794)
			(stroke
				(width 0.1)
				(type default)
			)
			(layer "F.Fab")
		)
		(fp_line
			(start 0.120396 0.2794)
			(end -0.12065 0.2794)
			(stroke
				(width 0.1)
				(type default)
			)
			(layer "F.Fab")
		)
		(fp_line
			(start -0.12065 0.3048)
			(end -0.67945 0.3048)
			(stroke
				(width 0.1)
				(type default)
			)
			(layer "F.Fab")
		)
		(fp_line
			(start -0.12065 0.2794)
			(end -0.12065 0.3048)
			(stroke
				(width 0.1)
				(type default)
			)
			(layer "F.Fab")
		)
		(fp_line
			(start -0.12065 -0.2794)
			(end 0.12065 -0.2794)
			(stroke
				(width 0.1)
				(type default)
			)
			(layer "F.Fab")
		)
		(fp_line
			(start -0.12065 -0.305054)
			(end -0.12065 -0.2794)
			(stroke
				(width 0.1)
				(type default)
			)
			(layer "F.Fab")
		)
		(fp_line
			(start -0.67945 0.3048)
			(end -0.67945 -0.305054)
			(stroke
				(width 0.1)
				(type default)
			)
			(layer "F.Fab")
		)
		(fp_line
			(start -0.67945 -0.305054)
			(end -0.12065 -0.305054)
			(stroke
				(width 0.1)
				(type default)
			)
			(layer "F.Fab")
		)
		(pad "1" smd circle
			(at -0.40005 0 180)
			(size 0 0)
			(layers "F.Cu" "F.Mask" "F.Paste")
			(net "FB_BMC_ISOLATE_R2")
		)
		(pad "2" smd circle
			(at 0.40005 0 180)
			(size 0 0)
			(layers "F.Cu" "F.Mask" "F.Paste")
			(net "FB_BMC_ISOLATE1")
		)
	)
	(footprint ""
		(layer "F.Cu")
		(at 428.226474 -121.61266 180)
		(property "Reference" "PC628"
			(at 0 0 180)
			(layer "F.SilkS")
			(hide yes)
			(effects
				(font
					(size 1.27 1.27)
				)
			)
		)
		(property "Value" ""
			(at 0 0 180)
			(layer "F.Fab")
			(effects
				(font
					(size 1.27 1.27)
				)
			)
		)
		(duplicate_pad_numbers_are_jumpers no)
		(fp_line
			(start 0.7874 0.4064)
			(end -0.7874 0.4064)
			(stroke
				(width 0.1524)
				(type default)
			)
			(layer "F.SilkS")
		)
		(fp_line
			(start 0.7874 -0.4064)
			(end 0.7874 0.4064)
			(stroke
				(width 0.1524)
				(type default)
			)
			(layer "F.SilkS")
		)
		(fp_line
			(start -0.7874 0.4064)
			(end -0.7874 -0.4064)
			(stroke
				(width 0.1524)
				(type default)
			)
			(layer "F.SilkS")
		)
		(fp_line
			(start -0.7874 -0.4064)
			(end 0.7874 -0.4064)
			(stroke
				(width 0.1524)
				(type default)
			)
			(layer "F.SilkS")
		)
		(fp_line
			(start 0.67945 0.3048)
			(end 0.120396 0.3048)
			(stroke
				(width 0.1)
				(type default)
			)
			(layer "F.Fab")
		)
		(fp_line
			(start 0.67945 -0.3048)
			(end 0.67945 0.3048)
			(stroke
				(width 0.1)
				(type default)
			)
			(layer "F.Fab")
		)
		(fp_line
			(start 0.12065 -0.2794)
			(end 0.12065 -0.3048)
			(stroke
				(width 0.1)
				(type default)
			)
			(layer "F.Fab")
		)
		(fp_line
			(start 0.12065 -0.3048)
			(end 0.67945 -0.3048)
			(stroke
				(width 0.1)
				(type default)
			)
			(layer "F.Fab")
		)
		(fp_line
			(start 0.120396 0.3048)
			(end 0.120396 0.2794)
			(stroke
				(width 0.1)
				(type default)
			)
			(layer "F.Fab")
		)
		(fp_line
			(start 0.120396 0.2794)
			(end -0.12065 0.2794)
			(stroke
				(width 0.1)
				(type default)
			)
			(layer "F.Fab")
		)
		(fp_line
			(start -0.12065 0.3048)
			(end -0.67945 0.3048)
			(stroke
				(width 0.1)
				(type default)
			)
			(layer "F.Fab")
		)
		(fp_line
			(start -0.12065 0.2794)
			(end -0.12065 0.3048)
			(stroke
				(width 0.1)
				(type default)
			)
			(layer "F.Fab")
		)
		(fp_line
			(start -0.12065 -0.2794)
			(end 0.12065 -0.2794)
			(stroke
				(width 0.1)
				(type default)
			)
			(layer "F.Fab")
		)
		(fp_line
			(start -0.12065 -0.305054)
			(end -0.12065 -0.2794)
			(stroke
				(width 0.1)
				(type default)
			)
			(layer "F.Fab")
		)
		(fp_line
			(start -0.67945 0.3048)
			(end -0.67945 -0.305054)
			(stroke
				(width 0.1)
				(type default)
			)
			(layer "F.Fab")
		)
		(fp_line
			(start -0.67945 -0.305054)
			(end -0.12065 -0.305054)
			(stroke
				(width 0.1)
				(type default)
			)
			(layer "F.Fab")
		)
		(pad "1" smd circle
			(at -0.40005 0 180)
			(size 0 0)
			(layers "F.Cu" "F.Mask" "F.Paste")
			(net "PVCCD_HV_CPU0_ISENSE_N")
		)
		(pad "2" smd circle
			(at 0.40005 0 180)
			(size 0 0)
			(layers "F.Cu" "F.Mask" "F.Paste")
			(net "GND")
		)
	)
	(footprint ""
		(layer "F.Cu")
		(at 292.34638 -411.21584)
		(property "Reference" "C2458"
			(at 0 0 0)
			(layer "F.SilkS")
			(hide yes)
			(effects
				(font
					(size 1.27 1.27)
				)
			)
		)
		(property "Value" ""
			(at 0 0 0)
			(layer "F.Fab")
			(effects
				(font
					(size 1.27 1.27)
				)
			)
		)
		(duplicate_pad_numbers_are_jumpers no)
		(fp_line
			(start -0.7874 -0.4064)
			(end 0.7874 -0.4064)
			(stroke
				(width 0.1524)
				(type default)
			)
			(layer "F.SilkS")
		)
		(fp_line
			(start -0.7874 0.4064)
			(end -0.7874 -0.4064)
			(stroke
				(width 0.1524)
				(type default)
			)
			(layer "F.SilkS")
		)
		(fp_line
			(start 0.7874 -0.4064)
			(end 0.7874 0.4064)
			(stroke
				(width 0.1524)
				(type default)
			)
			(layer "F.SilkS")
		)
		(fp_line
			(start 0.7874 0.4064)
			(end -0.7874 0.4064)
			(stroke
				(width 0.1524)
				(type default)
			)
			(layer "F.SilkS")
		)
		(fp_line
			(start -0.67945 -0.305054)
			(end -0.12065 -0.305054)
			(stroke
				(width 0.1)
				(type default)
			)
			(layer "F.Fab")
		)
		(fp_line
			(start -0.67945 0.3048)
			(end -0.67945 -0.305054)
			(stroke
				(width 0.1)
				(type default)
			)
			(layer "F.Fab")
		)
		(fp_line
			(start -0.12065 -0.305054)
			(end -0.12065 -0.2794)
			(stroke
				(width 0.1)
				(type default)
			)
			(layer "F.Fab")
		)
		(fp_line
			(start -0.12065 -0.2794)
			(end 0.12065 -0.2794)
			(stroke
				(width 0.1)
				(type default)
			)
			(layer "F.Fab")
		)
		(fp_line
			(start -0.12065 0.2794)
			(end -0.12065 0.3048)
			(stroke
				(width 0.1)
				(type default)
			)
			(layer "F.Fab")
		)
		(fp_line
			(start -0.12065 0.3048)
			(end -0.67945 0.3048)
			(stroke
				(width 0.1)
				(type default)
			)
			(layer "F.Fab")
		)
		(fp_line
			(start 0.120396 0.2794)
			(end -0.12065 0.2794)
			(stroke
				(width 0.1)
				(type default)
			)
			(layer "F.Fab")
		)
		(fp_line
			(start 0.120396 0.3048)
			(end 0.120396 0.2794)
			(stroke
				(width 0.1)
				(type default)
			)
			(layer "F.Fab")
		)
		(fp_line
			(start 0.12065 -0.3048)
			(end 0.67945 -0.3048)
			(stroke
				(width 0.1)
				(type default)
			)
			(layer "F.Fab")
		)
		(fp_line
			(start 0.12065 -0.2794)
			(end 0.12065 -0.3048)
			(stroke
				(width 0.1)
				(type default)
			)
			(layer "F.Fab")
		)
		(fp_line
			(start 0.67945 -0.3048)
			(end 0.67945 0.3048)
			(stroke
				(width 0.1)
				(type default)
			)
			(layer "F.Fab")
		)
		(fp_line
			(start 0.67945 0.3048)
			(end 0.120396 0.3048)
			(stroke
				(width 0.1)
				(type default)
			)
			(layer "F.Fab")
		)
		(pad "1" smd circle
			(at -0.40005 0)
			(size 0 0)
			(layers "F.Cu" "F.Mask" "F.Paste")
			(net "P3V3_AUX")
		)
		(pad "2" smd circle
			(at 0.40005 0)
			(size 0 0)
			(layers "F.Cu" "F.Mask" "F.Paste")
			(net "GND")
		)
	)
	(footprint ""
		(layer "F.Cu")
		(at 43.60037 -363.251242)
		(property "Reference" "PL43"
			(at 0.233172 -3.211068 0)
			(unlocked yes)
			(layer "F.SilkS")
			(effects
				(font
					(size 0.7874 0.5842)
					(thickness 0.1524)
				)
				(justify left)
			)
		)
		(property "Value" ""
			(at 0 0 0)
			(layer "F.Fab")
			(effects
				(font
					(size 1.27 1.27)
				)
			)
		)
		(duplicate_pad_numbers_are_jumpers no)
		(fp_line
			(start -2.249932 -2.249932)
			(end 2.249932 -2.249932)
			(stroke
				(width 0.1524)
				(type default)
			)
			(layer "F.SilkS")
		)
		(fp_line
			(start -2.249932 -1.3843)
			(end -2.249932 -2.249932)
			(stroke
				(width 0.1524)
				(type default)
			)
			(layer "F.SilkS")
		)
		(fp_line
			(start -2.249932 2.249932)
			(end -2.249932 1.3843)
			(stroke
				(width 0.1524)
				(type default)
			)
			(layer "F.SilkS")
		)
		(fp_line
			(start 2.249932 -2.249932)
			(end 2.249932 -1.3843)
			(stroke
				(width 0.1524)
				(type default)
			)
			(layer "F.SilkS")
		)
		(fp_line
			(start 2.249932 1.3843)
			(end 2.249932 2.249932)
			(stroke
				(width 0.1524)
				(type default)
			)
			(layer "F.SilkS")
		)
		(fp_line
			(start 2.249932 2.249932)
			(end -2.249932 2.249932)
			(stroke
				(width 0.1524)
				(type default)
			)
			(layer "F.SilkS")
		)
		(fp_line
			(start -2.249932 -2.249932)
			(end 2.249932 -2.249932)
			(stroke
				(width 0.1)
				(type default)
			)
			(layer "F.Fab")
		)
		(fp_line
			(start -2.249932 2.249932)
			(end -2.249932 -2.249932)
			(stroke
				(width 0.1)
				(type default)
			)
			(layer "F.Fab")
		)
		(fp_line
			(start 2.249932 -2.249932)
			(end 2.249932 2.249932)
			(stroke
				(width 0.1)
				(type default)
			)
			(layer "F.Fab")
		)
		(fp_line
			(start 2.249932 2.249932)
			(end -2.249932 2.249932)
			(stroke
				(width 0.1)
				(type default)
			)
			(layer "F.Fab")
		)
		(pad "1" smd rect
			(at -1.82499 0)
			(size 1.0668 2.5146)
			(layers "F.Cu" "F.Mask" "F.Paste")
			(net "P12V_AUX")
		)
		(pad "2" smd rect
			(at 1.82499 0)
			(size 1.0668 2.5146)
			(layers "F.Cu" "F.Mask" "F.Paste")
			(net "SW_P12V_PVCCFA_EHV_FIVRA_CPU1_L")
		)
	)
	(footprint ""
		(layer "F.Cu")
		(at 202.59294 -132.050028)
		(property "Reference" "Q54"
			(at -1.651 -2.25933 0)
			(unlocked yes)
			(layer "F.SilkS")
			(effects
				(font
					(size 0.7874 0.5842)
					(thickness 0.1524)
				)
				(justify left)
			)
		)
		(property "Value" ""
			(at 0 0 0)
			(layer "F.Fab")
			(effects
				(font
					(size 1.27 1.27)
				)
			)
		)
		(duplicate_pad_numbers_are_jumpers no)
		(fp_line
			(start -1.603248 -1.500124)
			(end 1.603248 -1.500124)
			(stroke
				(width 0.1524)
				(type default)
			)
			(layer "F.SilkS")
		)
		(fp_line
			(start -1.603248 1.500124)
			(end -1.603248 -1.500124)
			(stroke
				(width 0.1524)
				(type default)
			)
			(layer "F.SilkS")
		)
		(fp_line
			(start 1.603248 -1.500124)
			(end 1.603248 1.500124)
			(stroke
				(width 0.1524)
				(type default)
			)
			(layer "F.SilkS")
		)
		(fp_line
			(start 1.603248 1.500124)
			(end -1.603248 1.500124)
			(stroke
				(width 0.1524)
				(type default)
			)
			(layer "F.SilkS")
		)
		(fp_line
			(start -1.249934 -1.169924)
			(end -1.249934 -0.729996)
			(stroke
				(width 0.1)
				(type default)
			)
			(layer "F.Fab")
		)
		(fp_line
			(start -1.249934 -0.729996)
			(end -0.6985 -0.729996)
			(stroke
				(width 0.1)
				(type default)
			)
			(layer "F.Fab")
		)
		(fp_line
			(start -1.249934 0.729996)
			(end -1.249934 1.169924)
			(stroke
				(width 0.1)
				(type default)
			)
			(layer "F.Fab")
		)
		(fp_line
			(start -1.249934 1.169924)
			(end -0.700024 1.169924)
			(stroke
				(width 0.1)
				(type default)
			)
			(layer "F.Fab")
		)
		(fp_line
			(start -0.700024 -1.500124)
			(end -0.700024 -1.169924)
			(stroke
				(width 0.1)
				(type default)
			)
			(layer "F.Fab")
		)
		(fp_line
			(start -0.700024 -1.169924)
			(end -1.249934 -1.169924)
			(stroke
				(width 0.1)
				(type default)
			)
			(layer "F.Fab")
		)
		(fp_line
			(start -0.700024 1.169924)
			(end -0.700024 1.500124)
			(stroke
				(width 0.1)
				(type default)
			)
			(layer "F.Fab")
		)
		(fp_line
			(start -0.700024 1.500124)
			(end 0.700024 1.500124)
			(stroke
				(width 0.1)
				(type default)
			)
			(layer "F.Fab")
		)
		(fp_line
			(start -0.6985 -0.729996)
			(end -0.6985 0.729996)
			(stroke
				(width 0.1)
				(type default)
			)
			(layer "F.Fab")
		)
		(fp_line
			(start -0.6985 0.729996)
			(end -1.249934 0.729996)
			(stroke
				(width 0.1)
				(type default)
			)
			(layer "F.Fab")
		)
		(fp_line
			(start 0.700024 -1.500124)
			(end -0.700024 -1.500124)
			(stroke
				(width 0.1)
				(type default)
			)
			(layer "F.Fab")
		)
		(fp_line
			(start 0.700024 -0.219964)
			(end 0.700024 -1.500124)
			(stroke
				(width 0.1)
				(type default)
			)
			(layer "F.Fab")
		)
		(fp_line
			(start 0.700024 0.219964)
			(end 1.249934 0.219964)
			(stroke
				(width 0.1)
				(type default)
			)
			(layer "F.Fab")
		)
		(fp_line
			(start 0.700024 1.500124)
			(end 0.700024 0.219964)
			(stroke
				(width 0.1)
				(type default)
			)
			(layer "F.Fab")
		)
		(fp_line
			(start 1.249934 -0.219964)
			(end 0.700024 -0.219964)
			(stroke
				(width 0.1)
				(type default)
			)
			(layer "F.Fab")
		)
		(fp_line
			(start 1.249934 0.219964)
			(end 1.249934 -0.219964)
			(stroke
				(width 0.1)
				(type default)
			)
			(layer "F.Fab")
		)
		(fp_rect
			(start -0.700024 1.500124)
			(end 0.700024 -1.500124)
			(stroke
				(width 0)
				(type default)
			)
			(fill no)
			(layer "F.Fab")
		)
		(pad "D" smd rect
			(at 0.999998 0 270)
			(size 0.8128 0.9144)
			(layers "F.Cu" "F.Mask" "F.Paste")
			(net "P12V_AUX_BLEEDING")
		)
		(pad "G" smd rect
			(at -0.999998 -0.94996 270)
			(size 0.8128 0.9144)
			(layers "F.Cu" "F.Mask" "F.Paste")
			(net "FM_P12V_HSC_EN_R_N")
		)
		(pad "S" smd rect
			(at -0.999998 0.94996 270)
			(size 0.8128 0.9144)
			(layers "F.Cu" "F.Mask" "F.Paste")
			(net "GND")
		)
	)
	(footprint ""
		(layer "F.Cu")
		(at 188.839348 -423.86123 -90)
		(property "Reference" "R2585"
			(at 0 0 270)
			(layer "F.SilkS")
			(hide yes)
			(effects
				(font
					(size 1.27 1.27)
				)
			)
		)
		(property "Value" ""
			(at 0 0 270)
			(layer "F.Fab")
			(effects
				(font
					(size 1.27 1.27)
				)
			)
		)
		(duplicate_pad_numbers_are_jumpers no)
		(fp_line
			(start -0.7874 0.4064)
			(end -0.7874 -0.4064)
			(stroke
				(width 0.1524)
				(type default)
			)
			(layer "F.SilkS")
		)
		(fp_line
			(start 0.7874 0.4064)
			(end -0.7874 0.4064)
			(stroke
				(width 0.1524)
				(type default)
			)
			(layer "F.SilkS")
		)
		(fp_line
			(start -0.7874 -0.4064)
			(end 0.7874 -0.4064)
			(stroke
				(width 0.1524)
				(type default)
			)
			(layer "F.SilkS")
		)
		(fp_line
			(start 0.7874 -0.4064)
			(end 0.7874 0.4064)
			(stroke
				(width 0.1524)
				(type default)
			)
			(layer "F.SilkS")
		)
		(fp_line
			(start -0.67945 0.3048)
			(end -0.67945 -0.305054)
			(stroke
				(width 0.1)
				(type default)
			)
			(layer "F.Fab")
		)
		(fp_line
			(start -0.12065 0.3048)
			(end -0.67945 0.3048)
			(stroke
				(width 0.1)
				(type default)
			)
			(layer "F.Fab")
		)
		(fp_line
			(start 0.120396 0.3048)
			(end 0.120396 0.2794)
			(stroke
				(width 0.1)
				(type default)
			)
			(layer "F.Fab")
		)
		(fp_line
			(start 0.67945 0.3048)
			(end 0.120396 0.3048)
			(stroke
				(width 0.1)
				(type default)
			)
			(layer "F.Fab")
		)
		(fp_line
			(start -0.12065 0.2794)
			(end -0.12065 0.3048)
			(stroke
				(width 0.1)
				(type default)
			)
			(layer "F.Fab")
		)
		(fp_line
			(start 0.120396 0.2794)
			(end -0.12065 0.2794)
			(stroke
				(width 0.1)
				(type default)
			)
			(layer "F.Fab")
		)
		(fp_line
			(start -0.12065 -0.2794)
			(end 0.12065 -0.2794)
			(stroke
				(width 0.1)
				(type default)
			)
			(layer "F.Fab")
		)
		(fp_line
			(start 0.12065 -0.2794)
			(end 0.12065 -0.3048)
			(stroke
				(width 0.1)
				(type default)
			)
			(layer "F.Fab")
		)
		(fp_line
			(start 0.12065 -0.3048)
			(end 0.67945 -0.3048)
			(stroke
				(width 0.1)
				(type default)
			)
			(layer "F.Fab")
		)
		(fp_line
			(start 0.67945 -0.3048)
			(end 0.67945 0.3048)
			(stroke
				(width 0.1)
				(type default)
			)
			(layer "F.Fab")
		)
		(fp_line
			(start -0.67945 -0.305054)
			(end -0.12065 -0.305054)
			(stroke
				(width 0.1)
				(type default)
			)
			(layer "F.Fab")
		)
		(fp_line
			(start -0.12065 -0.305054)
			(end -0.12065 -0.2794)
			(stroke
				(width 0.1)
				(type default)
			)
			(layer "F.Fab")
		)
		(pad "1" smd circle
			(at -0.40005 0 270)
			(size 0 0)
			(layers "F.Cu" "F.Mask" "F.Paste")
			(net "HSC_EN")
		)
		(pad "2" smd circle
			(at 0.40005 0 270)
			(size 0 0)
			(layers "F.Cu" "F.Mask" "F.Paste")
			(net "GND")
		)
	)
	(footprint ""
		(layer "F.Cu")
		(at 83.910678 -408.517344 -90)
		(property "Reference" "C686"
			(at 0 0 270)
			(layer "F.SilkS")
			(hide yes)
			(effects
				(font
					(size 1.27 1.27)
				)
			)
		)
		(property "Value" ""
			(at 0 0 270)
			(layer "F.Fab")
			(effects
				(font
					(size 1.27 1.27)
				)
			)
		)
		(duplicate_pad_numbers_are_jumpers no)
		(fp_line
			(start -0.299974 0.150114)
			(end -0.299974 -0.150114)
			(stroke
				(width 0.1)
				(type default)
			)
			(layer "F.Fab")
		)
		(fp_line
			(start 0.299974 0.150114)
			(end -0.299974 0.150114)
			(stroke
				(width 0.1)
				(type default)
			)
			(layer "F.Fab")
		)
		(fp_line
			(start -0.299974 -0.150114)
			(end 0.299974 -0.150114)
			(stroke
				(width 0.1)
				(type default)
			)
			(layer "F.Fab")
		)
		(fp_line
			(start 0.299974 -0.150114)
			(end 0.299974 0.150114)
			(stroke
				(width 0.1)
				(type default)
			)
			(layer "F.Fab")
		)
		(pad "1" smd rect
			(at -0.2667 0 270)
			(size 0.3048 0.381)
			(layers "F.Cu" "F.Mask" "F.Paste")
			(net "P5E_CPU1_PE4_TX_C_DN<11>")
		)
		(pad "2" smd rect
			(at 0.2667 0 270)
			(size 0.3048 0.381)
			(layers "F.Cu" "F.Mask" "F.Paste")
			(net "P5E_CPU1_PE4_TX_DN<11>")
		)
	)
	(footprint ""
		(layer "F.Cu")
		(at 336.86496 -206.024734)
		(property "Reference" "H23"
			(at -1.58496 4.537456 0)
			(unlocked yes)
			(layer "F.SilkS")
			(effects
				(font
					(size 0.7874 0.5842)
					(thickness 0.1524)
				)
				(justify left)
			)
		)
		(property "Value" ""
			(at 0 0 0)
			(layer "F.Fab")
			(effects
				(font
					(size 1.27 1.27)
				)
			)
		)
		(duplicate_pad_numbers_are_jumpers no)
		(fp_circle
			(center 0 0)
			(end 2.5273 0)
			(stroke
				(width 0.1524)
				(type default)
			)
			(fill no)
			(layer "F.SilkS")
		)
		(fp_circle
			(center 0 0)
			(end 2.5273 0)
			(stroke
				(width 0.1524)
				(type default)
			)
			(fill no)
			(layer "B.SilkS")
		)
		(fp_circle
			(center 0 0)
			(end 2.5273 0)
			(stroke
				(width 0.1)
				(type default)
			)
			(fill no)
			(layer "B.Fab")
		)
		(fp_circle
			(center 0 0)
			(end 2.5273 0)
			(stroke
				(width 0.1)
				(type default)
			)
			(fill no)
			(layer "F.Fab")
		)
		(pad "" np_thru_hole circle
			(at 0 0)
			(size 3.429 3.429)
			(drill 3.429)
			(layers "*.Cu" "*.Mask")
			(clearance 0.381)
			(thermal_gap 0.381)
		)
	)
	(footprint ""
		(layer "F.Cu")
		(at 437.240172 -32.173418 90)
		(property "Reference" "R3871"
			(at 0 0 90)
			(layer "F.SilkS")
			(hide yes)
			(effects
				(font
					(size 1.27 1.27)
				)
			)
		)
		(property "Value" ""
			(at 0 0 90)
			(layer "F.Fab")
			(effects
				(font
					(size 1.27 1.27)
				)
			)
		)
		(duplicate_pad_numbers_are_jumpers no)
		(fp_line
			(start 0.7874 -0.4064)
			(end 0.7874 0.4064)
			(stroke
				(width 0.1524)
				(type default)
			)
			(layer "F.SilkS")
		)
		(fp_line
			(start -0.7874 -0.4064)
			(end 0.7874 -0.4064)
			(stroke
				(width 0.1524)
				(type default)
			)
			(layer "F.SilkS")
		)
		(fp_line
			(start 0.7874 0.4064)
			(end -0.7874 0.4064)
			(stroke
				(width 0.1524)
				(type default)
			)
			(layer "F.SilkS")
		)
		(fp_line
			(start -0.7874 0.4064)
			(end -0.7874 -0.4064)
			(stroke
				(width 0.1524)
				(type default)
			)
			(layer "F.SilkS")
		)
		(fp_line
			(start -0.12065 -0.305054)
			(end -0.12065 -0.2794)
			(stroke
				(width 0.1)
				(type default)
			)
			(layer "F.Fab")
		)
		(fp_line
			(start -0.67945 -0.305054)
			(end -0.12065 -0.305054)
			(stroke
				(width 0.1)
				(type default)
			)
			(layer "F.Fab")
		)
		(fp_line
			(start 0.67945 -0.3048)
			(end 0.67945 0.3048)
			(stroke
				(width 0.1)
				(type default)
			)
			(layer "F.Fab")
		)
		(fp_line
			(start 0.12065 -0.3048)
			(end 0.67945 -0.3048)
			(stroke
				(width 0.1)
				(type default)
			)
			(layer "F.Fab")
		)
		(fp_line
			(start 0.12065 -0.2794)
			(end 0.12065 -0.3048)
			(stroke
				(width 0.1)
				(type default)
			)
			(layer "F.Fab")
		)
		(fp_line
			(start -0.12065 -0.2794)
			(end 0.12065 -0.2794)
			(stroke
				(width 0.1)
				(type default)
			)
			(layer "F.Fab")
		)
		(fp_line
			(start 0.120396 0.2794)
			(end -0.12065 0.2794)
			(stroke
				(width 0.1)
				(type default)
			)
			(layer "F.Fab")
		)
		(fp_line
			(start -0.12065 0.2794)
			(end -0.12065 0.3048)
			(stroke
				(width 0.1)
				(type default)
			)
			(layer "F.Fab")
		)
		(fp_line
			(start 0.67945 0.3048)
			(end 0.120396 0.3048)
			(stroke
				(width 0.1)
				(type default)
			)
			(layer "F.Fab")
		)
		(fp_line
			(start 0.120396 0.3048)
			(end 0.120396 0.2794)
			(stroke
				(width 0.1)
				(type default)
			)
			(layer "F.Fab")
		)
		(fp_line
			(start -0.12065 0.3048)
			(end -0.67945 0.3048)
			(stroke
				(width 0.1)
				(type default)
			)
			(layer "F.Fab")
		)
		(fp_line
			(start -0.67945 0.3048)
			(end -0.67945 -0.305054)
			(stroke
				(width 0.1)
				(type default)
			)
			(layer "F.Fab")
		)
		(pad "1" smd circle
			(at -0.40005 0 90)
			(size 0 0)
			(layers "F.Cu" "F.Mask" "F.Paste")
			(net "P12V_OCP_IMON_1")
		)
		(pad "2" smd circle
			(at 0.40005 0 90)
			(size 0 0)
			(layers "F.Cu" "F.Mask" "F.Paste")
			(net "P12V_OCP_SFF_ISENSE_MPS_MAM")
		)
	)
	(footprint ""
		(layer "F.Cu")
		(at 22.91588 -430.367948)
		(property "Reference" "R2910"
			(at 0 0 0)
			(layer "F.SilkS")
			(hide yes)
			(effects
				(font
					(size 1.27 1.27)
				)
			)
		)
		(property "Value" ""
			(at 0 0 0)
			(layer "F.Fab")
			(effects
				(font
					(size 1.27 1.27)
				)
			)
		)
		(duplicate_pad_numbers_are_jumpers no)
		(fp_line
			(start -0.7874 -0.4064)
			(end 0.7874 -0.4064)
			(stroke
				(width 0.1524)
				(type default)
			)
			(layer "F.SilkS")
		)
		(fp_line
			(start -0.7874 0.4064)
			(end -0.7874 -0.4064)
			(stroke
				(width 0.1524)
				(type default)
			)
			(layer "F.SilkS")
		)
		(fp_line
			(start 0.7874 -0.4064)
			(end 0.7874 0.4064)
			(stroke
				(width 0.1524)
				(type default)
			)
			(layer "F.SilkS")
		)
		(fp_line
			(start 0.7874 0.4064)
			(end -0.7874 0.4064)
			(stroke
				(width 0.1524)
				(type default)
			)
			(layer "F.SilkS")
		)
		(fp_line
			(start -0.67945 -0.305054)
			(end -0.12065 -0.305054)
			(stroke
				(width 0.1)
				(type default)
			)
			(layer "F.Fab")
		)
		(fp_line
			(start -0.67945 0.3048)
			(end -0.67945 -0.305054)
			(stroke
				(width 0.1)
				(type default)
			)
			(layer "F.Fab")
		)
		(fp_line
			(start -0.12065 -0.305054)
			(end -0.12065 -0.2794)
			(stroke
				(width 0.1)
				(type default)
			)
			(layer "F.Fab")
		)
		(fp_line
			(start -0.12065 -0.2794)
			(end 0.12065 -0.2794)
			(stroke
				(width 0.1)
				(type default)
			)
			(layer "F.Fab")
		)
		(fp_line
			(start -0.12065 0.2794)
			(end -0.12065 0.3048)
			(stroke
				(width 0.1)
				(type default)
			)
			(layer "F.Fab")
		)
		(fp_line
			(start -0.12065 0.3048)
			(end -0.67945 0.3048)
			(stroke
				(width 0.1)
				(type default)
			)
			(layer "F.Fab")
		)
		(fp_line
			(start 0.120396 0.2794)
			(end -0.12065 0.2794)
			(stroke
				(width 0.1)
				(type default)
			)
			(layer "F.Fab")
		)
		(fp_line
			(start 0.120396 0.3048)
			(end 0.120396 0.2794)
			(stroke
				(width 0.1)
				(type default)
			)
			(layer "F.Fab")
		)
		(fp_line
			(start 0.12065 -0.3048)
			(end 0.67945 -0.3048)
			(stroke
				(width 0.1)
				(type default)
			)
			(layer "F.Fab")
		)
		(fp_line
			(start 0.12065 -0.2794)
			(end 0.12065 -0.3048)
			(stroke
				(width 0.1)
				(type default)
			)
			(layer "F.Fab")
		)
		(fp_line
			(start 0.67945 -0.3048)
			(end 0.67945 0.3048)
			(stroke
				(width 0.1)
				(type default)
			)
			(layer "F.Fab")
		)
		(fp_line
			(start 0.67945 0.3048)
			(end 0.120396 0.3048)
			(stroke
				(width 0.1)
				(type default)
			)
			(layer "F.Fab")
		)
		(pad "1" smd circle
			(at -0.40005 0)
			(size 0 0)
			(layers "F.Cu" "F.Mask" "F.Paste")
			(net "P3V3_AUX")
		)
		(pad "2" smd circle
			(at 0.40005 0)
			(size 0 0)
			(layers "F.Cu" "F.Mask" "F.Paste")
			(net "FM_SWB_PWR_EN_R")
		)
	)
	(footprint ""
		(layer "F.Cu")
		(at 96.150938 -417.76777 90)
		(property "Reference" "R4186"
			(at 0 0 90)
			(layer "F.SilkS")
			(hide yes)
			(effects
				(font
					(size 1.27 1.27)
				)
			)
		)
		(property "Value" ""
			(at 0 0 90)
			(layer "F.Fab")
			(effects
				(font
					(size 1.27 1.27)
				)
			)
		)
		(duplicate_pad_numbers_are_jumpers no)
		(fp_line
			(start 0.7874 -0.4064)
			(end 0.7874 0.4064)
			(stroke
				(width 0.1524)
				(type default)
			)
			(layer "F.SilkS")
		)
		(fp_line
			(start -0.7874 -0.4064)
			(end 0.7874 -0.4064)
			(stroke
				(width 0.1524)
				(type default)
			)
			(layer "F.SilkS")
		)
		(fp_line
			(start 0.7874 0.4064)
			(end -0.7874 0.4064)
			(stroke
				(width 0.1524)
				(type default)
			)
			(layer "F.SilkS")
		)
		(fp_line
			(start -0.7874 0.4064)
			(end -0.7874 -0.4064)
			(stroke
				(width 0.1524)
				(type default)
			)
			(layer "F.SilkS")
		)
		(fp_line
			(start -0.12065 -0.305054)
			(end -0.12065 -0.2794)
			(stroke
				(width 0.1)
				(type default)
			)
			(layer "F.Fab")
		)
		(fp_line
			(start -0.67945 -0.305054)
			(end -0.12065 -0.305054)
			(stroke
				(width 0.1)
				(type default)
			)
			(layer "F.Fab")
		)
		(fp_line
			(start 0.67945 -0.3048)
			(end 0.67945 0.3048)
			(stroke
				(width 0.1)
				(type default)
			)
			(layer "F.Fab")
		)
		(fp_line
			(start 0.12065 -0.3048)
			(end 0.67945 -0.3048)
			(stroke
				(width 0.1)
				(type default)
			)
			(layer "F.Fab")
		)
		(fp_line
			(start 0.12065 -0.2794)
			(end 0.12065 -0.3048)
			(stroke
				(width 0.1)
				(type default)
			)
			(layer "F.Fab")
		)
		(fp_line
			(start -0.12065 -0.2794)
			(end 0.12065 -0.2794)
			(stroke
				(width 0.1)
				(type default)
			)
			(layer "F.Fab")
		)
		(fp_line
			(start 0.120396 0.2794)
			(end -0.12065 0.2794)
			(stroke
				(width 0.1)
				(type default)
			)
			(layer "F.Fab")
		)
		(fp_line
			(start -0.12065 0.2794)
			(end -0.12065 0.3048)
			(stroke
				(width 0.1)
				(type default)
			)
			(layer "F.Fab")
		)
		(fp_line
			(start 0.67945 0.3048)
			(end 0.120396 0.3048)
			(stroke
				(width 0.1)
				(type default)
			)
			(layer "F.Fab")
		)
		(fp_line
			(start 0.120396 0.3048)
			(end 0.120396 0.2794)
			(stroke
				(width 0.1)
				(type default)
			)
			(layer "F.Fab")
		)
		(fp_line
			(start -0.12065 0.3048)
			(end -0.67945 0.3048)
			(stroke
				(width 0.1)
				(type default)
			)
			(layer "F.Fab")
		)
		(fp_line
			(start -0.67945 0.3048)
			(end -0.67945 -0.305054)
			(stroke
				(width 0.1)
				(type default)
			)
			(layer "F.Fab")
		)
		(pad "1" smd circle
			(at -0.40005 0 90)
			(size 0 0)
			(layers "F.Cu" "F.Mask" "F.Paste")
			(net "P3V3_AUX")
		)
		(pad "2" smd circle
			(at 0.40005 0 90)
			(size 0 0)
			(layers "F.Cu" "F.Mask" "F.Paste")
			(net "U272_2_ADD2")
		)
	)
	(footprint ""
		(layer "F.Cu")
		(at 33.186878 -16.099536 90)
		(property "Reference" "C818"
			(at 0 0 90)
			(layer "F.SilkS")
			(hide yes)
			(effects
				(font
					(size 1.27 1.27)
				)
			)
		)
		(property "Value" ""
			(at 0 0 90)
			(layer "F.Fab")
			(effects
				(font
					(size 1.27 1.27)
				)
			)
		)
		(duplicate_pad_numbers_are_jumpers no)
		(fp_line
			(start 0.299974 -0.150114)
			(end 0.299974 0.150114)
			(stroke
				(width 0.1)
				(type default)
			)
			(layer "F.Fab")
		)
		(fp_line
			(start -0.299974 -0.150114)
			(end 0.299974 -0.150114)
			(stroke
				(width 0.1)
				(type default)
			)
			(layer "F.Fab")
		)
		(fp_line
			(start 0.299974 0.150114)
			(end -0.299974 0.150114)
			(stroke
				(width 0.1)
				(type default)
			)
			(layer "F.Fab")
		)
		(fp_line
			(start -0.299974 0.150114)
			(end -0.299974 -0.150114)
			(stroke
				(width 0.1)
				(type default)
			)
			(layer "F.Fab")
		)
		(pad "1" smd rect
			(at -0.2667 0 90)
			(size 0.3048 0.381)
			(layers "F.Cu" "F.Mask" "F.Paste")
			(net "P5E_CPU1_PE1_TX_C_DN<9>")
		)
		(pad "2" smd rect
			(at 0.2667 0 90)
			(size 0.3048 0.381)
			(layers "F.Cu" "F.Mask" "F.Paste")
			(net "P5E_CPU1_PE1_TX_DN<9>")
		)
	)
	(footprint ""
		(layer "F.Cu")
		(at 114.706654 -361.72775)
		(property "Reference" "PC555"
			(at 0 0 0)
			(layer "F.SilkS")
			(hide yes)
			(effects
				(font
					(size 1.27 1.27)
				)
			)
		)
		(property "Value" ""
			(at 0 0 0)
			(layer "F.Fab")
			(effects
				(font
					(size 1.27 1.27)
				)
			)
		)
		(duplicate_pad_numbers_are_jumpers no)
		(fp_line
			(start -0.7874 -0.4064)
			(end 0.7874 -0.4064)
			(stroke
				(width 0.1524)
				(type default)
			)
			(layer "F.SilkS")
		)
		(fp_line
			(start -0.7874 0.4064)
			(end -0.7874 -0.4064)
			(stroke
				(width 0.1524)
				(type default)
			)
			(layer "F.SilkS")
		)
		(fp_line
			(start 0.7874 -0.4064)
			(end 0.7874 0.4064)
			(stroke
				(width 0.1524)
				(type default)
			)
			(layer "F.SilkS")
		)
		(fp_line
			(start 0.7874 0.4064)
			(end -0.7874 0.4064)
			(stroke
				(width 0.1524)
				(type default)
			)
			(layer "F.SilkS")
		)
		(fp_line
			(start -0.67945 -0.305054)
			(end -0.12065 -0.305054)
			(stroke
				(width 0.1)
				(type default)
			)
			(layer "F.Fab")
		)
		(fp_line
			(start -0.67945 0.3048)
			(end -0.67945 -0.305054)
			(stroke
				(width 0.1)
				(type default)
			)
			(layer "F.Fab")
		)
		(fp_line
			(start -0.12065 -0.305054)
			(end -0.12065 -0.2794)
			(stroke
				(width 0.1)
				(type default)
			)
			(layer "F.Fab")
		)
		(fp_line
			(start -0.12065 -0.2794)
			(end 0.12065 -0.2794)
			(stroke
				(width 0.1)
				(type default)
			)
			(layer "F.Fab")
		)
		(fp_line
			(start -0.12065 0.2794)
			(end -0.12065 0.3048)
			(stroke
				(width 0.1)
				(type default)
			)
			(layer "F.Fab")
		)
		(fp_line
			(start -0.12065 0.3048)
			(end -0.67945 0.3048)
			(stroke
				(width 0.1)
				(type default)
			)
			(layer "F.Fab")
		)
		(fp_line
			(start 0.120396 0.2794)
			(end -0.12065 0.2794)
			(stroke
				(width 0.1)
				(type default)
			)
			(layer "F.Fab")
		)
		(fp_line
			(start 0.120396 0.3048)
			(end 0.120396 0.2794)
			(stroke
				(width 0.1)
				(type default)
			)
			(layer "F.Fab")
		)
		(fp_line
			(start 0.12065 -0.3048)
			(end 0.67945 -0.3048)
			(stroke
				(width 0.1)
				(type default)
			)
			(layer "F.Fab")
		)
		(fp_line
			(start 0.12065 -0.2794)
			(end 0.12065 -0.3048)
			(stroke
				(width 0.1)
				(type default)
			)
			(layer "F.Fab")
		)
		(fp_line
			(start 0.67945 -0.3048)
			(end 0.67945 0.3048)
			(stroke
				(width 0.1)
				(type default)
			)
			(layer "F.Fab")
		)
		(fp_line
			(start 0.67945 0.3048)
			(end 0.120396 0.3048)
			(stroke
				(width 0.1)
				(type default)
			)
			(layer "F.Fab")
		)
		(pad "1" smd circle
			(at -0.40005 0)
			(size 0 0)
			(layers "F.Cu" "F.Mask" "F.Paste")
			(net "PVCCIN_CPU1_VCC")
		)
		(pad "2" smd circle
			(at 0.40005 0)
			(size 0 0)
			(layers "F.Cu" "F.Mask" "F.Paste")
			(net "GND")
		)
	)
	(footprint ""
		(layer "F.Cu")
		(at 223.70288 -43.525948)
		(property "Reference" "R3533"
			(at 0 0 0)
			(layer "F.SilkS")
			(hide yes)
			(effects
				(font
					(size 1.27 1.27)
				)
			)
		)
		(property "Value" ""
			(at 0 0 0)
			(layer "F.Fab")
			(effects
				(font
					(size 1.27 1.27)
				)
			)
		)
		(duplicate_pad_numbers_are_jumpers no)
		(fp_line
			(start -0.7874 -0.4064)
			(end 0.7874 -0.4064)
			(stroke
				(width 0.1524)
				(type default)
			)
			(layer "F.SilkS")
		)
		(fp_line
			(start -0.7874 0.4064)
			(end -0.7874 -0.4064)
			(stroke
				(width 0.1524)
				(type default)
			)
			(layer "F.SilkS")
		)
		(fp_line
			(start 0.7874 -0.4064)
			(end 0.7874 0.4064)
			(stroke
				(width 0.1524)
				(type default)
			)
			(layer "F.SilkS")
		)
		(fp_line
			(start 0.7874 0.4064)
			(end -0.7874 0.4064)
			(stroke
				(width 0.1524)
				(type default)
			)
			(layer "F.SilkS")
		)
		(fp_line
			(start -0.67945 -0.305054)
			(end -0.12065 -0.305054)
			(stroke
				(width 0.1)
				(type default)
			)
			(layer "F.Fab")
		)
		(fp_line
			(start -0.67945 0.3048)
			(end -0.67945 -0.305054)
			(stroke
				(width 0.1)
				(type default)
			)
			(layer "F.Fab")
		)
		(fp_line
			(start -0.12065 -0.305054)
			(end -0.12065 -0.2794)
			(stroke
				(width 0.1)
				(type default)
			)
			(layer "F.Fab")
		)
		(fp_line
			(start -0.12065 -0.2794)
			(end 0.12065 -0.2794)
			(stroke
				(width 0.1)
				(type default)
			)
			(layer "F.Fab")
		)
		(fp_line
			(start -0.12065 0.2794)
			(end -0.12065 0.3048)
			(stroke
				(width 0.1)
				(type default)
			)
			(layer "F.Fab")
		)
		(fp_line
			(start -0.12065 0.3048)
			(end -0.67945 0.3048)
			(stroke
				(width 0.1)
				(type default)
			)
			(layer "F.Fab")
		)
		(fp_line
			(start 0.120396 0.2794)
			(end -0.12065 0.2794)
			(stroke
				(width 0.1)
				(type default)
			)
			(layer "F.Fab")
		)
		(fp_line
			(start 0.120396 0.3048)
			(end 0.120396 0.2794)
			(stroke
				(width 0.1)
				(type default)
			)
			(layer "F.Fab")
		)
		(fp_line
			(start 0.12065 -0.3048)
			(end 0.67945 -0.3048)
			(stroke
				(width 0.1)
				(type default)
			)
			(layer "F.Fab")
		)
		(fp_line
			(start 0.12065 -0.2794)
			(end 0.12065 -0.3048)
			(stroke
				(width 0.1)
				(type default)
			)
			(layer "F.Fab")
		)
		(fp_line
			(start 0.67945 -0.3048)
			(end 0.67945 0.3048)
			(stroke
				(width 0.1)
				(type default)
			)
			(layer "F.Fab")
		)
		(fp_line
			(start 0.67945 0.3048)
			(end 0.120396 0.3048)
			(stroke
				(width 0.1)
				(type default)
			)
			(layer "F.Fab")
		)
		(pad "1" smd circle
			(at -0.40005 0)
			(size 0 0)
			(layers "F.Cu" "F.Mask" "F.Paste")
			(net "SMB_E1S_3V3AUX_ISO_SCL_R")
		)
		(pad "2" smd circle
			(at 0.40005 0)
			(size 0 0)
			(layers "F.Cu" "F.Mask" "F.Paste")
			(net "SMB_E1S_3V3AUX_ISO_SCL")
		)
	)
	(footprint ""
		(layer "F.Cu")
		(at 322.8721 -76.585064 -90)
		(property "Reference" "R2974"
			(at 0 0 270)
			(layer "F.SilkS")
			(hide yes)
			(effects
				(font
					(size 1.27 1.27)
				)
			)
		)
		(property "Value" ""
			(at 0 0 270)
			(layer "F.Fab")
			(effects
				(font
					(size 1.27 1.27)
				)
			)
		)
		(duplicate_pad_numbers_are_jumpers no)
		(fp_line
			(start -0.7874 0.4064)
			(end -0.7874 -0.4064)
			(stroke
				(width 0.1524)
				(type default)
			)
			(layer "F.SilkS")
		)
		(fp_line
			(start 0.7874 0.4064)
			(end -0.7874 0.4064)
			(stroke
				(width 0.1524)
				(type default)
			)
			(layer "F.SilkS")
		)
		(fp_line
			(start -0.7874 -0.4064)
			(end 0.7874 -0.4064)
			(stroke
				(width 0.1524)
				(type default)
			)
			(layer "F.SilkS")
		)
		(fp_line
			(start 0.7874 -0.4064)
			(end 0.7874 0.4064)
			(stroke
				(width 0.1524)
				(type default)
			)
			(layer "F.SilkS")
		)
		(fp_line
			(start -0.67945 0.3048)
			(end -0.67945 -0.305054)
			(stroke
				(width 0.1)
				(type default)
			)
			(layer "F.Fab")
		)
		(fp_line
			(start -0.12065 0.3048)
			(end -0.67945 0.3048)
			(stroke
				(width 0.1)
				(type default)
			)
			(layer "F.Fab")
		)
		(fp_line
			(start 0.120396 0.3048)
			(end 0.120396 0.2794)
			(stroke
				(width 0.1)
				(type default)
			)
			(layer "F.Fab")
		)
		(fp_line
			(start 0.67945 0.3048)
			(end 0.120396 0.3048)
			(stroke
				(width 0.1)
				(type default)
			)
			(layer "F.Fab")
		)
		(fp_line
			(start -0.12065 0.2794)
			(end -0.12065 0.3048)
			(stroke
				(width 0.1)
				(type default)
			)
			(layer "F.Fab")
		)
		(fp_line
			(start 0.120396 0.2794)
			(end -0.12065 0.2794)
			(stroke
				(width 0.1)
				(type default)
			)
			(layer "F.Fab")
		)
		(fp_line
			(start -0.12065 -0.2794)
			(end 0.12065 -0.2794)
			(stroke
				(width 0.1)
				(type default)
			)
			(layer "F.Fab")
		)
		(fp_line
			(start 0.12065 -0.2794)
			(end 0.12065 -0.3048)
			(stroke
				(width 0.1)
				(type default)
			)
			(layer "F.Fab")
		)
		(fp_line
			(start 0.12065 -0.3048)
			(end 0.67945 -0.3048)
			(stroke
				(width 0.1)
				(type default)
			)
			(layer "F.Fab")
		)
		(fp_line
			(start 0.67945 -0.3048)
			(end 0.67945 0.3048)
			(stroke
				(width 0.1)
				(type default)
			)
			(layer "F.Fab")
		)
		(fp_line
			(start -0.67945 -0.305054)
			(end -0.12065 -0.305054)
			(stroke
				(width 0.1)
				(type default)
			)
			(layer "F.Fab")
		)
		(fp_line
			(start -0.12065 -0.305054)
			(end -0.12065 -0.2794)
			(stroke
				(width 0.1)
				(type default)
			)
			(layer "F.Fab")
		)
		(pad "1" smd circle
			(at -0.40005 0 270)
			(size 0 0)
			(layers "F.Cu" "F.Mask" "F.Paste")
			(net "P1V05_PCH_AUX")
		)
		(pad "2" smd circle
			(at 0.40005 0 270)
			(size 0 0)
			(layers "F.Cu" "F.Mask" "F.Paste")
			(net "FAB_REV_ID1")
		)
	)
	(footprint ""
		(layer "F.Cu")
		(at 28.532328 -98.570034)
		(property "Reference" "R3859"
			(at 0 0 0)
			(layer "F.SilkS")
			(hide yes)
			(effects
				(font
					(size 1.27 1.27)
				)
			)
		)
		(property "Value" ""
			(at 0 0 0)
			(layer "F.Fab")
			(effects
				(font
					(size 1.27 1.27)
				)
			)
		)
		(duplicate_pad_numbers_are_jumpers no)
		(fp_line
			(start -0.7874 -0.4064)
			(end 0.7874 -0.4064)
			(stroke
				(width 0.1524)
				(type default)
			)
			(layer "F.SilkS")
		)
		(fp_line
			(start -0.7874 0.4064)
			(end -0.7874 -0.4064)
			(stroke
				(width 0.1524)
				(type default)
			)
			(layer "F.SilkS")
		)
		(fp_line
			(start 0.7874 -0.4064)
			(end 0.7874 0.4064)
			(stroke
				(width 0.1524)
				(type default)
			)
			(layer "F.SilkS")
		)
		(fp_line
			(start 0.7874 0.4064)
			(end -0.7874 0.4064)
			(stroke
				(width 0.1524)
				(type default)
			)
			(layer "F.SilkS")
		)
		(fp_line
			(start -0.67945 -0.305054)
			(end -0.12065 -0.305054)
			(stroke
				(width 0.1)
				(type default)
			)
			(layer "F.Fab")
		)
		(fp_line
			(start -0.67945 0.3048)
			(end -0.67945 -0.305054)
			(stroke
				(width 0.1)
				(type default)
			)
			(layer "F.Fab")
		)
		(fp_line
			(start -0.12065 -0.305054)
			(end -0.12065 -0.2794)
			(stroke
				(width 0.1)
				(type default)
			)
			(layer "F.Fab")
		)
		(fp_line
			(start -0.12065 -0.2794)
			(end 0.12065 -0.2794)
			(stroke
				(width 0.1)
				(type default)
			)
			(layer "F.Fab")
		)
		(fp_line
			(start -0.12065 0.2794)
			(end -0.12065 0.3048)
			(stroke
				(width 0.1)
				(type default)
			)
			(layer "F.Fab")
		)
		(fp_line
			(start -0.12065 0.3048)
			(end -0.67945 0.3048)
			(stroke
				(width 0.1)
				(type default)
			)
			(layer "F.Fab")
		)
		(fp_line
			(start 0.120396 0.2794)
			(end -0.12065 0.2794)
			(stroke
				(width 0.1)
				(type default)
			)
			(layer "F.Fab")
		)
		(fp_line
			(start 0.120396 0.3048)
			(end 0.120396 0.2794)
			(stroke
				(width 0.1)
				(type default)
			)
			(layer "F.Fab")
		)
		(fp_line
			(start 0.12065 -0.3048)
			(end 0.67945 -0.3048)
			(stroke
				(width 0.1)
				(type default)
			)
			(layer "F.Fab")
		)
		(fp_line
			(start 0.12065 -0.2794)
			(end 0.12065 -0.3048)
			(stroke
				(width 0.1)
				(type default)
			)
			(layer "F.Fab")
		)
		(fp_line
			(start 0.67945 -0.3048)
			(end 0.67945 0.3048)
			(stroke
				(width 0.1)
				(type default)
			)
			(layer "F.Fab")
		)
		(fp_line
			(start 0.67945 0.3048)
			(end 0.120396 0.3048)
			(stroke
				(width 0.1)
				(type default)
			)
			(layer "F.Fab")
		)
		(pad "1" smd rect
			(at -0.40005 0 180)
			(size 0.4572 0.508)
			(layers "F.Cu" "F.Mask" "F.Paste")
			(net "P12V_OCP_V3_2_ISENSE_MAM_MAM")
		)
		(pad "2" smd rect
			(at 0.40005 0 180)
			(size 0.4572 0.508)
			(layers "F.Cu" "F.Mask" "F.Paste")
			(net "P12V_OCP_V3_2_ISENSE_MAM")
		)
	)
	(footprint ""
		(layer "F.Cu")
		(at 274.495006 -21.259292 180)
		(property "Reference" "R3185"
			(at 0 0 180)
			(layer "F.SilkS")
			(hide yes)
			(effects
				(font
					(size 1.27 1.27)
				)
			)
		)
		(property "Value" ""
			(at 0 0 180)
			(layer "F.Fab")
			(effects
				(font
					(size 1.27 1.27)
				)
			)
		)
		(duplicate_pad_numbers_are_jumpers no)
		(fp_line
			(start 0.7874 0.4064)
			(end -0.7874 0.4064)
			(stroke
				(width 0.1524)
				(type default)
			)
			(layer "F.SilkS")
		)
		(fp_line
			(start 0.7874 -0.4064)
			(end 0.7874 0.4064)
			(stroke
				(width 0.1524)
				(type default)
			)
			(layer "F.SilkS")
		)
		(fp_line
			(start -0.7874 0.4064)
			(end -0.7874 -0.4064)
			(stroke
				(width 0.1524)
				(type default)
			)
			(layer "F.SilkS")
		)
		(fp_line
			(start -0.7874 -0.4064)
			(end 0.7874 -0.4064)
			(stroke
				(width 0.1524)
				(type default)
			)
			(layer "F.SilkS")
		)
		(fp_line
			(start 0.67945 0.3048)
			(end 0.120396 0.3048)
			(stroke
				(width 0.1)
				(type default)
			)
			(layer "F.Fab")
		)
		(fp_line
			(start 0.67945 -0.3048)
			(end 0.67945 0.3048)
			(stroke
				(width 0.1)
				(type default)
			)
			(layer "F.Fab")
		)
		(fp_line
			(start 0.12065 -0.2794)
			(end 0.12065 -0.3048)
			(stroke
				(width 0.1)
				(type default)
			)
			(layer "F.Fab")
		)
		(fp_line
			(start 0.12065 -0.3048)
			(end 0.67945 -0.3048)
			(stroke
				(width 0.1)
				(type default)
			)
			(layer "F.Fab")
		)
		(fp_line
			(start 0.120396 0.3048)
			(end 0.120396 0.2794)
			(stroke
				(width 0.1)
				(type default)
			)
			(layer "F.Fab")
		)
		(fp_line
			(start 0.120396 0.2794)
			(end -0.12065 0.2794)
			(stroke
				(width 0.1)
				(type default)
			)
			(layer "F.Fab")
		)
		(fp_line
			(start -0.12065 0.3048)
			(end -0.67945 0.3048)
			(stroke
				(width 0.1)
				(type default)
			)
			(layer "F.Fab")
		)
		(fp_line
			(start -0.12065 0.2794)
			(end -0.12065 0.3048)
			(stroke
				(width 0.1)
				(type default)
			)
			(layer "F.Fab")
		)
		(fp_line
			(start -0.12065 -0.2794)
			(end 0.12065 -0.2794)
			(stroke
				(width 0.1)
				(type default)
			)
			(layer "F.Fab")
		)
		(fp_line
			(start -0.12065 -0.305054)
			(end -0.12065 -0.2794)
			(stroke
				(width 0.1)
				(type default)
			)
			(layer "F.Fab")
		)
		(fp_line
			(start -0.67945 0.3048)
			(end -0.67945 -0.305054)
			(stroke
				(width 0.1)
				(type default)
			)
			(layer "F.Fab")
		)
		(fp_line
			(start -0.67945 -0.305054)
			(end -0.12065 -0.305054)
			(stroke
				(width 0.1)
				(type default)
			)
			(layer "F.Fab")
		)
		(pad "1" smd circle
			(at -0.40005 0 180)
			(size 0 0)
			(layers "F.Cu" "F.Mask" "F.Paste")
			(net "OCP_V3_2_WAKE_BUFF_N")
		)
		(pad "2" smd circle
			(at 0.40005 0 180)
			(size 0 0)
			(layers "F.Cu" "F.Mask" "F.Paste")
			(net "OCP_V3_2_WAKE_BUFF_R_N")
		)
	)
	(footprint ""
		(layer "F.Cu")
		(at 432.80584 -138.557762 -90)
		(property "Reference" "R2386"
			(at 0 0 270)
			(layer "F.SilkS")
			(hide yes)
			(effects
				(font
					(size 1.27 1.27)
				)
			)
		)
		(property "Value" ""
			(at 0 0 270)
			(layer "F.Fab")
			(effects
				(font
					(size 1.27 1.27)
				)
			)
		)
		(duplicate_pad_numbers_are_jumpers no)
		(fp_line
			(start -0.7874 0.4064)
			(end -0.7874 -0.4064)
			(stroke
				(width 0.1524)
				(type default)
			)
			(layer "F.SilkS")
		)
		(fp_line
			(start 0.7874 0.4064)
			(end -0.7874 0.4064)
			(stroke
				(width 0.1524)
				(type default)
			)
			(layer "F.SilkS")
		)
		(fp_line
			(start -0.7874 -0.4064)
			(end 0.7874 -0.4064)
			(stroke
				(width 0.1524)
				(type default)
			)
			(layer "F.SilkS")
		)
		(fp_line
			(start 0.7874 -0.4064)
			(end 0.7874 0.4064)
			(stroke
				(width 0.1524)
				(type default)
			)
			(layer "F.SilkS")
		)
		(fp_line
			(start -0.67945 0.3048)
			(end -0.67945 -0.305054)
			(stroke
				(width 0.1)
				(type default)
			)
			(layer "F.Fab")
		)
		(fp_line
			(start -0.12065 0.3048)
			(end -0.67945 0.3048)
			(stroke
				(width 0.1)
				(type default)
			)
			(layer "F.Fab")
		)
		(fp_line
			(start 0.120396 0.3048)
			(end 0.120396 0.2794)
			(stroke
				(width 0.1)
				(type default)
			)
			(layer "F.Fab")
		)
		(fp_line
			(start 0.67945 0.3048)
			(end 0.120396 0.3048)
			(stroke
				(width 0.1)
				(type default)
			)
			(layer "F.Fab")
		)
		(fp_line
			(start -0.12065 0.2794)
			(end -0.12065 0.3048)
			(stroke
				(width 0.1)
				(type default)
			)
			(layer "F.Fab")
		)
		(fp_line
			(start 0.120396 0.2794)
			(end -0.12065 0.2794)
			(stroke
				(width 0.1)
				(type default)
			)
			(layer "F.Fab")
		)
		(fp_line
			(start -0.12065 -0.2794)
			(end 0.12065 -0.2794)
			(stroke
				(width 0.1)
				(type default)
			)
			(layer "F.Fab")
		)
		(fp_line
			(start 0.12065 -0.2794)
			(end 0.12065 -0.3048)
			(stroke
				(width 0.1)
				(type default)
			)
			(layer "F.Fab")
		)
		(fp_line
			(start 0.12065 -0.3048)
			(end 0.67945 -0.3048)
			(stroke
				(width 0.1)
				(type default)
			)
			(layer "F.Fab")
		)
		(fp_line
			(start 0.67945 -0.3048)
			(end 0.67945 0.3048)
			(stroke
				(width 0.1)
				(type default)
			)
			(layer "F.Fab")
		)
		(fp_line
			(start -0.67945 -0.305054)
			(end -0.12065 -0.305054)
			(stroke
				(width 0.1)
				(type default)
			)
			(layer "F.Fab")
		)
		(fp_line
			(start -0.12065 -0.305054)
			(end -0.12065 -0.2794)
			(stroke
				(width 0.1)
				(type default)
			)
			(layer "F.Fab")
		)
		(pad "1" smd circle
			(at -0.40005 0 270)
			(size 0 0)
			(layers "F.Cu" "F.Mask" "F.Paste")
			(net "PVNN_TERM_CPU0")
		)
		(pad "2" smd circle
			(at 0.40005 0 270)
			(size 0 0)
			(layers "F.Cu" "F.Mask" "F.Paste")
			(net "SVID_DIO0_CPU0_R")
		)
	)
	(footprint ""
		(layer "F.Cu")
		(at 292.61054 -94.800674)
		(property "Reference" "R710"
			(at 0 0 0)
			(layer "F.SilkS")
			(hide yes)
			(effects
				(font
					(size 1.27 1.27)
				)
			)
		)
		(property "Value" ""
			(at 0 0 0)
			(layer "F.Fab")
			(effects
				(font
					(size 1.27 1.27)
				)
			)
		)
		(duplicate_pad_numbers_are_jumpers no)
		(fp_line
			(start -0.7874 -0.4064)
			(end 0.7874 -0.4064)
			(stroke
				(width 0.1524)
				(type default)
			)
			(layer "F.SilkS")
		)
		(fp_line
			(start -0.7874 0.4064)
			(end -0.7874 -0.4064)
			(stroke
				(width 0.1524)
				(type default)
			)
			(layer "F.SilkS")
		)
		(fp_line
			(start 0.7874 -0.4064)
			(end 0.7874 0.4064)
			(stroke
				(width 0.1524)
				(type default)
			)
			(layer "F.SilkS")
		)
		(fp_line
			(start 0.7874 0.4064)
			(end -0.7874 0.4064)
			(stroke
				(width 0.1524)
				(type default)
			)
			(layer "F.SilkS")
		)
		(fp_line
			(start -0.67945 -0.305054)
			(end -0.12065 -0.305054)
			(stroke
				(width 0.1)
				(type default)
			)
			(layer "F.Fab")
		)
		(fp_line
			(start -0.67945 0.3048)
			(end -0.67945 -0.305054)
			(stroke
				(width 0.1)
				(type default)
			)
			(layer "F.Fab")
		)
		(fp_line
			(start -0.12065 -0.305054)
			(end -0.12065 -0.2794)
			(stroke
				(width 0.1)
				(type default)
			)
			(layer "F.Fab")
		)
		(fp_line
			(start -0.12065 -0.2794)
			(end 0.12065 -0.2794)
			(stroke
				(width 0.1)
				(type default)
			)
			(layer "F.Fab")
		)
		(fp_line
			(start -0.12065 0.2794)
			(end -0.12065 0.3048)
			(stroke
				(width 0.1)
				(type default)
			)
			(layer "F.Fab")
		)
		(fp_line
			(start -0.12065 0.3048)
			(end -0.67945 0.3048)
			(stroke
				(width 0.1)
				(type default)
			)
			(layer "F.Fab")
		)
		(fp_line
			(start 0.120396 0.2794)
			(end -0.12065 0.2794)
			(stroke
				(width 0.1)
				(type default)
			)
			(layer "F.Fab")
		)
		(fp_line
			(start 0.120396 0.3048)
			(end 0.120396 0.2794)
			(stroke
				(width 0.1)
				(type default)
			)
			(layer "F.Fab")
		)
		(fp_line
			(start 0.12065 -0.3048)
			(end 0.67945 -0.3048)
			(stroke
				(width 0.1)
				(type default)
			)
			(layer "F.Fab")
		)
		(fp_line
			(start 0.12065 -0.2794)
			(end 0.12065 -0.3048)
			(stroke
				(width 0.1)
				(type default)
			)
			(layer "F.Fab")
		)
		(fp_line
			(start 0.67945 -0.3048)
			(end 0.67945 0.3048)
			(stroke
				(width 0.1)
				(type default)
			)
			(layer "F.Fab")
		)
		(fp_line
			(start 0.67945 0.3048)
			(end 0.120396 0.3048)
			(stroke
				(width 0.1)
				(type default)
			)
			(layer "F.Fab")
		)
		(pad "1" smd circle
			(at -0.40005 0)
			(size 0 0)
			(layers "F.Cu" "F.Mask" "F.Paste")
			(net "PD_MB_FRU_WP")
		)
		(pad "2" smd circle
			(at 0.40005 0)
			(size 0 0)
			(layers "F.Cu" "F.Mask" "F.Paste")
			(net "GND")
		)
	)
	(footprint ""
		(layer "F.Cu")
		(at 286.033718 -367.357152 -90)
		(property "Reference" "PC1352"
			(at 0 0 270)
			(layer "F.SilkS")
			(hide yes)
			(effects
				(font
					(size 1.27 1.27)
				)
			)
		)
		(property "Value" ""
			(at 0 0 270)
			(layer "F.Fab")
			(effects
				(font
					(size 1.27 1.27)
				)
			)
		)
		(duplicate_pad_numbers_are_jumpers no)
		(fp_line
			(start -0.7874 0.4064)
			(end -0.7874 -0.4064)
			(stroke
				(width 0.1524)
				(type default)
			)
			(layer "F.SilkS")
		)
		(fp_line
			(start 0.7874 0.4064)
			(end -0.7874 0.4064)
			(stroke
				(width 0.1524)
				(type default)
			)
			(layer "F.SilkS")
		)
		(fp_line
			(start -0.7874 -0.4064)
			(end 0.7874 -0.4064)
			(stroke
				(width 0.1524)
				(type default)
			)
			(layer "F.SilkS")
		)
		(fp_line
			(start 0.7874 -0.4064)
			(end 0.7874 0.4064)
			(stroke
				(width 0.1524)
				(type default)
			)
			(layer "F.SilkS")
		)
		(fp_line
			(start -0.67945 0.3048)
			(end -0.67945 -0.305054)
			(stroke
				(width 0.1)
				(type default)
			)
			(layer "F.Fab")
		)
		(fp_line
			(start -0.12065 0.3048)
			(end -0.67945 0.3048)
			(stroke
				(width 0.1)
				(type default)
			)
			(layer "F.Fab")
		)
		(fp_line
			(start 0.120396 0.3048)
			(end 0.120396 0.2794)
			(stroke
				(width 0.1)
				(type default)
			)
			(layer "F.Fab")
		)
		(fp_line
			(start 0.67945 0.3048)
			(end 0.120396 0.3048)
			(stroke
				(width 0.1)
				(type default)
			)
			(layer "F.Fab")
		)
		(fp_line
			(start -0.12065 0.2794)
			(end -0.12065 0.3048)
			(stroke
				(width 0.1)
				(type default)
			)
			(layer "F.Fab")
		)
		(fp_line
			(start 0.120396 0.2794)
			(end -0.12065 0.2794)
			(stroke
				(width 0.1)
				(type default)
			)
			(layer "F.Fab")
		)
		(fp_line
			(start -0.12065 -0.2794)
			(end 0.12065 -0.2794)
			(stroke
				(width 0.1)
				(type default)
			)
			(layer "F.Fab")
		)
		(fp_line
			(start 0.12065 -0.2794)
			(end 0.12065 -0.3048)
			(stroke
				(width 0.1)
				(type default)
			)
			(layer "F.Fab")
		)
		(fp_line
			(start 0.12065 -0.3048)
			(end 0.67945 -0.3048)
			(stroke
				(width 0.1)
				(type default)
			)
			(layer "F.Fab")
		)
		(fp_line
			(start 0.67945 -0.3048)
			(end 0.67945 0.3048)
			(stroke
				(width 0.1)
				(type default)
			)
			(layer "F.Fab")
		)
		(fp_line
			(start -0.67945 -0.305054)
			(end -0.12065 -0.305054)
			(stroke
				(width 0.1)
				(type default)
			)
			(layer "F.Fab")
		)
		(fp_line
			(start -0.12065 -0.305054)
			(end -0.12065 -0.2794)
			(stroke
				(width 0.1)
				(type default)
			)
			(layer "F.Fab")
		)
		(pad "1" smd circle
			(at -0.40005 0 270)
			(size 0 0)
			(layers "F.Cu" "F.Mask" "F.Paste")
			(net "GND")
		)
		(pad "2" smd circle
			(at 0.40005 0 270)
			(size 0 0)
			(layers "F.Cu" "F.Mask" "F.Paste")
			(net "PVCCIN_CPU0_VREF")
		)
	)
	(footprint ""
		(layer "F.Cu")
		(at 128.401572 -132.034026)
		(property "Reference" "R2565"
			(at 0 0 0)
			(layer "F.SilkS")
			(hide yes)
			(effects
				(font
					(size 1.27 1.27)
				)
			)
		)
		(property "Value" ""
			(at 0 0 0)
			(layer "F.Fab")
			(effects
				(font
					(size 1.27 1.27)
				)
			)
		)
		(duplicate_pad_numbers_are_jumpers no)
		(fp_line
			(start -0.7874 -0.4064)
			(end 0.7874 -0.4064)
			(stroke
				(width 0.1524)
				(type default)
			)
			(layer "F.SilkS")
		)
		(fp_line
			(start -0.7874 0.4064)
			(end -0.7874 -0.4064)
			(stroke
				(width 0.1524)
				(type default)
			)
			(layer "F.SilkS")
		)
		(fp_line
			(start 0.7874 -0.4064)
			(end 0.7874 0.4064)
			(stroke
				(width 0.1524)
				(type default)
			)
			(layer "F.SilkS")
		)
		(fp_line
			(start 0.7874 0.4064)
			(end -0.7874 0.4064)
			(stroke
				(width 0.1524)
				(type default)
			)
			(layer "F.SilkS")
		)
		(fp_line
			(start -0.67945 -0.305054)
			(end -0.12065 -0.305054)
			(stroke
				(width 0.1)
				(type default)
			)
			(layer "F.Fab")
		)
		(fp_line
			(start -0.67945 0.3048)
			(end -0.67945 -0.305054)
			(stroke
				(width 0.1)
				(type default)
			)
			(layer "F.Fab")
		)
		(fp_line
			(start -0.12065 -0.305054)
			(end -0.12065 -0.2794)
			(stroke
				(width 0.1)
				(type default)
			)
			(layer "F.Fab")
		)
		(fp_line
			(start -0.12065 -0.2794)
			(end 0.12065 -0.2794)
			(stroke
				(width 0.1)
				(type default)
			)
			(layer "F.Fab")
		)
		(fp_line
			(start -0.12065 0.2794)
			(end -0.12065 0.3048)
			(stroke
				(width 0.1)
				(type default)
			)
			(layer "F.Fab")
		)
		(fp_line
			(start -0.12065 0.3048)
			(end -0.67945 0.3048)
			(stroke
				(width 0.1)
				(type default)
			)
			(layer "F.Fab")
		)
		(fp_line
			(start 0.120396 0.2794)
			(end -0.12065 0.2794)
			(stroke
				(width 0.1)
				(type default)
			)
			(layer "F.Fab")
		)
		(fp_line
			(start 0.120396 0.3048)
			(end 0.120396 0.2794)
			(stroke
				(width 0.1)
				(type default)
			)
			(layer "F.Fab")
		)
		(fp_line
			(start 0.12065 -0.3048)
			(end 0.67945 -0.3048)
			(stroke
				(width 0.1)
				(type default)
			)
			(layer "F.Fab")
		)
		(fp_line
			(start 0.12065 -0.2794)
			(end 0.12065 -0.3048)
			(stroke
				(width 0.1)
				(type default)
			)
			(layer "F.Fab")
		)
		(fp_line
			(start 0.67945 -0.3048)
			(end 0.67945 0.3048)
			(stroke
				(width 0.1)
				(type default)
			)
			(layer "F.Fab")
		)
		(fp_line
			(start 0.67945 0.3048)
			(end 0.120396 0.3048)
			(stroke
				(width 0.1)
				(type default)
			)
			(layer "F.Fab")
		)
		(pad "1" smd circle
			(at -0.40005 0)
			(size 0 0)
			(layers "F.Cu" "F.Mask" "F.Paste")
			(net "SMB_FRU_3V3AUX_SCL_R")
		)
		(pad "2" smd circle
			(at 0.40005 0)
			(size 0 0)
			(layers "F.Cu" "F.Mask" "F.Paste")
			(net "SMB_FRU_3V3AUX_SCL")
		)
	)
	(footprint ""
		(layer "F.Cu")
		(at 215.646 -111.6838 90)
		(property "Reference" "R4779"
			(at 0 0 90)
			(layer "F.SilkS")
			(hide yes)
			(effects
				(font
					(size 1.27 1.27)
				)
			)
		)
		(property "Value" ""
			(at 0 0 90)
			(layer "F.Fab")
			(effects
				(font
					(size 1.27 1.27)
				)
			)
		)
		(duplicate_pad_numbers_are_jumpers no)
		(fp_line
			(start 0.7874 -0.4064)
			(end 0.7874 0.4064)
			(stroke
				(width 0.1524)
				(type default)
			)
			(layer "F.SilkS")
		)
		(fp_line
			(start -0.7874 -0.4064)
			(end 0.7874 -0.4064)
			(stroke
				(width 0.1524)
				(type default)
			)
			(layer "F.SilkS")
		)
		(fp_line
			(start 0.7874 0.4064)
			(end -0.7874 0.4064)
			(stroke
				(width 0.1524)
				(type default)
			)
			(layer "F.SilkS")
		)
		(fp_line
			(start -0.7874 0.4064)
			(end -0.7874 -0.4064)
			(stroke
				(width 0.1524)
				(type default)
			)
			(layer "F.SilkS")
		)
		(fp_line
			(start -0.12065 -0.305054)
			(end -0.12065 -0.2794)
			(stroke
				(width 0.1)
				(type default)
			)
			(layer "F.Fab")
		)
		(fp_line
			(start -0.67945 -0.305054)
			(end -0.12065 -0.305054)
			(stroke
				(width 0.1)
				(type default)
			)
			(layer "F.Fab")
		)
		(fp_line
			(start 0.67945 -0.3048)
			(end 0.67945 0.3048)
			(stroke
				(width 0.1)
				(type default)
			)
			(layer "F.Fab")
		)
		(fp_line
			(start 0.12065 -0.3048)
			(end 0.67945 -0.3048)
			(stroke
				(width 0.1)
				(type default)
			)
			(layer "F.Fab")
		)
		(fp_line
			(start 0.12065 -0.2794)
			(end 0.12065 -0.3048)
			(stroke
				(width 0.1)
				(type default)
			)
			(layer "F.Fab")
		)
		(fp_line
			(start -0.12065 -0.2794)
			(end 0.12065 -0.2794)
			(stroke
				(width 0.1)
				(type default)
			)
			(layer "F.Fab")
		)
		(fp_line
			(start 0.120396 0.2794)
			(end -0.12065 0.2794)
			(stroke
				(width 0.1)
				(type default)
			)
			(layer "F.Fab")
		)
		(fp_line
			(start -0.12065 0.2794)
			(end -0.12065 0.3048)
			(stroke
				(width 0.1)
				(type default)
			)
			(layer "F.Fab")
		)
		(fp_line
			(start 0.67945 0.3048)
			(end 0.120396 0.3048)
			(stroke
				(width 0.1)
				(type default)
			)
			(layer "F.Fab")
		)
		(fp_line
			(start 0.120396 0.3048)
			(end 0.120396 0.2794)
			(stroke
				(width 0.1)
				(type default)
			)
			(layer "F.Fab")
		)
		(fp_line
			(start -0.12065 0.3048)
			(end -0.67945 0.3048)
			(stroke
				(width 0.1)
				(type default)
			)
			(layer "F.Fab")
		)
		(fp_line
			(start -0.67945 0.3048)
			(end -0.67945 -0.305054)
			(stroke
				(width 0.1)
				(type default)
			)
			(layer "F.Fab")
		)
		(pad "1" smd circle
			(at -0.40005 0 90)
			(size 0 0)
			(layers "F.Cu" "F.Mask" "F.Paste")
			(net "P12V_AUX_UV_TRIGGER")
		)
		(pad "2" smd circle
			(at 0.40005 0 90)
			(size 0 0)
			(layers "F.Cu" "F.Mask" "F.Paste")
			(net "IRQ_UV_DETECT_R2_N")
		)
	)
	(footprint ""
		(layer "F.Cu")
		(at 294.899588 -362.584746 -90)
		(property "Reference" "PC1212_P0_2"
			(at 0 0 270)
			(layer "F.SilkS")
			(hide yes)
			(effects
				(font
					(size 1.27 1.27)
				)
			)
		)
		(property "Value" ""
			(at 0 0 270)
			(layer "F.Fab")
			(effects
				(font
					(size 1.27 1.27)
				)
			)
		)
		(duplicate_pad_numbers_are_jumpers no)
		(fp_line
			(start -0.7874 0.4064)
			(end -0.7874 -0.4064)
			(stroke
				(width 0.1524)
				(type default)
			)
			(layer "F.SilkS")
		)
		(fp_line
			(start 0.7874 0.4064)
			(end -0.7874 0.4064)
			(stroke
				(width 0.1524)
				(type default)
			)
			(layer "F.SilkS")
		)
		(fp_line
			(start -0.7874 -0.4064)
			(end 0.7874 -0.4064)
			(stroke
				(width 0.1524)
				(type default)
			)
			(layer "F.SilkS")
		)
		(fp_line
			(start 0.7874 -0.4064)
			(end 0.7874 0.4064)
			(stroke
				(width 0.1524)
				(type default)
			)
			(layer "F.SilkS")
		)
		(fp_line
			(start -0.67945 0.3048)
			(end -0.67945 -0.305054)
			(stroke
				(width 0.1)
				(type default)
			)
			(layer "F.Fab")
		)
		(fp_line
			(start -0.12065 0.3048)
			(end -0.67945 0.3048)
			(stroke
				(width 0.1)
				(type default)
			)
			(layer "F.Fab")
		)
		(fp_line
			(start 0.120396 0.3048)
			(end 0.120396 0.2794)
			(stroke
				(width 0.1)
				(type default)
			)
			(layer "F.Fab")
		)
		(fp_line
			(start 0.67945 0.3048)
			(end 0.120396 0.3048)
			(stroke
				(width 0.1)
				(type default)
			)
			(layer "F.Fab")
		)
		(fp_line
			(start -0.12065 0.2794)
			(end -0.12065 0.3048)
			(stroke
				(width 0.1)
				(type default)
			)
			(layer "F.Fab")
		)
		(fp_line
			(start 0.120396 0.2794)
			(end -0.12065 0.2794)
			(stroke
				(width 0.1)
				(type default)
			)
			(layer "F.Fab")
		)
		(fp_line
			(start -0.12065 -0.2794)
			(end 0.12065 -0.2794)
			(stroke
				(width 0.1)
				(type default)
			)
			(layer "F.Fab")
		)
		(fp_line
			(start 0.12065 -0.2794)
			(end 0.12065 -0.3048)
			(stroke
				(width 0.1)
				(type default)
			)
			(layer "F.Fab")
		)
		(fp_line
			(start 0.12065 -0.3048)
			(end 0.67945 -0.3048)
			(stroke
				(width 0.1)
				(type default)
			)
			(layer "F.Fab")
		)
		(fp_line
			(start 0.67945 -0.3048)
			(end 0.67945 0.3048)
			(stroke
				(width 0.1)
				(type default)
			)
			(layer "F.Fab")
		)
		(fp_line
			(start -0.67945 -0.305054)
			(end -0.12065 -0.305054)
			(stroke
				(width 0.1)
				(type default)
			)
			(layer "F.Fab")
		)
		(fp_line
			(start -0.12065 -0.305054)
			(end -0.12065 -0.2794)
			(stroke
				(width 0.1)
				(type default)
			)
			(layer "F.Fab")
		)
		(pad "1" smd circle
			(at -0.40005 0 270)
			(size 0 0)
			(layers "F.Cu" "F.Mask" "F.Paste")
			(net "PVCCFA_EHV_FIVRA_CPU0_PVCC2")
		)
		(pad "2" smd circle
			(at 0.40005 0 270)
			(size 0 0)
			(layers "F.Cu" "F.Mask" "F.Paste")
			(net "GND")
		)
	)
	(footprint ""
		(layer "F.Cu")
		(at 275.323046 -15.093188)
		(property "Reference" "U219"
			(at -5.59308 0.464312 0)
			(unlocked yes)
			(layer "F.SilkS")
			(effects
				(font
					(size 0.7874 0.5842)
					(thickness 0.1524)
				)
				(justify left)
			)
		)
		(property "Value" ""
			(at 0 0 0)
			(layer "F.Fab")
			(effects
				(font
					(size 1.27 1.27)
				)
			)
		)
		(duplicate_pad_numbers_are_jumpers no)
		(fp_line
			(start -1.733296 -1.549908)
			(end -1.733296 1.549908)
			(stroke
				(width 0.1524)
				(type default)
			)
			(layer "F.SilkS")
		)
		(fp_line
			(start -1.733296 1.549908)
			(end 1.733296 1.549908)
			(stroke
				(width 0.1524)
				(type default)
			)
			(layer "F.SilkS")
		)
		(fp_line
			(start -0.660908 -1.549908)
			(end -1.733296 -1.549908)
			(stroke
				(width 0.1524)
				(type default)
			)
			(layer "F.SilkS")
		)
		(fp_line
			(start 0 -0.889)
			(end -0.660908 -1.549908)
			(stroke
				(width 0.1524)
				(type default)
			)
			(layer "F.SilkS")
		)
		(fp_line
			(start 0.660908 -1.549908)
			(end 0 -0.889)
			(stroke
				(width 0.1524)
				(type default)
			)
			(layer "F.SilkS")
		)
		(fp_line
			(start 1.733296 -1.549908)
			(end 0.660908 -1.549908)
			(stroke
				(width 0.1524)
				(type default)
			)
			(layer "F.SilkS")
		)
		(fp_line
			(start 1.733296 1.549908)
			(end 1.733296 -1.549908)
			(stroke
				(width 0.1524)
				(type default)
			)
			(layer "F.SilkS")
		)
		(fp_poly
			(pts
				(xy -2.4384 -1.20396) (xy -1.9304 -0.94996) (xy -2.4384 -0.69596)
			)
			(stroke
				(width 0)
				(type default)
			)
			(fill yes)
			(layer "F.SilkS")
		)
		(fp_line
			(start -0.849884 -1.549908)
			(end -0.849884 1.549908)
			(stroke
				(width 0.1)
				(type default)
			)
			(layer "F.Fab")
		)
		(fp_line
			(start -0.849884 1.549908)
			(end 0.849884 1.549908)
			(stroke
				(width 0.1)
				(type default)
			)
			(layer "F.Fab")
		)
		(fp_line
			(start 0.849884 -1.549908)
			(end -0.849884 -1.549908)
			(stroke
				(width 0.1)
				(type default)
			)
			(layer "F.Fab")
		)
		(fp_line
			(start 0.849884 1.549908)
			(end 0.849884 -1.549908)
			(stroke
				(width 0.1)
				(type default)
			)
			(layer "F.Fab")
		)
		(fp_poly
			(pts
				(xy -2.4384 -1.20396) (xy -2.4384 -0.69596) (xy -1.9304 -0.94996)
			)
			(stroke
				(width 0)
				(type default)
			)
			(fill yes)
			(layer "F.Fab")
		)
		(pad "1" smd rect
			(at -1.199896 -0.94996 270)
			(size 0.5588 0.8128)
			(layers "F.Cu" "F.Mask" "F.Paste")
			(net "NC_U219_NC1")
		)
		(pad "2" smd rect
			(at -1.199896 0 270)
			(size 0.5588 0.8128)
			(layers "F.Cu" "F.Mask" "F.Paste")
			(net "OCP_V3_2_WAKE_BUFF_R_N")
		)
		(pad "3" smd rect
			(at -1.199896 0.94996 270)
			(size 0.5588 0.8128)
			(layers "F.Cu" "F.Mask" "F.Paste")
			(net "GND")
		)
		(pad "4" smd rect
			(at 1.199896 0.94996 270)
			(size 0.5588 0.8128)
			(layers "F.Cu" "F.Mask" "F.Paste")
			(net "IRQ_LVC3_V3_2_WAKE_BUF_N")
		)
		(pad "5" smd rect
			(at 1.199896 -0.94996 270)
			(size 0.5588 0.8128)
			(layers "F.Cu" "F.Mask" "F.Paste")
			(net "P3V3_AUX")
		)
	)
	(footprint ""
		(layer "F.Cu")
		(at 369.190778 -391.797286 180)
		(property "Reference" "R4166"
			(at 0 0 180)
			(layer "F.SilkS")
			(hide yes)
			(effects
				(font
					(size 1.27 1.27)
				)
			)
		)
		(property "Value" ""
			(at 0 0 180)
			(layer "F.Fab")
			(effects
				(font
					(size 1.27 1.27)
				)
			)
		)
		(duplicate_pad_numbers_are_jumpers no)
		(fp_line
			(start 0.7874 0.4064)
			(end -0.7874 0.4064)
			(stroke
				(width 0.1524)
				(type default)
			)
			(layer "F.SilkS")
		)
		(fp_line
			(start 0.7874 -0.4064)
			(end 0.7874 0.4064)
			(stroke
				(width 0.1524)
				(type default)
			)
			(layer "F.SilkS")
		)
		(fp_line
			(start -0.7874 0.4064)
			(end -0.7874 -0.4064)
			(stroke
				(width 0.1524)
				(type default)
			)
			(layer "F.SilkS")
		)
		(fp_line
			(start -0.7874 -0.4064)
			(end 0.7874 -0.4064)
			(stroke
				(width 0.1524)
				(type default)
			)
			(layer "F.SilkS")
		)
		(fp_line
			(start 0.67945 0.3048)
			(end 0.120396 0.3048)
			(stroke
				(width 0.1)
				(type default)
			)
			(layer "F.Fab")
		)
		(fp_line
			(start 0.67945 -0.3048)
			(end 0.67945 0.3048)
			(stroke
				(width 0.1)
				(type default)
			)
			(layer "F.Fab")
		)
		(fp_line
			(start 0.12065 -0.2794)
			(end 0.12065 -0.3048)
			(stroke
				(width 0.1)
				(type default)
			)
			(layer "F.Fab")
		)
		(fp_line
			(start 0.12065 -0.3048)
			(end 0.67945 -0.3048)
			(stroke
				(width 0.1)
				(type default)
			)
			(layer "F.Fab")
		)
		(fp_line
			(start 0.120396 0.3048)
			(end 0.120396 0.2794)
			(stroke
				(width 0.1)
				(type default)
			)
			(layer "F.Fab")
		)
		(fp_line
			(start 0.120396 0.2794)
			(end -0.12065 0.2794)
			(stroke
				(width 0.1)
				(type default)
			)
			(layer "F.Fab")
		)
		(fp_line
			(start -0.12065 0.3048)
			(end -0.67945 0.3048)
			(stroke
				(width 0.1)
				(type default)
			)
			(layer "F.Fab")
		)
		(fp_line
			(start -0.12065 0.2794)
			(end -0.12065 0.3048)
			(stroke
				(width 0.1)
				(type default)
			)
			(layer "F.Fab")
		)
		(fp_line
			(start -0.12065 -0.2794)
			(end 0.12065 -0.2794)
			(stroke
				(width 0.1)
				(type default)
			)
			(layer "F.Fab")
		)
		(fp_line
			(start -0.12065 -0.305054)
			(end -0.12065 -0.2794)
			(stroke
				(width 0.1)
				(type default)
			)
			(layer "F.Fab")
		)
		(fp_line
			(start -0.67945 0.3048)
			(end -0.67945 -0.305054)
			(stroke
				(width 0.1)
				(type default)
			)
			(layer "F.Fab")
		)
		(fp_line
			(start -0.67945 -0.305054)
			(end -0.12065 -0.305054)
			(stroke
				(width 0.1)
				(type default)
			)
			(layer "F.Fab")
		)
		(pad "1" smd circle
			(at -0.40005 0 180)
			(size 0 0)
			(layers "F.Cu" "F.Mask" "F.Paste")
			(net "P3V3_AUX")
		)
		(pad "2" smd circle
			(at 0.40005 0 180)
			(size 0 0)
			(layers "F.Cu" "F.Mask" "F.Paste")
			(net "GPU_3V3IO_RSVD3_N")
		)
	)
	(footprint ""
		(layer "F.Cu")
		(at 279.40762 -426.68698)
		(property "Reference" "C4562"
			(at 0 0 0)
			(layer "F.SilkS")
			(hide yes)
			(effects
				(font
					(size 1.27 1.27)
				)
			)
		)
		(property "Value" ""
			(at 0 0 0)
			(layer "F.Fab")
			(effects
				(font
					(size 1.27 1.27)
				)
			)
		)
		(duplicate_pad_numbers_are_jumpers no)
		(fp_line
			(start -0.7874 -0.4064)
			(end 0.7874 -0.4064)
			(stroke
				(width 0.1524)
				(type default)
			)
			(layer "F.SilkS")
		)
		(fp_line
			(start -0.7874 0.4064)
			(end -0.7874 -0.4064)
			(stroke
				(width 0.1524)
				(type default)
			)
			(layer "F.SilkS")
		)
		(fp_line
			(start 0.7874 -0.4064)
			(end 0.7874 0.4064)
			(stroke
				(width 0.1524)
				(type default)
			)
			(layer "F.SilkS")
		)
		(fp_line
			(start 0.7874 0.4064)
			(end -0.7874 0.4064)
			(stroke
				(width 0.1524)
				(type default)
			)
			(layer "F.SilkS")
		)
		(fp_line
			(start -0.67945 -0.305054)
			(end -0.12065 -0.305054)
			(stroke
				(width 0.1)
				(type default)
			)
			(layer "F.Fab")
		)
		(fp_line
			(start -0.67945 0.3048)
			(end -0.67945 -0.305054)
			(stroke
				(width 0.1)
				(type default)
			)
			(layer "F.Fab")
		)
		(fp_line
			(start -0.12065 -0.305054)
			(end -0.12065 -0.2794)
			(stroke
				(width 0.1)
				(type default)
			)
			(layer "F.Fab")
		)
		(fp_line
			(start -0.12065 -0.2794)
			(end 0.12065 -0.2794)
			(stroke
				(width 0.1)
				(type default)
			)
			(layer "F.Fab")
		)
		(fp_line
			(start -0.12065 0.2794)
			(end -0.12065 0.3048)
			(stroke
				(width 0.1)
				(type default)
			)
			(layer "F.Fab")
		)
		(fp_line
			(start -0.12065 0.3048)
			(end -0.67945 0.3048)
			(stroke
				(width 0.1)
				(type default)
			)
			(layer "F.Fab")
		)
		(fp_line
			(start 0.120396 0.2794)
			(end -0.12065 0.2794)
			(stroke
				(width 0.1)
				(type default)
			)
			(layer "F.Fab")
		)
		(fp_line
			(start 0.120396 0.3048)
			(end 0.120396 0.2794)
			(stroke
				(width 0.1)
				(type default)
			)
			(layer "F.Fab")
		)
		(fp_line
			(start 0.12065 -0.3048)
			(end 0.67945 -0.3048)
			(stroke
				(width 0.1)
				(type default)
			)
			(layer "F.Fab")
		)
		(fp_line
			(start 0.12065 -0.2794)
			(end 0.12065 -0.3048)
			(stroke
				(width 0.1)
				(type default)
			)
			(layer "F.Fab")
		)
		(fp_line
			(start 0.67945 -0.3048)
			(end 0.67945 0.3048)
			(stroke
				(width 0.1)
				(type default)
			)
			(layer "F.Fab")
		)
		(fp_line
			(start 0.67945 0.3048)
			(end 0.120396 0.3048)
			(stroke
				(width 0.1)
				(type default)
			)
			(layer "F.Fab")
		)
		(pad "1" smd circle
			(at -0.40005 0)
			(size 0 0)
			(layers "F.Cu" "F.Mask" "F.Paste")
			(net "U369_VDD")
		)
		(pad "2" smd circle
			(at 0.40005 0)
			(size 0 0)
			(layers "F.Cu" "F.Mask" "F.Paste")
			(net "GND")
		)
	)
	(footprint ""
		(layer "F.Cu")
		(at 172.878242 -28.03779 90)
		(property "Reference" "PR4010"
			(at 0 0 90)
			(layer "F.SilkS")
			(hide yes)
			(effects
				(font
					(size 1.27 1.27)
				)
			)
		)
		(property "Value" ""
			(at 0 0 90)
			(layer "F.Fab")
			(effects
				(font
					(size 1.27 1.27)
				)
			)
		)
		(duplicate_pad_numbers_are_jumpers no)
		(fp_line
			(start 0.7874 -0.4064)
			(end 0.7874 0.4064)
			(stroke
				(width 0.1524)
				(type default)
			)
			(layer "F.SilkS")
		)
		(fp_line
			(start -0.7874 -0.4064)
			(end 0.7874 -0.4064)
			(stroke
				(width 0.1524)
				(type default)
			)
			(layer "F.SilkS")
		)
		(fp_line
			(start 0.7874 0.4064)
			(end -0.7874 0.4064)
			(stroke
				(width 0.1524)
				(type default)
			)
			(layer "F.SilkS")
		)
		(fp_line
			(start -0.7874 0.4064)
			(end -0.7874 -0.4064)
			(stroke
				(width 0.1524)
				(type default)
			)
			(layer "F.SilkS")
		)
		(fp_line
			(start -0.12065 -0.305054)
			(end -0.12065 -0.2794)
			(stroke
				(width 0.1)
				(type default)
			)
			(layer "F.Fab")
		)
		(fp_line
			(start -0.67945 -0.305054)
			(end -0.12065 -0.305054)
			(stroke
				(width 0.1)
				(type default)
			)
			(layer "F.Fab")
		)
		(fp_line
			(start 0.67945 -0.3048)
			(end 0.67945 0.3048)
			(stroke
				(width 0.1)
				(type default)
			)
			(layer "F.Fab")
		)
		(fp_line
			(start 0.12065 -0.3048)
			(end 0.67945 -0.3048)
			(stroke
				(width 0.1)
				(type default)
			)
			(layer "F.Fab")
		)
		(fp_line
			(start 0.12065 -0.2794)
			(end 0.12065 -0.3048)
			(stroke
				(width 0.1)
				(type default)
			)
			(layer "F.Fab")
		)
		(fp_line
			(start -0.12065 -0.2794)
			(end 0.12065 -0.2794)
			(stroke
				(width 0.1)
				(type default)
			)
			(layer "F.Fab")
		)
		(fp_line
			(start 0.120396 0.2794)
			(end -0.12065 0.2794)
			(stroke
				(width 0.1)
				(type default)
			)
			(layer "F.Fab")
		)
		(fp_line
			(start -0.12065 0.2794)
			(end -0.12065 0.3048)
			(stroke
				(width 0.1)
				(type default)
			)
			(layer "F.Fab")
		)
		(fp_line
			(start 0.67945 0.3048)
			(end 0.120396 0.3048)
			(stroke
				(width 0.1)
				(type default)
			)
			(layer "F.Fab")
		)
		(fp_line
			(start 0.120396 0.3048)
			(end 0.120396 0.2794)
			(stroke
				(width 0.1)
				(type default)
			)
			(layer "F.Fab")
		)
		(fp_line
			(start -0.12065 0.3048)
			(end -0.67945 0.3048)
			(stroke
				(width 0.1)
				(type default)
			)
			(layer "F.Fab")
		)
		(fp_line
			(start -0.67945 0.3048)
			(end -0.67945 -0.305054)
			(stroke
				(width 0.1)
				(type default)
			)
			(layer "F.Fab")
		)
		(pad "1" smd circle
			(at -0.40005 0 90)
			(size 0 0)
			(layers "F.Cu" "F.Mask" "F.Paste")
			(net "P12V_AUX")
		)
		(pad "2" smd circle
			(at 0.40005 0 90)
			(size 0 0)
			(layers "F.Cu" "F.Mask" "F.Paste")
			(net "P12V_SCM_OV_FB")
		)
	)
	(footprint ""
		(layer "F.Cu")
		(at 152.96388 -129.758948 180)
		(property "Reference" "R3206"
			(at 0 0 180)
			(layer "F.SilkS")
			(hide yes)
			(effects
				(font
					(size 1.27 1.27)
				)
			)
		)
		(property "Value" ""
			(at 0 0 180)
			(layer "F.Fab")
			(effects
				(font
					(size 1.27 1.27)
				)
			)
		)
		(duplicate_pad_numbers_are_jumpers no)
		(fp_line
			(start 0.7874 0.4064)
			(end -0.7874 0.4064)
			(stroke
				(width 0.1524)
				(type default)
			)
			(layer "F.SilkS")
		)
		(fp_line
			(start 0.7874 -0.4064)
			(end 0.7874 0.4064)
			(stroke
				(width 0.1524)
				(type default)
			)
			(layer "F.SilkS")
		)
		(fp_line
			(start -0.7874 0.4064)
			(end -0.7874 -0.4064)
			(stroke
				(width 0.1524)
				(type default)
			)
			(layer "F.SilkS")
		)
		(fp_line
			(start -0.7874 -0.4064)
			(end 0.7874 -0.4064)
			(stroke
				(width 0.1524)
				(type default)
			)
			(layer "F.SilkS")
		)
		(fp_line
			(start 0.67945 0.3048)
			(end 0.120396 0.3048)
			(stroke
				(width 0.1)
				(type default)
			)
			(layer "F.Fab")
		)
		(fp_line
			(start 0.67945 -0.3048)
			(end 0.67945 0.3048)
			(stroke
				(width 0.1)
				(type default)
			)
			(layer "F.Fab")
		)
		(fp_line
			(start 0.12065 -0.2794)
			(end 0.12065 -0.3048)
			(stroke
				(width 0.1)
				(type default)
			)
			(layer "F.Fab")
		)
		(fp_line
			(start 0.12065 -0.3048)
			(end 0.67945 -0.3048)
			(stroke
				(width 0.1)
				(type default)
			)
			(layer "F.Fab")
		)
		(fp_line
			(start 0.120396 0.3048)
			(end 0.120396 0.2794)
			(stroke
				(width 0.1)
				(type default)
			)
			(layer "F.Fab")
		)
		(fp_line
			(start 0.120396 0.2794)
			(end -0.12065 0.2794)
			(stroke
				(width 0.1)
				(type default)
			)
			(layer "F.Fab")
		)
		(fp_line
			(start -0.12065 0.3048)
			(end -0.67945 0.3048)
			(stroke
				(width 0.1)
				(type default)
			)
			(layer "F.Fab")
		)
		(fp_line
			(start -0.12065 0.2794)
			(end -0.12065 0.3048)
			(stroke
				(width 0.1)
				(type default)
			)
			(layer "F.Fab")
		)
		(fp_line
			(start -0.12065 -0.2794)
			(end 0.12065 -0.2794)
			(stroke
				(width 0.1)
				(type default)
			)
			(layer "F.Fab")
		)
		(fp_line
			(start -0.12065 -0.305054)
			(end -0.12065 -0.2794)
			(stroke
				(width 0.1)
				(type default)
			)
			(layer "F.Fab")
		)
		(fp_line
			(start -0.67945 0.3048)
			(end -0.67945 -0.305054)
			(stroke
				(width 0.1)
				(type default)
			)
			(layer "F.Fab")
		)
		(fp_line
			(start -0.67945 -0.305054)
			(end -0.12065 -0.305054)
			(stroke
				(width 0.1)
				(type default)
			)
			(layer "F.Fab")
		)
		(pad "1" smd circle
			(at -0.40005 0 180)
			(size 0 0)
			(layers "F.Cu" "F.Mask" "F.Paste")
			(net "FM_NCSI_OCP_V3_2_R_OE")
		)
		(pad "2" smd circle
			(at 0.40005 0 180)
			(size 0 0)
			(layers "F.Cu" "F.Mask" "F.Paste")
			(net "FB_BMC_ISOLATE1")
		)
	)
	(footprint ""
		(layer "F.Cu")
		(at 187.28944 -355.90607)
		(property "Reference" "PC1681"
			(at 0 0 0)
			(layer "F.SilkS")
			(hide yes)
			(effects
				(font
					(size 1.27 1.27)
				)
			)
		)
		(property "Value" ""
			(at 0 0 0)
			(layer "F.Fab")
			(effects
				(font
					(size 1.27 1.27)
				)
			)
		)
		(duplicate_pad_numbers_are_jumpers no)
		(fp_line
			(start -1.524 -0.762)
			(end 1.524 -0.762)
			(stroke
				(width 0.1524)
				(type default)
			)
			(layer "F.SilkS")
		)
		(fp_line
			(start -1.524 0.762)
			(end -1.524 -0.762)
			(stroke
				(width 0.1524)
				(type default)
			)
			(layer "F.SilkS")
		)
		(fp_line
			(start 1.524 -0.762)
			(end 1.524 0.762)
			(stroke
				(width 0.1524)
				(type default)
			)
			(layer "F.SilkS")
		)
		(fp_line
			(start 1.524 0.762)
			(end -1.524 0.762)
			(stroke
				(width 0.1524)
				(type default)
			)
			(layer "F.SilkS")
		)
		(fp_line
			(start -1.1049 -0.724916)
			(end -1.1049 0.724916)
			(stroke
				(width 0.1)
				(type default)
			)
			(layer "F.Fab")
		)
		(fp_line
			(start -1.1049 0.724916)
			(end 1.1049 0.724916)
			(stroke
				(width 0.1)
				(type default)
			)
			(layer "F.Fab")
		)
		(fp_line
			(start 1.1049 -0.724916)
			(end -1.1049 -0.724916)
			(stroke
				(width 0.1)
				(type default)
			)
			(layer "F.Fab")
		)
		(fp_line
			(start 1.1049 0.724916)
			(end 1.1049 -0.724916)
			(stroke
				(width 0.1)
				(type default)
			)
			(layer "F.Fab")
		)
		(pad "1" smd rect
			(at -0.889 0 180)
			(size 1.016 1.27)
			(layers "F.Cu" "F.Mask" "F.Paste")
			(net "SW_P12V_PVCCFA_EHV_FIVRA_CPU1_R")
		)
		(pad "2" smd rect
			(at 0.889 0 180)
			(size 1.016 1.27)
			(layers "F.Cu" "F.Mask" "F.Paste")
			(net "GND")
		)
	)
	(footprint ""
		(layer "F.Cu")
		(at 221.67088 -44.922948 180)
		(property "Reference" "R3532"
			(at 0 0 180)
			(layer "F.SilkS")
			(hide yes)
			(effects
				(font
					(size 1.27 1.27)
				)
			)
		)
		(property "Value" ""
			(at 0 0 180)
			(layer "F.Fab")
			(effects
				(font
					(size 1.27 1.27)
				)
			)
		)
		(duplicate_pad_numbers_are_jumpers no)
		(fp_line
			(start 0.7874 0.4064)
			(end -0.7874 0.4064)
			(stroke
				(width 0.1524)
				(type default)
			)
			(layer "F.SilkS")
		)
		(fp_line
			(start 0.7874 -0.4064)
			(end 0.7874 0.4064)
			(stroke
				(width 0.1524)
				(type default)
			)
			(layer "F.SilkS")
		)
		(fp_line
			(start -0.7874 0.4064)
			(end -0.7874 -0.4064)
			(stroke
				(width 0.1524)
				(type default)
			)
			(layer "F.SilkS")
		)
		(fp_line
			(start -0.7874 -0.4064)
			(end 0.7874 -0.4064)
			(stroke
				(width 0.1524)
				(type default)
			)
			(layer "F.SilkS")
		)
		(fp_line
			(start 0.67945 0.3048)
			(end 0.120396 0.3048)
			(stroke
				(width 0.1)
				(type default)
			)
			(layer "F.Fab")
		)
		(fp_line
			(start 0.67945 -0.3048)
			(end 0.67945 0.3048)
			(stroke
				(width 0.1)
				(type default)
			)
			(layer "F.Fab")
		)
		(fp_line
			(start 0.12065 -0.2794)
			(end 0.12065 -0.3048)
			(stroke
				(width 0.1)
				(type default)
			)
			(layer "F.Fab")
		)
		(fp_line
			(start 0.12065 -0.3048)
			(end 0.67945 -0.3048)
			(stroke
				(width 0.1)
				(type default)
			)
			(layer "F.Fab")
		)
		(fp_line
			(start 0.120396 0.3048)
			(end 0.120396 0.2794)
			(stroke
				(width 0.1)
				(type default)
			)
			(layer "F.Fab")
		)
		(fp_line
			(start 0.120396 0.2794)
			(end -0.12065 0.2794)
			(stroke
				(width 0.1)
				(type default)
			)
			(layer "F.Fab")
		)
		(fp_line
			(start -0.12065 0.3048)
			(end -0.67945 0.3048)
			(stroke
				(width 0.1)
				(type default)
			)
			(layer "F.Fab")
		)
		(fp_line
			(start -0.12065 0.2794)
			(end -0.12065 0.3048)
			(stroke
				(width 0.1)
				(type default)
			)
			(layer "F.Fab")
		)
		(fp_line
			(start -0.12065 -0.2794)
			(end 0.12065 -0.2794)
			(stroke
				(width 0.1)
				(type default)
			)
			(layer "F.Fab")
		)
		(fp_line
			(start -0.12065 -0.305054)
			(end -0.12065 -0.2794)
			(stroke
				(width 0.1)
				(type default)
			)
			(layer "F.Fab")
		)
		(fp_line
			(start -0.67945 0.3048)
			(end -0.67945 -0.305054)
			(stroke
				(width 0.1)
				(type default)
			)
			(layer "F.Fab")
		)
		(fp_line
			(start -0.67945 -0.305054)
			(end -0.12065 -0.305054)
			(stroke
				(width 0.1)
				(type default)
			)
			(layer "F.Fab")
		)
		(pad "1" smd circle
			(at -0.40005 0 180)
			(size 0 0)
			(layers "F.Cu" "F.Mask" "F.Paste")
			(net "P3V3_E1S_0")
		)
		(pad "2" smd circle
			(at 0.40005 0 180)
			(size 0 0)
			(layers "F.Cu" "F.Mask" "F.Paste")
			(net "SMB_E1S_3V3AUX_ISO_SDA_R")
		)
	)
	(footprint ""
		(layer "F.Cu")
		(at 118.542816 -238.162592 90)
		(property "Reference" "C438"
			(at 0 0 90)
			(layer "F.SilkS")
			(hide yes)
			(effects
				(font
					(size 1.27 1.27)
				)
			)
		)
		(property "Value" ""
			(at 0 0 90)
			(layer "F.Fab")
			(effects
				(font
					(size 1.27 1.27)
				)
			)
		)
		(duplicate_pad_numbers_are_jumpers no)
		(fp_line
			(start 0.7874 -0.4064)
			(end 0.7874 0.4064)
			(stroke
				(width 0.1524)
				(type default)
			)
			(layer "F.SilkS")
		)
		(fp_line
			(start -0.7874 -0.4064)
			(end 0.7874 -0.4064)
			(stroke
				(width 0.1524)
				(type default)
			)
			(layer "F.SilkS")
		)
		(fp_line
			(start 0.7874 0.4064)
			(end -0.7874 0.4064)
			(stroke
				(width 0.1524)
				(type default)
			)
			(layer "F.SilkS")
		)
		(fp_line
			(start -0.7874 0.4064)
			(end -0.7874 -0.4064)
			(stroke
				(width 0.1524)
				(type default)
			)
			(layer "F.SilkS")
		)
		(fp_line
			(start -0.12065 -0.305054)
			(end -0.12065 -0.2794)
			(stroke
				(width 0.1)
				(type default)
			)
			(layer "F.Fab")
		)
		(fp_line
			(start -0.67945 -0.305054)
			(end -0.12065 -0.305054)
			(stroke
				(width 0.1)
				(type default)
			)
			(layer "F.Fab")
		)
		(fp_line
			(start 0.67945 -0.3048)
			(end 0.67945 0.3048)
			(stroke
				(width 0.1)
				(type default)
			)
			(layer "F.Fab")
		)
		(fp_line
			(start 0.12065 -0.3048)
			(end 0.67945 -0.3048)
			(stroke
				(width 0.1)
				(type default)
			)
			(layer "F.Fab")
		)
		(fp_line
			(start 0.12065 -0.2794)
			(end 0.12065 -0.3048)
			(stroke
				(width 0.1)
				(type default)
			)
			(layer "F.Fab")
		)
		(fp_line
			(start -0.12065 -0.2794)
			(end 0.12065 -0.2794)
			(stroke
				(width 0.1)
				(type default)
			)
			(layer "F.Fab")
		)
		(fp_line
			(start 0.120396 0.2794)
			(end -0.12065 0.2794)
			(stroke
				(width 0.1)
				(type default)
			)
			(layer "F.Fab")
		)
		(fp_line
			(start -0.12065 0.2794)
			(end -0.12065 0.3048)
			(stroke
				(width 0.1)
				(type default)
			)
			(layer "F.Fab")
		)
		(fp_line
			(start 0.67945 0.3048)
			(end 0.120396 0.3048)
			(stroke
				(width 0.1)
				(type default)
			)
			(layer "F.Fab")
		)
		(fp_line
			(start 0.120396 0.3048)
			(end 0.120396 0.2794)
			(stroke
				(width 0.1)
				(type default)
			)
			(layer "F.Fab")
		)
		(fp_line
			(start -0.12065 0.3048)
			(end -0.67945 0.3048)
			(stroke
				(width 0.1)
				(type default)
			)
			(layer "F.Fab")
		)
		(fp_line
			(start -0.67945 0.3048)
			(end -0.67945 -0.305054)
			(stroke
				(width 0.1)
				(type default)
			)
			(layer "F.Fab")
		)
		(pad "1" smd circle
			(at -0.40005 0 90)
			(size 0 0)
			(layers "F.Cu" "F.Mask" "F.Paste")
			(net "PVCCINFAON_CPU1")
		)
		(pad "2" smd circle
			(at 0.40005 0 90)
			(size 0 0)
			(layers "F.Cu" "F.Mask" "F.Paste")
			(net "GND")
		)
	)
	(footprint ""
		(layer "F.Cu")
		(at 101.071172 -362.602526)
		(property "Reference" "R2455"
			(at 0 0 0)
			(layer "F.SilkS")
			(hide yes)
			(effects
				(font
					(size 1.27 1.27)
				)
			)
		)
		(property "Value" ""
			(at 0 0 0)
			(layer "F.Fab")
			(effects
				(font
					(size 1.27 1.27)
				)
			)
		)
		(duplicate_pad_numbers_are_jumpers no)
		(fp_line
			(start -0.7874 -0.4064)
			(end 0.7874 -0.4064)
			(stroke
				(width 0.1524)
				(type default)
			)
			(layer "F.SilkS")
		)
		(fp_line
			(start -0.7874 0.4064)
			(end -0.7874 -0.4064)
			(stroke
				(width 0.1524)
				(type default)
			)
			(layer "F.SilkS")
		)
		(fp_line
			(start 0.7874 -0.4064)
			(end 0.7874 0.4064)
			(stroke
				(width 0.1524)
				(type default)
			)
			(layer "F.SilkS")
		)
		(fp_line
			(start 0.7874 0.4064)
			(end -0.7874 0.4064)
			(stroke
				(width 0.1524)
				(type default)
			)
			(layer "F.SilkS")
		)
		(fp_line
			(start -0.67945 -0.305054)
			(end -0.12065 -0.305054)
			(stroke
				(width 0.1)
				(type default)
			)
			(layer "F.Fab")
		)
		(fp_line
			(start -0.67945 0.3048)
			(end -0.67945 -0.305054)
			(stroke
				(width 0.1)
				(type default)
			)
			(layer "F.Fab")
		)
		(fp_line
			(start -0.12065 -0.305054)
			(end -0.12065 -0.2794)
			(stroke
				(width 0.1)
				(type default)
			)
			(layer "F.Fab")
		)
		(fp_line
			(start -0.12065 -0.2794)
			(end 0.12065 -0.2794)
			(stroke
				(width 0.1)
				(type default)
			)
			(layer "F.Fab")
		)
		(fp_line
			(start -0.12065 0.2794)
			(end -0.12065 0.3048)
			(stroke
				(width 0.1)
				(type default)
			)
			(layer "F.Fab")
		)
		(fp_line
			(start -0.12065 0.3048)
			(end -0.67945 0.3048)
			(stroke
				(width 0.1)
				(type default)
			)
			(layer "F.Fab")
		)
		(fp_line
			(start 0.120396 0.2794)
			(end -0.12065 0.2794)
			(stroke
				(width 0.1)
				(type default)
			)
			(layer "F.Fab")
		)
		(fp_line
			(start 0.120396 0.3048)
			(end 0.120396 0.2794)
			(stroke
				(width 0.1)
				(type default)
			)
			(layer "F.Fab")
		)
		(fp_line
			(start 0.12065 -0.3048)
			(end 0.67945 -0.3048)
			(stroke
				(width 0.1)
				(type default)
			)
			(layer "F.Fab")
		)
		(fp_line
			(start 0.12065 -0.2794)
			(end 0.12065 -0.3048)
			(stroke
				(width 0.1)
				(type default)
			)
			(layer "F.Fab")
		)
		(fp_line
			(start 0.67945 -0.3048)
			(end 0.67945 0.3048)
			(stroke
				(width 0.1)
				(type default)
			)
			(layer "F.Fab")
		)
		(fp_line
			(start 0.67945 0.3048)
			(end 0.120396 0.3048)
			(stroke
				(width 0.1)
				(type default)
			)
			(layer "F.Fab")
		)
		(pad "1" smd circle
			(at -0.40005 0)
			(size 0 0)
			(layers "F.Cu" "F.Mask" "F.Paste")
			(net "SMB_VR_3V3AUX_SCL_R")
		)
		(pad "2" smd circle
			(at 0.40005 0)
			(size 0 0)
			(layers "F.Cu" "F.Mask" "F.Paste")
			(net "SMB_VR_3V3AUX_SCL_R3")
		)
	)
	(footprint ""
		(layer "F.Cu")
		(at 336.018124 -25.070562 -90)
		(property "Reference" "R1479"
			(at 0 0 270)
			(layer "F.SilkS")
			(hide yes)
			(effects
				(font
					(size 1.27 1.27)
				)
			)
		)
		(property "Value" ""
			(at 0 0 270)
			(layer "F.Fab")
			(effects
				(font
					(size 1.27 1.27)
				)
			)
		)
		(duplicate_pad_numbers_are_jumpers no)
		(fp_line
			(start -0.7874 0.4064)
			(end -0.7874 -0.4064)
			(stroke
				(width 0.1524)
				(type default)
			)
			(layer "F.SilkS")
		)
		(fp_line
			(start 0.7874 0.4064)
			(end -0.7874 0.4064)
			(stroke
				(width 0.1524)
				(type default)
			)
			(layer "F.SilkS")
		)
		(fp_line
			(start -0.7874 -0.4064)
			(end 0.7874 -0.4064)
			(stroke
				(width 0.1524)
				(type default)
			)
			(layer "F.SilkS")
		)
		(fp_line
			(start 0.7874 -0.4064)
			(end 0.7874 0.4064)
			(stroke
				(width 0.1524)
				(type default)
			)
			(layer "F.SilkS")
		)
		(fp_line
			(start -0.67945 0.3048)
			(end -0.67945 -0.305054)
			(stroke
				(width 0.1)
				(type default)
			)
			(layer "F.Fab")
		)
		(fp_line
			(start -0.12065 0.3048)
			(end -0.67945 0.3048)
			(stroke
				(width 0.1)
				(type default)
			)
			(layer "F.Fab")
		)
		(fp_line
			(start 0.120396 0.3048)
			(end 0.120396 0.2794)
			(stroke
				(width 0.1)
				(type default)
			)
			(layer "F.Fab")
		)
		(fp_line
			(start 0.67945 0.3048)
			(end 0.120396 0.3048)
			(stroke
				(width 0.1)
				(type default)
			)
			(layer "F.Fab")
		)
		(fp_line
			(start -0.12065 0.2794)
			(end -0.12065 0.3048)
			(stroke
				(width 0.1)
				(type default)
			)
			(layer "F.Fab")
		)
		(fp_line
			(start 0.120396 0.2794)
			(end -0.12065 0.2794)
			(stroke
				(width 0.1)
				(type default)
			)
			(layer "F.Fab")
		)
		(fp_line
			(start -0.12065 -0.2794)
			(end 0.12065 -0.2794)
			(stroke
				(width 0.1)
				(type default)
			)
			(layer "F.Fab")
		)
		(fp_line
			(start 0.12065 -0.2794)
			(end 0.12065 -0.3048)
			(stroke
				(width 0.1)
				(type default)
			)
			(layer "F.Fab")
		)
		(fp_line
			(start 0.12065 -0.3048)
			(end 0.67945 -0.3048)
			(stroke
				(width 0.1)
				(type default)
			)
			(layer "F.Fab")
		)
		(fp_line
			(start 0.67945 -0.3048)
			(end 0.67945 0.3048)
			(stroke
				(width 0.1)
				(type default)
			)
			(layer "F.Fab")
		)
		(fp_line
			(start -0.67945 -0.305054)
			(end -0.12065 -0.305054)
			(stroke
				(width 0.1)
				(type default)
			)
			(layer "F.Fab")
		)
		(fp_line
			(start -0.12065 -0.305054)
			(end -0.12065 -0.2794)
			(stroke
				(width 0.1)
				(type default)
			)
			(layer "F.Fab")
		)
		(pad "1" smd circle
			(at -0.40005 0 270)
			(size 0 0)
			(layers "F.Cu" "F.Mask" "F.Paste")
			(net "ESPI_LFRAME_N_BMC_CS0_N")
		)
		(pad "2" smd circle
			(at 0.40005 0 270)
			(size 0 0)
			(layers "F.Cu" "F.Mask" "F.Paste")
			(net "ESPI_HOST_LPC_BMC_LFRAME_N")
		)
	)
	(footprint ""
		(layer "F.Cu")
		(at 54.242716 -112.96269 180)
		(property "Reference" "R3713"
			(at 0 0 180)
			(layer "F.SilkS")
			(hide yes)
			(effects
				(font
					(size 1.27 1.27)
				)
			)
		)
		(property "Value" ""
			(at 0 0 180)
			(layer "F.Fab")
			(effects
				(font
					(size 1.27 1.27)
				)
			)
		)
		(duplicate_pad_numbers_are_jumpers no)
		(fp_line
			(start 0.7874 0.4064)
			(end -0.7874 0.4064)
			(stroke
				(width 0.1524)
				(type default)
			)
			(layer "F.SilkS")
		)
		(fp_line
			(start 0.7874 -0.4064)
			(end 0.7874 0.4064)
			(stroke
				(width 0.1524)
				(type default)
			)
			(layer "F.SilkS")
		)
		(fp_line
			(start -0.7874 0.4064)
			(end -0.7874 -0.4064)
			(stroke
				(width 0.1524)
				(type default)
			)
			(layer "F.SilkS")
		)
		(fp_line
			(start -0.7874 -0.4064)
			(end 0.7874 -0.4064)
			(stroke
				(width 0.1524)
				(type default)
			)
			(layer "F.SilkS")
		)
		(fp_line
			(start 0.67945 0.3048)
			(end 0.120396 0.3048)
			(stroke
				(width 0.1)
				(type default)
			)
			(layer "F.Fab")
		)
		(fp_line
			(start 0.67945 -0.3048)
			(end 0.67945 0.3048)
			(stroke
				(width 0.1)
				(type default)
			)
			(layer "F.Fab")
		)
		(fp_line
			(start 0.12065 -0.2794)
			(end 0.12065 -0.3048)
			(stroke
				(width 0.1)
				(type default)
			)
			(layer "F.Fab")
		)
		(fp_line
			(start 0.12065 -0.3048)
			(end 0.67945 -0.3048)
			(stroke
				(width 0.1)
				(type default)
			)
			(layer "F.Fab")
		)
		(fp_line
			(start 0.120396 0.3048)
			(end 0.120396 0.2794)
			(stroke
				(width 0.1)
				(type default)
			)
			(layer "F.Fab")
		)
		(fp_line
			(start 0.120396 0.2794)
			(end -0.12065 0.2794)
			(stroke
				(width 0.1)
				(type default)
			)
			(layer "F.Fab")
		)
		(fp_line
			(start -0.12065 0.3048)
			(end -0.67945 0.3048)
			(stroke
				(width 0.1)
				(type default)
			)
			(layer "F.Fab")
		)
		(fp_line
			(start -0.12065 0.2794)
			(end -0.12065 0.3048)
			(stroke
				(width 0.1)
				(type default)
			)
			(layer "F.Fab")
		)
		(fp_line
			(start -0.12065 -0.2794)
			(end 0.12065 -0.2794)
			(stroke
				(width 0.1)
				(type default)
			)
			(layer "F.Fab")
		)
		(fp_line
			(start -0.12065 -0.305054)
			(end -0.12065 -0.2794)
			(stroke
				(width 0.1)
				(type default)
			)
			(layer "F.Fab")
		)
		(fp_line
			(start -0.67945 0.3048)
			(end -0.67945 -0.305054)
			(stroke
				(width 0.1)
				(type default)
			)
			(layer "F.Fab")
		)
		(fp_line
			(start -0.67945 -0.305054)
			(end -0.12065 -0.305054)
			(stroke
				(width 0.1)
				(type default)
			)
			(layer "F.Fab")
		)
		(pad "1" smd circle
			(at -0.40005 0 180)
			(size 0 0)
			(layers "F.Cu" "F.Mask" "F.Paste")
			(net "SMB_VR_3V3AUX_SCL_R6")
		)
		(pad "2" smd circle
			(at 0.40005 0 180)
			(size 0 0)
			(layers "F.Cu" "F.Mask" "F.Paste")
			(net "SMB_VR_3V3AUX_SCL")
		)
	)
	(footprint ""
		(layer "F.Cu")
		(at 50.785014 -152.164542 90)
		(property "Reference" "PC443_P1_2"
			(at 0 0 90)
			(layer "F.SilkS")
			(hide yes)
			(effects
				(font
					(size 1.27 1.27)
				)
			)
		)
		(property "Value" ""
			(at 0 0 90)
			(layer "F.Fab")
			(effects
				(font
					(size 1.27 1.27)
				)
			)
		)
		(duplicate_pad_numbers_are_jumpers no)
		(fp_line
			(start 0.7874 -0.4064)
			(end 0.7874 0.4064)
			(stroke
				(width 0.1524)
				(type default)
			)
			(layer "F.SilkS")
		)
		(fp_line
			(start -0.7874 -0.4064)
			(end 0.7874 -0.4064)
			(stroke
				(width 0.1524)
				(type default)
			)
			(layer "F.SilkS")
		)
		(fp_line
			(start 0.7874 0.4064)
			(end -0.7874 0.4064)
			(stroke
				(width 0.1524)
				(type default)
			)
			(layer "F.SilkS")
		)
		(fp_line
			(start -0.7874 0.4064)
			(end -0.7874 -0.4064)
			(stroke
				(width 0.1524)
				(type default)
			)
			(layer "F.SilkS")
		)
		(fp_line
			(start -0.12065 -0.305054)
			(end -0.12065 -0.2794)
			(stroke
				(width 0.1)
				(type default)
			)
			(layer "F.Fab")
		)
		(fp_line
			(start -0.67945 -0.305054)
			(end -0.12065 -0.305054)
			(stroke
				(width 0.1)
				(type default)
			)
			(layer "F.Fab")
		)
		(fp_line
			(start 0.67945 -0.3048)
			(end 0.67945 0.3048)
			(stroke
				(width 0.1)
				(type default)
			)
			(layer "F.Fab")
		)
		(fp_line
			(start 0.12065 -0.3048)
			(end 0.67945 -0.3048)
			(stroke
				(width 0.1)
				(type default)
			)
			(layer "F.Fab")
		)
		(fp_line
			(start 0.12065 -0.2794)
			(end 0.12065 -0.3048)
			(stroke
				(width 0.1)
				(type default)
			)
			(layer "F.Fab")
		)
		(fp_line
			(start -0.12065 -0.2794)
			(end 0.12065 -0.2794)
			(stroke
				(width 0.1)
				(type default)
			)
			(layer "F.Fab")
		)
		(fp_line
			(start 0.120396 0.2794)
			(end -0.12065 0.2794)
			(stroke
				(width 0.1)
				(type default)
			)
			(layer "F.Fab")
		)
		(fp_line
			(start -0.12065 0.2794)
			(end -0.12065 0.3048)
			(stroke
				(width 0.1)
				(type default)
			)
			(layer "F.Fab")
		)
		(fp_line
			(start 0.67945 0.3048)
			(end 0.120396 0.3048)
			(stroke
				(width 0.1)
				(type default)
			)
			(layer "F.Fab")
		)
		(fp_line
			(start 0.120396 0.3048)
			(end 0.120396 0.2794)
			(stroke
				(width 0.1)
				(type default)
			)
			(layer "F.Fab")
		)
		(fp_line
			(start -0.12065 0.3048)
			(end -0.67945 0.3048)
			(stroke
				(width 0.1)
				(type default)
			)
			(layer "F.Fab")
		)
		(fp_line
			(start -0.67945 0.3048)
			(end -0.67945 -0.305054)
			(stroke
				(width 0.1)
				(type default)
			)
			(layer "F.Fab")
		)
		(pad "1" smd circle
			(at -0.40005 0 90)
			(size 0 0)
			(layers "F.Cu" "F.Mask" "F.Paste")
			(net "SW_P12V_PVCCINFAON_CPU1_FLT")
		)
		(pad "2" smd circle
			(at 0.40005 0 90)
			(size 0 0)
			(layers "F.Cu" "F.Mask" "F.Paste")
			(net "GND")
		)
	)
	(footprint ""
		(layer "F.Cu")
		(at 103.519478 -420.84879 90)
		(property "Reference" "C2275"
			(at 0 0 90)
			(layer "F.SilkS")
			(hide yes)
			(effects
				(font
					(size 1.27 1.27)
				)
			)
		)
		(property "Value" ""
			(at 0 0 90)
			(layer "F.Fab")
			(effects
				(font
					(size 1.27 1.27)
				)
			)
		)
		(duplicate_pad_numbers_are_jumpers no)
		(fp_line
			(start 0.7874 -0.4064)
			(end 0.7874 0.4064)
			(stroke
				(width 0.1524)
				(type default)
			)
			(layer "F.SilkS")
		)
		(fp_line
			(start -0.7874 -0.4064)
			(end 0.7874 -0.4064)
			(stroke
				(width 0.1524)
				(type default)
			)
			(layer "F.SilkS")
		)
		(fp_line
			(start 0.7874 0.4064)
			(end -0.7874 0.4064)
			(stroke
				(width 0.1524)
				(type default)
			)
			(layer "F.SilkS")
		)
		(fp_line
			(start -0.7874 0.4064)
			(end -0.7874 -0.4064)
			(stroke
				(width 0.1524)
				(type default)
			)
			(layer "F.SilkS")
		)
		(fp_line
			(start -0.12065 -0.305054)
			(end -0.12065 -0.2794)
			(stroke
				(width 0.1)
				(type default)
			)
			(layer "F.Fab")
		)
		(fp_line
			(start -0.67945 -0.305054)
			(end -0.12065 -0.305054)
			(stroke
				(width 0.1)
				(type default)
			)
			(layer "F.Fab")
		)
		(fp_line
			(start 0.67945 -0.3048)
			(end 0.67945 0.3048)
			(stroke
				(width 0.1)
				(type default)
			)
			(layer "F.Fab")
		)
		(fp_line
			(start 0.12065 -0.3048)
			(end 0.67945 -0.3048)
			(stroke
				(width 0.1)
				(type default)
			)
			(layer "F.Fab")
		)
		(fp_line
			(start 0.12065 -0.2794)
			(end 0.12065 -0.3048)
			(stroke
				(width 0.1)
				(type default)
			)
			(layer "F.Fab")
		)
		(fp_line
			(start -0.12065 -0.2794)
			(end 0.12065 -0.2794)
			(stroke
				(width 0.1)
				(type default)
			)
			(layer "F.Fab")
		)
		(fp_line
			(start 0.120396 0.2794)
			(end -0.12065 0.2794)
			(stroke
				(width 0.1)
				(type default)
			)
			(layer "F.Fab")
		)
		(fp_line
			(start -0.12065 0.2794)
			(end -0.12065 0.3048)
			(stroke
				(width 0.1)
				(type default)
			)
			(layer "F.Fab")
		)
		(fp_line
			(start 0.67945 0.3048)
			(end 0.120396 0.3048)
			(stroke
				(width 0.1)
				(type default)
			)
			(layer "F.Fab")
		)
		(fp_line
			(start 0.120396 0.3048)
			(end 0.120396 0.2794)
			(stroke
				(width 0.1)
				(type default)
			)
			(layer "F.Fab")
		)
		(fp_line
			(start -0.12065 0.3048)
			(end -0.67945 0.3048)
			(stroke
				(width 0.1)
				(type default)
			)
			(layer "F.Fab")
		)
		(fp_line
			(start -0.67945 0.3048)
			(end -0.67945 -0.305054)
			(stroke
				(width 0.1)
				(type default)
			)
			(layer "F.Fab")
		)
		(pad "1" smd circle
			(at -0.40005 0 90)
			(size 0 0)
			(layers "F.Cu" "F.Mask" "F.Paste")
			(net "P3V3_AUX")
		)
		(pad "2" smd circle
			(at 0.40005 0 90)
			(size 0 0)
			(layers "F.Cu" "F.Mask" "F.Paste")
			(net "GND")
		)
	)
	(footprint ""
		(layer "F.Cu")
		(at 118.542816 -258.72694 90)
		(property "Reference" "C228"
			(at 0 0 90)
			(layer "F.SilkS")
			(hide yes)
			(effects
				(font
					(size 1.27 1.27)
				)
			)
		)
		(property "Value" ""
			(at 0 0 90)
			(layer "F.Fab")
			(effects
				(font
					(size 1.27 1.27)
				)
			)
		)
		(duplicate_pad_numbers_are_jumpers no)
		(fp_line
			(start 0.7874 -0.4064)
			(end 0.7874 0.4064)
			(stroke
				(width 0.1524)
				(type default)
			)
			(layer "F.SilkS")
		)
		(fp_line
			(start -0.7874 -0.4064)
			(end 0.7874 -0.4064)
			(stroke
				(width 0.1524)
				(type default)
			)
			(layer "F.SilkS")
		)
		(fp_line
			(start 0.7874 0.4064)
			(end -0.7874 0.4064)
			(stroke
				(width 0.1524)
				(type default)
			)
			(layer "F.SilkS")
		)
		(fp_line
			(start -0.7874 0.4064)
			(end -0.7874 -0.4064)
			(stroke
				(width 0.1524)
				(type default)
			)
			(layer "F.SilkS")
		)
		(fp_line
			(start -0.12065 -0.305054)
			(end -0.12065 -0.2794)
			(stroke
				(width 0.1)
				(type default)
			)
			(layer "F.Fab")
		)
		(fp_line
			(start -0.67945 -0.305054)
			(end -0.12065 -0.305054)
			(stroke
				(width 0.1)
				(type default)
			)
			(layer "F.Fab")
		)
		(fp_line
			(start 0.67945 -0.3048)
			(end 0.67945 0.3048)
			(stroke
				(width 0.1)
				(type default)
			)
			(layer "F.Fab")
		)
		(fp_line
			(start 0.12065 -0.3048)
			(end 0.67945 -0.3048)
			(stroke
				(width 0.1)
				(type default)
			)
			(layer "F.Fab")
		)
		(fp_line
			(start 0.12065 -0.2794)
			(end 0.12065 -0.3048)
			(stroke
				(width 0.1)
				(type default)
			)
			(layer "F.Fab")
		)
		(fp_line
			(start -0.12065 -0.2794)
			(end 0.12065 -0.2794)
			(stroke
				(width 0.1)
				(type default)
			)
			(layer "F.Fab")
		)
		(fp_line
			(start 0.120396 0.2794)
			(end -0.12065 0.2794)
			(stroke
				(width 0.1)
				(type default)
			)
			(layer "F.Fab")
		)
		(fp_line
			(start -0.12065 0.2794)
			(end -0.12065 0.3048)
			(stroke
				(width 0.1)
				(type default)
			)
			(layer "F.Fab")
		)
		(fp_line
			(start 0.67945 0.3048)
			(end 0.120396 0.3048)
			(stroke
				(width 0.1)
				(type default)
			)
			(layer "F.Fab")
		)
		(fp_line
			(start 0.120396 0.3048)
			(end 0.120396 0.2794)
			(stroke
				(width 0.1)
				(type default)
			)
			(layer "F.Fab")
		)
		(fp_line
			(start -0.12065 0.3048)
			(end -0.67945 0.3048)
			(stroke
				(width 0.1)
				(type default)
			)
			(layer "F.Fab")
		)
		(fp_line
			(start -0.67945 0.3048)
			(end -0.67945 -0.305054)
			(stroke
				(width 0.1)
				(type default)
			)
			(layer "F.Fab")
		)
		(pad "1" smd circle
			(at -0.40005 0 90)
			(size 0 0)
			(layers "F.Cu" "F.Mask" "F.Paste")
			(net "PVCCIN_CPU1")
		)
		(pad "2" smd circle
			(at 0.40005 0 90)
			(size 0 0)
			(layers "F.Cu" "F.Mask" "F.Paste")
			(net "GND")
		)
	)
	(footprint ""
		(layer "F.Cu")
		(at 181.7624 -93.538548 90)
		(property "Reference" "R4589"
			(at 0 0 90)
			(layer "F.SilkS")
			(hide yes)
			(effects
				(font
					(size 1.27 1.27)
				)
			)
		)
		(property "Value" ""
			(at 0 0 90)
			(layer "F.Fab")
			(effects
				(font
					(size 1.27 1.27)
				)
			)
		)
		(duplicate_pad_numbers_are_jumpers no)
		(fp_line
			(start 0.7874 -0.4064)
			(end 0.7874 0.4064)
			(stroke
				(width 0.1524)
				(type default)
			)
			(layer "F.SilkS")
		)
		(fp_line
			(start -0.7874 -0.4064)
			(end 0.7874 -0.4064)
			(stroke
				(width 0.1524)
				(type default)
			)
			(layer "F.SilkS")
		)
		(fp_line
			(start 0.7874 0.4064)
			(end -0.7874 0.4064)
			(stroke
				(width 0.1524)
				(type default)
			)
			(layer "F.SilkS")
		)
		(fp_line
			(start -0.7874 0.4064)
			(end -0.7874 -0.4064)
			(stroke
				(width 0.1524)
				(type default)
			)
			(layer "F.SilkS")
		)
		(fp_line
			(start -0.12065 -0.305054)
			(end -0.12065 -0.2794)
			(stroke
				(width 0.1)
				(type default)
			)
			(layer "F.Fab")
		)
		(fp_line
			(start -0.67945 -0.305054)
			(end -0.12065 -0.305054)
			(stroke
				(width 0.1)
				(type default)
			)
			(layer "F.Fab")
		)
		(fp_line
			(start 0.67945 -0.3048)
			(end 0.67945 0.3048)
			(stroke
				(width 0.1)
				(type default)
			)
			(layer "F.Fab")
		)
		(fp_line
			(start 0.12065 -0.3048)
			(end 0.67945 -0.3048)
			(stroke
				(width 0.1)
				(type default)
			)
			(layer "F.Fab")
		)
		(fp_line
			(start 0.12065 -0.2794)
			(end 0.12065 -0.3048)
			(stroke
				(width 0.1)
				(type default)
			)
			(layer "F.Fab")
		)
		(fp_line
			(start -0.12065 -0.2794)
			(end 0.12065 -0.2794)
			(stroke
				(width 0.1)
				(type default)
			)
			(layer "F.Fab")
		)
		(fp_line
			(start 0.120396 0.2794)
			(end -0.12065 0.2794)
			(stroke
				(width 0.1)
				(type default)
			)
			(layer "F.Fab")
		)
		(fp_line
			(start -0.12065 0.2794)
			(end -0.12065 0.3048)
			(stroke
				(width 0.1)
				(type default)
			)
			(layer "F.Fab")
		)
		(fp_line
			(start 0.67945 0.3048)
			(end 0.120396 0.3048)
			(stroke
				(width 0.1)
				(type default)
			)
			(layer "F.Fab")
		)
		(fp_line
			(start 0.120396 0.3048)
			(end 0.120396 0.2794)
			(stroke
				(width 0.1)
				(type default)
			)
			(layer "F.Fab")
		)
		(fp_line
			(start -0.12065 0.3048)
			(end -0.67945 0.3048)
			(stroke
				(width 0.1)
				(type default)
			)
			(layer "F.Fab")
		)
		(fp_line
			(start -0.67945 0.3048)
			(end -0.67945 -0.305054)
			(stroke
				(width 0.1)
				(type default)
			)
			(layer "F.Fab")
		)
		(pad "1" smd rect
			(at -0.40005 0 270)
			(size 0.4572 0.508)
			(layers "F.Cu" "F.Mask" "F.Paste")
			(net "P3V3_AUX")
		)
		(pad "2" smd rect
			(at 0.40005 0 270)
			(size 0.4572 0.508)
			(layers "F.Cu" "F.Mask" "F.Paste")
			(net "FAB_BMC_REV_ID1")
		)
	)
	(footprint ""
		(layer "F.Cu")
		(at 107.2769 -252.956568 -90)
		(property "Reference" "C275"
			(at 0 0 270)
			(layer "F.SilkS")
			(hide yes)
			(effects
				(font
					(size 1.27 1.27)
				)
			)
		)
		(property "Value" ""
			(at 0 0 270)
			(layer "F.Fab")
			(effects
				(font
					(size 1.27 1.27)
				)
			)
		)
		(duplicate_pad_numbers_are_jumpers no)
		(fp_line
			(start -0.7874 0.4064)
			(end -0.7874 -0.4064)
			(stroke
				(width 0.1524)
				(type default)
			)
			(layer "F.SilkS")
		)
		(fp_line
			(start 0.7874 0.4064)
			(end -0.7874 0.4064)
			(stroke
				(width 0.1524)
				(type default)
			)
			(layer "F.SilkS")
		)
		(fp_line
			(start -0.7874 -0.4064)
			(end 0.7874 -0.4064)
			(stroke
				(width 0.1524)
				(type default)
			)
			(layer "F.SilkS")
		)
		(fp_line
			(start 0.7874 -0.4064)
			(end 0.7874 0.4064)
			(stroke
				(width 0.1524)
				(type default)
			)
			(layer "F.SilkS")
		)
		(fp_line
			(start -0.67945 0.3048)
			(end -0.67945 -0.305054)
			(stroke
				(width 0.1)
				(type default)
			)
			(layer "F.Fab")
		)
		(fp_line
			(start -0.12065 0.3048)
			(end -0.67945 0.3048)
			(stroke
				(width 0.1)
				(type default)
			)
			(layer "F.Fab")
		)
		(fp_line
			(start 0.120396 0.3048)
			(end 0.120396 0.2794)
			(stroke
				(width 0.1)
				(type default)
			)
			(layer "F.Fab")
		)
		(fp_line
			(start 0.67945 0.3048)
			(end 0.120396 0.3048)
			(stroke
				(width 0.1)
				(type default)
			)
			(layer "F.Fab")
		)
		(fp_line
			(start -0.12065 0.2794)
			(end -0.12065 0.3048)
			(stroke
				(width 0.1)
				(type default)
			)
			(layer "F.Fab")
		)
		(fp_line
			(start 0.120396 0.2794)
			(end -0.12065 0.2794)
			(stroke
				(width 0.1)
				(type default)
			)
			(layer "F.Fab")
		)
		(fp_line
			(start -0.12065 -0.2794)
			(end 0.12065 -0.2794)
			(stroke
				(width 0.1)
				(type default)
			)
			(layer "F.Fab")
		)
		(fp_line
			(start 0.12065 -0.2794)
			(end 0.12065 -0.3048)
			(stroke
				(width 0.1)
				(type default)
			)
			(layer "F.Fab")
		)
		(fp_line
			(start 0.12065 -0.3048)
			(end 0.67945 -0.3048)
			(stroke
				(width 0.1)
				(type default)
			)
			(layer "F.Fab")
		)
		(fp_line
			(start 0.67945 -0.3048)
			(end 0.67945 0.3048)
			(stroke
				(width 0.1)
				(type default)
			)
			(layer "F.Fab")
		)
		(fp_line
			(start -0.67945 -0.305054)
			(end -0.12065 -0.305054)
			(stroke
				(width 0.1)
				(type default)
			)
			(layer "F.Fab")
		)
		(fp_line
			(start -0.12065 -0.305054)
			(end -0.12065 -0.2794)
			(stroke
				(width 0.1)
				(type default)
			)
			(layer "F.Fab")
		)
		(pad "1" smd circle
			(at -0.40005 0 270)
			(size 0 0)
			(layers "F.Cu" "F.Mask" "F.Paste")
			(net "PVCCIN_CPU1")
		)
		(pad "2" smd circle
			(at 0.40005 0 270)
			(size 0 0)
			(layers "F.Cu" "F.Mask" "F.Paste")
			(net "GND")
		)
	)
	(footprint ""
		(layer "F.Cu")
		(at 368.7572 -71.42226)
		(property "Reference" "D142"
			(at -5.7912 -0.94107 0)
			(unlocked yes)
			(layer "F.SilkS")
			(effects
				(font
					(size 0.7874 0.5842)
					(thickness 0.1524)
				)
				(justify left)
			)
		)
		(property "Value" ""
			(at 0 0 0)
			(layer "F.Fab")
			(effects
				(font
					(size 1.27 1.27)
				)
			)
		)
		(duplicate_pad_numbers_are_jumpers no)
		(fp_line
			(start -0.90678 0.4826)
			(end -0.90678 -0.4699)
			(stroke
				(width 0.1524)
				(type default)
			)
			(layer "F.SilkS")
		)
		(fp_line
			(start -0.89408 -0.4826)
			(end 0.90678 -0.4826)
			(stroke
				(width 0.1524)
				(type default)
			)
			(layer "F.SilkS")
		)
		(fp_line
			(start -0.79248 -0.4826)
			(end 1.03378 -0.4826)
			(stroke
				(width 0.1524)
				(type default)
			)
			(layer "F.SilkS")
		)
		(fp_line
			(start -0.64008 -0.4826)
			(end 1.16078 -0.4826)
			(stroke
				(width 0.1524)
				(type default)
			)
			(layer "F.SilkS")
		)
		(fp_line
			(start 0.90678 -0.4826)
			(end 0.90678 0.4826)
			(stroke
				(width 0.1524)
				(type default)
			)
			(layer "F.SilkS")
		)
		(fp_line
			(start 0.90678 0.4826)
			(end -0.90678 0.4826)
			(stroke
				(width 0.1524)
				(type default)
			)
			(layer "F.SilkS")
		)
		(fp_line
			(start 1.03378 -0.4826)
			(end 1.03378 0.4826)
			(stroke
				(width 0.1524)
				(type default)
			)
			(layer "F.SilkS")
		)
		(fp_line
			(start 1.03378 0.4826)
			(end -0.79248 0.4826)
			(stroke
				(width 0.1524)
				(type default)
			)
			(layer "F.SilkS")
		)
		(fp_line
			(start 1.16078 -0.4826)
			(end 1.16078 0.4826)
			(stroke
				(width 0.1524)
				(type default)
			)
			(layer "F.SilkS")
		)
		(fp_line
			(start 1.16078 0.4826)
			(end -0.64008 0.4826)
			(stroke
				(width 0.1524)
				(type default)
			)
			(layer "F.SilkS")
		)
		(fp_line
			(start -0.499872 -0.249936)
			(end 0.499872 -0.249936)
			(stroke
				(width 0.1)
				(type default)
			)
			(layer "F.Fab")
		)
		(fp_line
			(start -0.499872 0.249936)
			(end -0.499872 -0.249936)
			(stroke
				(width 0.1)
				(type default)
			)
			(layer "F.Fab")
		)
		(fp_line
			(start 0.499872 -0.249936)
			(end 0.499872 0.249936)
			(stroke
				(width 0.1)
				(type default)
			)
			(layer "F.Fab")
		)
		(fp_line
			(start 0.499872 0.249936)
			(end -0.499872 0.249936)
			(stroke
				(width 0.1)
				(type default)
			)
			(layer "F.Fab")
		)
		(pad "A" smd rect
			(at -0.47498 0)
			(size 0.6096 0.7112)
			(layers "F.Cu" "F.Mask" "F.Paste")
			(net "LED_P12V_AUX_R1")
		)
		(pad "C" smd rect
			(at 0.47498 0)
			(size 0.6096 0.7112)
			(layers "F.Cu" "F.Mask" "F.Paste")
			(net "GND")
		)
	)
	(footprint ""
		(layer "F.Cu")
		(at 420.4716 -177.724562 180)
		(property "Reference" "PC194"
			(at 0 0 180)
			(layer "F.SilkS")
			(hide yes)
			(effects
				(font
					(size 1.27 1.27)
				)
			)
		)
		(property "Value" ""
			(at 0 0 180)
			(layer "F.Fab")
			(effects
				(font
					(size 1.27 1.27)
				)
			)
		)
		(duplicate_pad_numbers_are_jumpers no)
		(fp_line
			(start 0.7874 0.4064)
			(end -0.7874 0.4064)
			(stroke
				(width 0.1524)
				(type default)
			)
			(layer "F.SilkS")
		)
		(fp_line
			(start 0.7874 -0.4064)
			(end 0.7874 0.4064)
			(stroke
				(width 0.1524)
				(type default)
			)
			(layer "F.SilkS")
		)
		(fp_line
			(start -0.7874 0.4064)
			(end -0.7874 -0.4064)
			(stroke
				(width 0.1524)
				(type default)
			)
			(layer "F.SilkS")
		)
		(fp_line
			(start -0.7874 -0.4064)
			(end 0.7874 -0.4064)
			(stroke
				(width 0.1524)
				(type default)
			)
			(layer "F.SilkS")
		)
		(fp_line
			(start 0.67945 0.3048)
			(end 0.120396 0.3048)
			(stroke
				(width 0.1)
				(type default)
			)
			(layer "F.Fab")
		)
		(fp_line
			(start 0.67945 -0.3048)
			(end 0.67945 0.3048)
			(stroke
				(width 0.1)
				(type default)
			)
			(layer "F.Fab")
		)
		(fp_line
			(start 0.12065 -0.2794)
			(end 0.12065 -0.3048)
			(stroke
				(width 0.1)
				(type default)
			)
			(layer "F.Fab")
		)
		(fp_line
			(start 0.12065 -0.3048)
			(end 0.67945 -0.3048)
			(stroke
				(width 0.1)
				(type default)
			)
			(layer "F.Fab")
		)
		(fp_line
			(start 0.120396 0.3048)
			(end 0.120396 0.2794)
			(stroke
				(width 0.1)
				(type default)
			)
			(layer "F.Fab")
		)
		(fp_line
			(start 0.120396 0.2794)
			(end -0.12065 0.2794)
			(stroke
				(width 0.1)
				(type default)
			)
			(layer "F.Fab")
		)
		(fp_line
			(start -0.12065 0.3048)
			(end -0.67945 0.3048)
			(stroke
				(width 0.1)
				(type default)
			)
			(layer "F.Fab")
		)
		(fp_line
			(start -0.12065 0.2794)
			(end -0.12065 0.3048)
			(stroke
				(width 0.1)
				(type default)
			)
			(layer "F.Fab")
		)
		(fp_line
			(start -0.12065 -0.2794)
			(end 0.12065 -0.2794)
			(stroke
				(width 0.1)
				(type default)
			)
			(layer "F.Fab")
		)
		(fp_line
			(start -0.12065 -0.305054)
			(end -0.12065 -0.2794)
			(stroke
				(width 0.1)
				(type default)
			)
			(layer "F.Fab")
		)
		(fp_line
			(start -0.67945 0.3048)
			(end -0.67945 -0.305054)
			(stroke
				(width 0.1)
				(type default)
			)
			(layer "F.Fab")
		)
		(fp_line
			(start -0.67945 -0.305054)
			(end -0.12065 -0.305054)
			(stroke
				(width 0.1)
				(type default)
			)
			(layer "F.Fab")
		)
		(pad "1" smd circle
			(at -0.40005 0 180)
			(size 0 0)
			(layers "F.Cu" "F.Mask" "F.Paste")
			(net "SW_PVCCINFAON_CPU0_BOOT2_R")
		)
		(pad "2" smd circle
			(at 0.40005 0 180)
			(size 0 0)
			(layers "F.Cu" "F.Mask" "F.Paste")
			(net "SW_PVCCINFAON_CPU0_BOOTR2")
		)
	)
	(footprint ""
		(layer "F.Cu")
		(at 224.074482 -57.412382 90)
		(property "Reference" "R3767"
			(at 0 0 90)
			(layer "F.SilkS")
			(hide yes)
			(effects
				(font
					(size 1.27 1.27)
				)
			)
		)
		(property "Value" ""
			(at 0 0 90)
			(layer "F.Fab")
			(effects
				(font
					(size 1.27 1.27)
				)
			)
		)
		(duplicate_pad_numbers_are_jumpers no)
		(fp_line
			(start 4.0386 -1.7526)
			(end 4.0386 1.7526)
			(stroke
				(width 0.1524)
				(type default)
			)
			(layer "F.SilkS")
		)
		(fp_line
			(start -4.0386 -1.7526)
			(end 4.0386 -1.7526)
			(stroke
				(width 0.1524)
				(type default)
			)
			(layer "F.SilkS")
		)
		(fp_line
			(start 4.0386 1.7526)
			(end -4.0386 1.7526)
			(stroke
				(width 0.1524)
				(type default)
			)
			(layer "F.SilkS")
		)
		(fp_line
			(start -4.0386 1.7526)
			(end -4.0386 -1.7526)
			(stroke
				(width 0.1524)
				(type default)
			)
			(layer "F.SilkS")
		)
		(fp_line
			(start 4.0386 -1.7526)
			(end 4.0386 1.7526)
			(stroke
				(width 0.1)
				(type default)
			)
			(layer "F.Fab")
		)
		(fp_line
			(start -4.0386 -1.7526)
			(end 4.0386 -1.7526)
			(stroke
				(width 0.1)
				(type default)
			)
			(layer "F.Fab")
		)
		(fp_line
			(start 4.0386 1.7526)
			(end -4.0386 1.7526)
			(stroke
				(width 0.1)
				(type default)
			)
			(layer "F.Fab")
		)
		(fp_line
			(start -4.0386 1.7526)
			(end -4.0386 -1.7526)
			(stroke
				(width 0.1)
				(type default)
			)
			(layer "F.Fab")
		)
		(pad "1" smd rect
			(at -3.1115 0 90)
			(size 1.524 3.2004)
			(layers "F.Cu" "F.Mask" "F.Paste")
			(net "P3V3_E1S_0")
		)
		(pad "2" smd rect
			(at 3.1115 0 90)
			(size 1.524 3.2004)
			(layers "F.Cu" "F.Mask" "F.Paste")
			(net "P3V3_E1S_0_R")
		)
	)
	(footprint ""
		(layer "F.Cu")
		(at 111.332772 -129.472182)
		(property "Reference" "R1089"
			(at 0 0 0)
			(layer "F.SilkS")
			(hide yes)
			(effects
				(font
					(size 1.27 1.27)
				)
			)
		)
		(property "Value" ""
			(at 0 0 0)
			(layer "F.Fab")
			(effects
				(font
					(size 1.27 1.27)
				)
			)
		)
		(duplicate_pad_numbers_are_jumpers no)
		(fp_line
			(start -0.7874 -0.4064)
			(end 0.7874 -0.4064)
			(stroke
				(width 0.1524)
				(type default)
			)
			(layer "F.SilkS")
		)
		(fp_line
			(start -0.7874 0.4064)
			(end -0.7874 -0.4064)
			(stroke
				(width 0.1524)
				(type default)
			)
			(layer "F.SilkS")
		)
		(fp_line
			(start 0.7874 -0.4064)
			(end 0.7874 0.4064)
			(stroke
				(width 0.1524)
				(type default)
			)
			(layer "F.SilkS")
		)
		(fp_line
			(start 0.7874 0.4064)
			(end -0.7874 0.4064)
			(stroke
				(width 0.1524)
				(type default)
			)
			(layer "F.SilkS")
		)
		(fp_line
			(start -0.67945 -0.305054)
			(end -0.12065 -0.305054)
			(stroke
				(width 0.1)
				(type default)
			)
			(layer "F.Fab")
		)
		(fp_line
			(start -0.67945 0.3048)
			(end -0.67945 -0.305054)
			(stroke
				(width 0.1)
				(type default)
			)
			(layer "F.Fab")
		)
		(fp_line
			(start -0.12065 -0.305054)
			(end -0.12065 -0.2794)
			(stroke
				(width 0.1)
				(type default)
			)
			(layer "F.Fab")
		)
		(fp_line
			(start -0.12065 -0.2794)
			(end 0.12065 -0.2794)
			(stroke
				(width 0.1)
				(type default)
			)
			(layer "F.Fab")
		)
		(fp_line
			(start -0.12065 0.2794)
			(end -0.12065 0.3048)
			(stroke
				(width 0.1)
				(type default)
			)
			(layer "F.Fab")
		)
		(fp_line
			(start -0.12065 0.3048)
			(end -0.67945 0.3048)
			(stroke
				(width 0.1)
				(type default)
			)
			(layer "F.Fab")
		)
		(fp_line
			(start 0.120396 0.2794)
			(end -0.12065 0.2794)
			(stroke
				(width 0.1)
				(type default)
			)
			(layer "F.Fab")
		)
		(fp_line
			(start 0.120396 0.3048)
			(end 0.120396 0.2794)
			(stroke
				(width 0.1)
				(type default)
			)
			(layer "F.Fab")
		)
		(fp_line
			(start 0.12065 -0.3048)
			(end 0.67945 -0.3048)
			(stroke
				(width 0.1)
				(type default)
			)
			(layer "F.Fab")
		)
		(fp_line
			(start 0.12065 -0.2794)
			(end 0.12065 -0.3048)
			(stroke
				(width 0.1)
				(type default)
			)
			(layer "F.Fab")
		)
		(fp_line
			(start 0.67945 -0.3048)
			(end 0.67945 0.3048)
			(stroke
				(width 0.1)
				(type default)
			)
			(layer "F.Fab")
		)
		(fp_line
			(start 0.67945 0.3048)
			(end 0.120396 0.3048)
			(stroke
				(width 0.1)
				(type default)
			)
			(layer "F.Fab")
		)
		(pad "1" smd circle
			(at -0.40005 0)
			(size 0 0)
			(layers "F.Cu" "F.Mask" "F.Paste")
			(net "P3V3_AUX")
		)
		(pad "2" smd circle
			(at 0.40005 0)
			(size 0 0)
			(layers "F.Cu" "F.Mask" "F.Paste")
			(net "SMB_SENSOR_M2_P0_3V3AUX_SCL")
		)
	)
	(footprint ""
		(layer "F.Cu")
		(at 152.70988 -122.519948)
		(property "Reference" "R2344"
			(at 0 0 0)
			(layer "F.SilkS")
			(hide yes)
			(effects
				(font
					(size 1.27 1.27)
				)
			)
		)
		(property "Value" ""
			(at 0 0 0)
			(layer "F.Fab")
			(effects
				(font
					(size 1.27 1.27)
				)
			)
		)
		(duplicate_pad_numbers_are_jumpers no)
		(fp_line
			(start -0.7874 -0.4064)
			(end 0.7874 -0.4064)
			(stroke
				(width 0.1524)
				(type default)
			)
			(layer "F.SilkS")
		)
		(fp_line
			(start -0.7874 0.4064)
			(end -0.7874 -0.4064)
			(stroke
				(width 0.1524)
				(type default)
			)
			(layer "F.SilkS")
		)
		(fp_line
			(start 0.7874 -0.4064)
			(end 0.7874 0.4064)
			(stroke
				(width 0.1524)
				(type default)
			)
			(layer "F.SilkS")
		)
		(fp_line
			(start 0.7874 0.4064)
			(end -0.7874 0.4064)
			(stroke
				(width 0.1524)
				(type default)
			)
			(layer "F.SilkS")
		)
		(fp_line
			(start -0.67945 -0.305054)
			(end -0.12065 -0.305054)
			(stroke
				(width 0.1)
				(type default)
			)
			(layer "F.Fab")
		)
		(fp_line
			(start -0.67945 0.3048)
			(end -0.67945 -0.305054)
			(stroke
				(width 0.1)
				(type default)
			)
			(layer "F.Fab")
		)
		(fp_line
			(start -0.12065 -0.305054)
			(end -0.12065 -0.2794)
			(stroke
				(width 0.1)
				(type default)
			)
			(layer "F.Fab")
		)
		(fp_line
			(start -0.12065 -0.2794)
			(end 0.12065 -0.2794)
			(stroke
				(width 0.1)
				(type default)
			)
			(layer "F.Fab")
		)
		(fp_line
			(start -0.12065 0.2794)
			(end -0.12065 0.3048)
			(stroke
				(width 0.1)
				(type default)
			)
			(layer "F.Fab")
		)
		(fp_line
			(start -0.12065 0.3048)
			(end -0.67945 0.3048)
			(stroke
				(width 0.1)
				(type default)
			)
			(layer "F.Fab")
		)
		(fp_line
			(start 0.120396 0.2794)
			(end -0.12065 0.2794)
			(stroke
				(width 0.1)
				(type default)
			)
			(layer "F.Fab")
		)
		(fp_line
			(start 0.120396 0.3048)
			(end 0.120396 0.2794)
			(stroke
				(width 0.1)
				(type default)
			)
			(layer "F.Fab")
		)
		(fp_line
			(start 0.12065 -0.3048)
			(end 0.67945 -0.3048)
			(stroke
				(width 0.1)
				(type default)
			)
			(layer "F.Fab")
		)
		(fp_line
			(start 0.12065 -0.2794)
			(end 0.12065 -0.3048)
			(stroke
				(width 0.1)
				(type default)
			)
			(layer "F.Fab")
		)
		(fp_line
			(start 0.67945 -0.3048)
			(end 0.67945 0.3048)
			(stroke
				(width 0.1)
				(type default)
			)
			(layer "F.Fab")
		)
		(fp_line
			(start 0.67945 0.3048)
			(end 0.120396 0.3048)
			(stroke
				(width 0.1)
				(type default)
			)
			(layer "F.Fab")
		)
		(pad "1" smd circle
			(at -0.40005 0)
			(size 0 0)
			(layers "F.Cu" "F.Mask" "F.Paste")
			(net "P3V3_AUX")
		)
		(pad "2" smd circle
			(at 0.40005 0)
			(size 0 0)
			(layers "F.Cu" "F.Mask" "F.Paste")
			(net "PWRGD_P5V_AUX_R1")
		)
	)
	(footprint ""
		(layer "F.Cu")
		(at 32.06115 -129.633472 90)
		(property "Reference" "PU22"
			(at -6.968236 -4.331208 0)
			(unlocked yes)
			(layer "F.SilkS")
			(effects
				(font
					(size 0.7874 0.5842)
					(thickness 0.1524)
				)
			)
		)
		(property "Value" ""
			(at 0 0 90)
			(layer "F.Fab")
			(effects
				(font
					(size 1.27 1.27)
				)
			)
		)
		(duplicate_pad_numbers_are_jumpers no)
		(fp_line
			(start 0.1778 -3.2385)
			(end 0.1778 -2.8575)
			(stroke
				(width 0.1524)
				(type default)
			)
			(layer "F.SilkS")
		)
		(fp_line
			(start -1.8034 -2.8702)
			(end -1.8034 -3.6322)
			(stroke
				(width 0.1524)
				(type default)
			)
			(layer "F.SilkS")
		)
		(fp_line
			(start 2.500122 -2.500122)
			(end 2.500122 -2.015998)
			(stroke
				(width 0.1524)
				(type default)
			)
			(layer "F.SilkS")
		)
		(fp_line
			(start 2.015998 -2.500122)
			(end 2.500122 -2.500122)
			(stroke
				(width 0.1524)
				(type default)
			)
			(layer "F.SilkS")
		)
		(fp_line
			(start -2.500122 -2.500122)
			(end -2.015998 -2.500122)
			(stroke
				(width 0.1524)
				(type default)
			)
			(layer "F.SilkS")
		)
		(fp_line
			(start -2.500122 -2.015998)
			(end -2.500122 -2.500122)
			(stroke
				(width 0.1524)
				(type default)
			)
			(layer "F.SilkS")
		)
		(fp_line
			(start 2.8702 -1.778)
			(end 3.6322 -1.778)
			(stroke
				(width 0.1524)
				(type default)
			)
			(layer "F.SilkS")
		)
		(fp_line
			(start -3.2639 -0.1778)
			(end -2.8829 -0.1778)
			(stroke
				(width 0.1524)
				(type default)
			)
			(layer "F.SilkS")
		)
		(fp_line
			(start 2.8829 0.2032)
			(end 3.2639 0.2032)
			(stroke
				(width 0.1524)
				(type default)
			)
			(layer "F.SilkS")
		)
		(fp_line
			(start -3.6576 1.8034)
			(end -2.8956 1.8034)
			(stroke
				(width 0.1524)
				(type default)
			)
			(layer "F.SilkS")
		)
		(fp_line
			(start 2.500122 2.015998)
			(end 2.500122 2.500122)
			(stroke
				(width 0.1524)
				(type default)
			)
			(layer "F.SilkS")
		)
		(fp_line
			(start 2.500122 2.500122)
			(end 2.015998 2.500122)
			(stroke
				(width 0.1524)
				(type default)
			)
			(layer "F.SilkS")
		)
		(fp_line
			(start -2.015998 2.500122)
			(end -2.500122 2.500122)
			(stroke
				(width 0.1524)
				(type default)
			)
			(layer "F.SilkS")
		)
		(fp_line
			(start -2.500122 2.500122)
			(end -2.500122 2.018538)
			(stroke
				(width 0.1524)
				(type default)
			)
			(layer "F.SilkS")
		)
		(fp_line
			(start -0.2032 2.8829)
			(end -0.2032 3.2639)
			(stroke
				(width 0.1524)
				(type default)
			)
			(layer "F.SilkS")
		)
		(fp_line
			(start 1.778 3.6322)
			(end 1.778 2.8702)
			(stroke
				(width 0.1524)
				(type default)
			)
			(layer "F.SilkS")
		)
		(fp_poly
			(pts
				(xy -3.504184 -1.508506) (xy -3.504184 -2.09169) (xy -2.921 -1.800098)
			)
			(stroke
				(width 0)
				(type default)
			)
			(fill yes)
			(layer "F.SilkS")
		)
		(fp_line
			(start 0.1778 -3.2385)
			(end 0.1778 -2.8575)
			(stroke
				(width 0.1)
				(type default)
			)
			(layer "F.Fab")
		)
		(fp_line
			(start -1.8034 -2.8702)
			(end -1.8034 -3.6322)
			(stroke
				(width 0.1)
				(type default)
			)
			(layer "F.Fab")
		)
		(fp_line
			(start 2.500122 -2.500122)
			(end 2.500122 2.500122)
			(stroke
				(width 0.1)
				(type default)
			)
			(layer "F.Fab")
		)
		(fp_line
			(start -2.500122 -2.500122)
			(end 2.500122 -2.500122)
			(stroke
				(width 0.1)
				(type default)
			)
			(layer "F.Fab")
		)
		(fp_line
			(start 2.8702 -1.778)
			(end 3.6322 -1.778)
			(stroke
				(width 0.1)
				(type default)
			)
			(layer "F.Fab")
		)
		(fp_line
			(start -3.2639 -0.1778)
			(end -2.8829 -0.1778)
			(stroke
				(width 0.1)
				(type default)
			)
			(layer "F.Fab")
		)
		(fp_line
			(start 2.8829 0.2032)
			(end 3.2639 0.2032)
			(stroke
				(width 0.1)
				(type default)
			)
			(layer "F.Fab")
		)
		(fp_line
			(start -3.6576 1.8034)
			(end -2.8956 1.8034)
			(stroke
				(width 0.1)
				(type default)
			)
			(layer "F.Fab")
		)
		(fp_line
			(start 2.500122 2.500122)
			(end -2.500122 2.500122)
			(stroke
				(width 0.1)
				(type default)
			)
			(layer "F.Fab")
		)
		(fp_line
			(start -2.500122 2.500122)
			(end -2.500122 -2.500122)
			(stroke
				(width 0.1)
				(type default)
			)
			(layer "F.Fab")
		)
		(fp_line
			(start -0.2032 2.8829)
			(end -0.2032 3.2639)
			(stroke
				(width 0.1)
				(type default)
			)
			(layer "F.Fab")
		)
		(fp_line
			(start 1.778 3.6322)
			(end 1.778 2.8702)
			(stroke
				(width 0.1)
				(type default)
			)
			(layer "F.Fab")
		)
		(fp_poly
			(pts
				(xy -2.921 -1.800098) (xy -3.504184 -1.508506) (xy -3.504184 -2.09169)
			)
			(stroke
				(width 0)
				(type default)
			)
			(fill yes)
			(layer "F.Fab")
		)
		(fp_text user "31"
			(at 2.371598 -4.09321 0)
			(unlocked yes)
			(layer "F.SilkS")
			(effects
				(font
					(size 0.635 0.4064)
					(thickness 0.1524)
				)
				(justify left)
			)
		)
		(fp_text user "40"
			(at -2.624074 -3.77825 0)
			(unlocked yes)
			(layer "F.SilkS")
			(effects
				(font
					(size 0.635 0.4064)
					(thickness 0.1524)
				)
				(justify left)
			)
		)
		(fp_text user "30"
			(at 3.873246 -1.40335 0)
			(unlocked yes)
			(layer "F.SilkS")
			(effects
				(font
					(size 0.635 0.4064)
					(thickness 0.1524)
				)
				(justify left)
			)
		)
		(fp_text user "21"
			(at 4.815586 -0.18669 0)
			(unlocked yes)
			(layer "F.SilkS")
			(effects
				(font
					(size 0.635 0.4064)
					(thickness 0.1524)
				)
				(justify left)
			)
		)
		(fp_text user "10"
			(at -3.165094 2.18821 0)
			(unlocked yes)
			(layer "F.SilkS")
			(effects
				(font
					(size 0.635 0.4064)
					(thickness 0.1524)
				)
				(justify left)
			)
		)
		(fp_text user "11"
			(at -2.166874 2.85877 0)
			(unlocked yes)
			(layer "F.SilkS")
			(effects
				(font
					(size 0.635 0.4064)
					(thickness 0.1524)
				)
				(justify left)
			)
		)
		(fp_text user "20"
			(at 2.277618 2.92735 0)
			(unlocked yes)
			(layer "F.SilkS")
			(effects
				(font
					(size 0.635 0.4064)
					(thickness 0.1524)
				)
				(justify left)
			)
		)
		(fp_text user "31"
			(at 1.8542 -3.172968 90)
			(unlocked yes)
			(layer "F.Fab")
			(effects
				(font
					(size 0.635 0.4064)
					(thickness 0.1524)
				)
				(justify left)
			)
		)
		(fp_text user "40"
			(at -3.2004 -3.096768 90)
			(unlocked yes)
			(layer "F.Fab")
			(effects
				(font
					(size 0.635 0.4064)
					(thickness 0.1524)
				)
				(justify left)
			)
		)
		(fp_text user "30"
			(at 3.096768 -2.51714 0)
			(unlocked yes)
			(layer "F.Fab")
			(effects
				(font
					(size 0.635 0.4064)
					(thickness 0.1524)
				)
				(justify left)
			)
		)
		(fp_text user "21"
			(at 2.974848 1.82372 0)
			(unlocked yes)
			(layer "F.Fab")
			(effects
				(font
					(size 0.635 0.4064)
					(thickness 0.1524)
				)
				(justify left)
			)
		)
		(fp_text user "10"
			(at -3.253232 2.1336 0)
			(unlocked yes)
			(layer "F.Fab")
			(effects
				(font
					(size 0.635 0.4064)
					(thickness 0.1524)
				)
				(justify left)
			)
		)
		(fp_text user "20"
			(at 2.0828 3.253232 90)
			(unlocked yes)
			(layer "F.Fab")
			(effects
				(font
					(size 0.635 0.4064)
					(thickness 0.1524)
				)
				(justify left)
			)
		)
		(fp_text user "11"
			(at -2.8702 3.278632 90)
			(unlocked yes)
			(layer "F.Fab")
			(effects
				(font
					(size 0.635 0.4064)
					(thickness 0.1524)
				)
				(justify left)
			)
		)
		(pad "1" smd rect
			(at -2.400046 -1.800098)
			(size 0.1778 0.6096)
			(layers "F.Cu" "F.Mask" "F.Paste")
			(net "PVCCFA_EHV_CPU1_BPWM1")
		)
		(pad "2" smd rect
			(at -2.400046 -1.400048)
			(size 0.1778 0.6096)
			(layers "F.Cu" "F.Mask" "F.Paste")
			(net "NC_PVCCINFAON_CPU1_APWM7")
		)
		(pad "3" smd rect
			(at -2.400046 -0.999998)
			(size 0.1778 0.6096)
			(layers "F.Cu" "F.Mask" "F.Paste")
			(net "NC_PVCCINFAON_CPU1_APWM6")
		)
		(pad "4" smd rect
			(at -2.400046 -0.599948)
			(size 0.1778 0.6096)
			(layers "F.Cu" "F.Mask" "F.Paste")
			(net "NC_PVCCINFAON_CPU1_APWM5")
		)
		(pad "5" smd rect
			(at -2.400046 -0.199898)
			(size 0.1778 0.6096)
			(layers "F.Cu" "F.Mask" "F.Paste")
			(net "NC_PVCCINFAON_CPU1_APWM4")
		)
		(pad "6" smd rect
			(at -2.400046 0.199898)
			(size 0.1778 0.6096)
			(layers "F.Cu" "F.Mask" "F.Paste")
			(net "NC_PVCCINFAON_CPU1_APWM3")
		)
		(pad "7" smd rect
			(at -2.400046 0.599948)
			(size 0.1778 0.6096)
			(layers "F.Cu" "F.Mask" "F.Paste")
			(net "PVCCINFAON_CPU1_APWM2")
		)
		(pad "8" smd rect
			(at -2.400046 0.999998)
			(size 0.1778 0.6096)
			(layers "F.Cu" "F.Mask" "F.Paste")
			(net "PVCCINFAON_CPU1_APWM1")
		)
		(pad "9" smd rect
			(at -2.400046 1.400048)
			(size 0.1778 0.6096)
			(layers "F.Cu" "F.Mask" "F.Paste")
			(net "SMB_DIO_PVCCINFAON_CPU1")
		)
		(pad "10" smd rect
			(at -2.400046 1.800098)
			(size 0.1778 0.6096)
			(layers "F.Cu" "F.Mask" "F.Paste")
			(net "SMB_CLK_PVCCINFAON_CPU1")
		)
		(pad "11" smd rect
			(at -1.800098 2.400046 90)
			(size 0.1778 0.6096)
			(layers "F.Cu" "F.Mask" "F.Paste")
			(net "NC_PVCCINFAON_CPU1_SMB_ALERT")
		)
		(pad "12" smd rect
			(at -1.400048 2.400046 90)
			(size 0.1778 0.6096)
			(layers "F.Cu" "F.Mask" "F.Paste")
			(net "PWRGD_PVCCINFAON_CPU1_R")
		)
		(pad "13" smd rect
			(at -0.999998 2.400046 90)
			(size 0.1778 0.6096)
			(layers "F.Cu" "F.Mask" "F.Paste")
			(net "PVCCINFAON_CPU1_EN_R")
		)
		(pad "14" smd rect
			(at -0.599948 2.400046 90)
			(size 0.1778 0.6096)
			(layers "F.Cu" "F.Mask" "F.Paste")
			(net "IRQ_PVCCFA_CPU1_VRHOT_N")
		)
		(pad "15" smd rect
			(at -0.199898 2.400046 90)
			(size 0.1778 0.6096)
			(layers "F.Cu" "F.Mask" "F.Paste")
			(net "PVCCINFAON_CPU1_PIN_ALERT")
		)
		(pad "16" smd rect
			(at 0.199898 2.400046 90)
			(size 0.1778 0.6096)
			(layers "F.Cu" "F.Mask" "F.Paste")
			(net "PWRGD_PVCCFA_EHV_CPU1_R")
		)
		(pad "17" smd rect
			(at 0.599948 2.400046 90)
			(size 0.1778 0.6096)
			(layers "F.Cu" "F.Mask" "F.Paste")
			(net "SVID_CLK_PVCCINFAON_CPU1_R")
		)
		(pad "18" smd rect
			(at 0.999998 2.400046 90)
			(size 0.1778 0.6096)
			(layers "F.Cu" "F.Mask" "F.Paste")
			(net "SVID_DIO_PVCCINFAON_CPU1_R")
		)
		(pad "19" smd rect
			(at 1.400048 2.400046 90)
			(size 0.1778 0.6096)
			(layers "F.Cu" "F.Mask" "F.Paste")
			(net "SVID_ALERT_PVCCINFAON_CPU1_R")
		)
		(pad "20" smd rect
			(at 1.800098 2.400046 90)
			(size 0.1778 0.6096)
			(layers "F.Cu" "F.Mask" "F.Paste")
			(net "PVCCFA_EHV_CPU1_EN_R")
		)
		(pad "21" smd rect
			(at 2.400046 1.800098)
			(size 0.1778 0.6096)
			(layers "F.Cu" "F.Mask" "F.Paste")
			(net "SH_PVCCINFAON_CPU1_R")
		)
		(pad "22" smd rect
			(at 2.400046 1.400048)
			(size 0.1778 0.6096)
			(layers "F.Cu" "F.Mask" "F.Paste")
			(net "VSENSE_PVCCINFAON_CPU1_DN")
		)
		(pad "23" smd rect
			(at 2.400046 0.999998)
			(size 0.1778 0.6096)
			(layers "F.Cu" "F.Mask" "F.Paste")
			(net "PVCCINFAON_CPU1_ACSP1")
		)
		(pad "24" smd rect
			(at 2.400046 0.599948)
			(size 0.1778 0.6096)
			(layers "F.Cu" "F.Mask" "F.Paste")
			(net "PVCCINFAON_CPU1_ACSP2")
		)
		(pad "25" smd rect
			(at 2.400046 0.199898)
			(size 0.1778 0.6096)
			(layers "F.Cu" "F.Mask" "F.Paste")
			(net "NC_PVCCINFAON_CPU1_ACSP3")
		)
		(pad "26" smd rect
			(at 2.400046 -0.199898)
			(size 0.1778 0.6096)
			(layers "F.Cu" "F.Mask" "F.Paste")
			(net "NC_PVCCINFAON_CPU1_ACSP4")
		)
		(pad "27" smd rect
			(at 2.400046 -0.599948)
			(size 0.1778 0.6096)
			(layers "F.Cu" "F.Mask" "F.Paste")
			(net "NC_PVCCINFAON_CPU1_ACSP5")
		)
		(pad "28" smd rect
			(at 2.400046 -0.999998)
			(size 0.1778 0.6096)
			(layers "F.Cu" "F.Mask" "F.Paste")
			(net "NC_PVCCINFAON_CPU1_ACSP6")
		)
		(pad "29" smd rect
			(at 2.400046 -1.400048)
			(size 0.1778 0.6096)
			(layers "F.Cu" "F.Mask" "F.Paste")
			(net "NC_PVCCINFAON_CPU1_ACSP7")
		)
		(pad "30" smd rect
			(at 2.400046 -1.800098)
			(size 0.1778 0.6096)
			(layers "F.Cu" "F.Mask" "F.Paste")
			(net "PVCCFA_EHV_CPU1_BCSP1")
		)
		(pad "31" smd rect
			(at 1.800098 -2.400046 90)
			(size 0.1778 0.6096)
			(layers "F.Cu" "F.Mask" "F.Paste")
			(net "VSENSE_PVCCFA_EHV_CPU1_DN")
		)
		(pad "32" smd rect
			(at 1.400048 -2.400046 90)
			(size 0.1778 0.6096)
			(layers "F.Cu" "F.Mask" "F.Paste")
			(net "SH_PVCCFA_EHV_CPU1_R")
		)
		(pad "33" smd rect
			(at 0.999998 -2.400046 90)
			(size 0.1778 0.6096)
			(layers "F.Cu" "F.Mask" "F.Paste")
			(net "PVCCINFAON_CPU1_VR_FAULT")
		)
		(pad "34" smd rect
			(at 0.599948 -2.400046 90)
			(size 0.1778 0.6096)
			(layers "F.Cu" "F.Mask" "F.Paste")
			(net "PVCCINFAON_CPU1_ADDR")
		)
		(pad "35" smd rect
			(at 0.199898 -2.400046 90)
			(size 0.1778 0.6096)
			(layers "F.Cu" "F.Mask" "F.Paste")
			(net "PVCCINFAON_CPU1_ATSEN")
		)
		(pad "36" smd rect
			(at -0.199898 -2.400046 90)
			(size 0.1778 0.6096)
			(layers "F.Cu" "F.Mask" "F.Paste")
			(net "PVCCFA_EHV_CPU1_BTSEN")
		)
		(pad "37" smd rect
			(at -0.599948 -2.400046 90)
			(size 0.1778 0.6096)
			(layers "F.Cu" "F.Mask" "F.Paste")
			(net "PVCCINFAON_CPU1_CSPIN")
		)
		(pad "38" smd rect
			(at -0.999998 -2.400046 90)
			(size 0.1778 0.6096)
			(layers "F.Cu" "F.Mask" "F.Paste")
			(net "PVCCINFAON_CPU1_VIN_CSNIN")
		)
		(pad "39" smd rect
			(at -1.400048 -2.400046 90)
			(size 0.1778 0.6096)
			(layers "F.Cu" "F.Mask" "F.Paste")
			(net "PVCCINFAON_CPU1_VCC")
		)
		(pad "40" smd rect
			(at -1.800098 -2.400046 90)
			(size 0.1778 0.6096)
			(layers "F.Cu" "F.Mask" "F.Paste")
			(net "PVCCINFAON_CPU1_VREF")
		)
		(pad "TH" smd rect
			(at 0 0 90)
			(size 3.6576 3.6576)
			(layers "F.Cu" "F.Mask" "F.Paste")
			(net "GND")
		)
		(zone
			(layer "F.Cu")
			(hatch none 0.5)
			(connect_pads
				(clearance 0)
			)
			(min_thickness 0.25)
			(keepout
				(tracks not_allowed)
				(vias allowed)
				(pads allowed)
				(copperpour not_allowed)
				(footprints allowed)
			)
			(placement
				(enabled no)
				(sheetname "")
			)
			(fill
				(thermal_gap 0.5)
				(thermal_bridge_width 0.5)
				(island_removal_mode 0)
			)
			(polygon
				(pts
					(xy 30.02915 -127.601472) (xy 30.02915 -131.665472) (xy 34.09315 -131.665472) (xy 34.09315 -127.601472)
					(xy 30.20695 -127.601472) (xy 30.20695 -127.753872) (xy 33.94075 -127.753872) (xy 33.94075 -131.513072)
					(xy 30.18155 -131.513072) (xy 30.18155 -127.601472)
				)
			)
		)
	)
	(footprint ""
		(layer "F.Cu")
		(at 239.152684 -54.736238 180)
		(property "Reference" "C1994"
			(at 0 0 180)
			(layer "F.SilkS")
			(hide yes)
			(effects
				(font
					(size 1.27 1.27)
				)
			)
		)
		(property "Value" ""
			(at 0 0 180)
			(layer "F.Fab")
			(effects
				(font
					(size 1.27 1.27)
				)
			)
		)
		(duplicate_pad_numbers_are_jumpers no)
		(fp_line
			(start 0.299974 0.150114)
			(end -0.299974 0.150114)
			(stroke
				(width 0.1)
				(type default)
			)
			(layer "F.Fab")
		)
		(fp_line
			(start 0.299974 -0.150114)
			(end 0.299974 0.150114)
			(stroke
				(width 0.1)
				(type default)
			)
			(layer "F.Fab")
		)
		(fp_line
			(start -0.299974 0.150114)
			(end -0.299974 -0.150114)
			(stroke
				(width 0.1)
				(type default)
			)
			(layer "F.Fab")
		)
		(fp_line
			(start -0.299974 -0.150114)
			(end 0.299974 -0.150114)
			(stroke
				(width 0.1)
				(type default)
			)
			(layer "F.Fab")
		)
		(pad "1" smd rect
			(at -0.2667 0 180)
			(size 0.3048 0.381)
			(layers "F.Cu" "F.Mask" "F.Paste")
			(net "P3E_PCH_E1S_TX_DN<1>")
		)
		(pad "2" smd rect
			(at 0.2667 0 180)
			(size 0.3048 0.381)
			(layers "F.Cu" "F.Mask" "F.Paste")
			(net "P3E_PCH_E1S_TX_C_DN<1>")
		)
		(zone
			(layer "In1.Cu")
			(hatch none 0.5)
			(connect_pads
				(clearance 0)
			)
			(min_thickness 0.25)
			(keepout
				(tracks not_allowed)
				(vias allowed)
				(pads allowed)
				(copperpour not_allowed)
				(footprints allowed)
			)
			(placement
				(enabled no)
				(sheetname "")
			)
			(fill
				(thermal_gap 0.5)
				(thermal_bridge_width 0.5)
				(island_removal_mode 0)
			)
			(polygon
				(pts
					(arc
						(start 239.012984 -54.976522)
						(mid 239.066866 -54.954204)
						(end 239.089184 -54.900322)
					)
					(arc
						(start 239.089184 -54.570122)
						(mid 239.066866 -54.51624)
						(end 239.012984 -54.493922)
					)
					(arc
						(start 238.758984 -54.493922)
						(mid 238.705102 -54.51624)
						(end 238.682784 -54.570122)
					)
					(arc
						(start 238.682784 -54.900322)
						(mid 238.705102 -54.954204)
						(end 238.758984 -54.976522)
					)
				)
			)
		)
		(zone
			(layer "In1.Cu")
			(hatch none 0.5)
			(connect_pads
				(clearance 0)
			)
			(min_thickness 0.25)
			(keepout
				(tracks not_allowed)
				(vias allowed)
				(pads allowed)
				(copperpour not_allowed)
				(footprints allowed)
			)
			(placement
				(enabled no)
				(sheetname "")
			)
			(fill
				(thermal_gap 0.5)
				(thermal_bridge_width 0.5)
				(island_removal_mode 0)
			)
			(polygon
				(pts
					(arc
						(start 239.546384 -54.976522)
						(mid 239.600266 -54.954204)
						(end 239.622584 -54.900322)
					)
					(arc
						(start 239.622584 -54.570122)
						(mid 239.600266 -54.51624)
						(end 239.546384 -54.493922)
					)
					(arc
						(start 239.292384 -54.493922)
						(mid 239.238502 -54.51624)
						(end 239.216184 -54.570122)
					)
					(arc
						(start 239.216184 -54.900322)
						(mid 239.238502 -54.954204)
						(end 239.292384 -54.976522)
					)
				)
			)
		)
	)
	(footprint ""
		(layer "F.Cu")
		(at 278.474678 -420.6113 90)
		(property "Reference" "U369"
			(at -1.6002 3.870452 90)
			(unlocked yes)
			(layer "F.SilkS")
			(effects
				(font
					(size 0.7874 0.5842)
					(thickness 0.1524)
				)
				(justify left)
			)
		)
		(property "Value" ""
			(at 0 0 90)
			(layer "F.Fab")
			(effects
				(font
					(size 1.27 1.27)
				)
			)
		)
		(duplicate_pad_numbers_are_jumpers no)
		(fp_line
			(start 2.03581 -1.525016)
			(end 0.82423 -1.525016)
			(stroke
				(width 0.1524)
				(type default)
			)
			(layer "F.SilkS")
		)
		(fp_line
			(start 0.82423 -1.525016)
			(end 0 -0.649986)
			(stroke
				(width 0.1524)
				(type default)
			)
			(layer "F.SilkS")
		)
		(fp_line
			(start -0.82423 -1.525016)
			(end -2.03581 -1.525016)
			(stroke
				(width 0.1524)
				(type default)
			)
			(layer "F.SilkS")
		)
		(fp_line
			(start -2.03581 -1.525016)
			(end -2.03581 1.525016)
			(stroke
				(width 0.1524)
				(type default)
			)
			(layer "F.SilkS")
		)
		(fp_line
			(start 0 -0.649986)
			(end -0.82423 -1.525016)
			(stroke
				(width 0.1524)
				(type default)
			)
			(layer "F.SilkS")
		)
		(fp_line
			(start 2.03581 1.525016)
			(end 2.03581 -1.525016)
			(stroke
				(width 0.1524)
				(type default)
			)
			(layer "F.SilkS")
		)
		(fp_line
			(start -2.03581 1.525016)
			(end 2.03581 1.525016)
			(stroke
				(width 0.1524)
				(type default)
			)
			(layer "F.SilkS")
		)
		(fp_poly
			(pts
				(xy -1.501902 -1.539748) (xy -1.886458 -2.309368) (xy -1.117092 -2.309368)
			)
			(stroke
				(width 0)
				(type default)
			)
			(fill yes)
			(layer "F.SilkS")
		)
		(fp_line
			(start 0.87503 -1.525016)
			(end -0.87503 -1.525016)
			(stroke
				(width 0.1)
				(type default)
			)
			(layer "F.Fab")
		)
		(fp_line
			(start -0.87503 -1.525016)
			(end -0.87503 1.525016)
			(stroke
				(width 0.1)
				(type default)
			)
			(layer "F.Fab")
		)
		(fp_line
			(start 0.87503 1.525016)
			(end 0.87503 -1.525016)
			(stroke
				(width 0.1)
				(type default)
			)
			(layer "F.Fab")
		)
		(fp_line
			(start -0.87503 1.525016)
			(end 0.87503 1.525016)
			(stroke
				(width 0.1)
				(type default)
			)
			(layer "F.Fab")
		)
		(fp_poly
			(pts
				(xy -2.12979 -0.943356) (xy -2.89941 -0.5588) (xy -2.89941 -1.328166)
			)
			(stroke
				(width 0)
				(type default)
			)
			(fill yes)
			(layer "F.Fab")
		)
		(pad "1" smd rect
			(at -1.35001 -0.94996)
			(size 0.6096 1.1176)
			(layers "F.Cu" "F.Mask" "F.Paste")
			(net "A_HSC_LOW_GATE")
		)
		(pad "2" smd rect
			(at -1.35001 0)
			(size 0.6096 1.1176)
			(layers "F.Cu" "F.Mask" "F.Paste")
			(net "GND")
		)
		(pad "3" smd rect
			(at -1.35001 0.94996)
			(size 0.6096 1.1176)
			(layers "F.Cu" "F.Mask" "F.Paste")
			(net "A_HSC_LOW")
		)
		(pad "4" smd rect
			(at 1.35001 0.94996)
			(size 0.6096 1.1176)
			(layers "F.Cu" "F.Mask" "F.Paste")
			(net "A_HSC_HIGH")
		)
		(pad "5" smd rect
			(at 1.35001 0)
			(size 0.6096 1.1176)
			(layers "F.Cu" "F.Mask" "F.Paste")
			(net "U369_VDD")
		)
		(pad "6" smd rect
			(at 1.35001 -0.94996)
			(size 0.6096 1.1176)
			(layers "F.Cu" "F.Mask" "F.Paste")
			(net "HSC_D_OC")
		)
	)
	(footprint ""
		(layer "F.Cu")
		(at 117.526816 -249.320558 -90)
		(property "Reference" "C278"
			(at 0 0 270)
			(layer "F.SilkS")
			(hide yes)
			(effects
				(font
					(size 1.27 1.27)
				)
			)
		)
		(property "Value" ""
			(at 0 0 270)
			(layer "F.Fab")
			(effects
				(font
					(size 1.27 1.27)
				)
			)
		)
		(duplicate_pad_numbers_are_jumpers no)
		(fp_line
			(start -0.7874 0.4064)
			(end -0.7874 -0.4064)
			(stroke
				(width 0.1524)
				(type default)
			)
			(layer "F.SilkS")
		)
		(fp_line
			(start 0.7874 0.4064)
			(end -0.7874 0.4064)
			(stroke
				(width 0.1524)
				(type default)
			)
			(layer "F.SilkS")
		)
		(fp_line
			(start -0.7874 -0.4064)
			(end 0.7874 -0.4064)
			(stroke
				(width 0.1524)
				(type default)
			)
			(layer "F.SilkS")
		)
		(fp_line
			(start 0.7874 -0.4064)
			(end 0.7874 0.4064)
			(stroke
				(width 0.1524)
				(type default)
			)
			(layer "F.SilkS")
		)
		(fp_line
			(start -0.67945 0.3048)
			(end -0.67945 -0.305054)
			(stroke
				(width 0.1)
				(type default)
			)
			(layer "F.Fab")
		)
		(fp_line
			(start -0.12065 0.3048)
			(end -0.67945 0.3048)
			(stroke
				(width 0.1)
				(type default)
			)
			(layer "F.Fab")
		)
		(fp_line
			(start 0.120396 0.3048)
			(end 0.120396 0.2794)
			(stroke
				(width 0.1)
				(type default)
			)
			(layer "F.Fab")
		)
		(fp_line
			(start 0.67945 0.3048)
			(end 0.120396 0.3048)
			(stroke
				(width 0.1)
				(type default)
			)
			(layer "F.Fab")
		)
		(fp_line
			(start -0.12065 0.2794)
			(end -0.12065 0.3048)
			(stroke
				(width 0.1)
				(type default)
			)
			(layer "F.Fab")
		)
		(fp_line
			(start 0.120396 0.2794)
			(end -0.12065 0.2794)
			(stroke
				(width 0.1)
				(type default)
			)
			(layer "F.Fab")
		)
		(fp_line
			(start -0.12065 -0.2794)
			(end 0.12065 -0.2794)
			(stroke
				(width 0.1)
				(type default)
			)
			(layer "F.Fab")
		)
		(fp_line
			(start 0.12065 -0.2794)
			(end 0.12065 -0.3048)
			(stroke
				(width 0.1)
				(type default)
			)
			(layer "F.Fab")
		)
		(fp_line
			(start 0.12065 -0.3048)
			(end 0.67945 -0.3048)
			(stroke
				(width 0.1)
				(type default)
			)
			(layer "F.Fab")
		)
		(fp_line
			(start 0.67945 -0.3048)
			(end 0.67945 0.3048)
			(stroke
				(width 0.1)
				(type default)
			)
			(layer "F.Fab")
		)
		(fp_line
			(start -0.67945 -0.305054)
			(end -0.12065 -0.305054)
			(stroke
				(width 0.1)
				(type default)
			)
			(layer "F.Fab")
		)
		(fp_line
			(start -0.12065 -0.305054)
			(end -0.12065 -0.2794)
			(stroke
				(width 0.1)
				(type default)
			)
			(layer "F.Fab")
		)
		(pad "1" smd circle
			(at -0.40005 0 270)
			(size 0 0)
			(layers "F.Cu" "F.Mask" "F.Paste")
			(net "PVCCIN_CPU1")
		)
		(pad "2" smd circle
			(at 0.40005 0 270)
			(size 0 0)
			(layers "F.Cu" "F.Mask" "F.Paste")
			(net "GND")
		)
	)
	(footprint ""
		(layer "F.Cu")
		(at 35.980878 -17.623536 90)
		(property "Reference" "C821"
			(at 0 0 90)
			(layer "F.SilkS")
			(hide yes)
			(effects
				(font
					(size 1.27 1.27)
				)
			)
		)
		(property "Value" ""
			(at 0 0 90)
			(layer "F.Fab")
			(effects
				(font
					(size 1.27 1.27)
				)
			)
		)
		(duplicate_pad_numbers_are_jumpers no)
		(fp_line
			(start 0.299974 -0.150114)
			(end 0.299974 0.150114)
			(stroke
				(width 0.1)
				(type default)
			)
			(layer "F.Fab")
		)
		(fp_line
			(start -0.299974 -0.150114)
			(end 0.299974 -0.150114)
			(stroke
				(width 0.1)
				(type default)
			)
			(layer "F.Fab")
		)
		(fp_line
			(start 0.299974 0.150114)
			(end -0.299974 0.150114)
			(stroke
				(width 0.1)
				(type default)
			)
			(layer "F.Fab")
		)
		(fp_line
			(start -0.299974 0.150114)
			(end -0.299974 -0.150114)
			(stroke
				(width 0.1)
				(type default)
			)
			(layer "F.Fab")
		)
		(pad "1" smd rect
			(at -0.2667 0 90)
			(size 0.3048 0.381)
			(layers "F.Cu" "F.Mask" "F.Paste")
			(net "P5E_CPU1_PE1_TX_C_DP<8>")
		)
		(pad "2" smd rect
			(at 0.2667 0 90)
			(size 0.3048 0.381)
			(layers "F.Cu" "F.Mask" "F.Paste")
			(net "P5E_CPU1_PE1_TX_DP<8>")
		)
	)
	(footprint ""
		(layer "F.Cu")
		(at 82.306668 -17.745202)
		(property "Reference" "R3831"
			(at 0 0 0)
			(layer "F.SilkS")
			(hide yes)
			(effects
				(font
					(size 1.27 1.27)
				)
			)
		)
		(property "Value" ""
			(at 0 0 0)
			(layer "F.Fab")
			(effects
				(font
					(size 1.27 1.27)
				)
			)
		)
		(duplicate_pad_numbers_are_jumpers no)
		(fp_line
			(start -0.7874 -0.4064)
			(end 0.7874 -0.4064)
			(stroke
				(width 0.1524)
				(type default)
			)
			(layer "F.SilkS")
		)
		(fp_line
			(start -0.7874 0.4064)
			(end -0.7874 -0.4064)
			(stroke
				(width 0.1524)
				(type default)
			)
			(layer "F.SilkS")
		)
		(fp_line
			(start 0.7874 -0.4064)
			(end 0.7874 0.4064)
			(stroke
				(width 0.1524)
				(type default)
			)
			(layer "F.SilkS")
		)
		(fp_line
			(start 0.7874 0.4064)
			(end -0.7874 0.4064)
			(stroke
				(width 0.1524)
				(type default)
			)
			(layer "F.SilkS")
		)
		(fp_line
			(start -0.67945 -0.305054)
			(end -0.12065 -0.305054)
			(stroke
				(width 0.1)
				(type default)
			)
			(layer "F.Fab")
		)
		(fp_line
			(start -0.67945 0.3048)
			(end -0.67945 -0.305054)
			(stroke
				(width 0.1)
				(type default)
			)
			(layer "F.Fab")
		)
		(fp_line
			(start -0.12065 -0.305054)
			(end -0.12065 -0.2794)
			(stroke
				(width 0.1)
				(type default)
			)
			(layer "F.Fab")
		)
		(fp_line
			(start -0.12065 -0.2794)
			(end 0.12065 -0.2794)
			(stroke
				(width 0.1)
				(type default)
			)
			(layer "F.Fab")
		)
		(fp_line
			(start -0.12065 0.2794)
			(end -0.12065 0.3048)
			(stroke
				(width 0.1)
				(type default)
			)
			(layer "F.Fab")
		)
		(fp_line
			(start -0.12065 0.3048)
			(end -0.67945 0.3048)
			(stroke
				(width 0.1)
				(type default)
			)
			(layer "F.Fab")
		)
		(fp_line
			(start 0.120396 0.2794)
			(end -0.12065 0.2794)
			(stroke
				(width 0.1)
				(type default)
			)
			(layer "F.Fab")
		)
		(fp_line
			(start 0.120396 0.3048)
			(end 0.120396 0.2794)
			(stroke
				(width 0.1)
				(type default)
			)
			(layer "F.Fab")
		)
		(fp_line
			(start 0.12065 -0.3048)
			(end 0.67945 -0.3048)
			(stroke
				(width 0.1)
				(type default)
			)
			(layer "F.Fab")
		)
		(fp_line
			(start 0.12065 -0.2794)
			(end 0.12065 -0.3048)
			(stroke
				(width 0.1)
				(type default)
			)
			(layer "F.Fab")
		)
		(fp_line
			(start 0.67945 -0.3048)
			(end 0.67945 0.3048)
			(stroke
				(width 0.1)
				(type default)
			)
			(layer "F.Fab")
		)
		(fp_line
			(start 0.67945 0.3048)
			(end 0.120396 0.3048)
			(stroke
				(width 0.1)
				(type default)
			)
			(layer "F.Fab")
		)
		(pad "1" smd circle
			(at -0.40005 0)
			(size 0 0)
			(layers "F.Cu" "F.Mask" "F.Paste")
			(net "P12V_OCP_PWRGD_2")
		)
		(pad "2" smd circle
			(at 0.40005 0)
			(size 0 0)
			(layers "F.Cu" "F.Mask" "F.Paste")
			(net "HP_LVC3_OCP_V3_2_P12V_PWRGD")
		)
	)
	(footprint ""
		(layer "F.Cu")
		(at 70.41896 -61.158628 90)
		(property "Reference" "PC1322"
			(at 0 0 90)
			(layer "F.SilkS")
			(hide yes)
			(effects
				(font
					(size 1.27 1.27)
				)
			)
		)
		(property "Value" ""
			(at 0 0 90)
			(layer "F.Fab")
			(effects
				(font
					(size 1.27 1.27)
				)
			)
		)
		(duplicate_pad_numbers_are_jumpers no)
		(fp_line
			(start 0.7874 -0.4064)
			(end 0.7874 0.4064)
			(stroke
				(width 0.1524)
				(type default)
			)
			(layer "F.SilkS")
		)
		(fp_line
			(start -0.7874 -0.4064)
			(end 0.7874 -0.4064)
			(stroke
				(width 0.1524)
				(type default)
			)
			(layer "F.SilkS")
		)
		(fp_line
			(start 0.7874 0.4064)
			(end -0.7874 0.4064)
			(stroke
				(width 0.1524)
				(type default)
			)
			(layer "F.SilkS")
		)
		(fp_line
			(start -0.7874 0.4064)
			(end -0.7874 -0.4064)
			(stroke
				(width 0.1524)
				(type default)
			)
			(layer "F.SilkS")
		)
		(fp_line
			(start -0.12065 -0.305054)
			(end -0.12065 -0.2794)
			(stroke
				(width 0.1)
				(type default)
			)
			(layer "F.Fab")
		)
		(fp_line
			(start -0.67945 -0.305054)
			(end -0.12065 -0.305054)
			(stroke
				(width 0.1)
				(type default)
			)
			(layer "F.Fab")
		)
		(fp_line
			(start 0.67945 -0.3048)
			(end 0.67945 0.3048)
			(stroke
				(width 0.1)
				(type default)
			)
			(layer "F.Fab")
		)
		(fp_line
			(start 0.12065 -0.3048)
			(end 0.67945 -0.3048)
			(stroke
				(width 0.1)
				(type default)
			)
			(layer "F.Fab")
		)
		(fp_line
			(start 0.12065 -0.2794)
			(end 0.12065 -0.3048)
			(stroke
				(width 0.1)
				(type default)
			)
			(layer "F.Fab")
		)
		(fp_line
			(start -0.12065 -0.2794)
			(end 0.12065 -0.2794)
			(stroke
				(width 0.1)
				(type default)
			)
			(layer "F.Fab")
		)
		(fp_line
			(start 0.120396 0.2794)
			(end -0.12065 0.2794)
			(stroke
				(width 0.1)
				(type default)
			)
			(layer "F.Fab")
		)
		(fp_line
			(start -0.12065 0.2794)
			(end -0.12065 0.3048)
			(stroke
				(width 0.1)
				(type default)
			)
			(layer "F.Fab")
		)
		(fp_line
			(start 0.67945 0.3048)
			(end 0.120396 0.3048)
			(stroke
				(width 0.1)
				(type default)
			)
			(layer "F.Fab")
		)
		(fp_line
			(start 0.120396 0.3048)
			(end 0.120396 0.2794)
			(stroke
				(width 0.1)
				(type default)
			)
			(layer "F.Fab")
		)
		(fp_line
			(start -0.12065 0.3048)
			(end -0.67945 0.3048)
			(stroke
				(width 0.1)
				(type default)
			)
			(layer "F.Fab")
		)
		(fp_line
			(start -0.67945 0.3048)
			(end -0.67945 -0.305054)
			(stroke
				(width 0.1)
				(type default)
			)
			(layer "F.Fab")
		)
		(pad "1" smd circle
			(at -0.40005 0 90)
			(size 0 0)
			(layers "F.Cu" "F.Mask" "F.Paste")
			(net "P3V3_OCP_GATE_PU207_2")
		)
		(pad "2" smd circle
			(at 0.40005 0 90)
			(size 0 0)
			(layers "F.Cu" "F.Mask" "F.Paste")
			(net "GND")
		)
	)
	(footprint ""
		(layer "F.Cu")
		(at 20.11426 -165.751256)
		(property "Reference" "R1718"
			(at 0 0 0)
			(layer "F.SilkS")
			(hide yes)
			(effects
				(font
					(size 1.27 1.27)
				)
			)
		)
		(property "Value" ""
			(at 0 0 0)
			(layer "F.Fab")
			(effects
				(font
					(size 1.27 1.27)
				)
			)
		)
		(duplicate_pad_numbers_are_jumpers no)
		(fp_line
			(start -0.7874 -0.4064)
			(end 0.7874 -0.4064)
			(stroke
				(width 0.1524)
				(type default)
			)
			(layer "F.SilkS")
		)
		(fp_line
			(start -0.7874 0.4064)
			(end -0.7874 -0.4064)
			(stroke
				(width 0.1524)
				(type default)
			)
			(layer "F.SilkS")
		)
		(fp_line
			(start 0.7874 -0.4064)
			(end 0.7874 0.4064)
			(stroke
				(width 0.1524)
				(type default)
			)
			(layer "F.SilkS")
		)
		(fp_line
			(start 0.7874 0.4064)
			(end -0.7874 0.4064)
			(stroke
				(width 0.1524)
				(type default)
			)
			(layer "F.SilkS")
		)
		(fp_line
			(start -0.67945 -0.305054)
			(end -0.12065 -0.305054)
			(stroke
				(width 0.1)
				(type default)
			)
			(layer "F.Fab")
		)
		(fp_line
			(start -0.67945 0.3048)
			(end -0.67945 -0.305054)
			(stroke
				(width 0.1)
				(type default)
			)
			(layer "F.Fab")
		)
		(fp_line
			(start -0.12065 -0.305054)
			(end -0.12065 -0.2794)
			(stroke
				(width 0.1)
				(type default)
			)
			(layer "F.Fab")
		)
		(fp_line
			(start -0.12065 -0.2794)
			(end 0.12065 -0.2794)
			(stroke
				(width 0.1)
				(type default)
			)
			(layer "F.Fab")
		)
		(fp_line
			(start -0.12065 0.2794)
			(end -0.12065 0.3048)
			(stroke
				(width 0.1)
				(type default)
			)
			(layer "F.Fab")
		)
		(fp_line
			(start -0.12065 0.3048)
			(end -0.67945 0.3048)
			(stroke
				(width 0.1)
				(type default)
			)
			(layer "F.Fab")
		)
		(fp_line
			(start 0.120396 0.2794)
			(end -0.12065 0.2794)
			(stroke
				(width 0.1)
				(type default)
			)
			(layer "F.Fab")
		)
		(fp_line
			(start 0.120396 0.3048)
			(end 0.120396 0.2794)
			(stroke
				(width 0.1)
				(type default)
			)
			(layer "F.Fab")
		)
		(fp_line
			(start 0.12065 -0.3048)
			(end 0.67945 -0.3048)
			(stroke
				(width 0.1)
				(type default)
			)
			(layer "F.Fab")
		)
		(fp_line
			(start 0.12065 -0.2794)
			(end 0.12065 -0.3048)
			(stroke
				(width 0.1)
				(type default)
			)
			(layer "F.Fab")
		)
		(fp_line
			(start 0.67945 -0.3048)
			(end 0.67945 0.3048)
			(stroke
				(width 0.1)
				(type default)
			)
			(layer "F.Fab")
		)
		(fp_line
			(start 0.67945 0.3048)
			(end 0.120396 0.3048)
			(stroke
				(width 0.1)
				(type default)
			)
			(layer "F.Fab")
		)
		(pad "1" smd circle
			(at -0.40005 0)
			(size 0 0)
			(layers "F.Cu" "F.Mask" "F.Paste")
			(net "PVNN_TERM_CPU1")
		)
		(pad "2" smd circle
			(at 0.40005 0)
			(size 0 0)
			(layers "F.Cu" "F.Mask" "F.Paste")
			(net "SVID_CLK1_CPU1_R")
		)
	)
	(footprint ""
		(layer "F.Cu")
		(at 176.078388 -416.729418 180)
		(property "Reference" "R3436"
			(at 0 0 180)
			(layer "F.SilkS")
			(hide yes)
			(effects
				(font
					(size 1.27 1.27)
				)
			)
		)
		(property "Value" ""
			(at 0 0 180)
			(layer "F.Fab")
			(effects
				(font
					(size 1.27 1.27)
				)
			)
		)
		(duplicate_pad_numbers_are_jumpers no)
		(fp_line
			(start 0.7874 0.4064)
			(end -0.7874 0.4064)
			(stroke
				(width 0.1524)
				(type default)
			)
			(layer "F.SilkS")
		)
		(fp_line
			(start 0.7874 -0.4064)
			(end 0.7874 0.4064)
			(stroke
				(width 0.1524)
				(type default)
			)
			(layer "F.SilkS")
		)
		(fp_line
			(start -0.7874 0.4064)
			(end -0.7874 -0.4064)
			(stroke
				(width 0.1524)
				(type default)
			)
			(layer "F.SilkS")
		)
		(fp_line
			(start -0.7874 -0.4064)
			(end 0.7874 -0.4064)
			(stroke
				(width 0.1524)
				(type default)
			)
			(layer "F.SilkS")
		)
		(fp_line
			(start 0.67945 0.3048)
			(end 0.120396 0.3048)
			(stroke
				(width 0.1)
				(type default)
			)
			(layer "F.Fab")
		)
		(fp_line
			(start 0.67945 -0.3048)
			(end 0.67945 0.3048)
			(stroke
				(width 0.1)
				(type default)
			)
			(layer "F.Fab")
		)
		(fp_line
			(start 0.12065 -0.2794)
			(end 0.12065 -0.3048)
			(stroke
				(width 0.1)
				(type default)
			)
			(layer "F.Fab")
		)
		(fp_line
			(start 0.12065 -0.3048)
			(end 0.67945 -0.3048)
			(stroke
				(width 0.1)
				(type default)
			)
			(layer "F.Fab")
		)
		(fp_line
			(start 0.120396 0.3048)
			(end 0.120396 0.2794)
			(stroke
				(width 0.1)
				(type default)
			)
			(layer "F.Fab")
		)
		(fp_line
			(start 0.120396 0.2794)
			(end -0.12065 0.2794)
			(stroke
				(width 0.1)
				(type default)
			)
			(layer "F.Fab")
		)
		(fp_line
			(start -0.12065 0.3048)
			(end -0.67945 0.3048)
			(stroke
				(width 0.1)
				(type default)
			)
			(layer "F.Fab")
		)
		(fp_line
			(start -0.12065 0.2794)
			(end -0.12065 0.3048)
			(stroke
				(width 0.1)
				(type default)
			)
			(layer "F.Fab")
		)
		(fp_line
			(start -0.12065 -0.2794)
			(end 0.12065 -0.2794)
			(stroke
				(width 0.1)
				(type default)
			)
			(layer "F.Fab")
		)
		(fp_line
			(start -0.12065 -0.305054)
			(end -0.12065 -0.2794)
			(stroke
				(width 0.1)
				(type default)
			)
			(layer "F.Fab")
		)
		(fp_line
			(start -0.67945 0.3048)
			(end -0.67945 -0.305054)
			(stroke
				(width 0.1)
				(type default)
			)
			(layer "F.Fab")
		)
		(fp_line
			(start -0.67945 -0.305054)
			(end -0.12065 -0.305054)
			(stroke
				(width 0.1)
				(type default)
			)
			(layer "F.Fab")
		)
		(pad "1" smd circle
			(at -0.40005 0 180)
			(size 0 0)
			(layers "F.Cu" "F.Mask" "F.Paste")
			(net "P3V3_AUX")
		)
		(pad "2" smd circle
			(at 0.40005 0 180)
			(size 0 0)
			(layers "F.Cu" "F.Mask" "F.Paste")
			(net "GPU_HMC_PRSNT_ISO_N")
		)
	)
	(footprint ""
		(layer "F.Cu")
		(at 118.86184 -413.189928 180)
		(property "Reference" "R4476"
			(at 0 0 180)
			(layer "F.SilkS")
			(hide yes)
			(effects
				(font
					(size 1.27 1.27)
				)
			)
		)
		(property "Value" ""
			(at 0 0 180)
			(layer "F.Fab")
			(effects
				(font
					(size 1.27 1.27)
				)
			)
		)
		(duplicate_pad_numbers_are_jumpers no)
		(fp_line
			(start 0.7874 0.4064)
			(end -0.7874 0.4064)
			(stroke
				(width 0.1524)
				(type default)
			)
			(layer "F.SilkS")
		)
		(fp_line
			(start 0.7874 -0.4064)
			(end 0.7874 0.4064)
			(stroke
				(width 0.1524)
				(type default)
			)
			(layer "F.SilkS")
		)
		(fp_line
			(start -0.7874 0.4064)
			(end -0.7874 -0.4064)
			(stroke
				(width 0.1524)
				(type default)
			)
			(layer "F.SilkS")
		)
		(fp_line
			(start -0.7874 -0.4064)
			(end 0.7874 -0.4064)
			(stroke
				(width 0.1524)
				(type default)
			)
			(layer "F.SilkS")
		)
		(fp_line
			(start 0.67945 0.3048)
			(end 0.120396 0.3048)
			(stroke
				(width 0.1)
				(type default)
			)
			(layer "F.Fab")
		)
		(fp_line
			(start 0.67945 -0.3048)
			(end 0.67945 0.3048)
			(stroke
				(width 0.1)
				(type default)
			)
			(layer "F.Fab")
		)
		(fp_line
			(start 0.12065 -0.2794)
			(end 0.12065 -0.3048)
			(stroke
				(width 0.1)
				(type default)
			)
			(layer "F.Fab")
		)
		(fp_line
			(start 0.12065 -0.3048)
			(end 0.67945 -0.3048)
			(stroke
				(width 0.1)
				(type default)
			)
			(layer "F.Fab")
		)
		(fp_line
			(start 0.120396 0.3048)
			(end 0.120396 0.2794)
			(stroke
				(width 0.1)
				(type default)
			)
			(layer "F.Fab")
		)
		(fp_line
			(start 0.120396 0.2794)
			(end -0.12065 0.2794)
			(stroke
				(width 0.1)
				(type default)
			)
			(layer "F.Fab")
		)
		(fp_line
			(start -0.12065 0.3048)
			(end -0.67945 0.3048)
			(stroke
				(width 0.1)
				(type default)
			)
			(layer "F.Fab")
		)
		(fp_line
			(start -0.12065 0.2794)
			(end -0.12065 0.3048)
			(stroke
				(width 0.1)
				(type default)
			)
			(layer "F.Fab")
		)
		(fp_line
			(start -0.12065 -0.2794)
			(end 0.12065 -0.2794)
			(stroke
				(width 0.1)
				(type default)
			)
			(layer "F.Fab")
		)
		(fp_line
			(start -0.12065 -0.305054)
			(end -0.12065 -0.2794)
			(stroke
				(width 0.1)
				(type default)
			)
			(layer "F.Fab")
		)
		(fp_line
			(start -0.67945 0.3048)
			(end -0.67945 -0.305054)
			(stroke
				(width 0.1)
				(type default)
			)
			(layer "F.Fab")
		)
		(fp_line
			(start -0.67945 -0.305054)
			(end -0.12065 -0.305054)
			(stroke
				(width 0.1)
				(type default)
			)
			(layer "F.Fab")
		)
		(pad "1" smd circle
			(at -0.40005 0 180)
			(size 0 0)
			(layers "F.Cu" "F.Mask" "F.Paste")
			(net "FM_PLD_CLKS_DEV_EN")
		)
		(pad "2" smd circle
			(at 0.40005 0 180)
			(size 0 0)
			(layers "F.Cu" "F.Mask" "F.Paste")
			(net "FM_9ZXL045_DEV_EN")
		)
	)
	(footprint ""
		(layer "F.Cu")
		(at 28.081732 -411.434534)
		(property "Reference" "Q107"
			(at 0.0508 -2.306828 0)
			(unlocked yes)
			(layer "F.SilkS")
			(effects
				(font
					(size 0.7874 0.5842)
					(thickness 0.1524)
				)
				(justify left)
			)
		)
		(property "Value" ""
			(at 0 0 0)
			(layer "F.Fab")
			(effects
				(font
					(size 1.27 1.27)
				)
			)
		)
		(duplicate_pad_numbers_are_jumpers no)
		(fp_line
			(start -1.332738 -1.100074)
			(end -0.4826 -1.100074)
			(stroke
				(width 0.1524)
				(type default)
			)
			(layer "F.SilkS")
		)
		(fp_line
			(start -1.332738 1.100074)
			(end -1.332738 -1.100074)
			(stroke
				(width 0.1524)
				(type default)
			)
			(layer "F.SilkS")
		)
		(fp_line
			(start -0.4826 -1.100074)
			(end 0 -0.541274)
			(stroke
				(width 0.1524)
				(type default)
			)
			(layer "F.SilkS")
		)
		(fp_line
			(start 0 -0.541274)
			(end 0.4826 -1.100074)
			(stroke
				(width 0.1524)
				(type default)
			)
			(layer "F.SilkS")
		)
		(fp_line
			(start 0.4826 -1.100074)
			(end 1.332738 -1.100074)
			(stroke
				(width 0.1524)
				(type default)
			)
			(layer "F.SilkS")
		)
		(fp_line
			(start 1.332738 -1.100074)
			(end 1.332738 1.100074)
			(stroke
				(width 0.1524)
				(type default)
			)
			(layer "F.SilkS")
		)
		(fp_line
			(start 1.332738 1.100074)
			(end -1.332738 1.100074)
			(stroke
				(width 0.1524)
				(type default)
			)
			(layer "F.SilkS")
		)
		(fp_poly
			(pts
				(xy -0.542544 -1.945132) (xy -0.893572 -1.24333) (xy -1.2446 -1.945132)
			)
			(stroke
				(width 0)
				(type default)
			)
			(fill yes)
			(layer "F.SilkS")
		)
		(fp_line
			(start -0.674878 -1.100074)
			(end 0.674878 -1.100074)
			(stroke
				(width 0.1)
				(type default)
			)
			(layer "F.Fab")
		)
		(fp_line
			(start -0.674878 1.100074)
			(end -0.674878 -1.100074)
			(stroke
				(width 0.1)
				(type default)
			)
			(layer "F.Fab")
		)
		(fp_line
			(start 0.674878 -1.100074)
			(end 0.674878 1.100074)
			(stroke
				(width 0.1)
				(type default)
			)
			(layer "F.Fab")
		)
		(fp_line
			(start 0.674878 1.100074)
			(end -0.674878 1.100074)
			(stroke
				(width 0.1)
				(type default)
			)
			(layer "F.Fab")
		)
		(fp_poly
			(pts
				(xy -2.2352 -0.298958) (xy -2.2352 -1.001014) (xy -1.533144 -0.649986)
			)
			(stroke
				(width 0)
				(type default)
			)
			(fill yes)
			(layer "F.Fab")
		)
		(pad "1" smd rect
			(at -0.94996 -0.649986 90)
			(size 0.4318 0.508)
			(layers "F.Cu" "F.Mask" "F.Paste")
			(net "GND")
		)
		(pad "2" smd rect
			(at -0.94996 0 90)
			(size 0.4318 0.508)
			(layers "F.Cu" "F.Mask" "F.Paste")
			(net "GPU_PRSNT_N")
		)
		(pad "3" smd rect
			(at -0.94996 0.649986 90)
			(size 0.4318 0.508)
			(layers "F.Cu" "F.Mask" "F.Paste")
			(net "GPU_PRSNT_N_ISO")
		)
		(pad "4" smd rect
			(at 0.94996 0.649986 90)
			(size 0.4318 0.508)
			(layers "F.Cu" "F.Mask" "F.Paste")
			(net "GND")
		)
		(pad "5" smd rect
			(at 0.94996 0 90)
			(size 0.4318 0.508)
			(layers "F.Cu" "F.Mask" "F.Paste")
			(net "GPU_PRSNT")
		)
		(pad "6" smd rect
			(at 0.94996 -0.649986 90)
			(size 0.4318 0.508)
			(layers "F.Cu" "F.Mask" "F.Paste")
			(net "GPU_PRSNT")
		)
	)
	(footprint ""
		(layer "F.Cu")
		(at 87.935562 -53.880258 90)
		(property "Reference" "PR4523"
			(at 0 0 90)
			(layer "F.SilkS")
			(hide yes)
			(effects
				(font
					(size 1.27 1.27)
				)
			)
		)
		(property "Value" ""
			(at 0 0 90)
			(layer "F.Fab")
			(effects
				(font
					(size 1.27 1.27)
				)
			)
		)
		(duplicate_pad_numbers_are_jumpers no)
		(fp_line
			(start 0.7874 -0.4064)
			(end 0.7874 0.4064)
			(stroke
				(width 0.1524)
				(type default)
			)
			(layer "F.SilkS")
		)
		(fp_line
			(start -0.7874 -0.4064)
			(end 0.7874 -0.4064)
			(stroke
				(width 0.1524)
				(type default)
			)
			(layer "F.SilkS")
		)
		(fp_line
			(start 0.7874 0.4064)
			(end -0.7874 0.4064)
			(stroke
				(width 0.1524)
				(type default)
			)
			(layer "F.SilkS")
		)
		(fp_line
			(start -0.7874 0.4064)
			(end -0.7874 -0.4064)
			(stroke
				(width 0.1524)
				(type default)
			)
			(layer "F.SilkS")
		)
		(fp_line
			(start -0.12065 -0.305054)
			(end -0.12065 -0.2794)
			(stroke
				(width 0.1)
				(type default)
			)
			(layer "F.Fab")
		)
		(fp_line
			(start -0.67945 -0.305054)
			(end -0.12065 -0.305054)
			(stroke
				(width 0.1)
				(type default)
			)
			(layer "F.Fab")
		)
		(fp_line
			(start 0.67945 -0.3048)
			(end 0.67945 0.3048)
			(stroke
				(width 0.1)
				(type default)
			)
			(layer "F.Fab")
		)
		(fp_line
			(start 0.12065 -0.3048)
			(end 0.67945 -0.3048)
			(stroke
				(width 0.1)
				(type default)
			)
			(layer "F.Fab")
		)
		(fp_line
			(start 0.12065 -0.2794)
			(end 0.12065 -0.3048)
			(stroke
				(width 0.1)
				(type default)
			)
			(layer "F.Fab")
		)
		(fp_line
			(start -0.12065 -0.2794)
			(end 0.12065 -0.2794)
			(stroke
				(width 0.1)
				(type default)
			)
			(layer "F.Fab")
		)
		(fp_line
			(start 0.120396 0.2794)
			(end -0.12065 0.2794)
			(stroke
				(width 0.1)
				(type default)
			)
			(layer "F.Fab")
		)
		(fp_line
			(start -0.12065 0.2794)
			(end -0.12065 0.3048)
			(stroke
				(width 0.1)
				(type default)
			)
			(layer "F.Fab")
		)
		(fp_line
			(start 0.67945 0.3048)
			(end 0.120396 0.3048)
			(stroke
				(width 0.1)
				(type default)
			)
			(layer "F.Fab")
		)
		(fp_line
			(start 0.120396 0.3048)
			(end 0.120396 0.2794)
			(stroke
				(width 0.1)
				(type default)
			)
			(layer "F.Fab")
		)
		(fp_line
			(start -0.12065 0.3048)
			(end -0.67945 0.3048)
			(stroke
				(width 0.1)
				(type default)
			)
			(layer "F.Fab")
		)
		(fp_line
			(start -0.67945 0.3048)
			(end -0.67945 -0.305054)
			(stroke
				(width 0.1)
				(type default)
			)
			(layer "F.Fab")
		)
		(pad "1" smd circle
			(at -0.40005 0 90)
			(size 0 0)
			(layers "F.Cu" "F.Mask" "F.Paste")
			(net "P3V3_OCP_V3_2_R")
		)
		(pad "2" smd circle
			(at 0.40005 0 90)
			(size 0 0)
			(layers "F.Cu" "F.Mask" "F.Paste")
			(net "P3V3_OCP_GATE_2")
		)
	)
	(footprint ""
		(layer "F.Cu")
		(at 406.779984 -16.088614 90)
		(property "Reference" "C851"
			(at 0 0 90)
			(layer "F.SilkS")
			(hide yes)
			(effects
				(font
					(size 1.27 1.27)
				)
			)
		)
		(property "Value" ""
			(at 0 0 90)
			(layer "F.Fab")
			(effects
				(font
					(size 1.27 1.27)
				)
			)
		)
		(duplicate_pad_numbers_are_jumpers no)
		(fp_line
			(start 0.299974 -0.150114)
			(end 0.299974 0.150114)
			(stroke
				(width 0.1)
				(type default)
			)
			(layer "F.Fab")
		)
		(fp_line
			(start -0.299974 -0.150114)
			(end 0.299974 -0.150114)
			(stroke
				(width 0.1)
				(type default)
			)
			(layer "F.Fab")
		)
		(fp_line
			(start 0.299974 0.150114)
			(end -0.299974 0.150114)
			(stroke
				(width 0.1)
				(type default)
			)
			(layer "F.Fab")
		)
		(fp_line
			(start -0.299974 0.150114)
			(end -0.299974 -0.150114)
			(stroke
				(width 0.1)
				(type default)
			)
			(layer "F.Fab")
		)
		(pad "1" smd rect
			(at -0.2667 0 90)
			(size 0.3048 0.381)
			(layers "F.Cu" "F.Mask" "F.Paste")
			(net "P5E_CPU0_PE1_TX_C_DP<9>")
		)
		(pad "2" smd rect
			(at 0.2667 0 90)
			(size 0.3048 0.381)
			(layers "F.Cu" "F.Mask" "F.Paste")
			(net "P5E_CPU0_PE1_TX_DP<9>")
		)
	)
	(footprint ""
		(layer "F.Cu")
		(at 353.242626 -238.160052 90)
		(property "Reference" "C590"
			(at 0 0 90)
			(layer "F.SilkS")
			(hide yes)
			(effects
				(font
					(size 1.27 1.27)
				)
			)
		)
		(property "Value" ""
			(at 0 0 90)
			(layer "F.Fab")
			(effects
				(font
					(size 1.27 1.27)
				)
			)
		)
		(duplicate_pad_numbers_are_jumpers no)
		(fp_line
			(start 0.7874 -0.4064)
			(end 0.7874 0.4064)
			(stroke
				(width 0.1524)
				(type default)
			)
			(layer "F.SilkS")
		)
		(fp_line
			(start -0.7874 -0.4064)
			(end 0.7874 -0.4064)
			(stroke
				(width 0.1524)
				(type default)
			)
			(layer "F.SilkS")
		)
		(fp_line
			(start 0.7874 0.4064)
			(end -0.7874 0.4064)
			(stroke
				(width 0.1524)
				(type default)
			)
			(layer "F.SilkS")
		)
		(fp_line
			(start -0.7874 0.4064)
			(end -0.7874 -0.4064)
			(stroke
				(width 0.1524)
				(type default)
			)
			(layer "F.SilkS")
		)
		(fp_line
			(start -0.12065 -0.305054)
			(end -0.12065 -0.2794)
			(stroke
				(width 0.1)
				(type default)
			)
			(layer "F.Fab")
		)
		(fp_line
			(start -0.67945 -0.305054)
			(end -0.12065 -0.305054)
			(stroke
				(width 0.1)
				(type default)
			)
			(layer "F.Fab")
		)
		(fp_line
			(start 0.67945 -0.3048)
			(end 0.67945 0.3048)
			(stroke
				(width 0.1)
				(type default)
			)
			(layer "F.Fab")
		)
		(fp_line
			(start 0.12065 -0.3048)
			(end 0.67945 -0.3048)
			(stroke
				(width 0.1)
				(type default)
			)
			(layer "F.Fab")
		)
		(fp_line
			(start 0.12065 -0.2794)
			(end 0.12065 -0.3048)
			(stroke
				(width 0.1)
				(type default)
			)
			(layer "F.Fab")
		)
		(fp_line
			(start -0.12065 -0.2794)
			(end 0.12065 -0.2794)
			(stroke
				(width 0.1)
				(type default)
			)
			(layer "F.Fab")
		)
		(fp_line
			(start 0.120396 0.2794)
			(end -0.12065 0.2794)
			(stroke
				(width 0.1)
				(type default)
			)
			(layer "F.Fab")
		)
		(fp_line
			(start -0.12065 0.2794)
			(end -0.12065 0.3048)
			(stroke
				(width 0.1)
				(type default)
			)
			(layer "F.Fab")
		)
		(fp_line
			(start 0.67945 0.3048)
			(end 0.120396 0.3048)
			(stroke
				(width 0.1)
				(type default)
			)
			(layer "F.Fab")
		)
		(fp_line
			(start 0.120396 0.3048)
			(end 0.120396 0.2794)
			(stroke
				(width 0.1)
				(type default)
			)
			(layer "F.Fab")
		)
		(fp_line
			(start -0.12065 0.3048)
			(end -0.67945 0.3048)
			(stroke
				(width 0.1)
				(type default)
			)
			(layer "F.Fab")
		)
		(fp_line
			(start -0.67945 0.3048)
			(end -0.67945 -0.305054)
			(stroke
				(width 0.1)
				(type default)
			)
			(layer "F.Fab")
		)
		(pad "1" smd circle
			(at -0.40005 0 90)
			(size 0 0)
			(layers "F.Cu" "F.Mask" "F.Paste")
			(net "PVNN_MAIN_CPU0")
		)
		(pad "2" smd circle
			(at 0.40005 0 90)
			(size 0 0)
			(layers "F.Cu" "F.Mask" "F.Paste")
			(net "GND")
		)
	)
	(footprint ""
		(layer "F.Cu")
		(at 146.541236 -66.708528)
		(property "Reference" "C1614"
			(at 0 0 0)
			(layer "F.SilkS")
			(hide yes)
			(effects
				(font
					(size 1.27 1.27)
				)
			)
		)
		(property "Value" ""
			(at 0 0 0)
			(layer "F.Fab")
			(effects
				(font
					(size 1.27 1.27)
				)
			)
		)
		(duplicate_pad_numbers_are_jumpers no)
		(fp_line
			(start -0.7874 -0.4064)
			(end 0.7874 -0.4064)
			(stroke
				(width 0.1524)
				(type default)
			)
			(layer "F.SilkS")
		)
		(fp_line
			(start -0.7874 0.4064)
			(end -0.7874 -0.4064)
			(stroke
				(width 0.1524)
				(type default)
			)
			(layer "F.SilkS")
		)
		(fp_line
			(start 0.7874 -0.4064)
			(end 0.7874 0.4064)
			(stroke
				(width 0.1524)
				(type default)
			)
			(layer "F.SilkS")
		)
		(fp_line
			(start 0.7874 0.4064)
			(end -0.7874 0.4064)
			(stroke
				(width 0.1524)
				(type default)
			)
			(layer "F.SilkS")
		)
		(fp_line
			(start -0.67945 -0.305054)
			(end -0.12065 -0.305054)
			(stroke
				(width 0.1)
				(type default)
			)
			(layer "F.Fab")
		)
		(fp_line
			(start -0.67945 0.3048)
			(end -0.67945 -0.305054)
			(stroke
				(width 0.1)
				(type default)
			)
			(layer "F.Fab")
		)
		(fp_line
			(start -0.12065 -0.305054)
			(end -0.12065 -0.2794)
			(stroke
				(width 0.1)
				(type default)
			)
			(layer "F.Fab")
		)
		(fp_line
			(start -0.12065 -0.2794)
			(end 0.12065 -0.2794)
			(stroke
				(width 0.1)
				(type default)
			)
			(layer "F.Fab")
		)
		(fp_line
			(start -0.12065 0.2794)
			(end -0.12065 0.3048)
			(stroke
				(width 0.1)
				(type default)
			)
			(layer "F.Fab")
		)
		(fp_line
			(start -0.12065 0.3048)
			(end -0.67945 0.3048)
			(stroke
				(width 0.1)
				(type default)
			)
			(layer "F.Fab")
		)
		(fp_line
			(start 0.120396 0.2794)
			(end -0.12065 0.2794)
			(stroke
				(width 0.1)
				(type default)
			)
			(layer "F.Fab")
		)
		(fp_line
			(start 0.120396 0.3048)
			(end 0.120396 0.2794)
			(stroke
				(width 0.1)
				(type default)
			)
			(layer "F.Fab")
		)
		(fp_line
			(start 0.12065 -0.3048)
			(end 0.67945 -0.3048)
			(stroke
				(width 0.1)
				(type default)
			)
			(layer "F.Fab")
		)
		(fp_line
			(start 0.12065 -0.2794)
			(end 0.12065 -0.3048)
			(stroke
				(width 0.1)
				(type default)
			)
			(layer "F.Fab")
		)
		(fp_line
			(start 0.67945 -0.3048)
			(end 0.67945 0.3048)
			(stroke
				(width 0.1)
				(type default)
			)
			(layer "F.Fab")
		)
		(fp_line
			(start 0.67945 0.3048)
			(end 0.120396 0.3048)
			(stroke
				(width 0.1)
				(type default)
			)
			(layer "F.Fab")
		)
		(pad "1" smd circle
			(at -0.40005 0)
			(size 0 0)
			(layers "F.Cu" "F.Mask" "F.Paste")
			(net "P3V3_AUX")
		)
		(pad "2" smd circle
			(at 0.40005 0)
			(size 0 0)
			(layers "F.Cu" "F.Mask" "F.Paste")
			(net "GND")
		)
	)
	(footprint ""
		(layer "F.Cu")
		(at 444.87338 -44.670218)
		(property "Reference" "U236"
			(at -3.71348 -2.052828 0)
			(unlocked yes)
			(layer "F.SilkS")
			(effects
				(font
					(size 0.7874 0.5842)
					(thickness 0.1524)
				)
				(justify left)
			)
		)
		(property "Value" ""
			(at 0 0 0)
			(layer "F.Fab")
			(effects
				(font
					(size 1.27 1.27)
				)
			)
		)
		(duplicate_pad_numbers_are_jumpers no)
		(fp_line
			(start -1.463548 -1.549908)
			(end -0.787908 -1.549908)
			(stroke
				(width 0.1524)
				(type default)
			)
			(layer "F.SilkS")
		)
		(fp_line
			(start -1.463548 1.549908)
			(end -1.463548 -1.549908)
			(stroke
				(width 0.1524)
				(type default)
			)
			(layer "F.SilkS")
		)
		(fp_line
			(start -0.787908 -1.549908)
			(end 0 -0.762)
			(stroke
				(width 0.1524)
				(type default)
			)
			(layer "F.SilkS")
		)
		(fp_line
			(start 0 -0.762)
			(end 0.762 -1.549908)
			(stroke
				(width 0.1524)
				(type default)
			)
			(layer "F.SilkS")
		)
		(fp_line
			(start 0.762 -1.549908)
			(end 1.463548 -1.549908)
			(stroke
				(width 0.1524)
				(type default)
			)
			(layer "F.SilkS")
		)
		(fp_line
			(start 1.463548 -1.549908)
			(end 1.463548 1.549908)
			(stroke
				(width 0.1524)
				(type default)
			)
			(layer "F.SilkS")
		)
		(fp_line
			(start 1.463548 1.549908)
			(end -1.463548 1.549908)
			(stroke
				(width 0.1524)
				(type default)
			)
			(layer "F.SilkS")
		)
		(fp_poly
			(pts
				(xy -2.86004 -1.050036) (xy -3.4798 -0.740156) (xy -3.4798 -1.359916)
			)
			(stroke
				(width 0)
				(type default)
			)
			(fill yes)
			(layer "F.SilkS")
		)
		(fp_line
			(start -1.549908 -1.549908)
			(end 1.549908 -1.549908)
			(stroke
				(width 0.1)
				(type default)
			)
			(layer "F.Fab")
		)
		(fp_line
			(start -1.549908 1.549908)
			(end -1.549908 -1.549908)
			(stroke
				(width 0.1)
				(type default)
			)
			(layer "F.Fab")
		)
		(fp_line
			(start 1.549908 -1.549908)
			(end 1.549908 1.549908)
			(stroke
				(width 0.1)
				(type default)
			)
			(layer "F.Fab")
		)
		(fp_line
			(start 1.549908 1.549908)
			(end -1.549908 1.549908)
			(stroke
				(width 0.1)
				(type default)
			)
			(layer "F.Fab")
		)
		(fp_poly
			(pts
				(xy -3.4798 -1.359916) (xy -2.86004 -1.050036) (xy -3.4798 -0.740156)
			)
			(stroke
				(width 0)
				(type default)
			)
			(fill yes)
			(layer "F.Fab")
		)
		(pad "1" smd rect
			(at -2.175002 -1.050036 90)
			(size 0.6096 1.1684)
			(layers "F.Cu" "F.Mask" "F.Paste")
			(net "P3V3_AUX")
		)
		(pad "2" smd rect
			(at -2.175002 -0.32512 90)
			(size 0.4318 1.1684)
			(layers "F.Cu" "F.Mask" "F.Paste")
			(net "SMB_OCP_SFF_3V3AUX_SCL")
		)
		(pad "3" smd rect
			(at -2.175002 0.32512 90)
			(size 0.4318 1.1684)
			(layers "F.Cu" "F.Mask" "F.Paste")
			(net "SMB_OCP_SFF_3V3AUX_SDA")
		)
		(pad "4" smd rect
			(at -2.175002 1.050036 90)
			(size 0.6096 1.1684)
			(layers "F.Cu" "F.Mask" "F.Paste")
			(net "GND")
		)
		(pad "5" smd rect
			(at 2.175002 1.050036 90)
			(size 0.6096 1.1684)
			(layers "F.Cu" "F.Mask" "F.Paste")
			(net "HP_LVC3_OCP_V3_1_R_EN")
		)
		(pad "6" smd rect
			(at 2.175002 0.32512 90)
			(size 0.4318 1.1684)
			(layers "F.Cu" "F.Mask" "F.Paste")
			(net "SMB_OCP_SFF_3V3AUX_BUF_SDA")
		)
		(pad "7" smd rect
			(at 2.175002 -0.32512 90)
			(size 0.4318 1.1684)
			(layers "F.Cu" "F.Mask" "F.Paste")
			(net "SMB_OCP_SFF_3V3AUX_BUF_SCL")
		)
		(pad "8" smd rect
			(at 2.175002 -1.050036 90)
			(size 0.6096 1.1684)
			(layers "F.Cu" "F.Mask" "F.Paste")
			(net "P3V3_OCP_SFF")
		)
	)
	(footprint ""
		(layer "F.Cu")
		(at 46.350428 -98.824034)
		(property "Reference" "C2042"
			(at 0 0 0)
			(layer "F.SilkS")
			(hide yes)
			(effects
				(font
					(size 1.27 1.27)
				)
			)
		)
		(property "Value" ""
			(at 0 0 0)
			(layer "F.Fab")
			(effects
				(font
					(size 1.27 1.27)
				)
			)
		)
		(duplicate_pad_numbers_are_jumpers no)
		(fp_line
			(start -0.7874 -0.4064)
			(end 0.7874 -0.4064)
			(stroke
				(width 0.1524)
				(type default)
			)
			(layer "F.SilkS")
		)
		(fp_line
			(start -0.7874 0.4064)
			(end -0.7874 -0.4064)
			(stroke
				(width 0.1524)
				(type default)
			)
			(layer "F.SilkS")
		)
		(fp_line
			(start 0.7874 -0.4064)
			(end 0.7874 0.4064)
			(stroke
				(width 0.1524)
				(type default)
			)
			(layer "F.SilkS")
		)
		(fp_line
			(start 0.7874 0.4064)
			(end -0.7874 0.4064)
			(stroke
				(width 0.1524)
				(type default)
			)
			(layer "F.SilkS")
		)
		(fp_line
			(start -0.67945 -0.305054)
			(end -0.12065 -0.305054)
			(stroke
				(width 0.1)
				(type default)
			)
			(layer "F.Fab")
		)
		(fp_line
			(start -0.67945 0.3048)
			(end -0.67945 -0.305054)
			(stroke
				(width 0.1)
				(type default)
			)
			(layer "F.Fab")
		)
		(fp_line
			(start -0.12065 -0.305054)
			(end -0.12065 -0.2794)
			(stroke
				(width 0.1)
				(type default)
			)
			(layer "F.Fab")
		)
		(fp_line
			(start -0.12065 -0.2794)
			(end 0.12065 -0.2794)
			(stroke
				(width 0.1)
				(type default)
			)
			(layer "F.Fab")
		)
		(fp_line
			(start -0.12065 0.2794)
			(end -0.12065 0.3048)
			(stroke
				(width 0.1)
				(type default)
			)
			(layer "F.Fab")
		)
		(fp_line
			(start -0.12065 0.3048)
			(end -0.67945 0.3048)
			(stroke
				(width 0.1)
				(type default)
			)
			(layer "F.Fab")
		)
		(fp_line
			(start 0.120396 0.2794)
			(end -0.12065 0.2794)
			(stroke
				(width 0.1)
				(type default)
			)
			(layer "F.Fab")
		)
		(fp_line
			(start 0.120396 0.3048)
			(end 0.120396 0.2794)
			(stroke
				(width 0.1)
				(type default)
			)
			(layer "F.Fab")
		)
		(fp_line
			(start 0.12065 -0.3048)
			(end 0.67945 -0.3048)
			(stroke
				(width 0.1)
				(type default)
			)
			(layer "F.Fab")
		)
		(fp_line
			(start 0.12065 -0.2794)
			(end 0.12065 -0.3048)
			(stroke
				(width 0.1)
				(type default)
			)
			(layer "F.Fab")
		)
		(fp_line
			(start 0.67945 -0.3048)
			(end 0.67945 0.3048)
			(stroke
				(width 0.1)
				(type default)
			)
			(layer "F.Fab")
		)
		(fp_line
			(start 0.67945 0.3048)
			(end 0.120396 0.3048)
			(stroke
				(width 0.1)
				(type default)
			)
			(layer "F.Fab")
		)
		(pad "1" smd circle
			(at -0.40005 0)
			(size 0 0)
			(layers "F.Cu" "F.Mask" "F.Paste")
			(net "P3V3_AUX_ADC_MAM")
		)
		(pad "2" smd circle
			(at 0.40005 0)
			(size 0 0)
			(layers "F.Cu" "F.Mask" "F.Paste")
			(net "GND")
		)
	)
	(footprint ""
		(layer "F.Cu")
		(at 11.895836 -92.687648 -90)
		(property "Reference" "C2041"
			(at 0 0 270)
			(layer "F.SilkS")
			(hide yes)
			(effects
				(font
					(size 1.27 1.27)
				)
			)
		)
		(property "Value" ""
			(at 0 0 270)
			(layer "F.Fab")
			(effects
				(font
					(size 1.27 1.27)
				)
			)
		)
		(duplicate_pad_numbers_are_jumpers no)
		(fp_line
			(start -0.7874 0.4064)
			(end -0.7874 -0.4064)
			(stroke
				(width 0.1524)
				(type default)
			)
			(layer "F.SilkS")
		)
		(fp_line
			(start 0.7874 0.4064)
			(end -0.7874 0.4064)
			(stroke
				(width 0.1524)
				(type default)
			)
			(layer "F.SilkS")
		)
		(fp_line
			(start -0.7874 -0.4064)
			(end 0.7874 -0.4064)
			(stroke
				(width 0.1524)
				(type default)
			)
			(layer "F.SilkS")
		)
		(fp_line
			(start 0.7874 -0.4064)
			(end 0.7874 0.4064)
			(stroke
				(width 0.1524)
				(type default)
			)
			(layer "F.SilkS")
		)
		(fp_line
			(start -0.67945 0.3048)
			(end -0.67945 -0.305054)
			(stroke
				(width 0.1)
				(type default)
			)
			(layer "F.Fab")
		)
		(fp_line
			(start -0.12065 0.3048)
			(end -0.67945 0.3048)
			(stroke
				(width 0.1)
				(type default)
			)
			(layer "F.Fab")
		)
		(fp_line
			(start 0.120396 0.3048)
			(end 0.120396 0.2794)
			(stroke
				(width 0.1)
				(type default)
			)
			(layer "F.Fab")
		)
		(fp_line
			(start 0.67945 0.3048)
			(end 0.120396 0.3048)
			(stroke
				(width 0.1)
				(type default)
			)
			(layer "F.Fab")
		)
		(fp_line
			(start -0.12065 0.2794)
			(end -0.12065 0.3048)
			(stroke
				(width 0.1)
				(type default)
			)
			(layer "F.Fab")
		)
		(fp_line
			(start 0.120396 0.2794)
			(end -0.12065 0.2794)
			(stroke
				(width 0.1)
				(type default)
			)
			(layer "F.Fab")
		)
		(fp_line
			(start -0.12065 -0.2794)
			(end 0.12065 -0.2794)
			(stroke
				(width 0.1)
				(type default)
			)
			(layer "F.Fab")
		)
		(fp_line
			(start 0.12065 -0.2794)
			(end 0.12065 -0.3048)
			(stroke
				(width 0.1)
				(type default)
			)
			(layer "F.Fab")
		)
		(fp_line
			(start 0.12065 -0.3048)
			(end 0.67945 -0.3048)
			(stroke
				(width 0.1)
				(type default)
			)
			(layer "F.Fab")
		)
		(fp_line
			(start 0.67945 -0.3048)
			(end 0.67945 0.3048)
			(stroke
				(width 0.1)
				(type default)
			)
			(layer "F.Fab")
		)
		(fp_line
			(start -0.67945 -0.305054)
			(end -0.12065 -0.305054)
			(stroke
				(width 0.1)
				(type default)
			)
			(layer "F.Fab")
		)
		(fp_line
			(start -0.12065 -0.305054)
			(end -0.12065 -0.2794)
			(stroke
				(width 0.1)
				(type default)
			)
			(layer "F.Fab")
		)
		(pad "1" smd circle
			(at -0.40005 0 270)
			(size 0 0)
			(layers "F.Cu" "F.Mask" "F.Paste")
			(net "RST_USB_HUB_R_N")
		)
		(pad "2" smd circle
			(at 0.40005 0 270)
			(size 0 0)
			(layers "F.Cu" "F.Mask" "F.Paste")
			(net "GND")
		)
	)
	(footprint ""
		(layer "F.Cu")
		(at 434.448204 -103.927402 -90)
		(property "Reference" "PC2089"
			(at 0 0 270)
			(layer "F.SilkS")
			(hide yes)
			(effects
				(font
					(size 1.27 1.27)
				)
			)
		)
		(property "Value" ""
			(at 0 0 270)
			(layer "F.Fab")
			(effects
				(font
					(size 1.27 1.27)
				)
			)
		)
		(duplicate_pad_numbers_are_jumpers no)
		(fp_line
			(start -0.7874 0.4064)
			(end -0.7874 -0.4064)
			(stroke
				(width 0.1524)
				(type default)
			)
			(layer "F.SilkS")
		)
		(fp_line
			(start 0.7874 0.4064)
			(end -0.7874 0.4064)
			(stroke
				(width 0.1524)
				(type default)
			)
			(layer "F.SilkS")
		)
		(fp_line
			(start -0.7874 -0.4064)
			(end 0.7874 -0.4064)
			(stroke
				(width 0.1524)
				(type default)
			)
			(layer "F.SilkS")
		)
		(fp_line
			(start 0.7874 -0.4064)
			(end 0.7874 0.4064)
			(stroke
				(width 0.1524)
				(type default)
			)
			(layer "F.SilkS")
		)
		(fp_line
			(start -0.67945 0.3048)
			(end -0.67945 -0.305054)
			(stroke
				(width 0.1)
				(type default)
			)
			(layer "F.Fab")
		)
		(fp_line
			(start -0.12065 0.3048)
			(end -0.67945 0.3048)
			(stroke
				(width 0.1)
				(type default)
			)
			(layer "F.Fab")
		)
		(fp_line
			(start 0.120396 0.3048)
			(end 0.120396 0.2794)
			(stroke
				(width 0.1)
				(type default)
			)
			(layer "F.Fab")
		)
		(fp_line
			(start 0.67945 0.3048)
			(end 0.120396 0.3048)
			(stroke
				(width 0.1)
				(type default)
			)
			(layer "F.Fab")
		)
		(fp_line
			(start -0.12065 0.2794)
			(end -0.12065 0.3048)
			(stroke
				(width 0.1)
				(type default)
			)
			(layer "F.Fab")
		)
		(fp_line
			(start 0.120396 0.2794)
			(end -0.12065 0.2794)
			(stroke
				(width 0.1)
				(type default)
			)
			(layer "F.Fab")
		)
		(fp_line
			(start -0.12065 -0.2794)
			(end 0.12065 -0.2794)
			(stroke
				(width 0.1)
				(type default)
			)
			(layer "F.Fab")
		)
		(fp_line
			(start 0.12065 -0.2794)
			(end 0.12065 -0.3048)
			(stroke
				(width 0.1)
				(type default)
			)
			(layer "F.Fab")
		)
		(fp_line
			(start 0.12065 -0.3048)
			(end 0.67945 -0.3048)
			(stroke
				(width 0.1)
				(type default)
			)
			(layer "F.Fab")
		)
		(fp_line
			(start 0.67945 -0.3048)
			(end 0.67945 0.3048)
			(stroke
				(width 0.1)
				(type default)
			)
			(layer "F.Fab")
		)
		(fp_line
			(start -0.67945 -0.305054)
			(end -0.12065 -0.305054)
			(stroke
				(width 0.1)
				(type default)
			)
			(layer "F.Fab")
		)
		(fp_line
			(start -0.12065 -0.305054)
			(end -0.12065 -0.2794)
			(stroke
				(width 0.1)
				(type default)
			)
			(layer "F.Fab")
		)
		(pad "1" smd circle
			(at -0.40005 0 270)
			(size 0 0)
			(layers "F.Cu" "F.Mask" "F.Paste")
			(net "P3V3_OCP_GATE_PU202_1")
		)
		(pad "2" smd circle
			(at 0.40005 0 270)
			(size 0 0)
			(layers "F.Cu" "F.Mask" "F.Paste")
			(net "GND")
		)
	)
	(footprint ""
		(layer "F.Cu")
		(at 152.693624 -52.318412)
		(property "Reference" "U264"
			(at 4.867656 -2.900426 0)
			(unlocked yes)
			(layer "F.SilkS")
			(effects
				(font
					(size 0.7874 0.5842)
					(thickness 0.1524)
				)
			)
		)
		(property "Value" ""
			(at 0 0 0)
			(layer "F.Fab")
			(effects
				(font
					(size 1.27 1.27)
				)
			)
		)
		(duplicate_pad_numbers_are_jumpers no)
		(fp_line
			(start -1.500124 -1.500124)
			(end -1.004062 -1.500124)
			(stroke
				(width 0.1524)
				(type default)
			)
			(layer "F.SilkS")
		)
		(fp_line
			(start -1.500124 -1.004062)
			(end -1.500124 -1.500124)
			(stroke
				(width 0.1524)
				(type default)
			)
			(layer "F.SilkS")
		)
		(fp_line
			(start -1.500124 1.500124)
			(end -1.500124 1.004062)
			(stroke
				(width 0.1524)
				(type default)
			)
			(layer "F.SilkS")
		)
		(fp_line
			(start -1.004062 1.500124)
			(end -1.500124 1.500124)
			(stroke
				(width 0.1524)
				(type default)
			)
			(layer "F.SilkS")
		)
		(fp_line
			(start 1.004062 -1.500124)
			(end 1.500124 -1.500124)
			(stroke
				(width 0.1524)
				(type default)
			)
			(layer "F.SilkS")
		)
		(fp_line
			(start 1.500124 -1.500124)
			(end 1.500124 -1.004062)
			(stroke
				(width 0.1524)
				(type default)
			)
			(layer "F.SilkS")
		)
		(fp_line
			(start 1.500124 1.004062)
			(end 1.500124 1.500124)
			(stroke
				(width 0.1524)
				(type default)
			)
			(layer "F.SilkS")
		)
		(fp_line
			(start 1.500124 1.500124)
			(end 1.004062 1.500124)
			(stroke
				(width 0.1524)
				(type default)
			)
			(layer "F.SilkS")
		)
		(fp_poly
			(pts
				(xy -2.196846 -1.60782) (xy -1.83769 -0.530352) (xy -2.915412 -0.889508)
			)
			(stroke
				(width 0)
				(type default)
			)
			(fill yes)
			(layer "F.SilkS")
		)
		(fp_line
			(start -1.500124 -1.500124)
			(end 1.500124 -1.500124)
			(stroke
				(width 0.1)
				(type default)
			)
			(layer "F.Fab")
		)
		(fp_line
			(start -1.500124 1.500124)
			(end -1.500124 -1.500124)
			(stroke
				(width 0.1)
				(type default)
			)
			(layer "F.Fab")
		)
		(fp_line
			(start 1.500124 -1.500124)
			(end 1.500124 1.500124)
			(stroke
				(width 0.1)
				(type default)
			)
			(layer "F.Fab")
		)
		(fp_line
			(start 1.500124 1.500124)
			(end -1.500124 1.500124)
			(stroke
				(width 0.1)
				(type default)
			)
			(layer "F.Fab")
		)
		(fp_poly
			(pts
				(xy -2.847848 -1.258062) (xy -2.847848 -0.242062) (xy -1.831848 -0.750062)
			)
			(stroke
				(width 0)
				(type default)
			)
			(fill yes)
			(layer "F.Fab")
		)
		(pad "1" smd rect
			(at -1.400048 -0.750062 270)
			(size 0.2286 0.6096)
			(layers "F.Cu" "F.Mask" "F.Paste")
			(net "INA230_4_A1")
		)
		(pad "2" smd rect
			(at -1.400048 -0.249936 270)
			(size 0.2286 0.6096)
			(layers "F.Cu" "F.Mask" "F.Paste")
			(net "INA230_4_A0")
		)
		(pad "3" smd rect
			(at -1.400048 0.249936 270)
			(size 0.2286 0.6096)
			(layers "F.Cu" "F.Mask" "F.Paste")
			(net "M2_0_P3V3_ADC_ALERT_R")
		)
		(pad "4" smd rect
			(at -1.400048 0.750062 270)
			(size 0.2286 0.6096)
			(layers "F.Cu" "F.Mask" "F.Paste")
			(net "SMB_INA230_4_3V3AUX_SDA_R1")
		)
		(pad "5" smd rect
			(at -0.750062 1.400048)
			(size 0.2286 0.6096)
			(layers "F.Cu" "F.Mask" "F.Paste")
			(net "SMB_INA230_4_3V3AUX_SCL_R1")
		)
		(pad "6" smd rect
			(at -0.249936 1.400048)
			(size 0.2286 0.6096)
			(layers "F.Cu" "F.Mask" "F.Paste")
			(net "NC_INA230_4_NC0")
		)
		(pad "7" smd rect
			(at 0.249936 1.400048)
			(size 0.2286 0.6096)
			(layers "F.Cu" "F.Mask" "F.Paste")
			(net "NC_INA230_4_NC1")
		)
		(pad "8" smd rect
			(at 0.750062 1.400048)
			(size 0.2286 0.6096)
			(layers "F.Cu" "F.Mask" "F.Paste")
			(net "NC_INA230_4_NC2")
		)
		(pad "9" smd rect
			(at 1.400048 0.750062 270)
			(size 0.2286 0.6096)
			(layers "F.Cu" "F.Mask" "F.Paste")
			(net "P3V3_AUX")
		)
		(pad "10" smd rect
			(at 1.400048 0.249936 270)
			(size 0.2286 0.6096)
			(layers "F.Cu" "F.Mask" "F.Paste")
			(net "GND")
		)
		(pad "11" smd rect
			(at 1.400048 -0.249936 270)
			(size 0.2286 0.6096)
			(layers "F.Cu" "F.Mask" "F.Paste")
			(net "P3V3")
		)
		(pad "12" smd rect
			(at 1.400048 -0.750062 270)
			(size 0.2286 0.6096)
			(layers "F.Cu" "F.Mask" "F.Paste")
			(net "VSENSE_P12V_INA230_4_INN")
		)
		(pad "13" smd rect
			(at 0.750062 -1.400048)
			(size 0.2286 0.6096)
			(layers "F.Cu" "F.Mask" "F.Paste")
			(net "VSENSE_P12V_INA230_4_INP")
		)
		(pad "14" smd rect
			(at 0.249936 -1.400048)
			(size 0.2286 0.6096)
			(layers "F.Cu" "F.Mask" "F.Paste")
			(net "NC_INA230_4_NC3")
		)
		(pad "15" smd rect
			(at -0.249936 -1.400048)
			(size 0.2286 0.6096)
			(layers "F.Cu" "F.Mask" "F.Paste")
			(net "NC_INA230_4_NC4")
		)
		(pad "16" smd rect
			(at -0.750062 -1.400048)
			(size 0.2286 0.6096)
			(layers "F.Cu" "F.Mask" "F.Paste")
			(net "NC_INA230_4_NC5")
		)
		(pad "TH" smd rect
			(at 0 0)
			(size 1.7018 1.7018)
			(layers "F.Cu" "F.Mask" "F.Paste")
			(net "GND")
		)
		(zone
			(layer "F.Cu")
			(hatch none 0.5)
			(connect_pads
				(clearance 0)
			)
			(min_thickness 0.25)
			(keepout
				(tracks not_allowed)
				(vias allowed)
				(pads allowed)
				(copperpour not_allowed)
				(footprints allowed)
			)
			(placement
				(enabled no)
				(sheetname "")
			)
			(fill
				(thermal_gap 0.5)
				(thermal_bridge_width 0.5)
				(island_removal_mode 0)
			)
			(polygon
				(pts
					(xy 151.649176 -52.343812) (xy 151.649176 -53.36286) (xy 153.738072 -53.36286) (xy 153.738072 -51.273964)
					(xy 151.649176 -51.273964) (xy 151.649176 -52.318412) (xy 151.791924 -52.318412) (xy 151.791924 -51.416712)
					(xy 153.595324 -51.416712) (xy 153.595324 -53.220112) (xy 151.791924 -53.220112) (xy 151.791924 -52.343812)
				)
			)
		)
	)
	(footprint ""
		(layer "F.Cu")
		(at 366.72139 -338.3026 -90)
		(property "Reference" "PC1340"
			(at 0 0 270)
			(layer "F.SilkS")
			(hide yes)
			(effects
				(font
					(size 1.27 1.27)
				)
			)
		)
		(property "Value" ""
			(at 0 0 270)
			(layer "F.Fab")
			(effects
				(font
					(size 1.27 1.27)
				)
			)
		)
		(duplicate_pad_numbers_are_jumpers no)
		(fp_line
			(start -0.7874 0.4064)
			(end -0.7874 -0.4064)
			(stroke
				(width 0.1524)
				(type default)
			)
			(layer "F.SilkS")
		)
		(fp_line
			(start 0.7874 0.4064)
			(end -0.7874 0.4064)
			(stroke
				(width 0.1524)
				(type default)
			)
			(layer "F.SilkS")
		)
		(fp_line
			(start -0.7874 -0.4064)
			(end 0.7874 -0.4064)
			(stroke
				(width 0.1524)
				(type default)
			)
			(layer "F.SilkS")
		)
		(fp_line
			(start 0.7874 -0.4064)
			(end 0.7874 0.4064)
			(stroke
				(width 0.1524)
				(type default)
			)
			(layer "F.SilkS")
		)
		(fp_line
			(start -0.67945 0.3048)
			(end -0.67945 -0.305054)
			(stroke
				(width 0.1)
				(type default)
			)
			(layer "F.Fab")
		)
		(fp_line
			(start -0.12065 0.3048)
			(end -0.67945 0.3048)
			(stroke
				(width 0.1)
				(type default)
			)
			(layer "F.Fab")
		)
		(fp_line
			(start 0.120396 0.3048)
			(end 0.120396 0.2794)
			(stroke
				(width 0.1)
				(type default)
			)
			(layer "F.Fab")
		)
		(fp_line
			(start 0.67945 0.3048)
			(end 0.120396 0.3048)
			(stroke
				(width 0.1)
				(type default)
			)
			(layer "F.Fab")
		)
		(fp_line
			(start -0.12065 0.2794)
			(end -0.12065 0.3048)
			(stroke
				(width 0.1)
				(type default)
			)
			(layer "F.Fab")
		)
		(fp_line
			(start 0.120396 0.2794)
			(end -0.12065 0.2794)
			(stroke
				(width 0.1)
				(type default)
			)
			(layer "F.Fab")
		)
		(fp_line
			(start -0.12065 -0.2794)
			(end 0.12065 -0.2794)
			(stroke
				(width 0.1)
				(type default)
			)
			(layer "F.Fab")
		)
		(fp_line
			(start 0.12065 -0.2794)
			(end 0.12065 -0.3048)
			(stroke
				(width 0.1)
				(type default)
			)
			(layer "F.Fab")
		)
		(fp_line
			(start 0.12065 -0.3048)
			(end 0.67945 -0.3048)
			(stroke
				(width 0.1)
				(type default)
			)
			(layer "F.Fab")
		)
		(fp_line
			(start 0.67945 -0.3048)
			(end 0.67945 0.3048)
			(stroke
				(width 0.1)
				(type default)
			)
			(layer "F.Fab")
		)
		(fp_line
			(start -0.67945 -0.305054)
			(end -0.12065 -0.305054)
			(stroke
				(width 0.1)
				(type default)
			)
			(layer "F.Fab")
		)
		(fp_line
			(start -0.12065 -0.305054)
			(end -0.12065 -0.2794)
			(stroke
				(width 0.1)
				(type default)
			)
			(layer "F.Fab")
		)
		(pad "1" smd circle
			(at -0.40005 0 270)
			(size 0 0)
			(layers "F.Cu" "F.Mask" "F.Paste")
			(net "GND")
		)
		(pad "2" smd circle
			(at 0.40005 0 270)
			(size 0 0)
			(layers "F.Cu" "F.Mask" "F.Paste")
			(net "PVCCIN_CPU0_VREF")
		)
	)
	(footprint ""
		(layer "F.Cu")
		(at 19.216878 -17.623536 90)
		(property "Reference" "C809"
			(at 0 0 90)
			(layer "F.SilkS")
			(hide yes)
			(effects
				(font
					(size 1.27 1.27)
				)
			)
		)
		(property "Value" ""
			(at 0 0 90)
			(layer "F.Fab")
			(effects
				(font
					(size 1.27 1.27)
				)
			)
		)
		(duplicate_pad_numbers_are_jumpers no)
		(fp_line
			(start 0.299974 -0.150114)
			(end 0.299974 0.150114)
			(stroke
				(width 0.1)
				(type default)
			)
			(layer "F.Fab")
		)
		(fp_line
			(start -0.299974 -0.150114)
			(end 0.299974 -0.150114)
			(stroke
				(width 0.1)
				(type default)
			)
			(layer "F.Fab")
		)
		(fp_line
			(start 0.299974 0.150114)
			(end -0.299974 0.150114)
			(stroke
				(width 0.1)
				(type default)
			)
			(layer "F.Fab")
		)
		(fp_line
			(start -0.299974 0.150114)
			(end -0.299974 -0.150114)
			(stroke
				(width 0.1)
				(type default)
			)
			(layer "F.Fab")
		)
		(pad "1" smd rect
			(at -0.2667 0 90)
			(size 0.3048 0.381)
			(layers "F.Cu" "F.Mask" "F.Paste")
			(net "P5E_CPU1_PE1_TX_C_DP<14>")
		)
		(pad "2" smd rect
			(at 0.2667 0 90)
			(size 0.3048 0.381)
			(layers "F.Cu" "F.Mask" "F.Paste")
			(net "P5E_CPU1_PE1_TX_DP<14>")
		)
	)
	(footprint ""
		(layer "F.Cu")
		(at 185.7756 -93.91015 90)
		(property "Reference" "R4771"
			(at 0 0 90)
			(layer "F.SilkS")
			(hide yes)
			(effects
				(font
					(size 1.27 1.27)
				)
			)
		)
		(property "Value" ""
			(at 0 0 90)
			(layer "F.Fab")
			(effects
				(font
					(size 1.27 1.27)
				)
			)
		)
		(duplicate_pad_numbers_are_jumpers no)
		(fp_line
			(start 0.7874 -0.4064)
			(end 0.7874 0.4064)
			(stroke
				(width 0.1524)
				(type default)
			)
			(layer "F.SilkS")
		)
		(fp_line
			(start -0.7874 -0.4064)
			(end 0.7874 -0.4064)
			(stroke
				(width 0.1524)
				(type default)
			)
			(layer "F.SilkS")
		)
		(fp_line
			(start 0.7874 0.4064)
			(end -0.7874 0.4064)
			(stroke
				(width 0.1524)
				(type default)
			)
			(layer "F.SilkS")
		)
		(fp_line
			(start -0.7874 0.4064)
			(end -0.7874 -0.4064)
			(stroke
				(width 0.1524)
				(type default)
			)
			(layer "F.SilkS")
		)
		(fp_line
			(start -0.12065 -0.305054)
			(end -0.12065 -0.2794)
			(stroke
				(width 0.1)
				(type default)
			)
			(layer "F.Fab")
		)
		(fp_line
			(start -0.67945 -0.305054)
			(end -0.12065 -0.305054)
			(stroke
				(width 0.1)
				(type default)
			)
			(layer "F.Fab")
		)
		(fp_line
			(start 0.67945 -0.3048)
			(end 0.67945 0.3048)
			(stroke
				(width 0.1)
				(type default)
			)
			(layer "F.Fab")
		)
		(fp_line
			(start 0.12065 -0.3048)
			(end 0.67945 -0.3048)
			(stroke
				(width 0.1)
				(type default)
			)
			(layer "F.Fab")
		)
		(fp_line
			(start 0.12065 -0.2794)
			(end 0.12065 -0.3048)
			(stroke
				(width 0.1)
				(type default)
			)
			(layer "F.Fab")
		)
		(fp_line
			(start -0.12065 -0.2794)
			(end 0.12065 -0.2794)
			(stroke
				(width 0.1)
				(type default)
			)
			(layer "F.Fab")
		)
		(fp_line
			(start 0.120396 0.2794)
			(end -0.12065 0.2794)
			(stroke
				(width 0.1)
				(type default)
			)
			(layer "F.Fab")
		)
		(fp_line
			(start -0.12065 0.2794)
			(end -0.12065 0.3048)
			(stroke
				(width 0.1)
				(type default)
			)
			(layer "F.Fab")
		)
		(fp_line
			(start 0.67945 0.3048)
			(end 0.120396 0.3048)
			(stroke
				(width 0.1)
				(type default)
			)
			(layer "F.Fab")
		)
		(fp_line
			(start 0.120396 0.3048)
			(end 0.120396 0.2794)
			(stroke
				(width 0.1)
				(type default)
			)
			(layer "F.Fab")
		)
		(fp_line
			(start -0.12065 0.3048)
			(end -0.67945 0.3048)
			(stroke
				(width 0.1)
				(type default)
			)
			(layer "F.Fab")
		)
		(fp_line
			(start -0.67945 0.3048)
			(end -0.67945 -0.305054)
			(stroke
				(width 0.1)
				(type default)
			)
			(layer "F.Fab")
		)
		(pad "1" smd circle
			(at -0.40005 0 90)
			(size 0 0)
			(layers "F.Cu" "F.Mask" "F.Paste")
			(net "HP_LVC3_SCM_HSC_PWRGD")
		)
		(pad "2" smd circle
			(at 0.40005 0 90)
			(size 0 0)
			(layers "F.Cu" "F.Mask" "F.Paste")
			(net "HP_LVC3_SCM_HSC_PWRGD_PLD")
		)
	)
	(footprint ""
		(layer "F.Cu")
		(at 435.17312 -42.140886 180)
		(property "Reference" "R1317"
			(at 0 0 180)
			(layer "F.SilkS")
			(hide yes)
			(effects
				(font
					(size 1.27 1.27)
				)
			)
		)
		(property "Value" ""
			(at 0 0 180)
			(layer "F.Fab")
			(effects
				(font
					(size 1.27 1.27)
				)
			)
		)
		(duplicate_pad_numbers_are_jumpers no)
		(fp_line
			(start 0.7874 0.4064)
			(end -0.7874 0.4064)
			(stroke
				(width 0.1524)
				(type default)
			)
			(layer "F.SilkS")
		)
		(fp_line
			(start 0.7874 -0.4064)
			(end 0.7874 0.4064)
			(stroke
				(width 0.1524)
				(type default)
			)
			(layer "F.SilkS")
		)
		(fp_line
			(start -0.7874 0.4064)
			(end -0.7874 -0.4064)
			(stroke
				(width 0.1524)
				(type default)
			)
			(layer "F.SilkS")
		)
		(fp_line
			(start -0.7874 -0.4064)
			(end 0.7874 -0.4064)
			(stroke
				(width 0.1524)
				(type default)
			)
			(layer "F.SilkS")
		)
		(fp_line
			(start 0.67945 0.3048)
			(end 0.120396 0.3048)
			(stroke
				(width 0.1)
				(type default)
			)
			(layer "F.Fab")
		)
		(fp_line
			(start 0.67945 -0.3048)
			(end 0.67945 0.3048)
			(stroke
				(width 0.1)
				(type default)
			)
			(layer "F.Fab")
		)
		(fp_line
			(start 0.12065 -0.2794)
			(end 0.12065 -0.3048)
			(stroke
				(width 0.1)
				(type default)
			)
			(layer "F.Fab")
		)
		(fp_line
			(start 0.12065 -0.3048)
			(end 0.67945 -0.3048)
			(stroke
				(width 0.1)
				(type default)
			)
			(layer "F.Fab")
		)
		(fp_line
			(start 0.120396 0.3048)
			(end 0.120396 0.2794)
			(stroke
				(width 0.1)
				(type default)
			)
			(layer "F.Fab")
		)
		(fp_line
			(start 0.120396 0.2794)
			(end -0.12065 0.2794)
			(stroke
				(width 0.1)
				(type default)
			)
			(layer "F.Fab")
		)
		(fp_line
			(start -0.12065 0.3048)
			(end -0.67945 0.3048)
			(stroke
				(width 0.1)
				(type default)
			)
			(layer "F.Fab")
		)
		(fp_line
			(start -0.12065 0.2794)
			(end -0.12065 0.3048)
			(stroke
				(width 0.1)
				(type default)
			)
			(layer "F.Fab")
		)
		(fp_line
			(start -0.12065 -0.2794)
			(end 0.12065 -0.2794)
			(stroke
				(width 0.1)
				(type default)
			)
			(layer "F.Fab")
		)
		(fp_line
			(start -0.12065 -0.305054)
			(end -0.12065 -0.2794)
			(stroke
				(width 0.1)
				(type default)
			)
			(layer "F.Fab")
		)
		(fp_line
			(start -0.67945 0.3048)
			(end -0.67945 -0.305054)
			(stroke
				(width 0.1)
				(type default)
			)
			(layer "F.Fab")
		)
		(fp_line
			(start -0.67945 -0.305054)
			(end -0.12065 -0.305054)
			(stroke
				(width 0.1)
				(type default)
			)
			(layer "F.Fab")
		)
		(pad "1" smd circle
			(at -0.40005 0 180)
			(size 0 0)
			(layers "F.Cu" "F.Mask" "F.Paste")
			(net "P1V05_PCH_AUX")
		)
		(pad "2" smd circle
			(at 0.40005 0 180)
			(size 0 0)
			(layers "F.Cu" "F.Mask" "F.Paste")
			(net "PU_BIOS_RCVR_BOOT")
		)
	)
	(footprint ""
		(layer "F.Cu")
		(at 16.645382 -104.76611 90)
		(property "Reference" "R3652"
			(at 0 0 90)
			(layer "F.SilkS")
			(hide yes)
			(effects
				(font
					(size 1.27 1.27)
				)
			)
		)
		(property "Value" ""
			(at 0 0 90)
			(layer "F.Fab")
			(effects
				(font
					(size 1.27 1.27)
				)
			)
		)
		(duplicate_pad_numbers_are_jumpers no)
		(fp_line
			(start 0.7874 -0.4064)
			(end 0.7874 0.4064)
			(stroke
				(width 0.1524)
				(type default)
			)
			(layer "F.SilkS")
		)
		(fp_line
			(start -0.7874 -0.4064)
			(end 0.00127 -0.4064)
			(stroke
				(width 0.1524)
				(type default)
			)
			(layer "F.SilkS")
		)
		(fp_line
			(start 0.01905 0.4064)
			(end -0.7874 0.4064)
			(stroke
				(width 0.1524)
				(type default)
			)
			(layer "F.SilkS")
		)
		(fp_line
			(start -0.12065 -0.305054)
			(end -0.12065 -0.2794)
			(stroke
				(width 0.1)
				(type default)
			)
			(layer "F.Fab")
		)
		(fp_line
			(start -0.67945 -0.305054)
			(end -0.12065 -0.305054)
			(stroke
				(width 0.1)
				(type default)
			)
			(layer "F.Fab")
		)
		(fp_line
			(start 0.67945 -0.3048)
			(end 0.67945 0.3048)
			(stroke
				(width 0.1)
				(type default)
			)
			(layer "F.Fab")
		)
		(fp_line
			(start 0.12065 -0.3048)
			(end 0.67945 -0.3048)
			(stroke
				(width 0.1)
				(type default)
			)
			(layer "F.Fab")
		)
		(fp_line
			(start 0.12065 -0.2794)
			(end 0.12065 -0.3048)
			(stroke
				(width 0.1)
				(type default)
			)
			(layer "F.Fab")
		)
		(fp_line
			(start -0.12065 -0.2794)
			(end 0.12065 -0.2794)
			(stroke
				(width 0.1)
				(type default)
			)
			(layer "F.Fab")
		)
		(fp_line
			(start 0.120396 0.2794)
			(end -0.12065 0.2794)
			(stroke
				(width 0.1)
				(type default)
			)
			(layer "F.Fab")
		)
		(fp_line
			(start -0.12065 0.2794)
			(end -0.12065 0.3048)
			(stroke
				(width 0.1)
				(type default)
			)
			(layer "F.Fab")
		)
		(fp_line
			(start 0.67945 0.3048)
			(end 0.120396 0.3048)
			(stroke
				(width 0.1)
				(type default)
			)
			(layer "F.Fab")
		)
		(fp_line
			(start 0.120396 0.3048)
			(end 0.120396 0.2794)
			(stroke
				(width 0.1)
				(type default)
			)
			(layer "F.Fab")
		)
		(fp_line
			(start -0.12065 0.3048)
			(end -0.67945 0.3048)
			(stroke
				(width 0.1)
				(type default)
			)
			(layer "F.Fab")
		)
		(fp_line
			(start -0.67945 0.3048)
			(end -0.67945 -0.305054)
			(stroke
				(width 0.1)
				(type default)
			)
			(layer "F.Fab")
		)
		(pad "1" smd rect
			(at -0.40005 0 270)
			(size 0.4572 0.508)
			(layers "F.Cu" "F.Mask" "F.Paste")
			(net "USB2_P0_R_DN")
		)
		(pad "2" smd rect
			(at 0.40005 0 270)
			(size 0.4572 0.508)
			(layers "F.Cu" "F.Mask" "F.Paste")
			(net "USB2_HOST_BMC_B_DN")
		)
	)
	(footprint ""
		(layer "F.Cu")
		(at 179.352448 -398.191482 180)
		(property "Reference" "PC2193"
			(at 0 0 180)
			(layer "F.SilkS")
			(hide yes)
			(effects
				(font
					(size 1.27 1.27)
				)
			)
		)
		(property "Value" ""
			(at 0 0 180)
			(layer "F.Fab")
			(effects
				(font
					(size 1.27 1.27)
				)
			)
		)
		(duplicate_pad_numbers_are_jumpers no)
		(fp_line
			(start 0.7874 0.4064)
			(end -0.7874 0.4064)
			(stroke
				(width 0.1524)
				(type default)
			)
			(layer "F.SilkS")
		)
		(fp_line
			(start 0.7874 -0.4064)
			(end 0.7874 0.4064)
			(stroke
				(width 0.1524)
				(type default)
			)
			(layer "F.SilkS")
		)
		(fp_line
			(start -0.7874 0.4064)
			(end -0.7874 -0.4064)
			(stroke
				(width 0.1524)
				(type default)
			)
			(layer "F.SilkS")
		)
		(fp_line
			(start -0.7874 -0.4064)
			(end 0.7874 -0.4064)
			(stroke
				(width 0.1524)
				(type default)
			)
			(layer "F.SilkS")
		)
		(fp_line
			(start 0.67945 0.3048)
			(end 0.120396 0.3048)
			(stroke
				(width 0.1)
				(type default)
			)
			(layer "F.Fab")
		)
		(fp_line
			(start 0.67945 -0.3048)
			(end 0.67945 0.3048)
			(stroke
				(width 0.1)
				(type default)
			)
			(layer "F.Fab")
		)
		(fp_line
			(start 0.12065 -0.2794)
			(end 0.12065 -0.3048)
			(stroke
				(width 0.1)
				(type default)
			)
			(layer "F.Fab")
		)
		(fp_line
			(start 0.12065 -0.3048)
			(end 0.67945 -0.3048)
			(stroke
				(width 0.1)
				(type default)
			)
			(layer "F.Fab")
		)
		(fp_line
			(start 0.120396 0.3048)
			(end 0.120396 0.2794)
			(stroke
				(width 0.1)
				(type default)
			)
			(layer "F.Fab")
		)
		(fp_line
			(start 0.120396 0.2794)
			(end -0.12065 0.2794)
			(stroke
				(width 0.1)
				(type default)
			)
			(layer "F.Fab")
		)
		(fp_line
			(start -0.12065 0.3048)
			(end -0.67945 0.3048)
			(stroke
				(width 0.1)
				(type default)
			)
			(layer "F.Fab")
		)
		(fp_line
			(start -0.12065 0.2794)
			(end -0.12065 0.3048)
			(stroke
				(width 0.1)
				(type default)
			)
			(layer "F.Fab")
		)
		(fp_line
			(start -0.12065 -0.2794)
			(end 0.12065 -0.2794)
			(stroke
				(width 0.1)
				(type default)
			)
			(layer "F.Fab")
		)
		(fp_line
			(start -0.12065 -0.305054)
			(end -0.12065 -0.2794)
			(stroke
				(width 0.1)
				(type default)
			)
			(layer "F.Fab")
		)
		(fp_line
			(start -0.67945 0.3048)
			(end -0.67945 -0.305054)
			(stroke
				(width 0.1)
				(type default)
			)
			(layer "F.Fab")
		)
		(fp_line
			(start -0.67945 -0.305054)
			(end -0.12065 -0.305054)
			(stroke
				(width 0.1)
				(type default)
			)
			(layer "F.Fab")
		)
		(pad "1" smd circle
			(at -0.40005 0 180)
			(size 0 0)
			(layers "F.Cu" "F.Mask" "F.Paste")
			(net "HSC_IMON")
		)
		(pad "2" smd circle
			(at 0.40005 0 180)
			(size 0 0)
			(layers "F.Cu" "F.Mask" "F.Paste")
			(net "AGND_HSC")
		)
	)
	(footprint ""
		(layer "F.Cu")
		(at 416.097974 -175.88865 180)
		(property "Reference" "PC190_P0_2"
			(at 0 0 180)
			(layer "F.SilkS")
			(hide yes)
			(effects
				(font
					(size 1.27 1.27)
				)
			)
		)
		(property "Value" ""
			(at 0 0 180)
			(layer "F.Fab")
			(effects
				(font
					(size 1.27 1.27)
				)
			)
		)
		(duplicate_pad_numbers_are_jumpers no)
		(fp_line
			(start 0.7874 0.4064)
			(end -0.7874 0.4064)
			(stroke
				(width 0.1524)
				(type default)
			)
			(layer "F.SilkS")
		)
		(fp_line
			(start 0.7874 -0.4064)
			(end 0.7874 0.4064)
			(stroke
				(width 0.1524)
				(type default)
			)
			(layer "F.SilkS")
		)
		(fp_line
			(start -0.7874 0.4064)
			(end -0.7874 -0.4064)
			(stroke
				(width 0.1524)
				(type default)
			)
			(layer "F.SilkS")
		)
		(fp_line
			(start -0.7874 -0.4064)
			(end 0.7874 -0.4064)
			(stroke
				(width 0.1524)
				(type default)
			)
			(layer "F.SilkS")
		)
		(fp_line
			(start 0.67945 0.3048)
			(end 0.120396 0.3048)
			(stroke
				(width 0.1)
				(type default)
			)
			(layer "F.Fab")
		)
		(fp_line
			(start 0.67945 -0.3048)
			(end 0.67945 0.3048)
			(stroke
				(width 0.1)
				(type default)
			)
			(layer "F.Fab")
		)
		(fp_line
			(start 0.12065 -0.2794)
			(end 0.12065 -0.3048)
			(stroke
				(width 0.1)
				(type default)
			)
			(layer "F.Fab")
		)
		(fp_line
			(start 0.12065 -0.3048)
			(end 0.67945 -0.3048)
			(stroke
				(width 0.1)
				(type default)
			)
			(layer "F.Fab")
		)
		(fp_line
			(start 0.120396 0.3048)
			(end 0.120396 0.2794)
			(stroke
				(width 0.1)
				(type default)
			)
			(layer "F.Fab")
		)
		(fp_line
			(start 0.120396 0.2794)
			(end -0.12065 0.2794)
			(stroke
				(width 0.1)
				(type default)
			)
			(layer "F.Fab")
		)
		(fp_line
			(start -0.12065 0.3048)
			(end -0.67945 0.3048)
			(stroke
				(width 0.1)
				(type default)
			)
			(layer "F.Fab")
		)
		(fp_line
			(start -0.12065 0.2794)
			(end -0.12065 0.3048)
			(stroke
				(width 0.1)
				(type default)
			)
			(layer "F.Fab")
		)
		(fp_line
			(start -0.12065 -0.2794)
			(end 0.12065 -0.2794)
			(stroke
				(width 0.1)
				(type default)
			)
			(layer "F.Fab")
		)
		(fp_line
			(start -0.12065 -0.305054)
			(end -0.12065 -0.2794)
			(stroke
				(width 0.1)
				(type default)
			)
			(layer "F.Fab")
		)
		(fp_line
			(start -0.67945 0.3048)
			(end -0.67945 -0.305054)
			(stroke
				(width 0.1)
				(type default)
			)
			(layer "F.Fab")
		)
		(fp_line
			(start -0.67945 -0.305054)
			(end -0.12065 -0.305054)
			(stroke
				(width 0.1)
				(type default)
			)
			(layer "F.Fab")
		)
		(pad "1" smd circle
			(at -0.40005 0 180)
			(size 0 0)
			(layers "F.Cu" "F.Mask" "F.Paste")
			(net "SW_P12V_PVCCINFAON_CPU0_FLT")
		)
		(pad "2" smd circle
			(at 0.40005 0 180)
			(size 0 0)
			(layers "F.Cu" "F.Mask" "F.Paste")
			(net "GND")
		)
	)
	(footprint ""
		(layer "F.Cu")
		(at 221.67088 -42.255948)
		(property "Reference" "C1998"
			(at 0 0 0)
			(layer "F.SilkS")
			(hide yes)
			(effects
				(font
					(size 1.27 1.27)
				)
			)
		)
		(property "Value" ""
			(at 0 0 0)
			(layer "F.Fab")
			(effects
				(font
					(size 1.27 1.27)
				)
			)
		)
		(duplicate_pad_numbers_are_jumpers no)
		(fp_line
			(start -0.7874 -0.4064)
			(end 0.7874 -0.4064)
			(stroke
				(width 0.1524)
				(type default)
			)
			(layer "F.SilkS")
		)
		(fp_line
			(start -0.7874 0.4064)
			(end -0.7874 -0.4064)
			(stroke
				(width 0.1524)
				(type default)
			)
			(layer "F.SilkS")
		)
		(fp_line
			(start 0.7874 -0.4064)
			(end 0.7874 0.4064)
			(stroke
				(width 0.1524)
				(type default)
			)
			(layer "F.SilkS")
		)
		(fp_line
			(start 0.7874 0.4064)
			(end -0.7874 0.4064)
			(stroke
				(width 0.1524)
				(type default)
			)
			(layer "F.SilkS")
		)
		(fp_line
			(start -0.67945 -0.305054)
			(end -0.12065 -0.305054)
			(stroke
				(width 0.1)
				(type default)
			)
			(layer "F.Fab")
		)
		(fp_line
			(start -0.67945 0.3048)
			(end -0.67945 -0.305054)
			(stroke
				(width 0.1)
				(type default)
			)
			(layer "F.Fab")
		)
		(fp_line
			(start -0.12065 -0.305054)
			(end -0.12065 -0.2794)
			(stroke
				(width 0.1)
				(type default)
			)
			(layer "F.Fab")
		)
		(fp_line
			(start -0.12065 -0.2794)
			(end 0.12065 -0.2794)
			(stroke
				(width 0.1)
				(type default)
			)
			(layer "F.Fab")
		)
		(fp_line
			(start -0.12065 0.2794)
			(end -0.12065 0.3048)
			(stroke
				(width 0.1)
				(type default)
			)
			(layer "F.Fab")
		)
		(fp_line
			(start -0.12065 0.3048)
			(end -0.67945 0.3048)
			(stroke
				(width 0.1)
				(type default)
			)
			(layer "F.Fab")
		)
		(fp_line
			(start 0.120396 0.2794)
			(end -0.12065 0.2794)
			(stroke
				(width 0.1)
				(type default)
			)
			(layer "F.Fab")
		)
		(fp_line
			(start 0.120396 0.3048)
			(end 0.120396 0.2794)
			(stroke
				(width 0.1)
				(type default)
			)
			(layer "F.Fab")
		)
		(fp_line
			(start 0.12065 -0.3048)
			(end 0.67945 -0.3048)
			(stroke
				(width 0.1)
				(type default)
			)
			(layer "F.Fab")
		)
		(fp_line
			(start 0.12065 -0.2794)
			(end 0.12065 -0.3048)
			(stroke
				(width 0.1)
				(type default)
			)
			(layer "F.Fab")
		)
		(fp_line
			(start 0.67945 -0.3048)
			(end 0.67945 0.3048)
			(stroke
				(width 0.1)
				(type default)
			)
			(layer "F.Fab")
		)
		(fp_line
			(start 0.67945 0.3048)
			(end 0.120396 0.3048)
			(stroke
				(width 0.1)
				(type default)
			)
			(layer "F.Fab")
		)
		(pad "1" smd circle
			(at -0.40005 0)
			(size 0 0)
			(layers "F.Cu" "F.Mask" "F.Paste")
			(net "P3V3_E1S_0")
		)
		(pad "2" smd circle
			(at 0.40005 0)
			(size 0 0)
			(layers "F.Cu" "F.Mask" "F.Paste")
			(net "GND")
		)
	)
	(footprint ""
		(layer "F.Cu")
		(at 9.29513 -98.184208 -90)
		(property "Reference" "C2030"
			(at 0 0 270)
			(layer "F.SilkS")
			(hide yes)
			(effects
				(font
					(size 1.27 1.27)
				)
			)
		)
		(property "Value" ""
			(at 0 0 270)
			(layer "F.Fab")
			(effects
				(font
					(size 1.27 1.27)
				)
			)
		)
		(duplicate_pad_numbers_are_jumpers no)
		(fp_line
			(start -0.7874 0.4064)
			(end -0.7874 -0.4064)
			(stroke
				(width 0.1524)
				(type default)
			)
			(layer "F.SilkS")
		)
		(fp_line
			(start 0.7874 0.4064)
			(end -0.7874 0.4064)
			(stroke
				(width 0.1524)
				(type default)
			)
			(layer "F.SilkS")
		)
		(fp_line
			(start -0.7874 -0.4064)
			(end 0.7874 -0.4064)
			(stroke
				(width 0.1524)
				(type default)
			)
			(layer "F.SilkS")
		)
		(fp_line
			(start 0.7874 -0.4064)
			(end 0.7874 0.4064)
			(stroke
				(width 0.1524)
				(type default)
			)
			(layer "F.SilkS")
		)
		(fp_line
			(start -0.67945 0.3048)
			(end -0.67945 -0.305054)
			(stroke
				(width 0.1)
				(type default)
			)
			(layer "F.Fab")
		)
		(fp_line
			(start -0.12065 0.3048)
			(end -0.67945 0.3048)
			(stroke
				(width 0.1)
				(type default)
			)
			(layer "F.Fab")
		)
		(fp_line
			(start 0.120396 0.3048)
			(end 0.120396 0.2794)
			(stroke
				(width 0.1)
				(type default)
			)
			(layer "F.Fab")
		)
		(fp_line
			(start 0.67945 0.3048)
			(end 0.120396 0.3048)
			(stroke
				(width 0.1)
				(type default)
			)
			(layer "F.Fab")
		)
		(fp_line
			(start -0.12065 0.2794)
			(end -0.12065 0.3048)
			(stroke
				(width 0.1)
				(type default)
			)
			(layer "F.Fab")
		)
		(fp_line
			(start 0.120396 0.2794)
			(end -0.12065 0.2794)
			(stroke
				(width 0.1)
				(type default)
			)
			(layer "F.Fab")
		)
		(fp_line
			(start -0.12065 -0.2794)
			(end 0.12065 -0.2794)
			(stroke
				(width 0.1)
				(type default)
			)
			(layer "F.Fab")
		)
		(fp_line
			(start 0.12065 -0.2794)
			(end 0.12065 -0.3048)
			(stroke
				(width 0.1)
				(type default)
			)
			(layer "F.Fab")
		)
		(fp_line
			(start 0.12065 -0.3048)
			(end 0.67945 -0.3048)
			(stroke
				(width 0.1)
				(type default)
			)
			(layer "F.Fab")
		)
		(fp_line
			(start 0.67945 -0.3048)
			(end 0.67945 0.3048)
			(stroke
				(width 0.1)
				(type default)
			)
			(layer "F.Fab")
		)
		(fp_line
			(start -0.67945 -0.305054)
			(end -0.12065 -0.305054)
			(stroke
				(width 0.1)
				(type default)
			)
			(layer "F.Fab")
		)
		(fp_line
			(start -0.12065 -0.305054)
			(end -0.12065 -0.2794)
			(stroke
				(width 0.1)
				(type default)
			)
			(layer "F.Fab")
		)
		(pad "1" smd circle
			(at -0.40005 0 270)
			(size 0 0)
			(layers "F.Cu" "F.Mask" "F.Paste")
			(net "USB_HUB_XTAL_OUT")
		)
		(pad "2" smd circle
			(at 0.40005 0 270)
			(size 0 0)
			(layers "F.Cu" "F.Mask" "F.Paste")
			(net "GND")
		)
	)
	(footprint ""
		(layer "F.Cu")
		(at 477.30537 -211.009992 90)
		(property "Reference" "X35"
			(at -0.1778 -1.92913 90)
			(unlocked yes)
			(layer "F.SilkS")
			(effects
				(font
					(size 0.7874 0.5842)
					(thickness 0.1524)
				)
				(justify left)
			)
		)
		(property "Value" ""
			(at 0 0 90)
			(layer "F.Fab")
			(effects
				(font
					(size 1.27 1.27)
				)
			)
		)
		(property "Device Type" "TP_TDR_4P_FTS_TH-TP_TDR_4P_DIPA"
			(at 1.30175 1.27 180)
			(unlocked yes)
			(layer "F.Fab")
			(hide yes)
			(effects
				(font
					(size 0.635 0.4064)
					(thickness 0.1524)
				)
			)
		)
		(property "User Part Number" "N_A"
			(at 1.30175 1.27 180)
			(unlocked yes)
			(layer "Cmts.User")
			(hide yes)
			(effects
				(font
					(size 0.635 0.4064)
					(thickness 0.1524)
				)
			)
		)
		(duplicate_pad_numbers_are_jumpers no)
		(fp_line
			(start 2.54 -1.27)
			(end 0 -1.27)
			(stroke
				(width 0.1524)
				(type default)
			)
			(layer "F.SilkS")
		)
		(fp_line
			(start 0 -1.27)
			(end 0 -0.635)
			(stroke
				(width 0.1524)
				(type default)
			)
			(layer "F.SilkS")
		)
		(fp_line
			(start 2.54 -1.1303)
			(end 2.54 -1.27)
			(stroke
				(width 0.1524)
				(type default)
			)
			(layer "F.SilkS")
		)
		(fp_line
			(start 0 0.635)
			(end 0 1.905)
			(stroke
				(width 0.1524)
				(type default)
			)
			(layer "F.SilkS")
		)
		(fp_line
			(start 2.54 1.4097)
			(end 2.54 1.1303)
			(stroke
				(width 0.1524)
				(type default)
			)
			(layer "F.SilkS")
		)
		(fp_line
			(start 0 3.175)
			(end 0 3.81)
			(stroke
				(width 0.1524)
				(type default)
			)
			(layer "F.SilkS")
		)
		(fp_line
			(start 2.54 3.81)
			(end 2.54 3.6703)
			(stroke
				(width 0.1524)
				(type default)
			)
			(layer "F.SilkS")
		)
		(fp_line
			(start 0 3.81)
			(end 2.54 3.81)
			(stroke
				(width 0.1524)
				(type default)
			)
			(layer "F.SilkS")
		)
		(fp_poly
			(pts
				(xy -0.761746 0) (xy -2.285746 -0.762) (xy -2.285746 0.762)
			)
			(stroke
				(width 0)
				(type default)
			)
			(fill yes)
			(layer "F.SilkS")
		)
		(fp_line
			(start 2.54 -1.27)
			(end 0 -1.27)
			(stroke
				(width 0.1)
				(type default)
			)
			(layer "F.Fab")
		)
		(fp_line
			(start 0 -1.27)
			(end 0 3.81)
			(stroke
				(width 0.1)
				(type default)
			)
			(layer "F.Fab")
		)
		(fp_line
			(start 2.54 3.81)
			(end 2.54 -1.27)
			(stroke
				(width 0.1)
				(type default)
			)
			(layer "F.Fab")
		)
		(fp_line
			(start 0 3.81)
			(end 2.54 3.81)
			(stroke
				(width 0.1)
				(type default)
			)
			(layer "F.Fab")
		)
		(fp_poly
			(pts
				(xy -0.761746 0) (xy -2.285746 -0.762) (xy -2.285746 0.762)
			)
			(stroke
				(width 0)
				(type default)
			)
			(fill yes)
			(layer "F.Fab")
		)
		(pad "1" thru_hole circle
			(at 0 0 90)
			(size 1.0033 1.0033)
			(drill 0.249936)
			(layers "*.Cu" "*.Mask")
			(remove_unused_layers no)
			(net "TDR_DIFF_85_NECK_IN2_DP")
			(clearance 0.10795)
			(thermal_gap 0.10795)
			(padstack
				(mode front_inner_back)
				(layer "Inner"
					(shape circle)
					(size 0.8001 0.8001)
					(clearance 0.1524)
				)
				(layer "B.Cu"
					(shape circle)
					(size 1.0033 1.0033)
					(clearance 0.10795)
				)
			)
		)
		(pad "2" thru_hole circle
			(at 2.54 0 90)
			(size 1.9939 1.9939)
			(drill 0.249936)
			(layers "*.Cu" "*.Mask")
			(remove_unused_layers no)
			(net "T1_GND")
			(clearance 0.10795)
			(thermal_gap 0.10795)
			(padstack
				(mode front_inner_back)
				(layer "Inner"
					(shape circle)
					(size 0.8001 0.8001)
					(clearance 0.1524)
				)
				(layer "B.Cu"
					(shape circle)
					(size 1.9939 1.9939)
					(clearance 0.10795)
				)
			)
		)
		(pad "3" thru_hole circle
			(at 2.54 2.54 90)
			(size 1.9939 1.9939)
			(drill 0.249936)
			(layers "*.Cu" "*.Mask")
			(remove_unused_layers no)
			(net "T1_GND")
			(clearance 0.10795)
			(thermal_gap 0.10795)
			(padstack
				(mode front_inner_back)
				(layer "Inner"
					(shape circle)
					(size 0.8001 0.8001)
					(clearance 0.1524)
				)
				(layer "B.Cu"
					(shape circle)
					(size 1.9939 1.9939)
					(clearance 0.10795)
				)
			)
		)
		(pad "4" thru_hole circle
			(at 0 2.54 90)
			(size 1.0033 1.0033)
			(drill 0.249936)
			(layers "*.Cu" "*.Mask")
			(remove_unused_layers no)
			(net "TDR_DIFF_85_NECK_IN2_DN")
			(clearance 0.10795)
			(thermal_gap 0.10795)
			(padstack
				(mode front_inner_back)
				(layer "Inner"
					(shape circle)
					(size 0.8001 0.8001)
					(clearance 0.1524)
				)
				(layer "B.Cu"
					(shape circle)
					(size 1.0033 1.0033)
					(clearance 0.10795)
				)
			)
		)
	)
	(footprint ""
		(layer "F.Cu")
		(at 427.490128 -346.017342)
		(property "Reference" "PC1186"
			(at 0 0 0)
			(layer "F.SilkS")
			(hide yes)
			(effects
				(font
					(size 1.27 1.27)
				)
			)
		)
		(property "Value" ""
			(at 0 0 0)
			(layer "F.Fab")
			(effects
				(font
					(size 1.27 1.27)
				)
			)
		)
		(duplicate_pad_numbers_are_jumpers no)
		(fp_line
			(start 2.750058 0.999998)
			(end -2.750058 0.999998)
			(stroke
				(width 0.1524)
				(type default)
			)
			(layer "F.SilkS")
		)
		(fp_circle
			(center 0 0.999998)
			(end 2.750058 0.999998)
			(stroke
				(width 0.1524)
				(type default)
			)
			(fill no)
			(layer "F.SilkS")
		)
		(fp_poly
			(pts
				(arc
					(start 2.750058 0.999998)
					(mid 0 3.750056)
					(end -2.750058 0.999998)
				)
			)
			(stroke
				(width 0)
				(type default)
			)
			(fill yes)
			(layer "F.SilkS")
		)
		(fp_circle
			(center 0 0.999998)
			(end 2.750058 0.999998)
			(stroke
				(width 0.1)
				(type default)
			)
			(fill no)
			(layer "F.Fab")
		)
		(pad "1" thru_hole rect
			(at 0 0)
			(size 1.5748 1.5748)
			(drill 1.0668)
			(layers "*.Cu" "*.Mask")
			(remove_unused_layers no)
			(net "PVCCFA_EHV_FIVRA_CPU0")
			(clearance 0)
			(padstack
				(mode front_inner_back)
				(layer "Inner"
					(shape circle)
					(size 1.5748 1.5748)
					(clearance 0)
				)
				(layer "B.Cu"
					(shape rect)
					(size 1.5748 1.5748)
					(clearance 0)
				)
			)
		)
		(pad "2" thru_hole circle
			(at 0 1.999996)
			(size 1.5748 1.5748)
			(drill 1.0668)
			(layers "*.Cu" "*.Mask")
			(remove_unused_layers no)
			(net "GND")
			(clearance 0)
		)
	)
	(footprint ""
		(layer "F.Cu")
		(at 45.805344 -148.837396 90)
		(property "Reference" "PL23"
			(at 0.094742 -5.884164 0)
			(unlocked yes)
			(layer "F.SilkS")
			(effects
				(font
					(size 0.7874 0.5842)
					(thickness 0.1524)
				)
				(justify left)
			)
		)
		(property "Value" ""
			(at 0 0 90)
			(layer "F.Fab")
			(effects
				(font
					(size 1.27 1.27)
				)
			)
		)
		(duplicate_pad_numbers_are_jumpers no)
		(fp_line
			(start 2.249932 -2.249932)
			(end 2.249932 -1.3843)
			(stroke
				(width 0.1524)
				(type default)
			)
			(layer "F.SilkS")
		)
		(fp_line
			(start -2.249932 -2.249932)
			(end 2.249932 -2.249932)
			(stroke
				(width 0.1524)
				(type default)
			)
			(layer "F.SilkS")
		)
		(fp_line
			(start -2.249932 -1.3843)
			(end -2.249932 -2.249932)
			(stroke
				(width 0.1524)
				(type default)
			)
			(layer "F.SilkS")
		)
		(fp_line
			(start 2.249932 1.3843)
			(end 2.249932 2.249932)
			(stroke
				(width 0.1524)
				(type default)
			)
			(layer "F.SilkS")
		)
		(fp_line
			(start 2.249932 2.249932)
			(end -2.249932 2.249932)
			(stroke
				(width 0.1524)
				(type default)
			)
			(layer "F.SilkS")
		)
		(fp_line
			(start -2.249932 2.249932)
			(end -2.249932 1.3843)
			(stroke
				(width 0.1524)
				(type default)
			)
			(layer "F.SilkS")
		)
		(fp_line
			(start 2.249932 -2.249932)
			(end 2.249932 2.249932)
			(stroke
				(width 0.1)
				(type default)
			)
			(layer "F.Fab")
		)
		(fp_line
			(start -2.249932 -2.249932)
			(end 2.249932 -2.249932)
			(stroke
				(width 0.1)
				(type default)
			)
			(layer "F.Fab")
		)
		(fp_line
			(start 2.249932 2.249932)
			(end -2.249932 2.249932)
			(stroke
				(width 0.1)
				(type default)
			)
			(layer "F.Fab")
		)
		(fp_line
			(start -2.249932 2.249932)
			(end -2.249932 -2.249932)
			(stroke
				(width 0.1)
				(type default)
			)
			(layer "F.Fab")
		)
		(pad "1" smd rect
			(at -1.82499 0 90)
			(size 1.0668 2.5146)
			(layers "F.Cu" "F.Mask" "F.Paste")
			(net "P12V_AUX")
		)
		(pad "2" smd rect
			(at 1.82499 0 90)
			(size 1.0668 2.5146)
			(layers "F.Cu" "F.Mask" "F.Paste")
			(net "SW_P12V_PVCCINFAON_CPU1_FLT")
		)
	)
	(footprint ""
		(layer "F.Cu")
		(at 24.684482 -397.687292 90)
		(property "Reference" "R4666"
			(at 0 0 90)
			(layer "F.SilkS")
			(hide yes)
			(effects
				(font
					(size 1.27 1.27)
				)
			)
		)
		(property "Value" ""
			(at 0 0 90)
			(layer "F.Fab")
			(effects
				(font
					(size 1.27 1.27)
				)
			)
		)
		(duplicate_pad_numbers_are_jumpers no)
		(fp_line
			(start -0.7874 -0.4064)
			(end 0.7874 -0.4064)
			(stroke
				(width 0.1524)
				(type default)
			)
			(layer "F.SilkS")
		)
		(fp_line
			(start 0.7874 0.4064)
			(end -0.002032 0.4064)
			(stroke
				(width 0.1524)
				(type default)
			)
			(layer "F.SilkS")
		)
		(fp_line
			(start -0.7874 0.4064)
			(end -0.7874 -0.4064)
			(stroke
				(width 0.1524)
				(type default)
			)
			(layer "F.SilkS")
		)
		(fp_line
			(start -0.12065 -0.305054)
			(end -0.12065 -0.2794)
			(stroke
				(width 0.1)
				(type default)
			)
			(layer "F.Fab")
		)
		(fp_line
			(start -0.67945 -0.305054)
			(end -0.12065 -0.305054)
			(stroke
				(width 0.1)
				(type default)
			)
			(layer "F.Fab")
		)
		(fp_line
			(start 0.67945 -0.3048)
			(end 0.67945 0.3048)
			(stroke
				(width 0.1)
				(type default)
			)
			(layer "F.Fab")
		)
		(fp_line
			(start 0.12065 -0.3048)
			(end 0.67945 -0.3048)
			(stroke
				(width 0.1)
				(type default)
			)
			(layer "F.Fab")
		)
		(fp_line
			(start 0.12065 -0.2794)
			(end 0.12065 -0.3048)
			(stroke
				(width 0.1)
				(type default)
			)
			(layer "F.Fab")
		)
		(fp_line
			(start -0.12065 -0.2794)
			(end 0.12065 -0.2794)
			(stroke
				(width 0.1)
				(type default)
			)
			(layer "F.Fab")
		)
		(fp_line
			(start 0.120396 0.2794)
			(end -0.12065 0.2794)
			(stroke
				(width 0.1)
				(type default)
			)
			(layer "F.Fab")
		)
		(fp_line
			(start -0.12065 0.2794)
			(end -0.12065 0.3048)
			(stroke
				(width 0.1)
				(type default)
			)
			(layer "F.Fab")
		)
		(fp_line
			(start 0.67945 0.3048)
			(end 0.120396 0.3048)
			(stroke
				(width 0.1)
				(type default)
			)
			(layer "F.Fab")
		)
		(fp_line
			(start 0.120396 0.3048)
			(end 0.120396 0.2794)
			(stroke
				(width 0.1)
				(type default)
			)
			(layer "F.Fab")
		)
		(fp_line
			(start -0.12065 0.3048)
			(end -0.67945 0.3048)
			(stroke
				(width 0.1)
				(type default)
			)
			(layer "F.Fab")
		)
		(fp_line
			(start -0.67945 0.3048)
			(end -0.67945 -0.305054)
			(stroke
				(width 0.1)
				(type default)
			)
			(layer "F.Fab")
		)
		(pad "1" smd rect
			(at -0.40005 0 270)
			(size 0.4572 0.508)
			(layers "F.Cu" "F.Mask" "F.Paste")
			(net "P2E_MB_BMC_RX_DN<0>")
		)
		(pad "2" smd rect
			(at 0.40005 0 270)
			(size 0.4572 0.508)
			(layers "F.Cu" "F.Mask" "F.Paste")
			(net "P2E_MB_BMC_RX_R2_DN<0>")
		)
	)
	(footprint ""
		(layer "F.Cu")
		(at 400.558 -158.562548)
		(property "Reference" "PC1644"
			(at 0 0 0)
			(layer "F.SilkS")
			(hide yes)
			(effects
				(font
					(size 1.27 1.27)
				)
			)
		)
		(property "Value" ""
			(at 0 0 0)
			(layer "F.Fab")
			(effects
				(font
					(size 1.27 1.27)
				)
			)
		)
		(duplicate_pad_numbers_are_jumpers no)
		(fp_line
			(start 2.750058 0.999998)
			(end -2.750058 0.999998)
			(stroke
				(width 0.1524)
				(type default)
			)
			(layer "F.SilkS")
		)
		(fp_circle
			(center 0 0.999998)
			(end 2.750058 0.999998)
			(stroke
				(width 0.1524)
				(type default)
			)
			(fill no)
			(layer "F.SilkS")
		)
		(fp_poly
			(pts
				(arc
					(start 2.750058 0.999998)
					(mid 0 3.750056)
					(end -2.750058 0.999998)
				)
			)
			(stroke
				(width 0)
				(type default)
			)
			(fill yes)
			(layer "F.SilkS")
		)
		(fp_circle
			(center 0 0.999998)
			(end 2.750058 0.999998)
			(stroke
				(width 0.1)
				(type default)
			)
			(fill no)
			(layer "F.Fab")
		)
		(pad "1" thru_hole rect
			(at 0 0)
			(size 1.5748 1.5748)
			(drill 1.0668)
			(layers "*.Cu" "*.Mask")
			(remove_unused_layers no)
			(net "PVCCD_HV_CPU0")
			(clearance 0)
			(padstack
				(mode front_inner_back)
				(layer "Inner"
					(shape circle)
					(size 1.5748 1.5748)
					(clearance 0)
				)
				(layer "B.Cu"
					(shape rect)
					(size 1.5748 1.5748)
					(clearance 0)
				)
			)
		)
		(pad "2" thru_hole circle
			(at 0 1.999996)
			(size 1.5748 1.5748)
			(drill 1.0668)
			(layers "*.Cu" "*.Mask")
			(remove_unused_layers no)
			(net "GND")
			(clearance 0)
		)
	)
	(footprint ""
		(layer "F.Cu")
		(at 109.337856 -31.49981)
		(property "Reference" "R3242"
			(at 0 0 0)
			(layer "F.SilkS")
			(hide yes)
			(effects
				(font
					(size 1.27 1.27)
				)
			)
		)
		(property "Value" ""
			(at 0 0 0)
			(layer "F.Fab")
			(effects
				(font
					(size 1.27 1.27)
				)
			)
		)
		(duplicate_pad_numbers_are_jumpers no)
		(fp_line
			(start -0.7874 -0.4064)
			(end 0.7874 -0.4064)
			(stroke
				(width 0.1524)
				(type default)
			)
			(layer "F.SilkS")
		)
		(fp_line
			(start -0.7874 0.4064)
			(end -0.7874 -0.4064)
			(stroke
				(width 0.1524)
				(type default)
			)
			(layer "F.SilkS")
		)
		(fp_line
			(start 0.7874 -0.4064)
			(end 0.7874 0.4064)
			(stroke
				(width 0.1524)
				(type default)
			)
			(layer "F.SilkS")
		)
		(fp_line
			(start 0.7874 0.4064)
			(end -0.7874 0.4064)
			(stroke
				(width 0.1524)
				(type default)
			)
			(layer "F.SilkS")
		)
		(fp_line
			(start -0.67945 -0.305054)
			(end -0.12065 -0.305054)
			(stroke
				(width 0.1)
				(type default)
			)
			(layer "F.Fab")
		)
		(fp_line
			(start -0.67945 0.3048)
			(end -0.67945 -0.305054)
			(stroke
				(width 0.1)
				(type default)
			)
			(layer "F.Fab")
		)
		(fp_line
			(start -0.12065 -0.305054)
			(end -0.12065 -0.2794)
			(stroke
				(width 0.1)
				(type default)
			)
			(layer "F.Fab")
		)
		(fp_line
			(start -0.12065 -0.2794)
			(end 0.12065 -0.2794)
			(stroke
				(width 0.1)
				(type default)
			)
			(layer "F.Fab")
		)
		(fp_line
			(start -0.12065 0.2794)
			(end -0.12065 0.3048)
			(stroke
				(width 0.1)
				(type default)
			)
			(layer "F.Fab")
		)
		(fp_line
			(start -0.12065 0.3048)
			(end -0.67945 0.3048)
			(stroke
				(width 0.1)
				(type default)
			)
			(layer "F.Fab")
		)
		(fp_line
			(start 0.120396 0.2794)
			(end -0.12065 0.2794)
			(stroke
				(width 0.1)
				(type default)
			)
			(layer "F.Fab")
		)
		(fp_line
			(start 0.120396 0.3048)
			(end 0.120396 0.2794)
			(stroke
				(width 0.1)
				(type default)
			)
			(layer "F.Fab")
		)
		(fp_line
			(start 0.12065 -0.3048)
			(end 0.67945 -0.3048)
			(stroke
				(width 0.1)
				(type default)
			)
			(layer "F.Fab")
		)
		(fp_line
			(start 0.12065 -0.2794)
			(end 0.12065 -0.3048)
			(stroke
				(width 0.1)
				(type default)
			)
			(layer "F.Fab")
		)
		(fp_line
			(start 0.67945 -0.3048)
			(end 0.67945 0.3048)
			(stroke
				(width 0.1)
				(type default)
			)
			(layer "F.Fab")
		)
		(fp_line
			(start 0.67945 0.3048)
			(end 0.120396 0.3048)
			(stroke
				(width 0.1)
				(type default)
			)
			(layer "F.Fab")
		)
		(pad "1" smd circle
			(at -0.40005 0)
			(size 0 0)
			(layers "F.Cu" "F.Mask" "F.Paste")
			(net "SMB_OCP_V3_2_3V3AUX_SCL")
		)
		(pad "2" smd circle
			(at 0.40005 0)
			(size 0 0)
			(layers "F.Cu" "F.Mask" "F.Paste")
			(net "P3V3_AUX")
		)
	)
	(footprint ""
		(layer "F.Cu")
		(at 204.93736 -118.074948 180)
		(property "Reference" "R4171"
			(at 0 0 180)
			(layer "F.SilkS")
			(hide yes)
			(effects
				(font
					(size 1.27 1.27)
				)
			)
		)
		(property "Value" ""
			(at 0 0 180)
			(layer "F.Fab")
			(effects
				(font
					(size 1.27 1.27)
				)
			)
		)
		(duplicate_pad_numbers_are_jumpers no)
		(fp_line
			(start 0.7874 0.4064)
			(end -0.7874 0.4064)
			(stroke
				(width 0.1524)
				(type default)
			)
			(layer "F.SilkS")
		)
		(fp_line
			(start 0.7874 -0.4064)
			(end 0.7874 0.4064)
			(stroke
				(width 0.1524)
				(type default)
			)
			(layer "F.SilkS")
		)
		(fp_line
			(start -0.7874 0.4064)
			(end -0.7874 -0.4064)
			(stroke
				(width 0.1524)
				(type default)
			)
			(layer "F.SilkS")
		)
		(fp_line
			(start -0.7874 -0.4064)
			(end 0.7874 -0.4064)
			(stroke
				(width 0.1524)
				(type default)
			)
			(layer "F.SilkS")
		)
		(fp_line
			(start 0.67945 0.3048)
			(end 0.120396 0.3048)
			(stroke
				(width 0.1)
				(type default)
			)
			(layer "F.Fab")
		)
		(fp_line
			(start 0.67945 -0.3048)
			(end 0.67945 0.3048)
			(stroke
				(width 0.1)
				(type default)
			)
			(layer "F.Fab")
		)
		(fp_line
			(start 0.12065 -0.2794)
			(end 0.12065 -0.3048)
			(stroke
				(width 0.1)
				(type default)
			)
			(layer "F.Fab")
		)
		(fp_line
			(start 0.12065 -0.3048)
			(end 0.67945 -0.3048)
			(stroke
				(width 0.1)
				(type default)
			)
			(layer "F.Fab")
		)
		(fp_line
			(start 0.120396 0.3048)
			(end 0.120396 0.2794)
			(stroke
				(width 0.1)
				(type default)
			)
			(layer "F.Fab")
		)
		(fp_line
			(start 0.120396 0.2794)
			(end -0.12065 0.2794)
			(stroke
				(width 0.1)
				(type default)
			)
			(layer "F.Fab")
		)
		(fp_line
			(start -0.12065 0.3048)
			(end -0.67945 0.3048)
			(stroke
				(width 0.1)
				(type default)
			)
			(layer "F.Fab")
		)
		(fp_line
			(start -0.12065 0.2794)
			(end -0.12065 0.3048)
			(stroke
				(width 0.1)
				(type default)
			)
			(layer "F.Fab")
		)
		(fp_line
			(start -0.12065 -0.2794)
			(end 0.12065 -0.2794)
			(stroke
				(width 0.1)
				(type default)
			)
			(layer "F.Fab")
		)
		(fp_line
			(start -0.12065 -0.305054)
			(end -0.12065 -0.2794)
			(stroke
				(width 0.1)
				(type default)
			)
			(layer "F.Fab")
		)
		(fp_line
			(start -0.67945 0.3048)
			(end -0.67945 -0.305054)
			(stroke
				(width 0.1)
				(type default)
			)
			(layer "F.Fab")
		)
		(fp_line
			(start -0.67945 -0.305054)
			(end -0.12065 -0.305054)
			(stroke
				(width 0.1)
				(type default)
			)
			(layer "F.Fab")
		)
		(pad "1" smd circle
			(at -0.40005 0 180)
			(size 0 0)
			(layers "F.Cu" "F.Mask" "F.Paste")
			(net "GPU_3V3IO_RSVD3_ISO")
		)
		(pad "2" smd circle
			(at 0.40005 0 180)
			(size 0 0)
			(layers "F.Cu" "F.Mask" "F.Paste")
			(net "GPU_3V3IO_RSVD3_ISO_R")
		)
	)
	(footprint ""
		(layer "F.Cu")
		(at 29.478478 -17.623536 90)
		(property "Reference" "C816"
			(at 0 0 90)
			(layer "F.SilkS")
			(hide yes)
			(effects
				(font
					(size 1.27 1.27)
				)
			)
		)
		(property "Value" ""
			(at 0 0 90)
			(layer "F.Fab")
			(effects
				(font
					(size 1.27 1.27)
				)
			)
		)
		(duplicate_pad_numbers_are_jumpers no)
		(fp_line
			(start 0.299974 -0.150114)
			(end 0.299974 0.150114)
			(stroke
				(width 0.1)
				(type default)
			)
			(layer "F.Fab")
		)
		(fp_line
			(start -0.299974 -0.150114)
			(end 0.299974 -0.150114)
			(stroke
				(width 0.1)
				(type default)
			)
			(layer "F.Fab")
		)
		(fp_line
			(start 0.299974 0.150114)
			(end -0.299974 0.150114)
			(stroke
				(width 0.1)
				(type default)
			)
			(layer "F.Fab")
		)
		(fp_line
			(start -0.299974 0.150114)
			(end -0.299974 -0.150114)
			(stroke
				(width 0.1)
				(type default)
			)
			(layer "F.Fab")
		)
		(pad "1" smd rect
			(at -0.2667 0 90)
			(size 0.3048 0.381)
			(layers "F.Cu" "F.Mask" "F.Paste")
			(net "P5E_CPU1_PE1_TX_C_DN<10>")
		)
		(pad "2" smd rect
			(at 0.2667 0 90)
			(size 0.3048 0.381)
			(layers "F.Cu" "F.Mask" "F.Paste")
			(net "P5E_CPU1_PE1_TX_DN<10>")
		)
	)
	(footprint ""
		(layer "F.Cu")
		(at 105.912158 -353.137724)
		(property "Reference" "PC549"
			(at 0 0 0)
			(layer "F.SilkS")
			(hide yes)
			(effects
				(font
					(size 1.27 1.27)
				)
			)
		)
		(property "Value" ""
			(at 0 0 0)
			(layer "F.Fab")
			(effects
				(font
					(size 1.27 1.27)
				)
			)
		)
		(duplicate_pad_numbers_are_jumpers no)
		(fp_line
			(start -0.7874 -0.4064)
			(end 0.7874 -0.4064)
			(stroke
				(width 0.1524)
				(type default)
			)
			(layer "F.SilkS")
		)
		(fp_line
			(start -0.7874 0.4064)
			(end -0.7874 -0.4064)
			(stroke
				(width 0.1524)
				(type default)
			)
			(layer "F.SilkS")
		)
		(fp_line
			(start 0.7874 -0.4064)
			(end 0.7874 0.4064)
			(stroke
				(width 0.1524)
				(type default)
			)
			(layer "F.SilkS")
		)
		(fp_line
			(start 0.7874 0.4064)
			(end -0.7874 0.4064)
			(stroke
				(width 0.1524)
				(type default)
			)
			(layer "F.SilkS")
		)
		(fp_line
			(start -0.67945 -0.305054)
			(end -0.12065 -0.305054)
			(stroke
				(width 0.1)
				(type default)
			)
			(layer "F.Fab")
		)
		(fp_line
			(start -0.67945 0.3048)
			(end -0.67945 -0.305054)
			(stroke
				(width 0.1)
				(type default)
			)
			(layer "F.Fab")
		)
		(fp_line
			(start -0.12065 -0.305054)
			(end -0.12065 -0.2794)
			(stroke
				(width 0.1)
				(type default)
			)
			(layer "F.Fab")
		)
		(fp_line
			(start -0.12065 -0.2794)
			(end 0.12065 -0.2794)
			(stroke
				(width 0.1)
				(type default)
			)
			(layer "F.Fab")
		)
		(fp_line
			(start -0.12065 0.2794)
			(end -0.12065 0.3048)
			(stroke
				(width 0.1)
				(type default)
			)
			(layer "F.Fab")
		)
		(fp_line
			(start -0.12065 0.3048)
			(end -0.67945 0.3048)
			(stroke
				(width 0.1)
				(type default)
			)
			(layer "F.Fab")
		)
		(fp_line
			(start 0.120396 0.2794)
			(end -0.12065 0.2794)
			(stroke
				(width 0.1)
				(type default)
			)
			(layer "F.Fab")
		)
		(fp_line
			(start 0.120396 0.3048)
			(end 0.120396 0.2794)
			(stroke
				(width 0.1)
				(type default)
			)
			(layer "F.Fab")
		)
		(fp_line
			(start 0.12065 -0.3048)
			(end 0.67945 -0.3048)
			(stroke
				(width 0.1)
				(type default)
			)
			(layer "F.Fab")
		)
		(fp_line
			(start 0.12065 -0.2794)
			(end 0.12065 -0.3048)
			(stroke
				(width 0.1)
				(type default)
			)
			(layer "F.Fab")
		)
		(fp_line
			(start 0.67945 -0.3048)
			(end 0.67945 0.3048)
			(stroke
				(width 0.1)
				(type default)
			)
			(layer "F.Fab")
		)
		(fp_line
			(start 0.67945 0.3048)
			(end 0.120396 0.3048)
			(stroke
				(width 0.1)
				(type default)
			)
			(layer "F.Fab")
		)
		(pad "1" smd circle
			(at -0.40005 0)
			(size 0 0)
			(layers "F.Cu" "F.Mask" "F.Paste")
			(net "SH_PVCCIN_CPU1_R")
		)
		(pad "2" smd circle
			(at 0.40005 0)
			(size 0 0)
			(layers "F.Cu" "F.Mask" "F.Paste")
			(net "VSENSE_PVCCIN_CPU1_DN")
		)
	)
	(footprint ""
		(layer "F.Cu")
		(at 216.065608 -399.743422 180)
		(property "Reference" "PC2350"
			(at 0 0 180)
			(layer "F.SilkS")
			(hide yes)
			(effects
				(font
					(size 1.27 1.27)
				)
			)
		)
		(property "Value" ""
			(at 0 0 180)
			(layer "F.Fab")
			(effects
				(font
					(size 1.27 1.27)
				)
			)
		)
		(duplicate_pad_numbers_are_jumpers no)
		(fp_line
			(start 0.7874 0.4064)
			(end -0.7874 0.4064)
			(stroke
				(width 0.1524)
				(type default)
			)
			(layer "F.SilkS")
		)
		(fp_line
			(start 0.7874 -0.4064)
			(end 0.7874 0.4064)
			(stroke
				(width 0.1524)
				(type default)
			)
			(layer "F.SilkS")
		)
		(fp_line
			(start -0.7874 0.4064)
			(end -0.7874 -0.4064)
			(stroke
				(width 0.1524)
				(type default)
			)
			(layer "F.SilkS")
		)
		(fp_line
			(start -0.7874 -0.4064)
			(end 0.7874 -0.4064)
			(stroke
				(width 0.1524)
				(type default)
			)
			(layer "F.SilkS")
		)
		(fp_line
			(start 0.67945 0.3048)
			(end 0.120396 0.3048)
			(stroke
				(width 0.1)
				(type default)
			)
			(layer "F.Fab")
		)
		(fp_line
			(start 0.67945 -0.3048)
			(end 0.67945 0.3048)
			(stroke
				(width 0.1)
				(type default)
			)
			(layer "F.Fab")
		)
		(fp_line
			(start 0.12065 -0.2794)
			(end 0.12065 -0.3048)
			(stroke
				(width 0.1)
				(type default)
			)
			(layer "F.Fab")
		)
		(fp_line
			(start 0.12065 -0.3048)
			(end 0.67945 -0.3048)
			(stroke
				(width 0.1)
				(type default)
			)
			(layer "F.Fab")
		)
		(fp_line
			(start 0.120396 0.3048)
			(end 0.120396 0.2794)
			(stroke
				(width 0.1)
				(type default)
			)
			(layer "F.Fab")
		)
		(fp_line
			(start 0.120396 0.2794)
			(end -0.12065 0.2794)
			(stroke
				(width 0.1)
				(type default)
			)
			(layer "F.Fab")
		)
		(fp_line
			(start -0.12065 0.3048)
			(end -0.67945 0.3048)
			(stroke
				(width 0.1)
				(type default)
			)
			(layer "F.Fab")
		)
		(fp_line
			(start -0.12065 0.2794)
			(end -0.12065 0.3048)
			(stroke
				(width 0.1)
				(type default)
			)
			(layer "F.Fab")
		)
		(fp_line
			(start -0.12065 -0.2794)
			(end 0.12065 -0.2794)
			(stroke
				(width 0.1)
				(type default)
			)
			(layer "F.Fab")
		)
		(fp_line
			(start -0.12065 -0.305054)
			(end -0.12065 -0.2794)
			(stroke
				(width 0.1)
				(type default)
			)
			(layer "F.Fab")
		)
		(fp_line
			(start -0.67945 0.3048)
			(end -0.67945 -0.305054)
			(stroke
				(width 0.1)
				(type default)
			)
			(layer "F.Fab")
		)
		(fp_line
			(start -0.67945 -0.305054)
			(end -0.12065 -0.305054)
			(stroke
				(width 0.1)
				(type default)
			)
			(layer "F.Fab")
		)
		(pad "1" smd circle
			(at -0.40005 0 180)
			(size 0 0)
			(layers "F.Cu" "F.Mask" "F.Paste")
			(net "HSC_OCREF")
		)
		(pad "2" smd circle
			(at 0.40005 0 180)
			(size 0 0)
			(layers "F.Cu" "F.Mask" "F.Paste")
			(net "AGND_HSC")
		)
	)
	(footprint ""
		(layer "F.Cu")
		(at 413.282384 -16.088614 90)
		(property "Reference" "C854"
			(at 0 0 90)
			(layer "F.SilkS")
			(hide yes)
			(effects
				(font
					(size 1.27 1.27)
				)
			)
		)
		(property "Value" ""
			(at 0 0 90)
			(layer "F.Fab")
			(effects
				(font
					(size 1.27 1.27)
				)
			)
		)
		(duplicate_pad_numbers_are_jumpers no)
		(fp_line
			(start 0.299974 -0.150114)
			(end 0.299974 0.150114)
			(stroke
				(width 0.1)
				(type default)
			)
			(layer "F.Fab")
		)
		(fp_line
			(start -0.299974 -0.150114)
			(end 0.299974 -0.150114)
			(stroke
				(width 0.1)
				(type default)
			)
			(layer "F.Fab")
		)
		(fp_line
			(start 0.299974 0.150114)
			(end -0.299974 0.150114)
			(stroke
				(width 0.1)
				(type default)
			)
			(layer "F.Fab")
		)
		(fp_line
			(start -0.299974 0.150114)
			(end -0.299974 -0.150114)
			(stroke
				(width 0.1)
				(type default)
			)
			(layer "F.Fab")
		)
		(pad "1" smd rect
			(at -0.2667 0 90)
			(size 0.3048 0.381)
			(layers "F.Cu" "F.Mask" "F.Paste")
			(net "P5E_CPU0_PE1_TX_C_DN<7>")
		)
		(pad "2" smd rect
			(at 0.2667 0 90)
			(size 0.3048 0.381)
			(layers "F.Cu" "F.Mask" "F.Paste")
			(net "P5E_CPU0_PE1_TX_DN<7>")
		)
	)
	(footprint ""
		(layer "F.Cu")
		(at 260.561582 -77.549502)
		(property "Reference" "PC1223"
			(at 0 0 0)
			(layer "F.SilkS")
			(hide yes)
			(effects
				(font
					(size 1.27 1.27)
				)
			)
		)
		(property "Value" ""
			(at 0 0 0)
			(layer "F.Fab")
			(effects
				(font
					(size 1.27 1.27)
				)
			)
		)
		(duplicate_pad_numbers_are_jumpers no)
		(fp_line
			(start -0.7874 -0.4064)
			(end 0.7874 -0.4064)
			(stroke
				(width 0.1524)
				(type default)
			)
			(layer "F.SilkS")
		)
		(fp_line
			(start -0.7874 0.4064)
			(end -0.7874 -0.4064)
			(stroke
				(width 0.1524)
				(type default)
			)
			(layer "F.SilkS")
		)
		(fp_line
			(start 0.7874 -0.4064)
			(end 0.7874 0.4064)
			(stroke
				(width 0.1524)
				(type default)
			)
			(layer "F.SilkS")
		)
		(fp_line
			(start 0.7874 0.4064)
			(end -0.7874 0.4064)
			(stroke
				(width 0.1524)
				(type default)
			)
			(layer "F.SilkS")
		)
		(fp_line
			(start -0.67945 -0.305054)
			(end -0.12065 -0.305054)
			(stroke
				(width 0.1)
				(type default)
			)
			(layer "F.Fab")
		)
		(fp_line
			(start -0.67945 0.3048)
			(end -0.67945 -0.305054)
			(stroke
				(width 0.1)
				(type default)
			)
			(layer "F.Fab")
		)
		(fp_line
			(start -0.12065 -0.305054)
			(end -0.12065 -0.2794)
			(stroke
				(width 0.1)
				(type default)
			)
			(layer "F.Fab")
		)
		(fp_line
			(start -0.12065 -0.2794)
			(end 0.12065 -0.2794)
			(stroke
				(width 0.1)
				(type default)
			)
			(layer "F.Fab")
		)
		(fp_line
			(start -0.12065 0.2794)
			(end -0.12065 0.3048)
			(stroke
				(width 0.1)
				(type default)
			)
			(layer "F.Fab")
		)
		(fp_line
			(start -0.12065 0.3048)
			(end -0.67945 0.3048)
			(stroke
				(width 0.1)
				(type default)
			)
			(layer "F.Fab")
		)
		(fp_line
			(start 0.120396 0.2794)
			(end -0.12065 0.2794)
			(stroke
				(width 0.1)
				(type default)
			)
			(layer "F.Fab")
		)
		(fp_line
			(start 0.120396 0.3048)
			(end 0.120396 0.2794)
			(stroke
				(width 0.1)
				(type default)
			)
			(layer "F.Fab")
		)
		(fp_line
			(start 0.12065 -0.3048)
			(end 0.67945 -0.3048)
			(stroke
				(width 0.1)
				(type default)
			)
			(layer "F.Fab")
		)
		(fp_line
			(start 0.12065 -0.2794)
			(end 0.12065 -0.3048)
			(stroke
				(width 0.1)
				(type default)
			)
			(layer "F.Fab")
		)
		(fp_line
			(start 0.67945 -0.3048)
			(end 0.67945 0.3048)
			(stroke
				(width 0.1)
				(type default)
			)
			(layer "F.Fab")
		)
		(fp_line
			(start 0.67945 0.3048)
			(end 0.120396 0.3048)
			(stroke
				(width 0.1)
				(type default)
			)
			(layer "F.Fab")
		)
		(pad "1" smd circle
			(at -0.40005 0)
			(size 0 0)
			(layers "F.Cu" "F.Mask" "F.Paste")
			(net "P1V05_PCH_AUX_FB")
		)
		(pad "2" smd circle
			(at 0.40005 0)
			(size 0 0)
			(layers "F.Cu" "F.Mask" "F.Paste")
			(net "SH_P1V05_PCH_AUX_P")
		)
	)
	(footprint ""
		(layer "F.Cu")
		(at 460.49692 -127.627888)
		(property "Reference" "H29"
			(at -5.78358 -6.25729 0)
			(unlocked yes)
			(layer "F.SilkS")
			(effects
				(font
					(size 0.7874 0.5842)
					(thickness 0.1524)
				)
				(justify left)
			)
		)
		(property "Value" ""
			(at 0 0 0)
			(layer "F.Fab")
			(effects
				(font
					(size 1.27 1.27)
				)
			)
		)
		(duplicate_pad_numbers_are_jumpers no)
		(fp_circle
			(center 0 0)
			(end 2.4003 0)
			(stroke
				(width 0.1524)
				(type default)
			)
			(fill no)
			(layer "F.SilkS")
		)
		(fp_arc
			(start 5.668518 3.363214)
			(mid -6.590047 -0.148895)
			(end 5.814314 -3.104896)
			(stroke
				(width 0.1524)
				(type default)
			)
			(layer "B.SilkS")
		)
		(fp_circle
			(center 0 0)
			(end 6.5913 0)
			(stroke
				(width 0.1)
				(type default)
			)
			(fill no)
			(layer "B.Fab")
		)
		(fp_circle
			(center 0 0)
			(end 2.4003 0)
			(stroke
				(width 0.1)
				(type default)
			)
			(fill no)
			(layer "F.Fab")
		)
		(pad "" np_thru_hole circle
			(at 0 0)
			(size 3.175 3.175)
			(drill 3.175)
			(layers "*.Cu" "*.Mask")
			(clearance 0.381)
			(thermal_gap 0.381)
		)
		(zone
			(layers "F.Cu" "B.Cu" "In1.Cu" "In2.Cu" "In3.Cu" "In4.Cu" "In5.Cu" "In6.Cu"
				"In7.Cu" "In8.Cu" "In9.Cu" "In10.Cu" "In11.Cu" "In12.Cu" "In13.Cu" "In14.Cu"
				"In15.Cu" "In16.Cu"
			)
			(hatch none 0.5)
			(connect_pads
				(clearance 0)
			)
			(min_thickness 0.25)
			(keepout
				(tracks not_allowed)
				(vias allowed)
				(pads allowed)
				(copperpour not_allowed)
				(footprints allowed)
			)
			(placement
				(enabled no)
				(sheetname "")
			)
			(fill
				(thermal_gap 0.5)
				(thermal_bridge_width 0.5)
				(island_removal_mode 0)
			)
			(polygon
				(pts
					(arc
						(start 462.59242 -127.627888)
						(mid 458.40142 -127.627888)
						(end 462.59242 -127.627888)
					)
				)
			)
		)
	)
	(footprint ""
		(layer "F.Cu")
		(at 116.84508 -400.414998 -90)
		(property "Reference" "R3510"
			(at 0 0 270)
			(layer "F.SilkS")
			(hide yes)
			(effects
				(font
					(size 1.27 1.27)
				)
			)
		)
		(property "Value" ""
			(at 0 0 270)
			(layer "F.Fab")
			(effects
				(font
					(size 1.27 1.27)
				)
			)
		)
		(duplicate_pad_numbers_are_jumpers no)
		(fp_line
			(start -0.7874 0.4064)
			(end -0.7874 -0.4064)
			(stroke
				(width 0.1524)
				(type default)
			)
			(layer "F.SilkS")
		)
		(fp_line
			(start 0.7874 0.4064)
			(end -0.7874 0.4064)
			(stroke
				(width 0.1524)
				(type default)
			)
			(layer "F.SilkS")
		)
		(fp_line
			(start -0.7874 -0.4064)
			(end 0.7874 -0.4064)
			(stroke
				(width 0.1524)
				(type default)
			)
			(layer "F.SilkS")
		)
		(fp_line
			(start 0.7874 -0.4064)
			(end 0.7874 0.4064)
			(stroke
				(width 0.1524)
				(type default)
			)
			(layer "F.SilkS")
		)
		(fp_line
			(start -0.67945 0.3048)
			(end -0.67945 -0.305054)
			(stroke
				(width 0.1)
				(type default)
			)
			(layer "F.Fab")
		)
		(fp_line
			(start -0.12065 0.3048)
			(end -0.67945 0.3048)
			(stroke
				(width 0.1)
				(type default)
			)
			(layer "F.Fab")
		)
		(fp_line
			(start 0.120396 0.3048)
			(end 0.120396 0.2794)
			(stroke
				(width 0.1)
				(type default)
			)
			(layer "F.Fab")
		)
		(fp_line
			(start 0.67945 0.3048)
			(end 0.120396 0.3048)
			(stroke
				(width 0.1)
				(type default)
			)
			(layer "F.Fab")
		)
		(fp_line
			(start -0.12065 0.2794)
			(end -0.12065 0.3048)
			(stroke
				(width 0.1)
				(type default)
			)
			(layer "F.Fab")
		)
		(fp_line
			(start 0.120396 0.2794)
			(end -0.12065 0.2794)
			(stroke
				(width 0.1)
				(type default)
			)
			(layer "F.Fab")
		)
		(fp_line
			(start -0.12065 -0.2794)
			(end 0.12065 -0.2794)
			(stroke
				(width 0.1)
				(type default)
			)
			(layer "F.Fab")
		)
		(fp_line
			(start 0.12065 -0.2794)
			(end 0.12065 -0.3048)
			(stroke
				(width 0.1)
				(type default)
			)
			(layer "F.Fab")
		)
		(fp_line
			(start 0.12065 -0.3048)
			(end 0.67945 -0.3048)
			(stroke
				(width 0.1)
				(type default)
			)
			(layer "F.Fab")
		)
		(fp_line
			(start 0.67945 -0.3048)
			(end 0.67945 0.3048)
			(stroke
				(width 0.1)
				(type default)
			)
			(layer "F.Fab")
		)
		(fp_line
			(start -0.67945 -0.305054)
			(end -0.12065 -0.305054)
			(stroke
				(width 0.1)
				(type default)
			)
			(layer "F.Fab")
		)
		(fp_line
			(start -0.12065 -0.305054)
			(end -0.12065 -0.2794)
			(stroke
				(width 0.1)
				(type default)
			)
			(layer "F.Fab")
		)
		(pad "1" smd circle
			(at -0.40005 0 270)
			(size 0 0)
			(layers "F.Cu" "F.Mask" "F.Paste")
			(net "P3V3_AUX")
		)
		(pad "2" smd circle
			(at 0.40005 0 270)
			(size 0 0)
			(layers "F.Cu" "F.Mask" "F.Paste")
			(net "FM_SMB_1_ALERT_GPU_N")
		)
	)
	(footprint ""
		(layer "F.Cu")
		(at 424.204892 -394.603478 180)
		(property "Reference" "C1976"
			(at 0 0 180)
			(layer "F.SilkS")
			(hide yes)
			(effects
				(font
					(size 1.27 1.27)
				)
			)
		)
		(property "Value" ""
			(at 0 0 180)
			(layer "F.Fab")
			(effects
				(font
					(size 1.27 1.27)
				)
			)
		)
		(duplicate_pad_numbers_are_jumpers no)
		(fp_line
			(start 0.7874 0.4064)
			(end -0.7874 0.4064)
			(stroke
				(width 0.1524)
				(type default)
			)
			(layer "F.SilkS")
		)
		(fp_line
			(start 0.7874 -0.4064)
			(end 0.7874 0.4064)
			(stroke
				(width 0.1524)
				(type default)
			)
			(layer "F.SilkS")
		)
		(fp_line
			(start -0.7874 0.4064)
			(end -0.7874 -0.4064)
			(stroke
				(width 0.1524)
				(type default)
			)
			(layer "F.SilkS")
		)
		(fp_line
			(start -0.7874 -0.4064)
			(end 0.7874 -0.4064)
			(stroke
				(width 0.1524)
				(type default)
			)
			(layer "F.SilkS")
		)
		(fp_line
			(start 0.67945 0.3048)
			(end 0.120396 0.3048)
			(stroke
				(width 0.1)
				(type default)
			)
			(layer "F.Fab")
		)
		(fp_line
			(start 0.67945 -0.3048)
			(end 0.67945 0.3048)
			(stroke
				(width 0.1)
				(type default)
			)
			(layer "F.Fab")
		)
		(fp_line
			(start 0.12065 -0.2794)
			(end 0.12065 -0.3048)
			(stroke
				(width 0.1)
				(type default)
			)
			(layer "F.Fab")
		)
		(fp_line
			(start 0.12065 -0.3048)
			(end 0.67945 -0.3048)
			(stroke
				(width 0.1)
				(type default)
			)
			(layer "F.Fab")
		)
		(fp_line
			(start 0.120396 0.3048)
			(end 0.120396 0.2794)
			(stroke
				(width 0.1)
				(type default)
			)
			(layer "F.Fab")
		)
		(fp_line
			(start 0.120396 0.2794)
			(end -0.12065 0.2794)
			(stroke
				(width 0.1)
				(type default)
			)
			(layer "F.Fab")
		)
		(fp_line
			(start -0.12065 0.3048)
			(end -0.67945 0.3048)
			(stroke
				(width 0.1)
				(type default)
			)
			(layer "F.Fab")
		)
		(fp_line
			(start -0.12065 0.2794)
			(end -0.12065 0.3048)
			(stroke
				(width 0.1)
				(type default)
			)
			(layer "F.Fab")
		)
		(fp_line
			(start -0.12065 -0.2794)
			(end 0.12065 -0.2794)
			(stroke
				(width 0.1)
				(type default)
			)
			(layer "F.Fab")
		)
		(fp_line
			(start -0.12065 -0.305054)
			(end -0.12065 -0.2794)
			(stroke
				(width 0.1)
				(type default)
			)
			(layer "F.Fab")
		)
		(fp_line
			(start -0.67945 0.3048)
			(end -0.67945 -0.305054)
			(stroke
				(width 0.1)
				(type default)
			)
			(layer "F.Fab")
		)
		(fp_line
			(start -0.67945 -0.305054)
			(end -0.12065 -0.305054)
			(stroke
				(width 0.1)
				(type default)
			)
			(layer "F.Fab")
		)
		(pad "1" smd circle
			(at -0.40005 0 180)
			(size 0 0)
			(layers "F.Cu" "F.Mask" "F.Paste")
			(net "GPU_FPGA_OVERT_ISO_N")
		)
		(pad "2" smd circle
			(at 0.40005 0 180)
			(size 0 0)
			(layers "F.Cu" "F.Mask" "F.Paste")
			(net "GND")
		)
	)
	(footprint ""
		(layer "F.Cu")
		(at 160.311084 -81.91246 -90)
		(property "Reference" "R3224"
			(at 0 0 270)
			(layer "F.SilkS")
			(hide yes)
			(effects
				(font
					(size 1.27 1.27)
				)
			)
		)
		(property "Value" ""
			(at 0 0 270)
			(layer "F.Fab")
			(effects
				(font
					(size 1.27 1.27)
				)
			)
		)
		(duplicate_pad_numbers_are_jumpers no)
		(fp_line
			(start -0.7874 0.4064)
			(end -0.7874 -0.4064)
			(stroke
				(width 0.1524)
				(type default)
			)
			(layer "F.SilkS")
		)
		(fp_line
			(start 0.7874 0.4064)
			(end -0.7874 0.4064)
			(stroke
				(width 0.1524)
				(type default)
			)
			(layer "F.SilkS")
		)
		(fp_line
			(start -0.7874 -0.4064)
			(end 0.7874 -0.4064)
			(stroke
				(width 0.1524)
				(type default)
			)
			(layer "F.SilkS")
		)
		(fp_line
			(start 0.7874 -0.4064)
			(end 0.7874 0.4064)
			(stroke
				(width 0.1524)
				(type default)
			)
			(layer "F.SilkS")
		)
		(fp_line
			(start -0.67945 0.3048)
			(end -0.67945 -0.305054)
			(stroke
				(width 0.1)
				(type default)
			)
			(layer "F.Fab")
		)
		(fp_line
			(start -0.12065 0.3048)
			(end -0.67945 0.3048)
			(stroke
				(width 0.1)
				(type default)
			)
			(layer "F.Fab")
		)
		(fp_line
			(start 0.120396 0.3048)
			(end 0.120396 0.2794)
			(stroke
				(width 0.1)
				(type default)
			)
			(layer "F.Fab")
		)
		(fp_line
			(start 0.67945 0.3048)
			(end 0.120396 0.3048)
			(stroke
				(width 0.1)
				(type default)
			)
			(layer "F.Fab")
		)
		(fp_line
			(start -0.12065 0.2794)
			(end -0.12065 0.3048)
			(stroke
				(width 0.1)
				(type default)
			)
			(layer "F.Fab")
		)
		(fp_line
			(start 0.120396 0.2794)
			(end -0.12065 0.2794)
			(stroke
				(width 0.1)
				(type default)
			)
			(layer "F.Fab")
		)
		(fp_line
			(start -0.12065 -0.2794)
			(end 0.12065 -0.2794)
			(stroke
				(width 0.1)
				(type default)
			)
			(layer "F.Fab")
		)
		(fp_line
			(start 0.12065 -0.2794)
			(end 0.12065 -0.3048)
			(stroke
				(width 0.1)
				(type default)
			)
			(layer "F.Fab")
		)
		(fp_line
			(start 0.12065 -0.3048)
			(end 0.67945 -0.3048)
			(stroke
				(width 0.1)
				(type default)
			)
			(layer "F.Fab")
		)
		(fp_line
			(start 0.67945 -0.3048)
			(end 0.67945 0.3048)
			(stroke
				(width 0.1)
				(type default)
			)
			(layer "F.Fab")
		)
		(fp_line
			(start -0.67945 -0.305054)
			(end -0.12065 -0.305054)
			(stroke
				(width 0.1)
				(type default)
			)
			(layer "F.Fab")
		)
		(fp_line
			(start -0.12065 -0.305054)
			(end -0.12065 -0.2794)
			(stroke
				(width 0.1)
				(type default)
			)
			(layer "F.Fab")
		)
		(pad "1" smd circle
			(at -0.40005 0 270)
			(size 0 0)
			(layers "F.Cu" "F.Mask" "F.Paste")
			(net "SMB_S3M_CPU1_PIROM_3V3AUX_SCL")
		)
		(pad "2" smd circle
			(at 0.40005 0 270)
			(size 0 0)
			(layers "F.Cu" "F.Mask" "F.Paste")
			(net "P3V3_AUX")
		)
	)
	(footprint ""
		(layer "F.Cu")
		(at 114.706654 -358.93375)
		(property "Reference" "PC101"
			(at 0 0 0)
			(layer "F.SilkS")
			(hide yes)
			(effects
				(font
					(size 1.27 1.27)
				)
			)
		)
		(property "Value" ""
			(at 0 0 0)
			(layer "F.Fab")
			(effects
				(font
					(size 1.27 1.27)
				)
			)
		)
		(duplicate_pad_numbers_are_jumpers no)
		(fp_line
			(start -0.7874 -0.4064)
			(end 0.7874 -0.4064)
			(stroke
				(width 0.1524)
				(type default)
			)
			(layer "F.SilkS")
		)
		(fp_line
			(start -0.7874 0.4064)
			(end -0.7874 -0.4064)
			(stroke
				(width 0.1524)
				(type default)
			)
			(layer "F.SilkS")
		)
		(fp_line
			(start 0.7874 -0.4064)
			(end 0.7874 0.4064)
			(stroke
				(width 0.1524)
				(type default)
			)
			(layer "F.SilkS")
		)
		(fp_line
			(start 0.7874 0.4064)
			(end -0.7874 0.4064)
			(stroke
				(width 0.1524)
				(type default)
			)
			(layer "F.SilkS")
		)
		(fp_line
			(start -0.67945 -0.305054)
			(end -0.12065 -0.305054)
			(stroke
				(width 0.1)
				(type default)
			)
			(layer "F.Fab")
		)
		(fp_line
			(start -0.67945 0.3048)
			(end -0.67945 -0.305054)
			(stroke
				(width 0.1)
				(type default)
			)
			(layer "F.Fab")
		)
		(fp_line
			(start -0.12065 -0.305054)
			(end -0.12065 -0.2794)
			(stroke
				(width 0.1)
				(type default)
			)
			(layer "F.Fab")
		)
		(fp_line
			(start -0.12065 -0.2794)
			(end 0.12065 -0.2794)
			(stroke
				(width 0.1)
				(type default)
			)
			(layer "F.Fab")
		)
		(fp_line
			(start -0.12065 0.2794)
			(end -0.12065 0.3048)
			(stroke
				(width 0.1)
				(type default)
			)
			(layer "F.Fab")
		)
		(fp_line
			(start -0.12065 0.3048)
			(end -0.67945 0.3048)
			(stroke
				(width 0.1)
				(type default)
			)
			(layer "F.Fab")
		)
		(fp_line
			(start 0.120396 0.2794)
			(end -0.12065 0.2794)
			(stroke
				(width 0.1)
				(type default)
			)
			(layer "F.Fab")
		)
		(fp_line
			(start 0.120396 0.3048)
			(end 0.120396 0.2794)
			(stroke
				(width 0.1)
				(type default)
			)
			(layer "F.Fab")
		)
		(fp_line
			(start 0.12065 -0.3048)
			(end 0.67945 -0.3048)
			(stroke
				(width 0.1)
				(type default)
			)
			(layer "F.Fab")
		)
		(fp_line
			(start 0.12065 -0.2794)
			(end 0.12065 -0.3048)
			(stroke
				(width 0.1)
				(type default)
			)
			(layer "F.Fab")
		)
		(fp_line
			(start 0.67945 -0.3048)
			(end 0.67945 0.3048)
			(stroke
				(width 0.1)
				(type default)
			)
			(layer "F.Fab")
		)
		(fp_line
			(start 0.67945 0.3048)
			(end 0.120396 0.3048)
			(stroke
				(width 0.1)
				(type default)
			)
			(layer "F.Fab")
		)
		(pad "1" smd circle
			(at -0.40005 0)
			(size 0 0)
			(layers "F.Cu" "F.Mask" "F.Paste")
			(net "PVCCFA_EHV_FIVRA_CPU1_BTSEN")
		)
		(pad "2" smd circle
			(at 0.40005 0)
			(size 0 0)
			(layers "F.Cu" "F.Mask" "F.Paste")
			(net "GND")
		)
	)
	(footprint ""
		(layer "F.Cu")
		(at 377.46559 -64.866012 180)
		(property "Reference" "R751"
			(at 0 0 180)
			(layer "F.SilkS")
			(hide yes)
			(effects
				(font
					(size 1.27 1.27)
				)
			)
		)
		(property "Value" ""
			(at 0 0 180)
			(layer "F.Fab")
			(effects
				(font
					(size 1.27 1.27)
				)
			)
		)
		(duplicate_pad_numbers_are_jumpers no)
		(fp_line
			(start 0.7874 0.4064)
			(end -0.7874 0.4064)
			(stroke
				(width 0.1524)
				(type default)
			)
			(layer "F.SilkS")
		)
		(fp_line
			(start 0.7874 -0.4064)
			(end 0.7874 0.4064)
			(stroke
				(width 0.1524)
				(type default)
			)
			(layer "F.SilkS")
		)
		(fp_line
			(start -0.7874 0.4064)
			(end -0.7874 -0.4064)
			(stroke
				(width 0.1524)
				(type default)
			)
			(layer "F.SilkS")
		)
		(fp_line
			(start -0.7874 -0.4064)
			(end 0.7874 -0.4064)
			(stroke
				(width 0.1524)
				(type default)
			)
			(layer "F.SilkS")
		)
		(fp_line
			(start 0.67945 0.3048)
			(end 0.120396 0.3048)
			(stroke
				(width 0.1)
				(type default)
			)
			(layer "F.Fab")
		)
		(fp_line
			(start 0.67945 -0.3048)
			(end 0.67945 0.3048)
			(stroke
				(width 0.1)
				(type default)
			)
			(layer "F.Fab")
		)
		(fp_line
			(start 0.12065 -0.2794)
			(end 0.12065 -0.3048)
			(stroke
				(width 0.1)
				(type default)
			)
			(layer "F.Fab")
		)
		(fp_line
			(start 0.12065 -0.3048)
			(end 0.67945 -0.3048)
			(stroke
				(width 0.1)
				(type default)
			)
			(layer "F.Fab")
		)
		(fp_line
			(start 0.120396 0.3048)
			(end 0.120396 0.2794)
			(stroke
				(width 0.1)
				(type default)
			)
			(layer "F.Fab")
		)
		(fp_line
			(start 0.120396 0.2794)
			(end -0.12065 0.2794)
			(stroke
				(width 0.1)
				(type default)
			)
			(layer "F.Fab")
		)
		(fp_line
			(start -0.12065 0.3048)
			(end -0.67945 0.3048)
			(stroke
				(width 0.1)
				(type default)
			)
			(layer "F.Fab")
		)
		(fp_line
			(start -0.12065 0.2794)
			(end -0.12065 0.3048)
			(stroke
				(width 0.1)
				(type default)
			)
			(layer "F.Fab")
		)
		(fp_line
			(start -0.12065 -0.2794)
			(end 0.12065 -0.2794)
			(stroke
				(width 0.1)
				(type default)
			)
			(layer "F.Fab")
		)
		(fp_line
			(start -0.12065 -0.305054)
			(end -0.12065 -0.2794)
			(stroke
				(width 0.1)
				(type default)
			)
			(layer "F.Fab")
		)
		(fp_line
			(start -0.67945 0.3048)
			(end -0.67945 -0.305054)
			(stroke
				(width 0.1)
				(type default)
			)
			(layer "F.Fab")
		)
		(fp_line
			(start -0.67945 -0.305054)
			(end -0.12065 -0.305054)
			(stroke
				(width 0.1)
				(type default)
			)
			(layer "F.Fab")
		)
		(pad "1" smd circle
			(at -0.40005 0 180)
			(size 0 0)
			(layers "F.Cu" "F.Mask" "F.Paste")
			(net "P1V05_PCH_AUX")
		)
		(pad "2" smd circle
			(at 0.40005 0 180)
			(size 0 0)
			(layers "F.Cu" "F.Mask" "F.Paste")
			(net "H_DBP_PRDY_N_PCH")
		)
	)
	(footprint ""
		(layer "F.Cu")
		(at 495.90833 -153.174192 -90)
		(property "Reference" "X4"
			(at -1.336548 2.921 90)
			(unlocked yes)
			(layer "F.SilkS")
			(effects
				(font
					(size 0.7874 0.5842)
					(thickness 0.1524)
				)
				(justify left)
			)
		)
		(property "Value" ""
			(at 0 0 270)
			(layer "F.Fab")
			(effects
				(font
					(size 1.27 1.27)
				)
			)
		)
		(property "Device Type" "TP_TDR_4P_FTS_TH-TP_TDR_4P_DIPA"
			(at 1.30175 1.27 0)
			(unlocked yes)
			(layer "F.Fab")
			(hide yes)
			(effects
				(font
					(size 0.635 0.4064)
					(thickness 0.1524)
				)
			)
		)
		(property "User Part Number" "N_A"
			(at 1.30175 1.27 0)
			(unlocked yes)
			(layer "Cmts.User")
			(hide yes)
			(effects
				(font
					(size 0.635 0.4064)
					(thickness 0.1524)
				)
			)
		)
		(duplicate_pad_numbers_are_jumpers no)
		(fp_line
			(start 0 3.81)
			(end 2.54 3.81)
			(stroke
				(width 0.1524)
				(type default)
			)
			(layer "F.SilkS")
		)
		(fp_line
			(start 2.54 3.81)
			(end 2.54 3.6703)
			(stroke
				(width 0.1524)
				(type default)
			)
			(layer "F.SilkS")
		)
		(fp_line
			(start 0 3.175)
			(end 0 3.81)
			(stroke
				(width 0.1524)
				(type default)
			)
			(layer "F.SilkS")
		)
		(fp_line
			(start 2.54 1.4097)
			(end 2.54 1.1303)
			(stroke
				(width 0.1524)
				(type default)
			)
			(layer "F.SilkS")
		)
		(fp_line
			(start 0 0.635)
			(end 0 1.905)
			(stroke
				(width 0.1524)
				(type default)
			)
			(layer "F.SilkS")
		)
		(fp_line
			(start 2.54 -1.1303)
			(end 2.54 -1.27)
			(stroke
				(width 0.1524)
				(type default)
			)
			(layer "F.SilkS")
		)
		(fp_line
			(start 0 -1.27)
			(end 0 -0.635)
			(stroke
				(width 0.1524)
				(type default)
			)
			(layer "F.SilkS")
		)
		(fp_line
			(start 2.54 -1.27)
			(end 0 -1.27)
			(stroke
				(width 0.1524)
				(type default)
			)
			(layer "F.SilkS")
		)
		(fp_poly
			(pts
				(xy -0.761746 0) (xy -2.285746 0.762) (xy -2.285746 -0.762)
			)
			(stroke
				(width 0)
				(type default)
			)
			(fill yes)
			(layer "F.SilkS")
		)
		(fp_line
			(start 0 3.81)
			(end 2.54 3.81)
			(stroke
				(width 0.1)
				(type default)
			)
			(layer "F.Fab")
		)
		(fp_line
			(start 2.54 3.81)
			(end 2.54 -1.27)
			(stroke
				(width 0.1)
				(type default)
			)
			(layer "F.Fab")
		)
		(fp_line
			(start 0 -1.27)
			(end 0 3.81)
			(stroke
				(width 0.1)
				(type default)
			)
			(layer "F.Fab")
		)
		(fp_line
			(start 2.54 -1.27)
			(end 0 -1.27)
			(stroke
				(width 0.1)
				(type default)
			)
			(layer "F.Fab")
		)
		(fp_poly
			(pts
				(xy -0.761746 0) (xy -2.285746 -0.762) (xy -2.285746 0.762)
			)
			(stroke
				(width 0)
				(type default)
			)
			(fill yes)
			(layer "F.Fab")
		)
		(pad "1" thru_hole circle
			(at 0 0 270)
			(size 1.0033 1.0033)
			(drill 0.249936)
			(layers "*.Cu" "*.Mask")
			(remove_unused_layers no)
			(net "TDR_DIFF_85_IN3_DP")
			(clearance 0.10795)
			(thermal_gap 0.10795)
			(padstack
				(mode front_inner_back)
				(layer "Inner"
					(shape circle)
					(size 0.8001 0.8001)
					(clearance 0.1524)
				)
				(layer "B.Cu"
					(shape circle)
					(size 1.0033 1.0033)
					(clearance 0.10795)
				)
			)
		)
		(pad "2" thru_hole circle
			(at 2.54 0 270)
			(size 1.9939 1.9939)
			(drill 0.249936)
			(layers "*.Cu" "*.Mask")
			(remove_unused_layers no)
			(net "T1_GND")
			(clearance 0.10795)
			(thermal_gap 0.10795)
			(padstack
				(mode front_inner_back)
				(layer "Inner"
					(shape circle)
					(size 0.8001 0.8001)
					(clearance 0.1524)
				)
				(layer "B.Cu"
					(shape circle)
					(size 1.9939 1.9939)
					(clearance 0.10795)
				)
			)
		)
		(pad "3" thru_hole circle
			(at 2.54 2.54 270)
			(size 1.9939 1.9939)
			(drill 0.249936)
			(layers "*.Cu" "*.Mask")
			(remove_unused_layers no)
			(net "T1_GND")
			(clearance 0.10795)
			(thermal_gap 0.10795)
			(padstack
				(mode front_inner_back)
				(layer "Inner"
					(shape circle)
					(size 0.8001 0.8001)
					(clearance 0.1524)
				)
				(layer "B.Cu"
					(shape circle)
					(size 1.9939 1.9939)
					(clearance 0.10795)
				)
			)
		)
		(pad "4" thru_hole circle
			(at 0 2.54 270)
			(size 1.0033 1.0033)
			(drill 0.249936)
			(layers "*.Cu" "*.Mask")
			(remove_unused_layers no)
			(net "TDR_DIFF_85_IN3_DN")
			(clearance 0.10795)
			(thermal_gap 0.10795)
			(padstack
				(mode front_inner_back)
				(layer "Inner"
					(shape circle)
					(size 0.8001 0.8001)
					(clearance 0.1524)
				)
				(layer "B.Cu"
					(shape circle)
					(size 1.0033 1.0033)
					(clearance 0.10795)
				)
			)
		)
	)
	(footprint ""
		(layer "F.Cu")
		(at 149.898608 -73.285858 180)
		(property "Reference" "C1613"
			(at 0 0 180)
			(layer "F.SilkS")
			(hide yes)
			(effects
				(font
					(size 1.27 1.27)
				)
			)
		)
		(property "Value" ""
			(at 0 0 180)
			(layer "F.Fab")
			(effects
				(font
					(size 1.27 1.27)
				)
			)
		)
		(duplicate_pad_numbers_are_jumpers no)
		(fp_line
			(start 0.7874 0.4064)
			(end -0.7874 0.4064)
			(stroke
				(width 0.1524)
				(type default)
			)
			(layer "F.SilkS")
		)
		(fp_line
			(start 0.7874 -0.4064)
			(end 0.7874 0.4064)
			(stroke
				(width 0.1524)
				(type default)
			)
			(layer "F.SilkS")
		)
		(fp_line
			(start -0.7874 0.4064)
			(end -0.7874 -0.4064)
			(stroke
				(width 0.1524)
				(type default)
			)
			(layer "F.SilkS")
		)
		(fp_line
			(start -0.7874 -0.4064)
			(end 0.7874 -0.4064)
			(stroke
				(width 0.1524)
				(type default)
			)
			(layer "F.SilkS")
		)
		(fp_line
			(start 0.67945 0.3048)
			(end 0.120396 0.3048)
			(stroke
				(width 0.1)
				(type default)
			)
			(layer "F.Fab")
		)
		(fp_line
			(start 0.67945 -0.3048)
			(end 0.67945 0.3048)
			(stroke
				(width 0.1)
				(type default)
			)
			(layer "F.Fab")
		)
		(fp_line
			(start 0.12065 -0.2794)
			(end 0.12065 -0.3048)
			(stroke
				(width 0.1)
				(type default)
			)
			(layer "F.Fab")
		)
		(fp_line
			(start 0.12065 -0.3048)
			(end 0.67945 -0.3048)
			(stroke
				(width 0.1)
				(type default)
			)
			(layer "F.Fab")
		)
		(fp_line
			(start 0.120396 0.3048)
			(end 0.120396 0.2794)
			(stroke
				(width 0.1)
				(type default)
			)
			(layer "F.Fab")
		)
		(fp_line
			(start 0.120396 0.2794)
			(end -0.12065 0.2794)
			(stroke
				(width 0.1)
				(type default)
			)
			(layer "F.Fab")
		)
		(fp_line
			(start -0.12065 0.3048)
			(end -0.67945 0.3048)
			(stroke
				(width 0.1)
				(type default)
			)
			(layer "F.Fab")
		)
		(fp_line
			(start -0.12065 0.2794)
			(end -0.12065 0.3048)
			(stroke
				(width 0.1)
				(type default)
			)
			(layer "F.Fab")
		)
		(fp_line
			(start -0.12065 -0.2794)
			(end 0.12065 -0.2794)
			(stroke
				(width 0.1)
				(type default)
			)
			(layer "F.Fab")
		)
		(fp_line
			(start -0.12065 -0.305054)
			(end -0.12065 -0.2794)
			(stroke
				(width 0.1)
				(type default)
			)
			(layer "F.Fab")
		)
		(fp_line
			(start -0.67945 0.3048)
			(end -0.67945 -0.305054)
			(stroke
				(width 0.1)
				(type default)
			)
			(layer "F.Fab")
		)
		(fp_line
			(start -0.67945 -0.305054)
			(end -0.12065 -0.305054)
			(stroke
				(width 0.1)
				(type default)
			)
			(layer "F.Fab")
		)
		(pad "1" smd circle
			(at -0.40005 0 180)
			(size 0 0)
			(layers "F.Cu" "F.Mask" "F.Paste")
			(net "P3V3_AUX")
		)
		(pad "2" smd circle
			(at 0.40005 0 180)
			(size 0 0)
			(layers "F.Cu" "F.Mask" "F.Paste")
			(net "GND")
		)
	)
	(footprint ""
		(layer "F.Cu")
		(at 306.83454 -433.0573 90)
		(property "Reference" "R4142"
			(at 0 0 90)
			(layer "F.SilkS")
			(hide yes)
			(effects
				(font
					(size 1.27 1.27)
				)
			)
		)
		(property "Value" ""
			(at 0 0 90)
			(layer "F.Fab")
			(effects
				(font
					(size 1.27 1.27)
				)
			)
		)
		(duplicate_pad_numbers_are_jumpers no)
		(fp_line
			(start 0.7874 -0.4064)
			(end 0.7874 0.4064)
			(stroke
				(width 0.1524)
				(type default)
			)
			(layer "F.SilkS")
		)
		(fp_line
			(start -0.7874 -0.4064)
			(end 0.7874 -0.4064)
			(stroke
				(width 0.1524)
				(type default)
			)
			(layer "F.SilkS")
		)
		(fp_line
			(start 0.7874 0.4064)
			(end -0.7874 0.4064)
			(stroke
				(width 0.1524)
				(type default)
			)
			(layer "F.SilkS")
		)
		(fp_line
			(start -0.7874 0.4064)
			(end -0.7874 -0.4064)
			(stroke
				(width 0.1524)
				(type default)
			)
			(layer "F.SilkS")
		)
		(fp_line
			(start -0.12065 -0.305054)
			(end -0.12065 -0.2794)
			(stroke
				(width 0.1)
				(type default)
			)
			(layer "F.Fab")
		)
		(fp_line
			(start -0.67945 -0.305054)
			(end -0.12065 -0.305054)
			(stroke
				(width 0.1)
				(type default)
			)
			(layer "F.Fab")
		)
		(fp_line
			(start 0.67945 -0.3048)
			(end 0.67945 0.3048)
			(stroke
				(width 0.1)
				(type default)
			)
			(layer "F.Fab")
		)
		(fp_line
			(start 0.12065 -0.3048)
			(end 0.67945 -0.3048)
			(stroke
				(width 0.1)
				(type default)
			)
			(layer "F.Fab")
		)
		(fp_line
			(start 0.12065 -0.2794)
			(end 0.12065 -0.3048)
			(stroke
				(width 0.1)
				(type default)
			)
			(layer "F.Fab")
		)
		(fp_line
			(start -0.12065 -0.2794)
			(end 0.12065 -0.2794)
			(stroke
				(width 0.1)
				(type default)
			)
			(layer "F.Fab")
		)
		(fp_line
			(start 0.120396 0.2794)
			(end -0.12065 0.2794)
			(stroke
				(width 0.1)
				(type default)
			)
			(layer "F.Fab")
		)
		(fp_line
			(start -0.12065 0.2794)
			(end -0.12065 0.3048)
			(stroke
				(width 0.1)
				(type default)
			)
			(layer "F.Fab")
		)
		(fp_line
			(start 0.67945 0.3048)
			(end 0.120396 0.3048)
			(stroke
				(width 0.1)
				(type default)
			)
			(layer "F.Fab")
		)
		(fp_line
			(start 0.120396 0.3048)
			(end 0.120396 0.2794)
			(stroke
				(width 0.1)
				(type default)
			)
			(layer "F.Fab")
		)
		(fp_line
			(start -0.12065 0.3048)
			(end -0.67945 0.3048)
			(stroke
				(width 0.1)
				(type default)
			)
			(layer "F.Fab")
		)
		(fp_line
			(start -0.67945 0.3048)
			(end -0.67945 -0.305054)
			(stroke
				(width 0.1)
				(type default)
			)
			(layer "F.Fab")
		)
		(pad "1" smd circle
			(at -0.40005 0 90)
			(size 0 0)
			(layers "F.Cu" "F.Mask" "F.Paste")
			(net "P3V3_AUX")
		)
		(pad "2" smd circle
			(at 0.40005 0 90)
			(size 0 0)
			(layers "F.Cu" "F.Mask" "F.Paste")
			(net "PRSNT_CABLE_GPU_A2_ISO_N")
		)
	)
	(footprint ""
		(layer "F.Cu")
		(at 23.392384 -176.82972 -90)
		(property "Reference" "PR2"
			(at 0 0 270)
			(layer "F.SilkS")
			(hide yes)
			(effects
				(font
					(size 1.27 1.27)
				)
			)
		)
		(property "Value" ""
			(at 0 0 270)
			(layer "F.Fab")
			(effects
				(font
					(size 1.27 1.27)
				)
			)
		)
		(duplicate_pad_numbers_are_jumpers no)
		(fp_line
			(start -0.7874 0.4064)
			(end -0.7874 -0.4064)
			(stroke
				(width 0.1524)
				(type default)
			)
			(layer "F.SilkS")
		)
		(fp_line
			(start 0.7874 0.4064)
			(end -0.7874 0.4064)
			(stroke
				(width 0.1524)
				(type default)
			)
			(layer "F.SilkS")
		)
		(fp_line
			(start -0.7874 -0.4064)
			(end 0.7874 -0.4064)
			(stroke
				(width 0.1524)
				(type default)
			)
			(layer "F.SilkS")
		)
		(fp_line
			(start 0.7874 -0.4064)
			(end 0.7874 0.4064)
			(stroke
				(width 0.1524)
				(type default)
			)
			(layer "F.SilkS")
		)
		(fp_line
			(start -0.67945 0.3048)
			(end -0.67945 -0.305054)
			(stroke
				(width 0.1)
				(type default)
			)
			(layer "F.Fab")
		)
		(fp_line
			(start -0.12065 0.3048)
			(end -0.67945 0.3048)
			(stroke
				(width 0.1)
				(type default)
			)
			(layer "F.Fab")
		)
		(fp_line
			(start 0.120396 0.3048)
			(end 0.120396 0.2794)
			(stroke
				(width 0.1)
				(type default)
			)
			(layer "F.Fab")
		)
		(fp_line
			(start 0.67945 0.3048)
			(end 0.120396 0.3048)
			(stroke
				(width 0.1)
				(type default)
			)
			(layer "F.Fab")
		)
		(fp_line
			(start -0.12065 0.2794)
			(end -0.12065 0.3048)
			(stroke
				(width 0.1)
				(type default)
			)
			(layer "F.Fab")
		)
		(fp_line
			(start 0.120396 0.2794)
			(end -0.12065 0.2794)
			(stroke
				(width 0.1)
				(type default)
			)
			(layer "F.Fab")
		)
		(fp_line
			(start -0.12065 -0.2794)
			(end 0.12065 -0.2794)
			(stroke
				(width 0.1)
				(type default)
			)
			(layer "F.Fab")
		)
		(fp_line
			(start 0.12065 -0.2794)
			(end 0.12065 -0.3048)
			(stroke
				(width 0.1)
				(type default)
			)
			(layer "F.Fab")
		)
		(fp_line
			(start 0.12065 -0.3048)
			(end 0.67945 -0.3048)
			(stroke
				(width 0.1)
				(type default)
			)
			(layer "F.Fab")
		)
		(fp_line
			(start 0.67945 -0.3048)
			(end 0.67945 0.3048)
			(stroke
				(width 0.1)
				(type default)
			)
			(layer "F.Fab")
		)
		(fp_line
			(start -0.67945 -0.305054)
			(end -0.12065 -0.305054)
			(stroke
				(width 0.1)
				(type default)
			)
			(layer "F.Fab")
		)
		(fp_line
			(start -0.12065 -0.305054)
			(end -0.12065 -0.2794)
			(stroke
				(width 0.1)
				(type default)
			)
			(layer "F.Fab")
		)
		(pad "1" smd circle
			(at -0.40005 0 270)
			(size 0 0)
			(layers "F.Cu" "F.Mask" "F.Paste")
			(net "GND")
		)
		(pad "2" smd circle
			(at 0.40005 0 270)
			(size 0 0)
			(layers "F.Cu" "F.Mask" "F.Paste")
			(net "GND")
		)
	)
	(footprint ""
		(layer "F.Cu")
		(at 174.112936 -363.249972)
		(property "Reference" "PL14"
			(at 0.844804 -3.134868 0)
			(unlocked yes)
			(layer "F.SilkS")
			(effects
				(font
					(size 0.7874 0.5842)
					(thickness 0.1524)
				)
				(justify left)
			)
		)
		(property "Value" ""
			(at 0 0 0)
			(layer "F.Fab")
			(effects
				(font
					(size 1.27 1.27)
				)
			)
		)
		(duplicate_pad_numbers_are_jumpers no)
		(fp_line
			(start -2.249932 -2.249932)
			(end 2.249932 -2.249932)
			(stroke
				(width 0.1524)
				(type default)
			)
			(layer "F.SilkS")
		)
		(fp_line
			(start -2.249932 -1.3843)
			(end -2.249932 -2.249932)
			(stroke
				(width 0.1524)
				(type default)
			)
			(layer "F.SilkS")
		)
		(fp_line
			(start -2.249932 2.249932)
			(end -2.249932 1.3843)
			(stroke
				(width 0.1524)
				(type default)
			)
			(layer "F.SilkS")
		)
		(fp_line
			(start 2.249932 -2.249932)
			(end 2.249932 -1.3843)
			(stroke
				(width 0.1524)
				(type default)
			)
			(layer "F.SilkS")
		)
		(fp_line
			(start 2.249932 1.3843)
			(end 2.249932 2.249932)
			(stroke
				(width 0.1524)
				(type default)
			)
			(layer "F.SilkS")
		)
		(fp_line
			(start 2.249932 2.249932)
			(end -2.249932 2.249932)
			(stroke
				(width 0.1524)
				(type default)
			)
			(layer "F.SilkS")
		)
		(fp_line
			(start -2.249932 -2.249932)
			(end 2.249932 -2.249932)
			(stroke
				(width 0.1)
				(type default)
			)
			(layer "F.Fab")
		)
		(fp_line
			(start -2.249932 2.249932)
			(end -2.249932 -2.249932)
			(stroke
				(width 0.1)
				(type default)
			)
			(layer "F.Fab")
		)
		(fp_line
			(start 2.249932 -2.249932)
			(end 2.249932 2.249932)
			(stroke
				(width 0.1)
				(type default)
			)
			(layer "F.Fab")
		)
		(fp_line
			(start 2.249932 2.249932)
			(end -2.249932 2.249932)
			(stroke
				(width 0.1)
				(type default)
			)
			(layer "F.Fab")
		)
		(pad "1" smd rect
			(at -1.82499 0)
			(size 1.0668 2.5146)
			(layers "F.Cu" "F.Mask" "F.Paste")
			(net "P12V_AUX")
		)
		(pad "2" smd rect
			(at 1.82499 0)
			(size 1.0668 2.5146)
			(layers "F.Cu" "F.Mask" "F.Paste")
			(net "SW_P12V_PVCCFA_EHV_FIVRA_CPU1_R")
		)
	)
	(footprint ""
		(layer "F.Cu")
		(at 365.308134 -337.955382)
		(property "Reference" "PC275_P0_3"
			(at 0 0 0)
			(layer "F.SilkS")
			(hide yes)
			(effects
				(font
					(size 1.27 1.27)
				)
			)
		)
		(property "Value" ""
			(at 0 0 0)
			(layer "F.Fab")
			(effects
				(font
					(size 1.27 1.27)
				)
			)
		)
		(duplicate_pad_numbers_are_jumpers no)
		(fp_line
			(start -0.7874 -0.4064)
			(end 0.7874 -0.4064)
			(stroke
				(width 0.1524)
				(type default)
			)
			(layer "F.SilkS")
		)
		(fp_line
			(start -0.7874 0.4064)
			(end -0.7874 -0.4064)
			(stroke
				(width 0.1524)
				(type default)
			)
			(layer "F.SilkS")
		)
		(fp_line
			(start 0.7874 -0.4064)
			(end 0.7874 0.4064)
			(stroke
				(width 0.1524)
				(type default)
			)
			(layer "F.SilkS")
		)
		(fp_line
			(start 0.7874 0.4064)
			(end -0.7874 0.4064)
			(stroke
				(width 0.1524)
				(type default)
			)
			(layer "F.SilkS")
		)
		(fp_line
			(start -0.67945 -0.305054)
			(end -0.12065 -0.305054)
			(stroke
				(width 0.1)
				(type default)
			)
			(layer "F.Fab")
		)
		(fp_line
			(start -0.67945 0.3048)
			(end -0.67945 -0.305054)
			(stroke
				(width 0.1)
				(type default)
			)
			(layer "F.Fab")
		)
		(fp_line
			(start -0.12065 -0.305054)
			(end -0.12065 -0.2794)
			(stroke
				(width 0.1)
				(type default)
			)
			(layer "F.Fab")
		)
		(fp_line
			(start -0.12065 -0.2794)
			(end 0.12065 -0.2794)
			(stroke
				(width 0.1)
				(type default)
			)
			(layer "F.Fab")
		)
		(fp_line
			(start -0.12065 0.2794)
			(end -0.12065 0.3048)
			(stroke
				(width 0.1)
				(type default)
			)
			(layer "F.Fab")
		)
		(fp_line
			(start -0.12065 0.3048)
			(end -0.67945 0.3048)
			(stroke
				(width 0.1)
				(type default)
			)
			(layer "F.Fab")
		)
		(fp_line
			(start 0.120396 0.2794)
			(end -0.12065 0.2794)
			(stroke
				(width 0.1)
				(type default)
			)
			(layer "F.Fab")
		)
		(fp_line
			(start 0.120396 0.3048)
			(end 0.120396 0.2794)
			(stroke
				(width 0.1)
				(type default)
			)
			(layer "F.Fab")
		)
		(fp_line
			(start 0.12065 -0.3048)
			(end 0.67945 -0.3048)
			(stroke
				(width 0.1)
				(type default)
			)
			(layer "F.Fab")
		)
		(fp_line
			(start 0.12065 -0.2794)
			(end 0.12065 -0.3048)
			(stroke
				(width 0.1)
				(type default)
			)
			(layer "F.Fab")
		)
		(fp_line
			(start 0.67945 -0.3048)
			(end 0.67945 0.3048)
			(stroke
				(width 0.1)
				(type default)
			)
			(layer "F.Fab")
		)
		(fp_line
			(start 0.67945 0.3048)
			(end 0.120396 0.3048)
			(stroke
				(width 0.1)
				(type default)
			)
			(layer "F.Fab")
		)
		(pad "1" smd circle
			(at -0.40005 0)
			(size 0 0)
			(layers "F.Cu" "F.Mask" "F.Paste")
			(net "SW_P12V_PVCCIN_CPU0_FLT")
		)
		(pad "2" smd circle
			(at 0.40005 0)
			(size 0 0)
			(layers "F.Cu" "F.Mask" "F.Paste")
			(net "GND")
		)
	)
	(footprint ""
		(layer "F.Cu")
		(at 439.49366 -106.38536 90)
		(property "Reference" "C2376"
			(at 0 0 90)
			(layer "F.SilkS")
			(hide yes)
			(effects
				(font
					(size 1.27 1.27)
				)
			)
		)
		(property "Value" ""
			(at 0 0 90)
			(layer "F.Fab")
			(effects
				(font
					(size 1.27 1.27)
				)
			)
		)
		(duplicate_pad_numbers_are_jumpers no)
		(fp_line
			(start 0.7874 -0.4064)
			(end 0.7874 0.4064)
			(stroke
				(width 0.1524)
				(type default)
			)
			(layer "F.SilkS")
		)
		(fp_line
			(start -0.7874 -0.4064)
			(end 0.7874 -0.4064)
			(stroke
				(width 0.1524)
				(type default)
			)
			(layer "F.SilkS")
		)
		(fp_line
			(start 0.7874 0.4064)
			(end -0.7874 0.4064)
			(stroke
				(width 0.1524)
				(type default)
			)
			(layer "F.SilkS")
		)
		(fp_line
			(start -0.7874 0.4064)
			(end -0.7874 -0.4064)
			(stroke
				(width 0.1524)
				(type default)
			)
			(layer "F.SilkS")
		)
		(fp_line
			(start -0.12065 -0.305054)
			(end -0.12065 -0.2794)
			(stroke
				(width 0.1)
				(type default)
			)
			(layer "F.Fab")
		)
		(fp_line
			(start -0.67945 -0.305054)
			(end -0.12065 -0.305054)
			(stroke
				(width 0.1)
				(type default)
			)
			(layer "F.Fab")
		)
		(fp_line
			(start 0.67945 -0.3048)
			(end 0.67945 0.3048)
			(stroke
				(width 0.1)
				(type default)
			)
			(layer "F.Fab")
		)
		(fp_line
			(start 0.12065 -0.3048)
			(end 0.67945 -0.3048)
			(stroke
				(width 0.1)
				(type default)
			)
			(layer "F.Fab")
		)
		(fp_line
			(start 0.12065 -0.2794)
			(end 0.12065 -0.3048)
			(stroke
				(width 0.1)
				(type default)
			)
			(layer "F.Fab")
		)
		(fp_line
			(start -0.12065 -0.2794)
			(end 0.12065 -0.2794)
			(stroke
				(width 0.1)
				(type default)
			)
			(layer "F.Fab")
		)
		(fp_line
			(start 0.120396 0.2794)
			(end -0.12065 0.2794)
			(stroke
				(width 0.1)
				(type default)
			)
			(layer "F.Fab")
		)
		(fp_line
			(start -0.12065 0.2794)
			(end -0.12065 0.3048)
			(stroke
				(width 0.1)
				(type default)
			)
			(layer "F.Fab")
		)
		(fp_line
			(start 0.67945 0.3048)
			(end 0.120396 0.3048)
			(stroke
				(width 0.1)
				(type default)
			)
			(layer "F.Fab")
		)
		(fp_line
			(start 0.120396 0.3048)
			(end 0.120396 0.2794)
			(stroke
				(width 0.1)
				(type default)
			)
			(layer "F.Fab")
		)
		(fp_line
			(start -0.12065 0.3048)
			(end -0.67945 0.3048)
			(stroke
				(width 0.1)
				(type default)
			)
			(layer "F.Fab")
		)
		(fp_line
			(start -0.67945 0.3048)
			(end -0.67945 -0.305054)
			(stroke
				(width 0.1)
				(type default)
			)
			(layer "F.Fab")
		)
		(pad "1" smd circle
			(at -0.40005 0 90)
			(size 0 0)
			(layers "F.Cu" "F.Mask" "F.Paste")
			(net "P3V3_AUX")
		)
		(pad "2" smd circle
			(at 0.40005 0 90)
			(size 0 0)
			(layers "F.Cu" "F.Mask" "F.Paste")
			(net "GND")
		)
	)
	(footprint ""
		(layer "F.Cu")
		(at 159.82188 -58.511948 180)
		(property "Reference" "R1700"
			(at 0 0 180)
			(layer "F.SilkS")
			(hide yes)
			(effects
				(font
					(size 1.27 1.27)
				)
			)
		)
		(property "Value" ""
			(at 0 0 180)
			(layer "F.Fab")
			(effects
				(font
					(size 1.27 1.27)
				)
			)
		)
		(duplicate_pad_numbers_are_jumpers no)
		(fp_line
			(start 0.7874 0.4064)
			(end -0.7874 0.4064)
			(stroke
				(width 0.1524)
				(type default)
			)
			(layer "F.SilkS")
		)
		(fp_line
			(start 0.7874 -0.4064)
			(end 0.7874 0.4064)
			(stroke
				(width 0.1524)
				(type default)
			)
			(layer "F.SilkS")
		)
		(fp_line
			(start -0.7874 0.4064)
			(end -0.7874 -0.4064)
			(stroke
				(width 0.1524)
				(type default)
			)
			(layer "F.SilkS")
		)
		(fp_line
			(start -0.7874 -0.4064)
			(end 0.7874 -0.4064)
			(stroke
				(width 0.1524)
				(type default)
			)
			(layer "F.SilkS")
		)
		(fp_line
			(start 0.67945 0.3048)
			(end 0.120396 0.3048)
			(stroke
				(width 0.1)
				(type default)
			)
			(layer "F.Fab")
		)
		(fp_line
			(start 0.67945 -0.3048)
			(end 0.67945 0.3048)
			(stroke
				(width 0.1)
				(type default)
			)
			(layer "F.Fab")
		)
		(fp_line
			(start 0.12065 -0.2794)
			(end 0.12065 -0.3048)
			(stroke
				(width 0.1)
				(type default)
			)
			(layer "F.Fab")
		)
		(fp_line
			(start 0.12065 -0.3048)
			(end 0.67945 -0.3048)
			(stroke
				(width 0.1)
				(type default)
			)
			(layer "F.Fab")
		)
		(fp_line
			(start 0.120396 0.3048)
			(end 0.120396 0.2794)
			(stroke
				(width 0.1)
				(type default)
			)
			(layer "F.Fab")
		)
		(fp_line
			(start 0.120396 0.2794)
			(end -0.12065 0.2794)
			(stroke
				(width 0.1)
				(type default)
			)
			(layer "F.Fab")
		)
		(fp_line
			(start -0.12065 0.3048)
			(end -0.67945 0.3048)
			(stroke
				(width 0.1)
				(type default)
			)
			(layer "F.Fab")
		)
		(fp_line
			(start -0.12065 0.2794)
			(end -0.12065 0.3048)
			(stroke
				(width 0.1)
				(type default)
			)
			(layer "F.Fab")
		)
		(fp_line
			(start -0.12065 -0.2794)
			(end 0.12065 -0.2794)
			(stroke
				(width 0.1)
				(type default)
			)
			(layer "F.Fab")
		)
		(fp_line
			(start -0.12065 -0.305054)
			(end -0.12065 -0.2794)
			(stroke
				(width 0.1)
				(type default)
			)
			(layer "F.Fab")
		)
		(fp_line
			(start -0.67945 0.3048)
			(end -0.67945 -0.305054)
			(stroke
				(width 0.1)
				(type default)
			)
			(layer "F.Fab")
		)
		(fp_line
			(start -0.67945 -0.305054)
			(end -0.12065 -0.305054)
			(stroke
				(width 0.1)
				(type default)
			)
			(layer "F.Fab")
		)
		(pad "1" smd circle
			(at -0.40005 0 180)
			(size 0 0)
			(layers "F.Cu" "F.Mask" "F.Paste")
			(net "P3V3_AUX")
		)
		(pad "2" smd circle
			(at 0.40005 0 180)
			(size 0 0)
			(layers "F.Cu" "F.Mask" "F.Paste")
			(net "SMB_PCIE_M2_0_EN")
		)
	)
	(footprint ""
		(layer "F.Cu")
		(at 325.860156 -251.76988)
		(property "Reference" "H25"
			(at -5.439156 -4.581398 0)
			(unlocked yes)
			(layer "F.SilkS")
			(effects
				(font
					(size 0.7874 0.5842)
					(thickness 0.1524)
				)
				(justify left)
			)
		)
		(property "Value" ""
			(at 0 0 0)
			(layer "F.Fab")
			(effects
				(font
					(size 1.27 1.27)
				)
			)
		)
		(duplicate_pad_numbers_are_jumpers no)
		(fp_circle
			(center 0 0)
			(end 2.5273 0)
			(stroke
				(width 0.1524)
				(type default)
			)
			(fill no)
			(layer "F.SilkS")
		)
		(fp_circle
			(center 0 0)
			(end 2.5273 0)
			(stroke
				(width 0.1524)
				(type default)
			)
			(fill no)
			(layer "B.SilkS")
		)
		(fp_circle
			(center 0 0)
			(end 2.5273 0)
			(stroke
				(width 0.1)
				(type default)
			)
			(fill no)
			(layer "B.Fab")
		)
		(fp_circle
			(center 0 0)
			(end 2.5273 0)
			(stroke
				(width 0.1)
				(type default)
			)
			(fill no)
			(layer "F.Fab")
		)
		(pad "" np_thru_hole circle
			(at 0 0)
			(size 3.429 3.429)
			(drill 3.429)
			(layers "*.Cu" "*.Mask")
			(clearance 0.381)
			(thermal_gap 0.381)
		)
	)
	(footprint ""
		(layer "F.Cu")
		(at 104.347264 -258.72694 90)
		(property "Reference" "C444"
			(at 0 0 90)
			(layer "F.SilkS")
			(hide yes)
			(effects
				(font
					(size 1.27 1.27)
				)
			)
		)
		(property "Value" ""
			(at 0 0 90)
			(layer "F.Fab")
			(effects
				(font
					(size 1.27 1.27)
				)
			)
		)
		(duplicate_pad_numbers_are_jumpers no)
		(fp_line
			(start 0.7874 -0.4064)
			(end 0.7874 0.4064)
			(stroke
				(width 0.1524)
				(type default)
			)
			(layer "F.SilkS")
		)
		(fp_line
			(start -0.7874 -0.4064)
			(end 0.7874 -0.4064)
			(stroke
				(width 0.1524)
				(type default)
			)
			(layer "F.SilkS")
		)
		(fp_line
			(start 0.7874 0.4064)
			(end -0.7874 0.4064)
			(stroke
				(width 0.1524)
				(type default)
			)
			(layer "F.SilkS")
		)
		(fp_line
			(start -0.7874 0.4064)
			(end -0.7874 -0.4064)
			(stroke
				(width 0.1524)
				(type default)
			)
			(layer "F.SilkS")
		)
		(fp_line
			(start -0.12065 -0.305054)
			(end -0.12065 -0.2794)
			(stroke
				(width 0.1)
				(type default)
			)
			(layer "F.Fab")
		)
		(fp_line
			(start -0.67945 -0.305054)
			(end -0.12065 -0.305054)
			(stroke
				(width 0.1)
				(type default)
			)
			(layer "F.Fab")
		)
		(fp_line
			(start 0.67945 -0.3048)
			(end 0.67945 0.3048)
			(stroke
				(width 0.1)
				(type default)
			)
			(layer "F.Fab")
		)
		(fp_line
			(start 0.12065 -0.3048)
			(end 0.67945 -0.3048)
			(stroke
				(width 0.1)
				(type default)
			)
			(layer "F.Fab")
		)
		(fp_line
			(start 0.12065 -0.2794)
			(end 0.12065 -0.3048)
			(stroke
				(width 0.1)
				(type default)
			)
			(layer "F.Fab")
		)
		(fp_line
			(start -0.12065 -0.2794)
			(end 0.12065 -0.2794)
			(stroke
				(width 0.1)
				(type default)
			)
			(layer "F.Fab")
		)
		(fp_line
			(start 0.120396 0.2794)
			(end -0.12065 0.2794)
			(stroke
				(width 0.1)
				(type default)
			)
			(layer "F.Fab")
		)
		(fp_line
			(start -0.12065 0.2794)
			(end -0.12065 0.3048)
			(stroke
				(width 0.1)
				(type default)
			)
			(layer "F.Fab")
		)
		(fp_line
			(start 0.67945 0.3048)
			(end 0.120396 0.3048)
			(stroke
				(width 0.1)
				(type default)
			)
			(layer "F.Fab")
		)
		(fp_line
			(start 0.120396 0.3048)
			(end 0.120396 0.2794)
			(stroke
				(width 0.1)
				(type default)
			)
			(layer "F.Fab")
		)
		(fp_line
			(start -0.12065 0.3048)
			(end -0.67945 0.3048)
			(stroke
				(width 0.1)
				(type default)
			)
			(layer "F.Fab")
		)
		(fp_line
			(start -0.67945 0.3048)
			(end -0.67945 -0.305054)
			(stroke
				(width 0.1)
				(type default)
			)
			(layer "F.Fab")
		)
		(pad "1" smd circle
			(at -0.40005 0 90)
			(size 0 0)
			(layers "F.Cu" "F.Mask" "F.Paste")
			(net "PVCCFA_EHV_CPU1")
		)
		(pad "2" smd circle
			(at 0.40005 0 90)
			(size 0 0)
			(layers "F.Cu" "F.Mask" "F.Paste")
			(net "GND")
		)
	)
	(footprint ""
		(layer "F.Cu")
		(at 94.899988 -22.29993)
		(property "Reference" "H101"
			(at -6.23824 -4.478528 0)
			(unlocked yes)
			(layer "F.SilkS")
			(effects
				(font
					(size 0.7874 0.5842)
					(thickness 0.1524)
				)
				(justify left)
			)
		)
		(property "Value" ""
			(at 0 0 0)
			(layer "F.Fab")
			(effects
				(font
					(size 1.27 1.27)
				)
			)
		)
		(duplicate_pad_numbers_are_jumpers no)
		(pad "1" thru_hole circle
			(at 0 0)
			(size 10.0076 10.0076)
			(drill 5.6134)
			(layers "*.Cu" "*.Mask")
			(remove_unused_layers no)
			(net "GND")
			(clearance -1.9431)
		)
	)
	(footprint ""
		(layer "F.Cu")
		(at 131.32308 -21.554948 90)
		(property "Reference" "R3254"
			(at 0 0 90)
			(layer "F.SilkS")
			(hide yes)
			(effects
				(font
					(size 1.27 1.27)
				)
			)
		)
		(property "Value" ""
			(at 0 0 90)
			(layer "F.Fab")
			(effects
				(font
					(size 1.27 1.27)
				)
			)
		)
		(duplicate_pad_numbers_are_jumpers no)
		(fp_line
			(start 0.7874 -0.4064)
			(end 0.7874 0.4064)
			(stroke
				(width 0.1524)
				(type default)
			)
			(layer "F.SilkS")
		)
		(fp_line
			(start -0.7874 -0.4064)
			(end 0.7874 -0.4064)
			(stroke
				(width 0.1524)
				(type default)
			)
			(layer "F.SilkS")
		)
		(fp_line
			(start 0.7874 0.4064)
			(end -0.7874 0.4064)
			(stroke
				(width 0.1524)
				(type default)
			)
			(layer "F.SilkS")
		)
		(fp_line
			(start -0.7874 0.4064)
			(end -0.7874 -0.4064)
			(stroke
				(width 0.1524)
				(type default)
			)
			(layer "F.SilkS")
		)
		(fp_line
			(start -0.12065 -0.305054)
			(end -0.12065 -0.2794)
			(stroke
				(width 0.1)
				(type default)
			)
			(layer "F.Fab")
		)
		(fp_line
			(start -0.67945 -0.305054)
			(end -0.12065 -0.305054)
			(stroke
				(width 0.1)
				(type default)
			)
			(layer "F.Fab")
		)
		(fp_line
			(start 0.67945 -0.3048)
			(end 0.67945 0.3048)
			(stroke
				(width 0.1)
				(type default)
			)
			(layer "F.Fab")
		)
		(fp_line
			(start 0.12065 -0.3048)
			(end 0.67945 -0.3048)
			(stroke
				(width 0.1)
				(type default)
			)
			(layer "F.Fab")
		)
		(fp_line
			(start 0.12065 -0.2794)
			(end 0.12065 -0.3048)
			(stroke
				(width 0.1)
				(type default)
			)
			(layer "F.Fab")
		)
		(fp_line
			(start -0.12065 -0.2794)
			(end 0.12065 -0.2794)
			(stroke
				(width 0.1)
				(type default)
			)
			(layer "F.Fab")
		)
		(fp_line
			(start 0.120396 0.2794)
			(end -0.12065 0.2794)
			(stroke
				(width 0.1)
				(type default)
			)
			(layer "F.Fab")
		)
		(fp_line
			(start -0.12065 0.2794)
			(end -0.12065 0.3048)
			(stroke
				(width 0.1)
				(type default)
			)
			(layer "F.Fab")
		)
		(fp_line
			(start 0.67945 0.3048)
			(end 0.120396 0.3048)
			(stroke
				(width 0.1)
				(type default)
			)
			(layer "F.Fab")
		)
		(fp_line
			(start 0.120396 0.3048)
			(end 0.120396 0.2794)
			(stroke
				(width 0.1)
				(type default)
			)
			(layer "F.Fab")
		)
		(fp_line
			(start -0.12065 0.3048)
			(end -0.67945 0.3048)
			(stroke
				(width 0.1)
				(type default)
			)
			(layer "F.Fab")
		)
		(fp_line
			(start -0.67945 0.3048)
			(end -0.67945 -0.305054)
			(stroke
				(width 0.1)
				(type default)
			)
			(layer "F.Fab")
		)
		(pad "1" smd circle
			(at -0.40005 0 90)
			(size 0 0)
			(layers "F.Cu" "F.Mask" "F.Paste")
			(net "TP_PCIE_HPM_TXP<3>")
		)
		(pad "2" smd circle
			(at 0.40005 0 90)
			(size 0 0)
			(layers "F.Cu" "F.Mask" "F.Paste")
			(net "LED_HDD_ACTIVITY_B_N")
		)
	)
	(footprint ""
		(layer "F.Cu")
		(at 129.159 -53.304948)
		(property "Reference" "R4631"
			(at 0 0 0)
			(layer "F.SilkS")
			(hide yes)
			(effects
				(font
					(size 1.27 1.27)
				)
			)
		)
		(property "Value" ""
			(at 0 0 0)
			(layer "F.Fab")
			(effects
				(font
					(size 1.27 1.27)
				)
			)
		)
		(duplicate_pad_numbers_are_jumpers no)
		(fp_line
			(start -0.7874 -0.4064)
			(end 0.7874 -0.4064)
			(stroke
				(width 0.1524)
				(type default)
			)
			(layer "F.SilkS")
		)
		(fp_line
			(start -0.7874 0.4064)
			(end -0.7874 -0.4064)
			(stroke
				(width 0.1524)
				(type default)
			)
			(layer "F.SilkS")
		)
		(fp_line
			(start 0.7874 -0.4064)
			(end 0.7874 0.4064)
			(stroke
				(width 0.1524)
				(type default)
			)
			(layer "F.SilkS")
		)
		(fp_line
			(start 0.7874 0.4064)
			(end -0.7874 0.4064)
			(stroke
				(width 0.1524)
				(type default)
			)
			(layer "F.SilkS")
		)
		(fp_line
			(start -0.67945 -0.305054)
			(end -0.12065 -0.305054)
			(stroke
				(width 0.1)
				(type default)
			)
			(layer "F.Fab")
		)
		(fp_line
			(start -0.67945 0.3048)
			(end -0.67945 -0.305054)
			(stroke
				(width 0.1)
				(type default)
			)
			(layer "F.Fab")
		)
		(fp_line
			(start -0.12065 -0.305054)
			(end -0.12065 -0.2794)
			(stroke
				(width 0.1)
				(type default)
			)
			(layer "F.Fab")
		)
		(fp_line
			(start -0.12065 -0.2794)
			(end 0.12065 -0.2794)
			(stroke
				(width 0.1)
				(type default)
			)
			(layer "F.Fab")
		)
		(fp_line
			(start -0.12065 0.2794)
			(end -0.12065 0.3048)
			(stroke
				(width 0.1)
				(type default)
			)
			(layer "F.Fab")
		)
		(fp_line
			(start -0.12065 0.3048)
			(end -0.67945 0.3048)
			(stroke
				(width 0.1)
				(type default)
			)
			(layer "F.Fab")
		)
		(fp_line
			(start 0.120396 0.2794)
			(end -0.12065 0.2794)
			(stroke
				(width 0.1)
				(type default)
			)
			(layer "F.Fab")
		)
		(fp_line
			(start 0.120396 0.3048)
			(end 0.120396 0.2794)
			(stroke
				(width 0.1)
				(type default)
			)
			(layer "F.Fab")
		)
		(fp_line
			(start 0.12065 -0.3048)
			(end 0.67945 -0.3048)
			(stroke
				(width 0.1)
				(type default)
			)
			(layer "F.Fab")
		)
		(fp_line
			(start 0.12065 -0.2794)
			(end 0.12065 -0.3048)
			(stroke
				(width 0.1)
				(type default)
			)
			(layer "F.Fab")
		)
		(fp_line
			(start 0.67945 -0.3048)
			(end 0.67945 0.3048)
			(stroke
				(width 0.1)
				(type default)
			)
			(layer "F.Fab")
		)
		(fp_line
			(start 0.67945 0.3048)
			(end 0.120396 0.3048)
			(stroke
				(width 0.1)
				(type default)
			)
			(layer "F.Fab")
		)
		(pad "1" smd circle
			(at -0.40005 0)
			(size 0 0)
			(layers "F.Cu" "F.Mask" "F.Paste")
			(net "JTAG_BMC_SW_TDI_R")
		)
		(pad "2" smd circle
			(at 0.40005 0)
			(size 0 0)
			(layers "F.Cu" "F.Mask" "F.Paste")
			(net "JTAG_BMC_SW_TDI")
		)
	)
	(footprint ""
		(layer "F.Cu")
		(at 437.425846 -387.527292 180)
		(property "Reference" "PC1845"
			(at 0 0 180)
			(layer "F.SilkS")
			(hide yes)
			(effects
				(font
					(size 1.27 1.27)
				)
			)
		)
		(property "Value" ""
			(at 0 0 180)
			(layer "F.Fab")
			(effects
				(font
					(size 1.27 1.27)
				)
			)
		)
		(duplicate_pad_numbers_are_jumpers no)
		(fp_line
			(start 2.750058 2.750058)
			(end 2.750058 0.9398)
			(stroke
				(width 0.1524)
				(type default)
			)
			(layer "F.SilkS")
		)
		(fp_line
			(start 2.750058 -0.9398)
			(end 2.750058 -2.750058)
			(stroke
				(width 0.1524)
				(type default)
			)
			(layer "F.SilkS")
		)
		(fp_line
			(start 2.750058 -2.750058)
			(end -1.988058 -2.750058)
			(stroke
				(width 0.1524)
				(type default)
			)
			(layer "F.SilkS")
		)
		(fp_line
			(start -1.988058 2.750058)
			(end 2.750058 2.750058)
			(stroke
				(width 0.1524)
				(type default)
			)
			(layer "F.SilkS")
		)
		(fp_line
			(start -1.988058 -2.750058)
			(end -2.750058 -1.988058)
			(stroke
				(width 0.1524)
				(type default)
			)
			(layer "F.SilkS")
		)
		(fp_line
			(start -2.750058 1.988058)
			(end -1.988058 2.750058)
			(stroke
				(width 0.1524)
				(type default)
			)
			(layer "F.SilkS")
		)
		(fp_line
			(start -2.750058 0.9398)
			(end -2.750058 1.988058)
			(stroke
				(width 0.1524)
				(type default)
			)
			(layer "F.SilkS")
		)
		(fp_line
			(start -2.750058 -1.988058)
			(end -2.750058 -0.9398)
			(stroke
				(width 0.1524)
				(type default)
			)
			(layer "F.SilkS")
		)
		(fp_line
			(start 2.750058 2.750058)
			(end 2.750058 -2.750058)
			(stroke
				(width 0.1)
				(type default)
			)
			(layer "F.Fab")
		)
		(fp_line
			(start 2.750058 -2.750058)
			(end -2.750058 -2.750058)
			(stroke
				(width 0.1)
				(type default)
			)
			(layer "F.Fab")
		)
		(fp_line
			(start -2.750058 2.750058)
			(end 2.750058 2.750058)
			(stroke
				(width 0.1)
				(type default)
			)
			(layer "F.Fab")
		)
		(fp_line
			(start -2.750058 -2.750058)
			(end -2.750058 2.750058)
			(stroke
				(width 0.1)
				(type default)
			)
			(layer "F.Fab")
		)
		(pad "1" smd rect
			(at -2.199894 0 270)
			(size 1.6002 3.0226)
			(layers "F.Cu" "F.Mask" "F.Paste")
			(net "P5V_AUX")
		)
		(pad "2" smd rect
			(at 2.199894 0 270)
			(size 1.6002 3.0226)
			(layers "F.Cu" "F.Mask" "F.Paste")
			(net "GND")
		)
	)
	(footprint ""
		(layer "F.Cu")
		(at 164.361114 -408.517344 -90)
		(property "Reference" "C1544"
			(at 0 0 270)
			(layer "F.SilkS")
			(hide yes)
			(effects
				(font
					(size 1.27 1.27)
				)
			)
		)
		(property "Value" ""
			(at 0 0 270)
			(layer "F.Fab")
			(effects
				(font
					(size 1.27 1.27)
				)
			)
		)
		(duplicate_pad_numbers_are_jumpers no)
		(fp_line
			(start -0.299974 0.150114)
			(end -0.299974 -0.150114)
			(stroke
				(width 0.1)
				(type default)
			)
			(layer "F.Fab")
		)
		(fp_line
			(start 0.299974 0.150114)
			(end -0.299974 0.150114)
			(stroke
				(width 0.1)
				(type default)
			)
			(layer "F.Fab")
		)
		(fp_line
			(start -0.299974 -0.150114)
			(end 0.299974 -0.150114)
			(stroke
				(width 0.1)
				(type default)
			)
			(layer "F.Fab")
		)
		(fp_line
			(start 0.299974 -0.150114)
			(end 0.299974 0.150114)
			(stroke
				(width 0.1)
				(type default)
			)
			(layer "F.Fab")
		)
		(pad "1" smd rect
			(at -0.2667 0 270)
			(size 0.3048 0.381)
			(layers "F.Cu" "F.Mask" "F.Paste")
			(net "P5E_CPU1_PE3_TX_C_DN<1>")
		)
		(pad "2" smd rect
			(at 0.2667 0 270)
			(size 0.3048 0.381)
			(layers "F.Cu" "F.Mask" "F.Paste")
			(net "P5E_CPU1_PE3_TX_DN<1>")
		)
	)
	(footprint ""
		(layer "F.Cu")
		(at 417.66744 -51.87696 90)
		(property "Reference" "R4681"
			(at 0 0 90)
			(layer "F.SilkS")
			(hide yes)
			(effects
				(font
					(size 1.27 1.27)
				)
			)
		)
		(property "Value" ""
			(at 0 0 90)
			(layer "F.Fab")
			(effects
				(font
					(size 1.27 1.27)
				)
			)
		)
		(duplicate_pad_numbers_are_jumpers no)
		(fp_line
			(start 0.7874 -0.4064)
			(end 0.7874 0.4064)
			(stroke
				(width 0.1524)
				(type default)
			)
			(layer "F.SilkS")
		)
		(fp_line
			(start -0.7874 -0.4064)
			(end 0.7874 -0.4064)
			(stroke
				(width 0.1524)
				(type default)
			)
			(layer "F.SilkS")
		)
		(fp_line
			(start 0.7874 0.4064)
			(end -0.7874 0.4064)
			(stroke
				(width 0.1524)
				(type default)
			)
			(layer "F.SilkS")
		)
		(fp_line
			(start -0.7874 0.4064)
			(end -0.7874 -0.4064)
			(stroke
				(width 0.1524)
				(type default)
			)
			(layer "F.SilkS")
		)
		(fp_line
			(start -0.12065 -0.305054)
			(end -0.12065 -0.2794)
			(stroke
				(width 0.1)
				(type default)
			)
			(layer "F.Fab")
		)
		(fp_line
			(start -0.67945 -0.305054)
			(end -0.12065 -0.305054)
			(stroke
				(width 0.1)
				(type default)
			)
			(layer "F.Fab")
		)
		(fp_line
			(start 0.67945 -0.3048)
			(end 0.67945 0.3048)
			(stroke
				(width 0.1)
				(type default)
			)
			(layer "F.Fab")
		)
		(fp_line
			(start 0.12065 -0.3048)
			(end 0.67945 -0.3048)
			(stroke
				(width 0.1)
				(type default)
			)
			(layer "F.Fab")
		)
		(fp_line
			(start 0.12065 -0.2794)
			(end 0.12065 -0.3048)
			(stroke
				(width 0.1)
				(type default)
			)
			(layer "F.Fab")
		)
		(fp_line
			(start -0.12065 -0.2794)
			(end 0.12065 -0.2794)
			(stroke
				(width 0.1)
				(type default)
			)
			(layer "F.Fab")
		)
		(fp_line
			(start 0.120396 0.2794)
			(end -0.12065 0.2794)
			(stroke
				(width 0.1)
				(type default)
			)
			(layer "F.Fab")
		)
		(fp_line
			(start -0.12065 0.2794)
			(end -0.12065 0.3048)
			(stroke
				(width 0.1)
				(type default)
			)
			(layer "F.Fab")
		)
		(fp_line
			(start 0.67945 0.3048)
			(end 0.120396 0.3048)
			(stroke
				(width 0.1)
				(type default)
			)
			(layer "F.Fab")
		)
		(fp_line
			(start 0.120396 0.3048)
			(end 0.120396 0.2794)
			(stroke
				(width 0.1)
				(type default)
			)
			(layer "F.Fab")
		)
		(fp_line
			(start -0.12065 0.3048)
			(end -0.67945 0.3048)
			(stroke
				(width 0.1)
				(type default)
			)
			(layer "F.Fab")
		)
		(fp_line
			(start -0.67945 0.3048)
			(end -0.67945 -0.305054)
			(stroke
				(width 0.1)
				(type default)
			)
			(layer "F.Fab")
		)
		(pad "1" smd circle
			(at -0.40005 0 90)
			(size 0 0)
			(layers "F.Cu" "F.Mask" "F.Paste")
			(net "PWRGD_P3V3_R1")
		)
		(pad "2" smd circle
			(at 0.40005 0 90)
			(size 0 0)
			(layers "F.Cu" "F.Mask" "F.Paste")
			(net "GND")
		)
	)
	(footprint ""
		(layer "F.Cu")
		(at 210.560412 -98.809048)
		(property "Reference" "R2219"
			(at 0 0 0)
			(layer "F.SilkS")
			(hide yes)
			(effects
				(font
					(size 1.27 1.27)
				)
			)
		)
		(property "Value" ""
			(at 0 0 0)
			(layer "F.Fab")
			(effects
				(font
					(size 1.27 1.27)
				)
			)
		)
		(duplicate_pad_numbers_are_jumpers no)
		(fp_line
			(start -0.7874 -0.4064)
			(end 0.7874 -0.4064)
			(stroke
				(width 0.1524)
				(type default)
			)
			(layer "F.SilkS")
		)
		(fp_line
			(start -0.7874 0.4064)
			(end -0.7874 -0.4064)
			(stroke
				(width 0.1524)
				(type default)
			)
			(layer "F.SilkS")
		)
		(fp_line
			(start 0.7874 -0.4064)
			(end 0.7874 0.4064)
			(stroke
				(width 0.1524)
				(type default)
			)
			(layer "F.SilkS")
		)
		(fp_line
			(start 0.7874 0.4064)
			(end -0.7874 0.4064)
			(stroke
				(width 0.1524)
				(type default)
			)
			(layer "F.SilkS")
		)
		(fp_line
			(start -0.67945 -0.305054)
			(end -0.12065 -0.305054)
			(stroke
				(width 0.1)
				(type default)
			)
			(layer "F.Fab")
		)
		(fp_line
			(start -0.67945 0.3048)
			(end -0.67945 -0.305054)
			(stroke
				(width 0.1)
				(type default)
			)
			(layer "F.Fab")
		)
		(fp_line
			(start -0.12065 -0.305054)
			(end -0.12065 -0.2794)
			(stroke
				(width 0.1)
				(type default)
			)
			(layer "F.Fab")
		)
		(fp_line
			(start -0.12065 -0.2794)
			(end 0.12065 -0.2794)
			(stroke
				(width 0.1)
				(type default)
			)
			(layer "F.Fab")
		)
		(fp_line
			(start -0.12065 0.2794)
			(end -0.12065 0.3048)
			(stroke
				(width 0.1)
				(type default)
			)
			(layer "F.Fab")
		)
		(fp_line
			(start -0.12065 0.3048)
			(end -0.67945 0.3048)
			(stroke
				(width 0.1)
				(type default)
			)
			(layer "F.Fab")
		)
		(fp_line
			(start 0.120396 0.2794)
			(end -0.12065 0.2794)
			(stroke
				(width 0.1)
				(type default)
			)
			(layer "F.Fab")
		)
		(fp_line
			(start 0.120396 0.3048)
			(end 0.120396 0.2794)
			(stroke
				(width 0.1)
				(type default)
			)
			(layer "F.Fab")
		)
		(fp_line
			(start 0.12065 -0.3048)
			(end 0.67945 -0.3048)
			(stroke
				(width 0.1)
				(type default)
			)
			(layer "F.Fab")
		)
		(fp_line
			(start 0.12065 -0.2794)
			(end 0.12065 -0.3048)
			(stroke
				(width 0.1)
				(type default)
			)
			(layer "F.Fab")
		)
		(fp_line
			(start 0.67945 -0.3048)
			(end 0.67945 0.3048)
			(stroke
				(width 0.1)
				(type default)
			)
			(layer "F.Fab")
		)
		(fp_line
			(start 0.67945 0.3048)
			(end 0.120396 0.3048)
			(stroke
				(width 0.1)
				(type default)
			)
			(layer "F.Fab")
		)
		(pad "1" smd circle
			(at -0.40005 0)
			(size 0 0)
			(layers "F.Cu" "F.Mask" "F.Paste")
			(net "P12V_AUX")
		)
		(pad "2" smd circle
			(at 0.40005 0)
			(size 0 0)
			(layers "F.Cu" "F.Mask" "F.Paste")
			(net "A_P12V_STBY_ADR_TRIGGER")
		)
	)
	(footprint ""
		(layer "F.Cu")
		(at 261.436612 -133.001512 180)
		(property "Reference" "R4497"
			(at 0 0 180)
			(layer "F.SilkS")
			(hide yes)
			(effects
				(font
					(size 1.27 1.27)
				)
			)
		)
		(property "Value" ""
			(at 0 0 180)
			(layer "F.Fab")
			(effects
				(font
					(size 1.27 1.27)
				)
			)
		)
		(duplicate_pad_numbers_are_jumpers no)
		(fp_line
			(start 0.7874 0.4064)
			(end -0.7874 0.4064)
			(stroke
				(width 0.1524)
				(type default)
			)
			(layer "F.SilkS")
		)
		(fp_line
			(start 0.7874 -0.4064)
			(end 0.7874 0.4064)
			(stroke
				(width 0.1524)
				(type default)
			)
			(layer "F.SilkS")
		)
		(fp_line
			(start -0.7874 0.4064)
			(end -0.7874 -0.4064)
			(stroke
				(width 0.1524)
				(type default)
			)
			(layer "F.SilkS")
		)
		(fp_line
			(start -0.7874 -0.4064)
			(end 0.7874 -0.4064)
			(stroke
				(width 0.1524)
				(type default)
			)
			(layer "F.SilkS")
		)
		(fp_line
			(start 0.67945 0.3048)
			(end 0.120396 0.3048)
			(stroke
				(width 0.1)
				(type default)
			)
			(layer "F.Fab")
		)
		(fp_line
			(start 0.67945 -0.3048)
			(end 0.67945 0.3048)
			(stroke
				(width 0.1)
				(type default)
			)
			(layer "F.Fab")
		)
		(fp_line
			(start 0.12065 -0.2794)
			(end 0.12065 -0.3048)
			(stroke
				(width 0.1)
				(type default)
			)
			(layer "F.Fab")
		)
		(fp_line
			(start 0.12065 -0.3048)
			(end 0.67945 -0.3048)
			(stroke
				(width 0.1)
				(type default)
			)
			(layer "F.Fab")
		)
		(fp_line
			(start 0.120396 0.3048)
			(end 0.120396 0.2794)
			(stroke
				(width 0.1)
				(type default)
			)
			(layer "F.Fab")
		)
		(fp_line
			(start 0.120396 0.2794)
			(end -0.12065 0.2794)
			(stroke
				(width 0.1)
				(type default)
			)
			(layer "F.Fab")
		)
		(fp_line
			(start -0.12065 0.3048)
			(end -0.67945 0.3048)
			(stroke
				(width 0.1)
				(type default)
			)
			(layer "F.Fab")
		)
		(fp_line
			(start -0.12065 0.2794)
			(end -0.12065 0.3048)
			(stroke
				(width 0.1)
				(type default)
			)
			(layer "F.Fab")
		)
		(fp_line
			(start -0.12065 -0.2794)
			(end 0.12065 -0.2794)
			(stroke
				(width 0.1)
				(type default)
			)
			(layer "F.Fab")
		)
		(fp_line
			(start -0.12065 -0.305054)
			(end -0.12065 -0.2794)
			(stroke
				(width 0.1)
				(type default)
			)
			(layer "F.Fab")
		)
		(fp_line
			(start -0.67945 0.3048)
			(end -0.67945 -0.305054)
			(stroke
				(width 0.1)
				(type default)
			)
			(layer "F.Fab")
		)
		(fp_line
			(start -0.67945 -0.305054)
			(end -0.12065 -0.305054)
			(stroke
				(width 0.1)
				(type default)
			)
			(layer "F.Fab")
		)
		(pad "1" smd circle
			(at -0.40005 0 180)
			(size 0 0)
			(layers "F.Cu" "F.Mask" "F.Paste")
			(net "SMB_HOST_CLK_BUF_ISO_3V3AUX_SDA")
		)
		(pad "2" smd circle
			(at 0.40005 0 180)
			(size 0 0)
			(layers "F.Cu" "F.Mask" "F.Paste")
			(net "SMB_HOST_DB2000_3V3AUX_SDA")
		)
	)
	(footprint ""
		(layer "F.Cu")
		(at 442.70549 -368.767614)
		(property "Reference" "C1227"
			(at 0 0 0)
			(layer "F.SilkS")
			(hide yes)
			(effects
				(font
					(size 1.27 1.27)
				)
			)
		)
		(property "Value" ""
			(at 0 0 0)
			(layer "F.Fab")
			(effects
				(font
					(size 1.27 1.27)
				)
			)
		)
		(duplicate_pad_numbers_are_jumpers no)
		(fp_line
			(start -0.7874 -0.4064)
			(end 0.7874 -0.4064)
			(stroke
				(width 0.1524)
				(type default)
			)
			(layer "F.SilkS")
		)
		(fp_line
			(start -0.7874 0.4064)
			(end -0.7874 -0.4064)
			(stroke
				(width 0.1524)
				(type default)
			)
			(layer "F.SilkS")
		)
		(fp_line
			(start 0.7874 -0.4064)
			(end 0.7874 0.4064)
			(stroke
				(width 0.1524)
				(type default)
			)
			(layer "F.SilkS")
		)
		(fp_line
			(start 0.7874 0.4064)
			(end -0.7874 0.4064)
			(stroke
				(width 0.1524)
				(type default)
			)
			(layer "F.SilkS")
		)
		(fp_line
			(start -0.67945 -0.305054)
			(end -0.12065 -0.305054)
			(stroke
				(width 0.1)
				(type default)
			)
			(layer "F.Fab")
		)
		(fp_line
			(start -0.67945 0.3048)
			(end -0.67945 -0.305054)
			(stroke
				(width 0.1)
				(type default)
			)
			(layer "F.Fab")
		)
		(fp_line
			(start -0.12065 -0.305054)
			(end -0.12065 -0.2794)
			(stroke
				(width 0.1)
				(type default)
			)
			(layer "F.Fab")
		)
		(fp_line
			(start -0.12065 -0.2794)
			(end 0.12065 -0.2794)
			(stroke
				(width 0.1)
				(type default)
			)
			(layer "F.Fab")
		)
		(fp_line
			(start -0.12065 0.2794)
			(end -0.12065 0.3048)
			(stroke
				(width 0.1)
				(type default)
			)
			(layer "F.Fab")
		)
		(fp_line
			(start -0.12065 0.3048)
			(end -0.67945 0.3048)
			(stroke
				(width 0.1)
				(type default)
			)
			(layer "F.Fab")
		)
		(fp_line
			(start 0.120396 0.2794)
			(end -0.12065 0.2794)
			(stroke
				(width 0.1)
				(type default)
			)
			(layer "F.Fab")
		)
		(fp_line
			(start 0.120396 0.3048)
			(end 0.120396 0.2794)
			(stroke
				(width 0.1)
				(type default)
			)
			(layer "F.Fab")
		)
		(fp_line
			(start 0.12065 -0.3048)
			(end 0.67945 -0.3048)
			(stroke
				(width 0.1)
				(type default)
			)
			(layer "F.Fab")
		)
		(fp_line
			(start 0.12065 -0.2794)
			(end 0.12065 -0.3048)
			(stroke
				(width 0.1)
				(type default)
			)
			(layer "F.Fab")
		)
		(fp_line
			(start 0.67945 -0.3048)
			(end 0.67945 0.3048)
			(stroke
				(width 0.1)
				(type default)
			)
			(layer "F.Fab")
		)
		(fp_line
			(start 0.67945 0.3048)
			(end 0.120396 0.3048)
			(stroke
				(width 0.1)
				(type default)
			)
			(layer "F.Fab")
		)
		(pad "1" smd circle
			(at -0.40005 0)
			(size 0 0)
			(layers "F.Cu" "F.Mask" "F.Paste")
			(net "P5V")
		)
		(pad "2" smd circle
			(at 0.40005 0)
			(size 0 0)
			(layers "F.Cu" "F.Mask" "F.Paste")
			(net "GND")
		)
	)
	(footprint ""
		(layer "F.Cu")
		(at 188.28258 -29.758386 -90)
		(property "Reference" "PR4003"
			(at 0 0 270)
			(layer "F.SilkS")
			(hide yes)
			(effects
				(font
					(size 1.27 1.27)
				)
			)
		)
		(property "Value" ""
			(at 0 0 270)
			(layer "F.Fab")
			(effects
				(font
					(size 1.27 1.27)
				)
			)
		)
		(duplicate_pad_numbers_are_jumpers no)
		(fp_line
			(start -0.7874 0.4064)
			(end -0.7874 -0.4064)
			(stroke
				(width 0.1524)
				(type default)
			)
			(layer "F.SilkS")
		)
		(fp_line
			(start 0.7874 0.4064)
			(end -0.7874 0.4064)
			(stroke
				(width 0.1524)
				(type default)
			)
			(layer "F.SilkS")
		)
		(fp_line
			(start -0.7874 -0.4064)
			(end 0.7874 -0.4064)
			(stroke
				(width 0.1524)
				(type default)
			)
			(layer "F.SilkS")
		)
		(fp_line
			(start 0.7874 -0.4064)
			(end 0.7874 0.4064)
			(stroke
				(width 0.1524)
				(type default)
			)
			(layer "F.SilkS")
		)
		(fp_line
			(start -0.67945 0.3048)
			(end -0.67945 -0.305054)
			(stroke
				(width 0.1)
				(type default)
			)
			(layer "F.Fab")
		)
		(fp_line
			(start -0.12065 0.3048)
			(end -0.67945 0.3048)
			(stroke
				(width 0.1)
				(type default)
			)
			(layer "F.Fab")
		)
		(fp_line
			(start 0.120396 0.3048)
			(end 0.120396 0.2794)
			(stroke
				(width 0.1)
				(type default)
			)
			(layer "F.Fab")
		)
		(fp_line
			(start 0.67945 0.3048)
			(end 0.120396 0.3048)
			(stroke
				(width 0.1)
				(type default)
			)
			(layer "F.Fab")
		)
		(fp_line
			(start -0.12065 0.2794)
			(end -0.12065 0.3048)
			(stroke
				(width 0.1)
				(type default)
			)
			(layer "F.Fab")
		)
		(fp_line
			(start 0.120396 0.2794)
			(end -0.12065 0.2794)
			(stroke
				(width 0.1)
				(type default)
			)
			(layer "F.Fab")
		)
		(fp_line
			(start -0.12065 -0.2794)
			(end 0.12065 -0.2794)
			(stroke
				(width 0.1)
				(type default)
			)
			(layer "F.Fab")
		)
		(fp_line
			(start 0.12065 -0.2794)
			(end 0.12065 -0.3048)
			(stroke
				(width 0.1)
				(type default)
			)
			(layer "F.Fab")
		)
		(fp_line
			(start 0.12065 -0.3048)
			(end 0.67945 -0.3048)
			(stroke
				(width 0.1)
				(type default)
			)
			(layer "F.Fab")
		)
		(fp_line
			(start 0.67945 -0.3048)
			(end 0.67945 0.3048)
			(stroke
				(width 0.1)
				(type default)
			)
			(layer "F.Fab")
		)
		(fp_line
			(start -0.67945 -0.305054)
			(end -0.12065 -0.305054)
			(stroke
				(width 0.1)
				(type default)
			)
			(layer "F.Fab")
		)
		(fp_line
			(start -0.12065 -0.305054)
			(end -0.12065 -0.2794)
			(stroke
				(width 0.1)
				(type default)
			)
			(layer "F.Fab")
		)
		(pad "1" smd circle
			(at -0.40005 0 270)
			(size 0 0)
			(layers "F.Cu" "F.Mask" "F.Paste")
			(net "P12V_AUX")
		)
		(pad "2" smd circle
			(at 0.40005 0 270)
			(size 0 0)
			(layers "F.Cu" "F.Mask" "F.Paste")
			(net "P12V_SCM_VCC")
		)
	)
	(footprint ""
		(layer "F.Cu")
		(at 105.315004 -247.715278 90)
		(property "Reference" "C222"
			(at 0 0 90)
			(layer "F.SilkS")
			(hide yes)
			(effects
				(font
					(size 1.27 1.27)
				)
			)
		)
		(property "Value" ""
			(at 0 0 90)
			(layer "F.Fab")
			(effects
				(font
					(size 1.27 1.27)
				)
			)
		)
		(duplicate_pad_numbers_are_jumpers no)
		(fp_line
			(start 0.7874 -0.4064)
			(end 0.7874 0.4064)
			(stroke
				(width 0.1524)
				(type default)
			)
			(layer "F.SilkS")
		)
		(fp_line
			(start -0.7874 -0.4064)
			(end 0.7874 -0.4064)
			(stroke
				(width 0.1524)
				(type default)
			)
			(layer "F.SilkS")
		)
		(fp_line
			(start 0.7874 0.4064)
			(end -0.7874 0.4064)
			(stroke
				(width 0.1524)
				(type default)
			)
			(layer "F.SilkS")
		)
		(fp_line
			(start -0.7874 0.4064)
			(end -0.7874 -0.4064)
			(stroke
				(width 0.1524)
				(type default)
			)
			(layer "F.SilkS")
		)
		(fp_line
			(start -0.12065 -0.305054)
			(end -0.12065 -0.2794)
			(stroke
				(width 0.1)
				(type default)
			)
			(layer "F.Fab")
		)
		(fp_line
			(start -0.67945 -0.305054)
			(end -0.12065 -0.305054)
			(stroke
				(width 0.1)
				(type default)
			)
			(layer "F.Fab")
		)
		(fp_line
			(start 0.67945 -0.3048)
			(end 0.67945 0.3048)
			(stroke
				(width 0.1)
				(type default)
			)
			(layer "F.Fab")
		)
		(fp_line
			(start 0.12065 -0.3048)
			(end 0.67945 -0.3048)
			(stroke
				(width 0.1)
				(type default)
			)
			(layer "F.Fab")
		)
		(fp_line
			(start 0.12065 -0.2794)
			(end 0.12065 -0.3048)
			(stroke
				(width 0.1)
				(type default)
			)
			(layer "F.Fab")
		)
		(fp_line
			(start -0.12065 -0.2794)
			(end 0.12065 -0.2794)
			(stroke
				(width 0.1)
				(type default)
			)
			(layer "F.Fab")
		)
		(fp_line
			(start 0.120396 0.2794)
			(end -0.12065 0.2794)
			(stroke
				(width 0.1)
				(type default)
			)
			(layer "F.Fab")
		)
		(fp_line
			(start -0.12065 0.2794)
			(end -0.12065 0.3048)
			(stroke
				(width 0.1)
				(type default)
			)
			(layer "F.Fab")
		)
		(fp_line
			(start 0.67945 0.3048)
			(end 0.120396 0.3048)
			(stroke
				(width 0.1)
				(type default)
			)
			(layer "F.Fab")
		)
		(fp_line
			(start 0.120396 0.3048)
			(end 0.120396 0.2794)
			(stroke
				(width 0.1)
				(type default)
			)
			(layer "F.Fab")
		)
		(fp_line
			(start -0.12065 0.3048)
			(end -0.67945 0.3048)
			(stroke
				(width 0.1)
				(type default)
			)
			(layer "F.Fab")
		)
		(fp_line
			(start -0.67945 0.3048)
			(end -0.67945 -0.305054)
			(stroke
				(width 0.1)
				(type default)
			)
			(layer "F.Fab")
		)
		(pad "1" smd circle
			(at -0.40005 0 90)
			(size 0 0)
			(layers "F.Cu" "F.Mask" "F.Paste")
			(net "PVCCIN_CPU1")
		)
		(pad "2" smd circle
			(at 0.40005 0 90)
			(size 0 0)
			(layers "F.Cu" "F.Mask" "F.Paste")
			(net "GND")
		)
	)
	(footprint ""
		(layer "F.Cu")
		(at 435.17312 -43.262804 180)
		(property "Reference" "R2133"
			(at 0 0 180)
			(layer "F.SilkS")
			(hide yes)
			(effects
				(font
					(size 1.27 1.27)
				)
			)
		)
		(property "Value" ""
			(at 0 0 180)
			(layer "F.Fab")
			(effects
				(font
					(size 1.27 1.27)
				)
			)
		)
		(duplicate_pad_numbers_are_jumpers no)
		(fp_line
			(start 0.7874 0.4064)
			(end -0.7874 0.4064)
			(stroke
				(width 0.1524)
				(type default)
			)
			(layer "F.SilkS")
		)
		(fp_line
			(start 0.7874 -0.4064)
			(end 0.7874 0.4064)
			(stroke
				(width 0.1524)
				(type default)
			)
			(layer "F.SilkS")
		)
		(fp_line
			(start -0.7874 0.4064)
			(end -0.7874 -0.4064)
			(stroke
				(width 0.1524)
				(type default)
			)
			(layer "F.SilkS")
		)
		(fp_line
			(start -0.7874 -0.4064)
			(end 0.7874 -0.4064)
			(stroke
				(width 0.1524)
				(type default)
			)
			(layer "F.SilkS")
		)
		(fp_line
			(start 0.67945 0.3048)
			(end 0.120396 0.3048)
			(stroke
				(width 0.1)
				(type default)
			)
			(layer "F.Fab")
		)
		(fp_line
			(start 0.67945 -0.3048)
			(end 0.67945 0.3048)
			(stroke
				(width 0.1)
				(type default)
			)
			(layer "F.Fab")
		)
		(fp_line
			(start 0.12065 -0.2794)
			(end 0.12065 -0.3048)
			(stroke
				(width 0.1)
				(type default)
			)
			(layer "F.Fab")
		)
		(fp_line
			(start 0.12065 -0.3048)
			(end 0.67945 -0.3048)
			(stroke
				(width 0.1)
				(type default)
			)
			(layer "F.Fab")
		)
		(fp_line
			(start 0.120396 0.3048)
			(end 0.120396 0.2794)
			(stroke
				(width 0.1)
				(type default)
			)
			(layer "F.Fab")
		)
		(fp_line
			(start 0.120396 0.2794)
			(end -0.12065 0.2794)
			(stroke
				(width 0.1)
				(type default)
			)
			(layer "F.Fab")
		)
		(fp_line
			(start -0.12065 0.3048)
			(end -0.67945 0.3048)
			(stroke
				(width 0.1)
				(type default)
			)
			(layer "F.Fab")
		)
		(fp_line
			(start -0.12065 0.2794)
			(end -0.12065 0.3048)
			(stroke
				(width 0.1)
				(type default)
			)
			(layer "F.Fab")
		)
		(fp_line
			(start -0.12065 -0.2794)
			(end 0.12065 -0.2794)
			(stroke
				(width 0.1)
				(type default)
			)
			(layer "F.Fab")
		)
		(fp_line
			(start -0.12065 -0.305054)
			(end -0.12065 -0.2794)
			(stroke
				(width 0.1)
				(type default)
			)
			(layer "F.Fab")
		)
		(fp_line
			(start -0.67945 0.3048)
			(end -0.67945 -0.305054)
			(stroke
				(width 0.1)
				(type default)
			)
			(layer "F.Fab")
		)
		(fp_line
			(start -0.67945 -0.305054)
			(end -0.12065 -0.305054)
			(stroke
				(width 0.1)
				(type default)
			)
			(layer "F.Fab")
		)
		(pad "1" smd circle
			(at -0.40005 0 180)
			(size 0 0)
			(layers "F.Cu" "F.Mask" "F.Paste")
			(net "P3V3_AUX")
		)
		(pad "2" smd circle
			(at 0.40005 0 180)
			(size 0 0)
			(layers "F.Cu" "F.Mask" "F.Paste")
			(net "PU_ESPI_ENABLE_STRAP")
		)
	)
	(footprint ""
		(layer "F.Cu")
		(at 80.381602 -74.901552 -90)
		(property "Reference" "R3093"
			(at 0 0 270)
			(layer "F.SilkS")
			(hide yes)
			(effects
				(font
					(size 1.27 1.27)
				)
			)
		)
		(property "Value" ""
			(at 0 0 270)
			(layer "F.Fab")
			(effects
				(font
					(size 1.27 1.27)
				)
			)
		)
		(duplicate_pad_numbers_are_jumpers no)
		(fp_line
			(start -0.7874 0.4064)
			(end -0.7874 -0.4064)
			(stroke
				(width 0.1524)
				(type default)
			)
			(layer "F.SilkS")
		)
		(fp_line
			(start 0.7874 0.4064)
			(end -0.7874 0.4064)
			(stroke
				(width 0.1524)
				(type default)
			)
			(layer "F.SilkS")
		)
		(fp_line
			(start -0.7874 -0.4064)
			(end 0.7874 -0.4064)
			(stroke
				(width 0.1524)
				(type default)
			)
			(layer "F.SilkS")
		)
		(fp_line
			(start 0.7874 -0.4064)
			(end 0.7874 0.4064)
			(stroke
				(width 0.1524)
				(type default)
			)
			(layer "F.SilkS")
		)
		(fp_line
			(start -0.67945 0.3048)
			(end -0.67945 -0.305054)
			(stroke
				(width 0.1)
				(type default)
			)
			(layer "F.Fab")
		)
		(fp_line
			(start -0.12065 0.3048)
			(end -0.67945 0.3048)
			(stroke
				(width 0.1)
				(type default)
			)
			(layer "F.Fab")
		)
		(fp_line
			(start 0.120396 0.3048)
			(end 0.120396 0.2794)
			(stroke
				(width 0.1)
				(type default)
			)
			(layer "F.Fab")
		)
		(fp_line
			(start 0.67945 0.3048)
			(end 0.120396 0.3048)
			(stroke
				(width 0.1)
				(type default)
			)
			(layer "F.Fab")
		)
		(fp_line
			(start -0.12065 0.2794)
			(end -0.12065 0.3048)
			(stroke
				(width 0.1)
				(type default)
			)
			(layer "F.Fab")
		)
		(fp_line
			(start 0.120396 0.2794)
			(end -0.12065 0.2794)
			(stroke
				(width 0.1)
				(type default)
			)
			(layer "F.Fab")
		)
		(fp_line
			(start -0.12065 -0.2794)
			(end 0.12065 -0.2794)
			(stroke
				(width 0.1)
				(type default)
			)
			(layer "F.Fab")
		)
		(fp_line
			(start 0.12065 -0.2794)
			(end 0.12065 -0.3048)
			(stroke
				(width 0.1)
				(type default)
			)
			(layer "F.Fab")
		)
		(fp_line
			(start 0.12065 -0.3048)
			(end 0.67945 -0.3048)
			(stroke
				(width 0.1)
				(type default)
			)
			(layer "F.Fab")
		)
		(fp_line
			(start 0.67945 -0.3048)
			(end 0.67945 0.3048)
			(stroke
				(width 0.1)
				(type default)
			)
			(layer "F.Fab")
		)
		(fp_line
			(start -0.67945 -0.305054)
			(end -0.12065 -0.305054)
			(stroke
				(width 0.1)
				(type default)
			)
			(layer "F.Fab")
		)
		(fp_line
			(start -0.12065 -0.305054)
			(end -0.12065 -0.2794)
			(stroke
				(width 0.1)
				(type default)
			)
			(layer "F.Fab")
		)
		(pad "1" smd circle
			(at -0.40005 0 270)
			(size 0 0)
			(layers "F.Cu" "F.Mask" "F.Paste")
			(net "LED_PWRGD_PVCCD_HV_CPU1")
		)
		(pad "2" smd circle
			(at 0.40005 0 270)
			(size 0 0)
			(layers "F.Cu" "F.Mask" "F.Paste")
			(net "P3V3_AUX")
		)
	)
	(footprint ""
		(layer "F.Cu")
		(at 159.267144 -53.867304 180)
		(property "Reference" "R3574"
			(at 0 0 180)
			(layer "F.SilkS")
			(hide yes)
			(effects
				(font
					(size 1.27 1.27)
				)
			)
		)
		(property "Value" ""
			(at 0 0 180)
			(layer "F.Fab")
			(effects
				(font
					(size 1.27 1.27)
				)
			)
		)
		(duplicate_pad_numbers_are_jumpers no)
		(fp_line
			(start 0.7874 0.4064)
			(end -0.7874 0.4064)
			(stroke
				(width 0.1524)
				(type default)
			)
			(layer "F.SilkS")
		)
		(fp_line
			(start 0.7874 -0.4064)
			(end 0.7874 0.4064)
			(stroke
				(width 0.1524)
				(type default)
			)
			(layer "F.SilkS")
		)
		(fp_line
			(start -0.7874 0.4064)
			(end -0.7874 -0.4064)
			(stroke
				(width 0.1524)
				(type default)
			)
			(layer "F.SilkS")
		)
		(fp_line
			(start -0.7874 -0.4064)
			(end 0.7874 -0.4064)
			(stroke
				(width 0.1524)
				(type default)
			)
			(layer "F.SilkS")
		)
		(fp_line
			(start 0.67945 0.3048)
			(end 0.120396 0.3048)
			(stroke
				(width 0.1)
				(type default)
			)
			(layer "F.Fab")
		)
		(fp_line
			(start 0.67945 -0.3048)
			(end 0.67945 0.3048)
			(stroke
				(width 0.1)
				(type default)
			)
			(layer "F.Fab")
		)
		(fp_line
			(start 0.12065 -0.2794)
			(end 0.12065 -0.3048)
			(stroke
				(width 0.1)
				(type default)
			)
			(layer "F.Fab")
		)
		(fp_line
			(start 0.12065 -0.3048)
			(end 0.67945 -0.3048)
			(stroke
				(width 0.1)
				(type default)
			)
			(layer "F.Fab")
		)
		(fp_line
			(start 0.120396 0.3048)
			(end 0.120396 0.2794)
			(stroke
				(width 0.1)
				(type default)
			)
			(layer "F.Fab")
		)
		(fp_line
			(start 0.120396 0.2794)
			(end -0.12065 0.2794)
			(stroke
				(width 0.1)
				(type default)
			)
			(layer "F.Fab")
		)
		(fp_line
			(start -0.12065 0.3048)
			(end -0.67945 0.3048)
			(stroke
				(width 0.1)
				(type default)
			)
			(layer "F.Fab")
		)
		(fp_line
			(start -0.12065 0.2794)
			(end -0.12065 0.3048)
			(stroke
				(width 0.1)
				(type default)
			)
			(layer "F.Fab")
		)
		(fp_line
			(start -0.12065 -0.2794)
			(end 0.12065 -0.2794)
			(stroke
				(width 0.1)
				(type default)
			)
			(layer "F.Fab")
		)
		(fp_line
			(start -0.12065 -0.305054)
			(end -0.12065 -0.2794)
			(stroke
				(width 0.1)
				(type default)
			)
			(layer "F.Fab")
		)
		(fp_line
			(start -0.67945 0.3048)
			(end -0.67945 -0.305054)
			(stroke
				(width 0.1)
				(type default)
			)
			(layer "F.Fab")
		)
		(fp_line
			(start -0.67945 -0.305054)
			(end -0.12065 -0.305054)
			(stroke
				(width 0.1)
				(type default)
			)
			(layer "F.Fab")
		)
		(pad "1" smd circle
			(at -0.40005 0 180)
			(size 0 0)
			(layers "F.Cu" "F.Mask" "F.Paste")
			(net "P3V3")
		)
		(pad "2" smd circle
			(at 0.40005 0 180)
			(size 0 0)
			(layers "F.Cu" "F.Mask" "F.Paste")
			(net "VSENSE_P12V_INA230_4_INP")
		)
	)
	(footprint ""
		(layer "F.Cu")
		(at 349.523304 -336.192368 90)
		(property "Reference" "PC292"
			(at 0 0 90)
			(layer "F.SilkS")
			(hide yes)
			(effects
				(font
					(size 1.27 1.27)
				)
			)
		)
		(property "Value" ""
			(at 0 0 90)
			(layer "F.Fab")
			(effects
				(font
					(size 1.27 1.27)
				)
			)
		)
		(duplicate_pad_numbers_are_jumpers no)
		(fp_line
			(start 0.7874 -0.4064)
			(end 0.7874 0.4064)
			(stroke
				(width 0.1524)
				(type default)
			)
			(layer "F.SilkS")
		)
		(fp_line
			(start -0.7874 -0.4064)
			(end 0.7874 -0.4064)
			(stroke
				(width 0.1524)
				(type default)
			)
			(layer "F.SilkS")
		)
		(fp_line
			(start 0.7874 0.4064)
			(end -0.7874 0.4064)
			(stroke
				(width 0.1524)
				(type default)
			)
			(layer "F.SilkS")
		)
		(fp_line
			(start -0.7874 0.4064)
			(end -0.7874 -0.4064)
			(stroke
				(width 0.1524)
				(type default)
			)
			(layer "F.SilkS")
		)
		(fp_line
			(start -0.12065 -0.305054)
			(end -0.12065 -0.2794)
			(stroke
				(width 0.1)
				(type default)
			)
			(layer "F.Fab")
		)
		(fp_line
			(start -0.67945 -0.305054)
			(end -0.12065 -0.305054)
			(stroke
				(width 0.1)
				(type default)
			)
			(layer "F.Fab")
		)
		(fp_line
			(start 0.67945 -0.3048)
			(end 0.67945 0.3048)
			(stroke
				(width 0.1)
				(type default)
			)
			(layer "F.Fab")
		)
		(fp_line
			(start 0.12065 -0.3048)
			(end 0.67945 -0.3048)
			(stroke
				(width 0.1)
				(type default)
			)
			(layer "F.Fab")
		)
		(fp_line
			(start 0.12065 -0.2794)
			(end 0.12065 -0.3048)
			(stroke
				(width 0.1)
				(type default)
			)
			(layer "F.Fab")
		)
		(fp_line
			(start -0.12065 -0.2794)
			(end 0.12065 -0.2794)
			(stroke
				(width 0.1)
				(type default)
			)
			(layer "F.Fab")
		)
		(fp_line
			(start 0.120396 0.2794)
			(end -0.12065 0.2794)
			(stroke
				(width 0.1)
				(type default)
			)
			(layer "F.Fab")
		)
		(fp_line
			(start -0.12065 0.2794)
			(end -0.12065 0.3048)
			(stroke
				(width 0.1)
				(type default)
			)
			(layer "F.Fab")
		)
		(fp_line
			(start 0.67945 0.3048)
			(end 0.120396 0.3048)
			(stroke
				(width 0.1)
				(type default)
			)
			(layer "F.Fab")
		)
		(fp_line
			(start 0.120396 0.3048)
			(end 0.120396 0.2794)
			(stroke
				(width 0.1)
				(type default)
			)
			(layer "F.Fab")
		)
		(fp_line
			(start -0.12065 0.3048)
			(end -0.67945 0.3048)
			(stroke
				(width 0.1)
				(type default)
			)
			(layer "F.Fab")
		)
		(fp_line
			(start -0.67945 0.3048)
			(end -0.67945 -0.305054)
			(stroke
				(width 0.1)
				(type default)
			)
			(layer "F.Fab")
		)
		(pad "1" smd circle
			(at -0.40005 0 90)
			(size 0 0)
			(layers "F.Cu" "F.Mask" "F.Paste")
			(net "PVCCIN_CPU0_VDD2")
		)
		(pad "2" smd circle
			(at 0.40005 0 90)
			(size 0 0)
			(layers "F.Cu" "F.Mask" "F.Paste")
			(net "GND")
		)
	)
	(footprint ""
		(layer "F.Cu")
		(at 307.899308 -30.255718 -90)
		(property "Reference" "R1307"
			(at 0 0 270)
			(layer "F.SilkS")
			(hide yes)
			(effects
				(font
					(size 1.27 1.27)
				)
			)
		)
		(property "Value" ""
			(at 0 0 270)
			(layer "F.Fab")
			(effects
				(font
					(size 1.27 1.27)
				)
			)
		)
		(duplicate_pad_numbers_are_jumpers no)
		(fp_line
			(start -0.7874 0.4064)
			(end -0.7874 -0.4064)
			(stroke
				(width 0.1524)
				(type default)
			)
			(layer "F.SilkS")
		)
		(fp_line
			(start 0.7874 0.4064)
			(end -0.7874 0.4064)
			(stroke
				(width 0.1524)
				(type default)
			)
			(layer "F.SilkS")
		)
		(fp_line
			(start -0.7874 -0.4064)
			(end 0.7874 -0.4064)
			(stroke
				(width 0.1524)
				(type default)
			)
			(layer "F.SilkS")
		)
		(fp_line
			(start 0.7874 -0.4064)
			(end 0.7874 0.4064)
			(stroke
				(width 0.1524)
				(type default)
			)
			(layer "F.SilkS")
		)
		(fp_line
			(start -0.67945 0.3048)
			(end -0.67945 -0.305054)
			(stroke
				(width 0.1)
				(type default)
			)
			(layer "F.Fab")
		)
		(fp_line
			(start -0.12065 0.3048)
			(end -0.67945 0.3048)
			(stroke
				(width 0.1)
				(type default)
			)
			(layer "F.Fab")
		)
		(fp_line
			(start 0.120396 0.3048)
			(end 0.120396 0.2794)
			(stroke
				(width 0.1)
				(type default)
			)
			(layer "F.Fab")
		)
		(fp_line
			(start 0.67945 0.3048)
			(end 0.120396 0.3048)
			(stroke
				(width 0.1)
				(type default)
			)
			(layer "F.Fab")
		)
		(fp_line
			(start -0.12065 0.2794)
			(end -0.12065 0.3048)
			(stroke
				(width 0.1)
				(type default)
			)
			(layer "F.Fab")
		)
		(fp_line
			(start 0.120396 0.2794)
			(end -0.12065 0.2794)
			(stroke
				(width 0.1)
				(type default)
			)
			(layer "F.Fab")
		)
		(fp_line
			(start -0.12065 -0.2794)
			(end 0.12065 -0.2794)
			(stroke
				(width 0.1)
				(type default)
			)
			(layer "F.Fab")
		)
		(fp_line
			(start 0.12065 -0.2794)
			(end 0.12065 -0.3048)
			(stroke
				(width 0.1)
				(type default)
			)
			(layer "F.Fab")
		)
		(fp_line
			(start 0.12065 -0.3048)
			(end 0.67945 -0.3048)
			(stroke
				(width 0.1)
				(type default)
			)
			(layer "F.Fab")
		)
		(fp_line
			(start 0.67945 -0.3048)
			(end 0.67945 0.3048)
			(stroke
				(width 0.1)
				(type default)
			)
			(layer "F.Fab")
		)
		(fp_line
			(start -0.67945 -0.305054)
			(end -0.12065 -0.305054)
			(stroke
				(width 0.1)
				(type default)
			)
			(layer "F.Fab")
		)
		(fp_line
			(start -0.12065 -0.305054)
			(end -0.12065 -0.2794)
			(stroke
				(width 0.1)
				(type default)
			)
			(layer "F.Fab")
		)
		(pad "1" smd circle
			(at -0.40005 0 270)
			(size 0 0)
			(layers "F.Cu" "F.Mask" "F.Paste")
			(net "FM_THROTTLE_N")
		)
		(pad "2" smd circle
			(at 0.40005 0 270)
			(size 0 0)
			(layers "F.Cu" "F.Mask" "F.Paste")
			(net "FM_THROTTLE_R_N")
		)
	)
	(footprint ""
		(layer "F.Cu")
		(at 113.67008 -122.132598 90)
		(property "Reference" "R4039"
			(at 0 0 90)
			(layer "F.SilkS")
			(hide yes)
			(effects
				(font
					(size 1.27 1.27)
				)
			)
		)
		(property "Value" ""
			(at 0 0 90)
			(layer "F.Fab")
			(effects
				(font
					(size 1.27 1.27)
				)
			)
		)
		(duplicate_pad_numbers_are_jumpers no)
		(fp_line
			(start 0.7874 -0.4064)
			(end 0.7874 0.4064)
			(stroke
				(width 0.1524)
				(type default)
			)
			(layer "F.SilkS")
		)
		(fp_line
			(start -0.7874 -0.4064)
			(end 0.7874 -0.4064)
			(stroke
				(width 0.1524)
				(type default)
			)
			(layer "F.SilkS")
		)
		(fp_line
			(start 0.7874 0.4064)
			(end -0.7874 0.4064)
			(stroke
				(width 0.1524)
				(type default)
			)
			(layer "F.SilkS")
		)
		(fp_line
			(start -0.7874 0.4064)
			(end -0.7874 -0.4064)
			(stroke
				(width 0.1524)
				(type default)
			)
			(layer "F.SilkS")
		)
		(fp_line
			(start -0.12065 -0.305054)
			(end -0.12065 -0.2794)
			(stroke
				(width 0.1)
				(type default)
			)
			(layer "F.Fab")
		)
		(fp_line
			(start -0.67945 -0.305054)
			(end -0.12065 -0.305054)
			(stroke
				(width 0.1)
				(type default)
			)
			(layer "F.Fab")
		)
		(fp_line
			(start 0.67945 -0.3048)
			(end 0.67945 0.3048)
			(stroke
				(width 0.1)
				(type default)
			)
			(layer "F.Fab")
		)
		(fp_line
			(start 0.12065 -0.3048)
			(end 0.67945 -0.3048)
			(stroke
				(width 0.1)
				(type default)
			)
			(layer "F.Fab")
		)
		(fp_line
			(start 0.12065 -0.2794)
			(end 0.12065 -0.3048)
			(stroke
				(width 0.1)
				(type default)
			)
			(layer "F.Fab")
		)
		(fp_line
			(start -0.12065 -0.2794)
			(end 0.12065 -0.2794)
			(stroke
				(width 0.1)
				(type default)
			)
			(layer "F.Fab")
		)
		(fp_line
			(start 0.120396 0.2794)
			(end -0.12065 0.2794)
			(stroke
				(width 0.1)
				(type default)
			)
			(layer "F.Fab")
		)
		(fp_line
			(start -0.12065 0.2794)
			(end -0.12065 0.3048)
			(stroke
				(width 0.1)
				(type default)
			)
			(layer "F.Fab")
		)
		(fp_line
			(start 0.67945 0.3048)
			(end 0.120396 0.3048)
			(stroke
				(width 0.1)
				(type default)
			)
			(layer "F.Fab")
		)
		(fp_line
			(start 0.120396 0.3048)
			(end 0.120396 0.2794)
			(stroke
				(width 0.1)
				(type default)
			)
			(layer "F.Fab")
		)
		(fp_line
			(start -0.12065 0.3048)
			(end -0.67945 0.3048)
			(stroke
				(width 0.1)
				(type default)
			)
			(layer "F.Fab")
		)
		(fp_line
			(start -0.67945 0.3048)
			(end -0.67945 -0.305054)
			(stroke
				(width 0.1)
				(type default)
			)
			(layer "F.Fab")
		)
		(pad "1" smd circle
			(at -0.40005 0 90)
			(size 0 0)
			(layers "F.Cu" "F.Mask" "F.Paste")
			(net "P0V62_CPU0_RST_DDR_VREF")
		)
		(pad "2" smd circle
			(at 0.40005 0 90)
			(size 0 0)
			(layers "F.Cu" "F.Mask" "F.Paste")
			(net "GND")
		)
	)
	(footprint ""
		(layer "F.Cu")
		(at 131.6736 -125.758448 180)
		(property "Reference" "R3152"
			(at 0 0 180)
			(layer "F.SilkS")
			(hide yes)
			(effects
				(font
					(size 1.27 1.27)
				)
			)
		)
		(property "Value" ""
			(at 0 0 180)
			(layer "F.Fab")
			(effects
				(font
					(size 1.27 1.27)
				)
			)
		)
		(duplicate_pad_numbers_are_jumpers no)
		(fp_line
			(start 0.7874 0.4064)
			(end -0.7874 0.4064)
			(stroke
				(width 0.1524)
				(type default)
			)
			(layer "F.SilkS")
		)
		(fp_line
			(start 0.7874 -0.4064)
			(end 0.7874 0.4064)
			(stroke
				(width 0.1524)
				(type default)
			)
			(layer "F.SilkS")
		)
		(fp_line
			(start -0.7874 0.4064)
			(end -0.7874 -0.4064)
			(stroke
				(width 0.1524)
				(type default)
			)
			(layer "F.SilkS")
		)
		(fp_line
			(start -0.7874 -0.4064)
			(end 0.7874 -0.4064)
			(stroke
				(width 0.1524)
				(type default)
			)
			(layer "F.SilkS")
		)
		(fp_line
			(start 0.67945 0.3048)
			(end 0.120396 0.3048)
			(stroke
				(width 0.1)
				(type default)
			)
			(layer "F.Fab")
		)
		(fp_line
			(start 0.67945 -0.3048)
			(end 0.67945 0.3048)
			(stroke
				(width 0.1)
				(type default)
			)
			(layer "F.Fab")
		)
		(fp_line
			(start 0.12065 -0.2794)
			(end 0.12065 -0.3048)
			(stroke
				(width 0.1)
				(type default)
			)
			(layer "F.Fab")
		)
		(fp_line
			(start 0.12065 -0.3048)
			(end 0.67945 -0.3048)
			(stroke
				(width 0.1)
				(type default)
			)
			(layer "F.Fab")
		)
		(fp_line
			(start 0.120396 0.3048)
			(end 0.120396 0.2794)
			(stroke
				(width 0.1)
				(type default)
			)
			(layer "F.Fab")
		)
		(fp_line
			(start 0.120396 0.2794)
			(end -0.12065 0.2794)
			(stroke
				(width 0.1)
				(type default)
			)
			(layer "F.Fab")
		)
		(fp_line
			(start -0.12065 0.3048)
			(end -0.67945 0.3048)
			(stroke
				(width 0.1)
				(type default)
			)
			(layer "F.Fab")
		)
		(fp_line
			(start -0.12065 0.2794)
			(end -0.12065 0.3048)
			(stroke
				(width 0.1)
				(type default)
			)
			(layer "F.Fab")
		)
		(fp_line
			(start -0.12065 -0.2794)
			(end 0.12065 -0.2794)
			(stroke
				(width 0.1)
				(type default)
			)
			(layer "F.Fab")
		)
		(fp_line
			(start -0.12065 -0.305054)
			(end -0.12065 -0.2794)
			(stroke
				(width 0.1)
				(type default)
			)
			(layer "F.Fab")
		)
		(fp_line
			(start -0.67945 0.3048)
			(end -0.67945 -0.305054)
			(stroke
				(width 0.1)
				(type default)
			)
			(layer "F.Fab")
		)
		(fp_line
			(start -0.67945 -0.305054)
			(end -0.12065 -0.305054)
			(stroke
				(width 0.1)
				(type default)
			)
			(layer "F.Fab")
		)
		(pad "1" smd circle
			(at -0.40005 0 180)
			(size 0 0)
			(layers "F.Cu" "F.Mask" "F.Paste")
			(net "PD_SMB_OCP2_HP_ADD1")
		)
		(pad "2" smd circle
			(at 0.40005 0 180)
			(size 0 0)
			(layers "F.Cu" "F.Mask" "F.Paste")
			(net "GND")
		)
	)
	(footprint ""
		(layer "F.Cu")
		(at 114.706654 -359.94975)
		(property "Reference" "PC547"
			(at 0 0 0)
			(layer "F.SilkS")
			(hide yes)
			(effects
				(font
					(size 1.27 1.27)
				)
			)
		)
		(property "Value" ""
			(at 0 0 0)
			(layer "F.Fab")
			(effects
				(font
					(size 1.27 1.27)
				)
			)
		)
		(duplicate_pad_numbers_are_jumpers no)
		(fp_line
			(start -0.7874 -0.4064)
			(end 0.7874 -0.4064)
			(stroke
				(width 0.1524)
				(type default)
			)
			(layer "F.SilkS")
		)
		(fp_line
			(start -0.7874 0.4064)
			(end -0.7874 -0.4064)
			(stroke
				(width 0.1524)
				(type default)
			)
			(layer "F.SilkS")
		)
		(fp_line
			(start 0.7874 -0.4064)
			(end 0.7874 0.4064)
			(stroke
				(width 0.1524)
				(type default)
			)
			(layer "F.SilkS")
		)
		(fp_line
			(start 0.7874 0.4064)
			(end -0.7874 0.4064)
			(stroke
				(width 0.1524)
				(type default)
			)
			(layer "F.SilkS")
		)
		(fp_line
			(start -0.67945 -0.305054)
			(end -0.12065 -0.305054)
			(stroke
				(width 0.1)
				(type default)
			)
			(layer "F.Fab")
		)
		(fp_line
			(start -0.67945 0.3048)
			(end -0.67945 -0.305054)
			(stroke
				(width 0.1)
				(type default)
			)
			(layer "F.Fab")
		)
		(fp_line
			(start -0.12065 -0.305054)
			(end -0.12065 -0.2794)
			(stroke
				(width 0.1)
				(type default)
			)
			(layer "F.Fab")
		)
		(fp_line
			(start -0.12065 -0.2794)
			(end 0.12065 -0.2794)
			(stroke
				(width 0.1)
				(type default)
			)
			(layer "F.Fab")
		)
		(fp_line
			(start -0.12065 0.2794)
			(end -0.12065 0.3048)
			(stroke
				(width 0.1)
				(type default)
			)
			(layer "F.Fab")
		)
		(fp_line
			(start -0.12065 0.3048)
			(end -0.67945 0.3048)
			(stroke
				(width 0.1)
				(type default)
			)
			(layer "F.Fab")
		)
		(fp_line
			(start 0.120396 0.2794)
			(end -0.12065 0.2794)
			(stroke
				(width 0.1)
				(type default)
			)
			(layer "F.Fab")
		)
		(fp_line
			(start 0.120396 0.3048)
			(end 0.120396 0.2794)
			(stroke
				(width 0.1)
				(type default)
			)
			(layer "F.Fab")
		)
		(fp_line
			(start 0.12065 -0.3048)
			(end 0.67945 -0.3048)
			(stroke
				(width 0.1)
				(type default)
			)
			(layer "F.Fab")
		)
		(fp_line
			(start 0.12065 -0.2794)
			(end 0.12065 -0.3048)
			(stroke
				(width 0.1)
				(type default)
			)
			(layer "F.Fab")
		)
		(fp_line
			(start 0.67945 -0.3048)
			(end 0.67945 0.3048)
			(stroke
				(width 0.1)
				(type default)
			)
			(layer "F.Fab")
		)
		(fp_line
			(start 0.67945 0.3048)
			(end 0.120396 0.3048)
			(stroke
				(width 0.1)
				(type default)
			)
			(layer "F.Fab")
		)
		(pad "1" smd circle
			(at -0.40005 0)
			(size 0 0)
			(layers "F.Cu" "F.Mask" "F.Paste")
			(net "PVCCIN_CPU1_CSPIN")
		)
		(pad "2" smd circle
			(at 0.40005 0)
			(size 0 0)
			(layers "F.Cu" "F.Mask" "F.Paste")
			(net "GND")
		)
	)
	(footprint ""
		(layer "F.Cu")
		(at 440.383676 -15.656306 180)
		(property "Reference" "C1233"
			(at 0 0 180)
			(layer "F.SilkS")
			(hide yes)
			(effects
				(font
					(size 1.27 1.27)
				)
			)
		)
		(property "Value" ""
			(at 0 0 180)
			(layer "F.Fab")
			(effects
				(font
					(size 1.27 1.27)
				)
			)
		)
		(duplicate_pad_numbers_are_jumpers no)
		(fp_line
			(start 0.7874 0.4064)
			(end -0.7874 0.4064)
			(stroke
				(width 0.1524)
				(type default)
			)
			(layer "F.SilkS")
		)
		(fp_line
			(start 0.7874 -0.4064)
			(end 0.7874 0.4064)
			(stroke
				(width 0.1524)
				(type default)
			)
			(layer "F.SilkS")
		)
		(fp_line
			(start -0.7874 0.4064)
			(end -0.7874 -0.4064)
			(stroke
				(width 0.1524)
				(type default)
			)
			(layer "F.SilkS")
		)
		(fp_line
			(start -0.7874 -0.4064)
			(end 0.7874 -0.4064)
			(stroke
				(width 0.1524)
				(type default)
			)
			(layer "F.SilkS")
		)
		(fp_line
			(start 0.67945 0.3048)
			(end 0.120396 0.3048)
			(stroke
				(width 0.1)
				(type default)
			)
			(layer "F.Fab")
		)
		(fp_line
			(start 0.67945 -0.3048)
			(end 0.67945 0.3048)
			(stroke
				(width 0.1)
				(type default)
			)
			(layer "F.Fab")
		)
		(fp_line
			(start 0.12065 -0.2794)
			(end 0.12065 -0.3048)
			(stroke
				(width 0.1)
				(type default)
			)
			(layer "F.Fab")
		)
		(fp_line
			(start 0.12065 -0.3048)
			(end 0.67945 -0.3048)
			(stroke
				(width 0.1)
				(type default)
			)
			(layer "F.Fab")
		)
		(fp_line
			(start 0.120396 0.3048)
			(end 0.120396 0.2794)
			(stroke
				(width 0.1)
				(type default)
			)
			(layer "F.Fab")
		)
		(fp_line
			(start 0.120396 0.2794)
			(end -0.12065 0.2794)
			(stroke
				(width 0.1)
				(type default)
			)
			(layer "F.Fab")
		)
		(fp_line
			(start -0.12065 0.3048)
			(end -0.67945 0.3048)
			(stroke
				(width 0.1)
				(type default)
			)
			(layer "F.Fab")
		)
		(fp_line
			(start -0.12065 0.2794)
			(end -0.12065 0.3048)
			(stroke
				(width 0.1)
				(type default)
			)
			(layer "F.Fab")
		)
		(fp_line
			(start -0.12065 -0.2794)
			(end 0.12065 -0.2794)
			(stroke
				(width 0.1)
				(type default)
			)
			(layer "F.Fab")
		)
		(fp_line
			(start -0.12065 -0.305054)
			(end -0.12065 -0.2794)
			(stroke
				(width 0.1)
				(type default)
			)
			(layer "F.Fab")
		)
		(fp_line
			(start -0.67945 0.3048)
			(end -0.67945 -0.305054)
			(stroke
				(width 0.1)
				(type default)
			)
			(layer "F.Fab")
		)
		(fp_line
			(start -0.67945 -0.305054)
			(end -0.12065 -0.305054)
			(stroke
				(width 0.1)
				(type default)
			)
			(layer "F.Fab")
		)
		(pad "1" smd circle
			(at -0.40005 0 180)
			(size 0 0)
			(layers "F.Cu" "F.Mask" "F.Paste")
			(net "P12V_OCP_SFF")
		)
		(pad "2" smd circle
			(at 0.40005 0 180)
			(size 0 0)
			(layers "F.Cu" "F.Mask" "F.Paste")
			(net "GND")
		)
	)
	(footprint ""
		(layer "F.Cu")
		(at 309.522622 -42.916348 180)
		(property "Reference" "R381"
			(at 0 0 180)
			(layer "F.SilkS")
			(hide yes)
			(effects
				(font
					(size 1.27 1.27)
				)
			)
		)
		(property "Value" ""
			(at 0 0 180)
			(layer "F.Fab")
			(effects
				(font
					(size 1.27 1.27)
				)
			)
		)
		(duplicate_pad_numbers_are_jumpers no)
		(fp_line
			(start 0.7874 0.4064)
			(end -0.7874 0.4064)
			(stroke
				(width 0.1524)
				(type default)
			)
			(layer "F.SilkS")
		)
		(fp_line
			(start 0.7874 -0.4064)
			(end 0.7874 0.4064)
			(stroke
				(width 0.1524)
				(type default)
			)
			(layer "F.SilkS")
		)
		(fp_line
			(start -0.7874 0.4064)
			(end -0.7874 -0.4064)
			(stroke
				(width 0.1524)
				(type default)
			)
			(layer "F.SilkS")
		)
		(fp_line
			(start -0.7874 -0.4064)
			(end 0.7874 -0.4064)
			(stroke
				(width 0.1524)
				(type default)
			)
			(layer "F.SilkS")
		)
		(fp_line
			(start 0.67945 0.3048)
			(end 0.120396 0.3048)
			(stroke
				(width 0.1)
				(type default)
			)
			(layer "F.Fab")
		)
		(fp_line
			(start 0.67945 -0.3048)
			(end 0.67945 0.3048)
			(stroke
				(width 0.1)
				(type default)
			)
			(layer "F.Fab")
		)
		(fp_line
			(start 0.12065 -0.2794)
			(end 0.12065 -0.3048)
			(stroke
				(width 0.1)
				(type default)
			)
			(layer "F.Fab")
		)
		(fp_line
			(start 0.12065 -0.3048)
			(end 0.67945 -0.3048)
			(stroke
				(width 0.1)
				(type default)
			)
			(layer "F.Fab")
		)
		(fp_line
			(start 0.120396 0.3048)
			(end 0.120396 0.2794)
			(stroke
				(width 0.1)
				(type default)
			)
			(layer "F.Fab")
		)
		(fp_line
			(start 0.120396 0.2794)
			(end -0.12065 0.2794)
			(stroke
				(width 0.1)
				(type default)
			)
			(layer "F.Fab")
		)
		(fp_line
			(start -0.12065 0.3048)
			(end -0.67945 0.3048)
			(stroke
				(width 0.1)
				(type default)
			)
			(layer "F.Fab")
		)
		(fp_line
			(start -0.12065 0.2794)
			(end -0.12065 0.3048)
			(stroke
				(width 0.1)
				(type default)
			)
			(layer "F.Fab")
		)
		(fp_line
			(start -0.12065 -0.2794)
			(end 0.12065 -0.2794)
			(stroke
				(width 0.1)
				(type default)
			)
			(layer "F.Fab")
		)
		(fp_line
			(start -0.12065 -0.305054)
			(end -0.12065 -0.2794)
			(stroke
				(width 0.1)
				(type default)
			)
			(layer "F.Fab")
		)
		(fp_line
			(start -0.67945 0.3048)
			(end -0.67945 -0.305054)
			(stroke
				(width 0.1)
				(type default)
			)
			(layer "F.Fab")
		)
		(fp_line
			(start -0.67945 -0.305054)
			(end -0.12065 -0.305054)
			(stroke
				(width 0.1)
				(type default)
			)
			(layer "F.Fab")
		)
		(pad "1" smd circle
			(at -0.40005 0 180)
			(size 0 0)
			(layers "F.Cu" "F.Mask" "F.Paste")
			(net "FM_FLASH_SECURITY_STRAP")
		)
		(pad "2" smd circle
			(at 0.40005 0 180)
			(size 0 0)
			(layers "F.Cu" "F.Mask" "F.Paste")
			(net "GND")
		)
	)
	(footprint ""
		(layer "F.Cu")
		(at 64.793876 -79.078836)
		(property "Reference" "D76"
			(at -34.444686 34.341308 90)
			(unlocked yes)
			(layer "F.SilkS")
			(effects
				(font
					(size 0.635 0.4064)
					(thickness 0.1524)
				)
				(justify left)
			)
		)
		(property "Value" ""
			(at 0 0 0)
			(layer "F.Fab")
			(effects
				(font
					(size 1.27 1.27)
				)
			)
		)
		(duplicate_pad_numbers_are_jumpers no)
		(fp_line
			(start -0.90678 0.4826)
			(end -0.90678 -0.4699)
			(stroke
				(width 0.1524)
				(type default)
			)
			(layer "F.SilkS")
		)
		(fp_line
			(start -0.89408 -0.4826)
			(end 0.90678 -0.4826)
			(stroke
				(width 0.1524)
				(type default)
			)
			(layer "F.SilkS")
		)
		(fp_line
			(start -0.79248 -0.4826)
			(end 1.03378 -0.4826)
			(stroke
				(width 0.1524)
				(type default)
			)
			(layer "F.SilkS")
		)
		(fp_line
			(start -0.64008 -0.4826)
			(end 1.16078 -0.4826)
			(stroke
				(width 0.1524)
				(type default)
			)
			(layer "F.SilkS")
		)
		(fp_line
			(start 0.90678 -0.4826)
			(end 0.90678 0.4826)
			(stroke
				(width 0.1524)
				(type default)
			)
			(layer "F.SilkS")
		)
		(fp_line
			(start 0.90678 0.4826)
			(end -0.90678 0.4826)
			(stroke
				(width 0.1524)
				(type default)
			)
			(layer "F.SilkS")
		)
		(fp_line
			(start 1.03378 -0.4826)
			(end 1.03378 0.4826)
			(stroke
				(width 0.1524)
				(type default)
			)
			(layer "F.SilkS")
		)
		(fp_line
			(start 1.03378 0.4826)
			(end -0.79248 0.4826)
			(stroke
				(width 0.1524)
				(type default)
			)
			(layer "F.SilkS")
		)
		(fp_line
			(start 1.16078 -0.4826)
			(end 1.16078 0.4826)
			(stroke
				(width 0.1524)
				(type default)
			)
			(layer "F.SilkS")
		)
		(fp_line
			(start 1.16078 0.4826)
			(end -0.64008 0.4826)
			(stroke
				(width 0.1524)
				(type default)
			)
			(layer "F.SilkS")
		)
		(fp_line
			(start -0.499872 -0.249936)
			(end 0.499872 -0.249936)
			(stroke
				(width 0.1)
				(type default)
			)
			(layer "F.Fab")
		)
		(fp_line
			(start -0.499872 0.249936)
			(end -0.499872 -0.249936)
			(stroke
				(width 0.1)
				(type default)
			)
			(layer "F.Fab")
		)
		(fp_line
			(start 0.499872 -0.249936)
			(end 0.499872 0.249936)
			(stroke
				(width 0.1)
				(type default)
			)
			(layer "F.Fab")
		)
		(fp_line
			(start 0.499872 0.249936)
			(end -0.499872 0.249936)
			(stroke
				(width 0.1)
				(type default)
			)
			(layer "F.Fab")
		)
		(pad "A" smd rect
			(at -0.47498 0)
			(size 0.6096 0.7112)
			(layers "F.Cu" "F.Mask" "F.Paste")
			(net "LED_PWRGD_PVCCFA_EHV_FIVRA_CPU0")
		)
		(pad "C" smd rect
			(at 0.47498 0)
			(size 0.6096 0.7112)
			(layers "F.Cu" "F.Mask" "F.Paste")
			(net "LED_PWRGD_PVCCFA_EHV_FIVRA_CP_1")
		)
	)
	(footprint ""
		(layer "F.Cu")
		(at 506.598428 -153.16708 -90)
		(property "Reference" "X9"
			(at -1.373124 2.750058 90)
			(unlocked yes)
			(layer "F.SilkS")
			(effects
				(font
					(size 0.7874 0.5842)
					(thickness 0.1524)
				)
				(justify left)
			)
		)
		(property "Value" ""
			(at 0 0 270)
			(layer "F.Fab")
			(effects
				(font
					(size 1.27 1.27)
				)
			)
		)
		(property "Device Type" "TP_TDR_4P_FTS_MPKT4_H025P0200_I"
			(at 1.30175 1.27 0)
			(unlocked yes)
			(layer "F.Fab")
			(hide yes)
			(effects
				(font
					(size 0.635 0.4064)
					(thickness 0.1524)
				)
			)
		)
		(property "User Part Number" "TP15"
			(at 1.30175 1.27 0)
			(unlocked yes)
			(layer "Cmts.User")
			(hide yes)
			(effects
				(font
					(size 0.635 0.4064)
					(thickness 0.1524)
				)
			)
		)
		(duplicate_pad_numbers_are_jumpers no)
		(fp_line
			(start 0 3.81)
			(end 2.54 3.81)
			(stroke
				(width 0.1524)
				(type default)
			)
			(layer "F.SilkS")
		)
		(fp_line
			(start 2.54 3.81)
			(end 2.54 3.6703)
			(stroke
				(width 0.1524)
				(type default)
			)
			(layer "F.SilkS")
		)
		(fp_line
			(start 0 3.175)
			(end 0 3.81)
			(stroke
				(width 0.1524)
				(type default)
			)
			(layer "F.SilkS")
		)
		(fp_line
			(start 2.54 1.4097)
			(end 2.54 1.1303)
			(stroke
				(width 0.1524)
				(type default)
			)
			(layer "F.SilkS")
		)
		(fp_line
			(start 0 0.635)
			(end 0 1.905)
			(stroke
				(width 0.1524)
				(type default)
			)
			(layer "F.SilkS")
		)
		(fp_line
			(start 2.54 -1.1303)
			(end 2.54 -1.27)
			(stroke
				(width 0.1524)
				(type default)
			)
			(layer "F.SilkS")
		)
		(fp_line
			(start 0 -1.27)
			(end 0 -0.635)
			(stroke
				(width 0.1524)
				(type default)
			)
			(layer "F.SilkS")
		)
		(fp_line
			(start 2.54 -1.27)
			(end 0 -1.27)
			(stroke
				(width 0.1524)
				(type default)
			)
			(layer "F.SilkS")
		)
		(fp_poly
			(pts
				(xy -1.244346 0) (xy -2.768346 0.762) (xy -2.768346 -0.762)
			)
			(stroke
				(width 0)
				(type default)
			)
			(fill yes)
			(layer "F.SilkS")
		)
		(fp_line
			(start 0 3.81)
			(end 2.54 3.81)
			(stroke
				(width 0.1)
				(type default)
			)
			(layer "F.Fab")
		)
		(fp_line
			(start 2.54 3.81)
			(end 2.54 -1.27)
			(stroke
				(width 0.1)
				(type default)
			)
			(layer "F.Fab")
		)
		(fp_line
			(start 0 -1.27)
			(end 0 3.81)
			(stroke
				(width 0.1)
				(type default)
			)
			(layer "F.Fab")
		)
		(fp_line
			(start 2.54 -1.27)
			(end 0 -1.27)
			(stroke
				(width 0.1)
				(type default)
			)
			(layer "F.Fab")
		)
		(fp_poly
			(pts
				(xy -0.761746 0) (xy -2.285746 -0.762) (xy -2.285746 0.762)
			)
			(stroke
				(width 0)
				(type default)
			)
			(fill yes)
			(layer "F.Fab")
		)
		(pad "1" thru_hole circle
			(at 0 0 270)
			(size 1.0033 1.0033)
			(drill 0.249936)
			(layers "*.Cu" "*.Mask")
			(remove_unused_layers no)
			(net "TDR_DIFF_85_IN2_DN")
			(clearance 0.10795)
			(thermal_gap 0.10795)
			(padstack
				(mode front_inner_back)
				(layer "Inner"
					(shape circle)
					(size 0.8001 0.8001)
					(clearance 0.1524)
				)
				(layer "B.Cu"
					(shape circle)
					(size 1.0033 1.0033)
					(clearance 0.10795)
				)
			)
		)
		(pad "2" thru_hole circle
			(at 2.54 0 270)
			(size 1.9939 1.9939)
			(drill 0.249936)
			(layers "*.Cu" "*.Mask")
			(remove_unused_layers no)
			(net "T1_GND")
			(clearance 0.10795)
			(thermal_gap 0.10795)
			(padstack
				(mode front_inner_back)
				(layer "Inner"
					(shape circle)
					(size 0.8001 0.8001)
					(clearance 0.1524)
				)
				(layer "B.Cu"
					(shape circle)
					(size 1.9939 1.9939)
					(clearance 0.10795)
				)
			)
		)
		(pad "3" thru_hole circle
			(at 2.54 2.54 270)
			(size 1.9939 1.9939)
			(drill 0.249936)
			(layers "*.Cu" "*.Mask")
			(remove_unused_layers no)
			(net "T1_GND")
			(clearance 0.10795)
			(thermal_gap 0.10795)
			(padstack
				(mode front_inner_back)
				(layer "Inner"
					(shape circle)
					(size 0.8001 0.8001)
					(clearance 0.1524)
				)
				(layer "B.Cu"
					(shape circle)
					(size 1.9939 1.9939)
					(clearance 0.10795)
				)
			)
		)
		(pad "4" thru_hole circle
			(at 0 2.54 270)
			(size 1.0033 1.0033)
			(drill 0.249936)
			(layers "*.Cu" "*.Mask")
			(remove_unused_layers no)
			(net "TDR_DIFF_85_IN2_DP")
			(clearance 0.10795)
			(thermal_gap 0.10795)
			(padstack
				(mode front_inner_back)
				(layer "Inner"
					(shape circle)
					(size 0.8001 0.8001)
					(clearance 0.1524)
				)
				(layer "B.Cu"
					(shape circle)
					(size 1.0033 1.0033)
					(clearance 0.10795)
				)
			)
		)
	)
	(footprint ""
		(layer "F.Cu")
		(at 258.37388 -50.565304)
		(property "Reference" "PR3944"
			(at 0 0 0)
			(layer "F.SilkS")
			(hide yes)
			(effects
				(font
					(size 1.27 1.27)
				)
			)
		)
		(property "Value" ""
			(at 0 0 0)
			(layer "F.Fab")
			(effects
				(font
					(size 1.27 1.27)
				)
			)
		)
		(duplicate_pad_numbers_are_jumpers no)
		(fp_line
			(start -0.7874 -0.4064)
			(end 0.7874 -0.4064)
			(stroke
				(width 0.1524)
				(type default)
			)
			(layer "F.SilkS")
		)
		(fp_line
			(start -0.7874 0.4064)
			(end -0.7874 -0.4064)
			(stroke
				(width 0.1524)
				(type default)
			)
			(layer "F.SilkS")
		)
		(fp_line
			(start 0.7874 -0.4064)
			(end 0.7874 0.4064)
			(stroke
				(width 0.1524)
				(type default)
			)
			(layer "F.SilkS")
		)
		(fp_line
			(start 0.7874 0.4064)
			(end -0.7874 0.4064)
			(stroke
				(width 0.1524)
				(type default)
			)
			(layer "F.SilkS")
		)
		(fp_line
			(start -0.67945 -0.305054)
			(end -0.12065 -0.305054)
			(stroke
				(width 0.1)
				(type default)
			)
			(layer "F.Fab")
		)
		(fp_line
			(start -0.67945 0.3048)
			(end -0.67945 -0.305054)
			(stroke
				(width 0.1)
				(type default)
			)
			(layer "F.Fab")
		)
		(fp_line
			(start -0.12065 -0.305054)
			(end -0.12065 -0.2794)
			(stroke
				(width 0.1)
				(type default)
			)
			(layer "F.Fab")
		)
		(fp_line
			(start -0.12065 -0.2794)
			(end 0.12065 -0.2794)
			(stroke
				(width 0.1)
				(type default)
			)
			(layer "F.Fab")
		)
		(fp_line
			(start -0.12065 0.2794)
			(end -0.12065 0.3048)
			(stroke
				(width 0.1)
				(type default)
			)
			(layer "F.Fab")
		)
		(fp_line
			(start -0.12065 0.3048)
			(end -0.67945 0.3048)
			(stroke
				(width 0.1)
				(type default)
			)
			(layer "F.Fab")
		)
		(fp_line
			(start 0.120396 0.2794)
			(end -0.12065 0.2794)
			(stroke
				(width 0.1)
				(type default)
			)
			(layer "F.Fab")
		)
		(fp_line
			(start 0.120396 0.3048)
			(end 0.120396 0.2794)
			(stroke
				(width 0.1)
				(type default)
			)
			(layer "F.Fab")
		)
		(fp_line
			(start 0.12065 -0.3048)
			(end 0.67945 -0.3048)
			(stroke
				(width 0.1)
				(type default)
			)
			(layer "F.Fab")
		)
		(fp_line
			(start 0.12065 -0.2794)
			(end 0.12065 -0.3048)
			(stroke
				(width 0.1)
				(type default)
			)
			(layer "F.Fab")
		)
		(fp_line
			(start 0.67945 -0.3048)
			(end 0.67945 0.3048)
			(stroke
				(width 0.1)
				(type default)
			)
			(layer "F.Fab")
		)
		(fp_line
			(start 0.67945 0.3048)
			(end 0.120396 0.3048)
			(stroke
				(width 0.1)
				(type default)
			)
			(layer "F.Fab")
		)
		(pad "1" smd circle
			(at -0.40005 0)
			(size 0 0)
			(layers "F.Cu" "F.Mask" "F.Paste")
			(net "P12V_E1S_ISET_0")
		)
		(pad "2" smd circle
			(at 0.40005 0)
			(size 0 0)
			(layers "F.Cu" "F.Mask" "F.Paste")
			(net "GND")
		)
	)
	(footprint ""
		(layer "F.Cu")
		(at 224.2312 -51.0921 180)
		(property "Reference" "R4084"
			(at 0 0 180)
			(layer "F.SilkS")
			(hide yes)
			(effects
				(font
					(size 1.27 1.27)
				)
			)
		)
		(property "Value" ""
			(at 0 0 180)
			(layer "F.Fab")
			(effects
				(font
					(size 1.27 1.27)
				)
			)
		)
		(duplicate_pad_numbers_are_jumpers no)
		(fp_line
			(start 0.7874 0.4064)
			(end -0.7874 0.4064)
			(stroke
				(width 0.1524)
				(type default)
			)
			(layer "F.SilkS")
		)
		(fp_line
			(start 0.7874 -0.4064)
			(end 0.7874 0.4064)
			(stroke
				(width 0.1524)
				(type default)
			)
			(layer "F.SilkS")
		)
		(fp_line
			(start -0.7874 0.4064)
			(end -0.7874 -0.4064)
			(stroke
				(width 0.1524)
				(type default)
			)
			(layer "F.SilkS")
		)
		(fp_line
			(start -0.7874 -0.4064)
			(end 0.7874 -0.4064)
			(stroke
				(width 0.1524)
				(type default)
			)
			(layer "F.SilkS")
		)
		(fp_line
			(start 0.67945 0.3048)
			(end 0.120396 0.3048)
			(stroke
				(width 0.1)
				(type default)
			)
			(layer "F.Fab")
		)
		(fp_line
			(start 0.67945 -0.3048)
			(end 0.67945 0.3048)
			(stroke
				(width 0.1)
				(type default)
			)
			(layer "F.Fab")
		)
		(fp_line
			(start 0.12065 -0.2794)
			(end 0.12065 -0.3048)
			(stroke
				(width 0.1)
				(type default)
			)
			(layer "F.Fab")
		)
		(fp_line
			(start 0.12065 -0.3048)
			(end 0.67945 -0.3048)
			(stroke
				(width 0.1)
				(type default)
			)
			(layer "F.Fab")
		)
		(fp_line
			(start 0.120396 0.3048)
			(end 0.120396 0.2794)
			(stroke
				(width 0.1)
				(type default)
			)
			(layer "F.Fab")
		)
		(fp_line
			(start 0.120396 0.2794)
			(end -0.12065 0.2794)
			(stroke
				(width 0.1)
				(type default)
			)
			(layer "F.Fab")
		)
		(fp_line
			(start -0.12065 0.3048)
			(end -0.67945 0.3048)
			(stroke
				(width 0.1)
				(type default)
			)
			(layer "F.Fab")
		)
		(fp_line
			(start -0.12065 0.2794)
			(end -0.12065 0.3048)
			(stroke
				(width 0.1)
				(type default)
			)
			(layer "F.Fab")
		)
		(fp_line
			(start -0.12065 -0.2794)
			(end 0.12065 -0.2794)
			(stroke
				(width 0.1)
				(type default)
			)
			(layer "F.Fab")
		)
		(fp_line
			(start -0.12065 -0.305054)
			(end -0.12065 -0.2794)
			(stroke
				(width 0.1)
				(type default)
			)
			(layer "F.Fab")
		)
		(fp_line
			(start -0.67945 0.3048)
			(end -0.67945 -0.305054)
			(stroke
				(width 0.1)
				(type default)
			)
			(layer "F.Fab")
		)
		(fp_line
			(start -0.67945 -0.305054)
			(end -0.12065 -0.305054)
			(stroke
				(width 0.1)
				(type default)
			)
			(layer "F.Fab")
		)
		(pad "1" smd circle
			(at -0.40005 0 180)
			(size 0 0)
			(layers "F.Cu" "F.Mask" "F.Paste")
			(net "E1S_0_PRSNT_N")
		)
		(pad "2" smd circle
			(at 0.40005 0 180)
			(size 0 0)
			(layers "F.Cu" "F.Mask" "F.Paste")
			(net "E1S_0_CLKREQ_N")
		)
	)
	(footprint ""
		(layer "F.Cu")
		(at 341.627968 -402.371052 -90)
		(property "Reference" "C1555"
			(at 0 0 270)
			(layer "F.SilkS")
			(hide yes)
			(effects
				(font
					(size 1.27 1.27)
				)
			)
		)
		(property "Value" ""
			(at 0 0 270)
			(layer "F.Fab")
			(effects
				(font
					(size 1.27 1.27)
				)
			)
		)
		(duplicate_pad_numbers_are_jumpers no)
		(fp_line
			(start -0.299974 0.150114)
			(end -0.299974 -0.150114)
			(stroke
				(width 0.1)
				(type default)
			)
			(layer "F.Fab")
		)
		(fp_line
			(start 0.299974 0.150114)
			(end -0.299974 0.150114)
			(stroke
				(width 0.1)
				(type default)
			)
			(layer "F.Fab")
		)
		(fp_line
			(start -0.299974 -0.150114)
			(end 0.299974 -0.150114)
			(stroke
				(width 0.1)
				(type default)
			)
			(layer "F.Fab")
		)
		(fp_line
			(start 0.299974 -0.150114)
			(end 0.299974 0.150114)
			(stroke
				(width 0.1)
				(type default)
			)
			(layer "F.Fab")
		)
		(pad "1" smd rect
			(at -0.2667 0 270)
			(size 0.3048 0.381)
			(layers "F.Cu" "F.Mask" "F.Paste")
			(net "P5E_CPU0_PE4_TX_C_DP<12>")
		)
		(pad "2" smd rect
			(at 0.2667 0 270)
			(size 0.3048 0.381)
			(layers "F.Cu" "F.Mask" "F.Paste")
			(net "P5E_CPU0_PE4_TX_DP<12>")
		)
	)
	(footprint ""
		(layer "F.Cu")
		(at 447.510154 -118.336822)
		(property "Reference" "R3037"
			(at 0 0 0)
			(layer "F.SilkS")
			(hide yes)
			(effects
				(font
					(size 1.27 1.27)
				)
			)
		)
		(property "Value" ""
			(at 0 0 0)
			(layer "F.Fab")
			(effects
				(font
					(size 1.27 1.27)
				)
			)
		)
		(duplicate_pad_numbers_are_jumpers no)
		(fp_line
			(start -0.7874 -0.4064)
			(end 0.7874 -0.4064)
			(stroke
				(width 0.1524)
				(type default)
			)
			(layer "F.SilkS")
		)
		(fp_line
			(start -0.7874 0.4064)
			(end -0.7874 -0.4064)
			(stroke
				(width 0.1524)
				(type default)
			)
			(layer "F.SilkS")
		)
		(fp_line
			(start 0.7874 -0.4064)
			(end 0.7874 0.4064)
			(stroke
				(width 0.1524)
				(type default)
			)
			(layer "F.SilkS")
		)
		(fp_line
			(start 0.7874 0.4064)
			(end -0.7874 0.4064)
			(stroke
				(width 0.1524)
				(type default)
			)
			(layer "F.SilkS")
		)
		(fp_line
			(start -0.67945 -0.305054)
			(end -0.12065 -0.305054)
			(stroke
				(width 0.1)
				(type default)
			)
			(layer "F.Fab")
		)
		(fp_line
			(start -0.67945 0.3048)
			(end -0.67945 -0.305054)
			(stroke
				(width 0.1)
				(type default)
			)
			(layer "F.Fab")
		)
		(fp_line
			(start -0.12065 -0.305054)
			(end -0.12065 -0.2794)
			(stroke
				(width 0.1)
				(type default)
			)
			(layer "F.Fab")
		)
		(fp_line
			(start -0.12065 -0.2794)
			(end 0.12065 -0.2794)
			(stroke
				(width 0.1)
				(type default)
			)
			(layer "F.Fab")
		)
		(fp_line
			(start -0.12065 0.2794)
			(end -0.12065 0.3048)
			(stroke
				(width 0.1)
				(type default)
			)
			(layer "F.Fab")
		)
		(fp_line
			(start -0.12065 0.3048)
			(end -0.67945 0.3048)
			(stroke
				(width 0.1)
				(type default)
			)
			(layer "F.Fab")
		)
		(fp_line
			(start 0.120396 0.2794)
			(end -0.12065 0.2794)
			(stroke
				(width 0.1)
				(type default)
			)
			(layer "F.Fab")
		)
		(fp_line
			(start 0.120396 0.3048)
			(end 0.120396 0.2794)
			(stroke
				(width 0.1)
				(type default)
			)
			(layer "F.Fab")
		)
		(fp_line
			(start 0.12065 -0.3048)
			(end 0.67945 -0.3048)
			(stroke
				(width 0.1)
				(type default)
			)
			(layer "F.Fab")
		)
		(fp_line
			(start 0.12065 -0.2794)
			(end 0.12065 -0.3048)
			(stroke
				(width 0.1)
				(type default)
			)
			(layer "F.Fab")
		)
		(fp_line
			(start 0.67945 -0.3048)
			(end 0.67945 0.3048)
			(stroke
				(width 0.1)
				(type default)
			)
			(layer "F.Fab")
		)
		(fp_line
			(start 0.67945 0.3048)
			(end 0.120396 0.3048)
			(stroke
				(width 0.1)
				(type default)
			)
			(layer "F.Fab")
		)
		(pad "1" smd circle
			(at -0.40005 0)
			(size 0 0)
			(layers "F.Cu" "F.Mask" "F.Paste")
			(net "P3V3_AUX")
		)
		(pad "2" smd circle
			(at 0.40005 0)
			(size 0 0)
			(layers "F.Cu" "F.Mask" "F.Paste")
			(net "PD_SMB_OCP1_HP_ADD1")
		)
	)
	(footprint ""
		(layer "F.Cu")
		(at 117.526816 -252.956568 -90)
		(property "Reference" "C281"
			(at 0 0 270)
			(layer "F.SilkS")
			(hide yes)
			(effects
				(font
					(size 1.27 1.27)
				)
			)
		)
		(property "Value" ""
			(at 0 0 270)
			(layer "F.Fab")
			(effects
				(font
					(size 1.27 1.27)
				)
			)
		)
		(duplicate_pad_numbers_are_jumpers no)
		(fp_line
			(start -0.7874 0.4064)
			(end -0.7874 -0.4064)
			(stroke
				(width 0.1524)
				(type default)
			)
			(layer "F.SilkS")
		)
		(fp_line
			(start 0.7874 0.4064)
			(end -0.7874 0.4064)
			(stroke
				(width 0.1524)
				(type default)
			)
			(layer "F.SilkS")
		)
		(fp_line
			(start -0.7874 -0.4064)
			(end 0.7874 -0.4064)
			(stroke
				(width 0.1524)
				(type default)
			)
			(layer "F.SilkS")
		)
		(fp_line
			(start 0.7874 -0.4064)
			(end 0.7874 0.4064)
			(stroke
				(width 0.1524)
				(type default)
			)
			(layer "F.SilkS")
		)
		(fp_line
			(start -0.67945 0.3048)
			(end -0.67945 -0.305054)
			(stroke
				(width 0.1)
				(type default)
			)
			(layer "F.Fab")
		)
		(fp_line
			(start -0.12065 0.3048)
			(end -0.67945 0.3048)
			(stroke
				(width 0.1)
				(type default)
			)
			(layer "F.Fab")
		)
		(fp_line
			(start 0.120396 0.3048)
			(end 0.120396 0.2794)
			(stroke
				(width 0.1)
				(type default)
			)
			(layer "F.Fab")
		)
		(fp_line
			(start 0.67945 0.3048)
			(end 0.120396 0.3048)
			(stroke
				(width 0.1)
				(type default)
			)
			(layer "F.Fab")
		)
		(fp_line
			(start -0.12065 0.2794)
			(end -0.12065 0.3048)
			(stroke
				(width 0.1)
				(type default)
			)
			(layer "F.Fab")
		)
		(fp_line
			(start 0.120396 0.2794)
			(end -0.12065 0.2794)
			(stroke
				(width 0.1)
				(type default)
			)
			(layer "F.Fab")
		)
		(fp_line
			(start -0.12065 -0.2794)
			(end 0.12065 -0.2794)
			(stroke
				(width 0.1)
				(type default)
			)
			(layer "F.Fab")
		)
		(fp_line
			(start 0.12065 -0.2794)
			(end 0.12065 -0.3048)
			(stroke
				(width 0.1)
				(type default)
			)
			(layer "F.Fab")
		)
		(fp_line
			(start 0.12065 -0.3048)
			(end 0.67945 -0.3048)
			(stroke
				(width 0.1)
				(type default)
			)
			(layer "F.Fab")
		)
		(fp_line
			(start 0.67945 -0.3048)
			(end 0.67945 0.3048)
			(stroke
				(width 0.1)
				(type default)
			)
			(layer "F.Fab")
		)
		(fp_line
			(start -0.67945 -0.305054)
			(end -0.12065 -0.305054)
			(stroke
				(width 0.1)
				(type default)
			)
			(layer "F.Fab")
		)
		(fp_line
			(start -0.12065 -0.305054)
			(end -0.12065 -0.2794)
			(stroke
				(width 0.1)
				(type default)
			)
			(layer "F.Fab")
		)
		(pad "1" smd circle
			(at -0.40005 0 270)
			(size 0 0)
			(layers "F.Cu" "F.Mask" "F.Paste")
			(net "PVCCIN_CPU1")
		)
		(pad "2" smd circle
			(at 0.40005 0 270)
			(size 0 0)
			(layers "F.Cu" "F.Mask" "F.Paste")
			(net "GND")
		)
	)
	(footprint ""
		(layer "F.Cu")
		(at 30.248098 -137.99693 90)
		(property "Reference" "PR4244"
			(at 0 0 90)
			(layer "F.SilkS")
			(hide yes)
			(effects
				(font
					(size 1.27 1.27)
				)
			)
		)
		(property "Value" ""
			(at 0 0 90)
			(layer "F.Fab")
			(effects
				(font
					(size 1.27 1.27)
				)
			)
		)
		(duplicate_pad_numbers_are_jumpers no)
		(fp_line
			(start 0.7874 -0.4064)
			(end 0.7874 0.4064)
			(stroke
				(width 0.1524)
				(type default)
			)
			(layer "F.SilkS")
		)
		(fp_line
			(start -0.7874 -0.4064)
			(end 0.7874 -0.4064)
			(stroke
				(width 0.1524)
				(type default)
			)
			(layer "F.SilkS")
		)
		(fp_line
			(start 0.7874 0.4064)
			(end -0.7874 0.4064)
			(stroke
				(width 0.1524)
				(type default)
			)
			(layer "F.SilkS")
		)
		(fp_line
			(start -0.7874 0.4064)
			(end -0.7874 -0.4064)
			(stroke
				(width 0.1524)
				(type default)
			)
			(layer "F.SilkS")
		)
		(fp_line
			(start -0.12065 -0.305054)
			(end -0.12065 -0.2794)
			(stroke
				(width 0.1)
				(type default)
			)
			(layer "F.Fab")
		)
		(fp_line
			(start -0.67945 -0.305054)
			(end -0.12065 -0.305054)
			(stroke
				(width 0.1)
				(type default)
			)
			(layer "F.Fab")
		)
		(fp_line
			(start 0.67945 -0.3048)
			(end 0.67945 0.3048)
			(stroke
				(width 0.1)
				(type default)
			)
			(layer "F.Fab")
		)
		(fp_line
			(start 0.12065 -0.3048)
			(end 0.67945 -0.3048)
			(stroke
				(width 0.1)
				(type default)
			)
			(layer "F.Fab")
		)
		(fp_line
			(start 0.12065 -0.2794)
			(end 0.12065 -0.3048)
			(stroke
				(width 0.1)
				(type default)
			)
			(layer "F.Fab")
		)
		(fp_line
			(start -0.12065 -0.2794)
			(end 0.12065 -0.2794)
			(stroke
				(width 0.1)
				(type default)
			)
			(layer "F.Fab")
		)
		(fp_line
			(start 0.120396 0.2794)
			(end -0.12065 0.2794)
			(stroke
				(width 0.1)
				(type default)
			)
			(layer "F.Fab")
		)
		(fp_line
			(start -0.12065 0.2794)
			(end -0.12065 0.3048)
			(stroke
				(width 0.1)
				(type default)
			)
			(layer "F.Fab")
		)
		(fp_line
			(start 0.67945 0.3048)
			(end 0.120396 0.3048)
			(stroke
				(width 0.1)
				(type default)
			)
			(layer "F.Fab")
		)
		(fp_line
			(start 0.120396 0.3048)
			(end 0.120396 0.2794)
			(stroke
				(width 0.1)
				(type default)
			)
			(layer "F.Fab")
		)
		(fp_line
			(start -0.12065 0.3048)
			(end -0.67945 0.3048)
			(stroke
				(width 0.1)
				(type default)
			)
			(layer "F.Fab")
		)
		(fp_line
			(start -0.67945 0.3048)
			(end -0.67945 -0.305054)
			(stroke
				(width 0.1)
				(type default)
			)
			(layer "F.Fab")
		)
		(pad "1" smd circle
			(at -0.40005 0 90)
			(size 0 0)
			(layers "F.Cu" "F.Mask" "F.Paste")
			(net "NC_PVCCINFAON_CPU1_ACSP5")
		)
		(pad "2" smd circle
			(at 0.40005 0 90)
			(size 0 0)
			(layers "F.Cu" "F.Mask" "F.Paste")
			(net "GND")
		)
	)
	(footprint ""
		(layer "F.Cu")
		(at 114.91722 -296.05478)
		(property "Reference" "C240"
			(at 0 0 0)
			(layer "F.SilkS")
			(hide yes)
			(effects
				(font
					(size 1.27 1.27)
				)
			)
		)
		(property "Value" ""
			(at 0 0 0)
			(layer "F.Fab")
			(effects
				(font
					(size 1.27 1.27)
				)
			)
		)
		(duplicate_pad_numbers_are_jumpers no)
		(fp_line
			(start -1.524 -0.762)
			(end 1.524 -0.762)
			(stroke
				(width 0.1524)
				(type default)
			)
			(layer "F.SilkS")
		)
		(fp_line
			(start -1.524 0.762)
			(end -1.524 -0.762)
			(stroke
				(width 0.1524)
				(type default)
			)
			(layer "F.SilkS")
		)
		(fp_line
			(start 1.524 -0.762)
			(end 1.524 0.762)
			(stroke
				(width 0.1524)
				(type default)
			)
			(layer "F.SilkS")
		)
		(fp_line
			(start 1.524 0.762)
			(end -1.524 0.762)
			(stroke
				(width 0.1524)
				(type default)
			)
			(layer "F.SilkS")
		)
		(fp_line
			(start -1.1049 -0.724916)
			(end -1.1049 0.724916)
			(stroke
				(width 0.1)
				(type default)
			)
			(layer "F.Fab")
		)
		(fp_line
			(start -1.1049 0.724916)
			(end 1.1049 0.724916)
			(stroke
				(width 0.1)
				(type default)
			)
			(layer "F.Fab")
		)
		(fp_line
			(start 1.1049 -0.724916)
			(end -1.1049 -0.724916)
			(stroke
				(width 0.1)
				(type default)
			)
			(layer "F.Fab")
		)
		(fp_line
			(start 1.1049 0.724916)
			(end 1.1049 -0.724916)
			(stroke
				(width 0.1)
				(type default)
			)
			(layer "F.Fab")
		)
		(pad "1" smd rect
			(at -0.889 0 180)
			(size 1.016 1.27)
			(layers "F.Cu" "F.Mask" "F.Paste")
			(net "PVCCIN_CPU1")
		)
		(pad "2" smd rect
			(at 0.889 0 180)
			(size 1.016 1.27)
			(layers "F.Cu" "F.Mask" "F.Paste")
			(net "GND")
		)
	)
	(footprint ""
		(layer "F.Cu")
		(at 54.242716 -113.97869 180)
		(property "Reference" "R3714"
			(at 0 0 180)
			(layer "F.SilkS")
			(hide yes)
			(effects
				(font
					(size 1.27 1.27)
				)
			)
		)
		(property "Value" ""
			(at 0 0 180)
			(layer "F.Fab")
			(effects
				(font
					(size 1.27 1.27)
				)
			)
		)
		(duplicate_pad_numbers_are_jumpers no)
		(fp_line
			(start 0.7874 0.4064)
			(end -0.7874 0.4064)
			(stroke
				(width 0.1524)
				(type default)
			)
			(layer "F.SilkS")
		)
		(fp_line
			(start 0.7874 -0.4064)
			(end 0.7874 0.4064)
			(stroke
				(width 0.1524)
				(type default)
			)
			(layer "F.SilkS")
		)
		(fp_line
			(start -0.7874 0.4064)
			(end -0.7874 -0.4064)
			(stroke
				(width 0.1524)
				(type default)
			)
			(layer "F.SilkS")
		)
		(fp_line
			(start -0.7874 -0.4064)
			(end 0.7874 -0.4064)
			(stroke
				(width 0.1524)
				(type default)
			)
			(layer "F.SilkS")
		)
		(fp_line
			(start 0.67945 0.3048)
			(end 0.120396 0.3048)
			(stroke
				(width 0.1)
				(type default)
			)
			(layer "F.Fab")
		)
		(fp_line
			(start 0.67945 -0.3048)
			(end 0.67945 0.3048)
			(stroke
				(width 0.1)
				(type default)
			)
			(layer "F.Fab")
		)
		(fp_line
			(start 0.12065 -0.2794)
			(end 0.12065 -0.3048)
			(stroke
				(width 0.1)
				(type default)
			)
			(layer "F.Fab")
		)
		(fp_line
			(start 0.12065 -0.3048)
			(end 0.67945 -0.3048)
			(stroke
				(width 0.1)
				(type default)
			)
			(layer "F.Fab")
		)
		(fp_line
			(start 0.120396 0.3048)
			(end 0.120396 0.2794)
			(stroke
				(width 0.1)
				(type default)
			)
			(layer "F.Fab")
		)
		(fp_line
			(start 0.120396 0.2794)
			(end -0.12065 0.2794)
			(stroke
				(width 0.1)
				(type default)
			)
			(layer "F.Fab")
		)
		(fp_line
			(start -0.12065 0.3048)
			(end -0.67945 0.3048)
			(stroke
				(width 0.1)
				(type default)
			)
			(layer "F.Fab")
		)
		(fp_line
			(start -0.12065 0.2794)
			(end -0.12065 0.3048)
			(stroke
				(width 0.1)
				(type default)
			)
			(layer "F.Fab")
		)
		(fp_line
			(start -0.12065 -0.2794)
			(end 0.12065 -0.2794)
			(stroke
				(width 0.1)
				(type default)
			)
			(layer "F.Fab")
		)
		(fp_line
			(start -0.12065 -0.305054)
			(end -0.12065 -0.2794)
			(stroke
				(width 0.1)
				(type default)
			)
			(layer "F.Fab")
		)
		(fp_line
			(start -0.67945 0.3048)
			(end -0.67945 -0.305054)
			(stroke
				(width 0.1)
				(type default)
			)
			(layer "F.Fab")
		)
		(fp_line
			(start -0.67945 -0.305054)
			(end -0.12065 -0.305054)
			(stroke
				(width 0.1)
				(type default)
			)
			(layer "F.Fab")
		)
		(pad "1" smd circle
			(at -0.40005 0 180)
			(size 0 0)
			(layers "F.Cu" "F.Mask" "F.Paste")
			(net "SMB_VR_3V3AUX_SDA_R6")
		)
		(pad "2" smd circle
			(at 0.40005 0 180)
			(size 0 0)
			(layers "F.Cu" "F.Mask" "F.Paste")
			(net "SMB_VR_3V3AUX_SDA")
		)
	)
	(footprint ""
		(layer "F.Cu")
		(at 110.485682 -338.298028 -90)
		(property "Reference" "PC1359"
			(at 0 0 270)
			(layer "F.SilkS")
			(hide yes)
			(effects
				(font
					(size 1.27 1.27)
				)
			)
		)
		(property "Value" ""
			(at 0 0 270)
			(layer "F.Fab")
			(effects
				(font
					(size 1.27 1.27)
				)
			)
		)
		(duplicate_pad_numbers_are_jumpers no)
		(fp_line
			(start -0.7874 0.4064)
			(end -0.7874 -0.4064)
			(stroke
				(width 0.1524)
				(type default)
			)
			(layer "F.SilkS")
		)
		(fp_line
			(start 0.7874 0.4064)
			(end -0.7874 0.4064)
			(stroke
				(width 0.1524)
				(type default)
			)
			(layer "F.SilkS")
		)
		(fp_line
			(start -0.7874 -0.4064)
			(end 0.7874 -0.4064)
			(stroke
				(width 0.1524)
				(type default)
			)
			(layer "F.SilkS")
		)
		(fp_line
			(start 0.7874 -0.4064)
			(end 0.7874 0.4064)
			(stroke
				(width 0.1524)
				(type default)
			)
			(layer "F.SilkS")
		)
		(fp_line
			(start -0.67945 0.3048)
			(end -0.67945 -0.305054)
			(stroke
				(width 0.1)
				(type default)
			)
			(layer "F.Fab")
		)
		(fp_line
			(start -0.12065 0.3048)
			(end -0.67945 0.3048)
			(stroke
				(width 0.1)
				(type default)
			)
			(layer "F.Fab")
		)
		(fp_line
			(start 0.120396 0.3048)
			(end 0.120396 0.2794)
			(stroke
				(width 0.1)
				(type default)
			)
			(layer "F.Fab")
		)
		(fp_line
			(start 0.67945 0.3048)
			(end 0.120396 0.3048)
			(stroke
				(width 0.1)
				(type default)
			)
			(layer "F.Fab")
		)
		(fp_line
			(start -0.12065 0.2794)
			(end -0.12065 0.3048)
			(stroke
				(width 0.1)
				(type default)
			)
			(layer "F.Fab")
		)
		(fp_line
			(start 0.120396 0.2794)
			(end -0.12065 0.2794)
			(stroke
				(width 0.1)
				(type default)
			)
			(layer "F.Fab")
		)
		(fp_line
			(start -0.12065 -0.2794)
			(end 0.12065 -0.2794)
			(stroke
				(width 0.1)
				(type default)
			)
			(layer "F.Fab")
		)
		(fp_line
			(start 0.12065 -0.2794)
			(end 0.12065 -0.3048)
			(stroke
				(width 0.1)
				(type default)
			)
			(layer "F.Fab")
		)
		(fp_line
			(start 0.12065 -0.3048)
			(end 0.67945 -0.3048)
			(stroke
				(width 0.1)
				(type default)
			)
			(layer "F.Fab")
		)
		(fp_line
			(start 0.67945 -0.3048)
			(end 0.67945 0.3048)
			(stroke
				(width 0.1)
				(type default)
			)
			(layer "F.Fab")
		)
		(fp_line
			(start -0.67945 -0.305054)
			(end -0.12065 -0.305054)
			(stroke
				(width 0.1)
				(type default)
			)
			(layer "F.Fab")
		)
		(fp_line
			(start -0.12065 -0.305054)
			(end -0.12065 -0.2794)
			(stroke
				(width 0.1)
				(type default)
			)
			(layer "F.Fab")
		)
		(pad "1" smd circle
			(at -0.40005 0 270)
			(size 0 0)
			(layers "F.Cu" "F.Mask" "F.Paste")
			(net "GND")
		)
		(pad "2" smd circle
			(at 0.40005 0 270)
			(size 0 0)
			(layers "F.Cu" "F.Mask" "F.Paste")
			(net "PVCCIN_CPU1_VREF")
		)
	)
	(footprint ""
		(layer "F.Cu")
		(at 273.218148 -258.091686)
		(property "Reference" "J5"
			(at -3.683 -81.702148 0)
			(unlocked yes)
			(layer "F.SilkS")
			(effects
				(font
					(size 0.7874 0.5842)
					(thickness 0.1524)
				)
				(justify left)
			)
		)
		(property "Value" ""
			(at 0 0 0)
			(layer "F.Fab")
			(effects
				(font
					(size 1.27 1.27)
				)
			)
		)
		(duplicate_pad_numbers_are_jumpers no)
		(fp_line
			(start -3.24993 -81.000092)
			(end -3.24993 75.300078)
			(stroke
				(width 0.1524)
				(type default)
			)
			(layer "F.SilkS")
		)
		(fp_line
			(start 3.24993 -81.000092)
			(end -3.24993 -81.000092)
			(stroke
				(width 0.1524)
				(type default)
			)
			(layer "F.SilkS")
		)
		(fp_line
			(start 3.24993 -72.00011)
			(end -3.24993 -72.00011)
			(stroke
				(width 0.1524)
				(type default)
			)
			(layer "F.SilkS")
		)
		(fp_line
			(start 3.24993 72.00011)
			(end -3.24993 72.00011)
			(stroke
				(width 0.1524)
				(type default)
			)
			(layer "F.SilkS")
		)
		(fp_line
			(start 3.24993 78.005178)
			(end 3.24993 -81.000092)
			(stroke
				(width 0.1524)
				(type default)
			)
			(layer "F.SilkS")
		)
		(fp_poly
			(pts
				(xy -4.205224 -63.886842) (xy -3.333496 -63.450978) (xy -4.205224 -63.015114)
			)
			(stroke
				(width 0)
				(type default)
			)
			(fill yes)
			(layer "F.SilkS")
		)
		(fp_line
			(start -3.24993 -81.000092)
			(end -3.24993 81.000092)
			(stroke
				(width 0.1)
				(type default)
			)
			(layer "F.Fab")
		)
		(fp_line
			(start -3.24993 81.000092)
			(end 3.24993 81.000092)
			(stroke
				(width 0.1)
				(type default)
			)
			(layer "F.Fab")
		)
		(fp_line
			(start 3.24993 -81.000092)
			(end -3.24993 -81.000092)
			(stroke
				(width 0.1)
				(type default)
			)
			(layer "F.Fab")
		)
		(fp_line
			(start 3.24993 -72.00011)
			(end -3.24993 -72.00011)
			(stroke
				(width 0.1)
				(type default)
			)
			(layer "F.Fab")
		)
		(fp_line
			(start 3.24993 -71.000112)
			(end -3.24993 -71.000112)
			(stroke
				(width 0.1)
				(type default)
			)
			(layer "F.Fab")
		)
		(fp_line
			(start 3.24993 71.000112)
			(end -3.24993 71.000112)
			(stroke
				(width 0.1)
				(type default)
			)
			(layer "F.Fab")
		)
		(fp_line
			(start 3.24993 72.00011)
			(end -3.24993 72.00011)
			(stroke
				(width 0.1)
				(type default)
			)
			(layer "F.Fab")
		)
		(fp_line
			(start 3.24993 81.000092)
			(end 3.24993 -81.000092)
			(stroke
				(width 0.1)
				(type default)
			)
			(layer "F.Fab")
		)
		(fp_poly
			(pts
				(xy -4.445 -63.832994) (xy -4.445 -62.816994) (xy -3.429 -63.324994)
			)
			(stroke
				(width 0)
				(type default)
			)
			(fill yes)
			(layer "F.Fab")
		)
		(pad "1" smd rect
			(at -2.050034 -63.324994 270)
			(size 0.519938 1.4986)
			(layers "F.Cu" "F.Mask" "F.Paste")
			(net "P12V_S3_AUX_CPU0_NVDIMM")
		)
		(pad "2" smd rect
			(at -2.050034 -62.47511 270)
			(size 0.519938 1.4986)
			(layers "F.Cu" "F.Mask" "F.Paste")
			(net "TP_CHC_CPU0_DIMM1_FRU_0")
		)
		(pad "3" smd rect
			(at -2.050034 -61.624972 270)
			(size 0.519938 1.4986)
			(layers "F.Cu" "F.Mask" "F.Paste")
			(net "P3V3_AUX")
		)
		(pad "4" smd rect
			(at -2.050034 -60.775088 270)
			(size 0.519938 1.4986)
			(layers "F.Cu" "F.Mask" "F.Paste")
			(net "I3C_SPD_DDRABCD_CPU0_LVC1_SCL_4")
		)
		(pad "5" smd rect
			(at -2.050034 -59.92495 270)
			(size 0.519938 1.4986)
			(layers "F.Cu" "F.Mask" "F.Paste")
			(net "I3C_SPD_DDRABCD_CPU0_LVC1_SDA")
		)
		(pad "6" smd rect
			(at -2.050034 -59.075066 270)
			(size 0.519938 1.4986)
			(layers "F.Cu" "F.Mask" "F.Paste")
			(net "GND")
		)
		(pad "7" smd rect
			(at -2.050034 -58.224928 270)
			(size 0.519938 1.4986)
			(layers "F.Cu" "F.Mask" "F.Paste")
			(net "M_C_CPU0_SA_DQ<0>")
		)
		(pad "8" smd rect
			(at -2.050034 -57.375044 270)
			(size 0.519938 1.4986)
			(layers "F.Cu" "F.Mask" "F.Paste")
			(net "GND")
		)
		(pad "9" smd rect
			(at -2.050034 -56.524906 270)
			(size 0.519938 1.4986)
			(layers "F.Cu" "F.Mask" "F.Paste")
			(net "M_C_CPU0_SA_DQ<1>")
		)
		(pad "10" smd rect
			(at -2.050034 -55.675022 270)
			(size 0.519938 1.4986)
			(layers "F.Cu" "F.Mask" "F.Paste")
			(net "GND")
		)
		(pad "11" smd rect
			(at -2.050034 -54.824884 270)
			(size 0.519938 1.4986)
			(layers "F.Cu" "F.Mask" "F.Paste")
			(net "M_C_CPU0_SA_DQS_DP<0>")
		)
		(pad "12" smd rect
			(at -2.050034 -53.975 270)
			(size 0.519938 1.4986)
			(layers "F.Cu" "F.Mask" "F.Paste")
			(net "M_C_CPU0_SA_DQS_DN<0>")
		)
		(pad "13" smd rect
			(at -2.050034 -53.125116 270)
			(size 0.519938 1.4986)
			(layers "F.Cu" "F.Mask" "F.Paste")
			(net "GND")
		)
		(pad "14" smd rect
			(at -2.050034 -52.274978 270)
			(size 0.519938 1.4986)
			(layers "F.Cu" "F.Mask" "F.Paste")
			(net "M_C_CPU0_SA_DQ<4>")
		)
		(pad "15" smd rect
			(at -2.050034 -51.425094 270)
			(size 0.519938 1.4986)
			(layers "F.Cu" "F.Mask" "F.Paste")
			(net "GND")
		)
		(pad "16" smd rect
			(at -2.050034 -50.574956 270)
			(size 0.519938 1.4986)
			(layers "F.Cu" "F.Mask" "F.Paste")
			(net "M_C_CPU0_SA_DQ<5>")
		)
		(pad "17" smd rect
			(at -2.050034 -49.725072 270)
			(size 0.519938 1.4986)
			(layers "F.Cu" "F.Mask" "F.Paste")
			(net "GND")
		)
		(pad "18" smd rect
			(at -2.050034 -48.874934 270)
			(size 0.519938 1.4986)
			(layers "F.Cu" "F.Mask" "F.Paste")
			(net "M_C_CPU0_SA_DQ<8>")
		)
		(pad "19" smd rect
			(at -2.050034 -48.02505 270)
			(size 0.519938 1.4986)
			(layers "F.Cu" "F.Mask" "F.Paste")
			(net "GND")
		)
		(pad "20" smd rect
			(at -2.050034 -47.174912 270)
			(size 0.519938 1.4986)
			(layers "F.Cu" "F.Mask" "F.Paste")
			(net "M_C_CPU0_SA_DQ<9>")
		)
		(pad "21" smd rect
			(at -2.050034 -46.325028 270)
			(size 0.519938 1.4986)
			(layers "F.Cu" "F.Mask" "F.Paste")
			(net "GND")
		)
		(pad "22" smd rect
			(at -2.050034 -45.47489 270)
			(size 0.519938 1.4986)
			(layers "F.Cu" "F.Mask" "F.Paste")
			(net "M_C_CPU0_SA_DQS_DP<1>")
		)
		(pad "23" smd rect
			(at -2.050034 -44.625006 270)
			(size 0.519938 1.4986)
			(layers "F.Cu" "F.Mask" "F.Paste")
			(net "M_C_CPU0_SA_DQS_DN<1>")
		)
		(pad "24" smd rect
			(at -2.050034 -43.775122 270)
			(size 0.519938 1.4986)
			(layers "F.Cu" "F.Mask" "F.Paste")
			(net "GND")
		)
		(pad "25" smd rect
			(at -2.050034 -42.924984 270)
			(size 0.519938 1.4986)
			(layers "F.Cu" "F.Mask" "F.Paste")
			(net "M_C_CPU0_SA_DQ<12>")
		)
		(pad "26" smd rect
			(at -2.050034 -42.0751 270)
			(size 0.519938 1.4986)
			(layers "F.Cu" "F.Mask" "F.Paste")
			(net "GND")
		)
		(pad "27" smd rect
			(at -2.050034 -41.224962 270)
			(size 0.519938 1.4986)
			(layers "F.Cu" "F.Mask" "F.Paste")
			(net "M_C_CPU0_SA_DQ<13>")
		)
		(pad "28" smd rect
			(at -2.050034 -40.375078 270)
			(size 0.519938 1.4986)
			(layers "F.Cu" "F.Mask" "F.Paste")
			(net "GND")
		)
		(pad "29" smd rect
			(at -2.050034 -39.52494 270)
			(size 0.519938 1.4986)
			(layers "F.Cu" "F.Mask" "F.Paste")
			(net "M_C_CPU0_SA_DQ<16>")
		)
		(pad "30" smd rect
			(at -2.050034 -38.675056 270)
			(size 0.519938 1.4986)
			(layers "F.Cu" "F.Mask" "F.Paste")
			(net "GND")
		)
		(pad "31" smd rect
			(at -2.050034 -37.824918 270)
			(size 0.519938 1.4986)
			(layers "F.Cu" "F.Mask" "F.Paste")
			(net "M_C_CPU0_SA_DQ<17>")
		)
		(pad "32" smd rect
			(at -2.050034 -36.975034 270)
			(size 0.519938 1.4986)
			(layers "F.Cu" "F.Mask" "F.Paste")
			(net "GND")
		)
		(pad "33" smd rect
			(at -2.050034 -36.124896 270)
			(size 0.519938 1.4986)
			(layers "F.Cu" "F.Mask" "F.Paste")
			(net "M_C_CPU0_SA_DQS_DP<2>")
		)
		(pad "34" smd rect
			(at -2.050034 -35.275012 270)
			(size 0.519938 1.4986)
			(layers "F.Cu" "F.Mask" "F.Paste")
			(net "M_C_CPU0_SA_DQS_DN<2>")
		)
		(pad "35" smd rect
			(at -2.050034 -34.425128 270)
			(size 0.519938 1.4986)
			(layers "F.Cu" "F.Mask" "F.Paste")
			(net "GND")
		)
		(pad "36" smd rect
			(at -2.050034 -33.57499 270)
			(size 0.519938 1.4986)
			(layers "F.Cu" "F.Mask" "F.Paste")
			(net "M_C_CPU0_SA_DQ<20>")
		)
		(pad "37" smd rect
			(at -2.050034 -32.725106 270)
			(size 0.519938 1.4986)
			(layers "F.Cu" "F.Mask" "F.Paste")
			(net "GND")
		)
		(pad "38" smd rect
			(at -2.050034 -31.874968 270)
			(size 0.519938 1.4986)
			(layers "F.Cu" "F.Mask" "F.Paste")
			(net "M_C_CPU0_SA_DQ<21>")
		)
		(pad "39" smd rect
			(at -2.050034 -31.025084 270)
			(size 0.519938 1.4986)
			(layers "F.Cu" "F.Mask" "F.Paste")
			(net "GND")
		)
		(pad "40" smd rect
			(at -2.050034 -30.174946 270)
			(size 0.519938 1.4986)
			(layers "F.Cu" "F.Mask" "F.Paste")
			(net "M_C_CPU0_SA_DQ<24>")
		)
		(pad "41" smd rect
			(at -2.050034 -29.325062 270)
			(size 0.519938 1.4986)
			(layers "F.Cu" "F.Mask" "F.Paste")
			(net "GND")
		)
		(pad "42" smd rect
			(at -2.050034 -28.474924 270)
			(size 0.519938 1.4986)
			(layers "F.Cu" "F.Mask" "F.Paste")
			(net "M_C_CPU0_SA_DQ<25>")
		)
		(pad "43" smd rect
			(at -2.050034 -27.62504 270)
			(size 0.519938 1.4986)
			(layers "F.Cu" "F.Mask" "F.Paste")
			(net "GND")
		)
		(pad "44" smd rect
			(at -2.050034 -26.774902 270)
			(size 0.519938 1.4986)
			(layers "F.Cu" "F.Mask" "F.Paste")
			(net "M_C_CPU0_SA_DQS_DP<3>")
		)
		(pad "45" smd rect
			(at -2.050034 -25.925018 270)
			(size 0.519938 1.4986)
			(layers "F.Cu" "F.Mask" "F.Paste")
			(net "M_C_CPU0_SA_DQS_DN<3>")
		)
		(pad "46" smd rect
			(at -2.050034 -25.07488 270)
			(size 0.519938 1.4986)
			(layers "F.Cu" "F.Mask" "F.Paste")
			(net "GND")
		)
		(pad "47" smd rect
			(at -2.050034 -24.224996 270)
			(size 0.519938 1.4986)
			(layers "F.Cu" "F.Mask" "F.Paste")
			(net "M_C_CPU0_SA_DQ<28>")
		)
		(pad "48" smd rect
			(at -2.050034 -23.375112 270)
			(size 0.519938 1.4986)
			(layers "F.Cu" "F.Mask" "F.Paste")
			(net "GND")
		)
		(pad "49" smd rect
			(at -2.050034 -22.524974 270)
			(size 0.519938 1.4986)
			(layers "F.Cu" "F.Mask" "F.Paste")
			(net "M_C_CPU0_SA_DQ<29>")
		)
		(pad "50" smd rect
			(at -2.050034 -21.67509 270)
			(size 0.519938 1.4986)
			(layers "F.Cu" "F.Mask" "F.Paste")
			(net "GND")
		)
		(pad "51" smd rect
			(at -2.050034 -20.824952 270)
			(size 0.519938 1.4986)
			(layers "F.Cu" "F.Mask" "F.Paste")
			(net "M_C_CPU0_SA_CB<0>")
		)
		(pad "52" smd rect
			(at -2.050034 -19.975068 270)
			(size 0.519938 1.4986)
			(layers "F.Cu" "F.Mask" "F.Paste")
			(net "GND")
		)
		(pad "53" smd rect
			(at -2.050034 -19.12493 270)
			(size 0.519938 1.4986)
			(layers "F.Cu" "F.Mask" "F.Paste")
			(net "M_C_CPU0_SA_CB<1>")
		)
		(pad "54" smd rect
			(at -2.050034 -18.275046 270)
			(size 0.519938 1.4986)
			(layers "F.Cu" "F.Mask" "F.Paste")
			(net "GND")
		)
		(pad "55" smd rect
			(at -2.050034 -17.424908 270)
			(size 0.519938 1.4986)
			(layers "F.Cu" "F.Mask" "F.Paste")
			(net "M_C_CPU0_SA_DQS_DP<4>")
		)
		(pad "56" smd rect
			(at -2.050034 -16.575024 270)
			(size 0.519938 1.4986)
			(layers "F.Cu" "F.Mask" "F.Paste")
			(net "M_C_CPU0_SA_DQS_DN<4>")
		)
		(pad "57" smd rect
			(at -2.050034 -15.724886 270)
			(size 0.519938 1.4986)
			(layers "F.Cu" "F.Mask" "F.Paste")
			(net "GND")
		)
		(pad "58" smd rect
			(at -2.050034 -14.875002 270)
			(size 0.519938 1.4986)
			(layers "F.Cu" "F.Mask" "F.Paste")
			(net "M_C_CPU0_SA_CB<4>")
		)
		(pad "59" smd rect
			(at -2.050034 -14.025118 270)
			(size 0.519938 1.4986)
			(layers "F.Cu" "F.Mask" "F.Paste")
			(net "GND")
		)
		(pad "60" smd rect
			(at -2.050034 -13.17498 270)
			(size 0.519938 1.4986)
			(layers "F.Cu" "F.Mask" "F.Paste")
			(net "M_C_CPU0_SA_CB<5>")
		)
		(pad "61" smd rect
			(at -2.050034 -12.325096 270)
			(size 0.519938 1.4986)
			(layers "F.Cu" "F.Mask" "F.Paste")
			(net "GND")
		)
		(pad "62" smd rect
			(at -2.050034 -11.474958 270)
			(size 0.519938 1.4986)
			(layers "F.Cu" "F.Mask" "F.Paste")
			(net "M_C_CPU0_ALERT_N")
		)
		(pad "63" smd rect
			(at -2.050034 -10.625074 270)
			(size 0.519938 1.4986)
			(layers "F.Cu" "F.Mask" "F.Paste")
			(net "GND")
		)
		(pad "64" smd rect
			(at -2.050034 -9.774936 270)
			(size 0.519938 1.4986)
			(layers "F.Cu" "F.Mask" "F.Paste")
			(net "M_C_CPU0_SA_CS_N<0>")
		)
		(pad "65" smd rect
			(at -2.050034 -8.925052 270)
			(size 0.519938 1.4986)
			(layers "F.Cu" "F.Mask" "F.Paste")
			(net "GND")
		)
		(pad "66" smd rect
			(at -2.050034 -8.074914 270)
			(size 0.519938 1.4986)
			(layers "F.Cu" "F.Mask" "F.Paste")
			(net "M_C_CPU0_SA_CA<0>")
		)
		(pad "67" smd rect
			(at -2.050034 -7.22503 270)
			(size 0.519938 1.4986)
			(layers "F.Cu" "F.Mask" "F.Paste")
			(net "GND")
		)
		(pad "68" smd rect
			(at -2.050034 -6.374892 270)
			(size 0.519938 1.4986)
			(layers "F.Cu" "F.Mask" "F.Paste")
			(net "M_C_CPU0_SA_CA<2>")
		)
		(pad "69" smd rect
			(at -2.050034 -5.525008 270)
			(size 0.519938 1.4986)
			(layers "F.Cu" "F.Mask" "F.Paste")
			(net "GND")
		)
		(pad "70" smd rect
			(at -2.050034 -4.675124 270)
			(size 0.519938 1.4986)
			(layers "F.Cu" "F.Mask" "F.Paste")
			(net "M_C_CPU0_SA_CA<4>")
		)
		(pad "71" smd rect
			(at -2.050034 -3.824986 270)
			(size 0.519938 1.4986)
			(layers "F.Cu" "F.Mask" "F.Paste")
			(net "GND")
		)
		(pad "72" smd rect
			(at -2.050034 -2.975102 270)
			(size 0.519938 1.4986)
			(layers "F.Cu" "F.Mask" "F.Paste")
			(net "M_C_CPU0_SA_CA<6>")
		)
		(pad "73" smd rect
			(at -2.050034 -2.124964 270)
			(size 0.519938 1.4986)
			(layers "F.Cu" "F.Mask" "F.Paste")
			(net "GND")
		)
		(pad "74" smd rect
			(at -2.050034 -1.27508 270)
			(size 0.519938 1.4986)
			(layers "F.Cu" "F.Mask" "F.Paste")
			(net "M_C_CPU0_SA_PAR")
		)
		(pad "75" smd rect
			(at -2.050034 -0.424942 270)
			(size 0.519938 1.4986)
			(layers "F.Cu" "F.Mask" "F.Paste")
			(net "GND")
		)
		(pad "76" smd rect
			(at -2.050034 5.525008 270)
			(size 0.519938 1.4986)
			(layers "F.Cu" "F.Mask" "F.Paste")
			(net "M_C_CPU0_SB_CA<0>")
		)
		(pad "77" smd rect
			(at -2.050034 6.374892 270)
			(size 0.519938 1.4986)
			(layers "F.Cu" "F.Mask" "F.Paste")
			(net "GND")
		)
		(pad "78" smd rect
			(at -2.050034 7.22503 270)
			(size 0.519938 1.4986)
			(layers "F.Cu" "F.Mask" "F.Paste")
			(net "M_C_CPU0_SB_CA<2>")
		)
		(pad "79" smd rect
			(at -2.050034 8.074914 270)
			(size 0.519938 1.4986)
			(layers "F.Cu" "F.Mask" "F.Paste")
			(net "GND")
		)
		(pad "80" smd rect
			(at -2.050034 8.925052 270)
			(size 0.519938 1.4986)
			(layers "F.Cu" "F.Mask" "F.Paste")
			(net "M_C_CPU0_SB_CA<4>")
		)
		(pad "81" smd rect
			(at -2.050034 9.774936 270)
			(size 0.519938 1.4986)
			(layers "F.Cu" "F.Mask" "F.Paste")
			(net "GND")
		)
		(pad "82" smd rect
			(at -2.050034 10.625074 270)
			(size 0.519938 1.4986)
			(layers "F.Cu" "F.Mask" "F.Paste")
			(net "M_C_CPU0_SB_CA<6>")
		)
		(pad "83" smd rect
			(at -2.050034 11.474958 270)
			(size 0.519938 1.4986)
			(layers "F.Cu" "F.Mask" "F.Paste")
			(net "GND")
		)
		(pad "84" smd rect
			(at -2.050034 12.325096 270)
			(size 0.519938 1.4986)
			(layers "F.Cu" "F.Mask" "F.Paste")
			(net "M_C_CPU0_SB_CS_N<0>")
		)
		(pad "85" smd rect
			(at -2.050034 13.17498 270)
			(size 0.519938 1.4986)
			(layers "F.Cu" "F.Mask" "F.Paste")
			(net "GND")
		)
		(pad "86" smd rect
			(at -2.050034 14.025118 270)
			(size 0.519938 1.4986)
			(layers "F.Cu" "F.Mask" "F.Paste")
			(net "M_C_CPU0_SA_RSP<0>")
		)
		(pad "87" smd rect
			(at -2.050034 14.875002 270)
			(size 0.519938 1.4986)
			(layers "F.Cu" "F.Mask" "F.Paste")
			(net "M_C_CPU0_SB_RSP<0>")
		)
		(pad "88" smd rect
			(at -2.050034 15.724886 270)
			(size 0.519938 1.4986)
			(layers "F.Cu" "F.Mask" "F.Paste")
			(net "GND")
		)
		(pad "89" smd rect
			(at -2.050034 16.575024 270)
			(size 0.519938 1.4986)
			(layers "F.Cu" "F.Mask" "F.Paste")
			(net "M_C_CPU0_SB_CB<4>")
		)
		(pad "90" smd rect
			(at -2.050034 17.424908 270)
			(size 0.519938 1.4986)
			(layers "F.Cu" "F.Mask" "F.Paste")
			(net "GND")
		)
		(pad "91" smd rect
			(at -2.050034 18.275046 270)
			(size 0.519938 1.4986)
			(layers "F.Cu" "F.Mask" "F.Paste")
			(net "M_C_CPU0_SB_CB<5>")
		)
		(pad "92" smd rect
			(at -2.050034 19.12493 270)
			(size 0.519938 1.4986)
			(layers "F.Cu" "F.Mask" "F.Paste")
			(net "GND")
		)
		(pad "93" smd rect
			(at -2.050034 19.975068 270)
			(size 0.519938 1.4986)
			(layers "F.Cu" "F.Mask" "F.Paste")
			(net "M_C_CPU0_SB_DQS_DP<9>")
		)
		(pad "94" smd rect
			(at -2.050034 20.824952 270)
			(size 0.519938 1.4986)
			(layers "F.Cu" "F.Mask" "F.Paste")
			(net "M_C_CPU0_SB_DQS_DN<9>")
		)
		(pad "95" smd rect
			(at -2.050034 21.67509 270)
			(size 0.519938 1.4986)
			(layers "F.Cu" "F.Mask" "F.Paste")
			(net "GND")
		)
		(pad "96" smd rect
			(at -2.050034 22.524974 270)
			(size 0.519938 1.4986)
			(layers "F.Cu" "F.Mask" "F.Paste")
			(net "M_C_CPU0_SB_CB<0>")
		)
		(pad "97" smd rect
			(at -2.050034 23.375112 270)
			(size 0.519938 1.4986)
			(layers "F.Cu" "F.Mask" "F.Paste")
			(net "GND")
		)
		(pad "98" smd rect
			(at -2.050034 24.224996 270)
			(size 0.519938 1.4986)
			(layers "F.Cu" "F.Mask" "F.Paste")
			(net "M_C_CPU0_SB_CB<1>")
		)
		(pad "99" smd rect
			(at -2.050034 25.07488 270)
			(size 0.519938 1.4986)
			(layers "F.Cu" "F.Mask" "F.Paste")
			(net "GND")
		)
		(pad "100" smd rect
			(at -2.050034 25.925018 270)
			(size 0.519938 1.4986)
			(layers "F.Cu" "F.Mask" "F.Paste")
			(net "M_C_CPU0_SB_DQ<0>")
		)
		(pad "101" smd rect
			(at -2.050034 26.774902 270)
			(size 0.519938 1.4986)
			(layers "F.Cu" "F.Mask" "F.Paste")
			(net "GND")
		)
		(pad "102" smd rect
			(at -2.050034 27.62504 270)
			(size 0.519938 1.4986)
			(layers "F.Cu" "F.Mask" "F.Paste")
			(net "M_C_CPU0_SB_DQ<1>")
		)
		(pad "103" smd rect
			(at -2.050034 28.474924 270)
			(size 0.519938 1.4986)
			(layers "F.Cu" "F.Mask" "F.Paste")
			(net "GND")
		)
		(pad "104" smd rect
			(at -2.050034 29.325062 270)
			(size 0.519938 1.4986)
			(layers "F.Cu" "F.Mask" "F.Paste")
			(net "M_C_CPU0_SB_DQS_DP<0>")
		)
		(pad "105" smd rect
			(at -2.050034 30.174946 270)
			(size 0.519938 1.4986)
			(layers "F.Cu" "F.Mask" "F.Paste")
			(net "M_C_CPU0_SB_DQS_DN<0>")
		)
		(pad "106" smd rect
			(at -2.050034 31.025084 270)
			(size 0.519938 1.4986)
			(layers "F.Cu" "F.Mask" "F.Paste")
			(net "GND")
		)
		(pad "107" smd rect
			(at -2.050034 31.874968 270)
			(size 0.519938 1.4986)
			(layers "F.Cu" "F.Mask" "F.Paste")
			(net "M_C_CPU0_SB_DQ<4>")
		)
		(pad "108" smd rect
			(at -2.050034 32.725106 270)
			(size 0.519938 1.4986)
			(layers "F.Cu" "F.Mask" "F.Paste")
			(net "GND")
		)
		(pad "109" smd rect
			(at -2.050034 33.57499 270)
			(size 0.519938 1.4986)
			(layers "F.Cu" "F.Mask" "F.Paste")
			(net "M_C_CPU0_SB_DQ<5>")
		)
		(pad "110" smd rect
			(at -2.050034 34.425128 270)
			(size 0.519938 1.4986)
			(layers "F.Cu" "F.Mask" "F.Paste")
			(net "GND")
		)
		(pad "111" smd rect
			(at -2.050034 35.275012 270)
			(size 0.519938 1.4986)
			(layers "F.Cu" "F.Mask" "F.Paste")
			(net "M_C_CPU0_SB_DQ<8>")
		)
		(pad "112" smd rect
			(at -2.050034 36.124896 270)
			(size 0.519938 1.4986)
			(layers "F.Cu" "F.Mask" "F.Paste")
			(net "GND")
		)
		(pad "113" smd rect
			(at -2.050034 36.975034 270)
			(size 0.519938 1.4986)
			(layers "F.Cu" "F.Mask" "F.Paste")
			(net "M_C_CPU0_SB_DQ<9>")
		)
		(pad "114" smd rect
			(at -2.050034 37.824918 270)
			(size 0.519938 1.4986)
			(layers "F.Cu" "F.Mask" "F.Paste")
			(net "GND")
		)
		(pad "115" smd rect
			(at -2.050034 38.675056 270)
			(size 0.519938 1.4986)
			(layers "F.Cu" "F.Mask" "F.Paste")
			(net "M_C_CPU0_SB_DQS_DP<1>")
		)
		(pad "116" smd rect
			(at -2.050034 39.52494 270)
			(size 0.519938 1.4986)
			(layers "F.Cu" "F.Mask" "F.Paste")
			(net "M_C_CPU0_SB_DQS_DN<1>")
		)
		(pad "117" smd rect
			(at -2.050034 40.375078 270)
			(size 0.519938 1.4986)
			(layers "F.Cu" "F.Mask" "F.Paste")
			(net "GND")
		)
		(pad "118" smd rect
			(at -2.050034 41.224962 270)
			(size 0.519938 1.4986)
			(layers "F.Cu" "F.Mask" "F.Paste")
			(net "M_C_CPU0_SB_DQ<12>")
		)
		(pad "119" smd rect
			(at -2.050034 42.0751 270)
			(size 0.519938 1.4986)
			(layers "F.Cu" "F.Mask" "F.Paste")
			(net "GND")
		)
		(pad "120" smd rect
			(at -2.050034 42.924984 270)
			(size 0.519938 1.4986)
			(layers "F.Cu" "F.Mask" "F.Paste")
			(net "M_C_CPU0_SB_DQ<13>")
		)
		(pad "121" smd rect
			(at -2.050034 43.775122 270)
			(size 0.519938 1.4986)
			(layers "F.Cu" "F.Mask" "F.Paste")
			(net "GND")
		)
		(pad "122" smd rect
			(at -2.050034 44.625006 270)
			(size 0.519938 1.4986)
			(layers "F.Cu" "F.Mask" "F.Paste")
			(net "M_C_CPU0_SB_DQ<16>")
		)
		(pad "123" smd rect
			(at -2.050034 45.47489 270)
			(size 0.519938 1.4986)
			(layers "F.Cu" "F.Mask" "F.Paste")
			(net "GND")
		)
		(pad "124" smd rect
			(at -2.050034 46.325028 270)
			(size 0.519938 1.4986)
			(layers "F.Cu" "F.Mask" "F.Paste")
			(net "M_C_CPU0_SB_DQ<17>")
		)
		(pad "125" smd rect
			(at -2.050034 47.174912 270)
			(size 0.519938 1.4986)
			(layers "F.Cu" "F.Mask" "F.Paste")
			(net "GND")
		)
		(pad "126" smd rect
			(at -2.050034 48.02505 270)
			(size 0.519938 1.4986)
			(layers "F.Cu" "F.Mask" "F.Paste")
			(net "M_C_CPU0_SB_DQS_DP<2>")
		)
		(pad "127" smd rect
			(at -2.050034 48.874934 270)
			(size 0.519938 1.4986)
			(layers "F.Cu" "F.Mask" "F.Paste")
			(net "M_C_CPU0_SB_DQS_DN<2>")
		)
		(pad "128" smd rect
			(at -2.050034 49.725072 270)
			(size 0.519938 1.4986)
			(layers "F.Cu" "F.Mask" "F.Paste")
			(net "GND")
		)
		(pad "129" smd rect
			(at -2.050034 50.574956 270)
			(size 0.519938 1.4986)
			(layers "F.Cu" "F.Mask" "F.Paste")
			(net "M_C_CPU0_SB_DQ<20>")
		)
		(pad "130" smd rect
			(at -2.050034 51.425094 270)
			(size 0.519938 1.4986)
			(layers "F.Cu" "F.Mask" "F.Paste")
			(net "GND")
		)
		(pad "131" smd rect
			(at -2.050034 52.274978 270)
			(size 0.519938 1.4986)
			(layers "F.Cu" "F.Mask" "F.Paste")
			(net "M_C_CPU0_SB_DQ<21>")
		)
		(pad "132" smd rect
			(at -2.050034 53.125116 270)
			(size 0.519938 1.4986)
			(layers "F.Cu" "F.Mask" "F.Paste")
			(net "GND")
		)
		(pad "133" smd rect
			(at -2.050034 53.975 270)
			(size 0.519938 1.4986)
			(layers "F.Cu" "F.Mask" "F.Paste")
			(net "M_C_CPU0_SB_DQ<24>")
		)
		(pad "134" smd rect
			(at -2.050034 54.824884 270)
			(size 0.519938 1.4986)
			(layers "F.Cu" "F.Mask" "F.Paste")
			(net "GND")
		)
		(pad "135" smd rect
			(at -2.050034 55.675022 270)
			(size 0.519938 1.4986)
			(layers "F.Cu" "F.Mask" "F.Paste")
			(net "M_C_CPU0_SB_DQ<25>")
		)
		(pad "136" smd rect
			(at -2.050034 56.524906 270)
			(size 0.519938 1.4986)
			(layers "F.Cu" "F.Mask" "F.Paste")
			(net "GND")
		)
		(pad "137" smd rect
			(at -2.050034 57.375044 270)
			(size 0.519938 1.4986)
			(layers "F.Cu" "F.Mask" "F.Paste")
			(net "M_C_CPU0_SB_DQS_DP<3>")
		)
		(pad "138" smd rect
			(at -2.050034 58.224928 270)
			(size 0.519938 1.4986)
			(layers "F.Cu" "F.Mask" "F.Paste")
			(net "M_C_CPU0_SB_DQS_DN<3>")
		)
		(pad "139" smd rect
			(at -2.050034 59.075066 270)
			(size 0.519938 1.4986)
			(layers "F.Cu" "F.Mask" "F.Paste")
			(net "GND")
		)
		(pad "140" smd rect
			(at -2.050034 59.92495 270)
			(size 0.519938 1.4986)
			(layers "F.Cu" "F.Mask" "F.Paste")
			(net "M_C_CPU0_SB_DQ<28>")
		)
		(pad "141" smd rect
			(at -2.050034 60.775088 270)
			(size 0.519938 1.4986)
			(layers "F.Cu" "F.Mask" "F.Paste")
			(net "GND")
		)
		(pad "142" smd rect
			(at -2.050034 61.624972 270)
			(size 0.519938 1.4986)
			(layers "F.Cu" "F.Mask" "F.Paste")
			(net "M_C_CPU0_SB_DQ<29>")
		)
		(pad "143" smd rect
			(at -2.050034 62.47511 270)
			(size 0.519938 1.4986)
			(layers "F.Cu" "F.Mask" "F.Paste")
			(net "GND")
		)
		(pad "144" smd rect
			(at -2.050034 63.324994 270)
			(size 0.519938 1.4986)
			(layers "F.Cu" "F.Mask" "F.Paste")
			(net "TP_CHC_CPU0_DIMM1_FRU_1")
		)
		(pad "145" smd rect
			(at 2.050034 -63.324994 270)
			(size 0.519938 1.4986)
			(layers "F.Cu" "F.Mask" "F.Paste")
			(net "P12V_S3_AUX_CPU0_NVDIMM")
		)
		(pad "146" smd rect
			(at 2.050034 -62.47511 270)
			(size 0.519938 1.4986)
			(layers "F.Cu" "F.Mask" "F.Paste")
			(net "P12V_S3_AUX_CPU0_NVDIMM")
		)
		(pad "147" smd rect
			(at 2.050034 -61.624972 270)
			(size 0.519938 1.4986)
			(layers "F.Cu" "F.Mask" "F.Paste")
			(net "PWRGD_CHC_CPU0_DIMM1")
		)
		(pad "148" smd rect
			(at 2.050034 -60.775088 270)
			(size 0.519938 1.4986)
			(layers "F.Cu" "F.Mask" "F.Paste")
			(net "PD_CHC_CPU0_DIMM1_SAA")
		)
		(pad "149" smd rect
			(at 2.050034 -59.92495 270)
			(size 0.519938 1.4986)
			(layers "F.Cu" "F.Mask" "F.Paste")
			(net "TP_CHC_CPU0_DIMM1_FRU_2")
		)
		(pad "150" smd rect
			(at 2.050034 -59.075066 270)
			(size 0.519938 1.4986)
			(layers "F.Cu" "F.Mask" "F.Paste")
			(net "TP_CHC_CPU0_DIMM1_FRU_3")
		)
		(pad "151" smd rect
			(at 2.050034 -58.224928 270)
			(size 0.519938 1.4986)
			(layers "F.Cu" "F.Mask" "F.Paste")
			(net "GND")
		)
		(pad "152" smd rect
			(at 2.050034 -57.375044 270)
			(size 0.519938 1.4986)
			(layers "F.Cu" "F.Mask" "F.Paste")
			(net "M_C_CPU0_SA_DQ<2>")
		)
		(pad "153" smd rect
			(at 2.050034 -56.524906 270)
			(size 0.519938 1.4986)
			(layers "F.Cu" "F.Mask" "F.Paste")
			(net "GND")
		)
		(pad "154" smd rect
			(at 2.050034 -55.675022 270)
			(size 0.519938 1.4986)
			(layers "F.Cu" "F.Mask" "F.Paste")
			(net "M_C_CPU0_SA_DQ<3>")
		)
		(pad "155" smd rect
			(at 2.050034 -54.824884 270)
			(size 0.519938 1.4986)
			(layers "F.Cu" "F.Mask" "F.Paste")
			(net "GND")
		)
		(pad "156" smd rect
			(at 2.050034 -53.975 270)
			(size 0.519938 1.4986)
			(layers "F.Cu" "F.Mask" "F.Paste")
			(net "M_C_CPU0_SA_DQS_DN<5>")
		)
		(pad "157" smd rect
			(at 2.050034 -53.125116 270)
			(size 0.519938 1.4986)
			(layers "F.Cu" "F.Mask" "F.Paste")
			(net "M_C_CPU0_SA_DQS_DP<5>")
		)
		(pad "158" smd rect
			(at 2.050034 -52.274978 270)
			(size 0.519938 1.4986)
			(layers "F.Cu" "F.Mask" "F.Paste")
			(net "GND")
		)
		(pad "159" smd rect
			(at 2.050034 -51.425094 270)
			(size 0.519938 1.4986)
			(layers "F.Cu" "F.Mask" "F.Paste")
			(net "M_C_CPU0_SA_DQ<6>")
		)
		(pad "160" smd rect
			(at 2.050034 -50.574956 270)
			(size 0.519938 1.4986)
			(layers "F.Cu" "F.Mask" "F.Paste")
			(net "GND")
		)
		(pad "161" smd rect
			(at 2.050034 -49.725072 270)
			(size 0.519938 1.4986)
			(layers "F.Cu" "F.Mask" "F.Paste")
			(net "M_C_CPU0_SA_DQ<7>")
		)
		(pad "162" smd rect
			(at 2.050034 -48.874934 270)
			(size 0.519938 1.4986)
			(layers "F.Cu" "F.Mask" "F.Paste")
			(net "GND")
		)
		(pad "163" smd rect
			(at 2.050034 -48.02505 270)
			(size 0.519938 1.4986)
			(layers "F.Cu" "F.Mask" "F.Paste")
			(net "M_C_CPU0_SA_DQ<10>")
		)
		(pad "164" smd rect
			(at 2.050034 -47.174912 270)
			(size 0.519938 1.4986)
			(layers "F.Cu" "F.Mask" "F.Paste")
			(net "GND")
		)
		(pad "165" smd rect
			(at 2.050034 -46.325028 270)
			(size 0.519938 1.4986)
			(layers "F.Cu" "F.Mask" "F.Paste")
			(net "M_C_CPU0_SA_DQ<11>")
		)
		(pad "166" smd rect
			(at 2.050034 -45.47489 270)
			(size 0.519938 1.4986)
			(layers "F.Cu" "F.Mask" "F.Paste")
			(net "GND")
		)
		(pad "167" smd rect
			(at 2.050034 -44.625006 270)
			(size 0.519938 1.4986)
			(layers "F.Cu" "F.Mask" "F.Paste")
			(net "M_C_CPU0_SA_DQS_DN<6>")
		)
		(pad "168" smd rect
			(at 2.050034 -43.775122 270)
			(size 0.519938 1.4986)
			(layers "F.Cu" "F.Mask" "F.Paste")
			(net "M_C_CPU0_SA_DQS_DP<6>")
		)
		(pad "169" smd rect
			(at 2.050034 -42.924984 270)
			(size 0.519938 1.4986)
			(layers "F.Cu" "F.Mask" "F.Paste")
			(net "GND")
		)
		(pad "170" smd rect
			(at 2.050034 -42.0751 270)
			(size 0.519938 1.4986)
			(layers "F.Cu" "F.Mask" "F.Paste")
			(net "M_C_CPU0_SA_DQ<14>")
		)
		(pad "171" smd rect
			(at 2.050034 -41.224962 270)
			(size 0.519938 1.4986)
			(layers "F.Cu" "F.Mask" "F.Paste")
			(net "GND")
		)
		(pad "172" smd rect
			(at 2.050034 -40.375078 270)
			(size 0.519938 1.4986)
			(layers "F.Cu" "F.Mask" "F.Paste")
			(net "M_C_CPU0_SA_DQ<15>")
		)
		(pad "173" smd rect
			(at 2.050034 -39.52494 270)
			(size 0.519938 1.4986)
			(layers "F.Cu" "F.Mask" "F.Paste")
			(net "GND")
		)
		(pad "174" smd rect
			(at 2.050034 -38.675056 270)
			(size 0.519938 1.4986)
			(layers "F.Cu" "F.Mask" "F.Paste")
			(net "M_C_CPU0_SA_DQ<18>")
		)
		(pad "175" smd rect
			(at 2.050034 -37.824918 270)
			(size 0.519938 1.4986)
			(layers "F.Cu" "F.Mask" "F.Paste")
			(net "GND")
		)
		(pad "176" smd rect
			(at 2.050034 -36.975034 270)
			(size 0.519938 1.4986)
			(layers "F.Cu" "F.Mask" "F.Paste")
			(net "M_C_CPU0_SA_DQ<19>")
		)
		(pad "177" smd rect
			(at 2.050034 -36.124896 270)
			(size 0.519938 1.4986)
			(layers "F.Cu" "F.Mask" "F.Paste")
			(net "GND")
		)
		(pad "178" smd rect
			(at 2.050034 -35.275012 270)
			(size 0.519938 1.4986)
			(layers "F.Cu" "F.Mask" "F.Paste")
			(net "M_C_CPU0_SA_DQS_DN<7>")
		)
		(pad "179" smd rect
			(at 2.050034 -34.425128 270)
			(size 0.519938 1.4986)
			(layers "F.Cu" "F.Mask" "F.Paste")
			(net "M_C_CPU0_SA_DQS_DP<7>")
		)
		(pad "180" smd rect
			(at 2.050034 -33.57499 270)
			(size 0.519938 1.4986)
			(layers "F.Cu" "F.Mask" "F.Paste")
			(net "GND")
		)
		(pad "181" smd rect
			(at 2.050034 -32.725106 270)
			(size 0.519938 1.4986)
			(layers "F.Cu" "F.Mask" "F.Paste")
			(net "M_C_CPU0_SA_DQ<22>")
		)
		(pad "182" smd rect
			(at 2.050034 -31.874968 270)
			(size 0.519938 1.4986)
			(layers "F.Cu" "F.Mask" "F.Paste")
			(net "GND")
		)
		(pad "183" smd rect
			(at 2.050034 -31.025084 270)
			(size 0.519938 1.4986)
			(layers "F.Cu" "F.Mask" "F.Paste")
			(net "M_C_CPU0_SA_DQ<23>")
		)
		(pad "184" smd rect
			(at 2.050034 -30.174946 270)
			(size 0.519938 1.4986)
			(layers "F.Cu" "F.Mask" "F.Paste")
			(net "GND")
		)
		(pad "185" smd rect
			(at 2.050034 -29.325062 270)
			(size 0.519938 1.4986)
			(layers "F.Cu" "F.Mask" "F.Paste")
			(net "M_C_CPU0_SA_DQ<26>")
		)
		(pad "186" smd rect
			(at 2.050034 -28.474924 270)
			(size 0.519938 1.4986)
			(layers "F.Cu" "F.Mask" "F.Paste")
			(net "GND")
		)
		(pad "187" smd rect
			(at 2.050034 -27.62504 270)
			(size 0.519938 1.4986)
			(layers "F.Cu" "F.Mask" "F.Paste")
			(net "M_C_CPU0_SA_DQ<27>")
		)
		(pad "188" smd rect
			(at 2.050034 -26.774902 270)
			(size 0.519938 1.4986)
			(layers "F.Cu" "F.Mask" "F.Paste")
			(net "GND")
		)
		(pad "189" smd rect
			(at 2.050034 -25.925018 270)
			(size 0.519938 1.4986)
			(layers "F.Cu" "F.Mask" "F.Paste")
			(net "M_C_CPU0_SA_DQS_DN<8>")
		)
		(pad "190" smd rect
			(at 2.050034 -25.07488 270)
			(size 0.519938 1.4986)
			(layers "F.Cu" "F.Mask" "F.Paste")
			(net "M_C_CPU0_SA_DQS_DP<8>")
		)
		(pad "191" smd rect
			(at 2.050034 -24.224996 270)
			(size 0.519938 1.4986)
			(layers "F.Cu" "F.Mask" "F.Paste")
			(net "GND")
		)
		(pad "192" smd rect
			(at 2.050034 -23.375112 270)
			(size 0.519938 1.4986)
			(layers "F.Cu" "F.Mask" "F.Paste")
			(net "M_C_CPU0_SA_DQ<30>")
		)
		(pad "193" smd rect
			(at 2.050034 -22.524974 270)
			(size 0.519938 1.4986)
			(layers "F.Cu" "F.Mask" "F.Paste")
			(net "GND")
		)
		(pad "194" smd rect
			(at 2.050034 -21.67509 270)
			(size 0.519938 1.4986)
			(layers "F.Cu" "F.Mask" "F.Paste")
			(net "M_C_CPU0_SA_DQ<31>")
		)
		(pad "195" smd rect
			(at 2.050034 -20.824952 270)
			(size 0.519938 1.4986)
			(layers "F.Cu" "F.Mask" "F.Paste")
			(net "GND")
		)
		(pad "196" smd rect
			(at 2.050034 -19.975068 270)
			(size 0.519938 1.4986)
			(layers "F.Cu" "F.Mask" "F.Paste")
			(net "M_C_CPU0_SA_CB<2>")
		)
		(pad "197" smd rect
			(at 2.050034 -19.12493 270)
			(size 0.519938 1.4986)
			(layers "F.Cu" "F.Mask" "F.Paste")
			(net "GND")
		)
		(pad "198" smd rect
			(at 2.050034 -18.275046 270)
			(size 0.519938 1.4986)
			(layers "F.Cu" "F.Mask" "F.Paste")
			(net "M_C_CPU0_SA_CB<3>")
		)
		(pad "199" smd rect
			(at 2.050034 -17.424908 270)
			(size 0.519938 1.4986)
			(layers "F.Cu" "F.Mask" "F.Paste")
			(net "GND")
		)
		(pad "200" smd rect
			(at 2.050034 -16.575024 270)
			(size 0.519938 1.4986)
			(layers "F.Cu" "F.Mask" "F.Paste")
			(net "M_C_CPU0_SA_DQS_DN<9>")
		)
		(pad "201" smd rect
			(at 2.050034 -15.724886 270)
			(size 0.519938 1.4986)
			(layers "F.Cu" "F.Mask" "F.Paste")
			(net "M_C_CPU0_SA_DQS_DP<9>")
		)
		(pad "202" smd rect
			(at 2.050034 -14.875002 270)
			(size 0.519938 1.4986)
			(layers "F.Cu" "F.Mask" "F.Paste")
			(net "GND")
		)
		(pad "203" smd rect
			(at 2.050034 -14.025118 270)
			(size 0.519938 1.4986)
			(layers "F.Cu" "F.Mask" "F.Paste")
			(net "M_C_CPU0_SA_CB<6>")
		)
		(pad "204" smd rect
			(at 2.050034 -13.17498 270)
			(size 0.519938 1.4986)
			(layers "F.Cu" "F.Mask" "F.Paste")
			(net "GND")
		)
		(pad "205" smd rect
			(at 2.050034 -12.325096 270)
			(size 0.519938 1.4986)
			(layers "F.Cu" "F.Mask" "F.Paste")
			(net "M_C_CPU0_SA_CB<7>")
		)
		(pad "206" smd rect
			(at 2.050034 -11.474958 270)
			(size 0.519938 1.4986)
			(layers "F.Cu" "F.Mask" "F.Paste")
			(net "GND")
		)
		(pad "207" smd rect
			(at 2.050034 -10.625074 270)
			(size 0.519938 1.4986)
			(layers "F.Cu" "F.Mask" "F.Paste")
			(net "RST_M_CD_CPU0_FPGA_N")
		)
		(pad "208" smd rect
			(at 2.050034 -9.774936 270)
			(size 0.519938 1.4986)
			(layers "F.Cu" "F.Mask" "F.Paste")
			(net "GND")
		)
		(pad "209" smd rect
			(at 2.050034 -8.925052 270)
			(size 0.519938 1.4986)
			(layers "F.Cu" "F.Mask" "F.Paste")
			(net "M_C_CPU0_SA_CS_N<1>")
		)
		(pad "210" smd rect
			(at 2.050034 -8.074914 270)
			(size 0.519938 1.4986)
			(layers "F.Cu" "F.Mask" "F.Paste")
			(net "GND")
		)
		(pad "211" smd rect
			(at 2.050034 -7.22503 270)
			(size 0.519938 1.4986)
			(layers "F.Cu" "F.Mask" "F.Paste")
			(net "M_C_CPU0_SA_CA<1>")
		)
		(pad "212" smd rect
			(at 2.050034 -6.374892 270)
			(size 0.519938 1.4986)
			(layers "F.Cu" "F.Mask" "F.Paste")
			(net "GND")
		)
		(pad "213" smd rect
			(at 2.050034 -5.525008 270)
			(size 0.519938 1.4986)
			(layers "F.Cu" "F.Mask" "F.Paste")
			(net "M_C_CPU0_SA_CA<3>")
		)
		(pad "214" smd rect
			(at 2.050034 -4.675124 270)
			(size 0.519938 1.4986)
			(layers "F.Cu" "F.Mask" "F.Paste")
			(net "GND")
		)
		(pad "215" smd rect
			(at 2.050034 -3.824986 270)
			(size 0.519938 1.4986)
			(layers "F.Cu" "F.Mask" "F.Paste")
			(net "M_C_CPU0_SA_CA<5>")
		)
		(pad "216" smd rect
			(at 2.050034 -2.975102 270)
			(size 0.519938 1.4986)
			(layers "F.Cu" "F.Mask" "F.Paste")
			(net "GND")
		)
		(pad "217" smd rect
			(at 2.050034 -2.124964 270)
			(size 0.519938 1.4986)
			(layers "F.Cu" "F.Mask" "F.Paste")
			(net "M_C_CPU0_CLK_DP<0>")
		)
		(pad "218" smd rect
			(at 2.050034 -1.27508 270)
			(size 0.519938 1.4986)
			(layers "F.Cu" "F.Mask" "F.Paste")
			(net "M_C_CPU0_CLK_DN<0>")
		)
		(pad "219" smd rect
			(at 2.050034 -0.424942 270)
			(size 0.519938 1.4986)
			(layers "F.Cu" "F.Mask" "F.Paste")
			(net "GND")
		)
		(pad "220" smd rect
			(at 2.050034 5.525008 270)
			(size 0.519938 1.4986)
			(layers "F.Cu" "F.Mask" "F.Paste")
			(net "TP_CHC_CPU0_DIMM1_FRU_4")
		)
		(pad "221" smd rect
			(at 2.050034 6.374892 270)
			(size 0.519938 1.4986)
			(layers "F.Cu" "F.Mask" "F.Paste")
			(net "M_C_CPU0_SB_CA<1>")
		)
		(pad "222" smd rect
			(at 2.050034 7.22503 270)
			(size 0.519938 1.4986)
			(layers "F.Cu" "F.Mask" "F.Paste")
			(net "GND")
		)
		(pad "223" smd rect
			(at 2.050034 8.074914 270)
			(size 0.519938 1.4986)
			(layers "F.Cu" "F.Mask" "F.Paste")
			(net "M_C_CPU0_SB_CA<3>")
		)
		(pad "224" smd rect
			(at 2.050034 8.925052 270)
			(size 0.519938 1.4986)
			(layers "F.Cu" "F.Mask" "F.Paste")
			(net "GND")
		)
		(pad "225" smd rect
			(at 2.050034 9.774936 270)
			(size 0.519938 1.4986)
			(layers "F.Cu" "F.Mask" "F.Paste")
			(net "M_C_CPU0_SB_CA<5>")
		)
		(pad "226" smd rect
			(at 2.050034 10.625074 270)
			(size 0.519938 1.4986)
			(layers "F.Cu" "F.Mask" "F.Paste")
			(net "GND")
		)
		(pad "227" smd rect
			(at 2.050034 11.474958 270)
			(size 0.519938 1.4986)
			(layers "F.Cu" "F.Mask" "F.Paste")
			(net "M_C_CPU0_SB_PAR")
		)
		(pad "228" smd rect
			(at 2.050034 12.325096 270)
			(size 0.519938 1.4986)
			(layers "F.Cu" "F.Mask" "F.Paste")
			(net "GND")
		)
		(pad "229" smd rect
			(at 2.050034 13.17498 270)
			(size 0.519938 1.4986)
			(layers "F.Cu" "F.Mask" "F.Paste")
			(net "M_C_CPU0_SB_CS_N<1>")
		)
		(pad "230" smd rect
			(at 2.050034 14.025118 270)
			(size 0.519938 1.4986)
			(layers "F.Cu" "F.Mask" "F.Paste")
			(net "GND")
		)
		(pad "231" smd rect
			(at 2.050034 14.875002 270)
			(size 0.519938 1.4986)
			(layers "F.Cu" "F.Mask" "F.Paste")
			(net "TP_CHC_CPU0_DIMM1_FRU_5")
		)
		(pad "232" smd rect
			(at 2.050034 15.724886 270)
			(size 0.519938 1.4986)
			(layers "F.Cu" "F.Mask" "F.Paste")
			(net "TP_CHC_CPU0_DIMM1_FRU_6")
		)
		(pad "233" smd rect
			(at 2.050034 16.575024 270)
			(size 0.519938 1.4986)
			(layers "F.Cu" "F.Mask" "F.Paste")
			(net "GND")
		)
		(pad "234" smd rect
			(at 2.050034 17.424908 270)
			(size 0.519938 1.4986)
			(layers "F.Cu" "F.Mask" "F.Paste")
			(net "M_C_CPU0_SB_CB<6>")
		)
		(pad "235" smd rect
			(at 2.050034 18.275046 270)
			(size 0.519938 1.4986)
			(layers "F.Cu" "F.Mask" "F.Paste")
			(net "GND")
		)
		(pad "236" smd rect
			(at 2.050034 19.12493 270)
			(size 0.519938 1.4986)
			(layers "F.Cu" "F.Mask" "F.Paste")
			(net "M_C_CPU0_SB_CB<7>")
		)
		(pad "237" smd rect
			(at 2.050034 19.975068 270)
			(size 0.519938 1.4986)
			(layers "F.Cu" "F.Mask" "F.Paste")
			(net "GND")
		)
		(pad "238" smd rect
			(at 2.050034 20.824952 270)
			(size 0.519938 1.4986)
			(layers "F.Cu" "F.Mask" "F.Paste")
			(net "M_C_CPU0_SB_DQS_DN<4>")
		)
		(pad "239" smd rect
			(at 2.050034 21.67509 270)
			(size 0.519938 1.4986)
			(layers "F.Cu" "F.Mask" "F.Paste")
			(net "M_C_CPU0_SB_DQS_DP<4>")
		)
		(pad "240" smd rect
			(at 2.050034 22.524974 270)
			(size 0.519938 1.4986)
			(layers "F.Cu" "F.Mask" "F.Paste")
			(net "GND")
		)
		(pad "241" smd rect
			(at 2.050034 23.375112 270)
			(size 0.519938 1.4986)
			(layers "F.Cu" "F.Mask" "F.Paste")
			(net "M_C_CPU0_SB_CB<2>")
		)
		(pad "242" smd rect
			(at 2.050034 24.224996 270)
			(size 0.519938 1.4986)
			(layers "F.Cu" "F.Mask" "F.Paste")
			(net "GND")
		)
		(pad "243" smd rect
			(at 2.050034 25.07488 270)
			(size 0.519938 1.4986)
			(layers "F.Cu" "F.Mask" "F.Paste")
			(net "M_C_CPU0_SB_CB<3>")
		)
		(pad "244" smd rect
			(at 2.050034 25.925018 270)
			(size 0.519938 1.4986)
			(layers "F.Cu" "F.Mask" "F.Paste")
			(net "GND")
		)
		(pad "245" smd rect
			(at 2.050034 26.774902 270)
			(size 0.519938 1.4986)
			(layers "F.Cu" "F.Mask" "F.Paste")
			(net "M_C_CPU0_SB_DQ<2>")
		)
		(pad "246" smd rect
			(at 2.050034 27.62504 270)
			(size 0.519938 1.4986)
			(layers "F.Cu" "F.Mask" "F.Paste")
			(net "GND")
		)
		(pad "247" smd rect
			(at 2.050034 28.474924 270)
			(size 0.519938 1.4986)
			(layers "F.Cu" "F.Mask" "F.Paste")
			(net "M_C_CPU0_SB_DQ<3>")
		)
		(pad "248" smd rect
			(at 2.050034 29.325062 270)
			(size 0.519938 1.4986)
			(layers "F.Cu" "F.Mask" "F.Paste")
			(net "GND")
		)
		(pad "249" smd rect
			(at 2.050034 30.174946 270)
			(size 0.519938 1.4986)
			(layers "F.Cu" "F.Mask" "F.Paste")
			(net "M_C_CPU0_SB_DQS_DN<5>")
		)
		(pad "250" smd rect
			(at 2.050034 31.025084 270)
			(size 0.519938 1.4986)
			(layers "F.Cu" "F.Mask" "F.Paste")
			(net "M_C_CPU0_SB_DQS_DP<5>")
		)
		(pad "251" smd rect
			(at 2.050034 31.874968 270)
			(size 0.519938 1.4986)
			(layers "F.Cu" "F.Mask" "F.Paste")
			(net "GND")
		)
		(pad "252" smd rect
			(at 2.050034 32.725106 270)
			(size 0.519938 1.4986)
			(layers "F.Cu" "F.Mask" "F.Paste")
			(net "M_C_CPU0_SB_DQ<6>")
		)
		(pad "253" smd rect
			(at 2.050034 33.57499 270)
			(size 0.519938 1.4986)
			(layers "F.Cu" "F.Mask" "F.Paste")
			(net "GND")
		)
		(pad "254" smd rect
			(at 2.050034 34.425128 270)
			(size 0.519938 1.4986)
			(layers "F.Cu" "F.Mask" "F.Paste")
			(net "M_C_CPU0_SB_DQ<7>")
		)
		(pad "255" smd rect
			(at 2.050034 35.275012 270)
			(size 0.519938 1.4986)
			(layers "F.Cu" "F.Mask" "F.Paste")
			(net "GND")
		)
		(pad "256" smd rect
			(at 2.050034 36.124896 270)
			(size 0.519938 1.4986)
			(layers "F.Cu" "F.Mask" "F.Paste")
			(net "M_C_CPU0_SB_DQ<10>")
		)
		(pad "257" smd rect
			(at 2.050034 36.975034 270)
			(size 0.519938 1.4986)
			(layers "F.Cu" "F.Mask" "F.Paste")
			(net "GND")
		)
		(pad "258" smd rect
			(at 2.050034 37.824918 270)
			(size 0.519938 1.4986)
			(layers "F.Cu" "F.Mask" "F.Paste")
			(net "M_C_CPU0_SB_DQ<11>")
		)
		(pad "259" smd rect
			(at 2.050034 38.675056 270)
			(size 0.519938 1.4986)
			(layers "F.Cu" "F.Mask" "F.Paste")
			(net "GND")
		)
		(pad "260" smd rect
			(at 2.050034 39.52494 270)
			(size 0.519938 1.4986)
			(layers "F.Cu" "F.Mask" "F.Paste")
			(net "M_C_CPU0_SB_DQS_DN<6>")
		)
		(pad "261" smd rect
			(at 2.050034 40.375078 270)
			(size 0.519938 1.4986)
			(layers "F.Cu" "F.Mask" "F.Paste")
			(net "M_C_CPU0_SB_DQS_DP<6>")
		)
		(pad "262" smd rect
			(at 2.050034 41.224962 270)
			(size 0.519938 1.4986)
			(layers "F.Cu" "F.Mask" "F.Paste")
			(net "GND")
		)
		(pad "263" smd rect
			(at 2.050034 42.0751 270)
			(size 0.519938 1.4986)
			(layers "F.Cu" "F.Mask" "F.Paste")
			(net "M_C_CPU0_SB_DQ<14>")
		)
		(pad "264" smd rect
			(at 2.050034 42.924984 270)
			(size 0.519938 1.4986)
			(layers "F.Cu" "F.Mask" "F.Paste")
			(net "GND")
		)
		(pad "265" smd rect
			(at 2.050034 43.775122 270)
			(size 0.519938 1.4986)
			(layers "F.Cu" "F.Mask" "F.Paste")
			(net "M_C_CPU0_SB_DQ<15>")
		)
		(pad "266" smd rect
			(at 2.050034 44.625006 270)
			(size 0.519938 1.4986)
			(layers "F.Cu" "F.Mask" "F.Paste")
			(net "GND")
		)
		(pad "267" smd rect
			(at 2.050034 45.47489 270)
			(size 0.519938 1.4986)
			(layers "F.Cu" "F.Mask" "F.Paste")
			(net "M_C_CPU0_SB_DQ<18>")
		)
		(pad "268" smd rect
			(at 2.050034 46.325028 270)
			(size 0.519938 1.4986)
			(layers "F.Cu" "F.Mask" "F.Paste")
			(net "GND")
		)
		(pad "269" smd rect
			(at 2.050034 47.174912 270)
			(size 0.519938 1.4986)
			(layers "F.Cu" "F.Mask" "F.Paste")
			(net "M_C_CPU0_SB_DQ<19>")
		)
		(pad "270" smd rect
			(at 2.050034 48.02505 270)
			(size 0.519938 1.4986)
			(layers "F.Cu" "F.Mask" "F.Paste")
			(net "GND")
		)
		(pad "271" smd rect
			(at 2.050034 48.874934 270)
			(size 0.519938 1.4986)
			(layers "F.Cu" "F.Mask" "F.Paste")
			(net "M_C_CPU0_SB_DQS_DN<7>")
		)
		(pad "272" smd rect
			(at 2.050034 49.725072 270)
			(size 0.519938 1.4986)
			(layers "F.Cu" "F.Mask" "F.Paste")
			(net "M_C_CPU0_SB_DQS_DP<7>")
		)
		(pad "273" smd rect
			(at 2.050034 50.574956 270)
			(size 0.519938 1.4986)
			(layers "F.Cu" "F.Mask" "F.Paste")
			(net "GND")
		)
		(pad "274" smd rect
			(at 2.050034 51.425094 270)
			(size 0.519938 1.4986)
			(layers "F.Cu" "F.Mask" "F.Paste")
			(net "M_C_CPU0_SB_DQ<22>")
		)
		(pad "275" smd rect
			(at 2.050034 52.274978 270)
			(size 0.519938 1.4986)
			(layers "F.Cu" "F.Mask" "F.Paste")
			(net "GND")
		)
		(pad "276" smd rect
			(at 2.050034 53.125116 270)
			(size 0.519938 1.4986)
			(layers "F.Cu" "F.Mask" "F.Paste")
			(net "M_C_CPU0_SB_DQ<23>")
		)
		(pad "277" smd rect
			(at 2.050034 53.975 270)
			(size 0.519938 1.4986)
			(layers "F.Cu" "F.Mask" "F.Paste")
			(net "GND")
		)
		(pad "278" smd rect
			(at 2.050034 54.824884 270)
			(size 0.519938 1.4986)
			(layers "F.Cu" "F.Mask" "F.Paste")
			(net "M_C_CPU0_SB_DQ<26>")
		)
		(pad "279" smd rect
			(at 2.050034 55.675022 270)
			(size 0.519938 1.4986)
			(layers "F.Cu" "F.Mask" "F.Paste")
			(net "GND")
		)
		(pad "280" smd rect
			(at 2.050034 56.524906 270)
			(size 0.519938 1.4986)
			(layers "F.Cu" "F.Mask" "F.Paste")
			(net "M_C_CPU0_SB_DQ<27>")
		)
		(pad "281" smd rect
			(at 2.050034 57.375044 270)
			(size 0.519938 1.4986)
			(layers "F.Cu" "F.Mask" "F.Paste")
			(net "GND")
		)
		(pad "282" smd rect
			(at 2.050034 58.224928 270)
			(size 0.519938 1.4986)
			(layers "F.Cu" "F.Mask" "F.Paste")
			(net "M_C_CPU0_SB_DQS_DN<8>")
		)
		(pad "283" smd rect
			(at 2.050034 59.075066 270)
			(size 0.519938 1.4986)
			(layers "F.Cu" "F.Mask" "F.Paste")
			(net "M_C_CPU0_SB_DQS_DP<8>")
		)
		(pad "284" smd rect
			(at 2.050034 59.92495 270)
			(size 0.519938 1.4986)
			(layers "F.Cu" "F.Mask" "F.Paste")
			(net "GND")
		)
		(pad "285" smd rect
			(at 2.050034 60.775088 270)
			(size 0.519938 1.4986)
			(layers "F.Cu" "F.Mask" "F.Paste")
			(net "M_C_CPU0_SB_DQ<30>")
		)
		(pad "286" smd rect
			(at 2.050034 61.624972 270)
			(size 0.519938 1.4986)
			(layers "F.Cu" "F.Mask" "F.Paste")
			(net "GND")
		)
		(pad "287" smd rect
			(at 2.050034 62.47511 270)
			(size 0.519938 1.4986)
			(layers "F.Cu" "F.Mask" "F.Paste")
			(net "M_C_CPU0_SB_DQ<31>")
		)
		(pad "288" smd rect
			(at 2.050034 63.324994 270)
			(size 0.519938 1.4986)
			(layers "F.Cu" "F.Mask" "F.Paste")
			(net "GND")
		)
		(pad "G1" thru_hole oval
			(at 0 -68.97497)
			(size 2.8194 1.5748)
			(drill oval 2.4384 1.1938)
			(layers "*.Cu" "*.Mask")
			(remove_unused_layers no)
			(net "GND")
			(clearance 0.127)
			(thermal_gap 0.127)
		)
		(pad "G2" thru_hole oval
			(at 0 3.875024)
			(size 2.8194 1.5748)
			(drill oval 2.4384 1.1938)
			(layers "*.Cu" "*.Mask")
			(remove_unused_layers no)
			(net "GND")
			(clearance 0.127)
			(thermal_gap 0.127)
		)
		(pad "G3" thru_hole oval
			(at 0 68.97497)
			(size 2.8194 1.5748)
			(drill oval 2.4384 1.1938)
			(layers "*.Cu" "*.Mask")
			(remove_unused_layers no)
			(net "GND")
			(clearance 0.127)
			(thermal_gap 0.127)
		)
	)
	(footprint ""
		(layer "F.Cu")
		(at 332.438248 -402.371052 -90)
		(property "Reference" "C1793"
			(at 0 0 270)
			(layer "F.SilkS")
			(hide yes)
			(effects
				(font
					(size 1.27 1.27)
				)
			)
		)
		(property "Value" ""
			(at 0 0 270)
			(layer "F.Fab")
			(effects
				(font
					(size 1.27 1.27)
				)
			)
		)
		(duplicate_pad_numbers_are_jumpers no)
		(fp_line
			(start -0.299974 0.150114)
			(end -0.299974 -0.150114)
			(stroke
				(width 0.1)
				(type default)
			)
			(layer "F.Fab")
		)
		(fp_line
			(start 0.299974 0.150114)
			(end -0.299974 0.150114)
			(stroke
				(width 0.1)
				(type default)
			)
			(layer "F.Fab")
		)
		(fp_line
			(start -0.299974 -0.150114)
			(end 0.299974 -0.150114)
			(stroke
				(width 0.1)
				(type default)
			)
			(layer "F.Fab")
		)
		(fp_line
			(start 0.299974 -0.150114)
			(end 0.299974 0.150114)
			(stroke
				(width 0.1)
				(type default)
			)
			(layer "F.Fab")
		)
		(pad "1" smd rect
			(at -0.2667 0 270)
			(size 0.3048 0.381)
			(layers "F.Cu" "F.Mask" "F.Paste")
			(net "P5E_CPU0_PE4_TX_C_DP<9>")
		)
		(pad "2" smd rect
			(at 0.2667 0 270)
			(size 0.3048 0.381)
			(layers "F.Cu" "F.Mask" "F.Paste")
			(net "P5E_CPU0_PE4_TX_DP<9>")
		)
	)
	(footprint ""
		(layer "F.Cu")
		(at 217.881962 -67.324478 180)
		(property "Reference" "PR3965"
			(at 0 0 180)
			(layer "F.SilkS")
			(hide yes)
			(effects
				(font
					(size 1.27 1.27)
				)
			)
		)
		(property "Value" ""
			(at 0 0 180)
			(layer "F.Fab")
			(effects
				(font
					(size 1.27 1.27)
				)
			)
		)
		(duplicate_pad_numbers_are_jumpers no)
		(fp_line
			(start 0.7874 0.4064)
			(end -0.7874 0.4064)
			(stroke
				(width 0.1524)
				(type default)
			)
			(layer "F.SilkS")
		)
		(fp_line
			(start 0.7874 -0.4064)
			(end 0.7874 0.4064)
			(stroke
				(width 0.1524)
				(type default)
			)
			(layer "F.SilkS")
		)
		(fp_line
			(start -0.7874 0.4064)
			(end -0.7874 -0.4064)
			(stroke
				(width 0.1524)
				(type default)
			)
			(layer "F.SilkS")
		)
		(fp_line
			(start -0.7874 -0.4064)
			(end 0.7874 -0.4064)
			(stroke
				(width 0.1524)
				(type default)
			)
			(layer "F.SilkS")
		)
		(fp_line
			(start 0.67945 0.3048)
			(end 0.120396 0.3048)
			(stroke
				(width 0.1)
				(type default)
			)
			(layer "F.Fab")
		)
		(fp_line
			(start 0.67945 -0.3048)
			(end 0.67945 0.3048)
			(stroke
				(width 0.1)
				(type default)
			)
			(layer "F.Fab")
		)
		(fp_line
			(start 0.12065 -0.2794)
			(end 0.12065 -0.3048)
			(stroke
				(width 0.1)
				(type default)
			)
			(layer "F.Fab")
		)
		(fp_line
			(start 0.12065 -0.3048)
			(end 0.67945 -0.3048)
			(stroke
				(width 0.1)
				(type default)
			)
			(layer "F.Fab")
		)
		(fp_line
			(start 0.120396 0.3048)
			(end 0.120396 0.2794)
			(stroke
				(width 0.1)
				(type default)
			)
			(layer "F.Fab")
		)
		(fp_line
			(start 0.120396 0.2794)
			(end -0.12065 0.2794)
			(stroke
				(width 0.1)
				(type default)
			)
			(layer "F.Fab")
		)
		(fp_line
			(start -0.12065 0.3048)
			(end -0.67945 0.3048)
			(stroke
				(width 0.1)
				(type default)
			)
			(layer "F.Fab")
		)
		(fp_line
			(start -0.12065 0.2794)
			(end -0.12065 0.3048)
			(stroke
				(width 0.1)
				(type default)
			)
			(layer "F.Fab")
		)
		(fp_line
			(start -0.12065 -0.2794)
			(end 0.12065 -0.2794)
			(stroke
				(width 0.1)
				(type default)
			)
			(layer "F.Fab")
		)
		(fp_line
			(start -0.12065 -0.305054)
			(end -0.12065 -0.2794)
			(stroke
				(width 0.1)
				(type default)
			)
			(layer "F.Fab")
		)
		(fp_line
			(start -0.67945 0.3048)
			(end -0.67945 -0.305054)
			(stroke
				(width 0.1)
				(type default)
			)
			(layer "F.Fab")
		)
		(fp_line
			(start -0.67945 -0.305054)
			(end -0.12065 -0.305054)
			(stroke
				(width 0.1)
				(type default)
			)
			(layer "F.Fab")
		)
		(pad "1" smd circle
			(at -0.40005 0 180)
			(size 0 0)
			(layers "F.Cu" "F.Mask" "F.Paste")
			(net "P3V3_E1S_OV_0")
		)
		(pad "2" smd circle
			(at 0.40005 0 180)
			(size 0 0)
			(layers "F.Cu" "F.Mask" "F.Paste")
			(net "GND")
		)
	)
	(footprint ""
		(layer "F.Cu")
		(at 211.455 -68.253356 -90)
		(property "Reference" "R4710"
			(at 0 0 270)
			(layer "F.SilkS")
			(hide yes)
			(effects
				(font
					(size 1.27 1.27)
				)
			)
		)
		(property "Value" ""
			(at 0 0 270)
			(layer "F.Fab")
			(effects
				(font
					(size 1.27 1.27)
				)
			)
		)
		(duplicate_pad_numbers_are_jumpers no)
		(fp_line
			(start -0.7874 0.4064)
			(end -0.7874 -0.4064)
			(stroke
				(width 0.1524)
				(type default)
			)
			(layer "F.SilkS")
		)
		(fp_line
			(start 0.7874 0.4064)
			(end -0.7874 0.4064)
			(stroke
				(width 0.1524)
				(type default)
			)
			(layer "F.SilkS")
		)
		(fp_line
			(start -0.7874 -0.4064)
			(end 0.7874 -0.4064)
			(stroke
				(width 0.1524)
				(type default)
			)
			(layer "F.SilkS")
		)
		(fp_line
			(start 0.7874 -0.4064)
			(end 0.7874 0.4064)
			(stroke
				(width 0.1524)
				(type default)
			)
			(layer "F.SilkS")
		)
		(fp_line
			(start -0.67945 0.3048)
			(end -0.67945 -0.305054)
			(stroke
				(width 0.1)
				(type default)
			)
			(layer "F.Fab")
		)
		(fp_line
			(start -0.12065 0.3048)
			(end -0.67945 0.3048)
			(stroke
				(width 0.1)
				(type default)
			)
			(layer "F.Fab")
		)
		(fp_line
			(start 0.120396 0.3048)
			(end 0.120396 0.2794)
			(stroke
				(width 0.1)
				(type default)
			)
			(layer "F.Fab")
		)
		(fp_line
			(start 0.67945 0.3048)
			(end 0.120396 0.3048)
			(stroke
				(width 0.1)
				(type default)
			)
			(layer "F.Fab")
		)
		(fp_line
			(start -0.12065 0.2794)
			(end -0.12065 0.3048)
			(stroke
				(width 0.1)
				(type default)
			)
			(layer "F.Fab")
		)
		(fp_line
			(start 0.120396 0.2794)
			(end -0.12065 0.2794)
			(stroke
				(width 0.1)
				(type default)
			)
			(layer "F.Fab")
		)
		(fp_line
			(start -0.12065 -0.2794)
			(end 0.12065 -0.2794)
			(stroke
				(width 0.1)
				(type default)
			)
			(layer "F.Fab")
		)
		(fp_line
			(start 0.12065 -0.2794)
			(end 0.12065 -0.3048)
			(stroke
				(width 0.1)
				(type default)
			)
			(layer "F.Fab")
		)
		(fp_line
			(start 0.12065 -0.3048)
			(end 0.67945 -0.3048)
			(stroke
				(width 0.1)
				(type default)
			)
			(layer "F.Fab")
		)
		(fp_line
			(start 0.67945 -0.3048)
			(end 0.67945 0.3048)
			(stroke
				(width 0.1)
				(type default)
			)
			(layer "F.Fab")
		)
		(fp_line
			(start -0.67945 -0.305054)
			(end -0.12065 -0.305054)
			(stroke
				(width 0.1)
				(type default)
			)
			(layer "F.Fab")
		)
		(fp_line
			(start -0.12065 -0.305054)
			(end -0.12065 -0.2794)
			(stroke
				(width 0.1)
				(type default)
			)
			(layer "F.Fab")
		)
		(pad "1" smd circle
			(at -0.40005 0 270)
			(size 0 0)
			(layers "F.Cu" "F.Mask" "F.Paste")
			(net "P3V3_AUX")
		)
		(pad "2" smd circle
			(at 0.40005 0 270)
			(size 0 0)
			(layers "F.Cu" "F.Mask" "F.Paste")
			(net "LED_P12V_SCM_FAULT_D1")
		)
	)
	(footprint ""
		(layer "F.Cu")
		(at 385.637532 -73.394824 180)
		(property "Reference" "R2359"
			(at 0 0 180)
			(layer "F.SilkS")
			(hide yes)
			(effects
				(font
					(size 1.27 1.27)
				)
			)
		)
		(property "Value" ""
			(at 0 0 180)
			(layer "F.Fab")
			(effects
				(font
					(size 1.27 1.27)
				)
			)
		)
		(duplicate_pad_numbers_are_jumpers no)
		(fp_line
			(start 0.7874 0.4064)
			(end -0.7874 0.4064)
			(stroke
				(width 0.1524)
				(type default)
			)
			(layer "F.SilkS")
		)
		(fp_line
			(start 0.7874 -0.4064)
			(end 0.7874 0.4064)
			(stroke
				(width 0.1524)
				(type default)
			)
			(layer "F.SilkS")
		)
		(fp_line
			(start -0.7874 0.4064)
			(end -0.7874 -0.4064)
			(stroke
				(width 0.1524)
				(type default)
			)
			(layer "F.SilkS")
		)
		(fp_line
			(start -0.7874 -0.4064)
			(end 0.7874 -0.4064)
			(stroke
				(width 0.1524)
				(type default)
			)
			(layer "F.SilkS")
		)
		(fp_line
			(start 0.67945 0.3048)
			(end 0.120396 0.3048)
			(stroke
				(width 0.1)
				(type default)
			)
			(layer "F.Fab")
		)
		(fp_line
			(start 0.67945 -0.3048)
			(end 0.67945 0.3048)
			(stroke
				(width 0.1)
				(type default)
			)
			(layer "F.Fab")
		)
		(fp_line
			(start 0.12065 -0.2794)
			(end 0.12065 -0.3048)
			(stroke
				(width 0.1)
				(type default)
			)
			(layer "F.Fab")
		)
		(fp_line
			(start 0.12065 -0.3048)
			(end 0.67945 -0.3048)
			(stroke
				(width 0.1)
				(type default)
			)
			(layer "F.Fab")
		)
		(fp_line
			(start 0.120396 0.3048)
			(end 0.120396 0.2794)
			(stroke
				(width 0.1)
				(type default)
			)
			(layer "F.Fab")
		)
		(fp_line
			(start 0.120396 0.2794)
			(end -0.12065 0.2794)
			(stroke
				(width 0.1)
				(type default)
			)
			(layer "F.Fab")
		)
		(fp_line
			(start -0.12065 0.3048)
			(end -0.67945 0.3048)
			(stroke
				(width 0.1)
				(type default)
			)
			(layer "F.Fab")
		)
		(fp_line
			(start -0.12065 0.2794)
			(end -0.12065 0.3048)
			(stroke
				(width 0.1)
				(type default)
			)
			(layer "F.Fab")
		)
		(fp_line
			(start -0.12065 -0.2794)
			(end 0.12065 -0.2794)
			(stroke
				(width 0.1)
				(type default)
			)
			(layer "F.Fab")
		)
		(fp_line
			(start -0.12065 -0.305054)
			(end -0.12065 -0.2794)
			(stroke
				(width 0.1)
				(type default)
			)
			(layer "F.Fab")
		)
		(fp_line
			(start -0.67945 0.3048)
			(end -0.67945 -0.305054)
			(stroke
				(width 0.1)
				(type default)
			)
			(layer "F.Fab")
		)
		(fp_line
			(start -0.67945 -0.305054)
			(end -0.12065 -0.305054)
			(stroke
				(width 0.1)
				(type default)
			)
			(layer "F.Fab")
		)
		(pad "1" smd circle
			(at -0.40005 0 180)
			(size 0 0)
			(layers "F.Cu" "F.Mask" "F.Paste")
			(net "P3V3_AUX")
		)
		(pad "2" smd circle
			(at 0.40005 0 180)
			(size 0 0)
			(layers "F.Cu" "F.Mask" "F.Paste")
			(net "PWRGD_P1V8_PCH_AUX_R")
		)
	)
	(footprint ""
		(layer "F.Cu")
		(at 372.13159 -68.930012)
		(property "Reference" "C546"
			(at 0 0 0)
			(layer "F.SilkS")
			(hide yes)
			(effects
				(font
					(size 1.27 1.27)
				)
			)
		)
		(property "Value" ""
			(at 0 0 0)
			(layer "F.Fab")
			(effects
				(font
					(size 1.27 1.27)
				)
			)
		)
		(duplicate_pad_numbers_are_jumpers no)
		(fp_line
			(start -0.7874 -0.4064)
			(end 0.7874 -0.4064)
			(stroke
				(width 0.1524)
				(type default)
			)
			(layer "F.SilkS")
		)
		(fp_line
			(start -0.7874 0.4064)
			(end -0.7874 -0.4064)
			(stroke
				(width 0.1524)
				(type default)
			)
			(layer "F.SilkS")
		)
		(fp_line
			(start 0.7874 -0.4064)
			(end 0.7874 0.4064)
			(stroke
				(width 0.1524)
				(type default)
			)
			(layer "F.SilkS")
		)
		(fp_line
			(start 0.7874 0.4064)
			(end -0.7874 0.4064)
			(stroke
				(width 0.1524)
				(type default)
			)
			(layer "F.SilkS")
		)
		(fp_line
			(start -0.67945 -0.305054)
			(end -0.12065 -0.305054)
			(stroke
				(width 0.1)
				(type default)
			)
			(layer "F.Fab")
		)
		(fp_line
			(start -0.67945 0.3048)
			(end -0.67945 -0.305054)
			(stroke
				(width 0.1)
				(type default)
			)
			(layer "F.Fab")
		)
		(fp_line
			(start -0.12065 -0.305054)
			(end -0.12065 -0.2794)
			(stroke
				(width 0.1)
				(type default)
			)
			(layer "F.Fab")
		)
		(fp_line
			(start -0.12065 -0.2794)
			(end 0.12065 -0.2794)
			(stroke
				(width 0.1)
				(type default)
			)
			(layer "F.Fab")
		)
		(fp_line
			(start -0.12065 0.2794)
			(end -0.12065 0.3048)
			(stroke
				(width 0.1)
				(type default)
			)
			(layer "F.Fab")
		)
		(fp_line
			(start -0.12065 0.3048)
			(end -0.67945 0.3048)
			(stroke
				(width 0.1)
				(type default)
			)
			(layer "F.Fab")
		)
		(fp_line
			(start 0.120396 0.2794)
			(end -0.12065 0.2794)
			(stroke
				(width 0.1)
				(type default)
			)
			(layer "F.Fab")
		)
		(fp_line
			(start 0.120396 0.3048)
			(end 0.120396 0.2794)
			(stroke
				(width 0.1)
				(type default)
			)
			(layer "F.Fab")
		)
		(fp_line
			(start 0.12065 -0.3048)
			(end 0.67945 -0.3048)
			(stroke
				(width 0.1)
				(type default)
			)
			(layer "F.Fab")
		)
		(fp_line
			(start 0.12065 -0.2794)
			(end 0.12065 -0.3048)
			(stroke
				(width 0.1)
				(type default)
			)
			(layer "F.Fab")
		)
		(fp_line
			(start 0.67945 -0.3048)
			(end 0.67945 0.3048)
			(stroke
				(width 0.1)
				(type default)
			)
			(layer "F.Fab")
		)
		(fp_line
			(start 0.67945 0.3048)
			(end 0.120396 0.3048)
			(stroke
				(width 0.1)
				(type default)
			)
			(layer "F.Fab")
		)
		(pad "1" smd circle
			(at -0.40005 0)
			(size 0 0)
			(layers "F.Cu" "F.Mask" "F.Paste")
			(net "P3V3_AUX")
		)
		(pad "2" smd circle
			(at 0.40005 0)
			(size 0 0)
			(layers "F.Cu" "F.Mask" "F.Paste")
			(net "GND")
		)
	)
	(footprint ""
		(layer "F.Cu")
		(at 465.043266 -101.39299 180)
		(property "Reference" "R1149"
			(at 0 0 180)
			(layer "F.SilkS")
			(hide yes)
			(effects
				(font
					(size 1.27 1.27)
				)
			)
		)
		(property "Value" ""
			(at 0 0 180)
			(layer "F.Fab")
			(effects
				(font
					(size 1.27 1.27)
				)
			)
		)
		(duplicate_pad_numbers_are_jumpers no)
		(fp_line
			(start 0.7874 0.4064)
			(end -0.7874 0.4064)
			(stroke
				(width 0.1524)
				(type default)
			)
			(layer "F.SilkS")
		)
		(fp_line
			(start 0.7874 -0.4064)
			(end 0.7874 0.4064)
			(stroke
				(width 0.1524)
				(type default)
			)
			(layer "F.SilkS")
		)
		(fp_line
			(start -0.7874 0.4064)
			(end -0.7874 -0.4064)
			(stroke
				(width 0.1524)
				(type default)
			)
			(layer "F.SilkS")
		)
		(fp_line
			(start -0.7874 -0.4064)
			(end 0.7874 -0.4064)
			(stroke
				(width 0.1524)
				(type default)
			)
			(layer "F.SilkS")
		)
		(fp_line
			(start 0.67945 0.3048)
			(end 0.120396 0.3048)
			(stroke
				(width 0.1)
				(type default)
			)
			(layer "F.Fab")
		)
		(fp_line
			(start 0.67945 -0.3048)
			(end 0.67945 0.3048)
			(stroke
				(width 0.1)
				(type default)
			)
			(layer "F.Fab")
		)
		(fp_line
			(start 0.12065 -0.2794)
			(end 0.12065 -0.3048)
			(stroke
				(width 0.1)
				(type default)
			)
			(layer "F.Fab")
		)
		(fp_line
			(start 0.12065 -0.3048)
			(end 0.67945 -0.3048)
			(stroke
				(width 0.1)
				(type default)
			)
			(layer "F.Fab")
		)
		(fp_line
			(start 0.120396 0.3048)
			(end 0.120396 0.2794)
			(stroke
				(width 0.1)
				(type default)
			)
			(layer "F.Fab")
		)
		(fp_line
			(start 0.120396 0.2794)
			(end -0.12065 0.2794)
			(stroke
				(width 0.1)
				(type default)
			)
			(layer "F.Fab")
		)
		(fp_line
			(start -0.12065 0.3048)
			(end -0.67945 0.3048)
			(stroke
				(width 0.1)
				(type default)
			)
			(layer "F.Fab")
		)
		(fp_line
			(start -0.12065 0.2794)
			(end -0.12065 0.3048)
			(stroke
				(width 0.1)
				(type default)
			)
			(layer "F.Fab")
		)
		(fp_line
			(start -0.12065 -0.2794)
			(end 0.12065 -0.2794)
			(stroke
				(width 0.1)
				(type default)
			)
			(layer "F.Fab")
		)
		(fp_line
			(start -0.12065 -0.305054)
			(end -0.12065 -0.2794)
			(stroke
				(width 0.1)
				(type default)
			)
			(layer "F.Fab")
		)
		(fp_line
			(start -0.67945 0.3048)
			(end -0.67945 -0.305054)
			(stroke
				(width 0.1)
				(type default)
			)
			(layer "F.Fab")
		)
		(fp_line
			(start -0.67945 -0.305054)
			(end -0.12065 -0.305054)
			(stroke
				(width 0.1)
				(type default)
			)
			(layer "F.Fab")
		)
		(pad "1" smd circle
			(at -0.40005 0 180)
			(size 0 0)
			(layers "F.Cu" "F.Mask" "F.Paste")
			(net "P3V3_AUX")
		)
		(pad "2" smd circle
			(at 0.40005 0 180)
			(size 0 0)
			(layers "F.Cu" "F.Mask" "F.Paste")
			(net "HP_LVC3_OCP_V3_1_ATTN_OUT_SW_N")
		)
	)
	(footprint ""
		(layer "F.Cu")
		(at 120.37822 -423.479468)
		(property "Reference" "R3508"
			(at 0 0 0)
			(layer "F.SilkS")
			(hide yes)
			(effects
				(font
					(size 1.27 1.27)
				)
			)
		)
		(property "Value" ""
			(at 0 0 0)
			(layer "F.Fab")
			(effects
				(font
					(size 1.27 1.27)
				)
			)
		)
		(duplicate_pad_numbers_are_jumpers no)
		(fp_line
			(start -0.7874 -0.4064)
			(end 0.7874 -0.4064)
			(stroke
				(width 0.1524)
				(type default)
			)
			(layer "F.SilkS")
		)
		(fp_line
			(start -0.7874 0.4064)
			(end -0.7874 -0.4064)
			(stroke
				(width 0.1524)
				(type default)
			)
			(layer "F.SilkS")
		)
		(fp_line
			(start 0.7874 -0.4064)
			(end 0.7874 0.4064)
			(stroke
				(width 0.1524)
				(type default)
			)
			(layer "F.SilkS")
		)
		(fp_line
			(start 0.7874 0.4064)
			(end -0.7874 0.4064)
			(stroke
				(width 0.1524)
				(type default)
			)
			(layer "F.SilkS")
		)
		(fp_line
			(start -0.67945 -0.305054)
			(end -0.12065 -0.305054)
			(stroke
				(width 0.1)
				(type default)
			)
			(layer "F.Fab")
		)
		(fp_line
			(start -0.67945 0.3048)
			(end -0.67945 -0.305054)
			(stroke
				(width 0.1)
				(type default)
			)
			(layer "F.Fab")
		)
		(fp_line
			(start -0.12065 -0.305054)
			(end -0.12065 -0.2794)
			(stroke
				(width 0.1)
				(type default)
			)
			(layer "F.Fab")
		)
		(fp_line
			(start -0.12065 -0.2794)
			(end 0.12065 -0.2794)
			(stroke
				(width 0.1)
				(type default)
			)
			(layer "F.Fab")
		)
		(fp_line
			(start -0.12065 0.2794)
			(end -0.12065 0.3048)
			(stroke
				(width 0.1)
				(type default)
			)
			(layer "F.Fab")
		)
		(fp_line
			(start -0.12065 0.3048)
			(end -0.67945 0.3048)
			(stroke
				(width 0.1)
				(type default)
			)
			(layer "F.Fab")
		)
		(fp_line
			(start 0.120396 0.2794)
			(end -0.12065 0.2794)
			(stroke
				(width 0.1)
				(type default)
			)
			(layer "F.Fab")
		)
		(fp_line
			(start 0.120396 0.3048)
			(end 0.120396 0.2794)
			(stroke
				(width 0.1)
				(type default)
			)
			(layer "F.Fab")
		)
		(fp_line
			(start 0.12065 -0.3048)
			(end 0.67945 -0.3048)
			(stroke
				(width 0.1)
				(type default)
			)
			(layer "F.Fab")
		)
		(fp_line
			(start 0.12065 -0.2794)
			(end 0.12065 -0.3048)
			(stroke
				(width 0.1)
				(type default)
			)
			(layer "F.Fab")
		)
		(fp_line
			(start 0.67945 -0.3048)
			(end 0.67945 0.3048)
			(stroke
				(width 0.1)
				(type default)
			)
			(layer "F.Fab")
		)
		(fp_line
			(start 0.67945 0.3048)
			(end 0.120396 0.3048)
			(stroke
				(width 0.1)
				(type default)
			)
			(layer "F.Fab")
		)
		(pad "1" smd circle
			(at -0.40005 0)
			(size 0 0)
			(layers "F.Cu" "F.Mask" "F.Paste")
			(net "FM_GPU_PWR_EN_R1")
		)
		(pad "2" smd circle
			(at 0.40005 0)
			(size 0 0)
			(layers "F.Cu" "F.Mask" "F.Paste")
			(net "GND")
		)
	)
	(footprint ""
		(layer "F.Cu")
		(at 459.280768 -398.59077)
		(property "Reference" "H27"
			(at -5.8166 -5.552948 0)
			(unlocked yes)
			(layer "F.SilkS")
			(effects
				(font
					(size 0.7874 0.5842)
					(thickness 0.1524)
				)
				(justify left)
			)
		)
		(property "Value" ""
			(at 0 0 0)
			(layer "F.Fab")
			(effects
				(font
					(size 1.27 1.27)
				)
			)
		)
		(duplicate_pad_numbers_are_jumpers no)
		(fp_circle
			(center 0 0)
			(end 2.4003 0)
			(stroke
				(width 0.1524)
				(type default)
			)
			(fill no)
			(layer "F.SilkS")
		)
		(fp_arc
			(start 5.688076 3.330194)
			(mid -6.590791 -0.091812)
			(end 5.7785 -3.170936)
			(stroke
				(width 0.1524)
				(type default)
			)
			(layer "B.SilkS")
		)
		(fp_circle
			(center 0 0)
			(end 6.5913 0)
			(stroke
				(width 0.1)
				(type default)
			)
			(fill no)
			(layer "B.Fab")
		)
		(fp_circle
			(center 0 0)
			(end 2.4003 0)
			(stroke
				(width 0.1)
				(type default)
			)
			(fill no)
			(layer "F.Fab")
		)
		(pad "" np_thru_hole circle
			(at 0 0)
			(size 3.175 3.175)
			(drill 3.175)
			(layers "*.Cu" "*.Mask")
			(clearance 0.381)
			(thermal_gap 0.381)
		)
		(zone
			(layers "F.Cu" "B.Cu" "In1.Cu" "In2.Cu" "In3.Cu" "In4.Cu" "In5.Cu" "In6.Cu"
				"In7.Cu" "In8.Cu" "In9.Cu" "In10.Cu" "In11.Cu" "In12.Cu" "In13.Cu" "In14.Cu"
				"In15.Cu" "In16.Cu"
			)
			(hatch none 0.5)
			(connect_pads
				(clearance 0)
			)
			(min_thickness 0.25)
			(keepout
				(tracks not_allowed)
				(vias allowed)
				(pads allowed)
				(copperpour not_allowed)
				(footprints allowed)
			)
			(placement
				(enabled no)
				(sheetname "")
			)
			(fill
				(thermal_gap 0.5)
				(thermal_bridge_width 0.5)
				(island_removal_mode 0)
			)
			(polygon
				(pts
					(arc
						(start 461.376268 -398.59077)
						(mid 457.185268 -398.59077)
						(end 461.376268 -398.59077)
					)
				)
			)
		)
	)
	(footprint ""
		(layer "F.Cu")
		(at 187.842652 -424.87977 -90)
		(property "Reference" "R4901"
			(at 0 0 270)
			(layer "F.SilkS")
			(hide yes)
			(effects
				(font
					(size 1.27 1.27)
				)
			)
		)
		(property "Value" ""
			(at 0 0 270)
			(layer "F.Fab")
			(effects
				(font
					(size 1.27 1.27)
				)
			)
		)
		(duplicate_pad_numbers_are_jumpers no)
		(fp_line
			(start -0.7874 0.4064)
			(end -0.7874 -0.4064)
			(stroke
				(width 0.1524)
				(type default)
			)
			(layer "F.SilkS")
		)
		(fp_line
			(start 0.7874 0.4064)
			(end -0.7874 0.4064)
			(stroke
				(width 0.1524)
				(type default)
			)
			(layer "F.SilkS")
		)
		(fp_line
			(start -0.7874 -0.4064)
			(end 0.7874 -0.4064)
			(stroke
				(width 0.1524)
				(type default)
			)
			(layer "F.SilkS")
		)
		(fp_line
			(start 0.7874 -0.4064)
			(end 0.7874 0.4064)
			(stroke
				(width 0.1524)
				(type default)
			)
			(layer "F.SilkS")
		)
		(fp_line
			(start -0.67945 0.3048)
			(end -0.67945 -0.305054)
			(stroke
				(width 0.1)
				(type default)
			)
			(layer "F.Fab")
		)
		(fp_line
			(start -0.12065 0.3048)
			(end -0.67945 0.3048)
			(stroke
				(width 0.1)
				(type default)
			)
			(layer "F.Fab")
		)
		(fp_line
			(start 0.120396 0.3048)
			(end 0.120396 0.2794)
			(stroke
				(width 0.1)
				(type default)
			)
			(layer "F.Fab")
		)
		(fp_line
			(start 0.67945 0.3048)
			(end 0.120396 0.3048)
			(stroke
				(width 0.1)
				(type default)
			)
			(layer "F.Fab")
		)
		(fp_line
			(start -0.12065 0.2794)
			(end -0.12065 0.3048)
			(stroke
				(width 0.1)
				(type default)
			)
			(layer "F.Fab")
		)
		(fp_line
			(start 0.120396 0.2794)
			(end -0.12065 0.2794)
			(stroke
				(width 0.1)
				(type default)
			)
			(layer "F.Fab")
		)
		(fp_line
			(start -0.12065 -0.2794)
			(end 0.12065 -0.2794)
			(stroke
				(width 0.1)
				(type default)
			)
			(layer "F.Fab")
		)
		(fp_line
			(start 0.12065 -0.2794)
			(end 0.12065 -0.3048)
			(stroke
				(width 0.1)
				(type default)
			)
			(layer "F.Fab")
		)
		(fp_line
			(start 0.12065 -0.3048)
			(end 0.67945 -0.3048)
			(stroke
				(width 0.1)
				(type default)
			)
			(layer "F.Fab")
		)
		(fp_line
			(start 0.67945 -0.3048)
			(end 0.67945 0.3048)
			(stroke
				(width 0.1)
				(type default)
			)
			(layer "F.Fab")
		)
		(fp_line
			(start -0.67945 -0.305054)
			(end -0.12065 -0.305054)
			(stroke
				(width 0.1)
				(type default)
			)
			(layer "F.Fab")
		)
		(fp_line
			(start -0.12065 -0.305054)
			(end -0.12065 -0.2794)
			(stroke
				(width 0.1)
				(type default)
			)
			(layer "F.Fab")
		)
		(pad "1" smd circle
			(at -0.40005 0 270)
			(size 0 0)
			(layers "F.Cu" "F.Mask" "F.Paste")
			(net "P12V_PSU_FUSE")
		)
		(pad "2" smd circle
			(at 0.40005 0 270)
			(size 0 0)
			(layers "F.Cu" "F.Mask" "F.Paste")
			(net "HSC_EN")
		)
	)
	(footprint ""
		(layer "F.Cu")
		(at 118.6561 -362.501942 -90)
		(property "Reference" "PU174"
			(at -2.940558 0.323342 0)
			(unlocked yes)
			(layer "F.SilkS")
			(effects
				(font
					(size 0.7874 0.5842)
					(thickness 0.1524)
				)
			)
		)
		(property "Value" ""
			(at 0 0 270)
			(layer "F.Fab")
			(effects
				(font
					(size 1.27 1.27)
				)
			)
		)
		(duplicate_pad_numbers_are_jumpers no)
		(fp_line
			(start -1.949958 1.610106)
			(end -1.949958 -1.610106)
			(stroke
				(width 0.1524)
				(type default)
			)
			(layer "F.SilkS")
		)
		(fp_line
			(start 1.949958 1.610106)
			(end -1.949958 1.610106)
			(stroke
				(width 0.1524)
				(type default)
			)
			(layer "F.SilkS")
		)
		(fp_line
			(start 1.949958 -1.560068)
			(end 1.949958 1.610106)
			(stroke
				(width 0.1524)
				(type default)
			)
			(layer "F.SilkS")
		)
		(fp_line
			(start -1.949958 -1.610106)
			(end 1.949958 -1.610106)
			(stroke
				(width 0.1524)
				(type default)
			)
			(layer "F.SilkS")
		)
		(fp_line
			(start -0.750062 1.560068)
			(end -0.750062 -1.560068)
			(stroke
				(width 0.1)
				(type default)
			)
			(layer "F.Fab")
		)
		(fp_line
			(start 0.750062 1.560068)
			(end -0.750062 1.560068)
			(stroke
				(width 0.1)
				(type default)
			)
			(layer "F.Fab")
		)
		(fp_line
			(start -0.750062 -1.560068)
			(end 0.750062 -1.560068)
			(stroke
				(width 0.1)
				(type default)
			)
			(layer "F.Fab")
		)
		(fp_line
			(start 0.750062 -1.560068)
			(end 0.750062 1.560068)
			(stroke
				(width 0.1)
				(type default)
			)
			(layer "F.Fab")
		)
		(pad "D" smd rect
			(at 1.100074 0 180)
			(size 1.016 1.4224)
			(layers "F.Cu" "F.Mask" "F.Paste")
			(net "FM_HBM_VPP_SEL_CPU1_D")
		)
		(pad "G" smd rect
			(at -1.100074 -0.94996 180)
			(size 1.016 1.4224)
			(layers "F.Cu" "F.Mask" "F.Paste")
			(net "FM_HBM2_HBM3_VPP_SEL")
		)
		(pad "S" smd rect
			(at -1.100074 0.94996 180)
			(size 1.016 1.4224)
			(layers "F.Cu" "F.Mask" "F.Paste")
			(net "SH_PVPP_HBM_CPU1_N")
		)
	)
	(footprint ""
		(layer "F.Cu")
		(at 194.2719 -65.225168 -90)
		(property "Reference" "PC2204"
			(at 0 0 270)
			(layer "F.SilkS")
			(hide yes)
			(effects
				(font
					(size 1.27 1.27)
				)
			)
		)
		(property "Value" ""
			(at 0 0 270)
			(layer "F.Fab")
			(effects
				(font
					(size 1.27 1.27)
				)
			)
		)
		(duplicate_pad_numbers_are_jumpers no)
		(fp_line
			(start -1.524 0.762)
			(end -1.524 -0.762)
			(stroke
				(width 0.1524)
				(type default)
			)
			(layer "F.SilkS")
		)
		(fp_line
			(start 1.524 0.762)
			(end -1.524 0.762)
			(stroke
				(width 0.1524)
				(type default)
			)
			(layer "F.SilkS")
		)
		(fp_line
			(start -1.524 -0.762)
			(end 1.524 -0.762)
			(stroke
				(width 0.1524)
				(type default)
			)
			(layer "F.SilkS")
		)
		(fp_line
			(start 1.524 -0.762)
			(end 1.524 0.762)
			(stroke
				(width 0.1524)
				(type default)
			)
			(layer "F.SilkS")
		)
		(fp_line
			(start -1.1049 0.724916)
			(end 1.1049 0.724916)
			(stroke
				(width 0.1)
				(type default)
			)
			(layer "F.Fab")
		)
		(fp_line
			(start 1.1049 0.724916)
			(end 1.1049 -0.724916)
			(stroke
				(width 0.1)
				(type default)
			)
			(layer "F.Fab")
		)
		(fp_line
			(start -1.1049 -0.724916)
			(end -1.1049 0.724916)
			(stroke
				(width 0.1)
				(type default)
			)
			(layer "F.Fab")
		)
		(fp_line
			(start 1.1049 -0.724916)
			(end -1.1049 -0.724916)
			(stroke
				(width 0.1)
				(type default)
			)
			(layer "F.Fab")
		)
		(pad "1" smd rect
			(at -0.889 0 90)
			(size 1.016 1.27)
			(layers "F.Cu" "F.Mask" "F.Paste")
			(net "P3V3_E1S_0_R")
		)
		(pad "2" smd rect
			(at 0.889 0 90)
			(size 1.016 1.27)
			(layers "F.Cu" "F.Mask" "F.Paste")
			(net "GND")
		)
	)
	(footprint ""
		(layer "F.Cu")
		(at 348.044008 -20.602194)
		(property "Reference" "R1827"
			(at 0 0 0)
			(layer "F.SilkS")
			(hide yes)
			(effects
				(font
					(size 1.27 1.27)
				)
			)
		)
		(property "Value" ""
			(at 0 0 0)
			(layer "F.Fab")
			(effects
				(font
					(size 1.27 1.27)
				)
			)
		)
		(duplicate_pad_numbers_are_jumpers no)
		(fp_line
			(start -0.7874 -0.4064)
			(end 0.7874 -0.4064)
			(stroke
				(width 0.1524)
				(type default)
			)
			(layer "F.SilkS")
		)
		(fp_line
			(start -0.7874 0.4064)
			(end -0.7874 -0.4064)
			(stroke
				(width 0.1524)
				(type default)
			)
			(layer "F.SilkS")
		)
		(fp_line
			(start 0.7874 -0.4064)
			(end 0.7874 0.4064)
			(stroke
				(width 0.1524)
				(type default)
			)
			(layer "F.SilkS")
		)
		(fp_line
			(start 0.7874 0.4064)
			(end -0.7874 0.4064)
			(stroke
				(width 0.1524)
				(type default)
			)
			(layer "F.SilkS")
		)
		(fp_line
			(start -0.67945 -0.305054)
			(end -0.12065 -0.305054)
			(stroke
				(width 0.1)
				(type default)
			)
			(layer "F.Fab")
		)
		(fp_line
			(start -0.67945 0.3048)
			(end -0.67945 -0.305054)
			(stroke
				(width 0.1)
				(type default)
			)
			(layer "F.Fab")
		)
		(fp_line
			(start -0.12065 -0.305054)
			(end -0.12065 -0.2794)
			(stroke
				(width 0.1)
				(type default)
			)
			(layer "F.Fab")
		)
		(fp_line
			(start -0.12065 -0.2794)
			(end 0.12065 -0.2794)
			(stroke
				(width 0.1)
				(type default)
			)
			(layer "F.Fab")
		)
		(fp_line
			(start -0.12065 0.2794)
			(end -0.12065 0.3048)
			(stroke
				(width 0.1)
				(type default)
			)
			(layer "F.Fab")
		)
		(fp_line
			(start -0.12065 0.3048)
			(end -0.67945 0.3048)
			(stroke
				(width 0.1)
				(type default)
			)
			(layer "F.Fab")
		)
		(fp_line
			(start 0.120396 0.2794)
			(end -0.12065 0.2794)
			(stroke
				(width 0.1)
				(type default)
			)
			(layer "F.Fab")
		)
		(fp_line
			(start 0.120396 0.3048)
			(end 0.120396 0.2794)
			(stroke
				(width 0.1)
				(type default)
			)
			(layer "F.Fab")
		)
		(fp_line
			(start 0.12065 -0.3048)
			(end 0.67945 -0.3048)
			(stroke
				(width 0.1)
				(type default)
			)
			(layer "F.Fab")
		)
		(fp_line
			(start 0.12065 -0.2794)
			(end 0.12065 -0.3048)
			(stroke
				(width 0.1)
				(type default)
			)
			(layer "F.Fab")
		)
		(fp_line
			(start 0.67945 -0.3048)
			(end 0.67945 0.3048)
			(stroke
				(width 0.1)
				(type default)
			)
			(layer "F.Fab")
		)
		(fp_line
			(start 0.67945 0.3048)
			(end 0.120396 0.3048)
			(stroke
				(width 0.1)
				(type default)
			)
			(layer "F.Fab")
		)
		(pad "1" smd circle
			(at -0.40005 0)
			(size 0 0)
			(layers "F.Cu" "F.Mask" "F.Paste")
			(net "USB_OC1_REAR_R_N")
		)
		(pad "2" smd circle
			(at 0.40005 0)
			(size 0 0)
			(layers "F.Cu" "F.Mask" "F.Paste")
			(net "USB_OC1_REAR_N")
		)
	)
	(footprint ""
		(layer "F.Cu")
		(at 317.396622 -55.794148)
		(property "Reference" "R1496"
			(at 0 0 0)
			(layer "F.SilkS")
			(hide yes)
			(effects
				(font
					(size 1.27 1.27)
				)
			)
		)
		(property "Value" ""
			(at 0 0 0)
			(layer "F.Fab")
			(effects
				(font
					(size 1.27 1.27)
				)
			)
		)
		(duplicate_pad_numbers_are_jumpers no)
		(fp_line
			(start -0.7874 -0.4064)
			(end 0.7874 -0.4064)
			(stroke
				(width 0.1524)
				(type default)
			)
			(layer "F.SilkS")
		)
		(fp_line
			(start -0.7874 0.4064)
			(end -0.7874 -0.4064)
			(stroke
				(width 0.1524)
				(type default)
			)
			(layer "F.SilkS")
		)
		(fp_line
			(start 0.7874 -0.4064)
			(end 0.7874 0.4064)
			(stroke
				(width 0.1524)
				(type default)
			)
			(layer "F.SilkS")
		)
		(fp_line
			(start 0.7874 0.4064)
			(end -0.7874 0.4064)
			(stroke
				(width 0.1524)
				(type default)
			)
			(layer "F.SilkS")
		)
		(fp_line
			(start -0.67945 -0.305054)
			(end -0.12065 -0.305054)
			(stroke
				(width 0.1)
				(type default)
			)
			(layer "F.Fab")
		)
		(fp_line
			(start -0.67945 0.3048)
			(end -0.67945 -0.305054)
			(stroke
				(width 0.1)
				(type default)
			)
			(layer "F.Fab")
		)
		(fp_line
			(start -0.12065 -0.305054)
			(end -0.12065 -0.2794)
			(stroke
				(width 0.1)
				(type default)
			)
			(layer "F.Fab")
		)
		(fp_line
			(start -0.12065 -0.2794)
			(end 0.12065 -0.2794)
			(stroke
				(width 0.1)
				(type default)
			)
			(layer "F.Fab")
		)
		(fp_line
			(start -0.12065 0.2794)
			(end -0.12065 0.3048)
			(stroke
				(width 0.1)
				(type default)
			)
			(layer "F.Fab")
		)
		(fp_line
			(start -0.12065 0.3048)
			(end -0.67945 0.3048)
			(stroke
				(width 0.1)
				(type default)
			)
			(layer "F.Fab")
		)
		(fp_line
			(start 0.120396 0.2794)
			(end -0.12065 0.2794)
			(stroke
				(width 0.1)
				(type default)
			)
			(layer "F.Fab")
		)
		(fp_line
			(start 0.120396 0.3048)
			(end 0.120396 0.2794)
			(stroke
				(width 0.1)
				(type default)
			)
			(layer "F.Fab")
		)
		(fp_line
			(start 0.12065 -0.3048)
			(end 0.67945 -0.3048)
			(stroke
				(width 0.1)
				(type default)
			)
			(layer "F.Fab")
		)
		(fp_line
			(start 0.12065 -0.2794)
			(end 0.12065 -0.3048)
			(stroke
				(width 0.1)
				(type default)
			)
			(layer "F.Fab")
		)
		(fp_line
			(start 0.67945 -0.3048)
			(end 0.67945 0.3048)
			(stroke
				(width 0.1)
				(type default)
			)
			(layer "F.Fab")
		)
		(fp_line
			(start 0.67945 0.3048)
			(end 0.120396 0.3048)
			(stroke
				(width 0.1)
				(type default)
			)
			(layer "F.Fab")
		)
		(pad "1" smd circle
			(at -0.40005 0)
			(size 0 0)
			(layers "F.Cu" "F.Mask" "F.Paste")
			(net "P3V3_AUX")
		)
		(pad "2" smd circle
			(at 0.40005 0)
			(size 0 0)
			(layers "F.Cu" "F.Mask" "F.Paste")
			(net "FM_PCH_DFXTESTMODE")
		)
	)
	(footprint ""
		(layer "F.Cu")
		(at 431.202592 -118.815104 -90)
		(property "Reference" "PC1196"
			(at 0 0 270)
			(layer "F.SilkS")
			(hide yes)
			(effects
				(font
					(size 1.27 1.27)
				)
			)
		)
		(property "Value" ""
			(at 0 0 270)
			(layer "F.Fab")
			(effects
				(font
					(size 1.27 1.27)
				)
			)
		)
		(duplicate_pad_numbers_are_jumpers no)
		(fp_line
			(start -0.7874 0.4064)
			(end -0.7874 -0.4064)
			(stroke
				(width 0.1524)
				(type default)
			)
			(layer "F.SilkS")
		)
		(fp_line
			(start 0.7874 0.4064)
			(end -0.7874 0.4064)
			(stroke
				(width 0.1524)
				(type default)
			)
			(layer "F.SilkS")
		)
		(fp_line
			(start -0.7874 -0.4064)
			(end 0.7874 -0.4064)
			(stroke
				(width 0.1524)
				(type default)
			)
			(layer "F.SilkS")
		)
		(fp_line
			(start 0.7874 -0.4064)
			(end 0.7874 0.4064)
			(stroke
				(width 0.1524)
				(type default)
			)
			(layer "F.SilkS")
		)
		(fp_line
			(start -0.67945 0.3048)
			(end -0.67945 -0.305054)
			(stroke
				(width 0.1)
				(type default)
			)
			(layer "F.Fab")
		)
		(fp_line
			(start -0.12065 0.3048)
			(end -0.67945 0.3048)
			(stroke
				(width 0.1)
				(type default)
			)
			(layer "F.Fab")
		)
		(fp_line
			(start 0.120396 0.3048)
			(end 0.120396 0.2794)
			(stroke
				(width 0.1)
				(type default)
			)
			(layer "F.Fab")
		)
		(fp_line
			(start 0.67945 0.3048)
			(end 0.120396 0.3048)
			(stroke
				(width 0.1)
				(type default)
			)
			(layer "F.Fab")
		)
		(fp_line
			(start -0.12065 0.2794)
			(end -0.12065 0.3048)
			(stroke
				(width 0.1)
				(type default)
			)
			(layer "F.Fab")
		)
		(fp_line
			(start 0.120396 0.2794)
			(end -0.12065 0.2794)
			(stroke
				(width 0.1)
				(type default)
			)
			(layer "F.Fab")
		)
		(fp_line
			(start -0.12065 -0.2794)
			(end 0.12065 -0.2794)
			(stroke
				(width 0.1)
				(type default)
			)
			(layer "F.Fab")
		)
		(fp_line
			(start 0.12065 -0.2794)
			(end 0.12065 -0.3048)
			(stroke
				(width 0.1)
				(type default)
			)
			(layer "F.Fab")
		)
		(fp_line
			(start 0.12065 -0.3048)
			(end 0.67945 -0.3048)
			(stroke
				(width 0.1)
				(type default)
			)
			(layer "F.Fab")
		)
		(fp_line
			(start 0.67945 -0.3048)
			(end 0.67945 0.3048)
			(stroke
				(width 0.1)
				(type default)
			)
			(layer "F.Fab")
		)
		(fp_line
			(start -0.67945 -0.305054)
			(end -0.12065 -0.305054)
			(stroke
				(width 0.1)
				(type default)
			)
			(layer "F.Fab")
		)
		(fp_line
			(start -0.12065 -0.305054)
			(end -0.12065 -0.2794)
			(stroke
				(width 0.1)
				(type default)
			)
			(layer "F.Fab")
		)
		(pad "1" smd circle
			(at -0.40005 0 270)
			(size 0 0)
			(layers "F.Cu" "F.Mask" "F.Paste")
			(net "PVCCD_HV_CPU0_VREF")
		)
		(pad "2" smd circle
			(at 0.40005 0 270)
			(size 0 0)
			(layers "F.Cu" "F.Mask" "F.Paste")
			(net "GND")
		)
	)
	(footprint ""
		(layer "F.Cu")
		(at 297.41622 -419.02761 -90)
		(property "Reference" "R4134"
			(at 0 0 270)
			(layer "F.SilkS")
			(hide yes)
			(effects
				(font
					(size 1.27 1.27)
				)
			)
		)
		(property "Value" ""
			(at 0 0 270)
			(layer "F.Fab")
			(effects
				(font
					(size 1.27 1.27)
				)
			)
		)
		(duplicate_pad_numbers_are_jumpers no)
		(fp_line
			(start -0.7874 0.4064)
			(end -0.7874 -0.4064)
			(stroke
				(width 0.1524)
				(type default)
			)
			(layer "F.SilkS")
		)
		(fp_line
			(start 0.7874 0.4064)
			(end -0.7874 0.4064)
			(stroke
				(width 0.1524)
				(type default)
			)
			(layer "F.SilkS")
		)
		(fp_line
			(start -0.7874 -0.4064)
			(end 0.7874 -0.4064)
			(stroke
				(width 0.1524)
				(type default)
			)
			(layer "F.SilkS")
		)
		(fp_line
			(start 0.7874 -0.4064)
			(end 0.7874 0.4064)
			(stroke
				(width 0.1524)
				(type default)
			)
			(layer "F.SilkS")
		)
		(fp_line
			(start -0.67945 0.3048)
			(end -0.67945 -0.305054)
			(stroke
				(width 0.1)
				(type default)
			)
			(layer "F.Fab")
		)
		(fp_line
			(start -0.12065 0.3048)
			(end -0.67945 0.3048)
			(stroke
				(width 0.1)
				(type default)
			)
			(layer "F.Fab")
		)
		(fp_line
			(start 0.120396 0.3048)
			(end 0.120396 0.2794)
			(stroke
				(width 0.1)
				(type default)
			)
			(layer "F.Fab")
		)
		(fp_line
			(start 0.67945 0.3048)
			(end 0.120396 0.3048)
			(stroke
				(width 0.1)
				(type default)
			)
			(layer "F.Fab")
		)
		(fp_line
			(start -0.12065 0.2794)
			(end -0.12065 0.3048)
			(stroke
				(width 0.1)
				(type default)
			)
			(layer "F.Fab")
		)
		(fp_line
			(start 0.120396 0.2794)
			(end -0.12065 0.2794)
			(stroke
				(width 0.1)
				(type default)
			)
			(layer "F.Fab")
		)
		(fp_line
			(start -0.12065 -0.2794)
			(end 0.12065 -0.2794)
			(stroke
				(width 0.1)
				(type default)
			)
			(layer "F.Fab")
		)
		(fp_line
			(start 0.12065 -0.2794)
			(end 0.12065 -0.3048)
			(stroke
				(width 0.1)
				(type default)
			)
			(layer "F.Fab")
		)
		(fp_line
			(start 0.12065 -0.3048)
			(end 0.67945 -0.3048)
			(stroke
				(width 0.1)
				(type default)
			)
			(layer "F.Fab")
		)
		(fp_line
			(start 0.67945 -0.3048)
			(end 0.67945 0.3048)
			(stroke
				(width 0.1)
				(type default)
			)
			(layer "F.Fab")
		)
		(fp_line
			(start -0.67945 -0.305054)
			(end -0.12065 -0.305054)
			(stroke
				(width 0.1)
				(type default)
			)
			(layer "F.Fab")
		)
		(fp_line
			(start -0.12065 -0.305054)
			(end -0.12065 -0.2794)
			(stroke
				(width 0.1)
				(type default)
			)
			(layer "F.Fab")
		)
		(pad "1" smd circle
			(at -0.40005 0 270)
			(size 0 0)
			(layers "F.Cu" "F.Mask" "F.Paste")
			(net "GPU_3V3IO_RSVD5_FFU")
		)
		(pad "2" smd circle
			(at 0.40005 0 270)
			(size 0 0)
			(layers "F.Cu" "F.Mask" "F.Paste")
			(net "GND")
		)
	)
	(footprint ""
		(layer "F.Cu")
		(at 161.163 -99.786948)
		(property "Reference" "R1754"
			(at 0 0 0)
			(layer "F.SilkS")
			(hide yes)
			(effects
				(font
					(size 1.27 1.27)
				)
			)
		)
		(property "Value" ""
			(at 0 0 0)
			(layer "F.Fab")
			(effects
				(font
					(size 1.27 1.27)
				)
			)
		)
		(duplicate_pad_numbers_are_jumpers no)
		(fp_line
			(start -0.7874 -0.4064)
			(end 0.7874 -0.4064)
			(stroke
				(width 0.1524)
				(type default)
			)
			(layer "F.SilkS")
		)
		(fp_line
			(start -0.7874 0.4064)
			(end -0.7874 -0.4064)
			(stroke
				(width 0.1524)
				(type default)
			)
			(layer "F.SilkS")
		)
		(fp_line
			(start 0.7874 -0.4064)
			(end 0.7874 0.4064)
			(stroke
				(width 0.1524)
				(type default)
			)
			(layer "F.SilkS")
		)
		(fp_line
			(start 0.7874 0.4064)
			(end -0.7874 0.4064)
			(stroke
				(width 0.1524)
				(type default)
			)
			(layer "F.SilkS")
		)
		(fp_line
			(start -0.67945 -0.305054)
			(end -0.12065 -0.305054)
			(stroke
				(width 0.1)
				(type default)
			)
			(layer "F.Fab")
		)
		(fp_line
			(start -0.67945 0.3048)
			(end -0.67945 -0.305054)
			(stroke
				(width 0.1)
				(type default)
			)
			(layer "F.Fab")
		)
		(fp_line
			(start -0.12065 -0.305054)
			(end -0.12065 -0.2794)
			(stroke
				(width 0.1)
				(type default)
			)
			(layer "F.Fab")
		)
		(fp_line
			(start -0.12065 -0.2794)
			(end 0.12065 -0.2794)
			(stroke
				(width 0.1)
				(type default)
			)
			(layer "F.Fab")
		)
		(fp_line
			(start -0.12065 0.2794)
			(end -0.12065 0.3048)
			(stroke
				(width 0.1)
				(type default)
			)
			(layer "F.Fab")
		)
		(fp_line
			(start -0.12065 0.3048)
			(end -0.67945 0.3048)
			(stroke
				(width 0.1)
				(type default)
			)
			(layer "F.Fab")
		)
		(fp_line
			(start 0.120396 0.2794)
			(end -0.12065 0.2794)
			(stroke
				(width 0.1)
				(type default)
			)
			(layer "F.Fab")
		)
		(fp_line
			(start 0.120396 0.3048)
			(end 0.120396 0.2794)
			(stroke
				(width 0.1)
				(type default)
			)
			(layer "F.Fab")
		)
		(fp_line
			(start 0.12065 -0.3048)
			(end 0.67945 -0.3048)
			(stroke
				(width 0.1)
				(type default)
			)
			(layer "F.Fab")
		)
		(fp_line
			(start 0.12065 -0.2794)
			(end 0.12065 -0.3048)
			(stroke
				(width 0.1)
				(type default)
			)
			(layer "F.Fab")
		)
		(fp_line
			(start 0.67945 -0.3048)
			(end 0.67945 0.3048)
			(stroke
				(width 0.1)
				(type default)
			)
			(layer "F.Fab")
		)
		(fp_line
			(start 0.67945 0.3048)
			(end 0.120396 0.3048)
			(stroke
				(width 0.1)
				(type default)
			)
			(layer "F.Fab")
		)
		(pad "1" smd circle
			(at -0.40005 0)
			(size 0 0)
			(layers "F.Cu" "F.Mask" "F.Paste")
			(net "SGPIO_LD_0")
		)
		(pad "2" smd circle
			(at 0.40005 0)
			(size 0 0)
			(layers "F.Cu" "F.Mask" "F.Paste")
			(net "SGPIO_DEBUG_PLD_LD_N")
		)
	)
	(footprint ""
		(layer "F.Cu")
		(at 14.886178 -107.123484 180)
		(property "Reference" "R4482"
			(at 0 0 180)
			(layer "F.SilkS")
			(hide yes)
			(effects
				(font
					(size 1.27 1.27)
				)
			)
		)
		(property "Value" ""
			(at 0 0 180)
			(layer "F.Fab")
			(effects
				(font
					(size 1.27 1.27)
				)
			)
		)
		(duplicate_pad_numbers_are_jumpers no)
		(fp_line
			(start 0.7874 0.4064)
			(end -0.013462 0.4064)
			(stroke
				(width 0.1524)
				(type default)
			)
			(layer "F.SilkS")
		)
		(fp_line
			(start 0.7874 -0.4064)
			(end 0.7874 0.4064)
			(stroke
				(width 0.1524)
				(type default)
			)
			(layer "F.SilkS")
		)
		(fp_line
			(start -0.003302 -0.4064)
			(end 0.7874 -0.4064)
			(stroke
				(width 0.1524)
				(type default)
			)
			(layer "F.SilkS")
		)
		(fp_line
			(start 0.67945 0.3048)
			(end 0.120396 0.3048)
			(stroke
				(width 0.1)
				(type default)
			)
			(layer "F.Fab")
		)
		(fp_line
			(start 0.67945 -0.3048)
			(end 0.67945 0.3048)
			(stroke
				(width 0.1)
				(type default)
			)
			(layer "F.Fab")
		)
		(fp_line
			(start 0.12065 -0.2794)
			(end 0.12065 -0.3048)
			(stroke
				(width 0.1)
				(type default)
			)
			(layer "F.Fab")
		)
		(fp_line
			(start 0.12065 -0.3048)
			(end 0.67945 -0.3048)
			(stroke
				(width 0.1)
				(type default)
			)
			(layer "F.Fab")
		)
		(fp_line
			(start 0.120396 0.3048)
			(end 0.120396 0.2794)
			(stroke
				(width 0.1)
				(type default)
			)
			(layer "F.Fab")
		)
		(fp_line
			(start 0.120396 0.2794)
			(end -0.12065 0.2794)
			(stroke
				(width 0.1)
				(type default)
			)
			(layer "F.Fab")
		)
		(fp_line
			(start -0.12065 0.3048)
			(end -0.67945 0.3048)
			(stroke
				(width 0.1)
				(type default)
			)
			(layer "F.Fab")
		)
		(fp_line
			(start -0.12065 0.2794)
			(end -0.12065 0.3048)
			(stroke
				(width 0.1)
				(type default)
			)
			(layer "F.Fab")
		)
		(fp_line
			(start -0.12065 -0.2794)
			(end 0.12065 -0.2794)
			(stroke
				(width 0.1)
				(type default)
			)
			(layer "F.Fab")
		)
		(fp_line
			(start -0.12065 -0.305054)
			(end -0.12065 -0.2794)
			(stroke
				(width 0.1)
				(type default)
			)
			(layer "F.Fab")
		)
		(fp_line
			(start -0.67945 0.3048)
			(end -0.67945 -0.305054)
			(stroke
				(width 0.1)
				(type default)
			)
			(layer "F.Fab")
		)
		(fp_line
			(start -0.67945 -0.305054)
			(end -0.12065 -0.305054)
			(stroke
				(width 0.1)
				(type default)
			)
			(layer "F.Fab")
		)
		(pad "1" smd circle
			(at -0.40005 0 180)
			(size 0 0)
			(layers "F.Cu" "F.Mask" "F.Paste")
			(net "USB2_HOST_BMC_B_BUF_DP")
		)
		(pad "2" smd circle
			(at 0.40005 0 180)
			(size 0 0)
			(layers "F.Cu" "F.Mask" "F.Paste")
			(net "GND")
		)
	)
	(footprint ""
		(layer "F.Cu")
		(at 488.89793 -467.88705)
		(property "Reference" "U2_DC"
			(at -3.00355 1.898142 0)
			(unlocked yes)
			(layer "F.SilkS")
			(effects
				(font
					(size 0.7874 0.5842)
					(thickness 0.1524)
				)
				(justify left)
			)
		)
		(property "Value" ""
			(at 0 0 0)
			(layer "F.Fab")
			(effects
				(font
					(size 1.27 1.27)
				)
			)
		)
		(duplicate_pad_numbers_are_jumpers no)
		(pad "1" smd circle
			(at 0 0)
			(size 0.762 0.762)
			(layers "F.Cu" "F.Mask" "F.Paste")
			(net "Net_8483")
		)
	)
	(footprint ""
		(layer "F.Cu")
		(at 111.74222 -294.01008 180)
		(property "Reference" "C230"
			(at 0 0 180)
			(layer "F.SilkS")
			(hide yes)
			(effects
				(font
					(size 1.27 1.27)
				)
			)
		)
		(property "Value" ""
			(at 0 0 180)
			(layer "F.Fab")
			(effects
				(font
					(size 1.27 1.27)
				)
			)
		)
		(duplicate_pad_numbers_are_jumpers no)
		(fp_line
			(start 1.524 0.762)
			(end -1.524 0.762)
			(stroke
				(width 0.1524)
				(type default)
			)
			(layer "F.SilkS")
		)
		(fp_line
			(start 1.524 -0.762)
			(end 1.524 0.762)
			(stroke
				(width 0.1524)
				(type default)
			)
			(layer "F.SilkS")
		)
		(fp_line
			(start -1.524 0.762)
			(end -1.524 -0.762)
			(stroke
				(width 0.1524)
				(type default)
			)
			(layer "F.SilkS")
		)
		(fp_line
			(start -1.524 -0.762)
			(end 1.524 -0.762)
			(stroke
				(width 0.1524)
				(type default)
			)
			(layer "F.SilkS")
		)
		(fp_line
			(start 1.1049 0.724916)
			(end 1.1049 -0.724916)
			(stroke
				(width 0.1)
				(type default)
			)
			(layer "F.Fab")
		)
		(fp_line
			(start 1.1049 -0.724916)
			(end -1.1049 -0.724916)
			(stroke
				(width 0.1)
				(type default)
			)
			(layer "F.Fab")
		)
		(fp_line
			(start -1.1049 0.724916)
			(end 1.1049 0.724916)
			(stroke
				(width 0.1)
				(type default)
			)
			(layer "F.Fab")
		)
		(fp_line
			(start -1.1049 -0.724916)
			(end -1.1049 0.724916)
			(stroke
				(width 0.1)
				(type default)
			)
			(layer "F.Fab")
		)
		(pad "1" smd rect
			(at -0.889 0)
			(size 1.016 1.27)
			(layers "F.Cu" "F.Mask" "F.Paste")
			(net "PVCCIN_CPU1")
		)
		(pad "2" smd rect
			(at 0.889 0)
			(size 1.016 1.27)
			(layers "F.Cu" "F.Mask" "F.Paste")
			(net "GND")
		)
	)
	(footprint ""
		(layer "F.Cu")
		(at 215.351614 -99.79152)
		(property "Reference" "U206"
			(at -2.2606 -2.174748 0)
			(unlocked yes)
			(layer "F.SilkS")
			(effects
				(font
					(size 0.7874 0.5842)
					(thickness 0.1524)
				)
				(justify left)
			)
		)
		(property "Value" ""
			(at 0 0 0)
			(layer "F.Fab")
			(effects
				(font
					(size 1.27 1.27)
				)
			)
		)
		(duplicate_pad_numbers_are_jumpers no)
		(fp_line
			(start -2.046478 -1.450086)
			(end -2.046478 1.450086)
			(stroke
				(width 0.1524)
				(type default)
			)
			(layer "F.SilkS")
		)
		(fp_line
			(start -2.046478 1.450086)
			(end 2.046478 1.450086)
			(stroke
				(width 0.1524)
				(type default)
			)
			(layer "F.SilkS")
		)
		(fp_line
			(start -0.484886 -1.450086)
			(end -2.046478 -1.450086)
			(stroke
				(width 0.1524)
				(type default)
			)
			(layer "F.SilkS")
		)
		(fp_line
			(start 0 -0.762)
			(end -0.484886 -1.450086)
			(stroke
				(width 0.1524)
				(type default)
			)
			(layer "F.SilkS")
		)
		(fp_line
			(start 0.484886 -1.450086)
			(end 0 -0.762)
			(stroke
				(width 0.1524)
				(type default)
			)
			(layer "F.SilkS")
		)
		(fp_line
			(start 2.046478 -1.450086)
			(end 0.484886 -1.450086)
			(stroke
				(width 0.1524)
				(type default)
			)
			(layer "F.SilkS")
		)
		(fp_line
			(start 2.046478 1.450086)
			(end 2.046478 -1.450086)
			(stroke
				(width 0.1524)
				(type default)
			)
			(layer "F.SilkS")
		)
		(fp_poly
			(pts
				(xy -3.2512 -0.44196) (xy -3.2512 -1.45796) (xy -2.2352 -0.94996)
			)
			(stroke
				(width 0)
				(type default)
			)
			(fill yes)
			(layer "F.SilkS")
		)
		(fp_line
			(start -0.87503 -1.450086)
			(end -0.87503 1.450086)
			(stroke
				(width 0.1)
				(type default)
			)
			(layer "F.Fab")
		)
		(fp_line
			(start -0.87503 1.450086)
			(end 0.87503 1.450086)
			(stroke
				(width 0.1)
				(type default)
			)
			(layer "F.Fab")
		)
		(fp_line
			(start 0.87503 -1.450086)
			(end -0.87503 -1.450086)
			(stroke
				(width 0.1)
				(type default)
			)
			(layer "F.Fab")
		)
		(fp_line
			(start 0.87503 1.450086)
			(end 0.87503 -1.450086)
			(stroke
				(width 0.1)
				(type default)
			)
			(layer "F.Fab")
		)
		(fp_poly
			(pts
				(xy -3.2512 -0.44196) (xy -3.2512 -1.45796) (xy -2.2352 -0.94996)
			)
			(stroke
				(width 0)
				(type default)
			)
			(fill yes)
			(layer "F.Fab")
		)
		(pad "1" smd rect
			(at -1.309878 -0.94996 90)
			(size 0.635 1.2192)
			(layers "F.Cu" "F.Mask" "F.Paste")
			(net "FM_UV_ADR_TRIGGER_N")
		)
		(pad "2" smd rect
			(at -1.309878 0 90)
			(size 0.635 1.2192)
			(layers "F.Cu" "F.Mask" "F.Paste")
			(net "GND")
		)
		(pad "3" smd rect
			(at -1.309878 0.94996 90)
			(size 0.635 1.2192)
			(layers "F.Cu" "F.Mask" "F.Paste")
			(net "A_P12V_STBY_ADR_TRIGGER")
		)
		(pad "4" smd rect
			(at 1.309878 0.94996 90)
			(size 0.635 1.2192)
			(layers "F.Cu" "F.Mask" "F.Paste")
			(net "A_P12V_STBY_FP_TRIGGER")
		)
		(pad "5" smd rect
			(at 1.309878 0 90)
			(size 0.635 1.2192)
			(layers "F.Cu" "F.Mask" "F.Paste")
			(net "U206_VDD")
		)
		(pad "6" smd rect
			(at 1.309878 -0.94996 90)
			(size 0.635 1.2192)
			(layers "F.Cu" "F.Mask" "F.Paste")
			(net "A_P12V_STBY_FPH_GATE")
		)
	)
	(footprint ""
		(layer "F.Cu")
		(at 46.067472 -392.183112)
		(property "Reference" "R3362"
			(at 0 0 0)
			(layer "F.SilkS")
			(hide yes)
			(effects
				(font
					(size 1.27 1.27)
				)
			)
		)
		(property "Value" ""
			(at 0 0 0)
			(layer "F.Fab")
			(effects
				(font
					(size 1.27 1.27)
				)
			)
		)
		(duplicate_pad_numbers_are_jumpers no)
		(fp_line
			(start -0.7874 -0.4064)
			(end 0.7874 -0.4064)
			(stroke
				(width 0.1524)
				(type default)
			)
			(layer "F.SilkS")
		)
		(fp_line
			(start -0.7874 0.4064)
			(end -0.7874 -0.4064)
			(stroke
				(width 0.1524)
				(type default)
			)
			(layer "F.SilkS")
		)
		(fp_line
			(start 0.7874 -0.4064)
			(end 0.7874 0.4064)
			(stroke
				(width 0.1524)
				(type default)
			)
			(layer "F.SilkS")
		)
		(fp_line
			(start 0.7874 0.4064)
			(end -0.7874 0.4064)
			(stroke
				(width 0.1524)
				(type default)
			)
			(layer "F.SilkS")
		)
		(fp_line
			(start -0.67945 -0.305054)
			(end -0.12065 -0.305054)
			(stroke
				(width 0.1)
				(type default)
			)
			(layer "F.Fab")
		)
		(fp_line
			(start -0.67945 0.3048)
			(end -0.67945 -0.305054)
			(stroke
				(width 0.1)
				(type default)
			)
			(layer "F.Fab")
		)
		(fp_line
			(start -0.12065 -0.305054)
			(end -0.12065 -0.2794)
			(stroke
				(width 0.1)
				(type default)
			)
			(layer "F.Fab")
		)
		(fp_line
			(start -0.12065 -0.2794)
			(end 0.12065 -0.2794)
			(stroke
				(width 0.1)
				(type default)
			)
			(layer "F.Fab")
		)
		(fp_line
			(start -0.12065 0.2794)
			(end -0.12065 0.3048)
			(stroke
				(width 0.1)
				(type default)
			)
			(layer "F.Fab")
		)
		(fp_line
			(start -0.12065 0.3048)
			(end -0.67945 0.3048)
			(stroke
				(width 0.1)
				(type default)
			)
			(layer "F.Fab")
		)
		(fp_line
			(start 0.120396 0.2794)
			(end -0.12065 0.2794)
			(stroke
				(width 0.1)
				(type default)
			)
			(layer "F.Fab")
		)
		(fp_line
			(start 0.120396 0.3048)
			(end 0.120396 0.2794)
			(stroke
				(width 0.1)
				(type default)
			)
			(layer "F.Fab")
		)
		(fp_line
			(start 0.12065 -0.3048)
			(end 0.67945 -0.3048)
			(stroke
				(width 0.1)
				(type default)
			)
			(layer "F.Fab")
		)
		(fp_line
			(start 0.12065 -0.2794)
			(end 0.12065 -0.3048)
			(stroke
				(width 0.1)
				(type default)
			)
			(layer "F.Fab")
		)
		(fp_line
			(start 0.67945 -0.3048)
			(end 0.67945 0.3048)
			(stroke
				(width 0.1)
				(type default)
			)
			(layer "F.Fab")
		)
		(fp_line
			(start 0.67945 0.3048)
			(end 0.120396 0.3048)
			(stroke
				(width 0.1)
				(type default)
			)
			(layer "F.Fab")
		)
		(pad "1" smd circle
			(at -0.40005 0)
			(size 0 0)
			(layers "F.Cu" "F.Mask" "F.Paste")
			(net "PD_P2E_BUF2_ENSMB")
		)
		(pad "2" smd circle
			(at 0.40005 0)
			(size 0 0)
			(layers "F.Cu" "F.Mask" "F.Paste")
			(net "GND")
		)
	)
	(footprint ""
		(layer "F.Cu")
		(at 45.857922 -358.11841)
		(property "Reference" "PC727_P1_4"
			(at 0 0 0)
			(layer "F.SilkS")
			(hide yes)
			(effects
				(font
					(size 1.27 1.27)
				)
			)
		)
		(property "Value" ""
			(at 0 0 0)
			(layer "F.Fab")
			(effects
				(font
					(size 1.27 1.27)
				)
			)
		)
		(duplicate_pad_numbers_are_jumpers no)
		(fp_line
			(start -1.524 -0.762)
			(end 1.524 -0.762)
			(stroke
				(width 0.1524)
				(type default)
			)
			(layer "F.SilkS")
		)
		(fp_line
			(start -1.524 0.762)
			(end -1.524 -0.762)
			(stroke
				(width 0.1524)
				(type default)
			)
			(layer "F.SilkS")
		)
		(fp_line
			(start 1.524 -0.762)
			(end 1.524 0.762)
			(stroke
				(width 0.1524)
				(type default)
			)
			(layer "F.SilkS")
		)
		(fp_line
			(start 1.524 0.762)
			(end -1.524 0.762)
			(stroke
				(width 0.1524)
				(type default)
			)
			(layer "F.SilkS")
		)
		(fp_line
			(start -1.1049 -0.724916)
			(end -1.1049 0.724916)
			(stroke
				(width 0.1)
				(type default)
			)
			(layer "F.Fab")
		)
		(fp_line
			(start -1.1049 0.724916)
			(end 1.1049 0.724916)
			(stroke
				(width 0.1)
				(type default)
			)
			(layer "F.Fab")
		)
		(fp_line
			(start 1.1049 -0.724916)
			(end -1.1049 -0.724916)
			(stroke
				(width 0.1)
				(type default)
			)
			(layer "F.Fab")
		)
		(fp_line
			(start 1.1049 0.724916)
			(end 1.1049 -0.724916)
			(stroke
				(width 0.1)
				(type default)
			)
			(layer "F.Fab")
		)
		(pad "1" smd rect
			(at -0.889 0 180)
			(size 1.016 1.27)
			(layers "F.Cu" "F.Mask" "F.Paste")
			(net "SW_P12V_PVCCFA_EHV_FIVRA_CPU1_L")
		)
		(pad "2" smd rect
			(at 0.889 0 180)
			(size 1.016 1.27)
			(layers "F.Cu" "F.Mask" "F.Paste")
			(net "GND")
		)
	)
	(footprint ""
		(layer "F.Cu")
		(at 365.2012 -411.5562)
		(property "Reference" "R4799"
			(at 0 0 0)
			(layer "F.SilkS")
			(hide yes)
			(effects
				(font
					(size 1.27 1.27)
				)
			)
		)
		(property "Value" ""
			(at 0 0 0)
			(layer "F.Fab")
			(effects
				(font
					(size 1.27 1.27)
				)
			)
		)
		(duplicate_pad_numbers_are_jumpers no)
		(fp_line
			(start -0.7874 -0.4064)
			(end 0.7874 -0.4064)
			(stroke
				(width 0.1524)
				(type default)
			)
			(layer "F.SilkS")
		)
		(fp_line
			(start -0.7874 0.4064)
			(end -0.7874 -0.4064)
			(stroke
				(width 0.1524)
				(type default)
			)
			(layer "F.SilkS")
		)
		(fp_line
			(start 0.7874 -0.4064)
			(end 0.7874 0.4064)
			(stroke
				(width 0.1524)
				(type default)
			)
			(layer "F.SilkS")
		)
		(fp_line
			(start 0.7874 0.4064)
			(end -0.7874 0.4064)
			(stroke
				(width 0.1524)
				(type default)
			)
			(layer "F.SilkS")
		)
		(fp_line
			(start -0.67945 -0.305054)
			(end -0.12065 -0.305054)
			(stroke
				(width 0.1)
				(type default)
			)
			(layer "F.Fab")
		)
		(fp_line
			(start -0.67945 0.3048)
			(end -0.67945 -0.305054)
			(stroke
				(width 0.1)
				(type default)
			)
			(layer "F.Fab")
		)
		(fp_line
			(start -0.12065 -0.305054)
			(end -0.12065 -0.2794)
			(stroke
				(width 0.1)
				(type default)
			)
			(layer "F.Fab")
		)
		(fp_line
			(start -0.12065 -0.2794)
			(end 0.12065 -0.2794)
			(stroke
				(width 0.1)
				(type default)
			)
			(layer "F.Fab")
		)
		(fp_line
			(start -0.12065 0.2794)
			(end -0.12065 0.3048)
			(stroke
				(width 0.1)
				(type default)
			)
			(layer "F.Fab")
		)
		(fp_line
			(start -0.12065 0.3048)
			(end -0.67945 0.3048)
			(stroke
				(width 0.1)
				(type default)
			)
			(layer "F.Fab")
		)
		(fp_line
			(start 0.120396 0.2794)
			(end -0.12065 0.2794)
			(stroke
				(width 0.1)
				(type default)
			)
			(layer "F.Fab")
		)
		(fp_line
			(start 0.120396 0.3048)
			(end 0.120396 0.2794)
			(stroke
				(width 0.1)
				(type default)
			)
			(layer "F.Fab")
		)
		(fp_line
			(start 0.12065 -0.3048)
			(end 0.67945 -0.3048)
			(stroke
				(width 0.1)
				(type default)
			)
			(layer "F.Fab")
		)
		(fp_line
			(start 0.12065 -0.2794)
			(end 0.12065 -0.3048)
			(stroke
				(width 0.1)
				(type default)
			)
			(layer "F.Fab")
		)
		(fp_line
			(start 0.67945 -0.3048)
			(end 0.67945 0.3048)
			(stroke
				(width 0.1)
				(type default)
			)
			(layer "F.Fab")
		)
		(fp_line
			(start 0.67945 0.3048)
			(end 0.120396 0.3048)
			(stroke
				(width 0.1)
				(type default)
			)
			(layer "F.Fab")
		)
		(pad "1" smd circle
			(at -0.40005 0)
			(size 0 0)
			(layers "F.Cu" "F.Mask" "F.Paste")
			(net "PRSNT_CABLE_GPU_A3_N")
		)
		(pad "2" smd circle
			(at 0.40005 0)
			(size 0 0)
			(layers "F.Cu" "F.Mask" "F.Paste")
			(net "GND")
		)
	)
	(footprint ""
		(layer "F.Cu")
		(at 235.51388 -256.123948 -90)
		(property "Reference" "R3341"
			(at 0 0 270)
			(layer "F.SilkS")
			(hide yes)
			(effects
				(font
					(size 1.27 1.27)
				)
			)
		)
		(property "Value" ""
			(at 0 0 270)
			(layer "F.Fab")
			(effects
				(font
					(size 1.27 1.27)
				)
			)
		)
		(duplicate_pad_numbers_are_jumpers no)
		(fp_line
			(start -0.7874 0.4064)
			(end -0.7874 -0.4064)
			(stroke
				(width 0.1524)
				(type default)
			)
			(layer "F.SilkS")
		)
		(fp_line
			(start 0.7874 0.4064)
			(end -0.7874 0.4064)
			(stroke
				(width 0.1524)
				(type default)
			)
			(layer "F.SilkS")
		)
		(fp_line
			(start -0.7874 -0.4064)
			(end 0.7874 -0.4064)
			(stroke
				(width 0.1524)
				(type default)
			)
			(layer "F.SilkS")
		)
		(fp_line
			(start 0.7874 -0.4064)
			(end 0.7874 0.4064)
			(stroke
				(width 0.1524)
				(type default)
			)
			(layer "F.SilkS")
		)
		(fp_line
			(start -0.67945 0.3048)
			(end -0.67945 -0.305054)
			(stroke
				(width 0.1)
				(type default)
			)
			(layer "F.Fab")
		)
		(fp_line
			(start -0.12065 0.3048)
			(end -0.67945 0.3048)
			(stroke
				(width 0.1)
				(type default)
			)
			(layer "F.Fab")
		)
		(fp_line
			(start 0.120396 0.3048)
			(end 0.120396 0.2794)
			(stroke
				(width 0.1)
				(type default)
			)
			(layer "F.Fab")
		)
		(fp_line
			(start 0.67945 0.3048)
			(end 0.120396 0.3048)
			(stroke
				(width 0.1)
				(type default)
			)
			(layer "F.Fab")
		)
		(fp_line
			(start -0.12065 0.2794)
			(end -0.12065 0.3048)
			(stroke
				(width 0.1)
				(type default)
			)
			(layer "F.Fab")
		)
		(fp_line
			(start 0.120396 0.2794)
			(end -0.12065 0.2794)
			(stroke
				(width 0.1)
				(type default)
			)
			(layer "F.Fab")
		)
		(fp_line
			(start -0.12065 -0.2794)
			(end 0.12065 -0.2794)
			(stroke
				(width 0.1)
				(type default)
			)
			(layer "F.Fab")
		)
		(fp_line
			(start 0.12065 -0.2794)
			(end 0.12065 -0.3048)
			(stroke
				(width 0.1)
				(type default)
			)
			(layer "F.Fab")
		)
		(fp_line
			(start 0.12065 -0.3048)
			(end 0.67945 -0.3048)
			(stroke
				(width 0.1)
				(type default)
			)
			(layer "F.Fab")
		)
		(fp_line
			(start 0.67945 -0.3048)
			(end 0.67945 0.3048)
			(stroke
				(width 0.1)
				(type default)
			)
			(layer "F.Fab")
		)
		(fp_line
			(start -0.67945 -0.305054)
			(end -0.12065 -0.305054)
			(stroke
				(width 0.1)
				(type default)
			)
			(layer "F.Fab")
		)
		(fp_line
			(start -0.12065 -0.305054)
			(end -0.12065 -0.2794)
			(stroke
				(width 0.1)
				(type default)
			)
			(layer "F.Fab")
		)
		(pad "1" smd circle
			(at -0.40005 0 270)
			(size 0 0)
			(layers "F.Cu" "F.Mask" "F.Paste")
			(net "SMB_HOST_CLK_3V3AUX_SDA")
		)
		(pad "2" smd circle
			(at 0.40005 0 270)
			(size 0 0)
			(layers "F.Cu" "F.Mask" "F.Paste")
			(net "SMB_HOST_CLK_GEN2_3V3AUX_SDA")
		)
	)
	(footprint ""
		(layer "F.Cu")
		(at 105.3084 -252.956568 -90)
		(property "Reference" "C266"
			(at 0 0 270)
			(layer "F.SilkS")
			(hide yes)
			(effects
				(font
					(size 1.27 1.27)
				)
			)
		)
		(property "Value" ""
			(at 0 0 270)
			(layer "F.Fab")
			(effects
				(font
					(size 1.27 1.27)
				)
			)
		)
		(duplicate_pad_numbers_are_jumpers no)
		(fp_line
			(start -0.7874 0.4064)
			(end -0.7874 -0.4064)
			(stroke
				(width 0.1524)
				(type default)
			)
			(layer "F.SilkS")
		)
		(fp_line
			(start 0.7874 0.4064)
			(end -0.7874 0.4064)
			(stroke
				(width 0.1524)
				(type default)
			)
			(layer "F.SilkS")
		)
		(fp_line
			(start -0.7874 -0.4064)
			(end 0.7874 -0.4064)
			(stroke
				(width 0.1524)
				(type default)
			)
			(layer "F.SilkS")
		)
		(fp_line
			(start 0.7874 -0.4064)
			(end 0.7874 0.4064)
			(stroke
				(width 0.1524)
				(type default)
			)
			(layer "F.SilkS")
		)
		(fp_line
			(start -0.67945 0.3048)
			(end -0.67945 -0.305054)
			(stroke
				(width 0.1)
				(type default)
			)
			(layer "F.Fab")
		)
		(fp_line
			(start -0.12065 0.3048)
			(end -0.67945 0.3048)
			(stroke
				(width 0.1)
				(type default)
			)
			(layer "F.Fab")
		)
		(fp_line
			(start 0.120396 0.3048)
			(end 0.120396 0.2794)
			(stroke
				(width 0.1)
				(type default)
			)
			(layer "F.Fab")
		)
		(fp_line
			(start 0.67945 0.3048)
			(end 0.120396 0.3048)
			(stroke
				(width 0.1)
				(type default)
			)
			(layer "F.Fab")
		)
		(fp_line
			(start -0.12065 0.2794)
			(end -0.12065 0.3048)
			(stroke
				(width 0.1)
				(type default)
			)
			(layer "F.Fab")
		)
		(fp_line
			(start 0.120396 0.2794)
			(end -0.12065 0.2794)
			(stroke
				(width 0.1)
				(type default)
			)
			(layer "F.Fab")
		)
		(fp_line
			(start -0.12065 -0.2794)
			(end 0.12065 -0.2794)
			(stroke
				(width 0.1)
				(type default)
			)
			(layer "F.Fab")
		)
		(fp_line
			(start 0.12065 -0.2794)
			(end 0.12065 -0.3048)
			(stroke
				(width 0.1)
				(type default)
			)
			(layer "F.Fab")
		)
		(fp_line
			(start 0.12065 -0.3048)
			(end 0.67945 -0.3048)
			(stroke
				(width 0.1)
				(type default)
			)
			(layer "F.Fab")
		)
		(fp_line
			(start 0.67945 -0.3048)
			(end 0.67945 0.3048)
			(stroke
				(width 0.1)
				(type default)
			)
			(layer "F.Fab")
		)
		(fp_line
			(start -0.67945 -0.305054)
			(end -0.12065 -0.305054)
			(stroke
				(width 0.1)
				(type default)
			)
			(layer "F.Fab")
		)
		(fp_line
			(start -0.12065 -0.305054)
			(end -0.12065 -0.2794)
			(stroke
				(width 0.1)
				(type default)
			)
			(layer "F.Fab")
		)
		(pad "1" smd circle
			(at -0.40005 0 270)
			(size 0 0)
			(layers "F.Cu" "F.Mask" "F.Paste")
			(net "PVCCIN_CPU1")
		)
		(pad "2" smd circle
			(at 0.40005 0 270)
			(size 0 0)
			(layers "F.Cu" "F.Mask" "F.Paste")
			(net "GND")
		)
	)
	(footprint ""
		(layer "F.Cu")
		(at 369.419124 -333.716122)
		(property "Reference" "PU10_P0_4"
			(at 3.442716 -12.403836 0)
			(unlocked yes)
			(layer "F.SilkS")
			(effects
				(font
					(size 0.7874 0.5842)
					(thickness 0.1524)
				)
				(justify left)
			)
		)
		(property "Value" ""
			(at 0 0 0)
			(layer "F.Fab")
			(effects
				(font
					(size 1.27 1.27)
				)
			)
		)
		(duplicate_pad_numbers_are_jumpers no)
		(fp_line
			(start -2.500122 -2.999994)
			(end -2.24409 -2.999994)
			(stroke
				(width 0.1524)
				(type default)
			)
			(layer "F.SilkS")
		)
		(fp_line
			(start -2.500122 -2.529078)
			(end -2.500122 -2.999994)
			(stroke
				(width 0.1524)
				(type default)
			)
			(layer "F.SilkS")
		)
		(fp_line
			(start -2.500122 0.6604)
			(end -2.500122 0.229108)
			(stroke
				(width 0.1524)
				(type default)
			)
			(layer "F.SilkS")
		)
		(fp_line
			(start -2.500122 2.999994)
			(end -2.500122 2.339594)
			(stroke
				(width 0.1524)
				(type default)
			)
			(layer "F.SilkS")
		)
		(fp_line
			(start -2.2987 2.999994)
			(end -2.500122 2.999994)
			(stroke
				(width 0.1524)
				(type default)
			)
			(layer "F.SilkS")
		)
		(fp_line
			(start 2.31394 -2.999994)
			(end 2.500122 -2.999994)
			(stroke
				(width 0.1524)
				(type default)
			)
			(layer "F.SilkS")
		)
		(fp_line
			(start 2.500122 -2.999994)
			(end 2.500122 -2.44348)
			(stroke
				(width 0.1524)
				(type default)
			)
			(layer "F.SilkS")
		)
		(fp_line
			(start 2.500122 2.339594)
			(end 2.500122 2.999994)
			(stroke
				(width 0.1524)
				(type default)
			)
			(layer "F.SilkS")
		)
		(fp_line
			(start 2.500122 2.999994)
			(end 2.2987 2.999994)
			(stroke
				(width 0.1524)
				(type default)
			)
			(layer "F.SilkS")
		)
		(fp_poly
			(pts
				(xy -2.168652 -3.624834) (xy -2.676652 -2.608834) (xy -3.184652 -3.624834)
			)
			(stroke
				(width 0)
				(type default)
			)
			(fill yes)
			(layer "F.SilkS")
		)
		(fp_line
			(start -2.500122 -2.999994)
			(end 2.500122 -2.999994)
			(stroke
				(width 0.1)
				(type default)
			)
			(layer "F.Fab")
		)
		(fp_line
			(start -2.500122 2.999994)
			(end -2.500122 -2.999994)
			(stroke
				(width 0.1)
				(type default)
			)
			(layer "F.Fab")
		)
		(fp_line
			(start 2.500122 -2.999994)
			(end 2.500122 2.999994)
			(stroke
				(width 0.1)
				(type default)
			)
			(layer "F.Fab")
		)
		(fp_line
			(start 2.500122 2.999994)
			(end -2.500122 2.999994)
			(stroke
				(width 0.1)
				(type default)
			)
			(layer "F.Fab")
		)
		(fp_poly
			(pts
				(xy -4.218432 -2.783078) (xy -4.218432 -1.767078) (xy -3.202432 -2.275078)
			)
			(stroke
				(width 0)
				(type default)
			)
			(fill yes)
			(layer "F.Fab")
		)
		(pad "1" smd rect
			(at -2.400046 -2.275078 90)
			(size 0.2286 0.6096)
			(layers "F.Cu" "F.Mask" "F.Paste")
			(net "PVCCIN_CPU0_VOS4")
		)
		(pad "2" smd rect
			(at -2.400046 -1.82499 90)
			(size 0.2286 0.6096)
			(layers "F.Cu" "F.Mask" "F.Paste")
			(net "GND")
		)
		(pad "3" smd rect
			(at -2.400046 -1.374902 90)
			(size 0.2286 0.6096)
			(layers "F.Cu" "F.Mask" "F.Paste")
			(net "PVCCIN_CPU0_VDD4")
		)
		(pad "4" smd rect
			(at -2.400046 -0.925068 90)
			(size 0.2286 0.6096)
			(layers "F.Cu" "F.Mask" "F.Paste")
			(net "PVCCIN_CPU0_PVCC")
		)
		(pad "5" smd rect
			(at -2.400046 -0.47498 90)
			(size 0.2286 0.6096)
			(layers "F.Cu" "F.Mask" "F.Paste")
			(net "GND")
		)
		(pad "6" smd rect
			(at -2.400046 -0.024892 90)
			(size 0.2286 0.6096)
			(layers "F.Cu" "F.Mask" "F.Paste")
			(net "Net_8553")
		)
		(pad "7_9-20_24" smd circle
			(at 0 1.150112 90)
			(size 0 0)
			(layers "F.Cu" "F.Mask" "F.Paste")
			(net "GND")
		)
		(pad "10_19" smd rect
			(at 0 2.899918 90)
			(size 0.6096 4.318)
			(layers "F.Cu" "F.Mask" "F.Paste")
			(net "SW_PVCCIN_CPU0_SW4")
		)
		(pad "25_29" smd rect
			(at 1.549908 -1.279906 270)
			(size 2.0574 2.3114)
			(layers "F.Cu" "F.Mask" "F.Paste")
			(net "SW_P12V_PVCCIN_CPU0_FLT")
		)
		(pad "30" smd rect
			(at 2.05994 -2.899918)
			(size 0.2286 0.6096)
			(layers "F.Cu" "F.Mask" "F.Paste")
			(net "SW_P12V_PVCCIN_CPU0_FLT")
		)
		(pad "31" smd rect
			(at 1.610106 -2.899918)
			(size 0.2286 0.6096)
			(layers "F.Cu" "F.Mask" "F.Paste")
			(net "Net_8554")
		)
		(pad "32" smd rect
			(at 1.160018 -2.899918)
			(size 0.2286 0.6096)
			(layers "F.Cu" "F.Mask" "F.Paste")
			(net "SW_PVCCIN_CPU0_BOOTR4")
		)
		(pad "33" smd rect
			(at 0.70993 -2.899918)
			(size 0.2286 0.6096)
			(layers "F.Cu" "F.Mask" "F.Paste")
			(net "SW_PVCCIN_CPU0_BOOT4")
		)
		(pad "34" smd rect
			(at 0.260096 -2.899918)
			(size 0.2286 0.6096)
			(layers "F.Cu" "F.Mask" "F.Paste")
			(net "PVCCIN_CPU0_PWM4")
		)
		(pad "35" smd rect
			(at -0.189992 -2.899918)
			(size 0.2286 0.6096)
			(layers "F.Cu" "F.Mask" "F.Paste")
			(net "PVCCIN_CPU0_VDD4")
		)
		(pad "36" smd rect
			(at -0.64008 -2.899918)
			(size 0.2286 0.6096)
			(layers "F.Cu" "F.Mask" "F.Paste")
			(net "PVCCIN_CPU0_ATSEN")
		)
		(pad "37" smd rect
			(at -1.089914 -2.899918)
			(size 0.2286 0.6096)
			(layers "F.Cu" "F.Mask" "F.Paste")
			(net "PVCCIN_CPU0_LSET4")
		)
		(pad "38" smd rect
			(at -1.540002 -2.899918)
			(size 0.2286 0.6096)
			(layers "F.Cu" "F.Mask" "F.Paste")
			(net "PVCCIN_CPU0_IMON4")
		)
		(pad "39" smd rect
			(at -1.99009 -2.899918)
			(size 0.2286 0.6096)
			(layers "F.Cu" "F.Mask" "F.Paste")
			(net "PVCCIN_CPU0_VREF")
		)
		(pad "40" smd rect
			(at -0.87503 -1.27508)
			(size 1.7526 1.9558)
			(layers "F.Cu" "F.Mask" "F.Paste")
			(net "GND")
		)
		(pad "41" smd rect
			(at -1.525016 0.249936 270)
			(size 0.3048 0.4572)
			(layers "F.Cu" "F.Mask" "F.Paste")
			(net "Net_8552")
		)
		(zone
			(layer "F.Cu")
			(hatch none 0.5)
			(connect_pads
				(clearance 0)
			)
			(min_thickness 0.25)
			(keepout
				(tracks not_allowed)
				(vias allowed)
				(pads allowed)
				(copperpour not_allowed)
				(footprints allowed)
			)
			(placement
				(enabled no)
				(sheetname "")
			)
			(fill
				(thermal_gap 0.5)
				(thermal_bridge_width 0.5)
				(island_removal_mode 0)
			)
			(polygon
				(pts
					(xy 368.173508 -333.652368) (xy 368.468402 -333.652368) (xy 368.468402 -332.966822) (xy 366.919002 -332.966822)
					(xy 366.919002 -333.423514) (xy 367.614708 -333.423514) (xy 367.614708 -333.262986) (xy 368.173508 -333.262986)
				)
			)
		)
		(zone
			(layer "F.Cu")
			(hatch none 0.5)
			(connect_pads
				(clearance 0)
			)
			(min_thickness 0.25)
			(keepout
				(tracks not_allowed)
				(vias allowed)
				(pads allowed)
				(copperpour not_allowed)
				(footprints allowed)
			)
			(placement
				(enabled no)
				(sheetname "")
			)
			(fill
				(thermal_gap 0.5)
				(thermal_bridge_width 0.5)
				(island_removal_mode 0)
			)
			(polygon
				(pts
					(xy 366.919002 -330.716128) (xy 366.919002 -331.465428) (xy 371.919246 -331.465428) (xy 371.919246 -330.716128)
					(xy 371.6909 -330.716128) (xy 371.6909 -331.109828) (xy 371.628924 -331.171804) (xy 367.209324 -331.171804)
					(xy 367.209324 -330.716128)
				)
			)
		)
	)
	(footprint ""
		(layer "F.Cu")
		(at 451.497192 -20.979638)
		(property "Reference" "PU203"
			(at 1.984248 -5.8674 0)
			(unlocked yes)
			(layer "F.SilkS")
			(effects
				(font
					(size 0.7874 0.5842)
					(thickness 0.1524)
				)
				(justify left)
			)
		)
		(property "Value" ""
			(at 0 0 0)
			(layer "F.Fab")
			(effects
				(font
					(size 1.27 1.27)
				)
			)
		)
		(duplicate_pad_numbers_are_jumpers no)
		(fp_line
			(start -1.774952 -1.039876)
			(end -1.774952 1.039876)
			(stroke
				(width 0.1524)
				(type default)
			)
			(layer "F.SilkS")
		)
		(fp_line
			(start -1.774952 1.039876)
			(end 1.774952 1.039876)
			(stroke
				(width 0.1524)
				(type default)
			)
			(layer "F.SilkS")
		)
		(fp_line
			(start 1.774952 -1.039876)
			(end -1.774952 -1.039876)
			(stroke
				(width 0.1524)
				(type default)
			)
			(layer "F.SilkS")
		)
		(fp_line
			(start 1.774952 1.039876)
			(end 1.774952 -1.039876)
			(stroke
				(width 0.1524)
				(type default)
			)
			(layer "F.SilkS")
		)
		(fp_poly
			(pts
				(xy -1.769872 -1.039876) (xy -1.769872 -0.249936) (xy -2.531872 -0.249936) (xy -2.531872 -1.801876)
				(xy -0.999998 -1.801876) (xy -0.999998 -1.039876)
			)
			(stroke
				(width 0)
				(type default)
			)
			(fill yes)
			(layer "F.SilkS")
		)
		(fp_line
			(start -1.769872 -1.039876)
			(end -1.769872 1.039876)
			(stroke
				(width 0.1)
				(type default)
			)
			(layer "F.Fab")
		)
		(fp_line
			(start -1.769872 1.039876)
			(end 1.769872 1.039876)
			(stroke
				(width 0.1)
				(type default)
			)
			(layer "F.Fab")
		)
		(fp_line
			(start 1.769872 -1.039876)
			(end -1.769872 -1.039876)
			(stroke
				(width 0.1)
				(type default)
			)
			(layer "F.Fab")
		)
		(fp_line
			(start 1.769872 1.039876)
			(end 1.769872 -1.039876)
			(stroke
				(width 0.1)
				(type default)
			)
			(layer "F.Fab")
		)
		(fp_poly
			(pts
				(xy -1.769872 -1.039876) (xy -0.999998 -1.039876) (xy -0.999998 -1.801876) (xy -2.531872 -1.801876)
				(xy -2.531872 -0.249936) (xy -1.769872 -0.249936)
			)
			(stroke
				(width 0)
				(type default)
			)
			(fill yes)
			(layer "F.Fab")
		)
		(pad "A1" smd circle
			(at -1.500124 -0.750062)
			(size 0.2286 0.2286)
			(layers "F.Cu" "F.Mask" "F.Paste")
			(net "P12V_OCP_SENSE_1")
		)
		(pad "A2" smd circle
			(at -0.999998 -0.750062)
			(size 0.2286 0.2286)
			(layers "F.Cu" "F.Mask" "F.Paste")
			(net "P12V_OCP_VCC_1")
		)
		(pad "A3" smd circle
			(at -0.499872 -0.750062)
			(size 0.2286 0.2286)
			(layers "F.Cu" "F.Mask" "F.Paste")
			(net "P12V_AUX")
		)
		(pad "A4" smd circle
			(at 0 -0.750062)
			(size 0.2286 0.2286)
			(layers "F.Cu" "F.Mask" "F.Paste")
			(net "P12V_OCP_SFF")
		)
		(pad "A5" smd circle
			(at 0.499872 -0.750062)
			(size 0.2286 0.2286)
			(layers "F.Cu" "F.Mask" "F.Paste")
			(net "P12V_AUX")
		)
		(pad "A6" smd circle
			(at 0.999998 -0.750062)
			(size 0.2286 0.2286)
			(layers "F.Cu" "F.Mask" "F.Paste")
			(net "P12V_OCP_GATE_1")
		)
		(pad "A7" smd circle
			(at 1.500124 -0.750062)
			(size 0.2286 0.2286)
			(layers "F.Cu" "F.Mask" "F.Paste")
			(net "GND")
		)
		(pad "B1" smd circle
			(at -1.500124 -0.249936)
			(size 0.2286 0.2286)
			(layers "F.Cu" "F.Mask" "F.Paste")
			(net "P12V_OCP_CB_1")
		)
		(pad "B2" smd circle
			(at -0.999998 -0.249936)
			(size 0.2286 0.2286)
			(layers "F.Cu" "F.Mask" "F.Paste")
			(net "GND")
		)
		(pad "B3" smd circle
			(at -0.499872 -0.249936)
			(size 0.2286 0.2286)
			(layers "F.Cu" "F.Mask" "F.Paste")
			(net "P12V_AUX")
		)
		(pad "B4" smd circle
			(at 0 -0.249936)
			(size 0.2286 0.2286)
			(layers "F.Cu" "F.Mask" "F.Paste")
			(net "P12V_OCP_SFF")
		)
		(pad "B5" smd circle
			(at 0.499872 -0.249936)
			(size 0.2286 0.2286)
			(layers "F.Cu" "F.Mask" "F.Paste")
			(net "P12V_AUX")
		)
		(pad "B6" smd circle
			(at 0.999998 -0.249936)
			(size 0.2286 0.2286)
			(layers "F.Cu" "F.Mask" "F.Paste")
			(net "P12V_OCP_SFF")
		)
		(pad "B7" smd circle
			(at 1.500124 -0.249936)
			(size 0.2286 0.2286)
			(layers "F.Cu" "F.Mask" "F.Paste")
			(net "GND")
		)
		(pad "C1" smd circle
			(at -1.500124 0.249936)
			(size 0.2286 0.2286)
			(layers "F.Cu" "F.Mask" "F.Paste")
			(net "GND")
		)
		(pad "C2" smd circle
			(at -0.999998 0.249936)
			(size 0.2286 0.2286)
			(layers "F.Cu" "F.Mask" "F.Paste")
			(net "GND")
		)
		(pad "C3" smd circle
			(at -0.499872 0.249936)
			(size 0.2286 0.2286)
			(layers "F.Cu" "F.Mask" "F.Paste")
			(net "P12V_AUX")
		)
		(pad "C4" smd circle
			(at 0 0.249936)
			(size 0.2286 0.2286)
			(layers "F.Cu" "F.Mask" "F.Paste")
			(net "P12V_OCP_SFF")
		)
		(pad "C5" smd circle
			(at 0.499872 0.249936)
			(size 0.2286 0.2286)
			(layers "F.Cu" "F.Mask" "F.Paste")
			(net "P12V_AUX")
		)
		(pad "C6" smd circle
			(at 0.999998 0.249936)
			(size 0.2286 0.2286)
			(layers "F.Cu" "F.Mask" "F.Paste")
			(net "P12V_OCP_SFF")
		)
		(pad "C7" smd circle
			(at 1.500124 0.249936)
			(size 0.2286 0.2286)
			(layers "F.Cu" "F.Mask" "F.Paste")
			(net "P12V_OCP_FAULT_1")
		)
		(pad "D1" smd circle
			(at -1.500124 0.750062)
			(size 0.2286 0.2286)
			(layers "F.Cu" "F.Mask" "F.Paste")
			(net "P12V_OCP_REG_1")
		)
		(pad "D2" smd circle
			(at -0.999998 0.750062)
			(size 0.2286 0.2286)
			(layers "F.Cu" "F.Mask" "F.Paste")
			(net "P12V_OCP_UV_1")
		)
		(pad "D3" smd circle
			(at -0.499872 0.750062)
			(size 0.2286 0.2286)
			(layers "F.Cu" "F.Mask" "F.Paste")
			(net "P12V_OCP_OV_1")
		)
		(pad "D4" smd circle
			(at 0 0.750062)
			(size 0.2286 0.2286)
			(layers "F.Cu" "F.Mask" "F.Paste")
			(net "P12V_OCP_SFF")
		)
		(pad "D5" smd circle
			(at 0.499872 0.750062)
			(size 0.2286 0.2286)
			(layers "F.Cu" "F.Mask" "F.Paste")
			(net "P12V_AUX")
		)
		(pad "D6" smd circle
			(at 0.999998 0.750062)
			(size 0.2286 0.2286)
			(layers "F.Cu" "F.Mask" "F.Paste")
			(net "P12V_OCP_SFF")
		)
		(pad "D7" smd circle
			(at 1.500124 0.750062)
			(size 0.2286 0.2286)
			(layers "F.Cu" "F.Mask" "F.Paste")
			(net "P12V_OCP_PWRGD_1")
		)
	)
	(footprint ""
		(layer "F.Cu")
		(at 224.21215 -47.612046)
		(property "Reference" "R2287"
			(at 0 0 0)
			(layer "F.SilkS")
			(hide yes)
			(effects
				(font
					(size 1.27 1.27)
				)
			)
		)
		(property "Value" ""
			(at 0 0 0)
			(layer "F.Fab")
			(effects
				(font
					(size 1.27 1.27)
				)
			)
		)
		(duplicate_pad_numbers_are_jumpers no)
		(fp_line
			(start -0.7874 -0.4064)
			(end 0.7874 -0.4064)
			(stroke
				(width 0.1524)
				(type default)
			)
			(layer "F.SilkS")
		)
		(fp_line
			(start -0.7874 0.4064)
			(end -0.7874 -0.4064)
			(stroke
				(width 0.1524)
				(type default)
			)
			(layer "F.SilkS")
		)
		(fp_line
			(start 0.7874 -0.4064)
			(end 0.7874 0.4064)
			(stroke
				(width 0.1524)
				(type default)
			)
			(layer "F.SilkS")
		)
		(fp_line
			(start 0.7874 0.4064)
			(end -0.7874 0.4064)
			(stroke
				(width 0.1524)
				(type default)
			)
			(layer "F.SilkS")
		)
		(fp_line
			(start -0.67945 -0.305054)
			(end -0.12065 -0.305054)
			(stroke
				(width 0.1)
				(type default)
			)
			(layer "F.Fab")
		)
		(fp_line
			(start -0.67945 0.3048)
			(end -0.67945 -0.305054)
			(stroke
				(width 0.1)
				(type default)
			)
			(layer "F.Fab")
		)
		(fp_line
			(start -0.12065 -0.305054)
			(end -0.12065 -0.2794)
			(stroke
				(width 0.1)
				(type default)
			)
			(layer "F.Fab")
		)
		(fp_line
			(start -0.12065 -0.2794)
			(end 0.12065 -0.2794)
			(stroke
				(width 0.1)
				(type default)
			)
			(layer "F.Fab")
		)
		(fp_line
			(start -0.12065 0.2794)
			(end -0.12065 0.3048)
			(stroke
				(width 0.1)
				(type default)
			)
			(layer "F.Fab")
		)
		(fp_line
			(start -0.12065 0.3048)
			(end -0.67945 0.3048)
			(stroke
				(width 0.1)
				(type default)
			)
			(layer "F.Fab")
		)
		(fp_line
			(start 0.120396 0.2794)
			(end -0.12065 0.2794)
			(stroke
				(width 0.1)
				(type default)
			)
			(layer "F.Fab")
		)
		(fp_line
			(start 0.120396 0.3048)
			(end 0.120396 0.2794)
			(stroke
				(width 0.1)
				(type default)
			)
			(layer "F.Fab")
		)
		(fp_line
			(start 0.12065 -0.3048)
			(end 0.67945 -0.3048)
			(stroke
				(width 0.1)
				(type default)
			)
			(layer "F.Fab")
		)
		(fp_line
			(start 0.12065 -0.2794)
			(end 0.12065 -0.3048)
			(stroke
				(width 0.1)
				(type default)
			)
			(layer "F.Fab")
		)
		(fp_line
			(start 0.67945 -0.3048)
			(end 0.67945 0.3048)
			(stroke
				(width 0.1)
				(type default)
			)
			(layer "F.Fab")
		)
		(fp_line
			(start 0.67945 0.3048)
			(end 0.120396 0.3048)
			(stroke
				(width 0.1)
				(type default)
			)
			(layer "F.Fab")
		)
		(pad "1" smd circle
			(at -0.40005 0)
			(size 0 0)
			(layers "F.Cu" "F.Mask" "F.Paste")
			(net "P3V3_E1S_0")
		)
		(pad "2" smd circle
			(at 0.40005 0)
			(size 0 0)
			(layers "F.Cu" "F.Mask" "F.Paste")
			(net "E1S_0_PERST1_CLKREQ_N")
		)
	)
	(footprint ""
		(layer "F.Cu")
		(at 440.0804 -20.440396 180)
		(property "Reference" "PC2082"
			(at 0 0 180)
			(layer "F.SilkS")
			(hide yes)
			(effects
				(font
					(size 1.27 1.27)
				)
			)
		)
		(property "Value" ""
			(at 0 0 180)
			(layer "F.Fab")
			(effects
				(font
					(size 1.27 1.27)
				)
			)
		)
		(duplicate_pad_numbers_are_jumpers no)
		(fp_line
			(start 1.524 0.762)
			(end -1.524 0.762)
			(stroke
				(width 0.1524)
				(type default)
			)
			(layer "F.SilkS")
		)
		(fp_line
			(start 1.524 -0.762)
			(end 1.524 0.762)
			(stroke
				(width 0.1524)
				(type default)
			)
			(layer "F.SilkS")
		)
		(fp_line
			(start -1.524 0.762)
			(end -1.524 -0.762)
			(stroke
				(width 0.1524)
				(type default)
			)
			(layer "F.SilkS")
		)
		(fp_line
			(start -1.524 -0.762)
			(end 1.524 -0.762)
			(stroke
				(width 0.1524)
				(type default)
			)
			(layer "F.SilkS")
		)
		(fp_line
			(start 1.1049 0.724916)
			(end 1.1049 -0.724916)
			(stroke
				(width 0.1)
				(type default)
			)
			(layer "F.Fab")
		)
		(fp_line
			(start 1.1049 -0.724916)
			(end -1.1049 -0.724916)
			(stroke
				(width 0.1)
				(type default)
			)
			(layer "F.Fab")
		)
		(fp_line
			(start -1.1049 0.724916)
			(end 1.1049 0.724916)
			(stroke
				(width 0.1)
				(type default)
			)
			(layer "F.Fab")
		)
		(fp_line
			(start -1.1049 -0.724916)
			(end -1.1049 0.724916)
			(stroke
				(width 0.1)
				(type default)
			)
			(layer "F.Fab")
		)
		(pad "1" smd rect
			(at -0.889 0)
			(size 1.016 1.27)
			(layers "F.Cu" "F.Mask" "F.Paste")
			(net "P12V_OCP_SFF")
		)
		(pad "2" smd rect
			(at 0.889 0)
			(size 1.016 1.27)
			(layers "F.Cu" "F.Mask" "F.Paste")
			(net "GND")
		)
	)
	(footprint ""
		(layer "F.Cu")
		(at 153.21788 -41.811448)
		(property "Reference" "R3297"
			(at 0 0 0)
			(layer "F.SilkS")
			(hide yes)
			(effects
				(font
					(size 1.27 1.27)
				)
			)
		)
		(property "Value" ""
			(at 0 0 0)
			(layer "F.Fab")
			(effects
				(font
					(size 1.27 1.27)
				)
			)
		)
		(duplicate_pad_numbers_are_jumpers no)
		(fp_line
			(start -0.7874 -0.4064)
			(end 0.7874 -0.4064)
			(stroke
				(width 0.1524)
				(type default)
			)
			(layer "F.SilkS")
		)
		(fp_line
			(start -0.7874 0.4064)
			(end -0.7874 -0.4064)
			(stroke
				(width 0.1524)
				(type default)
			)
			(layer "F.SilkS")
		)
		(fp_line
			(start 0.7874 -0.4064)
			(end 0.7874 0.4064)
			(stroke
				(width 0.1524)
				(type default)
			)
			(layer "F.SilkS")
		)
		(fp_line
			(start 0.7874 0.4064)
			(end -0.7874 0.4064)
			(stroke
				(width 0.1524)
				(type default)
			)
			(layer "F.SilkS")
		)
		(fp_line
			(start -0.67945 -0.305054)
			(end -0.12065 -0.305054)
			(stroke
				(width 0.1)
				(type default)
			)
			(layer "F.Fab")
		)
		(fp_line
			(start -0.67945 0.3048)
			(end -0.67945 -0.305054)
			(stroke
				(width 0.1)
				(type default)
			)
			(layer "F.Fab")
		)
		(fp_line
			(start -0.12065 -0.305054)
			(end -0.12065 -0.2794)
			(stroke
				(width 0.1)
				(type default)
			)
			(layer "F.Fab")
		)
		(fp_line
			(start -0.12065 -0.2794)
			(end 0.12065 -0.2794)
			(stroke
				(width 0.1)
				(type default)
			)
			(layer "F.Fab")
		)
		(fp_line
			(start -0.12065 0.2794)
			(end -0.12065 0.3048)
			(stroke
				(width 0.1)
				(type default)
			)
			(layer "F.Fab")
		)
		(fp_line
			(start -0.12065 0.3048)
			(end -0.67945 0.3048)
			(stroke
				(width 0.1)
				(type default)
			)
			(layer "F.Fab")
		)
		(fp_line
			(start 0.120396 0.2794)
			(end -0.12065 0.2794)
			(stroke
				(width 0.1)
				(type default)
			)
			(layer "F.Fab")
		)
		(fp_line
			(start 0.120396 0.3048)
			(end 0.120396 0.2794)
			(stroke
				(width 0.1)
				(type default)
			)
			(layer "F.Fab")
		)
		(fp_line
			(start 0.12065 -0.3048)
			(end 0.67945 -0.3048)
			(stroke
				(width 0.1)
				(type default)
			)
			(layer "F.Fab")
		)
		(fp_line
			(start 0.12065 -0.2794)
			(end 0.12065 -0.3048)
			(stroke
				(width 0.1)
				(type default)
			)
			(layer "F.Fab")
		)
		(fp_line
			(start 0.67945 -0.3048)
			(end 0.67945 0.3048)
			(stroke
				(width 0.1)
				(type default)
			)
			(layer "F.Fab")
		)
		(fp_line
			(start 0.67945 0.3048)
			(end 0.120396 0.3048)
			(stroke
				(width 0.1)
				(type default)
			)
			(layer "F.Fab")
		)
		(pad "1" smd circle
			(at -0.40005 0)
			(size 0 0)
			(layers "F.Cu" "F.Mask" "F.Paste")
			(net "LED_HDD_ACTIVITY_B_N")
		)
		(pad "2" smd circle
			(at 0.40005 0)
			(size 0 0)
			(layers "F.Cu" "F.Mask" "F.Paste")
			(net "GND")
		)
	)
	(footprint ""
		(layer "F.Cu")
		(at 39.827454 -108.047282 180)
		(property "Reference" "R3684"
			(at 0 0 180)
			(layer "F.SilkS")
			(hide yes)
			(effects
				(font
					(size 1.27 1.27)
				)
			)
		)
		(property "Value" ""
			(at 0 0 180)
			(layer "F.Fab")
			(effects
				(font
					(size 1.27 1.27)
				)
			)
		)
		(duplicate_pad_numbers_are_jumpers no)
		(fp_line
			(start 0.7874 0.4064)
			(end -0.7874 0.4064)
			(stroke
				(width 0.1524)
				(type default)
			)
			(layer "F.SilkS")
		)
		(fp_line
			(start 0.7874 -0.4064)
			(end 0.7874 0.4064)
			(stroke
				(width 0.1524)
				(type default)
			)
			(layer "F.SilkS")
		)
		(fp_line
			(start -0.7874 0.4064)
			(end -0.7874 -0.4064)
			(stroke
				(width 0.1524)
				(type default)
			)
			(layer "F.SilkS")
		)
		(fp_line
			(start -0.7874 -0.4064)
			(end 0.7874 -0.4064)
			(stroke
				(width 0.1524)
				(type default)
			)
			(layer "F.SilkS")
		)
		(fp_line
			(start 0.67945 0.3048)
			(end 0.120396 0.3048)
			(stroke
				(width 0.1)
				(type default)
			)
			(layer "F.Fab")
		)
		(fp_line
			(start 0.67945 -0.3048)
			(end 0.67945 0.3048)
			(stroke
				(width 0.1)
				(type default)
			)
			(layer "F.Fab")
		)
		(fp_line
			(start 0.12065 -0.2794)
			(end 0.12065 -0.3048)
			(stroke
				(width 0.1)
				(type default)
			)
			(layer "F.Fab")
		)
		(fp_line
			(start 0.12065 -0.3048)
			(end 0.67945 -0.3048)
			(stroke
				(width 0.1)
				(type default)
			)
			(layer "F.Fab")
		)
		(fp_line
			(start 0.120396 0.3048)
			(end 0.120396 0.2794)
			(stroke
				(width 0.1)
				(type default)
			)
			(layer "F.Fab")
		)
		(fp_line
			(start 0.120396 0.2794)
			(end -0.12065 0.2794)
			(stroke
				(width 0.1)
				(type default)
			)
			(layer "F.Fab")
		)
		(fp_line
			(start -0.12065 0.3048)
			(end -0.67945 0.3048)
			(stroke
				(width 0.1)
				(type default)
			)
			(layer "F.Fab")
		)
		(fp_line
			(start -0.12065 0.2794)
			(end -0.12065 0.3048)
			(stroke
				(width 0.1)
				(type default)
			)
			(layer "F.Fab")
		)
		(fp_line
			(start -0.12065 -0.2794)
			(end 0.12065 -0.2794)
			(stroke
				(width 0.1)
				(type default)
			)
			(layer "F.Fab")
		)
		(fp_line
			(start -0.12065 -0.305054)
			(end -0.12065 -0.2794)
			(stroke
				(width 0.1)
				(type default)
			)
			(layer "F.Fab")
		)
		(fp_line
			(start -0.67945 0.3048)
			(end -0.67945 -0.305054)
			(stroke
				(width 0.1)
				(type default)
			)
			(layer "F.Fab")
		)
		(fp_line
			(start -0.67945 -0.305054)
			(end -0.12065 -0.305054)
			(stroke
				(width 0.1)
				(type default)
			)
			(layer "F.Fab")
		)
		(pad "1" smd rect
			(at -0.40005 0)
			(size 0.4572 0.508)
			(layers "F.Cu" "F.Mask" "F.Paste")
			(net "P3V3_ADC")
		)
		(pad "2" smd rect
			(at 0.40005 0)
			(size 0.4572 0.508)
			(layers "F.Cu" "F.Mask" "F.Paste")
			(net "P3V3_ADC_TIC")
		)
	)
	(footprint ""
		(layer "F.Cu")
		(at 166.77894 -28.044648)
		(property "Reference" "U307"
			(at 1.03632 2.521712 0)
			(unlocked yes)
			(layer "F.SilkS")
			(effects
				(font
					(size 0.7874 0.5842)
					(thickness 0.1524)
				)
			)
		)
		(property "Value" ""
			(at 0 0 0)
			(layer "F.Fab")
			(effects
				(font
					(size 1.27 1.27)
				)
			)
		)
		(duplicate_pad_numbers_are_jumpers no)
		(fp_line
			(start -1.949958 -1.610106)
			(end 1.949958 -1.610106)
			(stroke
				(width 0.1524)
				(type default)
			)
			(layer "F.SilkS")
		)
		(fp_line
			(start -1.949958 1.610106)
			(end -1.949958 -1.610106)
			(stroke
				(width 0.1524)
				(type default)
			)
			(layer "F.SilkS")
		)
		(fp_line
			(start 1.949958 -1.560068)
			(end 1.949958 1.610106)
			(stroke
				(width 0.1524)
				(type default)
			)
			(layer "F.SilkS")
		)
		(fp_line
			(start 1.949958 1.610106)
			(end -1.949958 1.610106)
			(stroke
				(width 0.1524)
				(type default)
			)
			(layer "F.SilkS")
		)
		(fp_line
			(start -0.750062 -1.560068)
			(end 0.750062 -1.560068)
			(stroke
				(width 0.1)
				(type default)
			)
			(layer "F.Fab")
		)
		(fp_line
			(start -0.750062 1.560068)
			(end -0.750062 -1.560068)
			(stroke
				(width 0.1)
				(type default)
			)
			(layer "F.Fab")
		)
		(fp_line
			(start 0.750062 -1.560068)
			(end 0.750062 1.560068)
			(stroke
				(width 0.1)
				(type default)
			)
			(layer "F.Fab")
		)
		(fp_line
			(start 0.750062 1.560068)
			(end -0.750062 1.560068)
			(stroke
				(width 0.1)
				(type default)
			)
			(layer "F.Fab")
		)
		(pad "D" smd rect
			(at 1.100074 0 270)
			(size 1.016 1.4224)
			(layers "F.Cu" "F.Mask" "F.Paste")
			(net "FM_LPC_ESPI_SEL")
		)
		(pad "G" smd rect
			(at -1.100074 -0.94996 270)
			(size 1.016 1.4224)
			(layers "F.Cu" "F.Mask" "F.Paste")
			(net "FM_ESPI_PLD_R_EN_BUF_R")
		)
		(pad "S" smd rect
			(at -1.100074 0.94996 270)
			(size 1.016 1.4224)
			(layers "F.Cu" "F.Mask" "F.Paste")
			(net "GND")
		)
	)
	(footprint ""
		(layer "F.Cu")
		(at 217.12428 -108.321348 90)
		(property "Reference" "U89"
			(at -0.264922 3.129788 0)
			(unlocked yes)
			(layer "F.SilkS")
			(effects
				(font
					(size 0.7874 0.5842)
					(thickness 0.1524)
				)
			)
		)
		(property "Value" ""
			(at 0 0 90)
			(layer "F.Fab")
			(effects
				(font
					(size 1.27 1.27)
				)
			)
		)
		(duplicate_pad_numbers_are_jumpers no)
		(fp_line
			(start -1.949958 -1.610106)
			(end 1.949958 -1.610106)
			(stroke
				(width 0.1524)
				(type default)
			)
			(layer "F.SilkS")
		)
		(fp_line
			(start 1.949958 -1.560068)
			(end 1.949958 1.610106)
			(stroke
				(width 0.1524)
				(type default)
			)
			(layer "F.SilkS")
		)
		(fp_line
			(start 1.949958 1.610106)
			(end -1.949958 1.610106)
			(stroke
				(width 0.1524)
				(type default)
			)
			(layer "F.SilkS")
		)
		(fp_line
			(start -1.949958 1.610106)
			(end -1.949958 -1.610106)
			(stroke
				(width 0.1524)
				(type default)
			)
			(layer "F.SilkS")
		)
		(fp_line
			(start 0.750062 -1.560068)
			(end 0.750062 1.560068)
			(stroke
				(width 0.1)
				(type default)
			)
			(layer "F.Fab")
		)
		(fp_line
			(start -0.750062 -1.560068)
			(end 0.750062 -1.560068)
			(stroke
				(width 0.1)
				(type default)
			)
			(layer "F.Fab")
		)
		(fp_line
			(start 0.750062 1.560068)
			(end -0.750062 1.560068)
			(stroke
				(width 0.1)
				(type default)
			)
			(layer "F.Fab")
		)
		(fp_line
			(start -0.750062 1.560068)
			(end -0.750062 -1.560068)
			(stroke
				(width 0.1)
				(type default)
			)
			(layer "F.Fab")
		)
		(pad "D" smd rect
			(at 1.100074 0)
			(size 1.016 1.4224)
			(layers "F.Cu" "F.Mask" "F.Paste")
			(net "FM_PLD_HEARTBEAT_LVC3_D")
		)
		(pad "G" smd rect
			(at -1.100074 -0.94996)
			(size 1.016 1.4224)
			(layers "F.Cu" "F.Mask" "F.Paste")
			(net "FM_PLD_HEARTBEAT_LVC3")
		)
		(pad "S" smd rect
			(at -1.100074 0.94996)
			(size 1.016 1.4224)
			(layers "F.Cu" "F.Mask" "F.Paste")
			(net "GND")
		)
	)
	(footprint ""
		(layer "F.Cu")
		(at 364.50143 -249.320304 -90)
		(property "Reference" "C969"
			(at 0 0 270)
			(layer "F.SilkS")
			(hide yes)
			(effects
				(font
					(size 1.27 1.27)
				)
			)
		)
		(property "Value" ""
			(at 0 0 270)
			(layer "F.Fab")
			(effects
				(font
					(size 1.27 1.27)
				)
			)
		)
		(duplicate_pad_numbers_are_jumpers no)
		(fp_line
			(start -0.7874 0.4064)
			(end -0.7874 -0.4064)
			(stroke
				(width 0.1524)
				(type default)
			)
			(layer "F.SilkS")
		)
		(fp_line
			(start 0.7874 0.4064)
			(end -0.7874 0.4064)
			(stroke
				(width 0.1524)
				(type default)
			)
			(layer "F.SilkS")
		)
		(fp_line
			(start -0.7874 -0.4064)
			(end 0.7874 -0.4064)
			(stroke
				(width 0.1524)
				(type default)
			)
			(layer "F.SilkS")
		)
		(fp_line
			(start 0.7874 -0.4064)
			(end 0.7874 0.4064)
			(stroke
				(width 0.1524)
				(type default)
			)
			(layer "F.SilkS")
		)
		(fp_line
			(start -0.67945 0.3048)
			(end -0.67945 -0.305054)
			(stroke
				(width 0.1)
				(type default)
			)
			(layer "F.Fab")
		)
		(fp_line
			(start -0.12065 0.3048)
			(end -0.67945 0.3048)
			(stroke
				(width 0.1)
				(type default)
			)
			(layer "F.Fab")
		)
		(fp_line
			(start 0.120396 0.3048)
			(end 0.120396 0.2794)
			(stroke
				(width 0.1)
				(type default)
			)
			(layer "F.Fab")
		)
		(fp_line
			(start 0.67945 0.3048)
			(end 0.120396 0.3048)
			(stroke
				(width 0.1)
				(type default)
			)
			(layer "F.Fab")
		)
		(fp_line
			(start -0.12065 0.2794)
			(end -0.12065 0.3048)
			(stroke
				(width 0.1)
				(type default)
			)
			(layer "F.Fab")
		)
		(fp_line
			(start 0.120396 0.2794)
			(end -0.12065 0.2794)
			(stroke
				(width 0.1)
				(type default)
			)
			(layer "F.Fab")
		)
		(fp_line
			(start -0.12065 -0.2794)
			(end 0.12065 -0.2794)
			(stroke
				(width 0.1)
				(type default)
			)
			(layer "F.Fab")
		)
		(fp_line
			(start 0.12065 -0.2794)
			(end 0.12065 -0.3048)
			(stroke
				(width 0.1)
				(type default)
			)
			(layer "F.Fab")
		)
		(fp_line
			(start 0.12065 -0.3048)
			(end 0.67945 -0.3048)
			(stroke
				(width 0.1)
				(type default)
			)
			(layer "F.Fab")
		)
		(fp_line
			(start 0.67945 -0.3048)
			(end 0.67945 0.3048)
			(stroke
				(width 0.1)
				(type default)
			)
			(layer "F.Fab")
		)
		(fp_line
			(start -0.67945 -0.305054)
			(end -0.12065 -0.305054)
			(stroke
				(width 0.1)
				(type default)
			)
			(layer "F.Fab")
		)
		(fp_line
			(start -0.12065 -0.305054)
			(end -0.12065 -0.2794)
			(stroke
				(width 0.1)
				(type default)
			)
			(layer "F.Fab")
		)
		(pad "1" smd circle
			(at -0.40005 0 270)
			(size 0 0)
			(layers "F.Cu" "F.Mask" "F.Paste")
			(net "PVCCIN_CPU0")
		)
		(pad "2" smd circle
			(at 0.40005 0 270)
			(size 0 0)
			(layers "F.Cu" "F.Mask" "F.Paste")
			(net "GND")
		)
	)
	(footprint ""
		(layer "F.Cu")
		(at 250.317 -38.048946 -90)
		(property "Reference" "R3972"
			(at 0 0 270)
			(layer "F.SilkS")
			(hide yes)
			(effects
				(font
					(size 1.27 1.27)
				)
			)
		)
		(property "Value" ""
			(at 0 0 270)
			(layer "F.Fab")
			(effects
				(font
					(size 1.27 1.27)
				)
			)
		)
		(duplicate_pad_numbers_are_jumpers no)
		(fp_line
			(start -0.7874 0.4064)
			(end -0.7874 -0.4064)
			(stroke
				(width 0.1524)
				(type default)
			)
			(layer "F.SilkS")
		)
		(fp_line
			(start 0.7874 0.4064)
			(end -0.7874 0.4064)
			(stroke
				(width 0.1524)
				(type default)
			)
			(layer "F.SilkS")
		)
		(fp_line
			(start -0.7874 -0.4064)
			(end 0.7874 -0.4064)
			(stroke
				(width 0.1524)
				(type default)
			)
			(layer "F.SilkS")
		)
		(fp_line
			(start 0.7874 -0.4064)
			(end 0.7874 0.4064)
			(stroke
				(width 0.1524)
				(type default)
			)
			(layer "F.SilkS")
		)
		(fp_line
			(start -0.67945 0.3048)
			(end -0.67945 -0.305054)
			(stroke
				(width 0.1)
				(type default)
			)
			(layer "F.Fab")
		)
		(fp_line
			(start -0.12065 0.3048)
			(end -0.67945 0.3048)
			(stroke
				(width 0.1)
				(type default)
			)
			(layer "F.Fab")
		)
		(fp_line
			(start 0.120396 0.3048)
			(end 0.120396 0.2794)
			(stroke
				(width 0.1)
				(type default)
			)
			(layer "F.Fab")
		)
		(fp_line
			(start 0.67945 0.3048)
			(end 0.120396 0.3048)
			(stroke
				(width 0.1)
				(type default)
			)
			(layer "F.Fab")
		)
		(fp_line
			(start -0.12065 0.2794)
			(end -0.12065 0.3048)
			(stroke
				(width 0.1)
				(type default)
			)
			(layer "F.Fab")
		)
		(fp_line
			(start 0.120396 0.2794)
			(end -0.12065 0.2794)
			(stroke
				(width 0.1)
				(type default)
			)
			(layer "F.Fab")
		)
		(fp_line
			(start -0.12065 -0.2794)
			(end 0.12065 -0.2794)
			(stroke
				(width 0.1)
				(type default)
			)
			(layer "F.Fab")
		)
		(fp_line
			(start 0.12065 -0.2794)
			(end 0.12065 -0.3048)
			(stroke
				(width 0.1)
				(type default)
			)
			(layer "F.Fab")
		)
		(fp_line
			(start 0.12065 -0.3048)
			(end 0.67945 -0.3048)
			(stroke
				(width 0.1)
				(type default)
			)
			(layer "F.Fab")
		)
		(fp_line
			(start 0.67945 -0.3048)
			(end 0.67945 0.3048)
			(stroke
				(width 0.1)
				(type default)
			)
			(layer "F.Fab")
		)
		(fp_line
			(start -0.67945 -0.305054)
			(end -0.12065 -0.305054)
			(stroke
				(width 0.1)
				(type default)
			)
			(layer "F.Fab")
		)
		(fp_line
			(start -0.12065 -0.305054)
			(end -0.12065 -0.2794)
			(stroke
				(width 0.1)
				(type default)
			)
			(layer "F.Fab")
		)
		(pad "1" smd circle
			(at -0.40005 0 270)
			(size 0 0)
			(layers "F.Cu" "F.Mask" "F.Paste")
			(net "P12V_E1S_PWRGD_0")
		)
		(pad "2" smd circle
			(at 0.40005 0 270)
			(size 0 0)
			(layers "F.Cu" "F.Mask" "F.Paste")
			(net "HP_LVC3_E1S_0_HSC_PWRGD")
		)
	)
	(footprint ""
		(layer "F.Cu")
		(at 453.054212 -23.603458)
		(property "Reference" "PC4056"
			(at 0 0 0)
			(layer "F.SilkS")
			(hide yes)
			(effects
				(font
					(size 1.27 1.27)
				)
			)
		)
		(property "Value" ""
			(at 0 0 0)
			(layer "F.Fab")
			(effects
				(font
					(size 1.27 1.27)
				)
			)
		)
		(duplicate_pad_numbers_are_jumpers no)
		(fp_line
			(start -0.7874 -0.4064)
			(end 0.7874 -0.4064)
			(stroke
				(width 0.1524)
				(type default)
			)
			(layer "F.SilkS")
		)
		(fp_line
			(start -0.7874 0.4064)
			(end -0.7874 -0.4064)
			(stroke
				(width 0.1524)
				(type default)
			)
			(layer "F.SilkS")
		)
		(fp_line
			(start 0.7874 -0.4064)
			(end 0.7874 0.4064)
			(stroke
				(width 0.1524)
				(type default)
			)
			(layer "F.SilkS")
		)
		(fp_line
			(start 0.7874 0.4064)
			(end -0.7874 0.4064)
			(stroke
				(width 0.1524)
				(type default)
			)
			(layer "F.SilkS")
		)
		(fp_line
			(start -0.67945 -0.305054)
			(end -0.12065 -0.305054)
			(stroke
				(width 0.1)
				(type default)
			)
			(layer "F.Fab")
		)
		(fp_line
			(start -0.67945 0.3048)
			(end -0.67945 -0.305054)
			(stroke
				(width 0.1)
				(type default)
			)
			(layer "F.Fab")
		)
		(fp_line
			(start -0.12065 -0.305054)
			(end -0.12065 -0.2794)
			(stroke
				(width 0.1)
				(type default)
			)
			(layer "F.Fab")
		)
		(fp_line
			(start -0.12065 -0.2794)
			(end 0.12065 -0.2794)
			(stroke
				(width 0.1)
				(type default)
			)
			(layer "F.Fab")
		)
		(fp_line
			(start -0.12065 0.2794)
			(end -0.12065 0.3048)
			(stroke
				(width 0.1)
				(type default)
			)
			(layer "F.Fab")
		)
		(fp_line
			(start -0.12065 0.3048)
			(end -0.67945 0.3048)
			(stroke
				(width 0.1)
				(type default)
			)
			(layer "F.Fab")
		)
		(fp_line
			(start 0.120396 0.2794)
			(end -0.12065 0.2794)
			(stroke
				(width 0.1)
				(type default)
			)
			(layer "F.Fab")
		)
		(fp_line
			(start 0.120396 0.3048)
			(end 0.120396 0.2794)
			(stroke
				(width 0.1)
				(type default)
			)
			(layer "F.Fab")
		)
		(fp_line
			(start 0.12065 -0.3048)
			(end 0.67945 -0.3048)
			(stroke
				(width 0.1)
				(type default)
			)
			(layer "F.Fab")
		)
		(fp_line
			(start 0.12065 -0.2794)
			(end 0.12065 -0.3048)
			(stroke
				(width 0.1)
				(type default)
			)
			(layer "F.Fab")
		)
		(fp_line
			(start 0.67945 -0.3048)
			(end 0.67945 0.3048)
			(stroke
				(width 0.1)
				(type default)
			)
			(layer "F.Fab")
		)
		(fp_line
			(start 0.67945 0.3048)
			(end 0.120396 0.3048)
			(stroke
				(width 0.1)
				(type default)
			)
			(layer "F.Fab")
		)
		(pad "1" smd circle
			(at -0.40005 0)
			(size 0 0)
			(layers "F.Cu" "F.Mask" "F.Paste")
			(net "P12V_OCP_GATE_1")
		)
		(pad "2" smd circle
			(at 0.40005 0)
			(size 0 0)
			(layers "F.Cu" "F.Mask" "F.Paste")
			(net "GND")
		)
	)
	(footprint ""
		(layer "F.Cu")
		(at 332.870048 -408.517344 -90)
		(property "Reference" "C920"
			(at 0 0 270)
			(layer "F.SilkS")
			(hide yes)
			(effects
				(font
					(size 1.27 1.27)
				)
			)
		)
		(property "Value" ""
			(at 0 0 270)
			(layer "F.Fab")
			(effects
				(font
					(size 1.27 1.27)
				)
			)
		)
		(duplicate_pad_numbers_are_jumpers no)
		(fp_line
			(start -0.299974 0.150114)
			(end -0.299974 -0.150114)
			(stroke
				(width 0.1)
				(type default)
			)
			(layer "F.Fab")
		)
		(fp_line
			(start 0.299974 0.150114)
			(end -0.299974 0.150114)
			(stroke
				(width 0.1)
				(type default)
			)
			(layer "F.Fab")
		)
		(fp_line
			(start -0.299974 -0.150114)
			(end 0.299974 -0.150114)
			(stroke
				(width 0.1)
				(type default)
			)
			(layer "F.Fab")
		)
		(fp_line
			(start 0.299974 -0.150114)
			(end 0.299974 0.150114)
			(stroke
				(width 0.1)
				(type default)
			)
			(layer "F.Fab")
		)
		(pad "1" smd rect
			(at -0.2667 0 270)
			(size 0.3048 0.381)
			(layers "F.Cu" "F.Mask" "F.Paste")
			(net "P5E_CPU0_PE0_TX_C_DN<6>")
		)
		(pad "2" smd rect
			(at 0.2667 0 270)
			(size 0.3048 0.381)
			(layers "F.Cu" "F.Mask" "F.Paste")
			(net "P5E_CPU0_PE0_TX_DN<6>")
		)
	)
	(footprint ""
		(layer "F.Cu")
		(at 218.12758 -131.973828)
		(property "Reference" "C1315"
			(at 0 0 0)
			(layer "F.SilkS")
			(hide yes)
			(effects
				(font
					(size 1.27 1.27)
				)
			)
		)
		(property "Value" ""
			(at 0 0 0)
			(layer "F.Fab")
			(effects
				(font
					(size 1.27 1.27)
				)
			)
		)
		(duplicate_pad_numbers_are_jumpers no)
		(fp_line
			(start -0.7874 -0.4064)
			(end 0.7874 -0.4064)
			(stroke
				(width 0.1524)
				(type default)
			)
			(layer "F.SilkS")
		)
		(fp_line
			(start -0.7874 0.4064)
			(end -0.7874 -0.4064)
			(stroke
				(width 0.1524)
				(type default)
			)
			(layer "F.SilkS")
		)
		(fp_line
			(start 0.7874 -0.4064)
			(end 0.7874 0.4064)
			(stroke
				(width 0.1524)
				(type default)
			)
			(layer "F.SilkS")
		)
		(fp_line
			(start 0.7874 0.4064)
			(end -0.7874 0.4064)
			(stroke
				(width 0.1524)
				(type default)
			)
			(layer "F.SilkS")
		)
		(fp_line
			(start -0.67945 -0.305054)
			(end -0.12065 -0.305054)
			(stroke
				(width 0.1)
				(type default)
			)
			(layer "F.Fab")
		)
		(fp_line
			(start -0.67945 0.3048)
			(end -0.67945 -0.305054)
			(stroke
				(width 0.1)
				(type default)
			)
			(layer "F.Fab")
		)
		(fp_line
			(start -0.12065 -0.305054)
			(end -0.12065 -0.2794)
			(stroke
				(width 0.1)
				(type default)
			)
			(layer "F.Fab")
		)
		(fp_line
			(start -0.12065 -0.2794)
			(end 0.12065 -0.2794)
			(stroke
				(width 0.1)
				(type default)
			)
			(layer "F.Fab")
		)
		(fp_line
			(start -0.12065 0.2794)
			(end -0.12065 0.3048)
			(stroke
				(width 0.1)
				(type default)
			)
			(layer "F.Fab")
		)
		(fp_line
			(start -0.12065 0.3048)
			(end -0.67945 0.3048)
			(stroke
				(width 0.1)
				(type default)
			)
			(layer "F.Fab")
		)
		(fp_line
			(start 0.120396 0.2794)
			(end -0.12065 0.2794)
			(stroke
				(width 0.1)
				(type default)
			)
			(layer "F.Fab")
		)
		(fp_line
			(start 0.120396 0.3048)
			(end 0.120396 0.2794)
			(stroke
				(width 0.1)
				(type default)
			)
			(layer "F.Fab")
		)
		(fp_line
			(start 0.12065 -0.3048)
			(end 0.67945 -0.3048)
			(stroke
				(width 0.1)
				(type default)
			)
			(layer "F.Fab")
		)
		(fp_line
			(start 0.12065 -0.2794)
			(end 0.12065 -0.3048)
			(stroke
				(width 0.1)
				(type default)
			)
			(layer "F.Fab")
		)
		(fp_line
			(start 0.67945 -0.3048)
			(end 0.67945 0.3048)
			(stroke
				(width 0.1)
				(type default)
			)
			(layer "F.Fab")
		)
		(fp_line
			(start 0.67945 0.3048)
			(end 0.120396 0.3048)
			(stroke
				(width 0.1)
				(type default)
			)
			(layer "F.Fab")
		)
		(pad "1" smd circle
			(at -0.40005 0)
			(size 0 0)
			(layers "F.Cu" "F.Mask" "F.Paste")
			(net "P3V3_AUX")
		)
		(pad "2" smd circle
			(at 0.40005 0)
			(size 0 0)
			(layers "F.Cu" "F.Mask" "F.Paste")
			(net "GND")
		)
	)
	(footprint ""
		(layer "F.Cu")
		(at 134.643114 -408.517344 -90)
		(property "Reference" "C1525"
			(at 0 0 270)
			(layer "F.SilkS")
			(hide yes)
			(effects
				(font
					(size 1.27 1.27)
				)
			)
		)
		(property "Value" ""
			(at 0 0 270)
			(layer "F.Fab")
			(effects
				(font
					(size 1.27 1.27)
				)
			)
		)
		(duplicate_pad_numbers_are_jumpers no)
		(fp_line
			(start -0.299974 0.150114)
			(end -0.299974 -0.150114)
			(stroke
				(width 0.1)
				(type default)
			)
			(layer "F.Fab")
		)
		(fp_line
			(start 0.299974 0.150114)
			(end -0.299974 0.150114)
			(stroke
				(width 0.1)
				(type default)
			)
			(layer "F.Fab")
		)
		(fp_line
			(start -0.299974 -0.150114)
			(end 0.299974 -0.150114)
			(stroke
				(width 0.1)
				(type default)
			)
			(layer "F.Fab")
		)
		(fp_line
			(start 0.299974 -0.150114)
			(end 0.299974 0.150114)
			(stroke
				(width 0.1)
				(type default)
			)
			(layer "F.Fab")
		)
		(pad "1" smd rect
			(at -0.2667 0 270)
			(size 0.3048 0.381)
			(layers "F.Cu" "F.Mask" "F.Paste")
			(net "P5E_CPU1_PE3_TX_C_DP<11>")
		)
		(pad "2" smd rect
			(at 0.2667 0 270)
			(size 0.3048 0.381)
			(layers "F.Cu" "F.Mask" "F.Paste")
			(net "P5E_CPU1_PE3_TX_DP<11>")
		)
	)
	(footprint ""
		(layer "F.Cu")
		(at 348.186248 -408.517344 -90)
		(property "Reference" "C930"
			(at 0 0 270)
			(layer "F.SilkS")
			(hide yes)
			(effects
				(font
					(size 1.27 1.27)
				)
			)
		)
		(property "Value" ""
			(at 0 0 270)
			(layer "F.Fab")
			(effects
				(font
					(size 1.27 1.27)
				)
			)
		)
		(duplicate_pad_numbers_are_jumpers no)
		(fp_line
			(start -0.299974 0.150114)
			(end -0.299974 -0.150114)
			(stroke
				(width 0.1)
				(type default)
			)
			(layer "F.Fab")
		)
		(fp_line
			(start 0.299974 0.150114)
			(end -0.299974 0.150114)
			(stroke
				(width 0.1)
				(type default)
			)
			(layer "F.Fab")
		)
		(fp_line
			(start -0.299974 -0.150114)
			(end 0.299974 -0.150114)
			(stroke
				(width 0.1)
				(type default)
			)
			(layer "F.Fab")
		)
		(fp_line
			(start 0.299974 -0.150114)
			(end 0.299974 0.150114)
			(stroke
				(width 0.1)
				(type default)
			)
			(layer "F.Fab")
		)
		(pad "1" smd rect
			(at -0.2667 0 270)
			(size 0.3048 0.381)
			(layers "F.Cu" "F.Mask" "F.Paste")
			(net "P5E_CPU0_PE0_TX_C_DN<1>")
		)
		(pad "2" smd rect
			(at 0.2667 0 270)
			(size 0.3048 0.381)
			(layers "F.Cu" "F.Mask" "F.Paste")
			(net "P5E_CPU0_PE0_TX_DN<1>")
		)
	)
	(footprint ""
		(layer "F.Cu")
		(at 123.6091 -414.283652)
		(property "Reference" "R4490"
			(at 0 0 0)
			(layer "F.SilkS")
			(hide yes)
			(effects
				(font
					(size 1.27 1.27)
				)
			)
		)
		(property "Value" ""
			(at 0 0 0)
			(layer "F.Fab")
			(effects
				(font
					(size 1.27 1.27)
				)
			)
		)
		(duplicate_pad_numbers_are_jumpers no)
		(fp_line
			(start -0.7874 -0.4064)
			(end 0.7874 -0.4064)
			(stroke
				(width 0.1524)
				(type default)
			)
			(layer "F.SilkS")
		)
		(fp_line
			(start -0.7874 0.4064)
			(end -0.7874 -0.4064)
			(stroke
				(width 0.1524)
				(type default)
			)
			(layer "F.SilkS")
		)
		(fp_line
			(start 0.7874 -0.4064)
			(end 0.7874 0.4064)
			(stroke
				(width 0.1524)
				(type default)
			)
			(layer "F.SilkS")
		)
		(fp_line
			(start 0.7874 0.4064)
			(end -0.7874 0.4064)
			(stroke
				(width 0.1524)
				(type default)
			)
			(layer "F.SilkS")
		)
		(fp_line
			(start -0.67945 -0.305054)
			(end -0.12065 -0.305054)
			(stroke
				(width 0.1)
				(type default)
			)
			(layer "F.Fab")
		)
		(fp_line
			(start -0.67945 0.3048)
			(end -0.67945 -0.305054)
			(stroke
				(width 0.1)
				(type default)
			)
			(layer "F.Fab")
		)
		(fp_line
			(start -0.12065 -0.305054)
			(end -0.12065 -0.2794)
			(stroke
				(width 0.1)
				(type default)
			)
			(layer "F.Fab")
		)
		(fp_line
			(start -0.12065 -0.2794)
			(end 0.12065 -0.2794)
			(stroke
				(width 0.1)
				(type default)
			)
			(layer "F.Fab")
		)
		(fp_line
			(start -0.12065 0.2794)
			(end -0.12065 0.3048)
			(stroke
				(width 0.1)
				(type default)
			)
			(layer "F.Fab")
		)
		(fp_line
			(start -0.12065 0.3048)
			(end -0.67945 0.3048)
			(stroke
				(width 0.1)
				(type default)
			)
			(layer "F.Fab")
		)
		(fp_line
			(start 0.120396 0.2794)
			(end -0.12065 0.2794)
			(stroke
				(width 0.1)
				(type default)
			)
			(layer "F.Fab")
		)
		(fp_line
			(start 0.120396 0.3048)
			(end 0.120396 0.2794)
			(stroke
				(width 0.1)
				(type default)
			)
			(layer "F.Fab")
		)
		(fp_line
			(start 0.12065 -0.3048)
			(end 0.67945 -0.3048)
			(stroke
				(width 0.1)
				(type default)
			)
			(layer "F.Fab")
		)
		(fp_line
			(start 0.12065 -0.2794)
			(end 0.12065 -0.3048)
			(stroke
				(width 0.1)
				(type default)
			)
			(layer "F.Fab")
		)
		(fp_line
			(start 0.67945 -0.3048)
			(end 0.67945 0.3048)
			(stroke
				(width 0.1)
				(type default)
			)
			(layer "F.Fab")
		)
		(fp_line
			(start 0.67945 0.3048)
			(end 0.120396 0.3048)
			(stroke
				(width 0.1)
				(type default)
			)
			(layer "F.Fab")
		)
		(pad "1" smd circle
			(at -0.40005 0)
			(size 0 0)
			(layers "F.Cu" "F.Mask" "F.Paste")
			(net "CLK_9ZXL045_SADR0")
		)
		(pad "2" smd circle
			(at 0.40005 0)
			(size 0 0)
			(layers "F.Cu" "F.Mask" "F.Paste")
			(net "GND")
		)
	)
	(footprint ""
		(layer "F.Cu")
		(at 454.742804 -76.588112 90)
		(property "Reference" "PC2343"
			(at 0 0 90)
			(layer "F.SilkS")
			(hide yes)
			(effects
				(font
					(size 1.27 1.27)
				)
			)
		)
		(property "Value" ""
			(at 0 0 90)
			(layer "F.Fab")
			(effects
				(font
					(size 1.27 1.27)
				)
			)
		)
		(duplicate_pad_numbers_are_jumpers no)
		(fp_line
			(start 1.524 -0.762)
			(end 1.524 0.762)
			(stroke
				(width 0.1524)
				(type default)
			)
			(layer "F.SilkS")
		)
		(fp_line
			(start -1.524 -0.762)
			(end 1.524 -0.762)
			(stroke
				(width 0.1524)
				(type default)
			)
			(layer "F.SilkS")
		)
		(fp_line
			(start 1.524 0.762)
			(end -1.524 0.762)
			(stroke
				(width 0.1524)
				(type default)
			)
			(layer "F.SilkS")
		)
		(fp_line
			(start -1.524 0.762)
			(end -1.524 -0.762)
			(stroke
				(width 0.1524)
				(type default)
			)
			(layer "F.SilkS")
		)
		(fp_line
			(start 1.1049 -0.724916)
			(end -1.1049 -0.724916)
			(stroke
				(width 0.1)
				(type default)
			)
			(layer "F.Fab")
		)
		(fp_line
			(start -1.1049 -0.724916)
			(end -1.1049 0.724916)
			(stroke
				(width 0.1)
				(type default)
			)
			(layer "F.Fab")
		)
		(fp_line
			(start 1.1049 0.724916)
			(end 1.1049 -0.724916)
			(stroke
				(width 0.1)
				(type default)
			)
			(layer "F.Fab")
		)
		(fp_line
			(start -1.1049 0.724916)
			(end 1.1049 0.724916)
			(stroke
				(width 0.1)
				(type default)
			)
			(layer "F.Fab")
		)
		(pad "1" smd rect
			(at -0.889 0 270)
			(size 1.016 1.27)
			(layers "F.Cu" "F.Mask" "F.Paste")
			(net "SW_P3V3_AUX_FLT")
		)
		(pad "2" smd rect
			(at 0.889 0 270)
			(size 1.016 1.27)
			(layers "F.Cu" "F.Mask" "F.Paste")
			(net "GND")
		)
	)
	(footprint ""
		(layer "F.Cu")
		(at 325.193914 -26.143712 180)
		(property "Reference" "C610"
			(at 0 0 180)
			(layer "F.SilkS")
			(hide yes)
			(effects
				(font
					(size 1.27 1.27)
				)
			)
		)
		(property "Value" ""
			(at 0 0 180)
			(layer "F.Fab")
			(effects
				(font
					(size 1.27 1.27)
				)
			)
		)
		(duplicate_pad_numbers_are_jumpers no)
		(fp_line
			(start 0.7874 0.4064)
			(end -0.7874 0.4064)
			(stroke
				(width 0.1524)
				(type default)
			)
			(layer "F.SilkS")
		)
		(fp_line
			(start 0.7874 -0.4064)
			(end 0.7874 0.4064)
			(stroke
				(width 0.1524)
				(type default)
			)
			(layer "F.SilkS")
		)
		(fp_line
			(start -0.7874 0.4064)
			(end -0.7874 -0.4064)
			(stroke
				(width 0.1524)
				(type default)
			)
			(layer "F.SilkS")
		)
		(fp_line
			(start -0.7874 -0.4064)
			(end 0.7874 -0.4064)
			(stroke
				(width 0.1524)
				(type default)
			)
			(layer "F.SilkS")
		)
		(fp_line
			(start 0.67945 0.3048)
			(end 0.120396 0.3048)
			(stroke
				(width 0.1)
				(type default)
			)
			(layer "F.Fab")
		)
		(fp_line
			(start 0.67945 -0.3048)
			(end 0.67945 0.3048)
			(stroke
				(width 0.1)
				(type default)
			)
			(layer "F.Fab")
		)
		(fp_line
			(start 0.12065 -0.2794)
			(end 0.12065 -0.3048)
			(stroke
				(width 0.1)
				(type default)
			)
			(layer "F.Fab")
		)
		(fp_line
			(start 0.12065 -0.3048)
			(end 0.67945 -0.3048)
			(stroke
				(width 0.1)
				(type default)
			)
			(layer "F.Fab")
		)
		(fp_line
			(start 0.120396 0.3048)
			(end 0.120396 0.2794)
			(stroke
				(width 0.1)
				(type default)
			)
			(layer "F.Fab")
		)
		(fp_line
			(start 0.120396 0.2794)
			(end -0.12065 0.2794)
			(stroke
				(width 0.1)
				(type default)
			)
			(layer "F.Fab")
		)
		(fp_line
			(start -0.12065 0.3048)
			(end -0.67945 0.3048)
			(stroke
				(width 0.1)
				(type default)
			)
			(layer "F.Fab")
		)
		(fp_line
			(start -0.12065 0.2794)
			(end -0.12065 0.3048)
			(stroke
				(width 0.1)
				(type default)
			)
			(layer "F.Fab")
		)
		(fp_line
			(start -0.12065 -0.2794)
			(end 0.12065 -0.2794)
			(stroke
				(width 0.1)
				(type default)
			)
			(layer "F.Fab")
		)
		(fp_line
			(start -0.12065 -0.305054)
			(end -0.12065 -0.2794)
			(stroke
				(width 0.1)
				(type default)
			)
			(layer "F.Fab")
		)
		(fp_line
			(start -0.67945 0.3048)
			(end -0.67945 -0.305054)
			(stroke
				(width 0.1)
				(type default)
			)
			(layer "F.Fab")
		)
		(fp_line
			(start -0.67945 -0.305054)
			(end -0.12065 -0.305054)
			(stroke
				(width 0.1)
				(type default)
			)
			(layer "F.Fab")
		)
		(pad "1" smd circle
			(at -0.40005 0 180)
			(size 0 0)
			(layers "F.Cu" "F.Mask" "F.Paste")
			(net "RST_SRTCRST_N")
		)
		(pad "2" smd circle
			(at 0.40005 0 180)
			(size 0 0)
			(layers "F.Cu" "F.Mask" "F.Paste")
			(net "GND")
		)
	)
	(footprint ""
		(layer "F.Cu")
		(at 441.099194 -125.035818 90)
		(property "Reference" "C2443"
			(at 0 0 90)
			(layer "F.SilkS")
			(hide yes)
			(effects
				(font
					(size 1.27 1.27)
				)
			)
		)
		(property "Value" ""
			(at 0 0 90)
			(layer "F.Fab")
			(effects
				(font
					(size 1.27 1.27)
				)
			)
		)
		(duplicate_pad_numbers_are_jumpers no)
		(fp_line
			(start 0.7874 -0.4064)
			(end 0.7874 0.4064)
			(stroke
				(width 0.1524)
				(type default)
			)
			(layer "F.SilkS")
		)
		(fp_line
			(start -0.7874 -0.4064)
			(end 0.7874 -0.4064)
			(stroke
				(width 0.1524)
				(type default)
			)
			(layer "F.SilkS")
		)
		(fp_line
			(start 0.7874 0.4064)
			(end -0.7874 0.4064)
			(stroke
				(width 0.1524)
				(type default)
			)
			(layer "F.SilkS")
		)
		(fp_line
			(start -0.7874 0.4064)
			(end -0.7874 -0.4064)
			(stroke
				(width 0.1524)
				(type default)
			)
			(layer "F.SilkS")
		)
		(fp_line
			(start -0.12065 -0.305054)
			(end -0.12065 -0.2794)
			(stroke
				(width 0.1)
				(type default)
			)
			(layer "F.Fab")
		)
		(fp_line
			(start -0.67945 -0.305054)
			(end -0.12065 -0.305054)
			(stroke
				(width 0.1)
				(type default)
			)
			(layer "F.Fab")
		)
		(fp_line
			(start 0.67945 -0.3048)
			(end 0.67945 0.3048)
			(stroke
				(width 0.1)
				(type default)
			)
			(layer "F.Fab")
		)
		(fp_line
			(start 0.12065 -0.3048)
			(end 0.67945 -0.3048)
			(stroke
				(width 0.1)
				(type default)
			)
			(layer "F.Fab")
		)
		(fp_line
			(start 0.12065 -0.2794)
			(end 0.12065 -0.3048)
			(stroke
				(width 0.1)
				(type default)
			)
			(layer "F.Fab")
		)
		(fp_line
			(start -0.12065 -0.2794)
			(end 0.12065 -0.2794)
			(stroke
				(width 0.1)
				(type default)
			)
			(layer "F.Fab")
		)
		(fp_line
			(start 0.120396 0.2794)
			(end -0.12065 0.2794)
			(stroke
				(width 0.1)
				(type default)
			)
			(layer "F.Fab")
		)
		(fp_line
			(start -0.12065 0.2794)
			(end -0.12065 0.3048)
			(stroke
				(width 0.1)
				(type default)
			)
			(layer "F.Fab")
		)
		(fp_line
			(start 0.67945 0.3048)
			(end 0.120396 0.3048)
			(stroke
				(width 0.1)
				(type default)
			)
			(layer "F.Fab")
		)
		(fp_line
			(start 0.120396 0.3048)
			(end 0.120396 0.2794)
			(stroke
				(width 0.1)
				(type default)
			)
			(layer "F.Fab")
		)
		(fp_line
			(start -0.12065 0.3048)
			(end -0.67945 0.3048)
			(stroke
				(width 0.1)
				(type default)
			)
			(layer "F.Fab")
		)
		(fp_line
			(start -0.67945 0.3048)
			(end -0.67945 -0.305054)
			(stroke
				(width 0.1)
				(type default)
			)
			(layer "F.Fab")
		)
		(pad "1" smd circle
			(at -0.40005 0 90)
			(size 0 0)
			(layers "F.Cu" "F.Mask" "F.Paste")
			(net "PVNN_TERM_CPU0")
		)
		(pad "2" smd circle
			(at 0.40005 0 90)
			(size 0 0)
			(layers "F.Cu" "F.Mask" "F.Paste")
			(net "GND")
		)
	)
	(footprint ""
		(layer "F.Cu")
		(at 402.106384 -16.088614 90)
		(property "Reference" "C846"
			(at 0 0 90)
			(layer "F.SilkS")
			(hide yes)
			(effects
				(font
					(size 1.27 1.27)
				)
			)
		)
		(property "Value" ""
			(at 0 0 90)
			(layer "F.Fab")
			(effects
				(font
					(size 1.27 1.27)
				)
			)
		)
		(duplicate_pad_numbers_are_jumpers no)
		(fp_line
			(start 0.299974 -0.150114)
			(end 0.299974 0.150114)
			(stroke
				(width 0.1)
				(type default)
			)
			(layer "F.Fab")
		)
		(fp_line
			(start -0.299974 -0.150114)
			(end 0.299974 -0.150114)
			(stroke
				(width 0.1)
				(type default)
			)
			(layer "F.Fab")
		)
		(fp_line
			(start 0.299974 0.150114)
			(end -0.299974 0.150114)
			(stroke
				(width 0.1)
				(type default)
			)
			(layer "F.Fab")
		)
		(fp_line
			(start -0.299974 0.150114)
			(end -0.299974 -0.150114)
			(stroke
				(width 0.1)
				(type default)
			)
			(layer "F.Fab")
		)
		(pad "1" smd rect
			(at -0.2667 0 90)
			(size 0.3048 0.381)
			(layers "F.Cu" "F.Mask" "F.Paste")
			(net "P5E_CPU0_PE1_TX_C_DN<11>")
		)
		(pad "2" smd rect
			(at 0.2667 0 90)
			(size 0.3048 0.381)
			(layers "F.Cu" "F.Mask" "F.Paste")
			(net "P5E_CPU0_PE1_TX_DN<11>")
		)
	)
	(footprint ""
		(layer "F.Cu")
		(at 249.374406 -92.06484 90)
		(property "Reference" "R1724"
			(at 0 0 90)
			(layer "F.SilkS")
			(hide yes)
			(effects
				(font
					(size 1.27 1.27)
				)
			)
		)
		(property "Value" ""
			(at 0 0 90)
			(layer "F.Fab")
			(effects
				(font
					(size 1.27 1.27)
				)
			)
		)
		(duplicate_pad_numbers_are_jumpers no)
		(fp_line
			(start 0.7874 -0.4064)
			(end 0.7874 0.4064)
			(stroke
				(width 0.1524)
				(type default)
			)
			(layer "F.SilkS")
		)
		(fp_line
			(start -0.7874 -0.4064)
			(end 0.7874 -0.4064)
			(stroke
				(width 0.1524)
				(type default)
			)
			(layer "F.SilkS")
		)
		(fp_line
			(start 0.7874 0.4064)
			(end -0.7874 0.4064)
			(stroke
				(width 0.1524)
				(type default)
			)
			(layer "F.SilkS")
		)
		(fp_line
			(start -0.7874 0.4064)
			(end -0.7874 -0.4064)
			(stroke
				(width 0.1524)
				(type default)
			)
			(layer "F.SilkS")
		)
		(fp_line
			(start -0.12065 -0.305054)
			(end -0.12065 -0.2794)
			(stroke
				(width 0.1)
				(type default)
			)
			(layer "F.Fab")
		)
		(fp_line
			(start -0.67945 -0.305054)
			(end -0.12065 -0.305054)
			(stroke
				(width 0.1)
				(type default)
			)
			(layer "F.Fab")
		)
		(fp_line
			(start 0.67945 -0.3048)
			(end 0.67945 0.3048)
			(stroke
				(width 0.1)
				(type default)
			)
			(layer "F.Fab")
		)
		(fp_line
			(start 0.12065 -0.3048)
			(end 0.67945 -0.3048)
			(stroke
				(width 0.1)
				(type default)
			)
			(layer "F.Fab")
		)
		(fp_line
			(start 0.12065 -0.2794)
			(end 0.12065 -0.3048)
			(stroke
				(width 0.1)
				(type default)
			)
			(layer "F.Fab")
		)
		(fp_line
			(start -0.12065 -0.2794)
			(end 0.12065 -0.2794)
			(stroke
				(width 0.1)
				(type default)
			)
			(layer "F.Fab")
		)
		(fp_line
			(start 0.120396 0.2794)
			(end -0.12065 0.2794)
			(stroke
				(width 0.1)
				(type default)
			)
			(layer "F.Fab")
		)
		(fp_line
			(start -0.12065 0.2794)
			(end -0.12065 0.3048)
			(stroke
				(width 0.1)
				(type default)
			)
			(layer "F.Fab")
		)
		(fp_line
			(start 0.67945 0.3048)
			(end 0.120396 0.3048)
			(stroke
				(width 0.1)
				(type default)
			)
			(layer "F.Fab")
		)
		(fp_line
			(start 0.120396 0.3048)
			(end 0.120396 0.2794)
			(stroke
				(width 0.1)
				(type default)
			)
			(layer "F.Fab")
		)
		(fp_line
			(start -0.12065 0.3048)
			(end -0.67945 0.3048)
			(stroke
				(width 0.1)
				(type default)
			)
			(layer "F.Fab")
		)
		(fp_line
			(start -0.67945 0.3048)
			(end -0.67945 -0.305054)
			(stroke
				(width 0.1)
				(type default)
			)
			(layer "F.Fab")
		)
		(pad "1" smd circle
			(at -0.40005 0 90)
			(size 0 0)
			(layers "F.Cu" "F.Mask" "F.Paste")
			(net "XTAL_CLK_GEN1_25M_X1_R")
		)
		(pad "2" smd circle
			(at 0.40005 0 90)
			(size 0 0)
			(layers "F.Cu" "F.Mask" "F.Paste")
			(net "XTAL_CLK_GEN1_25M_X1")
		)
	)
	(footprint ""
		(layer "F.Cu")
		(at 99.457002 -417.631626 90)
		(property "Reference" "R4202"
			(at 0 0 90)
			(layer "F.SilkS")
			(hide yes)
			(effects
				(font
					(size 1.27 1.27)
				)
			)
		)
		(property "Value" ""
			(at 0 0 90)
			(layer "F.Fab")
			(effects
				(font
					(size 1.27 1.27)
				)
			)
		)
		(duplicate_pad_numbers_are_jumpers no)
		(fp_line
			(start 0.7874 -0.4064)
			(end 0.7874 0.4064)
			(stroke
				(width 0.1524)
				(type default)
			)
			(layer "F.SilkS")
		)
		(fp_line
			(start -0.7874 -0.4064)
			(end 0.7874 -0.4064)
			(stroke
				(width 0.1524)
				(type default)
			)
			(layer "F.SilkS")
		)
		(fp_line
			(start 0.7874 0.4064)
			(end -0.7874 0.4064)
			(stroke
				(width 0.1524)
				(type default)
			)
			(layer "F.SilkS")
		)
		(fp_line
			(start -0.7874 0.4064)
			(end -0.7874 -0.4064)
			(stroke
				(width 0.1524)
				(type default)
			)
			(layer "F.SilkS")
		)
		(fp_line
			(start -0.12065 -0.305054)
			(end -0.12065 -0.2794)
			(stroke
				(width 0.1)
				(type default)
			)
			(layer "F.Fab")
		)
		(fp_line
			(start -0.67945 -0.305054)
			(end -0.12065 -0.305054)
			(stroke
				(width 0.1)
				(type default)
			)
			(layer "F.Fab")
		)
		(fp_line
			(start 0.67945 -0.3048)
			(end 0.67945 0.3048)
			(stroke
				(width 0.1)
				(type default)
			)
			(layer "F.Fab")
		)
		(fp_line
			(start 0.12065 -0.3048)
			(end 0.67945 -0.3048)
			(stroke
				(width 0.1)
				(type default)
			)
			(layer "F.Fab")
		)
		(fp_line
			(start 0.12065 -0.2794)
			(end 0.12065 -0.3048)
			(stroke
				(width 0.1)
				(type default)
			)
			(layer "F.Fab")
		)
		(fp_line
			(start -0.12065 -0.2794)
			(end 0.12065 -0.2794)
			(stroke
				(width 0.1)
				(type default)
			)
			(layer "F.Fab")
		)
		(fp_line
			(start 0.120396 0.2794)
			(end -0.12065 0.2794)
			(stroke
				(width 0.1)
				(type default)
			)
			(layer "F.Fab")
		)
		(fp_line
			(start -0.12065 0.2794)
			(end -0.12065 0.3048)
			(stroke
				(width 0.1)
				(type default)
			)
			(layer "F.Fab")
		)
		(fp_line
			(start 0.67945 0.3048)
			(end 0.120396 0.3048)
			(stroke
				(width 0.1)
				(type default)
			)
			(layer "F.Fab")
		)
		(fp_line
			(start 0.120396 0.3048)
			(end 0.120396 0.2794)
			(stroke
				(width 0.1)
				(type default)
			)
			(layer "F.Fab")
		)
		(fp_line
			(start -0.12065 0.3048)
			(end -0.67945 0.3048)
			(stroke
				(width 0.1)
				(type default)
			)
			(layer "F.Fab")
		)
		(fp_line
			(start -0.67945 0.3048)
			(end -0.67945 -0.305054)
			(stroke
				(width 0.1)
				(type default)
			)
			(layer "F.Fab")
		)
		(pad "1" smd circle
			(at -0.40005 0 90)
			(size 0 0)
			(layers "F.Cu" "F.Mask" "F.Paste")
			(net "P3V3_AUX")
		)
		(pad "2" smd circle
			(at 0.40005 0 90)
			(size 0 0)
			(layers "F.Cu" "F.Mask" "F.Paste")
			(net "U272_2_ADD0")
		)
	)
	(footprint ""
		(layer "F.Cu")
		(at 336.847688 -408.517344 -90)
		(property "Reference" "C923"
			(at 0 0 270)
			(layer "F.SilkS")
			(hide yes)
			(effects
				(font
					(size 1.27 1.27)
				)
			)
		)
		(property "Value" ""
			(at 0 0 270)
			(layer "F.Fab")
			(effects
				(font
					(size 1.27 1.27)
				)
			)
		)
		(duplicate_pad_numbers_are_jumpers no)
		(fp_line
			(start -0.299974 0.150114)
			(end -0.299974 -0.150114)
			(stroke
				(width 0.1)
				(type default)
			)
			(layer "F.Fab")
		)
		(fp_line
			(start 0.299974 0.150114)
			(end -0.299974 0.150114)
			(stroke
				(width 0.1)
				(type default)
			)
			(layer "F.Fab")
		)
		(fp_line
			(start -0.299974 -0.150114)
			(end 0.299974 -0.150114)
			(stroke
				(width 0.1)
				(type default)
			)
			(layer "F.Fab")
		)
		(fp_line
			(start 0.299974 -0.150114)
			(end 0.299974 0.150114)
			(stroke
				(width 0.1)
				(type default)
			)
			(layer "F.Fab")
		)
		(pad "1" smd rect
			(at -0.2667 0 270)
			(size 0.3048 0.381)
			(layers "F.Cu" "F.Mask" "F.Paste")
			(net "P5E_CPU0_PE0_TX_C_DP<5>")
		)
		(pad "2" smd rect
			(at 0.2667 0 270)
			(size 0.3048 0.381)
			(layers "F.Cu" "F.Mask" "F.Paste")
			(net "P5E_CPU0_PE0_TX_DP<5>")
		)
	)
	(footprint ""
		(layer "F.Cu")
		(at 427.634654 -366.691164 -90)
		(property "Reference" "PC1177"
			(at 0 0 270)
			(layer "F.SilkS")
			(hide yes)
			(effects
				(font
					(size 1.27 1.27)
				)
			)
		)
		(property "Value" ""
			(at 0 0 270)
			(layer "F.Fab")
			(effects
				(font
					(size 1.27 1.27)
				)
			)
		)
		(duplicate_pad_numbers_are_jumpers no)
		(fp_line
			(start -0.7874 0.4064)
			(end -0.7874 -0.4064)
			(stroke
				(width 0.1524)
				(type default)
			)
			(layer "F.SilkS")
		)
		(fp_line
			(start 0.7874 0.4064)
			(end -0.7874 0.4064)
			(stroke
				(width 0.1524)
				(type default)
			)
			(layer "F.SilkS")
		)
		(fp_line
			(start -0.7874 -0.4064)
			(end 0.7874 -0.4064)
			(stroke
				(width 0.1524)
				(type default)
			)
			(layer "F.SilkS")
		)
		(fp_line
			(start 0.7874 -0.4064)
			(end 0.7874 0.4064)
			(stroke
				(width 0.1524)
				(type default)
			)
			(layer "F.SilkS")
		)
		(fp_line
			(start -0.67945 0.3048)
			(end -0.67945 -0.305054)
			(stroke
				(width 0.1)
				(type default)
			)
			(layer "F.Fab")
		)
		(fp_line
			(start -0.12065 0.3048)
			(end -0.67945 0.3048)
			(stroke
				(width 0.1)
				(type default)
			)
			(layer "F.Fab")
		)
		(fp_line
			(start 0.120396 0.3048)
			(end 0.120396 0.2794)
			(stroke
				(width 0.1)
				(type default)
			)
			(layer "F.Fab")
		)
		(fp_line
			(start 0.67945 0.3048)
			(end 0.120396 0.3048)
			(stroke
				(width 0.1)
				(type default)
			)
			(layer "F.Fab")
		)
		(fp_line
			(start -0.12065 0.2794)
			(end -0.12065 0.3048)
			(stroke
				(width 0.1)
				(type default)
			)
			(layer "F.Fab")
		)
		(fp_line
			(start 0.120396 0.2794)
			(end -0.12065 0.2794)
			(stroke
				(width 0.1)
				(type default)
			)
			(layer "F.Fab")
		)
		(fp_line
			(start -0.12065 -0.2794)
			(end 0.12065 -0.2794)
			(stroke
				(width 0.1)
				(type default)
			)
			(layer "F.Fab")
		)
		(fp_line
			(start 0.12065 -0.2794)
			(end 0.12065 -0.3048)
			(stroke
				(width 0.1)
				(type default)
			)
			(layer "F.Fab")
		)
		(fp_line
			(start 0.12065 -0.3048)
			(end 0.67945 -0.3048)
			(stroke
				(width 0.1)
				(type default)
			)
			(layer "F.Fab")
		)
		(fp_line
			(start 0.67945 -0.3048)
			(end 0.67945 0.3048)
			(stroke
				(width 0.1)
				(type default)
			)
			(layer "F.Fab")
		)
		(fp_line
			(start -0.67945 -0.305054)
			(end -0.12065 -0.305054)
			(stroke
				(width 0.1)
				(type default)
			)
			(layer "F.Fab")
		)
		(fp_line
			(start -0.12065 -0.305054)
			(end -0.12065 -0.2794)
			(stroke
				(width 0.1)
				(type default)
			)
			(layer "F.Fab")
		)
		(pad "1" smd circle
			(at -0.40005 0 270)
			(size 0 0)
			(layers "F.Cu" "F.Mask" "F.Paste")
			(net "SW_PVCCFA_EHV_FIVRA_CPU0_BOOT3_")
		)
		(pad "2" smd circle
			(at 0.40005 0 270)
			(size 0 0)
			(layers "F.Cu" "F.Mask" "F.Paste")
			(net "SW_PVCCFA_EHV_FIVRA_CPU0_BOOTR3")
		)
	)
	(footprint ""
		(layer "F.Cu")
		(at 183.69788 -130.266948 -90)
		(property "Reference" "R283"
			(at 0 0 270)
			(layer "F.SilkS")
			(hide yes)
			(effects
				(font
					(size 1.27 1.27)
				)
			)
		)
		(property "Value" ""
			(at 0 0 270)
			(layer "F.Fab")
			(effects
				(font
					(size 1.27 1.27)
				)
			)
		)
		(duplicate_pad_numbers_are_jumpers no)
		(fp_line
			(start -0.7874 0.4064)
			(end -0.7874 -0.4064)
			(stroke
				(width 0.1524)
				(type default)
			)
			(layer "F.SilkS")
		)
		(fp_line
			(start 0.7874 0.4064)
			(end -0.7874 0.4064)
			(stroke
				(width 0.1524)
				(type default)
			)
			(layer "F.SilkS")
		)
		(fp_line
			(start -0.7874 -0.4064)
			(end 0.7874 -0.4064)
			(stroke
				(width 0.1524)
				(type default)
			)
			(layer "F.SilkS")
		)
		(fp_line
			(start 0.7874 -0.4064)
			(end 0.7874 0.4064)
			(stroke
				(width 0.1524)
				(type default)
			)
			(layer "F.SilkS")
		)
		(fp_line
			(start -0.67945 0.3048)
			(end -0.67945 -0.305054)
			(stroke
				(width 0.1)
				(type default)
			)
			(layer "F.Fab")
		)
		(fp_line
			(start -0.12065 0.3048)
			(end -0.67945 0.3048)
			(stroke
				(width 0.1)
				(type default)
			)
			(layer "F.Fab")
		)
		(fp_line
			(start 0.120396 0.3048)
			(end 0.120396 0.2794)
			(stroke
				(width 0.1)
				(type default)
			)
			(layer "F.Fab")
		)
		(fp_line
			(start 0.67945 0.3048)
			(end 0.120396 0.3048)
			(stroke
				(width 0.1)
				(type default)
			)
			(layer "F.Fab")
		)
		(fp_line
			(start -0.12065 0.2794)
			(end -0.12065 0.3048)
			(stroke
				(width 0.1)
				(type default)
			)
			(layer "F.Fab")
		)
		(fp_line
			(start 0.120396 0.2794)
			(end -0.12065 0.2794)
			(stroke
				(width 0.1)
				(type default)
			)
			(layer "F.Fab")
		)
		(fp_line
			(start -0.12065 -0.2794)
			(end 0.12065 -0.2794)
			(stroke
				(width 0.1)
				(type default)
			)
			(layer "F.Fab")
		)
		(fp_line
			(start 0.12065 -0.2794)
			(end 0.12065 -0.3048)
			(stroke
				(width 0.1)
				(type default)
			)
			(layer "F.Fab")
		)
		(fp_line
			(start 0.12065 -0.3048)
			(end 0.67945 -0.3048)
			(stroke
				(width 0.1)
				(type default)
			)
			(layer "F.Fab")
		)
		(fp_line
			(start 0.67945 -0.3048)
			(end 0.67945 0.3048)
			(stroke
				(width 0.1)
				(type default)
			)
			(layer "F.Fab")
		)
		(fp_line
			(start -0.67945 -0.305054)
			(end -0.12065 -0.305054)
			(stroke
				(width 0.1)
				(type default)
			)
			(layer "F.Fab")
		)
		(fp_line
			(start -0.12065 -0.305054)
			(end -0.12065 -0.2794)
			(stroke
				(width 0.1)
				(type default)
			)
			(layer "F.Fab")
		)
		(pad "1" smd circle
			(at -0.40005 0 270)
			(size 0 0)
			(layers "F.Cu" "F.Mask" "F.Paste")
			(net "P3V3_AUX")
		)
		(pad "2" smd circle
			(at 0.40005 0 270)
			(size 0 0)
			(layers "F.Cu" "F.Mask" "F.Paste")
			(net "FM_CPU0_PKGID0")
		)
	)
	(footprint ""
		(layer "F.Cu")
		(at 133.420104 -297.514772)
		(property "Reference" "H16"
			(at 0.201676 -6.217666 0)
			(unlocked yes)
			(layer "F.SilkS")
			(effects
				(font
					(size 0.7874 0.5842)
					(thickness 0.1524)
				)
				(justify left)
			)
		)
		(property "Value" ""
			(at 0 0 0)
			(layer "F.Fab")
			(effects
				(font
					(size 1.27 1.27)
				)
			)
		)
		(duplicate_pad_numbers_are_jumpers no)
		(fp_circle
			(center 0 0)
			(end 2.5273 0)
			(stroke
				(width 0.1524)
				(type default)
			)
			(fill no)
			(layer "F.SilkS")
		)
		(fp_circle
			(center 0 0)
			(end 2.5273 0)
			(stroke
				(width 0.1524)
				(type default)
			)
			(fill no)
			(layer "B.SilkS")
		)
		(fp_circle
			(center 0 0)
			(end 2.5273 0)
			(stroke
				(width 0.1)
				(type default)
			)
			(fill no)
			(layer "B.Fab")
		)
		(fp_circle
			(center 0 0)
			(end 2.5273 0)
			(stroke
				(width 0.1)
				(type default)
			)
			(fill no)
			(layer "F.Fab")
		)
		(pad "" np_thru_hole circle
			(at 0 0)
			(size 3.429 3.429)
			(drill 3.429)
			(layers "*.Cu" "*.Mask")
			(clearance 0.381)
			(thermal_gap 0.381)
		)
	)
	(footprint ""
		(layer "F.Cu")
		(at 16.110966 -92.687648 90)
		(property "Reference" "R3658"
			(at 0 0 90)
			(layer "F.SilkS")
			(hide yes)
			(effects
				(font
					(size 1.27 1.27)
				)
			)
		)
		(property "Value" ""
			(at 0 0 90)
			(layer "F.Fab")
			(effects
				(font
					(size 1.27 1.27)
				)
			)
		)
		(duplicate_pad_numbers_are_jumpers no)
		(fp_line
			(start 0.7874 -0.4064)
			(end 0.7874 0.4064)
			(stroke
				(width 0.1524)
				(type default)
			)
			(layer "F.SilkS")
		)
		(fp_line
			(start -0.7874 -0.4064)
			(end 0.7874 -0.4064)
			(stroke
				(width 0.1524)
				(type default)
			)
			(layer "F.SilkS")
		)
		(fp_line
			(start 0.7874 0.4064)
			(end -0.7874 0.4064)
			(stroke
				(width 0.1524)
				(type default)
			)
			(layer "F.SilkS")
		)
		(fp_line
			(start -0.7874 0.4064)
			(end -0.7874 -0.4064)
			(stroke
				(width 0.1524)
				(type default)
			)
			(layer "F.SilkS")
		)
		(fp_line
			(start -0.12065 -0.305054)
			(end -0.12065 -0.2794)
			(stroke
				(width 0.1)
				(type default)
			)
			(layer "F.Fab")
		)
		(fp_line
			(start -0.67945 -0.305054)
			(end -0.12065 -0.305054)
			(stroke
				(width 0.1)
				(type default)
			)
			(layer "F.Fab")
		)
		(fp_line
			(start 0.67945 -0.3048)
			(end 0.67945 0.3048)
			(stroke
				(width 0.1)
				(type default)
			)
			(layer "F.Fab")
		)
		(fp_line
			(start 0.12065 -0.3048)
			(end 0.67945 -0.3048)
			(stroke
				(width 0.1)
				(type default)
			)
			(layer "F.Fab")
		)
		(fp_line
			(start 0.12065 -0.2794)
			(end 0.12065 -0.3048)
			(stroke
				(width 0.1)
				(type default)
			)
			(layer "F.Fab")
		)
		(fp_line
			(start -0.12065 -0.2794)
			(end 0.12065 -0.2794)
			(stroke
				(width 0.1)
				(type default)
			)
			(layer "F.Fab")
		)
		(fp_line
			(start 0.120396 0.2794)
			(end -0.12065 0.2794)
			(stroke
				(width 0.1)
				(type default)
			)
			(layer "F.Fab")
		)
		(fp_line
			(start -0.12065 0.2794)
			(end -0.12065 0.3048)
			(stroke
				(width 0.1)
				(type default)
			)
			(layer "F.Fab")
		)
		(fp_line
			(start 0.67945 0.3048)
			(end 0.120396 0.3048)
			(stroke
				(width 0.1)
				(type default)
			)
			(layer "F.Fab")
		)
		(fp_line
			(start 0.120396 0.3048)
			(end 0.120396 0.2794)
			(stroke
				(width 0.1)
				(type default)
			)
			(layer "F.Fab")
		)
		(fp_line
			(start -0.12065 0.3048)
			(end -0.67945 0.3048)
			(stroke
				(width 0.1)
				(type default)
			)
			(layer "F.Fab")
		)
		(fp_line
			(start -0.67945 0.3048)
			(end -0.67945 -0.305054)
			(stroke
				(width 0.1)
				(type default)
			)
			(layer "F.Fab")
		)
		(pad "1" smd circle
			(at -0.40005 0 90)
			(size 0 0)
			(layers "F.Cu" "F.Mask" "F.Paste")
			(net "P3V3_AUX")
		)
		(pad "2" smd circle
			(at 0.40005 0 90)
			(size 0 0)
			(layers "F.Cu" "F.Mask" "F.Paste")
			(net "USB_HUB_OVCUR3")
		)
	)
	(footprint ""
		(layer "F.Cu")
		(at 392.84021 -402.371052 -90)
		(property "Reference" "C949"
			(at 0 0 270)
			(layer "F.SilkS")
			(hide yes)
			(effects
				(font
					(size 1.27 1.27)
				)
			)
		)
		(property "Value" ""
			(at 0 0 270)
			(layer "F.Fab")
			(effects
				(font
					(size 1.27 1.27)
				)
			)
		)
		(duplicate_pad_numbers_are_jumpers no)
		(fp_line
			(start -0.299974 0.150114)
			(end -0.299974 -0.150114)
			(stroke
				(width 0.1)
				(type default)
			)
			(layer "F.Fab")
		)
		(fp_line
			(start 0.299974 0.150114)
			(end -0.299974 0.150114)
			(stroke
				(width 0.1)
				(type default)
			)
			(layer "F.Fab")
		)
		(fp_line
			(start -0.299974 -0.150114)
			(end 0.299974 -0.150114)
			(stroke
				(width 0.1)
				(type default)
			)
			(layer "F.Fab")
		)
		(fp_line
			(start 0.299974 -0.150114)
			(end 0.299974 0.150114)
			(stroke
				(width 0.1)
				(type default)
			)
			(layer "F.Fab")
		)
		(pad "1" smd rect
			(at -0.2667 0 270)
			(size 0.3048 0.381)
			(layers "F.Cu" "F.Mask" "F.Paste")
			(net "P5E_CPU0_PE2_TX_C_DP<8>")
		)
		(pad "2" smd rect
			(at 0.2667 0 270)
			(size 0.3048 0.381)
			(layers "F.Cu" "F.Mask" "F.Paste")
			(net "P5E_CPU0_PE2_TX_DP<8>")
		)
	)
	(footprint ""
		(layer "F.Cu")
		(at 439.295032 -23.839678)
		(property "Reference" "PR3843"
			(at 0 0 0)
			(layer "F.SilkS")
			(hide yes)
			(effects
				(font
					(size 1.27 1.27)
				)
			)
		)
		(property "Value" ""
			(at 0 0 0)
			(layer "F.Fab")
			(effects
				(font
					(size 1.27 1.27)
				)
			)
		)
		(duplicate_pad_numbers_are_jumpers no)
		(fp_line
			(start -1.2954 -0.5842)
			(end 1.2954 -0.5842)
			(stroke
				(width 0.1524)
				(type default)
			)
			(layer "F.SilkS")
		)
		(fp_line
			(start -1.2954 0.5842)
			(end -1.2954 -0.5842)
			(stroke
				(width 0.1524)
				(type default)
			)
			(layer "F.SilkS")
		)
		(fp_line
			(start 1.2954 -0.5842)
			(end 1.2954 0.5842)
			(stroke
				(width 0.1524)
				(type default)
			)
			(layer "F.SilkS")
		)
		(fp_line
			(start 1.2954 0.5842)
			(end -1.2954 0.5842)
			(stroke
				(width 0.1524)
				(type default)
			)
			(layer "F.SilkS")
		)
		(fp_line
			(start -1.1938 -0.406654)
			(end -0.8636 -0.406654)
			(stroke
				(width 0.1)
				(type default)
			)
			(layer "F.Fab")
		)
		(fp_line
			(start -1.1938 0.4064)
			(end -1.1938 -0.406654)
			(stroke
				(width 0.1)
				(type default)
			)
			(layer "F.Fab")
		)
		(fp_line
			(start -0.8636 -0.4572)
			(end 0.8636 -0.4572)
			(stroke
				(width 0.1)
				(type default)
			)
			(layer "F.Fab")
		)
		(fp_line
			(start -0.8636 -0.406654)
			(end -0.8636 -0.4572)
			(stroke
				(width 0.1)
				(type default)
			)
			(layer "F.Fab")
		)
		(fp_line
			(start -0.8636 0.4064)
			(end -1.1938 0.4064)
			(stroke
				(width 0.1)
				(type default)
			)
			(layer "F.Fab")
		)
		(fp_line
			(start -0.8636 0.4318)
			(end -0.8636 0.4064)
			(stroke
				(width 0.1)
				(type default)
			)
			(layer "F.Fab")
		)
		(fp_line
			(start -0.8636 0.4572)
			(end -0.8636 0.4318)
			(stroke
				(width 0.1)
				(type default)
			)
			(layer "F.Fab")
		)
		(fp_line
			(start 0.8636 -0.4572)
			(end 0.8636 -0.406654)
			(stroke
				(width 0.1)
				(type default)
			)
			(layer "F.Fab")
		)
		(fp_line
			(start 0.8636 -0.406654)
			(end 1.1938 -0.406654)
			(stroke
				(width 0.1)
				(type default)
			)
			(layer "F.Fab")
		)
		(fp_line
			(start 0.8636 0.4064)
			(end 0.8636 0.4572)
			(stroke
				(width 0.1)
				(type default)
			)
			(layer "F.Fab")
		)
		(fp_line
			(start 0.8636 0.4572)
			(end -0.8636 0.4572)
			(stroke
				(width 0.1)
				(type default)
			)
			(layer "F.Fab")
		)
		(fp_line
			(start 1.1938 -0.406654)
			(end 1.1938 0.4064)
			(stroke
				(width 0.1)
				(type default)
			)
			(layer "F.Fab")
		)
		(fp_line
			(start 1.1938 0.4064)
			(end 0.8636 0.4064)
			(stroke
				(width 0.1)
				(type default)
			)
			(layer "F.Fab")
		)
		(pad "1" smd rect
			(at -0.7366 0 270)
			(size 0.7112 0.8128)
			(layers "F.Cu" "F.Mask" "F.Paste")
			(net "P12V_AUX")
		)
		(pad "2" smd rect
			(at 0.7366 0 270)
			(size 0.7112 0.8128)
			(layers "F.Cu" "F.Mask" "F.Paste")
			(net "P12V_OCP_AVIN_PD_1")
		)
	)
	(footprint ""
		(layer "F.Cu")
		(at 365.46663 -258.726686 90)
		(property "Reference" "C972"
			(at 0 0 90)
			(layer "F.SilkS")
			(hide yes)
			(effects
				(font
					(size 1.27 1.27)
				)
			)
		)
		(property "Value" ""
			(at 0 0 90)
			(layer "F.Fab")
			(effects
				(font
					(size 1.27 1.27)
				)
			)
		)
		(duplicate_pad_numbers_are_jumpers no)
		(fp_line
			(start 0.7874 -0.4064)
			(end 0.7874 0.4064)
			(stroke
				(width 0.1524)
				(type default)
			)
			(layer "F.SilkS")
		)
		(fp_line
			(start -0.7874 -0.4064)
			(end 0.7874 -0.4064)
			(stroke
				(width 0.1524)
				(type default)
			)
			(layer "F.SilkS")
		)
		(fp_line
			(start 0.7874 0.4064)
			(end -0.7874 0.4064)
			(stroke
				(width 0.1524)
				(type default)
			)
			(layer "F.SilkS")
		)
		(fp_line
			(start -0.7874 0.4064)
			(end -0.7874 -0.4064)
			(stroke
				(width 0.1524)
				(type default)
			)
			(layer "F.SilkS")
		)
		(fp_line
			(start -0.12065 -0.305054)
			(end -0.12065 -0.2794)
			(stroke
				(width 0.1)
				(type default)
			)
			(layer "F.Fab")
		)
		(fp_line
			(start -0.67945 -0.305054)
			(end -0.12065 -0.305054)
			(stroke
				(width 0.1)
				(type default)
			)
			(layer "F.Fab")
		)
		(fp_line
			(start 0.67945 -0.3048)
			(end 0.67945 0.3048)
			(stroke
				(width 0.1)
				(type default)
			)
			(layer "F.Fab")
		)
		(fp_line
			(start 0.12065 -0.3048)
			(end 0.67945 -0.3048)
			(stroke
				(width 0.1)
				(type default)
			)
			(layer "F.Fab")
		)
		(fp_line
			(start 0.12065 -0.2794)
			(end 0.12065 -0.3048)
			(stroke
				(width 0.1)
				(type default)
			)
			(layer "F.Fab")
		)
		(fp_line
			(start -0.12065 -0.2794)
			(end 0.12065 -0.2794)
			(stroke
				(width 0.1)
				(type default)
			)
			(layer "F.Fab")
		)
		(fp_line
			(start 0.120396 0.2794)
			(end -0.12065 0.2794)
			(stroke
				(width 0.1)
				(type default)
			)
			(layer "F.Fab")
		)
		(fp_line
			(start -0.12065 0.2794)
			(end -0.12065 0.3048)
			(stroke
				(width 0.1)
				(type default)
			)
			(layer "F.Fab")
		)
		(fp_line
			(start 0.67945 0.3048)
			(end 0.120396 0.3048)
			(stroke
				(width 0.1)
				(type default)
			)
			(layer "F.Fab")
		)
		(fp_line
			(start 0.120396 0.3048)
			(end 0.120396 0.2794)
			(stroke
				(width 0.1)
				(type default)
			)
			(layer "F.Fab")
		)
		(fp_line
			(start -0.12065 0.3048)
			(end -0.67945 0.3048)
			(stroke
				(width 0.1)
				(type default)
			)
			(layer "F.Fab")
		)
		(fp_line
			(start -0.67945 0.3048)
			(end -0.67945 -0.305054)
			(stroke
				(width 0.1)
				(type default)
			)
			(layer "F.Fab")
		)
		(pad "1" smd circle
			(at -0.40005 0 90)
			(size 0 0)
			(layers "F.Cu" "F.Mask" "F.Paste")
			(net "PVCCIN_CPU0")
		)
		(pad "2" smd circle
			(at 0.40005 0 90)
			(size 0 0)
			(layers "F.Cu" "F.Mask" "F.Paste")
			(net "GND")
		)
	)
	(footprint ""
		(layer "F.Cu")
		(at 66.333878 -402.371052 -90)
		(property "Reference" "C722"
			(at 0 0 270)
			(layer "F.SilkS")
			(hide yes)
			(effects
				(font
					(size 1.27 1.27)
				)
			)
		)
		(property "Value" ""
			(at 0 0 270)
			(layer "F.Fab")
			(effects
				(font
					(size 1.27 1.27)
				)
			)
		)
		(duplicate_pad_numbers_are_jumpers no)
		(fp_line
			(start -0.299974 0.150114)
			(end -0.299974 -0.150114)
			(stroke
				(width 0.1)
				(type default)
			)
			(layer "F.Fab")
		)
		(fp_line
			(start 0.299974 0.150114)
			(end -0.299974 0.150114)
			(stroke
				(width 0.1)
				(type default)
			)
			(layer "F.Fab")
		)
		(fp_line
			(start -0.299974 -0.150114)
			(end 0.299974 -0.150114)
			(stroke
				(width 0.1)
				(type default)
			)
			(layer "F.Fab")
		)
		(fp_line
			(start 0.299974 -0.150114)
			(end 0.299974 0.150114)
			(stroke
				(width 0.1)
				(type default)
			)
			(layer "F.Fab")
		)
		(pad "1" smd rect
			(at -0.2667 0 270)
			(size 0.3048 0.381)
			(layers "F.Cu" "F.Mask" "F.Paste")
			(net "P5E_CPU1_PE0_TX_C_DN<9>")
		)
		(pad "2" smd rect
			(at 0.2667 0 270)
			(size 0.3048 0.381)
			(layers "F.Cu" "F.Mask" "F.Paste")
			(net "P5E_CPU1_PE0_TX_DN<9>")
		)
	)
	(footprint ""
		(layer "F.Cu")
		(at 461.957928 -94.317566)
		(property "Reference" "C1840"
			(at 0 0 0)
			(layer "F.SilkS")
			(hide yes)
			(effects
				(font
					(size 1.27 1.27)
				)
			)
		)
		(property "Value" ""
			(at 0 0 0)
			(layer "F.Fab")
			(effects
				(font
					(size 1.27 1.27)
				)
			)
		)
		(duplicate_pad_numbers_are_jumpers no)
		(fp_line
			(start -0.7874 -0.4064)
			(end 0.7874 -0.4064)
			(stroke
				(width 0.1524)
				(type default)
			)
			(layer "F.SilkS")
		)
		(fp_line
			(start -0.7874 0.4064)
			(end -0.7874 -0.4064)
			(stroke
				(width 0.1524)
				(type default)
			)
			(layer "F.SilkS")
		)
		(fp_line
			(start 0.7874 -0.4064)
			(end 0.7874 0.4064)
			(stroke
				(width 0.1524)
				(type default)
			)
			(layer "F.SilkS")
		)
		(fp_line
			(start 0.7874 0.4064)
			(end -0.7874 0.4064)
			(stroke
				(width 0.1524)
				(type default)
			)
			(layer "F.SilkS")
		)
		(fp_line
			(start -0.67945 -0.305054)
			(end -0.12065 -0.305054)
			(stroke
				(width 0.1)
				(type default)
			)
			(layer "F.Fab")
		)
		(fp_line
			(start -0.67945 0.3048)
			(end -0.67945 -0.305054)
			(stroke
				(width 0.1)
				(type default)
			)
			(layer "F.Fab")
		)
		(fp_line
			(start -0.12065 -0.305054)
			(end -0.12065 -0.2794)
			(stroke
				(width 0.1)
				(type default)
			)
			(layer "F.Fab")
		)
		(fp_line
			(start -0.12065 -0.2794)
			(end 0.12065 -0.2794)
			(stroke
				(width 0.1)
				(type default)
			)
			(layer "F.Fab")
		)
		(fp_line
			(start -0.12065 0.2794)
			(end -0.12065 0.3048)
			(stroke
				(width 0.1)
				(type default)
			)
			(layer "F.Fab")
		)
		(fp_line
			(start -0.12065 0.3048)
			(end -0.67945 0.3048)
			(stroke
				(width 0.1)
				(type default)
			)
			(layer "F.Fab")
		)
		(fp_line
			(start 0.120396 0.2794)
			(end -0.12065 0.2794)
			(stroke
				(width 0.1)
				(type default)
			)
			(layer "F.Fab")
		)
		(fp_line
			(start 0.120396 0.3048)
			(end 0.120396 0.2794)
			(stroke
				(width 0.1)
				(type default)
			)
			(layer "F.Fab")
		)
		(fp_line
			(start 0.12065 -0.3048)
			(end 0.67945 -0.3048)
			(stroke
				(width 0.1)
				(type default)
			)
			(layer "F.Fab")
		)
		(fp_line
			(start 0.12065 -0.2794)
			(end 0.12065 -0.3048)
			(stroke
				(width 0.1)
				(type default)
			)
			(layer "F.Fab")
		)
		(fp_line
			(start 0.67945 -0.3048)
			(end 0.67945 0.3048)
			(stroke
				(width 0.1)
				(type default)
			)
			(layer "F.Fab")
		)
		(fp_line
			(start 0.67945 0.3048)
			(end 0.120396 0.3048)
			(stroke
				(width 0.1)
				(type default)
			)
			(layer "F.Fab")
		)
		(pad "1" smd circle
			(at -0.40005 0)
			(size 0 0)
			(layers "F.Cu" "F.Mask" "F.Paste")
			(net "P3V3_AUX")
		)
		(pad "2" smd circle
			(at 0.40005 0)
			(size 0 0)
			(layers "F.Cu" "F.Mask" "F.Paste")
			(net "GND")
		)
	)
	(footprint ""
		(layer "F.Cu")
		(at 241.308128 -110.240572 180)
		(property "Reference" "R1016"
			(at 0 0 180)
			(layer "F.SilkS")
			(hide yes)
			(effects
				(font
					(size 1.27 1.27)
				)
			)
		)
		(property "Value" ""
			(at 0 0 180)
			(layer "F.Fab")
			(effects
				(font
					(size 1.27 1.27)
				)
			)
		)
		(duplicate_pad_numbers_are_jumpers no)
		(fp_line
			(start 0.7874 0.4064)
			(end -0.7874 0.4064)
			(stroke
				(width 0.1524)
				(type default)
			)
			(layer "F.SilkS")
		)
		(fp_line
			(start 0.7874 -0.4064)
			(end 0.7874 0.4064)
			(stroke
				(width 0.1524)
				(type default)
			)
			(layer "F.SilkS")
		)
		(fp_line
			(start -0.7874 0.4064)
			(end -0.7874 -0.4064)
			(stroke
				(width 0.1524)
				(type default)
			)
			(layer "F.SilkS")
		)
		(fp_line
			(start -0.7874 -0.4064)
			(end 0.7874 -0.4064)
			(stroke
				(width 0.1524)
				(type default)
			)
			(layer "F.SilkS")
		)
		(fp_line
			(start 0.67945 0.3048)
			(end 0.120396 0.3048)
			(stroke
				(width 0.1)
				(type default)
			)
			(layer "F.Fab")
		)
		(fp_line
			(start 0.67945 -0.3048)
			(end 0.67945 0.3048)
			(stroke
				(width 0.1)
				(type default)
			)
			(layer "F.Fab")
		)
		(fp_line
			(start 0.12065 -0.2794)
			(end 0.12065 -0.3048)
			(stroke
				(width 0.1)
				(type default)
			)
			(layer "F.Fab")
		)
		(fp_line
			(start 0.12065 -0.3048)
			(end 0.67945 -0.3048)
			(stroke
				(width 0.1)
				(type default)
			)
			(layer "F.Fab")
		)
		(fp_line
			(start 0.120396 0.3048)
			(end 0.120396 0.2794)
			(stroke
				(width 0.1)
				(type default)
			)
			(layer "F.Fab")
		)
		(fp_line
			(start 0.120396 0.2794)
			(end -0.12065 0.2794)
			(stroke
				(width 0.1)
				(type default)
			)
			(layer "F.Fab")
		)
		(fp_line
			(start -0.12065 0.3048)
			(end -0.67945 0.3048)
			(stroke
				(width 0.1)
				(type default)
			)
			(layer "F.Fab")
		)
		(fp_line
			(start -0.12065 0.2794)
			(end -0.12065 0.3048)
			(stroke
				(width 0.1)
				(type default)
			)
			(layer "F.Fab")
		)
		(fp_line
			(start -0.12065 -0.2794)
			(end 0.12065 -0.2794)
			(stroke
				(width 0.1)
				(type default)
			)
			(layer "F.Fab")
		)
		(fp_line
			(start -0.12065 -0.305054)
			(end -0.12065 -0.2794)
			(stroke
				(width 0.1)
				(type default)
			)
			(layer "F.Fab")
		)
		(fp_line
			(start -0.67945 0.3048)
			(end -0.67945 -0.305054)
			(stroke
				(width 0.1)
				(type default)
			)
			(layer "F.Fab")
		)
		(fp_line
			(start -0.67945 -0.305054)
			(end -0.12065 -0.305054)
			(stroke
				(width 0.1)
				(type default)
			)
			(layer "F.Fab")
		)
		(pad "1" smd circle
			(at -0.40005 0 180)
			(size 0 0)
			(layers "F.Cu" "F.Mask" "F.Paste")
			(net "CLK_25M_CK440_CPU1_DP")
		)
		(pad "2" smd circle
			(at 0.40005 0 180)
			(size 0 0)
			(layers "F.Cu" "F.Mask" "F.Paste")
			(net "CLK_25M_CK440_CPU1_R_DP")
		)
	)
	(footprint ""
		(layer "F.Cu")
		(at 93.782896 -70.78599)
		(property "Reference" "D87"
			(at -47.431706 50.178462 90)
			(unlocked yes)
			(layer "F.SilkS")
			(effects
				(font
					(size 0.635 0.4064)
					(thickness 0.1524)
				)
				(justify left)
			)
		)
		(property "Value" ""
			(at 0 0 0)
			(layer "F.Fab")
			(effects
				(font
					(size 1.27 1.27)
				)
			)
		)
		(duplicate_pad_numbers_are_jumpers no)
		(fp_line
			(start -0.90678 0.4826)
			(end -0.90678 -0.4699)
			(stroke
				(width 0.1524)
				(type default)
			)
			(layer "F.SilkS")
		)
		(fp_line
			(start -0.89408 -0.4826)
			(end 0.90678 -0.4826)
			(stroke
				(width 0.1524)
				(type default)
			)
			(layer "F.SilkS")
		)
		(fp_line
			(start -0.79248 -0.4826)
			(end 1.03378 -0.4826)
			(stroke
				(width 0.1524)
				(type default)
			)
			(layer "F.SilkS")
		)
		(fp_line
			(start -0.64008 -0.4826)
			(end 1.16078 -0.4826)
			(stroke
				(width 0.1524)
				(type default)
			)
			(layer "F.SilkS")
		)
		(fp_line
			(start 0.90678 -0.4826)
			(end 0.90678 0.4826)
			(stroke
				(width 0.1524)
				(type default)
			)
			(layer "F.SilkS")
		)
		(fp_line
			(start 0.90678 0.4826)
			(end -0.90678 0.4826)
			(stroke
				(width 0.1524)
				(type default)
			)
			(layer "F.SilkS")
		)
		(fp_line
			(start 1.03378 -0.4826)
			(end 1.03378 0.4826)
			(stroke
				(width 0.1524)
				(type default)
			)
			(layer "F.SilkS")
		)
		(fp_line
			(start 1.03378 0.4826)
			(end -0.79248 0.4826)
			(stroke
				(width 0.1524)
				(type default)
			)
			(layer "F.SilkS")
		)
		(fp_line
			(start 1.16078 -0.4826)
			(end 1.16078 0.4826)
			(stroke
				(width 0.1524)
				(type default)
			)
			(layer "F.SilkS")
		)
		(fp_line
			(start 1.16078 0.4826)
			(end -0.64008 0.4826)
			(stroke
				(width 0.1524)
				(type default)
			)
			(layer "F.SilkS")
		)
		(fp_line
			(start -0.499872 -0.249936)
			(end 0.499872 -0.249936)
			(stroke
				(width 0.1)
				(type default)
			)
			(layer "F.Fab")
		)
		(fp_line
			(start -0.499872 0.249936)
			(end -0.499872 -0.249936)
			(stroke
				(width 0.1)
				(type default)
			)
			(layer "F.Fab")
		)
		(fp_line
			(start 0.499872 -0.249936)
			(end 0.499872 0.249936)
			(stroke
				(width 0.1)
				(type default)
			)
			(layer "F.Fab")
		)
		(fp_line
			(start 0.499872 0.249936)
			(end -0.499872 0.249936)
			(stroke
				(width 0.1)
				(type default)
			)
			(layer "F.Fab")
		)
		(pad "A" smd rect
			(at -0.47498 0)
			(size 0.6096 0.7112)
			(layers "F.Cu" "F.Mask" "F.Paste")
			(net "LED_PWRGD_PCH_PWROK_R")
		)
		(pad "C" smd rect
			(at 0.47498 0)
			(size 0.6096 0.7112)
			(layers "F.Cu" "F.Mask" "F.Paste")
			(net "LED_PWRGD_PCH_PWROK_R_D")
		)
	)
	(footprint ""
		(layer "F.Cu")
		(at 302.895 -419.10635 -90)
		(property "Reference" "R4120"
			(at 0 0 270)
			(layer "F.SilkS")
			(hide yes)
			(effects
				(font
					(size 1.27 1.27)
				)
			)
		)
		(property "Value" ""
			(at 0 0 270)
			(layer "F.Fab")
			(effects
				(font
					(size 1.27 1.27)
				)
			)
		)
		(duplicate_pad_numbers_are_jumpers no)
		(fp_line
			(start -0.7874 0.4064)
			(end -0.7874 -0.4064)
			(stroke
				(width 0.1524)
				(type default)
			)
			(layer "F.SilkS")
		)
		(fp_line
			(start 0.7874 0.4064)
			(end -0.7874 0.4064)
			(stroke
				(width 0.1524)
				(type default)
			)
			(layer "F.SilkS")
		)
		(fp_line
			(start -0.7874 -0.4064)
			(end 0.7874 -0.4064)
			(stroke
				(width 0.1524)
				(type default)
			)
			(layer "F.SilkS")
		)
		(fp_line
			(start 0.7874 -0.4064)
			(end 0.7874 0.4064)
			(stroke
				(width 0.1524)
				(type default)
			)
			(layer "F.SilkS")
		)
		(fp_line
			(start -0.67945 0.3048)
			(end -0.67945 -0.305054)
			(stroke
				(width 0.1)
				(type default)
			)
			(layer "F.Fab")
		)
		(fp_line
			(start -0.12065 0.3048)
			(end -0.67945 0.3048)
			(stroke
				(width 0.1)
				(type default)
			)
			(layer "F.Fab")
		)
		(fp_line
			(start 0.120396 0.3048)
			(end 0.120396 0.2794)
			(stroke
				(width 0.1)
				(type default)
			)
			(layer "F.Fab")
		)
		(fp_line
			(start 0.67945 0.3048)
			(end 0.120396 0.3048)
			(stroke
				(width 0.1)
				(type default)
			)
			(layer "F.Fab")
		)
		(fp_line
			(start -0.12065 0.2794)
			(end -0.12065 0.3048)
			(stroke
				(width 0.1)
				(type default)
			)
			(layer "F.Fab")
		)
		(fp_line
			(start 0.120396 0.2794)
			(end -0.12065 0.2794)
			(stroke
				(width 0.1)
				(type default)
			)
			(layer "F.Fab")
		)
		(fp_line
			(start -0.12065 -0.2794)
			(end 0.12065 -0.2794)
			(stroke
				(width 0.1)
				(type default)
			)
			(layer "F.Fab")
		)
		(fp_line
			(start 0.12065 -0.2794)
			(end 0.12065 -0.3048)
			(stroke
				(width 0.1)
				(type default)
			)
			(layer "F.Fab")
		)
		(fp_line
			(start 0.12065 -0.3048)
			(end 0.67945 -0.3048)
			(stroke
				(width 0.1)
				(type default)
			)
			(layer "F.Fab")
		)
		(fp_line
			(start 0.67945 -0.3048)
			(end 0.67945 0.3048)
			(stroke
				(width 0.1)
				(type default)
			)
			(layer "F.Fab")
		)
		(fp_line
			(start -0.67945 -0.305054)
			(end -0.12065 -0.305054)
			(stroke
				(width 0.1)
				(type default)
			)
			(layer "F.Fab")
		)
		(fp_line
			(start -0.12065 -0.305054)
			(end -0.12065 -0.2794)
			(stroke
				(width 0.1)
				(type default)
			)
			(layer "F.Fab")
		)
		(pad "1" smd circle
			(at -0.40005 0 270)
			(size 0 0)
			(layers "F.Cu" "F.Mask" "F.Paste")
			(net "GPU_3V3IO_RSVD0_FFU")
		)
		(pad "2" smd circle
			(at 0.40005 0 270)
			(size 0 0)
			(layers "F.Cu" "F.Mask" "F.Paste")
			(net "GND")
		)
	)
	(footprint ""
		(layer "F.Cu")
		(at 164.592 -23.713948)
		(property "Reference" "C1302"
			(at 0 0 0)
			(layer "F.SilkS")
			(hide yes)
			(effects
				(font
					(size 1.27 1.27)
				)
			)
		)
		(property "Value" ""
			(at 0 0 0)
			(layer "F.Fab")
			(effects
				(font
					(size 1.27 1.27)
				)
			)
		)
		(duplicate_pad_numbers_are_jumpers no)
		(fp_line
			(start -0.7874 -0.4064)
			(end 0.7874 -0.4064)
			(stroke
				(width 0.1524)
				(type default)
			)
			(layer "F.SilkS")
		)
		(fp_line
			(start -0.7874 0.4064)
			(end -0.7874 -0.4064)
			(stroke
				(width 0.1524)
				(type default)
			)
			(layer "F.SilkS")
		)
		(fp_line
			(start 0.7874 -0.4064)
			(end 0.7874 0.4064)
			(stroke
				(width 0.1524)
				(type default)
			)
			(layer "F.SilkS")
		)
		(fp_line
			(start 0.7874 0.4064)
			(end -0.7874 0.4064)
			(stroke
				(width 0.1524)
				(type default)
			)
			(layer "F.SilkS")
		)
		(fp_line
			(start -0.67945 -0.305054)
			(end -0.12065 -0.305054)
			(stroke
				(width 0.1)
				(type default)
			)
			(layer "F.Fab")
		)
		(fp_line
			(start -0.67945 0.3048)
			(end -0.67945 -0.305054)
			(stroke
				(width 0.1)
				(type default)
			)
			(layer "F.Fab")
		)
		(fp_line
			(start -0.12065 -0.305054)
			(end -0.12065 -0.2794)
			(stroke
				(width 0.1)
				(type default)
			)
			(layer "F.Fab")
		)
		(fp_line
			(start -0.12065 -0.2794)
			(end 0.12065 -0.2794)
			(stroke
				(width 0.1)
				(type default)
			)
			(layer "F.Fab")
		)
		(fp_line
			(start -0.12065 0.2794)
			(end -0.12065 0.3048)
			(stroke
				(width 0.1)
				(type default)
			)
			(layer "F.Fab")
		)
		(fp_line
			(start -0.12065 0.3048)
			(end -0.67945 0.3048)
			(stroke
				(width 0.1)
				(type default)
			)
			(layer "F.Fab")
		)
		(fp_line
			(start 0.120396 0.2794)
			(end -0.12065 0.2794)
			(stroke
				(width 0.1)
				(type default)
			)
			(layer "F.Fab")
		)
		(fp_line
			(start 0.120396 0.3048)
			(end 0.120396 0.2794)
			(stroke
				(width 0.1)
				(type default)
			)
			(layer "F.Fab")
		)
		(fp_line
			(start 0.12065 -0.3048)
			(end 0.67945 -0.3048)
			(stroke
				(width 0.1)
				(type default)
			)
			(layer "F.Fab")
		)
		(fp_line
			(start 0.12065 -0.2794)
			(end 0.12065 -0.3048)
			(stroke
				(width 0.1)
				(type default)
			)
			(layer "F.Fab")
		)
		(fp_line
			(start 0.67945 -0.3048)
			(end 0.67945 0.3048)
			(stroke
				(width 0.1)
				(type default)
			)
			(layer "F.Fab")
		)
		(fp_line
			(start 0.67945 0.3048)
			(end 0.120396 0.3048)
			(stroke
				(width 0.1)
				(type default)
			)
			(layer "F.Fab")
		)
		(pad "1" smd circle
			(at -0.40005 0)
			(size 0 0)
			(layers "F.Cu" "F.Mask" "F.Paste")
			(net "PVNN_TERM_CPU0")
		)
		(pad "2" smd circle
			(at 0.40005 0)
			(size 0 0)
			(layers "F.Cu" "F.Mask" "F.Paste")
			(net "GND")
		)
	)
	(footprint ""
		(layer "F.Cu")
		(at 272.08607 -97.063814)
		(property "Reference" "R113"
			(at 0 0 0)
			(layer "F.SilkS")
			(hide yes)
			(effects
				(font
					(size 1.27 1.27)
				)
			)
		)
		(property "Value" ""
			(at 0 0 0)
			(layer "F.Fab")
			(effects
				(font
					(size 1.27 1.27)
				)
			)
		)
		(duplicate_pad_numbers_are_jumpers no)
		(fp_line
			(start -0.7874 -0.4064)
			(end 0.7874 -0.4064)
			(stroke
				(width 0.1524)
				(type default)
			)
			(layer "F.SilkS")
		)
		(fp_line
			(start -0.7874 0.4064)
			(end -0.7874 -0.4064)
			(stroke
				(width 0.1524)
				(type default)
			)
			(layer "F.SilkS")
		)
		(fp_line
			(start 0.7874 -0.4064)
			(end 0.7874 0.4064)
			(stroke
				(width 0.1524)
				(type default)
			)
			(layer "F.SilkS")
		)
		(fp_line
			(start 0.7874 0.4064)
			(end -0.7874 0.4064)
			(stroke
				(width 0.1524)
				(type default)
			)
			(layer "F.SilkS")
		)
		(fp_line
			(start -0.67945 -0.305054)
			(end -0.12065 -0.305054)
			(stroke
				(width 0.1)
				(type default)
			)
			(layer "F.Fab")
		)
		(fp_line
			(start -0.67945 0.3048)
			(end -0.67945 -0.305054)
			(stroke
				(width 0.1)
				(type default)
			)
			(layer "F.Fab")
		)
		(fp_line
			(start -0.12065 -0.305054)
			(end -0.12065 -0.2794)
			(stroke
				(width 0.1)
				(type default)
			)
			(layer "F.Fab")
		)
		(fp_line
			(start -0.12065 -0.2794)
			(end 0.12065 -0.2794)
			(stroke
				(width 0.1)
				(type default)
			)
			(layer "F.Fab")
		)
		(fp_line
			(start -0.12065 0.2794)
			(end -0.12065 0.3048)
			(stroke
				(width 0.1)
				(type default)
			)
			(layer "F.Fab")
		)
		(fp_line
			(start -0.12065 0.3048)
			(end -0.67945 0.3048)
			(stroke
				(width 0.1)
				(type default)
			)
			(layer "F.Fab")
		)
		(fp_line
			(start 0.120396 0.2794)
			(end -0.12065 0.2794)
			(stroke
				(width 0.1)
				(type default)
			)
			(layer "F.Fab")
		)
		(fp_line
			(start 0.120396 0.3048)
			(end 0.120396 0.2794)
			(stroke
				(width 0.1)
				(type default)
			)
			(layer "F.Fab")
		)
		(fp_line
			(start 0.12065 -0.3048)
			(end 0.67945 -0.3048)
			(stroke
				(width 0.1)
				(type default)
			)
			(layer "F.Fab")
		)
		(fp_line
			(start 0.12065 -0.2794)
			(end 0.12065 -0.3048)
			(stroke
				(width 0.1)
				(type default)
			)
			(layer "F.Fab")
		)
		(fp_line
			(start 0.67945 -0.3048)
			(end 0.67945 0.3048)
			(stroke
				(width 0.1)
				(type default)
			)
			(layer "F.Fab")
		)
		(fp_line
			(start 0.67945 0.3048)
			(end 0.120396 0.3048)
			(stroke
				(width 0.1)
				(type default)
			)
			(layer "F.Fab")
		)
		(pad "1" smd circle
			(at -0.40005 0)
			(size 0 0)
			(layers "F.Cu" "F.Mask" "F.Paste")
			(net "FM_PLD_CLKS_OE_R_N")
		)
		(pad "2" smd circle
			(at 0.40005 0)
			(size 0 0)
			(layers "F.Cu" "F.Mask" "F.Paste")
			(net "FM_DB2000_OE_N")
		)
	)
	(footprint ""
		(layer "F.Cu")
		(at 39.827454 -106.015282 180)
		(property "Reference" "R3688"
			(at 0 0 180)
			(layer "F.SilkS")
			(hide yes)
			(effects
				(font
					(size 1.27 1.27)
				)
			)
		)
		(property "Value" ""
			(at 0 0 180)
			(layer "F.Fab")
			(effects
				(font
					(size 1.27 1.27)
				)
			)
		)
		(duplicate_pad_numbers_are_jumpers no)
		(fp_line
			(start 0.7874 0.4064)
			(end -0.7874 0.4064)
			(stroke
				(width 0.1524)
				(type default)
			)
			(layer "F.SilkS")
		)
		(fp_line
			(start 0.7874 -0.4064)
			(end 0.7874 0.4064)
			(stroke
				(width 0.1524)
				(type default)
			)
			(layer "F.SilkS")
		)
		(fp_line
			(start -0.7874 0.4064)
			(end -0.7874 -0.4064)
			(stroke
				(width 0.1524)
				(type default)
			)
			(layer "F.SilkS")
		)
		(fp_line
			(start -0.7874 -0.4064)
			(end 0.7874 -0.4064)
			(stroke
				(width 0.1524)
				(type default)
			)
			(layer "F.SilkS")
		)
		(fp_line
			(start 0.67945 0.3048)
			(end 0.120396 0.3048)
			(stroke
				(width 0.1)
				(type default)
			)
			(layer "F.Fab")
		)
		(fp_line
			(start 0.67945 -0.3048)
			(end 0.67945 0.3048)
			(stroke
				(width 0.1)
				(type default)
			)
			(layer "F.Fab")
		)
		(fp_line
			(start 0.12065 -0.2794)
			(end 0.12065 -0.3048)
			(stroke
				(width 0.1)
				(type default)
			)
			(layer "F.Fab")
		)
		(fp_line
			(start 0.12065 -0.3048)
			(end 0.67945 -0.3048)
			(stroke
				(width 0.1)
				(type default)
			)
			(layer "F.Fab")
		)
		(fp_line
			(start 0.120396 0.3048)
			(end 0.120396 0.2794)
			(stroke
				(width 0.1)
				(type default)
			)
			(layer "F.Fab")
		)
		(fp_line
			(start 0.120396 0.2794)
			(end -0.12065 0.2794)
			(stroke
				(width 0.1)
				(type default)
			)
			(layer "F.Fab")
		)
		(fp_line
			(start -0.12065 0.3048)
			(end -0.67945 0.3048)
			(stroke
				(width 0.1)
				(type default)
			)
			(layer "F.Fab")
		)
		(fp_line
			(start -0.12065 0.2794)
			(end -0.12065 0.3048)
			(stroke
				(width 0.1)
				(type default)
			)
			(layer "F.Fab")
		)
		(fp_line
			(start -0.12065 -0.2794)
			(end 0.12065 -0.2794)
			(stroke
				(width 0.1)
				(type default)
			)
			(layer "F.Fab")
		)
		(fp_line
			(start -0.12065 -0.305054)
			(end -0.12065 -0.2794)
			(stroke
				(width 0.1)
				(type default)
			)
			(layer "F.Fab")
		)
		(fp_line
			(start -0.67945 0.3048)
			(end -0.67945 -0.305054)
			(stroke
				(width 0.1)
				(type default)
			)
			(layer "F.Fab")
		)
		(fp_line
			(start -0.67945 -0.305054)
			(end -0.12065 -0.305054)
			(stroke
				(width 0.1)
				(type default)
			)
			(layer "F.Fab")
		)
		(pad "1" smd rect
			(at -0.40005 0)
			(size 0.4572 0.508)
			(layers "F.Cu" "F.Mask" "F.Paste")
			(net "P1V581_PDB_ADC")
		)
		(pad "2" smd rect
			(at 0.40005 0)
			(size 0.4572 0.508)
			(layers "F.Cu" "F.Mask" "F.Paste")
			(net "P3V3_PDB_AUX_ADC_TIC")
		)
	)
	(footprint ""
		(layer "F.Cu")
		(at 257.85953 -57.511442 180)
		(property "Reference" "R3974"
			(at 0 0 180)
			(layer "F.SilkS")
			(hide yes)
			(effects
				(font
					(size 1.27 1.27)
				)
			)
		)
		(property "Value" ""
			(at 0 0 180)
			(layer "F.Fab")
			(effects
				(font
					(size 1.27 1.27)
				)
			)
		)
		(duplicate_pad_numbers_are_jumpers no)
		(fp_line
			(start 0.7874 0.4064)
			(end -0.7874 0.4064)
			(stroke
				(width 0.1524)
				(type default)
			)
			(layer "F.SilkS")
		)
		(fp_line
			(start 0.7874 -0.4064)
			(end 0.7874 0.4064)
			(stroke
				(width 0.1524)
				(type default)
			)
			(layer "F.SilkS")
		)
		(fp_line
			(start -0.7874 0.4064)
			(end -0.7874 -0.4064)
			(stroke
				(width 0.1524)
				(type default)
			)
			(layer "F.SilkS")
		)
		(fp_line
			(start -0.7874 -0.4064)
			(end 0.7874 -0.4064)
			(stroke
				(width 0.1524)
				(type default)
			)
			(layer "F.SilkS")
		)
		(fp_line
			(start 0.67945 0.3048)
			(end 0.120396 0.3048)
			(stroke
				(width 0.1)
				(type default)
			)
			(layer "F.Fab")
		)
		(fp_line
			(start 0.67945 -0.3048)
			(end 0.67945 0.3048)
			(stroke
				(width 0.1)
				(type default)
			)
			(layer "F.Fab")
		)
		(fp_line
			(start 0.12065 -0.2794)
			(end 0.12065 -0.3048)
			(stroke
				(width 0.1)
				(type default)
			)
			(layer "F.Fab")
		)
		(fp_line
			(start 0.12065 -0.3048)
			(end 0.67945 -0.3048)
			(stroke
				(width 0.1)
				(type default)
			)
			(layer "F.Fab")
		)
		(fp_line
			(start 0.120396 0.3048)
			(end 0.120396 0.2794)
			(stroke
				(width 0.1)
				(type default)
			)
			(layer "F.Fab")
		)
		(fp_line
			(start 0.120396 0.2794)
			(end -0.12065 0.2794)
			(stroke
				(width 0.1)
				(type default)
			)
			(layer "F.Fab")
		)
		(fp_line
			(start -0.12065 0.3048)
			(end -0.67945 0.3048)
			(stroke
				(width 0.1)
				(type default)
			)
			(layer "F.Fab")
		)
		(fp_line
			(start -0.12065 0.2794)
			(end -0.12065 0.3048)
			(stroke
				(width 0.1)
				(type default)
			)
			(layer "F.Fab")
		)
		(fp_line
			(start -0.12065 -0.2794)
			(end 0.12065 -0.2794)
			(stroke
				(width 0.1)
				(type default)
			)
			(layer "F.Fab")
		)
		(fp_line
			(start -0.12065 -0.305054)
			(end -0.12065 -0.2794)
			(stroke
				(width 0.1)
				(type default)
			)
			(layer "F.Fab")
		)
		(fp_line
			(start -0.67945 0.3048)
			(end -0.67945 -0.305054)
			(stroke
				(width 0.1)
				(type default)
			)
			(layer "F.Fab")
		)
		(fp_line
			(start -0.67945 -0.305054)
			(end -0.12065 -0.305054)
			(stroke
				(width 0.1)
				(type default)
			)
			(layer "F.Fab")
		)
		(pad "1" smd rect
			(at -0.40005 0)
			(size 0.4572 0.508)
			(layers "F.Cu" "F.Mask" "F.Paste")
			(net "P12V_E1S_SENSE_0")
		)
		(pad "2" smd rect
			(at 0.40005 0)
			(size 0.4572 0.508)
			(layers "F.Cu" "F.Mask" "F.Paste")
			(net "P12V_E1S_0_ISENSE_MAM_MAM")
		)
	)
	(footprint ""
		(layer "F.Cu")
		(at 331.650086 -440.489848)
		(property "Reference" "J107"
			(at 3.42392 23.088092 0)
			(unlocked yes)
			(layer "F.SilkS")
			(effects
				(font
					(size 0.7874 0.5842)
					(thickness 0.1524)
				)
				(justify left)
			)
		)
		(property "Value" ""
			(at 0 0 0)
			(layer "F.Fab")
			(effects
				(font
					(size 1.27 1.27)
				)
			)
		)
		(duplicate_pad_numbers_are_jumpers no)
		(fp_line
			(start -4.249928 -11.999976)
			(end 18.64995 -11.999976)
			(stroke
				(width 0.1524)
				(type default)
			)
			(layer "F.SilkS")
		)
		(fp_line
			(start -4.249928 22.400006)
			(end -4.249928 -11.999976)
			(stroke
				(width 0.1524)
				(type default)
			)
			(layer "F.SilkS")
		)
		(fp_line
			(start -1.249934 -8.999982)
			(end -1.249934 19.400012)
			(stroke
				(width 0.1524)
				(type default)
			)
			(layer "F.SilkS")
		)
		(fp_line
			(start -1.249934 -1.500124)
			(end 15.649956 -1.500124)
			(stroke
				(width 0.1524)
				(type default)
			)
			(layer "F.SilkS")
		)
		(fp_line
			(start -1.249934 19.400012)
			(end 15.649956 19.400012)
			(stroke
				(width 0.1524)
				(type default)
			)
			(layer "F.SilkS")
		)
		(fp_line
			(start 0.0254 -0.9144)
			(end 1.0414 -0.9144)
			(stroke
				(width 0.1524)
				(type default)
			)
			(layer "F.SilkS")
		)
		(fp_line
			(start 0.5334 -1.4224)
			(end 0.0254 -0.9144)
			(stroke
				(width 0.1524)
				(type default)
			)
			(layer "F.SilkS")
		)
		(fp_line
			(start 0.5334 -1.4224)
			(end 0.5334 -0.5588)
			(stroke
				(width 0.1524)
				(type default)
			)
			(layer "F.SilkS")
		)
		(fp_line
			(start 0.5334 -0.5588)
			(end 1.8034 -0.5588)
			(stroke
				(width 0.1524)
				(type default)
			)
			(layer "F.SilkS")
		)
		(fp_line
			(start 1.0414 -0.9144)
			(end 0.5334 -1.4224)
			(stroke
				(width 0.1524)
				(type default)
			)
			(layer "F.SilkS")
		)
		(fp_line
			(start 1.8034 -0.5588)
			(end 2.032 -0.7874)
			(stroke
				(width 0.1524)
				(type default)
			)
			(layer "F.SilkS")
		)
		(fp_line
			(start 15.649956 -8.999982)
			(end -1.249934 -8.999982)
			(stroke
				(width 0.1524)
				(type default)
			)
			(layer "F.SilkS")
		)
		(fp_line
			(start 15.649956 19.400012)
			(end 15.649956 -8.999982)
			(stroke
				(width 0.1524)
				(type default)
			)
			(layer "F.SilkS")
		)
		(fp_line
			(start 18.64995 -11.999976)
			(end 18.64995 22.400006)
			(stroke
				(width 0.1524)
				(type default)
			)
			(layer "F.SilkS")
		)
		(fp_line
			(start 18.64995 22.400006)
			(end -4.249928 22.400006)
			(stroke
				(width 0.1524)
				(type default)
			)
			(layer "F.SilkS")
		)
		(fp_poly
			(pts
				(xy -2.484628 -0.43434) (xy -1.468628 0.07366) (xy -2.484628 0.58166)
			)
			(stroke
				(width 0)
				(type default)
			)
			(fill yes)
			(layer "F.SilkS")
		)
		(fp_line
			(start -4.249928 -11.999976)
			(end 18.64995 -11.999976)
			(stroke
				(width 0.1524)
				(type default)
			)
			(layer "B.SilkS")
		)
		(fp_line
			(start -4.249928 22.400006)
			(end -4.249928 -11.999976)
			(stroke
				(width 0.1524)
				(type default)
			)
			(layer "B.SilkS")
		)
		(fp_line
			(start 18.64995 -11.999976)
			(end 18.64995 22.400006)
			(stroke
				(width 0.1524)
				(type default)
			)
			(layer "B.SilkS")
		)
		(fp_line
			(start 18.64995 22.400006)
			(end -4.249928 22.400006)
			(stroke
				(width 0.1524)
				(type default)
			)
			(layer "B.SilkS")
		)
		(fp_line
			(start -4.249928 -11.999976)
			(end 18.64995 -11.999976)
			(stroke
				(width 0.1)
				(type default)
			)
			(layer "B.Fab")
		)
		(fp_line
			(start -4.249928 22.400006)
			(end -4.249928 -11.999976)
			(stroke
				(width 0.1)
				(type default)
			)
			(layer "B.Fab")
		)
		(fp_line
			(start 18.64995 -11.999976)
			(end 18.64995 22.400006)
			(stroke
				(width 0.1)
				(type default)
			)
			(layer "B.Fab")
		)
		(fp_line
			(start 18.64995 22.400006)
			(end -4.249928 22.400006)
			(stroke
				(width 0.1)
				(type default)
			)
			(layer "B.Fab")
		)
		(fp_line
			(start -1.249934 -8.999982)
			(end -1.249934 19.400012)
			(stroke
				(width 0.1)
				(type default)
			)
			(layer "F.Fab")
		)
		(fp_line
			(start -1.249934 19.400012)
			(end 15.649956 19.400012)
			(stroke
				(width 0.1)
				(type default)
			)
			(layer "F.Fab")
		)
		(fp_line
			(start 15.649956 -8.999982)
			(end -1.249934 -8.999982)
			(stroke
				(width 0.1)
				(type default)
			)
			(layer "F.Fab")
		)
		(fp_line
			(start 15.649956 19.400012)
			(end 15.649956 -8.999982)
			(stroke
				(width 0.1)
				(type default)
			)
			(layer "F.Fab")
		)
		(fp_poly
			(pts
				(xy -2.670048 -0.508) (xy -2.670048 0.508) (xy -1.654048 0)
			)
			(stroke
				(width 0)
				(type default)
			)
			(fill yes)
			(layer "F.Fab")
		)
		(fp_text user "B"
			(at -1.853692 1.373886 0)
			(unlocked yes)
			(layer "F.SilkS")
			(effects
				(font
					(size 0.7874 0.5842)
					(thickness 0.1524)
				)
			)
		)
		(fp_text user "C"
			(at -1.853692 2.574036 0)
			(unlocked yes)
			(layer "F.SilkS")
			(effects
				(font
					(size 0.7874 0.5842)
					(thickness 0.1524)
				)
			)
		)
		(fp_text user "D"
			(at -1.853692 3.773932 0)
			(unlocked yes)
			(layer "F.SilkS")
			(effects
				(font
					(size 0.7874 0.5842)
					(thickness 0.1524)
				)
			)
		)
		(fp_text user "E"
			(at -1.853692 4.974082 0)
			(unlocked yes)
			(layer "F.SilkS")
			(effects
				(font
					(size 0.7874 0.5842)
					(thickness 0.1524)
				)
			)
		)
		(fp_text user "F"
			(at -1.853692 6.173978 0)
			(unlocked yes)
			(layer "F.SilkS")
			(effects
				(font
					(size 0.7874 0.5842)
					(thickness 0.1524)
				)
			)
		)
		(fp_text user "G"
			(at -1.853692 7.373874 0)
			(unlocked yes)
			(layer "F.SilkS")
			(effects
				(font
					(size 0.7874 0.5842)
					(thickness 0.1524)
				)
			)
		)
		(fp_text user "H"
			(at -1.853692 8.574024 0)
			(unlocked yes)
			(layer "F.SilkS")
			(effects
				(font
					(size 0.7874 0.5842)
					(thickness 0.1524)
				)
			)
		)
		(fp_text user "I"
			(at -1.853692 9.77392 0)
			(unlocked yes)
			(layer "F.SilkS")
			(effects
				(font
					(size 0.7874 0.5842)
					(thickness 0.1524)
				)
			)
		)
		(fp_text user "J"
			(at -1.853692 10.97407 0)
			(unlocked yes)
			(layer "F.SilkS")
			(effects
				(font
					(size 0.7874 0.5842)
					(thickness 0.1524)
				)
			)
		)
		(fp_text user "K"
			(at -1.853692 12.173966 0)
			(unlocked yes)
			(layer "F.SilkS")
			(effects
				(font
					(size 0.7874 0.5842)
					(thickness 0.1524)
				)
			)
		)
		(fp_text user "L"
			(at -1.853692 13.374116 0)
			(unlocked yes)
			(layer "F.SilkS")
			(effects
				(font
					(size 0.7874 0.5842)
					(thickness 0.1524)
				)
			)
		)
		(fp_text user "M"
			(at -1.853692 14.574012 0)
			(unlocked yes)
			(layer "F.SilkS")
			(effects
				(font
					(size 0.7874 0.5842)
					(thickness 0.1524)
				)
			)
		)
		(fp_text user "N"
			(at -1.853692 15.773908 0)
			(unlocked yes)
			(layer "F.SilkS")
			(effects
				(font
					(size 0.7874 0.5842)
					(thickness 0.1524)
				)
			)
		)
		(fp_text user "1"
			(at 0.132842 20.09013 0)
			(unlocked yes)
			(layer "F.SilkS")
			(effects
				(font
					(size 0.7874 0.5842)
					(thickness 0.1524)
				)
			)
		)
		(fp_text user "2"
			(at 2.132838 20.09013 0)
			(unlocked yes)
			(layer "F.SilkS")
			(effects
				(font
					(size 0.7874 0.5842)
					(thickness 0.1524)
				)
			)
		)
		(fp_text user "EDGE OF DAUGHTER CARD"
			(at 2.2479 -0.899668 0)
			(unlocked yes)
			(layer "F.SilkS")
			(effects
				(font
					(size 0.635 0.4064)
					(thickness 0.1524)
				)
				(justify left)
			)
		)
		(fp_text user "3"
			(at 4.132834 20.09013 0)
			(unlocked yes)
			(layer "F.SilkS")
			(effects
				(font
					(size 0.7874 0.5842)
					(thickness 0.1524)
				)
			)
		)
		(fp_text user "4"
			(at 6.13283 20.09013 0)
			(unlocked yes)
			(layer "F.SilkS")
			(effects
				(font
					(size 0.7874 0.5842)
					(thickness 0.1524)
				)
			)
		)
		(fp_text user "5"
			(at 8.132826 20.09013 0)
			(unlocked yes)
			(layer "F.SilkS")
			(effects
				(font
					(size 0.7874 0.5842)
					(thickness 0.1524)
				)
			)
		)
		(fp_text user "6"
			(at 10.132822 20.09013 0)
			(unlocked yes)
			(layer "F.SilkS")
			(effects
				(font
					(size 0.7874 0.5842)
					(thickness 0.1524)
				)
			)
		)
		(fp_text user "7"
			(at 12.132818 20.09013 0)
			(unlocked yes)
			(layer "F.SilkS")
			(effects
				(font
					(size 0.7874 0.5842)
					(thickness 0.1524)
				)
			)
		)
		(fp_text user "8"
			(at 14.132814 20.09013 0)
			(unlocked yes)
			(layer "F.SilkS")
			(effects
				(font
					(size 0.7874 0.5842)
					(thickness 0.1524)
				)
			)
		)
		(fp_text user "PRESS-FIT"
			(at 17.240758 16.521684 90)
			(unlocked yes)
			(layer "F.SilkS")
			(effects
				(font
					(size 1.905 1.4224)
					(thickness 0.1524)
				)
				(justify left)
			)
		)
		(fp_text user "A"
			(at -1.225804 0.06477 0)
			(unlocked yes)
			(layer "B.SilkS")
			(effects
				(font
					(size 0.7874 0.5842)
					(thickness 0.1524)
				)
				(justify mirror)
			)
		)
		(fp_text user "G"
			(at -1.200404 7.48157 0)
			(unlocked yes)
			(layer "B.SilkS")
			(effects
				(font
					(size 0.7874 0.5842)
					(thickness 0.1524)
				)
				(justify mirror)
			)
		)
		(fp_text user "H"
			(at -1.175004 8.70077 0)
			(unlocked yes)
			(layer "B.SilkS")
			(effects
				(font
					(size 0.7874 0.5842)
					(thickness 0.1524)
				)
				(justify mirror)
			)
		)
		(fp_text user "B"
			(at -1.17348 1.391666 0)
			(unlocked yes)
			(layer "B.SilkS")
			(effects
				(font
					(size 0.7874 0.5842)
					(thickness 0.1524)
				)
				(justify mirror)
			)
		)
		(fp_text user "C"
			(at -1.17348 2.591816 0)
			(unlocked yes)
			(layer "B.SilkS")
			(effects
				(font
					(size 0.7874 0.5842)
					(thickness 0.1524)
				)
				(justify mirror)
			)
		)
		(fp_text user "D"
			(at -1.17348 3.791712 0)
			(unlocked yes)
			(layer "B.SilkS")
			(effects
				(font
					(size 0.7874 0.5842)
					(thickness 0.1524)
				)
				(justify mirror)
			)
		)
		(fp_text user "E"
			(at -1.17348 4.991862 0)
			(unlocked yes)
			(layer "B.SilkS")
			(effects
				(font
					(size 0.7874 0.5842)
					(thickness 0.1524)
				)
				(justify mirror)
			)
		)
		(fp_text user "F"
			(at -1.17348 6.191758 0)
			(unlocked yes)
			(layer "B.SilkS")
			(effects
				(font
					(size 0.7874 0.5842)
					(thickness 0.1524)
				)
				(justify mirror)
			)
		)
		(fp_text user "I"
			(at -1.17348 9.7917 0)
			(unlocked yes)
			(layer "B.SilkS")
			(effects
				(font
					(size 0.7874 0.5842)
					(thickness 0.1524)
				)
				(justify mirror)
			)
		)
		(fp_text user "J"
			(at -1.17348 10.99185 0)
			(unlocked yes)
			(layer "B.SilkS")
			(effects
				(font
					(size 0.7874 0.5842)
					(thickness 0.1524)
				)
				(justify mirror)
			)
		)
		(fp_text user "K"
			(at -1.17348 12.191746 0)
			(unlocked yes)
			(layer "B.SilkS")
			(effects
				(font
					(size 0.7874 0.5842)
					(thickness 0.1524)
				)
				(justify mirror)
			)
		)
		(fp_text user "L"
			(at -1.17348 13.391896 0)
			(unlocked yes)
			(layer "B.SilkS")
			(effects
				(font
					(size 0.7874 0.5842)
					(thickness 0.1524)
				)
				(justify mirror)
			)
		)
		(fp_text user "M"
			(at -1.17348 14.591792 0)
			(unlocked yes)
			(layer "B.SilkS")
			(effects
				(font
					(size 0.7874 0.5842)
					(thickness 0.1524)
				)
				(justify mirror)
			)
		)
		(fp_text user "N"
			(at -1.17348 15.791688 0)
			(unlocked yes)
			(layer "B.SilkS")
			(effects
				(font
					(size 0.7874 0.5842)
					(thickness 0.1524)
				)
				(justify mirror)
			)
		)
		(fp_text user "1"
			(at 0.376682 17.02181 0)
			(unlocked yes)
			(layer "B.SilkS")
			(effects
				(font
					(size 0.7874 0.5842)
					(thickness 0.1524)
				)
				(justify mirror)
			)
		)
		(fp_text user "2"
			(at 2.376678 17.02181 0)
			(unlocked yes)
			(layer "B.SilkS")
			(effects
				(font
					(size 0.7874 0.5842)
					(thickness 0.1524)
				)
				(justify mirror)
			)
		)
		(fp_text user "3"
			(at 4.376674 17.02181 0)
			(unlocked yes)
			(layer "B.SilkS")
			(effects
				(font
					(size 0.7874 0.5842)
					(thickness 0.1524)
				)
				(justify mirror)
			)
		)
		(fp_text user "4"
			(at 6.37667 17.02181 0)
			(unlocked yes)
			(layer "B.SilkS")
			(effects
				(font
					(size 0.7874 0.5842)
					(thickness 0.1524)
				)
				(justify mirror)
			)
		)
		(fp_text user "5"
			(at 8.376666 17.02181 0)
			(unlocked yes)
			(layer "B.SilkS")
			(effects
				(font
					(size 0.7874 0.5842)
					(thickness 0.1524)
				)
				(justify mirror)
			)
		)
		(fp_text user "6"
			(at 10.376662 17.02181 0)
			(unlocked yes)
			(layer "B.SilkS")
			(effects
				(font
					(size 0.7874 0.5842)
					(thickness 0.1524)
				)
				(justify mirror)
			)
		)
		(fp_text user "7"
			(at 12.376658 17.02181 0)
			(unlocked yes)
			(layer "B.SilkS")
			(effects
				(font
					(size 0.7874 0.5842)
					(thickness 0.1524)
				)
				(justify mirror)
			)
		)
		(fp_text user "PRESS-FIT"
			(at 14.206474 21.383498 0)
			(unlocked yes)
			(layer "B.SilkS")
			(effects
				(font
					(size 1.905 1.4224)
					(thickness 0.1524)
				)
				(justify left mirror)
			)
		)
		(fp_text user "8"
			(at 14.376654 17.02181 0)
			(unlocked yes)
			(layer "B.SilkS")
			(effects
				(font
					(size 0.7874 0.5842)
					(thickness 0.1524)
				)
				(justify mirror)
			)
		)
		(fp_text user "A"
			(at -1.199134 0 90)
			(unlocked yes)
			(layer "B.Fab")
			(effects
				(font
					(size 0.7874 0.5842)
					(thickness 0.1524)
				)
				(justify mirror)
			)
		)
		(fp_text user "G"
			(at -1.173734 7.4168 90)
			(unlocked yes)
			(layer "B.Fab")
			(effects
				(font
					(size 0.7874 0.5842)
					(thickness 0.1524)
				)
				(justify mirror)
			)
		)
		(fp_text user "H"
			(at -1.148334 8.636 90)
			(unlocked yes)
			(layer "B.Fab")
			(effects
				(font
					(size 0.7874 0.5842)
					(thickness 0.1524)
				)
				(justify mirror)
			)
		)
		(fp_text user "B"
			(at -1.14681 1.326896 90)
			(unlocked yes)
			(layer "B.Fab")
			(effects
				(font
					(size 0.7874 0.5842)
					(thickness 0.1524)
				)
				(justify mirror)
			)
		)
		(fp_text user "C"
			(at -1.14681 2.527046 90)
			(unlocked yes)
			(layer "B.Fab")
			(effects
				(font
					(size 0.7874 0.5842)
					(thickness 0.1524)
				)
				(justify mirror)
			)
		)
		(fp_text user "D"
			(at -1.14681 3.726942 90)
			(unlocked yes)
			(layer "B.Fab")
			(effects
				(font
					(size 0.7874 0.5842)
					(thickness 0.1524)
				)
				(justify mirror)
			)
		)
		(fp_text user "E"
			(at -1.14681 4.927092 90)
			(unlocked yes)
			(layer "B.Fab")
			(effects
				(font
					(size 0.7874 0.5842)
					(thickness 0.1524)
				)
				(justify mirror)
			)
		)
		(fp_text user "F"
			(at -1.14681 6.126988 90)
			(unlocked yes)
			(layer "B.Fab")
			(effects
				(font
					(size 0.7874 0.5842)
					(thickness 0.1524)
				)
				(justify mirror)
			)
		)
		(fp_text user "I"
			(at -1.14681 9.72693 90)
			(unlocked yes)
			(layer "B.Fab")
			(effects
				(font
					(size 0.7874 0.5842)
					(thickness 0.1524)
				)
				(justify mirror)
			)
		)
		(fp_text user "J"
			(at -1.14681 10.92708 90)
			(unlocked yes)
			(layer "B.Fab")
			(effects
				(font
					(size 0.7874 0.5842)
					(thickness 0.1524)
				)
				(justify mirror)
			)
		)
		(fp_text user "K"
			(at -1.14681 12.126976 90)
			(unlocked yes)
			(layer "B.Fab")
			(effects
				(font
					(size 0.7874 0.5842)
					(thickness 0.1524)
				)
				(justify mirror)
			)
		)
		(fp_text user "L"
			(at -1.14681 13.327126 90)
			(unlocked yes)
			(layer "B.Fab")
			(effects
				(font
					(size 0.7874 0.5842)
					(thickness 0.1524)
				)
				(justify mirror)
			)
		)
		(fp_text user "M"
			(at -1.14681 14.527022 90)
			(unlocked yes)
			(layer "B.Fab")
			(effects
				(font
					(size 0.7874 0.5842)
					(thickness 0.1524)
				)
				(justify mirror)
			)
		)
		(fp_text user "N"
			(at -1.14681 15.726918 90)
			(unlocked yes)
			(layer "B.Fab")
			(effects
				(font
					(size 0.7874 0.5842)
					(thickness 0.1524)
				)
				(justify mirror)
			)
		)
		(fp_text user "1"
			(at 0.060452 16.764 90)
			(unlocked yes)
			(layer "B.Fab")
			(effects
				(font
					(size 0.7874 0.5842)
					(thickness 0.1524)
				)
				(justify mirror)
			)
		)
		(fp_text user "2"
			(at 2.060448 16.764 90)
			(unlocked yes)
			(layer "B.Fab")
			(effects
				(font
					(size 0.7874 0.5842)
					(thickness 0.1524)
				)
				(justify mirror)
			)
		)
		(fp_text user "3"
			(at 4.060444 16.764 90)
			(unlocked yes)
			(layer "B.Fab")
			(effects
				(font
					(size 0.7874 0.5842)
					(thickness 0.1524)
				)
				(justify mirror)
			)
		)
		(fp_text user "4"
			(at 6.06044 16.764 90)
			(unlocked yes)
			(layer "B.Fab")
			(effects
				(font
					(size 0.7874 0.5842)
					(thickness 0.1524)
				)
				(justify mirror)
			)
		)
		(fp_text user "5"
			(at 8.060436 16.764 90)
			(unlocked yes)
			(layer "B.Fab")
			(effects
				(font
					(size 0.7874 0.5842)
					(thickness 0.1524)
				)
				(justify mirror)
			)
		)
		(fp_text user "6"
			(at 10.060432 16.764 90)
			(unlocked yes)
			(layer "B.Fab")
			(effects
				(font
					(size 0.7874 0.5842)
					(thickness 0.1524)
				)
				(justify mirror)
			)
		)
		(fp_text user "7"
			(at 12.060428 16.764 90)
			(unlocked yes)
			(layer "B.Fab")
			(effects
				(font
					(size 0.7874 0.5842)
					(thickness 0.1524)
				)
				(justify mirror)
			)
		)
		(fp_text user "8"
			(at 14.060424 16.764 90)
			(unlocked yes)
			(layer "B.Fab")
			(effects
				(font
					(size 0.7874 0.5842)
					(thickness 0.1524)
				)
				(justify mirror)
			)
		)
		(fp_text user "PRESS-FIT"
			(at 17.23771 -0.0762 90)
			(unlocked yes)
			(layer "B.Fab")
			(effects
				(font
					(size 1.905 1.4224)
					(thickness 0.1524)
				)
				(justify left mirror)
			)
		)
		(fp_text user "B"
			(at -2.253742 1.199896 90)
			(unlocked yes)
			(layer "F.Fab")
			(effects
				(font
					(size 0.7874 0.5842)
					(thickness 0.1524)
				)
			)
		)
		(fp_text user "C"
			(at -2.253742 2.400046 90)
			(unlocked yes)
			(layer "F.Fab")
			(effects
				(font
					(size 0.7874 0.5842)
					(thickness 0.1524)
				)
			)
		)
		(fp_text user "D"
			(at -2.253742 3.599942 90)
			(unlocked yes)
			(layer "F.Fab")
			(effects
				(font
					(size 0.7874 0.5842)
					(thickness 0.1524)
				)
			)
		)
		(fp_text user "E"
			(at -2.253742 4.800092 90)
			(unlocked yes)
			(layer "F.Fab")
			(effects
				(font
					(size 0.7874 0.5842)
					(thickness 0.1524)
				)
			)
		)
		(fp_text user "F"
			(at -2.253742 5.999988 90)
			(unlocked yes)
			(layer "F.Fab")
			(effects
				(font
					(size 0.7874 0.5842)
					(thickness 0.1524)
				)
			)
		)
		(fp_text user "G"
			(at -2.253742 7.199884 90)
			(unlocked yes)
			(layer "F.Fab")
			(effects
				(font
					(size 0.7874 0.5842)
					(thickness 0.1524)
				)
			)
		)
		(fp_text user "H"
			(at -2.253742 8.400034 90)
			(unlocked yes)
			(layer "F.Fab")
			(effects
				(font
					(size 0.7874 0.5842)
					(thickness 0.1524)
				)
			)
		)
		(fp_text user "I"
			(at -2.253742 9.59993 90)
			(unlocked yes)
			(layer "F.Fab")
			(effects
				(font
					(size 0.7874 0.5842)
					(thickness 0.1524)
				)
			)
		)
		(fp_text user "J"
			(at -2.253742 10.80008 90)
			(unlocked yes)
			(layer "F.Fab")
			(effects
				(font
					(size 0.7874 0.5842)
					(thickness 0.1524)
				)
			)
		)
		(fp_text user "K"
			(at -2.253742 11.999976 90)
			(unlocked yes)
			(layer "F.Fab")
			(effects
				(font
					(size 0.7874 0.5842)
					(thickness 0.1524)
				)
			)
		)
		(fp_text user "L"
			(at -2.253742 13.200126 90)
			(unlocked yes)
			(layer "F.Fab")
			(effects
				(font
					(size 0.7874 0.5842)
					(thickness 0.1524)
				)
			)
		)
		(fp_text user "M"
			(at -2.253742 14.400022 90)
			(unlocked yes)
			(layer "F.Fab")
			(effects
				(font
					(size 0.7874 0.5842)
					(thickness 0.1524)
				)
			)
		)
		(fp_text user "N"
			(at -2.253742 15.599918 90)
			(unlocked yes)
			(layer "F.Fab")
			(effects
				(font
					(size 0.7874 0.5842)
					(thickness 0.1524)
				)
			)
		)
		(fp_text user "1"
			(at 0.111252 19.8628 90)
			(unlocked yes)
			(layer "F.Fab")
			(effects
				(font
					(size 0.7874 0.5842)
					(thickness 0.1524)
				)
			)
		)
		(fp_text user "2"
			(at 2.111248 19.8628 90)
			(unlocked yes)
			(layer "F.Fab")
			(effects
				(font
					(size 0.7874 0.5842)
					(thickness 0.1524)
				)
			)
		)
		(fp_text user "3"
			(at 4.111244 19.8628 90)
			(unlocked yes)
			(layer "F.Fab")
			(effects
				(font
					(size 0.7874 0.5842)
					(thickness 0.1524)
				)
			)
		)
		(fp_text user "4"
			(at 6.11124 19.8628 90)
			(unlocked yes)
			(layer "F.Fab")
			(effects
				(font
					(size 0.7874 0.5842)
					(thickness 0.1524)
				)
			)
		)
		(fp_text user "5"
			(at 8.111236 19.8628 90)
			(unlocked yes)
			(layer "F.Fab")
			(effects
				(font
					(size 0.7874 0.5842)
					(thickness 0.1524)
				)
			)
		)
		(fp_text user "6"
			(at 10.111232 19.8628 90)
			(unlocked yes)
			(layer "F.Fab")
			(effects
				(font
					(size 0.7874 0.5842)
					(thickness 0.1524)
				)
			)
		)
		(fp_text user "7"
			(at 12.111228 19.8628 90)
			(unlocked yes)
			(layer "F.Fab")
			(effects
				(font
					(size 0.7874 0.5842)
					(thickness 0.1524)
				)
			)
		)
		(fp_text user "8"
			(at 14.111224 19.8628 90)
			(unlocked yes)
			(layer "F.Fab")
			(effects
				(font
					(size 0.7874 0.5842)
					(thickness 0.1524)
				)
			)
		)
		(fp_text user "PRESS-FIT"
			(at 17.240758 16.521684 90)
			(unlocked yes)
			(layer "F.Fab")
			(effects
				(font
					(size 1.905 1.4224)
					(thickness 0.1524)
				)
				(justify left)
			)
		)
		(pad "A1" thru_hole rect
			(at 0 0 180)
			(size 0.766318 0.766318)
			(drill 0.359918)
			(layers "*.Cu" "*.Mask")
			(remove_unused_layers no)
			(net "NC_J107_A1")
			(clearance 0.0508)
			(thermal_gap 0.0508)
			(padstack
				(mode front_inner_back)
				(layer "Inner"
					(shape circle)
					(size 0.766318 0.766318)
					(clearance 0.0508)
				)
				(layer "B.Cu"
					(shape rect)
					(size 0.766318 0.766318)
					(clearance 0.0508)
				)
			)
		)
		(pad "A2" thru_hole circle
			(at 1.999996 0.199898 180)
			(size 0.906272 0.906272)
			(drill 0.499872)
			(layers "*.Cu" "*.Mask")
			(remove_unused_layers no)
			(net "GND")
			(clearance 0.0508)
			(thermal_gap 0.0508)
		)
		(pad "A3" thru_hole circle
			(at 3.999992 0 180)
			(size 0.766318 0.766318)
			(drill 0.359918)
			(layers "*.Cu" "*.Mask")
			(remove_unused_layers no)
			(net "NC_J107_A3")
			(clearance 0.0508)
			(thermal_gap 0.0508)
		)
		(pad "A4" thru_hole circle
			(at 5.999988 0.199898 180)
			(size 0.906272 0.906272)
			(drill 0.499872)
			(layers "*.Cu" "*.Mask")
			(remove_unused_layers no)
			(net "GND")
			(clearance 0.0508)
			(thermal_gap 0.0508)
		)
		(pad "A5" thru_hole circle
			(at 7.999984 0 180)
			(size 0.766318 0.766318)
			(drill 0.359918)
			(layers "*.Cu" "*.Mask")
			(remove_unused_layers no)
			(net "NC_J107_A5")
			(clearance 0.0508)
			(thermal_gap 0.0508)
		)
		(pad "A6" thru_hole circle
			(at 9.99998 0.199898 180)
			(size 0.906272 0.906272)
			(drill 0.499872)
			(layers "*.Cu" "*.Mask")
			(remove_unused_layers no)
			(net "GND")
			(clearance 0.0508)
			(thermal_gap 0.0508)
		)
		(pad "A7" thru_hole circle
			(at 11.999976 0 180)
			(size 0.766318 0.766318)
			(drill 0.359918)
			(layers "*.Cu" "*.Mask")
			(remove_unused_layers no)
			(net "SWB_HSC_PWRGD")
			(clearance 0.0508)
			(thermal_gap 0.0508)
		)
		(pad "A8" thru_hole circle
			(at 13.999972 0.199898 180)
			(size 0.906272 0.906272)
			(drill 0.499872)
			(layers "*.Cu" "*.Mask")
			(remove_unused_layers no)
			(net "GND")
			(clearance 0.0508)
			(thermal_gap 0.0508)
		)
		(pad "B1" thru_hole circle
			(at 0 1.199896 180)
			(size 0.906272 0.906272)
			(drill 0.499872)
			(layers "*.Cu" "*.Mask")
			(remove_unused_layers no)
			(net "GND")
			(clearance 0.0508)
			(thermal_gap 0.0508)
		)
		(pad "B3" thru_hole circle
			(at 3.999992 1.199896 180)
			(size 0.906272 0.906272)
			(drill 0.499872)
			(layers "*.Cu" "*.Mask")
			(remove_unused_layers no)
			(net "GND")
			(clearance 0.0508)
			(thermal_gap 0.0508)
		)
		(pad "B5" thru_hole circle
			(at 7.999984 1.199896 180)
			(size 0.906272 0.906272)
			(drill 0.499872)
			(layers "*.Cu" "*.Mask")
			(remove_unused_layers no)
			(net "GND")
			(clearance 0.0508)
			(thermal_gap 0.0508)
		)
		(pad "B7" thru_hole circle
			(at 11.999976 1.199896 180)
			(size 0.906272 0.906272)
			(drill 0.499872)
			(layers "*.Cu" "*.Mask")
			(remove_unused_layers no)
			(net "GND")
			(clearance 0.0508)
			(thermal_gap 0.0508)
		)
		(pad "D2" thru_hole circle
			(at 1.999996 3.800094 180)
			(size 0.906272 0.906272)
			(drill 0.499872)
			(layers "*.Cu" "*.Mask")
			(remove_unused_layers no)
			(net "GND")
			(clearance 0.0508)
			(thermal_gap 0.0508)
		)
		(pad "D4" thru_hole circle
			(at 5.999988 3.800094 180)
			(size 0.906272 0.906272)
			(drill 0.499872)
			(layers "*.Cu" "*.Mask")
			(remove_unused_layers no)
			(net "GND")
			(clearance 0.0508)
			(thermal_gap 0.0508)
		)
		(pad "D6" thru_hole circle
			(at 9.99998 3.800094 180)
			(size 0.906272 0.906272)
			(drill 0.499872)
			(layers "*.Cu" "*.Mask")
			(remove_unused_layers no)
			(net "GND")
			(clearance 0.0508)
			(thermal_gap 0.0508)
		)
		(pad "D8" thru_hole circle
			(at 13.999972 3.800094 180)
			(size 0.906272 0.906272)
			(drill 0.499872)
			(layers "*.Cu" "*.Mask")
			(remove_unused_layers no)
			(net "GND")
			(clearance 0.0508)
			(thermal_gap 0.0508)
		)
		(pad "E1" thru_hole circle
			(at 0 4.800092 180)
			(size 0.906272 0.906272)
			(drill 0.499872)
			(layers "*.Cu" "*.Mask")
			(remove_unused_layers no)
			(net "GND")
			(clearance 0.0508)
			(thermal_gap 0.0508)
		)
		(pad "E3" thru_hole circle
			(at 3.999992 4.800092 180)
			(size 0.906272 0.906272)
			(drill 0.499872)
			(layers "*.Cu" "*.Mask")
			(remove_unused_layers no)
			(net "GND")
			(clearance 0.0508)
			(thermal_gap 0.0508)
		)
		(pad "E5" thru_hole circle
			(at 7.999984 4.800092 180)
			(size 0.906272 0.906272)
			(drill 0.499872)
			(layers "*.Cu" "*.Mask")
			(remove_unused_layers no)
			(net "GND")
			(clearance 0.0508)
			(thermal_gap 0.0508)
		)
		(pad "E7" thru_hole circle
			(at 11.999976 4.800092 180)
			(size 0.906272 0.906272)
			(drill 0.499872)
			(layers "*.Cu" "*.Mask")
			(remove_unused_layers no)
			(net "GND")
			(clearance 0.0508)
			(thermal_gap 0.0508)
		)
		(pad "G2" thru_hole circle
			(at 1.999996 7.400036 180)
			(size 0.906272 0.906272)
			(drill 0.499872)
			(layers "*.Cu" "*.Mask")
			(remove_unused_layers no)
			(net "GND")
			(clearance 0.0508)
			(thermal_gap 0.0508)
		)
		(pad "G4" thru_hole circle
			(at 5.999988 7.400036 180)
			(size 0.906272 0.906272)
			(drill 0.499872)
			(layers "*.Cu" "*.Mask")
			(remove_unused_layers no)
			(net "GND")
			(clearance 0.0508)
			(thermal_gap 0.0508)
		)
		(pad "G6" thru_hole circle
			(at 9.99998 7.400036 180)
			(size 0.906272 0.906272)
			(drill 0.499872)
			(layers "*.Cu" "*.Mask")
			(remove_unused_layers no)
			(net "GND")
			(clearance 0.0508)
			(thermal_gap 0.0508)
		)
		(pad "G8" thru_hole circle
			(at 13.999972 7.400036 180)
			(size 0.906272 0.906272)
			(drill 0.499872)
			(layers "*.Cu" "*.Mask")
			(remove_unused_layers no)
			(net "GND")
			(clearance 0.0508)
			(thermal_gap 0.0508)
		)
		(pad "H1" thru_hole circle
			(at 0 8.400034 180)
			(size 0.906272 0.906272)
			(drill 0.499872)
			(layers "*.Cu" "*.Mask")
			(remove_unused_layers no)
			(net "GND")
			(clearance 0.0508)
			(thermal_gap 0.0508)
		)
		(pad "H3" thru_hole circle
			(at 3.999992 8.400034 180)
			(size 0.906272 0.906272)
			(drill 0.499872)
			(layers "*.Cu" "*.Mask")
			(remove_unused_layers no)
			(net "GND")
			(clearance 0.0508)
			(thermal_gap 0.0508)
		)
		(pad "H5" thru_hole circle
			(at 7.999984 8.400034 180)
			(size 0.906272 0.906272)
			(drill 0.499872)
			(layers "*.Cu" "*.Mask")
			(remove_unused_layers no)
			(net "GND")
			(clearance 0.0508)
			(thermal_gap 0.0508)
		)
		(pad "H7" thru_hole circle
			(at 11.999976 8.400034 180)
			(size 0.906272 0.906272)
			(drill 0.499872)
			(layers "*.Cu" "*.Mask")
			(remove_unused_layers no)
			(net "GND")
			(clearance 0.0508)
			(thermal_gap 0.0508)
		)
		(pad "J2" thru_hole circle
			(at 1.999996 10.999978 180)
			(size 0.906272 0.906272)
			(drill 0.499872)
			(layers "*.Cu" "*.Mask")
			(remove_unused_layers no)
			(net "GND")
			(clearance 0.0508)
			(thermal_gap 0.0508)
		)
		(pad "J4" thru_hole circle
			(at 5.999988 10.999978 180)
			(size 0.906272 0.906272)
			(drill 0.499872)
			(layers "*.Cu" "*.Mask")
			(remove_unused_layers no)
			(net "GND")
			(clearance 0.0508)
			(thermal_gap 0.0508)
		)
		(pad "J6" thru_hole circle
			(at 9.99998 10.999978 180)
			(size 0.906272 0.906272)
			(drill 0.499872)
			(layers "*.Cu" "*.Mask")
			(remove_unused_layers no)
			(net "GND")
			(clearance 0.0508)
			(thermal_gap 0.0508)
		)
		(pad "J8" thru_hole circle
			(at 13.999972 10.999978 180)
			(size 0.906272 0.906272)
			(drill 0.499872)
			(layers "*.Cu" "*.Mask")
			(remove_unused_layers no)
			(net "GND")
			(clearance 0.0508)
			(thermal_gap 0.0508)
		)
		(pad "K1" thru_hole circle
			(at 0 11.999976 180)
			(size 0.906272 0.906272)
			(drill 0.499872)
			(layers "*.Cu" "*.Mask")
			(remove_unused_layers no)
			(net "GND")
			(clearance 0.0508)
			(thermal_gap 0.0508)
		)
		(pad "K3" thru_hole circle
			(at 3.999992 11.999976 180)
			(size 0.906272 0.906272)
			(drill 0.499872)
			(layers "*.Cu" "*.Mask")
			(remove_unused_layers no)
			(net "GND")
			(clearance 0.0508)
			(thermal_gap 0.0508)
		)
		(pad "K5" thru_hole circle
			(at 7.999984 11.999976 180)
			(size 0.906272 0.906272)
			(drill 0.499872)
			(layers "*.Cu" "*.Mask")
			(remove_unused_layers no)
			(net "GND")
			(clearance 0.0508)
			(thermal_gap 0.0508)
		)
		(pad "K7" thru_hole circle
			(at 11.999976 11.999976 180)
			(size 0.906272 0.906272)
			(drill 0.499872)
			(layers "*.Cu" "*.Mask")
			(remove_unused_layers no)
			(net "GND")
			(clearance 0.0508)
			(thermal_gap 0.0508)
		)
		(pad "M2" thru_hole circle
			(at 1.999996 14.59992 180)
			(size 0.906272 0.906272)
			(drill 0.499872)
			(layers "*.Cu" "*.Mask")
			(remove_unused_layers no)
			(net "GND")
			(clearance 0.0508)
			(thermal_gap 0.0508)
		)
		(pad "M4" thru_hole circle
			(at 5.999988 14.59992 180)
			(size 0.906272 0.906272)
			(drill 0.499872)
			(layers "*.Cu" "*.Mask")
			(remove_unused_layers no)
			(net "GND")
			(clearance 0.0508)
			(thermal_gap 0.0508)
		)
		(pad "M6" thru_hole circle
			(at 9.99998 14.59992 180)
			(size 0.906272 0.906272)
			(drill 0.499872)
			(layers "*.Cu" "*.Mask")
			(remove_unused_layers no)
			(net "GND")
			(clearance 0.0508)
			(thermal_gap 0.0508)
		)
		(pad "M8" thru_hole circle
			(at 13.999972 14.59992 180)
			(size 0.906272 0.906272)
			(drill 0.499872)
			(layers "*.Cu" "*.Mask")
			(remove_unused_layers no)
			(net "GND")
			(clearance 0.0508)
			(thermal_gap 0.0508)
		)
		(pad "N1" thru_hole circle
			(at 0 15.599918 180)
			(size 0.906272 0.906272)
			(drill 0.499872)
			(layers "*.Cu" "*.Mask")
			(remove_unused_layers no)
			(net "GND")
			(clearance 0.0508)
			(thermal_gap 0.0508)
		)
		(pad "N2" thru_hole circle
			(at 1.999996 15.80007 180)
			(size 0.766318 0.766318)
			(drill 0.359918)
			(layers "*.Cu" "*.Mask")
			(remove_unused_layers no)
			(net "PRSNT_CABLE_SWB_B2_N")
			(clearance 0.0508)
			(thermal_gap 0.0508)
		)
		(pad "N3" thru_hole circle
			(at 3.999992 15.599918 180)
			(size 0.906272 0.906272)
			(drill 0.499872)
			(layers "*.Cu" "*.Mask")
			(remove_unused_layers no)
			(net "GND")
			(clearance 0.0508)
			(thermal_gap 0.0508)
		)
		(pad "N4" thru_hole circle
			(at 5.999988 15.80007 180)
			(size 0.766318 0.766318)
			(drill 0.359918)
			(layers "*.Cu" "*.Mask")
			(remove_unused_layers no)
			(net "NC_J107_N4")
			(clearance 0.0508)
			(thermal_gap 0.0508)
		)
		(pad "N5" thru_hole circle
			(at 7.999984 15.599918 180)
			(size 0.906272 0.906272)
			(drill 0.499872)
			(layers "*.Cu" "*.Mask")
			(remove_unused_layers no)
			(net "GND")
			(clearance 0.0508)
			(thermal_gap 0.0508)
		)
		(pad "N6" thru_hole circle
			(at 9.99998 15.80007 180)
			(size 0.766318 0.766318)
			(drill 0.359918)
			(layers "*.Cu" "*.Mask")
			(remove_unused_layers no)
			(net "NC_J107_N6")
			(clearance 0.0508)
			(thermal_gap 0.0508)
		)
		(pad "N7" thru_hole circle
			(at 11.999976 15.599918 180)
			(size 0.906272 0.906272)
			(drill 0.499872)
			(layers "*.Cu" "*.Mask")
			(remove_unused_layers no)
			(net "GND")
			(clearance 0.0508)
			(thermal_gap 0.0508)
		)
		(pad "N8" thru_hole circle
			(at 13.999972 15.80007 180)
			(size 0.766318 0.766318)
			(drill 0.359918)
			(layers "*.Cu" "*.Mask")
			(remove_unused_layers no)
			(net "SWB_HSC_EN_BUF")
			(clearance 0.0508)
			(thermal_gap 0.0508)
		)
	)
	(footprint ""
		(layer "F.Cu")
		(at 40.161972 -434.344318 90)
		(property "Reference" "R2893"
			(at 0 0 90)
			(layer "F.SilkS")
			(hide yes)
			(effects
				(font
					(size 1.27 1.27)
				)
			)
		)
		(property "Value" ""
			(at 0 0 90)
			(layer "F.Fab")
			(effects
				(font
					(size 1.27 1.27)
				)
			)
		)
		(duplicate_pad_numbers_are_jumpers no)
		(fp_line
			(start 0.7874 -0.4064)
			(end 0.7874 0.4064)
			(stroke
				(width 0.1524)
				(type default)
			)
			(layer "F.SilkS")
		)
		(fp_line
			(start -0.7874 -0.4064)
			(end 0.7874 -0.4064)
			(stroke
				(width 0.1524)
				(type default)
			)
			(layer "F.SilkS")
		)
		(fp_line
			(start 0.7874 0.4064)
			(end -0.7874 0.4064)
			(stroke
				(width 0.1524)
				(type default)
			)
			(layer "F.SilkS")
		)
		(fp_line
			(start -0.7874 0.4064)
			(end -0.7874 -0.4064)
			(stroke
				(width 0.1524)
				(type default)
			)
			(layer "F.SilkS")
		)
		(fp_line
			(start -0.12065 -0.305054)
			(end -0.12065 -0.2794)
			(stroke
				(width 0.1)
				(type default)
			)
			(layer "F.Fab")
		)
		(fp_line
			(start -0.67945 -0.305054)
			(end -0.12065 -0.305054)
			(stroke
				(width 0.1)
				(type default)
			)
			(layer "F.Fab")
		)
		(fp_line
			(start 0.67945 -0.3048)
			(end 0.67945 0.3048)
			(stroke
				(width 0.1)
				(type default)
			)
			(layer "F.Fab")
		)
		(fp_line
			(start 0.12065 -0.3048)
			(end 0.67945 -0.3048)
			(stroke
				(width 0.1)
				(type default)
			)
			(layer "F.Fab")
		)
		(fp_line
			(start 0.12065 -0.2794)
			(end 0.12065 -0.3048)
			(stroke
				(width 0.1)
				(type default)
			)
			(layer "F.Fab")
		)
		(fp_line
			(start -0.12065 -0.2794)
			(end 0.12065 -0.2794)
			(stroke
				(width 0.1)
				(type default)
			)
			(layer "F.Fab")
		)
		(fp_line
			(start 0.120396 0.2794)
			(end -0.12065 0.2794)
			(stroke
				(width 0.1)
				(type default)
			)
			(layer "F.Fab")
		)
		(fp_line
			(start -0.12065 0.2794)
			(end -0.12065 0.3048)
			(stroke
				(width 0.1)
				(type default)
			)
			(layer "F.Fab")
		)
		(fp_line
			(start 0.67945 0.3048)
			(end 0.120396 0.3048)
			(stroke
				(width 0.1)
				(type default)
			)
			(layer "F.Fab")
		)
		(fp_line
			(start 0.120396 0.3048)
			(end 0.120396 0.2794)
			(stroke
				(width 0.1)
				(type default)
			)
			(layer "F.Fab")
		)
		(fp_line
			(start -0.12065 0.3048)
			(end -0.67945 0.3048)
			(stroke
				(width 0.1)
				(type default)
			)
			(layer "F.Fab")
		)
		(fp_line
			(start -0.67945 0.3048)
			(end -0.67945 -0.305054)
			(stroke
				(width 0.1)
				(type default)
			)
			(layer "F.Fab")
		)
		(pad "1" smd circle
			(at -0.40005 0 90)
			(size 0 0)
			(layers "F.Cu" "F.Mask" "F.Paste")
			(net "SMB_1_BMC_GPU_R_SCL")
		)
		(pad "2" smd circle
			(at 0.40005 0 90)
			(size 0 0)
			(layers "F.Cu" "F.Mask" "F.Paste")
			(net "SMB_1_BMC_GPU_BUF_R_SCL")
		)
	)
	(footprint ""
		(layer "F.Cu")
		(at 126.256034 -402.371052 -90)
		(property "Reference" "C747"
			(at 0 0 270)
			(layer "F.SilkS")
			(hide yes)
			(effects
				(font
					(size 1.27 1.27)
				)
			)
		)
		(property "Value" ""
			(at 0 0 270)
			(layer "F.Fab")
			(effects
				(font
					(size 1.27 1.27)
				)
			)
		)
		(duplicate_pad_numbers_are_jumpers no)
		(fp_line
			(start -0.299974 0.150114)
			(end -0.299974 -0.150114)
			(stroke
				(width 0.1)
				(type default)
			)
			(layer "F.Fab")
		)
		(fp_line
			(start 0.299974 0.150114)
			(end -0.299974 0.150114)
			(stroke
				(width 0.1)
				(type default)
			)
			(layer "F.Fab")
		)
		(fp_line
			(start -0.299974 -0.150114)
			(end 0.299974 -0.150114)
			(stroke
				(width 0.1)
				(type default)
			)
			(layer "F.Fab")
		)
		(fp_line
			(start 0.299974 -0.150114)
			(end 0.299974 0.150114)
			(stroke
				(width 0.1)
				(type default)
			)
			(layer "F.Fab")
		)
		(pad "1" smd rect
			(at -0.2667 0 270)
			(size 0.3048 0.381)
			(layers "F.Cu" "F.Mask" "F.Paste")
			(net "P5E_CPU1_PE2_TX_C_DP<13>")
		)
		(pad "2" smd rect
			(at 0.2667 0 270)
			(size 0.3048 0.381)
			(layers "F.Cu" "F.Mask" "F.Paste")
			(net "P5E_CPU1_PE2_TX_DP<13>")
		)
	)
	(footprint ""
		(layer "F.Cu")
		(at 322.287138 -13.721588 180)
		(property "Reference" "R1765"
			(at 0 0 180)
			(layer "F.SilkS")
			(hide yes)
			(effects
				(font
					(size 1.27 1.27)
				)
			)
		)
		(property "Value" ""
			(at 0 0 180)
			(layer "F.Fab")
			(effects
				(font
					(size 1.27 1.27)
				)
			)
		)
		(duplicate_pad_numbers_are_jumpers no)
		(fp_line
			(start 1.651 0.8382)
			(end -1.651 0.8382)
			(stroke
				(width 0.1524)
				(type default)
			)
			(layer "F.SilkS")
		)
		(fp_line
			(start 1.651 -0.8382)
			(end 1.651 0.8382)
			(stroke
				(width 0.1524)
				(type default)
			)
			(layer "F.SilkS")
		)
		(fp_line
			(start -1.651 0.8382)
			(end -1.651 -0.8382)
			(stroke
				(width 0.1524)
				(type default)
			)
			(layer "F.SilkS")
		)
		(fp_line
			(start -1.651 -0.8382)
			(end 1.651 -0.8382)
			(stroke
				(width 0.1524)
				(type default)
			)
			(layer "F.SilkS")
		)
		(fp_line
			(start 1.560576 0.7366)
			(end 1.560576 -0.7366)
			(stroke
				(width 0.1)
				(type default)
			)
			(layer "F.Fab")
		)
		(fp_line
			(start 1.560576 -0.7366)
			(end 1.524 -0.7366)
			(stroke
				(width 0.1)
				(type default)
			)
			(layer "F.Fab")
		)
		(fp_line
			(start 1.524 0.7366)
			(end 1.560576 0.7366)
			(stroke
				(width 0.1)
				(type default)
			)
			(layer "F.Fab")
		)
		(fp_line
			(start 1.524 -0.7366)
			(end -1.524 -0.7366)
			(stroke
				(width 0.1)
				(type default)
			)
			(layer "F.Fab")
		)
		(fp_line
			(start -1.524 0.7366)
			(end 1.524 0.7366)
			(stroke
				(width 0.1)
				(type default)
			)
			(layer "F.Fab")
		)
		(fp_line
			(start -1.524 -0.7366)
			(end -1.559814 -0.7366)
			(stroke
				(width 0.1)
				(type default)
			)
			(layer "F.Fab")
		)
		(fp_line
			(start -1.559814 0.7366)
			(end -1.524 0.7366)
			(stroke
				(width 0.1)
				(type default)
			)
			(layer "F.Fab")
		)
		(fp_line
			(start -1.559814 -0.7366)
			(end -1.559814 0.7366)
			(stroke
				(width 0.1)
				(type default)
			)
			(layer "F.Fab")
		)
		(pad "1" smd rect
			(at -0.94996 0)
			(size 1.1176 1.3716)
			(layers "F.Cu" "F.Mask" "F.Paste")
			(net "PGPPA_AUX")
		)
		(pad "2" smd rect
			(at 0.94996 0)
			(size 1.1176 1.3716)
			(layers "F.Cu" "F.Mask" "F.Paste")
			(net "P3V3_AUX")
		)
	)
	(footprint ""
		(layer "F.Cu")
		(at 461.593946 -105.011728 180)
		(property "Reference" "R4762"
			(at 0 0 180)
			(layer "F.SilkS")
			(hide yes)
			(effects
				(font
					(size 1.27 1.27)
				)
			)
		)
		(property "Value" ""
			(at 0 0 180)
			(layer "F.Fab")
			(effects
				(font
					(size 1.27 1.27)
				)
			)
		)
		(duplicate_pad_numbers_are_jumpers no)
		(fp_line
			(start 0.7874 0.4064)
			(end -0.7874 0.4064)
			(stroke
				(width 0.1524)
				(type default)
			)
			(layer "F.SilkS")
		)
		(fp_line
			(start 0.7874 -0.4064)
			(end 0.7874 0.4064)
			(stroke
				(width 0.1524)
				(type default)
			)
			(layer "F.SilkS")
		)
		(fp_line
			(start -0.7874 0.4064)
			(end -0.7874 -0.4064)
			(stroke
				(width 0.1524)
				(type default)
			)
			(layer "F.SilkS")
		)
		(fp_line
			(start -0.7874 -0.4064)
			(end 0.7874 -0.4064)
			(stroke
				(width 0.1524)
				(type default)
			)
			(layer "F.SilkS")
		)
		(fp_line
			(start 0.67945 0.3048)
			(end 0.120396 0.3048)
			(stroke
				(width 0.1)
				(type default)
			)
			(layer "F.Fab")
		)
		(fp_line
			(start 0.67945 -0.3048)
			(end 0.67945 0.3048)
			(stroke
				(width 0.1)
				(type default)
			)
			(layer "F.Fab")
		)
		(fp_line
			(start 0.12065 -0.2794)
			(end 0.12065 -0.3048)
			(stroke
				(width 0.1)
				(type default)
			)
			(layer "F.Fab")
		)
		(fp_line
			(start 0.12065 -0.3048)
			(end 0.67945 -0.3048)
			(stroke
				(width 0.1)
				(type default)
			)
			(layer "F.Fab")
		)
		(fp_line
			(start 0.120396 0.3048)
			(end 0.120396 0.2794)
			(stroke
				(width 0.1)
				(type default)
			)
			(layer "F.Fab")
		)
		(fp_line
			(start 0.120396 0.2794)
			(end -0.12065 0.2794)
			(stroke
				(width 0.1)
				(type default)
			)
			(layer "F.Fab")
		)
		(fp_line
			(start -0.12065 0.3048)
			(end -0.67945 0.3048)
			(stroke
				(width 0.1)
				(type default)
			)
			(layer "F.Fab")
		)
		(fp_line
			(start -0.12065 0.2794)
			(end -0.12065 0.3048)
			(stroke
				(width 0.1)
				(type default)
			)
			(layer "F.Fab")
		)
		(fp_line
			(start -0.12065 -0.2794)
			(end 0.12065 -0.2794)
			(stroke
				(width 0.1)
				(type default)
			)
			(layer "F.Fab")
		)
		(fp_line
			(start -0.12065 -0.305054)
			(end -0.12065 -0.2794)
			(stroke
				(width 0.1)
				(type default)
			)
			(layer "F.Fab")
		)
		(fp_line
			(start -0.67945 0.3048)
			(end -0.67945 -0.305054)
			(stroke
				(width 0.1)
				(type default)
			)
			(layer "F.Fab")
		)
		(fp_line
			(start -0.67945 -0.305054)
			(end -0.12065 -0.305054)
			(stroke
				(width 0.1)
				(type default)
			)
			(layer "F.Fab")
		)
		(pad "1" smd circle
			(at -0.40005 0 180)
			(size 0 0)
			(layers "F.Cu" "F.Mask" "F.Paste")
			(net "P3V3_AUX")
		)
		(pad "2" smd circle
			(at 0.40005 0 180)
			(size 0 0)
			(layers "F.Cu" "F.Mask" "F.Paste")
			(net "HP_LVC3_OCP_V3_1_PRSNT2_PLD_N")
		)
	)
	(footprint ""
		(layer "F.Cu")
		(at 56.341518 -408.517344 -90)
		(property "Reference" "C705"
			(at 0 0 270)
			(layer "F.SilkS")
			(hide yes)
			(effects
				(font
					(size 1.27 1.27)
				)
			)
		)
		(property "Value" ""
			(at 0 0 270)
			(layer "F.Fab")
			(effects
				(font
					(size 1.27 1.27)
				)
			)
		)
		(duplicate_pad_numbers_are_jumpers no)
		(fp_line
			(start -0.299974 0.150114)
			(end -0.299974 -0.150114)
			(stroke
				(width 0.1)
				(type default)
			)
			(layer "F.Fab")
		)
		(fp_line
			(start 0.299974 0.150114)
			(end -0.299974 0.150114)
			(stroke
				(width 0.1)
				(type default)
			)
			(layer "F.Fab")
		)
		(fp_line
			(start -0.299974 -0.150114)
			(end 0.299974 -0.150114)
			(stroke
				(width 0.1)
				(type default)
			)
			(layer "F.Fab")
		)
		(fp_line
			(start 0.299974 -0.150114)
			(end 0.299974 0.150114)
			(stroke
				(width 0.1)
				(type default)
			)
			(layer "F.Fab")
		)
		(pad "1" smd rect
			(at -0.2667 0 270)
			(size 0.3048 0.381)
			(layers "F.Cu" "F.Mask" "F.Paste")
			(net "P5E_CPU1_PE4_TX_C_DP<2>")
		)
		(pad "2" smd rect
			(at 0.2667 0 270)
			(size 0.3048 0.381)
			(layers "F.Cu" "F.Mask" "F.Paste")
			(net "P5E_CPU1_PE4_TX_DP<2>")
		)
	)
	(footprint ""
		(layer "F.Cu")
		(at 120.36044 -427.091348 180)
		(property "Reference" "R3506"
			(at 0 0 180)
			(layer "F.SilkS")
			(hide yes)
			(effects
				(font
					(size 1.27 1.27)
				)
			)
		)
		(property "Value" ""
			(at 0 0 180)
			(layer "F.Fab")
			(effects
				(font
					(size 1.27 1.27)
				)
			)
		)
		(duplicate_pad_numbers_are_jumpers no)
		(fp_line
			(start 0.7874 0.4064)
			(end -0.7874 0.4064)
			(stroke
				(width 0.1524)
				(type default)
			)
			(layer "F.SilkS")
		)
		(fp_line
			(start 0.7874 -0.4064)
			(end 0.7874 0.4064)
			(stroke
				(width 0.1524)
				(type default)
			)
			(layer "F.SilkS")
		)
		(fp_line
			(start -0.7874 0.4064)
			(end -0.7874 -0.4064)
			(stroke
				(width 0.1524)
				(type default)
			)
			(layer "F.SilkS")
		)
		(fp_line
			(start -0.7874 -0.4064)
			(end 0.7874 -0.4064)
			(stroke
				(width 0.1524)
				(type default)
			)
			(layer "F.SilkS")
		)
		(fp_line
			(start 0.67945 0.3048)
			(end 0.120396 0.3048)
			(stroke
				(width 0.1)
				(type default)
			)
			(layer "F.Fab")
		)
		(fp_line
			(start 0.67945 -0.3048)
			(end 0.67945 0.3048)
			(stroke
				(width 0.1)
				(type default)
			)
			(layer "F.Fab")
		)
		(fp_line
			(start 0.12065 -0.2794)
			(end 0.12065 -0.3048)
			(stroke
				(width 0.1)
				(type default)
			)
			(layer "F.Fab")
		)
		(fp_line
			(start 0.12065 -0.3048)
			(end 0.67945 -0.3048)
			(stroke
				(width 0.1)
				(type default)
			)
			(layer "F.Fab")
		)
		(fp_line
			(start 0.120396 0.3048)
			(end 0.120396 0.2794)
			(stroke
				(width 0.1)
				(type default)
			)
			(layer "F.Fab")
		)
		(fp_line
			(start 0.120396 0.2794)
			(end -0.12065 0.2794)
			(stroke
				(width 0.1)
				(type default)
			)
			(layer "F.Fab")
		)
		(fp_line
			(start -0.12065 0.3048)
			(end -0.67945 0.3048)
			(stroke
				(width 0.1)
				(type default)
			)
			(layer "F.Fab")
		)
		(fp_line
			(start -0.12065 0.2794)
			(end -0.12065 0.3048)
			(stroke
				(width 0.1)
				(type default)
			)
			(layer "F.Fab")
		)
		(fp_line
			(start -0.12065 -0.2794)
			(end 0.12065 -0.2794)
			(stroke
				(width 0.1)
				(type default)
			)
			(layer "F.Fab")
		)
		(fp_line
			(start -0.12065 -0.305054)
			(end -0.12065 -0.2794)
			(stroke
				(width 0.1)
				(type default)
			)
			(layer "F.Fab")
		)
		(fp_line
			(start -0.67945 0.3048)
			(end -0.67945 -0.305054)
			(stroke
				(width 0.1)
				(type default)
			)
			(layer "F.Fab")
		)
		(fp_line
			(start -0.67945 -0.305054)
			(end -0.12065 -0.305054)
			(stroke
				(width 0.1)
				(type default)
			)
			(layer "F.Fab")
		)
		(pad "1" smd circle
			(at -0.40005 0 180)
			(size 0 0)
			(layers "F.Cu" "F.Mask" "F.Paste")
			(net "P3V3_AUX")
		)
		(pad "2" smd circle
			(at 0.40005 0 180)
			(size 0 0)
			(layers "F.Cu" "F.Mask" "F.Paste")
			(net "GPU_FPGA_RST_R_N")
		)
	)
	(footprint ""
		(layer "F.Cu")
		(at 359.774998 -431.359818 180)
		(property "Reference" "J123"
			(at -0.529082 -11.63828 0)
			(unlocked yes)
			(layer "F.SilkS")
			(effects
				(font
					(size 0.7874 0.5842)
					(thickness 0.1524)
				)
				(justify left)
			)
		)
		(property "Value" ""
			(at 0 0 180)
			(layer "F.Fab")
			(effects
				(font
					(size 1.27 1.27)
				)
			)
		)
		(duplicate_pad_numbers_are_jumpers no)
		(fp_line
			(start 3.525012 21.310092)
			(end 3.525012 -10.489946)
			(stroke
				(width 0.1524)
				(type default)
			)
			(layer "F.SilkS")
		)
		(fp_line
			(start 3.525012 -10.489946)
			(end -3.525012 -10.489946)
			(stroke
				(width 0.1524)
				(type default)
			)
			(layer "F.SilkS")
		)
		(fp_line
			(start -3.525012 21.310092)
			(end 3.525012 21.310092)
			(stroke
				(width 0.1524)
				(type default)
			)
			(layer "F.SilkS")
		)
		(fp_line
			(start -3.525012 10.6299)
			(end 3.525012 10.6299)
			(stroke
				(width 0.1524)
				(type default)
			)
			(layer "F.SilkS")
		)
		(fp_line
			(start -3.525012 -10.489946)
			(end -3.525012 21.310092)
			(stroke
				(width 0.1524)
				(type default)
			)
			(layer "F.SilkS")
		)
		(fp_line
			(start 3.525012 21.310092)
			(end 3.525012 -10.489946)
			(stroke
				(width 0.1)
				(type default)
			)
			(layer "F.Fab")
		)
		(fp_line
			(start 3.525012 -10.489946)
			(end -3.525012 -10.489946)
			(stroke
				(width 0.1)
				(type default)
			)
			(layer "F.Fab")
		)
		(fp_line
			(start -3.525012 21.310092)
			(end 3.525012 21.310092)
			(stroke
				(width 0.1)
				(type default)
			)
			(layer "F.Fab")
		)
		(fp_line
			(start -3.525012 -10.489946)
			(end -3.525012 21.310092)
			(stroke
				(width 0.1)
				(type default)
			)
			(layer "F.Fab")
		)
		(pad "" np_thru_hole circle
			(at 0 -6.620002 180)
			(size 3.175 3.175)
			(drill 3.175)
			(layers "*.Cu" "*.Mask")
			(clearance 0.381)
			(thermal_gap 0.381)
		)
		(pad "" np_thru_hole circle
			(at 0 0 180)
			(size 0 0)
			(drill 3.175)
			(layers "*.Cu" "*.Mask")
			(clearance 0)
		)
		(pad "" np_thru_hole circle
			(at 0 5.130038 180)
			(size 3.175 3.175)
			(drill 3.175)
			(layers "*.Cu" "*.Mask")
			(clearance 0.381)
			(thermal_gap 0.381)
		)
		(zone
			(layers "F.Cu" "B.Cu" "In1.Cu" "In2.Cu" "In3.Cu" "In4.Cu" "In5.Cu" "In6.Cu"
				"In7.Cu" "In8.Cu" "In9.Cu" "In10.Cu" "In11.Cu" "In12.Cu" "In13.Cu" "In14.Cu"
				"In15.Cu" "In16.Cu"
			)
			(hatch none 0.5)
			(connect_pads
				(clearance 0)
			)
			(min_thickness 0.25)
			(keepout
				(tracks not_allowed)
				(vias allowed)
				(pads allowed)
				(copperpour not_allowed)
				(footprints allowed)
			)
			(placement
				(enabled no)
				(sheetname "")
			)
			(fill
				(thermal_gap 0.5)
				(thermal_bridge_width 0.5)
				(island_removal_mode 0)
			)
			(polygon
				(pts
					(arc
						(start 361.870498 -436.489856)
						(mid 357.679498 -436.489856)
						(end 361.870498 -436.489856)
					)
				)
			)
		)
		(zone
			(layers "F.Cu" "B.Cu" "In1.Cu" "In2.Cu" "In3.Cu" "In4.Cu" "In5.Cu" "In6.Cu"
				"In7.Cu" "In8.Cu" "In9.Cu" "In10.Cu" "In11.Cu" "In12.Cu" "In13.Cu" "In14.Cu"
				"In15.Cu" "In16.Cu"
			)
			(hatch none 0.5)
			(connect_pads
				(clearance 0)
			)
			(min_thickness 0.25)
			(keepout
				(tracks not_allowed)
				(vias allowed)
				(pads allowed)
				(copperpour not_allowed)
				(footprints allowed)
			)
			(placement
				(enabled no)
				(sheetname "")
			)
			(fill
				(thermal_gap 0.5)
				(thermal_bridge_width 0.5)
				(island_removal_mode 0)
			)
			(polygon
				(pts
					(arc
						(start 361.870498 -424.739816)
						(mid 357.679498 -424.739816)
						(end 361.870498 -424.739816)
					)
				)
			)
		)
		(zone
			(layers "F.Cu" "B.Cu" "In1.Cu" "In2.Cu" "In3.Cu" "In4.Cu" "In5.Cu" "In6.Cu"
				"In7.Cu" "In8.Cu" "In9.Cu" "In10.Cu" "In11.Cu" "In12.Cu" "In13.Cu" "In14.Cu"
				"In15.Cu" "In16.Cu"
			)
			(hatch none 0.5)
			(connect_pads
				(clearance 0)
			)
			(min_thickness 0.25)
			(keepout
				(tracks not_allowed)
				(vias allowed)
				(pads allowed)
				(copperpour not_allowed)
				(footprints allowed)
			)
			(placement
				(enabled no)
				(sheetname "")
			)
			(fill
				(thermal_gap 0.5)
				(thermal_bridge_width 0.5)
				(island_removal_mode 0)
			)
			(polygon
				(pts
					(arc
						(start 363.394498 -431.359818)
						(mid 356.155498 -431.359818)
						(end 363.394498 -431.359818)
					)
				)
			)
		)
	)
	(footprint ""
		(layer "F.Cu")
		(at 388.97433 -408.517344 -90)
		(property "Reference" "C881"
			(at 0 0 270)
			(layer "F.SilkS")
			(hide yes)
			(effects
				(font
					(size 1.27 1.27)
				)
			)
		)
		(property "Value" ""
			(at 0 0 270)
			(layer "F.Fab")
			(effects
				(font
					(size 1.27 1.27)
				)
			)
		)
		(duplicate_pad_numbers_are_jumpers no)
		(fp_line
			(start -0.299974 0.150114)
			(end -0.299974 -0.150114)
			(stroke
				(width 0.1)
				(type default)
			)
			(layer "F.Fab")
		)
		(fp_line
			(start 0.299974 0.150114)
			(end -0.299974 0.150114)
			(stroke
				(width 0.1)
				(type default)
			)
			(layer "F.Fab")
		)
		(fp_line
			(start -0.299974 -0.150114)
			(end 0.299974 -0.150114)
			(stroke
				(width 0.1)
				(type default)
			)
			(layer "F.Fab")
		)
		(fp_line
			(start 0.299974 -0.150114)
			(end 0.299974 0.150114)
			(stroke
				(width 0.1)
				(type default)
			)
			(layer "F.Fab")
		)
		(pad "1" smd rect
			(at -0.2667 0 270)
			(size 0.3048 0.381)
			(layers "F.Cu" "F.Mask" "F.Paste")
			(net "P5E_CPU0_PE3_TX_C_DP<10>")
		)
		(pad "2" smd rect
			(at 0.2667 0 270)
			(size 0.3048 0.381)
			(layers "F.Cu" "F.Mask" "F.Paste")
			(net "P5E_CPU0_PE3_TX_DP<10>")
		)
	)
	(footprint ""
		(layer "F.Cu")
		(at 193.38036 -116.804948 180)
		(property "Reference" "R3049"
			(at 0 0 180)
			(layer "F.SilkS")
			(hide yes)
			(effects
				(font
					(size 1.27 1.27)
				)
			)
		)
		(property "Value" ""
			(at 0 0 180)
			(layer "F.Fab")
			(effects
				(font
					(size 1.27 1.27)
				)
			)
		)
		(duplicate_pad_numbers_are_jumpers no)
		(fp_line
			(start 0.7874 0.4064)
			(end -0.7874 0.4064)
			(stroke
				(width 0.1524)
				(type default)
			)
			(layer "F.SilkS")
		)
		(fp_line
			(start 0.7874 -0.4064)
			(end 0.7874 0.4064)
			(stroke
				(width 0.1524)
				(type default)
			)
			(layer "F.SilkS")
		)
		(fp_line
			(start -0.7874 0.4064)
			(end -0.7874 -0.4064)
			(stroke
				(width 0.1524)
				(type default)
			)
			(layer "F.SilkS")
		)
		(fp_line
			(start -0.7874 -0.4064)
			(end 0.7874 -0.4064)
			(stroke
				(width 0.1524)
				(type default)
			)
			(layer "F.SilkS")
		)
		(fp_line
			(start 0.67945 0.3048)
			(end 0.120396 0.3048)
			(stroke
				(width 0.1)
				(type default)
			)
			(layer "F.Fab")
		)
		(fp_line
			(start 0.67945 -0.3048)
			(end 0.67945 0.3048)
			(stroke
				(width 0.1)
				(type default)
			)
			(layer "F.Fab")
		)
		(fp_line
			(start 0.12065 -0.2794)
			(end 0.12065 -0.3048)
			(stroke
				(width 0.1)
				(type default)
			)
			(layer "F.Fab")
		)
		(fp_line
			(start 0.12065 -0.3048)
			(end 0.67945 -0.3048)
			(stroke
				(width 0.1)
				(type default)
			)
			(layer "F.Fab")
		)
		(fp_line
			(start 0.120396 0.3048)
			(end 0.120396 0.2794)
			(stroke
				(width 0.1)
				(type default)
			)
			(layer "F.Fab")
		)
		(fp_line
			(start 0.120396 0.2794)
			(end -0.12065 0.2794)
			(stroke
				(width 0.1)
				(type default)
			)
			(layer "F.Fab")
		)
		(fp_line
			(start -0.12065 0.3048)
			(end -0.67945 0.3048)
			(stroke
				(width 0.1)
				(type default)
			)
			(layer "F.Fab")
		)
		(fp_line
			(start -0.12065 0.2794)
			(end -0.12065 0.3048)
			(stroke
				(width 0.1)
				(type default)
			)
			(layer "F.Fab")
		)
		(fp_line
			(start -0.12065 -0.2794)
			(end 0.12065 -0.2794)
			(stroke
				(width 0.1)
				(type default)
			)
			(layer "F.Fab")
		)
		(fp_line
			(start -0.12065 -0.305054)
			(end -0.12065 -0.2794)
			(stroke
				(width 0.1)
				(type default)
			)
			(layer "F.Fab")
		)
		(fp_line
			(start -0.67945 0.3048)
			(end -0.67945 -0.305054)
			(stroke
				(width 0.1)
				(type default)
			)
			(layer "F.Fab")
		)
		(fp_line
			(start -0.67945 -0.305054)
			(end -0.12065 -0.305054)
			(stroke
				(width 0.1)
				(type default)
			)
			(layer "F.Fab")
		)
		(pad "1" smd circle
			(at -0.40005 0 180)
			(size 0 0)
			(layers "F.Cu" "F.Mask" "F.Paste")
			(net "IRQ_SML1_PMBUS_ALERT_N")
		)
		(pad "2" smd circle
			(at 0.40005 0 180)
			(size 0 0)
			(layers "F.Cu" "F.Mask" "F.Paste")
			(net "IRQ_PSU_ALERT_R_N")
		)
	)
	(footprint ""
		(layer "F.Cu")
		(at 365.46663 -256.654046 -90)
		(property "Reference" "C988"
			(at 0 0 270)
			(layer "F.SilkS")
			(hide yes)
			(effects
				(font
					(size 1.27 1.27)
				)
			)
		)
		(property "Value" ""
			(at 0 0 270)
			(layer "F.Fab")
			(effects
				(font
					(size 1.27 1.27)
				)
			)
		)
		(duplicate_pad_numbers_are_jumpers no)
		(fp_line
			(start -0.7874 0.4064)
			(end -0.7874 -0.4064)
			(stroke
				(width 0.1524)
				(type default)
			)
			(layer "F.SilkS")
		)
		(fp_line
			(start 0.7874 0.4064)
			(end -0.7874 0.4064)
			(stroke
				(width 0.1524)
				(type default)
			)
			(layer "F.SilkS")
		)
		(fp_line
			(start -0.7874 -0.4064)
			(end 0.7874 -0.4064)
			(stroke
				(width 0.1524)
				(type default)
			)
			(layer "F.SilkS")
		)
		(fp_line
			(start 0.7874 -0.4064)
			(end 0.7874 0.4064)
			(stroke
				(width 0.1524)
				(type default)
			)
			(layer "F.SilkS")
		)
		(fp_line
			(start -0.67945 0.3048)
			(end -0.67945 -0.305054)
			(stroke
				(width 0.1)
				(type default)
			)
			(layer "F.Fab")
		)
		(fp_line
			(start -0.12065 0.3048)
			(end -0.67945 0.3048)
			(stroke
				(width 0.1)
				(type default)
			)
			(layer "F.Fab")
		)
		(fp_line
			(start 0.120396 0.3048)
			(end 0.120396 0.2794)
			(stroke
				(width 0.1)
				(type default)
			)
			(layer "F.Fab")
		)
		(fp_line
			(start 0.67945 0.3048)
			(end 0.120396 0.3048)
			(stroke
				(width 0.1)
				(type default)
			)
			(layer "F.Fab")
		)
		(fp_line
			(start -0.12065 0.2794)
			(end -0.12065 0.3048)
			(stroke
				(width 0.1)
				(type default)
			)
			(layer "F.Fab")
		)
		(fp_line
			(start 0.120396 0.2794)
			(end -0.12065 0.2794)
			(stroke
				(width 0.1)
				(type default)
			)
			(layer "F.Fab")
		)
		(fp_line
			(start -0.12065 -0.2794)
			(end 0.12065 -0.2794)
			(stroke
				(width 0.1)
				(type default)
			)
			(layer "F.Fab")
		)
		(fp_line
			(start 0.12065 -0.2794)
			(end 0.12065 -0.3048)
			(stroke
				(width 0.1)
				(type default)
			)
			(layer "F.Fab")
		)
		(fp_line
			(start 0.12065 -0.3048)
			(end 0.67945 -0.3048)
			(stroke
				(width 0.1)
				(type default)
			)
			(layer "F.Fab")
		)
		(fp_line
			(start 0.67945 -0.3048)
			(end 0.67945 0.3048)
			(stroke
				(width 0.1)
				(type default)
			)
			(layer "F.Fab")
		)
		(fp_line
			(start -0.67945 -0.305054)
			(end -0.12065 -0.305054)
			(stroke
				(width 0.1)
				(type default)
			)
			(layer "F.Fab")
		)
		(fp_line
			(start -0.12065 -0.305054)
			(end -0.12065 -0.2794)
			(stroke
				(width 0.1)
				(type default)
			)
			(layer "F.Fab")
		)
		(pad "1" smd circle
			(at -0.40005 0 270)
			(size 0 0)
			(layers "F.Cu" "F.Mask" "F.Paste")
			(net "PVCCIN_CPU0")
		)
		(pad "2" smd circle
			(at 0.40005 0 270)
			(size 0 0)
			(layers "F.Cu" "F.Mask" "F.Paste")
			(net "GND")
		)
	)
	(footprint ""
		(layer "F.Cu")
		(at 46.096428 -390.007348)
		(property "Reference" "R4646"
			(at 0 0 0)
			(layer "F.SilkS")
			(hide yes)
			(effects
				(font
					(size 1.27 1.27)
				)
			)
		)
		(property "Value" ""
			(at 0 0 0)
			(layer "F.Fab")
			(effects
				(font
					(size 1.27 1.27)
				)
			)
		)
		(duplicate_pad_numbers_are_jumpers no)
		(fp_line
			(start -0.7874 -0.4064)
			(end 0.7874 -0.4064)
			(stroke
				(width 0.1524)
				(type default)
			)
			(layer "F.SilkS")
		)
		(fp_line
			(start -0.7874 0.4064)
			(end -0.7874 -0.4064)
			(stroke
				(width 0.1524)
				(type default)
			)
			(layer "F.SilkS")
		)
		(fp_line
			(start 0.7874 -0.4064)
			(end 0.7874 0.4064)
			(stroke
				(width 0.1524)
				(type default)
			)
			(layer "F.SilkS")
		)
		(fp_line
			(start 0.7874 0.4064)
			(end -0.7874 0.4064)
			(stroke
				(width 0.1524)
				(type default)
			)
			(layer "F.SilkS")
		)
		(fp_line
			(start -0.67945 -0.305054)
			(end -0.12065 -0.305054)
			(stroke
				(width 0.1)
				(type default)
			)
			(layer "F.Fab")
		)
		(fp_line
			(start -0.67945 0.3048)
			(end -0.67945 -0.305054)
			(stroke
				(width 0.1)
				(type default)
			)
			(layer "F.Fab")
		)
		(fp_line
			(start -0.12065 -0.305054)
			(end -0.12065 -0.2794)
			(stroke
				(width 0.1)
				(type default)
			)
			(layer "F.Fab")
		)
		(fp_line
			(start -0.12065 -0.2794)
			(end 0.12065 -0.2794)
			(stroke
				(width 0.1)
				(type default)
			)
			(layer "F.Fab")
		)
		(fp_line
			(start -0.12065 0.2794)
			(end -0.12065 0.3048)
			(stroke
				(width 0.1)
				(type default)
			)
			(layer "F.Fab")
		)
		(fp_line
			(start -0.12065 0.3048)
			(end -0.67945 0.3048)
			(stroke
				(width 0.1)
				(type default)
			)
			(layer "F.Fab")
		)
		(fp_line
			(start 0.120396 0.2794)
			(end -0.12065 0.2794)
			(stroke
				(width 0.1)
				(type default)
			)
			(layer "F.Fab")
		)
		(fp_line
			(start 0.120396 0.3048)
			(end 0.120396 0.2794)
			(stroke
				(width 0.1)
				(type default)
			)
			(layer "F.Fab")
		)
		(fp_line
			(start 0.12065 -0.3048)
			(end 0.67945 -0.3048)
			(stroke
				(width 0.1)
				(type default)
			)
			(layer "F.Fab")
		)
		(fp_line
			(start 0.12065 -0.2794)
			(end 0.12065 -0.3048)
			(stroke
				(width 0.1)
				(type default)
			)
			(layer "F.Fab")
		)
		(fp_line
			(start 0.67945 -0.3048)
			(end 0.67945 0.3048)
			(stroke
				(width 0.1)
				(type default)
			)
			(layer "F.Fab")
		)
		(fp_line
			(start 0.67945 0.3048)
			(end 0.120396 0.3048)
			(stroke
				(width 0.1)
				(type default)
			)
			(layer "F.Fab")
		)
		(pad "1" smd circle
			(at -0.40005 0)
			(size 0 0)
			(layers "F.Cu" "F.Mask" "F.Paste")
			(net "FM_P2E_BUF2_EQB0")
		)
		(pad "2" smd circle
			(at 0.40005 0)
			(size 0 0)
			(layers "F.Cu" "F.Mask" "F.Paste")
			(net "GND")
		)
	)
	(footprint ""
		(layer "F.Cu")
		(at 441.353194 -375.662698 90)
		(property "Reference" "Q57"
			(at -0.4699 -6.276594 0)
			(unlocked yes)
			(layer "F.SilkS")
			(effects
				(font
					(size 0.7874 0.5842)
					(thickness 0.1524)
				)
				(justify left)
			)
		)
		(property "Value" ""
			(at 0 0 90)
			(layer "F.Fab")
			(effects
				(font
					(size 1.27 1.27)
				)
			)
		)
		(duplicate_pad_numbers_are_jumpers no)
		(fp_line
			(start 2.350008 -2.649982)
			(end 2.350008 -2.4892)
			(stroke
				(width 0.1524)
				(type default)
			)
			(layer "F.SilkS")
		)
		(fp_line
			(start -2.350008 -2.649982)
			(end 2.350008 -2.649982)
			(stroke
				(width 0.1524)
				(type default)
			)
			(layer "F.SilkS")
		)
		(fp_line
			(start -2.350008 -2.4384)
			(end -2.350008 -2.649982)
			(stroke
				(width 0.1524)
				(type default)
			)
			(layer "F.SilkS")
		)
		(fp_line
			(start 2.350008 2.4892)
			(end 2.350008 2.649982)
			(stroke
				(width 0.1524)
				(type default)
			)
			(layer "F.SilkS")
		)
		(fp_line
			(start 2.350008 2.649982)
			(end -2.350008 2.649982)
			(stroke
				(width 0.1524)
				(type default)
			)
			(layer "F.SilkS")
		)
		(fp_line
			(start -2.350008 2.649982)
			(end -2.350008 2.413)
			(stroke
				(width 0.1524)
				(type default)
			)
			(layer "F.SilkS")
		)
		(fp_poly
			(pts
				(xy -4.441444 -2.00914) (xy -5.482844 -1.62814) (xy -5.482844 -2.42824)
			)
			(stroke
				(width 0)
				(type default)
			)
			(fill yes)
			(layer "F.SilkS")
		)
		(fp_line
			(start 2.350008 -2.649982)
			(end 2.350008 2.649982)
			(stroke
				(width 0.1)
				(type default)
			)
			(layer "F.Fab")
		)
		(fp_line
			(start -2.350008 -2.649982)
			(end 2.350008 -2.649982)
			(stroke
				(width 0.1)
				(type default)
			)
			(layer "F.Fab")
		)
		(fp_line
			(start 2.350008 2.649982)
			(end -2.350008 2.649982)
			(stroke
				(width 0.1)
				(type default)
			)
			(layer "F.Fab")
		)
		(fp_line
			(start -2.350008 2.649982)
			(end -2.350008 -2.649982)
			(stroke
				(width 0.1)
				(type default)
			)
			(layer "F.Fab")
		)
		(fp_poly
			(pts
				(xy -3.717544 -1.905) (xy -4.758944 -2.3241) (xy -4.758944 -1.524)
			)
			(stroke
				(width 0)
				(type default)
			)
			(fill yes)
			(layer "F.Fab")
		)
		(pad "1" smd rect
			(at -2.999994 -1.905)
			(size 0.7112 1.1684)
			(layers "F.Cu" "F.Mask" "F.Paste")
			(net "P5V")
		)
		(pad "2" smd rect
			(at -2.999994 -0.635)
			(size 0.7112 1.1684)
			(layers "F.Cu" "F.Mask" "F.Paste")
			(net "P5V")
		)
		(pad "3" smd rect
			(at -2.999994 0.635)
			(size 0.7112 1.1684)
			(layers "F.Cu" "F.Mask" "F.Paste")
			(net "P5V")
		)
		(pad "4" smd rect
			(at -2.999994 1.905)
			(size 0.7112 1.1684)
			(layers "F.Cu" "F.Mask" "F.Paste")
			(net "VR_P5V_EN_D_R")
		)
		(pad "5" smd circle
			(at 0.925068 0)
			(size 0 0)
			(layers "F.Cu" "F.Mask" "F.Paste")
			(net "P5V_AUX")
		)
		(zone
			(layer "F.Cu")
			(hatch none 0.5)
			(connect_pads
				(clearance 0)
			)
			(min_thickness 0.25)
			(keepout
				(tracks not_allowed)
				(vias allowed)
				(pads allowed)
				(copperpour not_allowed)
				(footprints allowed)
			)
			(placement
				(enabled no)
				(sheetname "")
			)
			(fill
				(thermal_gap 0.5)
				(thermal_bridge_width 0.5)
				(island_removal_mode 0)
			)
			(polygon
				(pts
					(xy 439.194194 -374.272048) (xy 439.194194 -374.214898) (xy 443.512194 -374.214898) (xy 443.512194 -374.277128)
					(xy 443.994794 -374.277128) (xy 443.994794 -373.313198) (xy 438.711594 -373.313198) (xy 438.711594 -374.272048)
				)
			)
		)
	)
	(footprint ""
		(layer "F.Cu")
		(at 77.910944 -74.901552 -90)
		(property "Reference" "R3087"
			(at 0 0 270)
			(layer "F.SilkS")
			(hide yes)
			(effects
				(font
					(size 1.27 1.27)
				)
			)
		)
		(property "Value" ""
			(at 0 0 270)
			(layer "F.Fab")
			(effects
				(font
					(size 1.27 1.27)
				)
			)
		)
		(duplicate_pad_numbers_are_jumpers no)
		(fp_line
			(start -0.7874 0.4064)
			(end -0.7874 -0.4064)
			(stroke
				(width 0.1524)
				(type default)
			)
			(layer "F.SilkS")
		)
		(fp_line
			(start 0.7874 0.4064)
			(end -0.7874 0.4064)
			(stroke
				(width 0.1524)
				(type default)
			)
			(layer "F.SilkS")
		)
		(fp_line
			(start -0.7874 -0.4064)
			(end 0.7874 -0.4064)
			(stroke
				(width 0.1524)
				(type default)
			)
			(layer "F.SilkS")
		)
		(fp_line
			(start 0.7874 -0.4064)
			(end 0.7874 0.4064)
			(stroke
				(width 0.1524)
				(type default)
			)
			(layer "F.SilkS")
		)
		(fp_line
			(start -0.67945 0.3048)
			(end -0.67945 -0.305054)
			(stroke
				(width 0.1)
				(type default)
			)
			(layer "F.Fab")
		)
		(fp_line
			(start -0.12065 0.3048)
			(end -0.67945 0.3048)
			(stroke
				(width 0.1)
				(type default)
			)
			(layer "F.Fab")
		)
		(fp_line
			(start 0.120396 0.3048)
			(end 0.120396 0.2794)
			(stroke
				(width 0.1)
				(type default)
			)
			(layer "F.Fab")
		)
		(fp_line
			(start 0.67945 0.3048)
			(end 0.120396 0.3048)
			(stroke
				(width 0.1)
				(type default)
			)
			(layer "F.Fab")
		)
		(fp_line
			(start -0.12065 0.2794)
			(end -0.12065 0.3048)
			(stroke
				(width 0.1)
				(type default)
			)
			(layer "F.Fab")
		)
		(fp_line
			(start 0.120396 0.2794)
			(end -0.12065 0.2794)
			(stroke
				(width 0.1)
				(type default)
			)
			(layer "F.Fab")
		)
		(fp_line
			(start -0.12065 -0.2794)
			(end 0.12065 -0.2794)
			(stroke
				(width 0.1)
				(type default)
			)
			(layer "F.Fab")
		)
		(fp_line
			(start 0.12065 -0.2794)
			(end 0.12065 -0.3048)
			(stroke
				(width 0.1)
				(type default)
			)
			(layer "F.Fab")
		)
		(fp_line
			(start 0.12065 -0.3048)
			(end 0.67945 -0.3048)
			(stroke
				(width 0.1)
				(type default)
			)
			(layer "F.Fab")
		)
		(fp_line
			(start 0.67945 -0.3048)
			(end 0.67945 0.3048)
			(stroke
				(width 0.1)
				(type default)
			)
			(layer "F.Fab")
		)
		(fp_line
			(start -0.67945 -0.305054)
			(end -0.12065 -0.305054)
			(stroke
				(width 0.1)
				(type default)
			)
			(layer "F.Fab")
		)
		(fp_line
			(start -0.12065 -0.305054)
			(end -0.12065 -0.2794)
			(stroke
				(width 0.1)
				(type default)
			)
			(layer "F.Fab")
		)
		(pad "1" smd circle
			(at -0.40005 0 270)
			(size 0 0)
			(layers "F.Cu" "F.Mask" "F.Paste")
			(net "LED_PWRGD_PVPP_HBM_CPU0")
		)
		(pad "2" smd circle
			(at 0.40005 0 270)
			(size 0 0)
			(layers "F.Cu" "F.Mask" "F.Paste")
			(net "P3V3_AUX")
		)
	)
	(footprint ""
		(layer "F.Cu")
		(at 353.851972 -353.137724)
		(property "Reference" "PC331"
			(at 0 0 0)
			(layer "F.SilkS")
			(hide yes)
			(effects
				(font
					(size 1.27 1.27)
				)
			)
		)
		(property "Value" ""
			(at 0 0 0)
			(layer "F.Fab")
			(effects
				(font
					(size 1.27 1.27)
				)
			)
		)
		(duplicate_pad_numbers_are_jumpers no)
		(fp_line
			(start -0.7874 -0.4064)
			(end 0.7874 -0.4064)
			(stroke
				(width 0.1524)
				(type default)
			)
			(layer "F.SilkS")
		)
		(fp_line
			(start -0.7874 0.4064)
			(end -0.7874 -0.4064)
			(stroke
				(width 0.1524)
				(type default)
			)
			(layer "F.SilkS")
		)
		(fp_line
			(start 0.7874 -0.4064)
			(end 0.7874 0.4064)
			(stroke
				(width 0.1524)
				(type default)
			)
			(layer "F.SilkS")
		)
		(fp_line
			(start 0.7874 0.4064)
			(end -0.7874 0.4064)
			(stroke
				(width 0.1524)
				(type default)
			)
			(layer "F.SilkS")
		)
		(fp_line
			(start -0.67945 -0.305054)
			(end -0.12065 -0.305054)
			(stroke
				(width 0.1)
				(type default)
			)
			(layer "F.Fab")
		)
		(fp_line
			(start -0.67945 0.3048)
			(end -0.67945 -0.305054)
			(stroke
				(width 0.1)
				(type default)
			)
			(layer "F.Fab")
		)
		(fp_line
			(start -0.12065 -0.305054)
			(end -0.12065 -0.2794)
			(stroke
				(width 0.1)
				(type default)
			)
			(layer "F.Fab")
		)
		(fp_line
			(start -0.12065 -0.2794)
			(end 0.12065 -0.2794)
			(stroke
				(width 0.1)
				(type default)
			)
			(layer "F.Fab")
		)
		(fp_line
			(start -0.12065 0.2794)
			(end -0.12065 0.3048)
			(stroke
				(width 0.1)
				(type default)
			)
			(layer "F.Fab")
		)
		(fp_line
			(start -0.12065 0.3048)
			(end -0.67945 0.3048)
			(stroke
				(width 0.1)
				(type default)
			)
			(layer "F.Fab")
		)
		(fp_line
			(start 0.120396 0.2794)
			(end -0.12065 0.2794)
			(stroke
				(width 0.1)
				(type default)
			)
			(layer "F.Fab")
		)
		(fp_line
			(start 0.120396 0.3048)
			(end 0.120396 0.2794)
			(stroke
				(width 0.1)
				(type default)
			)
			(layer "F.Fab")
		)
		(fp_line
			(start 0.12065 -0.3048)
			(end 0.67945 -0.3048)
			(stroke
				(width 0.1)
				(type default)
			)
			(layer "F.Fab")
		)
		(fp_line
			(start 0.12065 -0.2794)
			(end 0.12065 -0.3048)
			(stroke
				(width 0.1)
				(type default)
			)
			(layer "F.Fab")
		)
		(fp_line
			(start 0.67945 -0.3048)
			(end 0.67945 0.3048)
			(stroke
				(width 0.1)
				(type default)
			)
			(layer "F.Fab")
		)
		(fp_line
			(start 0.67945 0.3048)
			(end 0.120396 0.3048)
			(stroke
				(width 0.1)
				(type default)
			)
			(layer "F.Fab")
		)
		(pad "1" smd circle
			(at -0.40005 0)
			(size 0 0)
			(layers "F.Cu" "F.Mask" "F.Paste")
			(net "SH_PVCCIN_CPU0_R")
		)
		(pad "2" smd circle
			(at 0.40005 0)
			(size 0 0)
			(layers "F.Cu" "F.Mask" "F.Paste")
			(net "VSENSE_PVCCIN_CPU0_DN")
		)
	)
	(footprint ""
		(layer "F.Cu")
		(at 422.497504 -131.975352 -90)
		(property "Reference" "PC1372"
			(at 0 0 270)
			(layer "F.SilkS")
			(hide yes)
			(effects
				(font
					(size 1.27 1.27)
				)
			)
		)
		(property "Value" ""
			(at 0 0 270)
			(layer "F.Fab")
			(effects
				(font
					(size 1.27 1.27)
				)
			)
		)
		(duplicate_pad_numbers_are_jumpers no)
		(fp_line
			(start -0.7874 0.4064)
			(end -0.7874 -0.4064)
			(stroke
				(width 0.1524)
				(type default)
			)
			(layer "F.SilkS")
		)
		(fp_line
			(start 0.7874 0.4064)
			(end -0.7874 0.4064)
			(stroke
				(width 0.1524)
				(type default)
			)
			(layer "F.SilkS")
		)
		(fp_line
			(start -0.7874 -0.4064)
			(end 0.7874 -0.4064)
			(stroke
				(width 0.1524)
				(type default)
			)
			(layer "F.SilkS")
		)
		(fp_line
			(start 0.7874 -0.4064)
			(end 0.7874 0.4064)
			(stroke
				(width 0.1524)
				(type default)
			)
			(layer "F.SilkS")
		)
		(fp_line
			(start -0.67945 0.3048)
			(end -0.67945 -0.305054)
			(stroke
				(width 0.1)
				(type default)
			)
			(layer "F.Fab")
		)
		(fp_line
			(start -0.12065 0.3048)
			(end -0.67945 0.3048)
			(stroke
				(width 0.1)
				(type default)
			)
			(layer "F.Fab")
		)
		(fp_line
			(start 0.120396 0.3048)
			(end 0.120396 0.2794)
			(stroke
				(width 0.1)
				(type default)
			)
			(layer "F.Fab")
		)
		(fp_line
			(start 0.67945 0.3048)
			(end 0.120396 0.3048)
			(stroke
				(width 0.1)
				(type default)
			)
			(layer "F.Fab")
		)
		(fp_line
			(start -0.12065 0.2794)
			(end -0.12065 0.3048)
			(stroke
				(width 0.1)
				(type default)
			)
			(layer "F.Fab")
		)
		(fp_line
			(start 0.120396 0.2794)
			(end -0.12065 0.2794)
			(stroke
				(width 0.1)
				(type default)
			)
			(layer "F.Fab")
		)
		(fp_line
			(start -0.12065 -0.2794)
			(end 0.12065 -0.2794)
			(stroke
				(width 0.1)
				(type default)
			)
			(layer "F.Fab")
		)
		(fp_line
			(start 0.12065 -0.2794)
			(end 0.12065 -0.3048)
			(stroke
				(width 0.1)
				(type default)
			)
			(layer "F.Fab")
		)
		(fp_line
			(start 0.12065 -0.3048)
			(end 0.67945 -0.3048)
			(stroke
				(width 0.1)
				(type default)
			)
			(layer "F.Fab")
		)
		(fp_line
			(start 0.67945 -0.3048)
			(end 0.67945 0.3048)
			(stroke
				(width 0.1)
				(type default)
			)
			(layer "F.Fab")
		)
		(fp_line
			(start -0.67945 -0.305054)
			(end -0.12065 -0.305054)
			(stroke
				(width 0.1)
				(type default)
			)
			(layer "F.Fab")
		)
		(fp_line
			(start -0.12065 -0.305054)
			(end -0.12065 -0.2794)
			(stroke
				(width 0.1)
				(type default)
			)
			(layer "F.Fab")
		)
		(pad "1" smd circle
			(at -0.40005 0 270)
			(size 0 0)
			(layers "F.Cu" "F.Mask" "F.Paste")
			(net "PVCCINFAON_CPU0_VREF")
		)
		(pad "2" smd circle
			(at 0.40005 0 270)
			(size 0 0)
			(layers "F.Cu" "F.Mask" "F.Paste")
			(net "GND")
		)
	)
	(footprint ""
		(layer "F.Cu")
		(at 337.730084 -27.678126 -90)
		(property "Reference" "R913"
			(at 0 0 270)
			(layer "F.SilkS")
			(hide yes)
			(effects
				(font
					(size 1.27 1.27)
				)
			)
		)
		(property "Value" ""
			(at 0 0 270)
			(layer "F.Fab")
			(effects
				(font
					(size 1.27 1.27)
				)
			)
		)
		(duplicate_pad_numbers_are_jumpers no)
		(fp_line
			(start -0.7874 0.4064)
			(end -0.7874 -0.4064)
			(stroke
				(width 0.1524)
				(type default)
			)
			(layer "F.SilkS")
		)
		(fp_line
			(start 0.7874 0.4064)
			(end -0.7874 0.4064)
			(stroke
				(width 0.1524)
				(type default)
			)
			(layer "F.SilkS")
		)
		(fp_line
			(start -0.7874 -0.4064)
			(end 0.7874 -0.4064)
			(stroke
				(width 0.1524)
				(type default)
			)
			(layer "F.SilkS")
		)
		(fp_line
			(start 0.7874 -0.4064)
			(end 0.7874 0.4064)
			(stroke
				(width 0.1524)
				(type default)
			)
			(layer "F.SilkS")
		)
		(fp_line
			(start -0.67945 0.3048)
			(end -0.67945 -0.305054)
			(stroke
				(width 0.1)
				(type default)
			)
			(layer "F.Fab")
		)
		(fp_line
			(start -0.12065 0.3048)
			(end -0.67945 0.3048)
			(stroke
				(width 0.1)
				(type default)
			)
			(layer "F.Fab")
		)
		(fp_line
			(start 0.120396 0.3048)
			(end 0.120396 0.2794)
			(stroke
				(width 0.1)
				(type default)
			)
			(layer "F.Fab")
		)
		(fp_line
			(start 0.67945 0.3048)
			(end 0.120396 0.3048)
			(stroke
				(width 0.1)
				(type default)
			)
			(layer "F.Fab")
		)
		(fp_line
			(start -0.12065 0.2794)
			(end -0.12065 0.3048)
			(stroke
				(width 0.1)
				(type default)
			)
			(layer "F.Fab")
		)
		(fp_line
			(start 0.120396 0.2794)
			(end -0.12065 0.2794)
			(stroke
				(width 0.1)
				(type default)
			)
			(layer "F.Fab")
		)
		(fp_line
			(start -0.12065 -0.2794)
			(end 0.12065 -0.2794)
			(stroke
				(width 0.1)
				(type default)
			)
			(layer "F.Fab")
		)
		(fp_line
			(start 0.12065 -0.2794)
			(end 0.12065 -0.3048)
			(stroke
				(width 0.1)
				(type default)
			)
			(layer "F.Fab")
		)
		(fp_line
			(start 0.12065 -0.3048)
			(end 0.67945 -0.3048)
			(stroke
				(width 0.1)
				(type default)
			)
			(layer "F.Fab")
		)
		(fp_line
			(start 0.67945 -0.3048)
			(end 0.67945 0.3048)
			(stroke
				(width 0.1)
				(type default)
			)
			(layer "F.Fab")
		)
		(fp_line
			(start -0.67945 -0.305054)
			(end -0.12065 -0.305054)
			(stroke
				(width 0.1)
				(type default)
			)
			(layer "F.Fab")
		)
		(fp_line
			(start -0.12065 -0.305054)
			(end -0.12065 -0.2794)
			(stroke
				(width 0.1)
				(type default)
			)
			(layer "F.Fab")
		)
		(pad "1" smd circle
			(at -0.40005 0 270)
			(size 0 0)
			(layers "F.Cu" "F.Mask" "F.Paste")
			(net "PU_OC6_USB_N")
		)
		(pad "2" smd circle
			(at 0.40005 0 270)
			(size 0 0)
			(layers "F.Cu" "F.Mask" "F.Paste")
			(net "P3V3_AUX")
		)
	)
	(footprint ""
		(layer "F.Cu")
		(at 312.443622 -38.89121 180)
		(property "Reference" "R4100"
			(at 0 0 180)
			(layer "F.SilkS")
			(hide yes)
			(effects
				(font
					(size 1.27 1.27)
				)
			)
		)
		(property "Value" ""
			(at 0 0 180)
			(layer "F.Fab")
			(effects
				(font
					(size 1.27 1.27)
				)
			)
		)
		(duplicate_pad_numbers_are_jumpers no)
		(fp_line
			(start 0.7874 0.4064)
			(end -0.7874 0.4064)
			(stroke
				(width 0.1524)
				(type default)
			)
			(layer "F.SilkS")
		)
		(fp_line
			(start 0.7874 -0.4064)
			(end 0.7874 0.4064)
			(stroke
				(width 0.1524)
				(type default)
			)
			(layer "F.SilkS")
		)
		(fp_line
			(start -0.7874 0.4064)
			(end -0.7874 -0.4064)
			(stroke
				(width 0.1524)
				(type default)
			)
			(layer "F.SilkS")
		)
		(fp_line
			(start -0.7874 -0.4064)
			(end 0.7874 -0.4064)
			(stroke
				(width 0.1524)
				(type default)
			)
			(layer "F.SilkS")
		)
		(fp_line
			(start 0.67945 0.3048)
			(end 0.120396 0.3048)
			(stroke
				(width 0.1)
				(type default)
			)
			(layer "F.Fab")
		)
		(fp_line
			(start 0.67945 -0.3048)
			(end 0.67945 0.3048)
			(stroke
				(width 0.1)
				(type default)
			)
			(layer "F.Fab")
		)
		(fp_line
			(start 0.12065 -0.2794)
			(end 0.12065 -0.3048)
			(stroke
				(width 0.1)
				(type default)
			)
			(layer "F.Fab")
		)
		(fp_line
			(start 0.12065 -0.3048)
			(end 0.67945 -0.3048)
			(stroke
				(width 0.1)
				(type default)
			)
			(layer "F.Fab")
		)
		(fp_line
			(start 0.120396 0.3048)
			(end 0.120396 0.2794)
			(stroke
				(width 0.1)
				(type default)
			)
			(layer "F.Fab")
		)
		(fp_line
			(start 0.120396 0.2794)
			(end -0.12065 0.2794)
			(stroke
				(width 0.1)
				(type default)
			)
			(layer "F.Fab")
		)
		(fp_line
			(start -0.12065 0.3048)
			(end -0.67945 0.3048)
			(stroke
				(width 0.1)
				(type default)
			)
			(layer "F.Fab")
		)
		(fp_line
			(start -0.12065 0.2794)
			(end -0.12065 0.3048)
			(stroke
				(width 0.1)
				(type default)
			)
			(layer "F.Fab")
		)
		(fp_line
			(start -0.12065 -0.2794)
			(end 0.12065 -0.2794)
			(stroke
				(width 0.1)
				(type default)
			)
			(layer "F.Fab")
		)
		(fp_line
			(start -0.12065 -0.305054)
			(end -0.12065 -0.2794)
			(stroke
				(width 0.1)
				(type default)
			)
			(layer "F.Fab")
		)
		(fp_line
			(start -0.67945 0.3048)
			(end -0.67945 -0.305054)
			(stroke
				(width 0.1)
				(type default)
			)
			(layer "F.Fab")
		)
		(fp_line
			(start -0.67945 -0.305054)
			(end -0.12065 -0.305054)
			(stroke
				(width 0.1)
				(type default)
			)
			(layer "F.Fab")
		)
		(pad "1" smd circle
			(at -0.40005 0 180)
			(size 0 0)
			(layers "F.Cu" "F.Mask" "F.Paste")
			(net "PD_PCH_GPPC_C10")
		)
		(pad "2" smd circle
			(at 0.40005 0 180)
			(size 0 0)
			(layers "F.Cu" "F.Mask" "F.Paste")
			(net "GND")
		)
	)
	(footprint ""
		(layer "F.Cu")
		(at 342.43899 -70.03796 90)
		(property "Reference" "C153"
			(at 0 0 90)
			(layer "F.SilkS")
			(hide yes)
			(effects
				(font
					(size 1.27 1.27)
				)
			)
		)
		(property "Value" ""
			(at 0 0 90)
			(layer "F.Fab")
			(effects
				(font
					(size 1.27 1.27)
				)
			)
		)
		(duplicate_pad_numbers_are_jumpers no)
		(fp_line
			(start 0.299974 -0.150114)
			(end 0.299974 0.150114)
			(stroke
				(width 0.1)
				(type default)
			)
			(layer "F.Fab")
		)
		(fp_line
			(start -0.299974 -0.150114)
			(end 0.299974 -0.150114)
			(stroke
				(width 0.1)
				(type default)
			)
			(layer "F.Fab")
		)
		(fp_line
			(start 0.299974 0.150114)
			(end -0.299974 0.150114)
			(stroke
				(width 0.1)
				(type default)
			)
			(layer "F.Fab")
		)
		(fp_line
			(start -0.299974 0.150114)
			(end -0.299974 -0.150114)
			(stroke
				(width 0.1)
				(type default)
			)
			(layer "F.Fab")
		)
		(pad "1" smd rect
			(at -0.2667 0 90)
			(size 0.3048 0.381)
			(layers "F.Cu" "F.Mask" "F.Paste")
			(net "DMI_CPU0_PCH_TX_C_DN<0>")
		)
		(pad "2" smd rect
			(at 0.2667 0 90)
			(size 0.3048 0.381)
			(layers "F.Cu" "F.Mask" "F.Paste")
			(net "DMI_CPU0_PCH_TX_DN<0>")
		)
	)
	(footprint ""
		(layer "F.Cu")
		(at 64.614298 -23.554182)
		(property "Reference" "PR3857"
			(at 0 0 0)
			(layer "F.SilkS")
			(hide yes)
			(effects
				(font
					(size 1.27 1.27)
				)
			)
		)
		(property "Value" ""
			(at 0 0 0)
			(layer "F.Fab")
			(effects
				(font
					(size 1.27 1.27)
				)
			)
		)
		(duplicate_pad_numbers_are_jumpers no)
		(fp_line
			(start -1.2954 -0.5842)
			(end 1.2954 -0.5842)
			(stroke
				(width 0.1524)
				(type default)
			)
			(layer "F.SilkS")
		)
		(fp_line
			(start -1.2954 0.5842)
			(end -1.2954 -0.5842)
			(stroke
				(width 0.1524)
				(type default)
			)
			(layer "F.SilkS")
		)
		(fp_line
			(start 1.2954 -0.5842)
			(end 1.2954 0.5842)
			(stroke
				(width 0.1524)
				(type default)
			)
			(layer "F.SilkS")
		)
		(fp_line
			(start 1.2954 0.5842)
			(end -1.2954 0.5842)
			(stroke
				(width 0.1524)
				(type default)
			)
			(layer "F.SilkS")
		)
		(fp_line
			(start -1.1938 -0.406654)
			(end -0.8636 -0.406654)
			(stroke
				(width 0.1)
				(type default)
			)
			(layer "F.Fab")
		)
		(fp_line
			(start -1.1938 0.4064)
			(end -1.1938 -0.406654)
			(stroke
				(width 0.1)
				(type default)
			)
			(layer "F.Fab")
		)
		(fp_line
			(start -0.8636 -0.4572)
			(end 0.8636 -0.4572)
			(stroke
				(width 0.1)
				(type default)
			)
			(layer "F.Fab")
		)
		(fp_line
			(start -0.8636 -0.406654)
			(end -0.8636 -0.4572)
			(stroke
				(width 0.1)
				(type default)
			)
			(layer "F.Fab")
		)
		(fp_line
			(start -0.8636 0.4064)
			(end -1.1938 0.4064)
			(stroke
				(width 0.1)
				(type default)
			)
			(layer "F.Fab")
		)
		(fp_line
			(start -0.8636 0.4318)
			(end -0.8636 0.4064)
			(stroke
				(width 0.1)
				(type default)
			)
			(layer "F.Fab")
		)
		(fp_line
			(start -0.8636 0.4572)
			(end -0.8636 0.4318)
			(stroke
				(width 0.1)
				(type default)
			)
			(layer "F.Fab")
		)
		(fp_line
			(start 0.8636 -0.4572)
			(end 0.8636 -0.406654)
			(stroke
				(width 0.1)
				(type default)
			)
			(layer "F.Fab")
		)
		(fp_line
			(start 0.8636 -0.406654)
			(end 1.1938 -0.406654)
			(stroke
				(width 0.1)
				(type default)
			)
			(layer "F.Fab")
		)
		(fp_line
			(start 0.8636 0.4064)
			(end 0.8636 0.4572)
			(stroke
				(width 0.1)
				(type default)
			)
			(layer "F.Fab")
		)
		(fp_line
			(start 0.8636 0.4572)
			(end -0.8636 0.4572)
			(stroke
				(width 0.1)
				(type default)
			)
			(layer "F.Fab")
		)
		(fp_line
			(start 1.1938 -0.406654)
			(end 1.1938 0.4064)
			(stroke
				(width 0.1)
				(type default)
			)
			(layer "F.Fab")
		)
		(fp_line
			(start 1.1938 0.4064)
			(end 0.8636 0.4064)
			(stroke
				(width 0.1)
				(type default)
			)
			(layer "F.Fab")
		)
		(pad "1" smd rect
			(at -0.7366 0 270)
			(size 0.7112 0.8128)
			(layers "F.Cu" "F.Mask" "F.Paste")
			(net "P12V_AUX")
		)
		(pad "2" smd rect
			(at 0.7366 0 270)
			(size 0.7112 0.8128)
			(layers "F.Cu" "F.Mask" "F.Paste")
			(net "P12V_OCP_AVIN_PD_2")
		)
	)
	(footprint ""
		(layer "F.Cu")
		(at 362.546646 -365.287814 90)
		(property "Reference" "PC335"
			(at 0 0 90)
			(layer "F.SilkS")
			(hide yes)
			(effects
				(font
					(size 1.27 1.27)
				)
			)
		)
		(property "Value" ""
			(at 0 0 90)
			(layer "F.Fab")
			(effects
				(font
					(size 1.27 1.27)
				)
			)
		)
		(duplicate_pad_numbers_are_jumpers no)
		(fp_line
			(start 0.7874 -0.4064)
			(end 0.7874 0.4064)
			(stroke
				(width 0.1524)
				(type default)
			)
			(layer "F.SilkS")
		)
		(fp_line
			(start -0.7874 -0.4064)
			(end 0.7874 -0.4064)
			(stroke
				(width 0.1524)
				(type default)
			)
			(layer "F.SilkS")
		)
		(fp_line
			(start 0.7874 0.4064)
			(end -0.7874 0.4064)
			(stroke
				(width 0.1524)
				(type default)
			)
			(layer "F.SilkS")
		)
		(fp_line
			(start -0.7874 0.4064)
			(end -0.7874 -0.4064)
			(stroke
				(width 0.1524)
				(type default)
			)
			(layer "F.SilkS")
		)
		(fp_line
			(start -0.12065 -0.305054)
			(end -0.12065 -0.2794)
			(stroke
				(width 0.1)
				(type default)
			)
			(layer "F.Fab")
		)
		(fp_line
			(start -0.67945 -0.305054)
			(end -0.12065 -0.305054)
			(stroke
				(width 0.1)
				(type default)
			)
			(layer "F.Fab")
		)
		(fp_line
			(start 0.67945 -0.3048)
			(end 0.67945 0.3048)
			(stroke
				(width 0.1)
				(type default)
			)
			(layer "F.Fab")
		)
		(fp_line
			(start 0.12065 -0.3048)
			(end 0.67945 -0.3048)
			(stroke
				(width 0.1)
				(type default)
			)
			(layer "F.Fab")
		)
		(fp_line
			(start 0.12065 -0.2794)
			(end 0.12065 -0.3048)
			(stroke
				(width 0.1)
				(type default)
			)
			(layer "F.Fab")
		)
		(fp_line
			(start -0.12065 -0.2794)
			(end 0.12065 -0.2794)
			(stroke
				(width 0.1)
				(type default)
			)
			(layer "F.Fab")
		)
		(fp_line
			(start 0.120396 0.2794)
			(end -0.12065 0.2794)
			(stroke
				(width 0.1)
				(type default)
			)
			(layer "F.Fab")
		)
		(fp_line
			(start -0.12065 0.2794)
			(end -0.12065 0.3048)
			(stroke
				(width 0.1)
				(type default)
			)
			(layer "F.Fab")
		)
		(fp_line
			(start 0.67945 0.3048)
			(end 0.120396 0.3048)
			(stroke
				(width 0.1)
				(type default)
			)
			(layer "F.Fab")
		)
		(fp_line
			(start 0.120396 0.3048)
			(end 0.120396 0.2794)
			(stroke
				(width 0.1)
				(type default)
			)
			(layer "F.Fab")
		)
		(fp_line
			(start -0.12065 0.3048)
			(end -0.67945 0.3048)
			(stroke
				(width 0.1)
				(type default)
			)
			(layer "F.Fab")
		)
		(fp_line
			(start -0.67945 0.3048)
			(end -0.67945 -0.305054)
			(stroke
				(width 0.1)
				(type default)
			)
			(layer "F.Fab")
		)
		(pad "1" smd circle
			(at -0.40005 0 90)
			(size 0 0)
			(layers "F.Cu" "F.Mask" "F.Paste")
			(net "PVCCIN_CPU0_VREF")
		)
		(pad "2" smd circle
			(at 0.40005 0 90)
			(size 0 0)
			(layers "F.Cu" "F.Mask" "F.Paste")
			(net "GND")
		)
	)
	(footprint ""
		(layer "F.Cu")
		(at 44.36999 -164.39134)
		(property "Reference" "PC461"
			(at 0 0 0)
			(layer "F.SilkS")
			(hide yes)
			(effects
				(font
					(size 1.27 1.27)
				)
			)
		)
		(property "Value" ""
			(at 0 0 0)
			(layer "F.Fab")
			(effects
				(font
					(size 1.27 1.27)
				)
			)
		)
		(duplicate_pad_numbers_are_jumpers no)
		(fp_line
			(start -3.400044 1.249934)
			(end 3.400044 1.249934)
			(stroke
				(width 0.1524)
				(type default)
			)
			(layer "F.SilkS")
		)
		(fp_circle
			(center 0 1.249934)
			(end 3.400044 1.249934)
			(stroke
				(width 0.1524)
				(type default)
			)
			(fill no)
			(layer "F.SilkS")
		)
		(fp_poly
			(pts
				(arc
					(start -3.400044 1.249934)
					(mid 0 4.649978)
					(end 3.400044 1.249934)
				)
			)
			(stroke
				(width 0)
				(type default)
			)
			(fill yes)
			(layer "F.SilkS")
		)
		(fp_circle
			(center 0 1.249934)
			(end 3.400044 1.249934)
			(stroke
				(width 0.1)
				(type default)
			)
			(fill no)
			(layer "F.Fab")
		)
		(pad "1" thru_hole rect
			(at 0 0)
			(size 1.524 1.524)
			(drill 1.016)
			(layers "*.Cu" "*.Mask")
			(remove_unused_layers no)
			(net "SW_P12V_PVCCINFAON_CPU1_FLT")
			(clearance 0)
			(padstack
				(mode front_inner_back)
				(layer "Inner"
					(shape circle)
					(size 1.524 1.524)
					(clearance 0)
				)
				(layer "B.Cu"
					(shape rect)
					(size 1.524 1.524)
					(clearance 0)
				)
			)
		)
		(pad "2" thru_hole circle
			(at 0 2.500122)
			(size 1.524 1.524)
			(drill 1.016)
			(layers "*.Cu" "*.Mask")
			(remove_unused_layers no)
			(net "GND")
			(clearance 0)
		)
	)
	(footprint ""
		(layer "F.Cu")
		(at 445.19088 -97.269808 180)
		(property "Reference" "R3600"
			(at 0 0 180)
			(layer "F.SilkS")
			(hide yes)
			(effects
				(font
					(size 1.27 1.27)
				)
			)
		)
		(property "Value" ""
			(at 0 0 180)
			(layer "F.Fab")
			(effects
				(font
					(size 1.27 1.27)
				)
			)
		)
		(duplicate_pad_numbers_are_jumpers no)
		(fp_line
			(start 0.7874 0.4064)
			(end -0.7874 0.4064)
			(stroke
				(width 0.1524)
				(type default)
			)
			(layer "F.SilkS")
		)
		(fp_line
			(start 0.7874 -0.4064)
			(end 0.7874 0.4064)
			(stroke
				(width 0.1524)
				(type default)
			)
			(layer "F.SilkS")
		)
		(fp_line
			(start -0.7874 0.4064)
			(end -0.7874 -0.4064)
			(stroke
				(width 0.1524)
				(type default)
			)
			(layer "F.SilkS")
		)
		(fp_line
			(start -0.7874 -0.4064)
			(end 0.7874 -0.4064)
			(stroke
				(width 0.1524)
				(type default)
			)
			(layer "F.SilkS")
		)
		(fp_line
			(start 0.67945 0.3048)
			(end 0.120396 0.3048)
			(stroke
				(width 0.1)
				(type default)
			)
			(layer "F.Fab")
		)
		(fp_line
			(start 0.67945 -0.3048)
			(end 0.67945 0.3048)
			(stroke
				(width 0.1)
				(type default)
			)
			(layer "F.Fab")
		)
		(fp_line
			(start 0.12065 -0.2794)
			(end 0.12065 -0.3048)
			(stroke
				(width 0.1)
				(type default)
			)
			(layer "F.Fab")
		)
		(fp_line
			(start 0.12065 -0.3048)
			(end 0.67945 -0.3048)
			(stroke
				(width 0.1)
				(type default)
			)
			(layer "F.Fab")
		)
		(fp_line
			(start 0.120396 0.3048)
			(end 0.120396 0.2794)
			(stroke
				(width 0.1)
				(type default)
			)
			(layer "F.Fab")
		)
		(fp_line
			(start 0.120396 0.2794)
			(end -0.12065 0.2794)
			(stroke
				(width 0.1)
				(type default)
			)
			(layer "F.Fab")
		)
		(fp_line
			(start -0.12065 0.3048)
			(end -0.67945 0.3048)
			(stroke
				(width 0.1)
				(type default)
			)
			(layer "F.Fab")
		)
		(fp_line
			(start -0.12065 0.2794)
			(end -0.12065 0.3048)
			(stroke
				(width 0.1)
				(type default)
			)
			(layer "F.Fab")
		)
		(fp_line
			(start -0.12065 -0.2794)
			(end 0.12065 -0.2794)
			(stroke
				(width 0.1)
				(type default)
			)
			(layer "F.Fab")
		)
		(fp_line
			(start -0.12065 -0.305054)
			(end -0.12065 -0.2794)
			(stroke
				(width 0.1)
				(type default)
			)
			(layer "F.Fab")
		)
		(fp_line
			(start -0.67945 0.3048)
			(end -0.67945 -0.305054)
			(stroke
				(width 0.1)
				(type default)
			)
			(layer "F.Fab")
		)
		(fp_line
			(start -0.67945 -0.305054)
			(end -0.12065 -0.305054)
			(stroke
				(width 0.1)
				(type default)
			)
			(layer "F.Fab")
		)
		(pad "1" smd circle
			(at -0.40005 0 180)
			(size 0 0)
			(layers "F.Cu" "F.Mask" "F.Paste")
			(net "SMB_INA230_1_3V3AUX_SCL_R")
		)
		(pad "2" smd circle
			(at 0.40005 0 180)
			(size 0 0)
			(layers "F.Cu" "F.Mask" "F.Paste")
			(net "SMB_INA230_1_3V3AUX_SCL_R1")
		)
	)
	(footprint ""
		(layer "F.Cu")
		(at 204.333348 -68.5292)
		(property "Reference" "R4711"
			(at 0 0 0)
			(layer "F.SilkS")
			(hide yes)
			(effects
				(font
					(size 1.27 1.27)
				)
			)
		)
		(property "Value" ""
			(at 0 0 0)
			(layer "F.Fab")
			(effects
				(font
					(size 1.27 1.27)
				)
			)
		)
		(duplicate_pad_numbers_are_jumpers no)
		(fp_line
			(start -0.7874 -0.4064)
			(end 0.7874 -0.4064)
			(stroke
				(width 0.1524)
				(type default)
			)
			(layer "F.SilkS")
		)
		(fp_line
			(start -0.7874 0.4064)
			(end -0.7874 -0.4064)
			(stroke
				(width 0.1524)
				(type default)
			)
			(layer "F.SilkS")
		)
		(fp_line
			(start 0.7874 -0.4064)
			(end 0.7874 0.4064)
			(stroke
				(width 0.1524)
				(type default)
			)
			(layer "F.SilkS")
		)
		(fp_line
			(start 0.7874 0.4064)
			(end -0.7874 0.4064)
			(stroke
				(width 0.1524)
				(type default)
			)
			(layer "F.SilkS")
		)
		(fp_line
			(start -0.67945 -0.305054)
			(end -0.12065 -0.305054)
			(stroke
				(width 0.1)
				(type default)
			)
			(layer "F.Fab")
		)
		(fp_line
			(start -0.67945 0.3048)
			(end -0.67945 -0.305054)
			(stroke
				(width 0.1)
				(type default)
			)
			(layer "F.Fab")
		)
		(fp_line
			(start -0.12065 -0.305054)
			(end -0.12065 -0.2794)
			(stroke
				(width 0.1)
				(type default)
			)
			(layer "F.Fab")
		)
		(fp_line
			(start -0.12065 -0.2794)
			(end 0.12065 -0.2794)
			(stroke
				(width 0.1)
				(type default)
			)
			(layer "F.Fab")
		)
		(fp_line
			(start -0.12065 0.2794)
			(end -0.12065 0.3048)
			(stroke
				(width 0.1)
				(type default)
			)
			(layer "F.Fab")
		)
		(fp_line
			(start -0.12065 0.3048)
			(end -0.67945 0.3048)
			(stroke
				(width 0.1)
				(type default)
			)
			(layer "F.Fab")
		)
		(fp_line
			(start 0.120396 0.2794)
			(end -0.12065 0.2794)
			(stroke
				(width 0.1)
				(type default)
			)
			(layer "F.Fab")
		)
		(fp_line
			(start 0.120396 0.3048)
			(end 0.120396 0.2794)
			(stroke
				(width 0.1)
				(type default)
			)
			(layer "F.Fab")
		)
		(fp_line
			(start 0.12065 -0.3048)
			(end 0.67945 -0.3048)
			(stroke
				(width 0.1)
				(type default)
			)
			(layer "F.Fab")
		)
		(fp_line
			(start 0.12065 -0.2794)
			(end 0.12065 -0.3048)
			(stroke
				(width 0.1)
				(type default)
			)
			(layer "F.Fab")
		)
		(fp_line
			(start 0.67945 -0.3048)
			(end 0.67945 0.3048)
			(stroke
				(width 0.1)
				(type default)
			)
			(layer "F.Fab")
		)
		(fp_line
			(start 0.67945 0.3048)
			(end 0.120396 0.3048)
			(stroke
				(width 0.1)
				(type default)
			)
			(layer "F.Fab")
		)
		(pad "1" smd circle
			(at -0.40005 0)
			(size 0 0)
			(layers "F.Cu" "F.Mask" "F.Paste")
			(net "LED_P12V_SCM_FAULT")
		)
		(pad "2" smd circle
			(at 0.40005 0)
			(size 0 0)
			(layers "F.Cu" "F.Mask" "F.Paste")
			(net "P3V3_AUX")
		)
	)
	(footprint ""
		(layer "F.Cu")
		(at 274.7137 -95.029274 180)
		(property "Reference" "R718"
			(at 0 0 180)
			(layer "F.SilkS")
			(hide yes)
			(effects
				(font
					(size 1.27 1.27)
				)
			)
		)
		(property "Value" ""
			(at 0 0 180)
			(layer "F.Fab")
			(effects
				(font
					(size 1.27 1.27)
				)
			)
		)
		(duplicate_pad_numbers_are_jumpers no)
		(fp_line
			(start 0.7874 0.4064)
			(end -0.7874 0.4064)
			(stroke
				(width 0.1524)
				(type default)
			)
			(layer "F.SilkS")
		)
		(fp_line
			(start 0.7874 -0.4064)
			(end 0.7874 0.4064)
			(stroke
				(width 0.1524)
				(type default)
			)
			(layer "F.SilkS")
		)
		(fp_line
			(start -0.7874 0.4064)
			(end -0.7874 -0.4064)
			(stroke
				(width 0.1524)
				(type default)
			)
			(layer "F.SilkS")
		)
		(fp_line
			(start -0.7874 -0.4064)
			(end 0.7874 -0.4064)
			(stroke
				(width 0.1524)
				(type default)
			)
			(layer "F.SilkS")
		)
		(fp_line
			(start 0.67945 0.3048)
			(end 0.120396 0.3048)
			(stroke
				(width 0.1)
				(type default)
			)
			(layer "F.Fab")
		)
		(fp_line
			(start 0.67945 -0.3048)
			(end 0.67945 0.3048)
			(stroke
				(width 0.1)
				(type default)
			)
			(layer "F.Fab")
		)
		(fp_line
			(start 0.12065 -0.2794)
			(end 0.12065 -0.3048)
			(stroke
				(width 0.1)
				(type default)
			)
			(layer "F.Fab")
		)
		(fp_line
			(start 0.12065 -0.3048)
			(end 0.67945 -0.3048)
			(stroke
				(width 0.1)
				(type default)
			)
			(layer "F.Fab")
		)
		(fp_line
			(start 0.120396 0.3048)
			(end 0.120396 0.2794)
			(stroke
				(width 0.1)
				(type default)
			)
			(layer "F.Fab")
		)
		(fp_line
			(start 0.120396 0.2794)
			(end -0.12065 0.2794)
			(stroke
				(width 0.1)
				(type default)
			)
			(layer "F.Fab")
		)
		(fp_line
			(start -0.12065 0.3048)
			(end -0.67945 0.3048)
			(stroke
				(width 0.1)
				(type default)
			)
			(layer "F.Fab")
		)
		(fp_line
			(start -0.12065 0.2794)
			(end -0.12065 0.3048)
			(stroke
				(width 0.1)
				(type default)
			)
			(layer "F.Fab")
		)
		(fp_line
			(start -0.12065 -0.2794)
			(end 0.12065 -0.2794)
			(stroke
				(width 0.1)
				(type default)
			)
			(layer "F.Fab")
		)
		(fp_line
			(start -0.12065 -0.305054)
			(end -0.12065 -0.2794)
			(stroke
				(width 0.1)
				(type default)
			)
			(layer "F.Fab")
		)
		(fp_line
			(start -0.67945 0.3048)
			(end -0.67945 -0.305054)
			(stroke
				(width 0.1)
				(type default)
			)
			(layer "F.Fab")
		)
		(fp_line
			(start -0.67945 -0.305054)
			(end -0.12065 -0.305054)
			(stroke
				(width 0.1)
				(type default)
			)
			(layer "F.Fab")
		)
		(pad "1" smd circle
			(at -0.40005 0 180)
			(size 0 0)
			(layers "F.Cu" "F.Mask" "F.Paste")
			(net "MB_FRU_ADDR1")
		)
		(pad "2" smd circle
			(at 0.40005 0 180)
			(size 0 0)
			(layers "F.Cu" "F.Mask" "F.Paste")
			(net "GND")
		)
	)
	(footprint ""
		(layer "F.Cu")
		(at 335.501488 -402.371052 -90)
		(property "Reference" "C1559"
			(at 0 0 270)
			(layer "F.SilkS")
			(hide yes)
			(effects
				(font
					(size 1.27 1.27)
				)
			)
		)
		(property "Value" ""
			(at 0 0 270)
			(layer "F.Fab")
			(effects
				(font
					(size 1.27 1.27)
				)
			)
		)
		(duplicate_pad_numbers_are_jumpers no)
		(fp_line
			(start -0.299974 0.150114)
			(end -0.299974 -0.150114)
			(stroke
				(width 0.1)
				(type default)
			)
			(layer "F.Fab")
		)
		(fp_line
			(start 0.299974 0.150114)
			(end -0.299974 0.150114)
			(stroke
				(width 0.1)
				(type default)
			)
			(layer "F.Fab")
		)
		(fp_line
			(start -0.299974 -0.150114)
			(end 0.299974 -0.150114)
			(stroke
				(width 0.1)
				(type default)
			)
			(layer "F.Fab")
		)
		(fp_line
			(start 0.299974 -0.150114)
			(end 0.299974 0.150114)
			(stroke
				(width 0.1)
				(type default)
			)
			(layer "F.Fab")
		)
		(pad "1" smd rect
			(at -0.2667 0 270)
			(size 0.3048 0.381)
			(layers "F.Cu" "F.Mask" "F.Paste")
			(net "P5E_CPU0_PE4_TX_C_DP<10>")
		)
		(pad "2" smd rect
			(at 0.2667 0 270)
			(size 0.3048 0.381)
			(layers "F.Cu" "F.Mask" "F.Paste")
			(net "P5E_CPU0_PE4_TX_DP<10>")
		)
	)
	(footprint ""
		(layer "F.Cu")
		(at 193.089022 -25.965912 90)
		(property "Reference" "R4013"
			(at 0 0 90)
			(layer "F.SilkS")
			(hide yes)
			(effects
				(font
					(size 1.27 1.27)
				)
			)
		)
		(property "Value" ""
			(at 0 0 90)
			(layer "F.Fab")
			(effects
				(font
					(size 1.27 1.27)
				)
			)
		)
		(duplicate_pad_numbers_are_jumpers no)
		(fp_line
			(start 0.7874 -0.4064)
			(end 0.7874 0.4064)
			(stroke
				(width 0.1524)
				(type default)
			)
			(layer "F.SilkS")
		)
		(fp_line
			(start -0.7874 -0.4064)
			(end 0.7874 -0.4064)
			(stroke
				(width 0.1524)
				(type default)
			)
			(layer "F.SilkS")
		)
		(fp_line
			(start 0.7874 0.4064)
			(end -0.7874 0.4064)
			(stroke
				(width 0.1524)
				(type default)
			)
			(layer "F.SilkS")
		)
		(fp_line
			(start -0.7874 0.4064)
			(end -0.7874 -0.4064)
			(stroke
				(width 0.1524)
				(type default)
			)
			(layer "F.SilkS")
		)
		(fp_line
			(start -0.12065 -0.305054)
			(end -0.12065 -0.2794)
			(stroke
				(width 0.1)
				(type default)
			)
			(layer "F.Fab")
		)
		(fp_line
			(start -0.67945 -0.305054)
			(end -0.12065 -0.305054)
			(stroke
				(width 0.1)
				(type default)
			)
			(layer "F.Fab")
		)
		(fp_line
			(start 0.67945 -0.3048)
			(end 0.67945 0.3048)
			(stroke
				(width 0.1)
				(type default)
			)
			(layer "F.Fab")
		)
		(fp_line
			(start 0.12065 -0.3048)
			(end 0.67945 -0.3048)
			(stroke
				(width 0.1)
				(type default)
			)
			(layer "F.Fab")
		)
		(fp_line
			(start 0.12065 -0.2794)
			(end 0.12065 -0.3048)
			(stroke
				(width 0.1)
				(type default)
			)
			(layer "F.Fab")
		)
		(fp_line
			(start -0.12065 -0.2794)
			(end 0.12065 -0.2794)
			(stroke
				(width 0.1)
				(type default)
			)
			(layer "F.Fab")
		)
		(fp_line
			(start 0.120396 0.2794)
			(end -0.12065 0.2794)
			(stroke
				(width 0.1)
				(type default)
			)
			(layer "F.Fab")
		)
		(fp_line
			(start -0.12065 0.2794)
			(end -0.12065 0.3048)
			(stroke
				(width 0.1)
				(type default)
			)
			(layer "F.Fab")
		)
		(fp_line
			(start 0.67945 0.3048)
			(end 0.120396 0.3048)
			(stroke
				(width 0.1)
				(type default)
			)
			(layer "F.Fab")
		)
		(fp_line
			(start 0.120396 0.3048)
			(end 0.120396 0.2794)
			(stroke
				(width 0.1)
				(type default)
			)
			(layer "F.Fab")
		)
		(fp_line
			(start -0.12065 0.3048)
			(end -0.67945 0.3048)
			(stroke
				(width 0.1)
				(type default)
			)
			(layer "F.Fab")
		)
		(fp_line
			(start -0.67945 0.3048)
			(end -0.67945 -0.305054)
			(stroke
				(width 0.1)
				(type default)
			)
			(layer "F.Fab")
		)
		(pad "1" smd circle
			(at -0.40005 0 90)
			(size 0 0)
			(layers "F.Cu" "F.Mask" "F.Paste")
			(net "P3V3_AUX")
		)
		(pad "2" smd circle
			(at 0.40005 0 90)
			(size 0 0)
			(layers "F.Cu" "F.Mask" "F.Paste")
			(net "P12V_SCM_FAULT_R_N")
		)
	)
	(footprint ""
		(layer "F.Cu")
		(at 360.383582 -386.41909)
		(property "Reference" "R4158"
			(at 0 0 0)
			(layer "F.SilkS")
			(hide yes)
			(effects
				(font
					(size 1.27 1.27)
				)
			)
		)
		(property "Value" ""
			(at 0 0 0)
			(layer "F.Fab")
			(effects
				(font
					(size 1.27 1.27)
				)
			)
		)
		(duplicate_pad_numbers_are_jumpers no)
		(fp_line
			(start -0.7874 -0.4064)
			(end 0.7874 -0.4064)
			(stroke
				(width 0.1524)
				(type default)
			)
			(layer "F.SilkS")
		)
		(fp_line
			(start -0.7874 0.4064)
			(end -0.7874 -0.4064)
			(stroke
				(width 0.1524)
				(type default)
			)
			(layer "F.SilkS")
		)
		(fp_line
			(start 0.7874 -0.4064)
			(end 0.7874 0.4064)
			(stroke
				(width 0.1524)
				(type default)
			)
			(layer "F.SilkS")
		)
		(fp_line
			(start 0.7874 0.4064)
			(end -0.7874 0.4064)
			(stroke
				(width 0.1524)
				(type default)
			)
			(layer "F.SilkS")
		)
		(fp_line
			(start -0.67945 -0.305054)
			(end -0.12065 -0.305054)
			(stroke
				(width 0.1)
				(type default)
			)
			(layer "F.Fab")
		)
		(fp_line
			(start -0.67945 0.3048)
			(end -0.67945 -0.305054)
			(stroke
				(width 0.1)
				(type default)
			)
			(layer "F.Fab")
		)
		(fp_line
			(start -0.12065 -0.305054)
			(end -0.12065 -0.2794)
			(stroke
				(width 0.1)
				(type default)
			)
			(layer "F.Fab")
		)
		(fp_line
			(start -0.12065 -0.2794)
			(end 0.12065 -0.2794)
			(stroke
				(width 0.1)
				(type default)
			)
			(layer "F.Fab")
		)
		(fp_line
			(start -0.12065 0.2794)
			(end -0.12065 0.3048)
			(stroke
				(width 0.1)
				(type default)
			)
			(layer "F.Fab")
		)
		(fp_line
			(start -0.12065 0.3048)
			(end -0.67945 0.3048)
			(stroke
				(width 0.1)
				(type default)
			)
			(layer "F.Fab")
		)
		(fp_line
			(start 0.120396 0.2794)
			(end -0.12065 0.2794)
			(stroke
				(width 0.1)
				(type default)
			)
			(layer "F.Fab")
		)
		(fp_line
			(start 0.120396 0.3048)
			(end 0.120396 0.2794)
			(stroke
				(width 0.1)
				(type default)
			)
			(layer "F.Fab")
		)
		(fp_line
			(start 0.12065 -0.3048)
			(end 0.67945 -0.3048)
			(stroke
				(width 0.1)
				(type default)
			)
			(layer "F.Fab")
		)
		(fp_line
			(start 0.12065 -0.2794)
			(end 0.12065 -0.3048)
			(stroke
				(width 0.1)
				(type default)
			)
			(layer "F.Fab")
		)
		(fp_line
			(start 0.67945 -0.3048)
			(end 0.67945 0.3048)
			(stroke
				(width 0.1)
				(type default)
			)
			(layer "F.Fab")
		)
		(fp_line
			(start 0.67945 0.3048)
			(end 0.120396 0.3048)
			(stroke
				(width 0.1)
				(type default)
			)
			(layer "F.Fab")
		)
		(pad "1" smd circle
			(at -0.40005 0)
			(size 0 0)
			(layers "F.Cu" "F.Mask" "F.Paste")
			(net "P3V3_AUX")
		)
		(pad "2" smd circle
			(at 0.40005 0)
			(size 0 0)
			(layers "F.Cu" "F.Mask" "F.Paste")
			(net "GPU_3V3IO_RSVD1")
		)
	)
	(footprint ""
		(layer "F.Cu")
		(at 193.38036 -121.884948)
		(property "Reference" "R2155"
			(at 0 0 0)
			(layer "F.SilkS")
			(hide yes)
			(effects
				(font
					(size 1.27 1.27)
				)
			)
		)
		(property "Value" ""
			(at 0 0 0)
			(layer "F.Fab")
			(effects
				(font
					(size 1.27 1.27)
				)
			)
		)
		(duplicate_pad_numbers_are_jumpers no)
		(fp_line
			(start -0.7874 -0.4064)
			(end 0.7874 -0.4064)
			(stroke
				(width 0.1524)
				(type default)
			)
			(layer "F.SilkS")
		)
		(fp_line
			(start -0.7874 0.4064)
			(end -0.7874 -0.4064)
			(stroke
				(width 0.1524)
				(type default)
			)
			(layer "F.SilkS")
		)
		(fp_line
			(start 0.7874 -0.4064)
			(end 0.7874 0.4064)
			(stroke
				(width 0.1524)
				(type default)
			)
			(layer "F.SilkS")
		)
		(fp_line
			(start 0.7874 0.4064)
			(end -0.7874 0.4064)
			(stroke
				(width 0.1524)
				(type default)
			)
			(layer "F.SilkS")
		)
		(fp_line
			(start -0.67945 -0.305054)
			(end -0.12065 -0.305054)
			(stroke
				(width 0.1)
				(type default)
			)
			(layer "F.Fab")
		)
		(fp_line
			(start -0.67945 0.3048)
			(end -0.67945 -0.305054)
			(stroke
				(width 0.1)
				(type default)
			)
			(layer "F.Fab")
		)
		(fp_line
			(start -0.12065 -0.305054)
			(end -0.12065 -0.2794)
			(stroke
				(width 0.1)
				(type default)
			)
			(layer "F.Fab")
		)
		(fp_line
			(start -0.12065 -0.2794)
			(end 0.12065 -0.2794)
			(stroke
				(width 0.1)
				(type default)
			)
			(layer "F.Fab")
		)
		(fp_line
			(start -0.12065 0.2794)
			(end -0.12065 0.3048)
			(stroke
				(width 0.1)
				(type default)
			)
			(layer "F.Fab")
		)
		(fp_line
			(start -0.12065 0.3048)
			(end -0.67945 0.3048)
			(stroke
				(width 0.1)
				(type default)
			)
			(layer "F.Fab")
		)
		(fp_line
			(start 0.120396 0.2794)
			(end -0.12065 0.2794)
			(stroke
				(width 0.1)
				(type default)
			)
			(layer "F.Fab")
		)
		(fp_line
			(start 0.120396 0.3048)
			(end 0.120396 0.2794)
			(stroke
				(width 0.1)
				(type default)
			)
			(layer "F.Fab")
		)
		(fp_line
			(start 0.12065 -0.3048)
			(end 0.67945 -0.3048)
			(stroke
				(width 0.1)
				(type default)
			)
			(layer "F.Fab")
		)
		(fp_line
			(start 0.12065 -0.2794)
			(end 0.12065 -0.3048)
			(stroke
				(width 0.1)
				(type default)
			)
			(layer "F.Fab")
		)
		(fp_line
			(start 0.67945 -0.3048)
			(end 0.67945 0.3048)
			(stroke
				(width 0.1)
				(type default)
			)
			(layer "F.Fab")
		)
		(fp_line
			(start 0.67945 0.3048)
			(end 0.120396 0.3048)
			(stroke
				(width 0.1)
				(type default)
			)
			(layer "F.Fab")
		)
		(pad "1" smd circle
			(at -0.40005 0)
			(size 0 0)
			(layers "F.Cu" "F.Mask" "F.Paste")
			(net "FM_BMC_READY_R_PLD_N")
		)
		(pad "2" smd circle
			(at 0.40005 0)
			(size 0 0)
			(layers "F.Cu" "F.Mask" "F.Paste")
			(net "FM_BMC_READY_R_N")
		)
	)
	(footprint ""
		(layer "F.Cu")
		(at 170.23588 -434.939948 180)
		(property "Reference" "R3456"
			(at 0 0 180)
			(layer "F.SilkS")
			(hide yes)
			(effects
				(font
					(size 1.27 1.27)
				)
			)
		)
		(property "Value" ""
			(at 0 0 180)
			(layer "F.Fab")
			(effects
				(font
					(size 1.27 1.27)
				)
			)
		)
		(duplicate_pad_numbers_are_jumpers no)
		(fp_line
			(start 0.7874 0.4064)
			(end -0.7874 0.4064)
			(stroke
				(width 0.1524)
				(type default)
			)
			(layer "F.SilkS")
		)
		(fp_line
			(start 0.7874 -0.4064)
			(end 0.7874 0.4064)
			(stroke
				(width 0.1524)
				(type default)
			)
			(layer "F.SilkS")
		)
		(fp_line
			(start -0.7874 0.4064)
			(end -0.7874 -0.4064)
			(stroke
				(width 0.1524)
				(type default)
			)
			(layer "F.SilkS")
		)
		(fp_line
			(start -0.7874 -0.4064)
			(end 0.7874 -0.4064)
			(stroke
				(width 0.1524)
				(type default)
			)
			(layer "F.SilkS")
		)
		(fp_line
			(start 0.67945 0.3048)
			(end 0.120396 0.3048)
			(stroke
				(width 0.1)
				(type default)
			)
			(layer "F.Fab")
		)
		(fp_line
			(start 0.67945 -0.3048)
			(end 0.67945 0.3048)
			(stroke
				(width 0.1)
				(type default)
			)
			(layer "F.Fab")
		)
		(fp_line
			(start 0.12065 -0.2794)
			(end 0.12065 -0.3048)
			(stroke
				(width 0.1)
				(type default)
			)
			(layer "F.Fab")
		)
		(fp_line
			(start 0.12065 -0.3048)
			(end 0.67945 -0.3048)
			(stroke
				(width 0.1)
				(type default)
			)
			(layer "F.Fab")
		)
		(fp_line
			(start 0.120396 0.3048)
			(end 0.120396 0.2794)
			(stroke
				(width 0.1)
				(type default)
			)
			(layer "F.Fab")
		)
		(fp_line
			(start 0.120396 0.2794)
			(end -0.12065 0.2794)
			(stroke
				(width 0.1)
				(type default)
			)
			(layer "F.Fab")
		)
		(fp_line
			(start -0.12065 0.3048)
			(end -0.67945 0.3048)
			(stroke
				(width 0.1)
				(type default)
			)
			(layer "F.Fab")
		)
		(fp_line
			(start -0.12065 0.2794)
			(end -0.12065 0.3048)
			(stroke
				(width 0.1)
				(type default)
			)
			(layer "F.Fab")
		)
		(fp_line
			(start -0.12065 -0.2794)
			(end 0.12065 -0.2794)
			(stroke
				(width 0.1)
				(type default)
			)
			(layer "F.Fab")
		)
		(fp_line
			(start -0.12065 -0.305054)
			(end -0.12065 -0.2794)
			(stroke
				(width 0.1)
				(type default)
			)
			(layer "F.Fab")
		)
		(fp_line
			(start -0.67945 0.3048)
			(end -0.67945 -0.305054)
			(stroke
				(width 0.1)
				(type default)
			)
			(layer "F.Fab")
		)
		(fp_line
			(start -0.67945 -0.305054)
			(end -0.12065 -0.305054)
			(stroke
				(width 0.1)
				(type default)
			)
			(layer "F.Fab")
		)
		(pad "1" smd circle
			(at -0.40005 0 180)
			(size 0 0)
			(layers "F.Cu" "F.Mask" "F.Paste")
			(net "P3V3_AUX")
		)
		(pad "2" smd circle
			(at 0.40005 0 180)
			(size 0 0)
			(layers "F.Cu" "F.Mask" "F.Paste")
			(net "GPU_BASE_STBY_EN_BUF_R")
		)
	)
	(footprint ""
		(layer "F.Cu")
		(at 193.38036 -119.344948)
		(property "Reference" "R1434"
			(at 0 0 0)
			(layer "F.SilkS")
			(hide yes)
			(effects
				(font
					(size 1.27 1.27)
				)
			)
		)
		(property "Value" ""
			(at 0 0 0)
			(layer "F.Fab")
			(effects
				(font
					(size 1.27 1.27)
				)
			)
		)
		(duplicate_pad_numbers_are_jumpers no)
		(fp_line
			(start -0.7874 -0.4064)
			(end 0.7874 -0.4064)
			(stroke
				(width 0.1524)
				(type default)
			)
			(layer "F.SilkS")
		)
		(fp_line
			(start -0.7874 0.4064)
			(end -0.7874 -0.4064)
			(stroke
				(width 0.1524)
				(type default)
			)
			(layer "F.SilkS")
		)
		(fp_line
			(start 0.7874 -0.4064)
			(end 0.7874 0.4064)
			(stroke
				(width 0.1524)
				(type default)
			)
			(layer "F.SilkS")
		)
		(fp_line
			(start 0.7874 0.4064)
			(end -0.7874 0.4064)
			(stroke
				(width 0.1524)
				(type default)
			)
			(layer "F.SilkS")
		)
		(fp_line
			(start -0.67945 -0.305054)
			(end -0.12065 -0.305054)
			(stroke
				(width 0.1)
				(type default)
			)
			(layer "F.Fab")
		)
		(fp_line
			(start -0.67945 0.3048)
			(end -0.67945 -0.305054)
			(stroke
				(width 0.1)
				(type default)
			)
			(layer "F.Fab")
		)
		(fp_line
			(start -0.12065 -0.305054)
			(end -0.12065 -0.2794)
			(stroke
				(width 0.1)
				(type default)
			)
			(layer "F.Fab")
		)
		(fp_line
			(start -0.12065 -0.2794)
			(end 0.12065 -0.2794)
			(stroke
				(width 0.1)
				(type default)
			)
			(layer "F.Fab")
		)
		(fp_line
			(start -0.12065 0.2794)
			(end -0.12065 0.3048)
			(stroke
				(width 0.1)
				(type default)
			)
			(layer "F.Fab")
		)
		(fp_line
			(start -0.12065 0.3048)
			(end -0.67945 0.3048)
			(stroke
				(width 0.1)
				(type default)
			)
			(layer "F.Fab")
		)
		(fp_line
			(start 0.120396 0.2794)
			(end -0.12065 0.2794)
			(stroke
				(width 0.1)
				(type default)
			)
			(layer "F.Fab")
		)
		(fp_line
			(start 0.120396 0.3048)
			(end 0.120396 0.2794)
			(stroke
				(width 0.1)
				(type default)
			)
			(layer "F.Fab")
		)
		(fp_line
			(start 0.12065 -0.3048)
			(end 0.67945 -0.3048)
			(stroke
				(width 0.1)
				(type default)
			)
			(layer "F.Fab")
		)
		(fp_line
			(start 0.12065 -0.2794)
			(end 0.12065 -0.3048)
			(stroke
				(width 0.1)
				(type default)
			)
			(layer "F.Fab")
		)
		(fp_line
			(start 0.67945 -0.3048)
			(end 0.67945 0.3048)
			(stroke
				(width 0.1)
				(type default)
			)
			(layer "F.Fab")
		)
		(fp_line
			(start 0.67945 0.3048)
			(end 0.120396 0.3048)
			(stroke
				(width 0.1)
				(type default)
			)
			(layer "F.Fab")
		)
		(pad "1" smd circle
			(at -0.40005 0)
			(size 0 0)
			(layers "F.Cu" "F.Mask" "F.Paste")
			(net "FM_SYS_THROTTLE_R_N")
		)
		(pad "2" smd circle
			(at 0.40005 0)
			(size 0 0)
			(layers "F.Cu" "F.Mask" "F.Paste")
			(net "P3V3_AUX")
		)
	)
	(footprint ""
		(layer "F.Cu")
		(at 118.542816 -240.277142 90)
		(property "Reference" "C426"
			(at 0 0 90)
			(layer "F.SilkS")
			(hide yes)
			(effects
				(font
					(size 1.27 1.27)
				)
			)
		)
		(property "Value" ""
			(at 0 0 90)
			(layer "F.Fab")
			(effects
				(font
					(size 1.27 1.27)
				)
			)
		)
		(duplicate_pad_numbers_are_jumpers no)
		(fp_line
			(start 0.7874 -0.4064)
			(end 0.7874 0.4064)
			(stroke
				(width 0.1524)
				(type default)
			)
			(layer "F.SilkS")
		)
		(fp_line
			(start -0.7874 -0.4064)
			(end 0.7874 -0.4064)
			(stroke
				(width 0.1524)
				(type default)
			)
			(layer "F.SilkS")
		)
		(fp_line
			(start 0.7874 0.4064)
			(end -0.7874 0.4064)
			(stroke
				(width 0.1524)
				(type default)
			)
			(layer "F.SilkS")
		)
		(fp_line
			(start -0.7874 0.4064)
			(end -0.7874 -0.4064)
			(stroke
				(width 0.1524)
				(type default)
			)
			(layer "F.SilkS")
		)
		(fp_line
			(start -0.12065 -0.305054)
			(end -0.12065 -0.2794)
			(stroke
				(width 0.1)
				(type default)
			)
			(layer "F.Fab")
		)
		(fp_line
			(start -0.67945 -0.305054)
			(end -0.12065 -0.305054)
			(stroke
				(width 0.1)
				(type default)
			)
			(layer "F.Fab")
		)
		(fp_line
			(start 0.67945 -0.3048)
			(end 0.67945 0.3048)
			(stroke
				(width 0.1)
				(type default)
			)
			(layer "F.Fab")
		)
		(fp_line
			(start 0.12065 -0.3048)
			(end 0.67945 -0.3048)
			(stroke
				(width 0.1)
				(type default)
			)
			(layer "F.Fab")
		)
		(fp_line
			(start 0.12065 -0.2794)
			(end 0.12065 -0.3048)
			(stroke
				(width 0.1)
				(type default)
			)
			(layer "F.Fab")
		)
		(fp_line
			(start -0.12065 -0.2794)
			(end 0.12065 -0.2794)
			(stroke
				(width 0.1)
				(type default)
			)
			(layer "F.Fab")
		)
		(fp_line
			(start 0.120396 0.2794)
			(end -0.12065 0.2794)
			(stroke
				(width 0.1)
				(type default)
			)
			(layer "F.Fab")
		)
		(fp_line
			(start -0.12065 0.2794)
			(end -0.12065 0.3048)
			(stroke
				(width 0.1)
				(type default)
			)
			(layer "F.Fab")
		)
		(fp_line
			(start 0.67945 0.3048)
			(end 0.120396 0.3048)
			(stroke
				(width 0.1)
				(type default)
			)
			(layer "F.Fab")
		)
		(fp_line
			(start 0.120396 0.3048)
			(end 0.120396 0.2794)
			(stroke
				(width 0.1)
				(type default)
			)
			(layer "F.Fab")
		)
		(fp_line
			(start -0.12065 0.3048)
			(end -0.67945 0.3048)
			(stroke
				(width 0.1)
				(type default)
			)
			(layer "F.Fab")
		)
		(fp_line
			(start -0.67945 0.3048)
			(end -0.67945 -0.305054)
			(stroke
				(width 0.1)
				(type default)
			)
			(layer "F.Fab")
		)
		(pad "1" smd circle
			(at -0.40005 0 90)
			(size 0 0)
			(layers "F.Cu" "F.Mask" "F.Paste")
			(net "PVCCFA_EHV_FIVRA_CPU1")
		)
		(pad "2" smd circle
			(at 0.40005 0 90)
			(size 0 0)
			(layers "F.Cu" "F.Mask" "F.Paste")
			(net "GND")
		)
	)
	(footprint ""
		(layer "F.Cu")
		(at 27.0383 -128.364996 180)
		(property "Reference" "PC474"
			(at 0 0 180)
			(layer "F.SilkS")
			(hide yes)
			(effects
				(font
					(size 1.27 1.27)
				)
			)
		)
		(property "Value" ""
			(at 0 0 180)
			(layer "F.Fab")
			(effects
				(font
					(size 1.27 1.27)
				)
			)
		)
		(duplicate_pad_numbers_are_jumpers no)
		(fp_line
			(start 0.7874 0.4064)
			(end -0.7874 0.4064)
			(stroke
				(width 0.1524)
				(type default)
			)
			(layer "F.SilkS")
		)
		(fp_line
			(start 0.7874 -0.4064)
			(end 0.7874 0.4064)
			(stroke
				(width 0.1524)
				(type default)
			)
			(layer "F.SilkS")
		)
		(fp_line
			(start -0.7874 0.4064)
			(end -0.7874 -0.4064)
			(stroke
				(width 0.1524)
				(type default)
			)
			(layer "F.SilkS")
		)
		(fp_line
			(start -0.7874 -0.4064)
			(end 0.7874 -0.4064)
			(stroke
				(width 0.1524)
				(type default)
			)
			(layer "F.SilkS")
		)
		(fp_line
			(start 0.67945 0.3048)
			(end 0.120396 0.3048)
			(stroke
				(width 0.1)
				(type default)
			)
			(layer "F.Fab")
		)
		(fp_line
			(start 0.67945 -0.3048)
			(end 0.67945 0.3048)
			(stroke
				(width 0.1)
				(type default)
			)
			(layer "F.Fab")
		)
		(fp_line
			(start 0.12065 -0.2794)
			(end 0.12065 -0.3048)
			(stroke
				(width 0.1)
				(type default)
			)
			(layer "F.Fab")
		)
		(fp_line
			(start 0.12065 -0.3048)
			(end 0.67945 -0.3048)
			(stroke
				(width 0.1)
				(type default)
			)
			(layer "F.Fab")
		)
		(fp_line
			(start 0.120396 0.3048)
			(end 0.120396 0.2794)
			(stroke
				(width 0.1)
				(type default)
			)
			(layer "F.Fab")
		)
		(fp_line
			(start 0.120396 0.2794)
			(end -0.12065 0.2794)
			(stroke
				(width 0.1)
				(type default)
			)
			(layer "F.Fab")
		)
		(fp_line
			(start -0.12065 0.3048)
			(end -0.67945 0.3048)
			(stroke
				(width 0.1)
				(type default)
			)
			(layer "F.Fab")
		)
		(fp_line
			(start -0.12065 0.2794)
			(end -0.12065 0.3048)
			(stroke
				(width 0.1)
				(type default)
			)
			(layer "F.Fab")
		)
		(fp_line
			(start -0.12065 -0.2794)
			(end 0.12065 -0.2794)
			(stroke
				(width 0.1)
				(type default)
			)
			(layer "F.Fab")
		)
		(fp_line
			(start -0.12065 -0.305054)
			(end -0.12065 -0.2794)
			(stroke
				(width 0.1)
				(type default)
			)
			(layer "F.Fab")
		)
		(fp_line
			(start -0.67945 0.3048)
			(end -0.67945 -0.305054)
			(stroke
				(width 0.1)
				(type default)
			)
			(layer "F.Fab")
		)
		(fp_line
			(start -0.67945 -0.305054)
			(end -0.12065 -0.305054)
			(stroke
				(width 0.1)
				(type default)
			)
			(layer "F.Fab")
		)
		(pad "1" smd circle
			(at -0.40005 0 180)
			(size 0 0)
			(layers "F.Cu" "F.Mask" "F.Paste")
			(net "PVCCINFAON_CPU1_VIN_CSNIN")
		)
		(pad "2" smd circle
			(at 0.40005 0 180)
			(size 0 0)
			(layers "F.Cu" "F.Mask" "F.Paste")
			(net "GND")
		)
	)
	(footprint ""
		(layer "F.Cu")
		(at 69.036438 -31.887922 90)
		(property "Reference" "PC2164"
			(at 0 0 90)
			(layer "F.SilkS")
			(hide yes)
			(effects
				(font
					(size 1.27 1.27)
				)
			)
		)
		(property "Value" ""
			(at 0 0 90)
			(layer "F.Fab")
			(effects
				(font
					(size 1.27 1.27)
				)
			)
		)
		(duplicate_pad_numbers_are_jumpers no)
		(fp_line
			(start 0.7874 -0.4064)
			(end 0.7874 0.4064)
			(stroke
				(width 0.1524)
				(type default)
			)
			(layer "F.SilkS")
		)
		(fp_line
			(start -0.7874 -0.4064)
			(end 0.7874 -0.4064)
			(stroke
				(width 0.1524)
				(type default)
			)
			(layer "F.SilkS")
		)
		(fp_line
			(start 0.7874 0.4064)
			(end -0.7874 0.4064)
			(stroke
				(width 0.1524)
				(type default)
			)
			(layer "F.SilkS")
		)
		(fp_line
			(start -0.7874 0.4064)
			(end -0.7874 -0.4064)
			(stroke
				(width 0.1524)
				(type default)
			)
			(layer "F.SilkS")
		)
		(fp_line
			(start -0.12065 -0.305054)
			(end -0.12065 -0.2794)
			(stroke
				(width 0.1)
				(type default)
			)
			(layer "F.Fab")
		)
		(fp_line
			(start -0.67945 -0.305054)
			(end -0.12065 -0.305054)
			(stroke
				(width 0.1)
				(type default)
			)
			(layer "F.Fab")
		)
		(fp_line
			(start 0.67945 -0.3048)
			(end 0.67945 0.3048)
			(stroke
				(width 0.1)
				(type default)
			)
			(layer "F.Fab")
		)
		(fp_line
			(start 0.12065 -0.3048)
			(end 0.67945 -0.3048)
			(stroke
				(width 0.1)
				(type default)
			)
			(layer "F.Fab")
		)
		(fp_line
			(start 0.12065 -0.2794)
			(end 0.12065 -0.3048)
			(stroke
				(width 0.1)
				(type default)
			)
			(layer "F.Fab")
		)
		(fp_line
			(start -0.12065 -0.2794)
			(end 0.12065 -0.2794)
			(stroke
				(width 0.1)
				(type default)
			)
			(layer "F.Fab")
		)
		(fp_line
			(start 0.120396 0.2794)
			(end -0.12065 0.2794)
			(stroke
				(width 0.1)
				(type default)
			)
			(layer "F.Fab")
		)
		(fp_line
			(start -0.12065 0.2794)
			(end -0.12065 0.3048)
			(stroke
				(width 0.1)
				(type default)
			)
			(layer "F.Fab")
		)
		(fp_line
			(start 0.67945 0.3048)
			(end 0.120396 0.3048)
			(stroke
				(width 0.1)
				(type default)
			)
			(layer "F.Fab")
		)
		(fp_line
			(start 0.120396 0.3048)
			(end 0.120396 0.2794)
			(stroke
				(width 0.1)
				(type default)
			)
			(layer "F.Fab")
		)
		(fp_line
			(start -0.12065 0.3048)
			(end -0.67945 0.3048)
			(stroke
				(width 0.1)
				(type default)
			)
			(layer "F.Fab")
		)
		(fp_line
			(start -0.67945 0.3048)
			(end -0.67945 -0.305054)
			(stroke
				(width 0.1)
				(type default)
			)
			(layer "F.Fab")
		)
		(pad "1" smd circle
			(at -0.40005 0 90)
			(size 0 0)
			(layers "F.Cu" "F.Mask" "F.Paste")
			(net "P12V_OCP_TIMER_2")
		)
		(pad "2" smd circle
			(at 0.40005 0 90)
			(size 0 0)
			(layers "F.Cu" "F.Mask" "F.Paste")
			(net "GND")
		)
	)
	(footprint ""
		(layer "F.Cu")
		(at 82.462624 -347.520514 -90)
		(property "Reference" "PC488"
			(at 0 0 270)
			(layer "F.SilkS")
			(hide yes)
			(effects
				(font
					(size 1.27 1.27)
				)
			)
		)
		(property "Value" ""
			(at 0 0 270)
			(layer "F.Fab")
			(effects
				(font
					(size 1.27 1.27)
				)
			)
		)
		(duplicate_pad_numbers_are_jumpers no)
		(fp_line
			(start -0.7874 0.4064)
			(end -0.7874 -0.4064)
			(stroke
				(width 0.1524)
				(type default)
			)
			(layer "F.SilkS")
		)
		(fp_line
			(start 0.7874 0.4064)
			(end -0.7874 0.4064)
			(stroke
				(width 0.1524)
				(type default)
			)
			(layer "F.SilkS")
		)
		(fp_line
			(start -0.7874 -0.4064)
			(end 0.7874 -0.4064)
			(stroke
				(width 0.1524)
				(type default)
			)
			(layer "F.SilkS")
		)
		(fp_line
			(start 0.7874 -0.4064)
			(end 0.7874 0.4064)
			(stroke
				(width 0.1524)
				(type default)
			)
			(layer "F.SilkS")
		)
		(fp_line
			(start -0.67945 0.3048)
			(end -0.67945 -0.305054)
			(stroke
				(width 0.1)
				(type default)
			)
			(layer "F.Fab")
		)
		(fp_line
			(start -0.12065 0.3048)
			(end -0.67945 0.3048)
			(stroke
				(width 0.1)
				(type default)
			)
			(layer "F.Fab")
		)
		(fp_line
			(start 0.120396 0.3048)
			(end 0.120396 0.2794)
			(stroke
				(width 0.1)
				(type default)
			)
			(layer "F.Fab")
		)
		(fp_line
			(start 0.67945 0.3048)
			(end 0.120396 0.3048)
			(stroke
				(width 0.1)
				(type default)
			)
			(layer "F.Fab")
		)
		(fp_line
			(start -0.12065 0.2794)
			(end -0.12065 0.3048)
			(stroke
				(width 0.1)
				(type default)
			)
			(layer "F.Fab")
		)
		(fp_line
			(start 0.120396 0.2794)
			(end -0.12065 0.2794)
			(stroke
				(width 0.1)
				(type default)
			)
			(layer "F.Fab")
		)
		(fp_line
			(start -0.12065 -0.2794)
			(end 0.12065 -0.2794)
			(stroke
				(width 0.1)
				(type default)
			)
			(layer "F.Fab")
		)
		(fp_line
			(start 0.12065 -0.2794)
			(end 0.12065 -0.3048)
			(stroke
				(width 0.1)
				(type default)
			)
			(layer "F.Fab")
		)
		(fp_line
			(start 0.12065 -0.3048)
			(end 0.67945 -0.3048)
			(stroke
				(width 0.1)
				(type default)
			)
			(layer "F.Fab")
		)
		(fp_line
			(start 0.67945 -0.3048)
			(end 0.67945 0.3048)
			(stroke
				(width 0.1)
				(type default)
			)
			(layer "F.Fab")
		)
		(fp_line
			(start -0.67945 -0.305054)
			(end -0.12065 -0.305054)
			(stroke
				(width 0.1)
				(type default)
			)
			(layer "F.Fab")
		)
		(fp_line
			(start -0.12065 -0.305054)
			(end -0.12065 -0.2794)
			(stroke
				(width 0.1)
				(type default)
			)
			(layer "F.Fab")
		)
		(pad "1" smd circle
			(at -0.40005 0 270)
			(size 0 0)
			(layers "F.Cu" "F.Mask" "F.Paste")
			(net "SW_PVCCIN_CPU1_BOOT7_R")
		)
		(pad "2" smd circle
			(at 0.40005 0 270)
			(size 0 0)
			(layers "F.Cu" "F.Mask" "F.Paste")
			(net "SW_PVCCIN_CPU1_BOOTR7")
		)
	)
	(footprint ""
		(layer "F.Cu")
		(at 109.00537 -337.830668)
		(property "Reference" "PC560_P1_2"
			(at 0 0 0)
			(layer "F.SilkS")
			(hide yes)
			(effects
				(font
					(size 1.27 1.27)
				)
			)
		)
		(property "Value" ""
			(at 0 0 0)
			(layer "F.Fab")
			(effects
				(font
					(size 1.27 1.27)
				)
			)
		)
		(duplicate_pad_numbers_are_jumpers no)
		(fp_line
			(start -0.7874 -0.4064)
			(end 0.7874 -0.4064)
			(stroke
				(width 0.1524)
				(type default)
			)
			(layer "F.SilkS")
		)
		(fp_line
			(start -0.7874 0.4064)
			(end -0.7874 -0.4064)
			(stroke
				(width 0.1524)
				(type default)
			)
			(layer "F.SilkS")
		)
		(fp_line
			(start 0.7874 -0.4064)
			(end 0.7874 0.4064)
			(stroke
				(width 0.1524)
				(type default)
			)
			(layer "F.SilkS")
		)
		(fp_line
			(start 0.7874 0.4064)
			(end -0.7874 0.4064)
			(stroke
				(width 0.1524)
				(type default)
			)
			(layer "F.SilkS")
		)
		(fp_line
			(start -0.67945 -0.305054)
			(end -0.12065 -0.305054)
			(stroke
				(width 0.1)
				(type default)
			)
			(layer "F.Fab")
		)
		(fp_line
			(start -0.67945 0.3048)
			(end -0.67945 -0.305054)
			(stroke
				(width 0.1)
				(type default)
			)
			(layer "F.Fab")
		)
		(fp_line
			(start -0.12065 -0.305054)
			(end -0.12065 -0.2794)
			(stroke
				(width 0.1)
				(type default)
			)
			(layer "F.Fab")
		)
		(fp_line
			(start -0.12065 -0.2794)
			(end 0.12065 -0.2794)
			(stroke
				(width 0.1)
				(type default)
			)
			(layer "F.Fab")
		)
		(fp_line
			(start -0.12065 0.2794)
			(end -0.12065 0.3048)
			(stroke
				(width 0.1)
				(type default)
			)
			(layer "F.Fab")
		)
		(fp_line
			(start -0.12065 0.3048)
			(end -0.67945 0.3048)
			(stroke
				(width 0.1)
				(type default)
			)
			(layer "F.Fab")
		)
		(fp_line
			(start 0.120396 0.2794)
			(end -0.12065 0.2794)
			(stroke
				(width 0.1)
				(type default)
			)
			(layer "F.Fab")
		)
		(fp_line
			(start 0.120396 0.3048)
			(end 0.120396 0.2794)
			(stroke
				(width 0.1)
				(type default)
			)
			(layer "F.Fab")
		)
		(fp_line
			(start 0.12065 -0.3048)
			(end 0.67945 -0.3048)
			(stroke
				(width 0.1)
				(type default)
			)
			(layer "F.Fab")
		)
		(fp_line
			(start 0.12065 -0.2794)
			(end 0.12065 -0.3048)
			(stroke
				(width 0.1)
				(type default)
			)
			(layer "F.Fab")
		)
		(fp_line
			(start 0.67945 -0.3048)
			(end 0.67945 0.3048)
			(stroke
				(width 0.1)
				(type default)
			)
			(layer "F.Fab")
		)
		(fp_line
			(start 0.67945 0.3048)
			(end 0.120396 0.3048)
			(stroke
				(width 0.1)
				(type default)
			)
			(layer "F.Fab")
		)
		(pad "1" smd circle
			(at -0.40005 0)
			(size 0 0)
			(layers "F.Cu" "F.Mask" "F.Paste")
			(net "SW_P12V_PVCCIN_CPU1_FLT")
		)
		(pad "2" smd circle
			(at 0.40005 0)
			(size 0 0)
			(layers "F.Cu" "F.Mask" "F.Paste")
			(net "GND")
		)
	)
	(footprint ""
		(layer "F.Cu")
		(at 362.49737 -355.340666 -90)
		(property "Reference" "PR345"
			(at 0 0 270)
			(layer "F.SilkS")
			(hide yes)
			(effects
				(font
					(size 1.27 1.27)
				)
			)
		)
		(property "Value" ""
			(at 0 0 270)
			(layer "F.Fab")
			(effects
				(font
					(size 1.27 1.27)
				)
			)
		)
		(duplicate_pad_numbers_are_jumpers no)
		(fp_line
			(start -0.7874 0.4064)
			(end -0.7874 -0.4064)
			(stroke
				(width 0.1524)
				(type default)
			)
			(layer "F.SilkS")
		)
		(fp_line
			(start 0.7874 0.4064)
			(end -0.7874 0.4064)
			(stroke
				(width 0.1524)
				(type default)
			)
			(layer "F.SilkS")
		)
		(fp_line
			(start -0.7874 -0.4064)
			(end 0.7874 -0.4064)
			(stroke
				(width 0.1524)
				(type default)
			)
			(layer "F.SilkS")
		)
		(fp_line
			(start 0.7874 -0.4064)
			(end 0.7874 0.4064)
			(stroke
				(width 0.1524)
				(type default)
			)
			(layer "F.SilkS")
		)
		(fp_line
			(start -0.67945 0.3048)
			(end -0.67945 -0.305054)
			(stroke
				(width 0.1)
				(type default)
			)
			(layer "F.Fab")
		)
		(fp_line
			(start -0.12065 0.3048)
			(end -0.67945 0.3048)
			(stroke
				(width 0.1)
				(type default)
			)
			(layer "F.Fab")
		)
		(fp_line
			(start 0.120396 0.3048)
			(end 0.120396 0.2794)
			(stroke
				(width 0.1)
				(type default)
			)
			(layer "F.Fab")
		)
		(fp_line
			(start 0.67945 0.3048)
			(end 0.120396 0.3048)
			(stroke
				(width 0.1)
				(type default)
			)
			(layer "F.Fab")
		)
		(fp_line
			(start -0.12065 0.2794)
			(end -0.12065 0.3048)
			(stroke
				(width 0.1)
				(type default)
			)
			(layer "F.Fab")
		)
		(fp_line
			(start 0.120396 0.2794)
			(end -0.12065 0.2794)
			(stroke
				(width 0.1)
				(type default)
			)
			(layer "F.Fab")
		)
		(fp_line
			(start -0.12065 -0.2794)
			(end 0.12065 -0.2794)
			(stroke
				(width 0.1)
				(type default)
			)
			(layer "F.Fab")
		)
		(fp_line
			(start 0.12065 -0.2794)
			(end 0.12065 -0.3048)
			(stroke
				(width 0.1)
				(type default)
			)
			(layer "F.Fab")
		)
		(fp_line
			(start 0.12065 -0.3048)
			(end 0.67945 -0.3048)
			(stroke
				(width 0.1)
				(type default)
			)
			(layer "F.Fab")
		)
		(fp_line
			(start 0.67945 -0.3048)
			(end 0.67945 0.3048)
			(stroke
				(width 0.1)
				(type default)
			)
			(layer "F.Fab")
		)
		(fp_line
			(start -0.67945 -0.305054)
			(end -0.12065 -0.305054)
			(stroke
				(width 0.1)
				(type default)
			)
			(layer "F.Fab")
		)
		(fp_line
			(start -0.12065 -0.305054)
			(end -0.12065 -0.2794)
			(stroke
				(width 0.1)
				(type default)
			)
			(layer "F.Fab")
		)
		(pad "1" smd circle
			(at -0.40005 0 270)
			(size 0 0)
			(layers "F.Cu" "F.Mask" "F.Paste")
			(net "SH_PVCCFA_EHV_FIVRA_CPU0")
		)
		(pad "2" smd circle
			(at 0.40005 0 270)
			(size 0 0)
			(layers "F.Cu" "F.Mask" "F.Paste")
			(net "SH_PVCCFA_EHV_FIVRA_CPU0_R")
		)
	)
	(footprint ""
		(layer "F.Cu")
		(at 255.45669 -39.482522 -90)
		(property "Reference" "PC2215"
			(at 0 0 270)
			(layer "F.SilkS")
			(hide yes)
			(effects
				(font
					(size 1.27 1.27)
				)
			)
		)
		(property "Value" ""
			(at 0 0 270)
			(layer "F.Fab")
			(effects
				(font
					(size 1.27 1.27)
				)
			)
		)
		(duplicate_pad_numbers_are_jumpers no)
		(fp_line
			(start -0.7874 0.4064)
			(end -0.7874 -0.4064)
			(stroke
				(width 0.1524)
				(type default)
			)
			(layer "F.SilkS")
		)
		(fp_line
			(start 0.7874 0.4064)
			(end -0.7874 0.4064)
			(stroke
				(width 0.1524)
				(type default)
			)
			(layer "F.SilkS")
		)
		(fp_line
			(start -0.7874 -0.4064)
			(end 0.7874 -0.4064)
			(stroke
				(width 0.1524)
				(type default)
			)
			(layer "F.SilkS")
		)
		(fp_line
			(start 0.7874 -0.4064)
			(end 0.7874 0.4064)
			(stroke
				(width 0.1524)
				(type default)
			)
			(layer "F.SilkS")
		)
		(fp_line
			(start -0.67945 0.3048)
			(end -0.67945 -0.305054)
			(stroke
				(width 0.1)
				(type default)
			)
			(layer "F.Fab")
		)
		(fp_line
			(start -0.12065 0.3048)
			(end -0.67945 0.3048)
			(stroke
				(width 0.1)
				(type default)
			)
			(layer "F.Fab")
		)
		(fp_line
			(start 0.120396 0.3048)
			(end 0.120396 0.2794)
			(stroke
				(width 0.1)
				(type default)
			)
			(layer "F.Fab")
		)
		(fp_line
			(start 0.67945 0.3048)
			(end 0.120396 0.3048)
			(stroke
				(width 0.1)
				(type default)
			)
			(layer "F.Fab")
		)
		(fp_line
			(start -0.12065 0.2794)
			(end -0.12065 0.3048)
			(stroke
				(width 0.1)
				(type default)
			)
			(layer "F.Fab")
		)
		(fp_line
			(start 0.120396 0.2794)
			(end -0.12065 0.2794)
			(stroke
				(width 0.1)
				(type default)
			)
			(layer "F.Fab")
		)
		(fp_line
			(start -0.12065 -0.2794)
			(end 0.12065 -0.2794)
			(stroke
				(width 0.1)
				(type default)
			)
			(layer "F.Fab")
		)
		(fp_line
			(start 0.12065 -0.2794)
			(end 0.12065 -0.3048)
			(stroke
				(width 0.1)
				(type default)
			)
			(layer "F.Fab")
		)
		(fp_line
			(start 0.12065 -0.3048)
			(end 0.67945 -0.3048)
			(stroke
				(width 0.1)
				(type default)
			)
			(layer "F.Fab")
		)
		(fp_line
			(start 0.67945 -0.3048)
			(end 0.67945 0.3048)
			(stroke
				(width 0.1)
				(type default)
			)
			(layer "F.Fab")
		)
		(fp_line
			(start -0.67945 -0.305054)
			(end -0.12065 -0.305054)
			(stroke
				(width 0.1)
				(type default)
			)
			(layer "F.Fab")
		)
		(fp_line
			(start -0.12065 -0.305054)
			(end -0.12065 -0.2794)
			(stroke
				(width 0.1)
				(type default)
			)
			(layer "F.Fab")
		)
		(pad "1" smd circle
			(at -0.40005 0 270)
			(size 0 0)
			(layers "F.Cu" "F.Mask" "F.Paste")
			(net "P12V_E1S_GATE_0")
		)
		(pad "2" smd circle
			(at 0.40005 0 270)
			(size 0 0)
			(layers "F.Cu" "F.Mask" "F.Paste")
			(net "GND")
		)
	)
	(footprint ""
		(layer "F.Cu")
		(at 186.8678 -358.14635)
		(property "Reference" "PC726_P1_3"
			(at 0 0 0)
			(layer "F.SilkS")
			(hide yes)
			(effects
				(font
					(size 1.27 1.27)
				)
			)
		)
		(property "Value" ""
			(at 0 0 0)
			(layer "F.Fab")
			(effects
				(font
					(size 1.27 1.27)
				)
			)
		)
		(duplicate_pad_numbers_are_jumpers no)
		(fp_line
			(start -1.524 -0.762)
			(end 1.524 -0.762)
			(stroke
				(width 0.1524)
				(type default)
			)
			(layer "F.SilkS")
		)
		(fp_line
			(start -1.524 0.762)
			(end -1.524 -0.762)
			(stroke
				(width 0.1524)
				(type default)
			)
			(layer "F.SilkS")
		)
		(fp_line
			(start 1.524 -0.762)
			(end 1.524 0.762)
			(stroke
				(width 0.1524)
				(type default)
			)
			(layer "F.SilkS")
		)
		(fp_line
			(start 1.524 0.762)
			(end -1.524 0.762)
			(stroke
				(width 0.1524)
				(type default)
			)
			(layer "F.SilkS")
		)
		(fp_line
			(start -1.1049 -0.724916)
			(end -1.1049 0.724916)
			(stroke
				(width 0.1)
				(type default)
			)
			(layer "F.Fab")
		)
		(fp_line
			(start -1.1049 0.724916)
			(end 1.1049 0.724916)
			(stroke
				(width 0.1)
				(type default)
			)
			(layer "F.Fab")
		)
		(fp_line
			(start 1.1049 -0.724916)
			(end -1.1049 -0.724916)
			(stroke
				(width 0.1)
				(type default)
			)
			(layer "F.Fab")
		)
		(fp_line
			(start 1.1049 0.724916)
			(end 1.1049 -0.724916)
			(stroke
				(width 0.1)
				(type default)
			)
			(layer "F.Fab")
		)
		(pad "1" smd rect
			(at -0.889 0 180)
			(size 1.016 1.27)
			(layers "F.Cu" "F.Mask" "F.Paste")
			(net "SW_P12V_PVCCFA_EHV_FIVRA_CPU1_R")
		)
		(pad "2" smd rect
			(at 0.889 0 180)
			(size 1.016 1.27)
			(layers "F.Cu" "F.Mask" "F.Paste")
			(net "GND")
		)
	)
	(footprint ""
		(layer "F.Cu")
		(at 265.64971 -22.29993)
		(property "Reference" "H102"
			(at -4.51104 -5.629148 0)
			(unlocked yes)
			(layer "F.SilkS")
			(effects
				(font
					(size 0.7874 0.5842)
					(thickness 0.1524)
				)
				(justify left)
			)
		)
		(property "Value" ""
			(at 0 0 0)
			(layer "F.Fab")
			(effects
				(font
					(size 1.27 1.27)
				)
			)
		)
		(duplicate_pad_numbers_are_jumpers no)
		(pad "1" thru_hole circle
			(at 0 0)
			(size 10.0076 10.0076)
			(drill 5.6134)
			(layers "*.Cu" "*.Mask")
			(remove_unused_layers no)
			(net "GND")
			(clearance -1.9431)
		)
	)
	(footprint ""
		(layer "F.Cu")
		(at 169.44848 -423.890948)
		(property "Reference" "R2909"
			(at 0 0 0)
			(layer "F.SilkS")
			(hide yes)
			(effects
				(font
					(size 1.27 1.27)
				)
			)
		)
		(property "Value" ""
			(at 0 0 0)
			(layer "F.Fab")
			(effects
				(font
					(size 1.27 1.27)
				)
			)
		)
		(duplicate_pad_numbers_are_jumpers no)
		(fp_line
			(start -0.7874 -0.4064)
			(end 0.7874 -0.4064)
			(stroke
				(width 0.1524)
				(type default)
			)
			(layer "F.SilkS")
		)
		(fp_line
			(start -0.7874 0.4064)
			(end -0.7874 -0.4064)
			(stroke
				(width 0.1524)
				(type default)
			)
			(layer "F.SilkS")
		)
		(fp_line
			(start 0.7874 -0.4064)
			(end 0.7874 0.4064)
			(stroke
				(width 0.1524)
				(type default)
			)
			(layer "F.SilkS")
		)
		(fp_line
			(start 0.7874 0.4064)
			(end -0.7874 0.4064)
			(stroke
				(width 0.1524)
				(type default)
			)
			(layer "F.SilkS")
		)
		(fp_line
			(start -0.67945 -0.305054)
			(end -0.12065 -0.305054)
			(stroke
				(width 0.1)
				(type default)
			)
			(layer "F.Fab")
		)
		(fp_line
			(start -0.67945 0.3048)
			(end -0.67945 -0.305054)
			(stroke
				(width 0.1)
				(type default)
			)
			(layer "F.Fab")
		)
		(fp_line
			(start -0.12065 -0.305054)
			(end -0.12065 -0.2794)
			(stroke
				(width 0.1)
				(type default)
			)
			(layer "F.Fab")
		)
		(fp_line
			(start -0.12065 -0.2794)
			(end 0.12065 -0.2794)
			(stroke
				(width 0.1)
				(type default)
			)
			(layer "F.Fab")
		)
		(fp_line
			(start -0.12065 0.2794)
			(end -0.12065 0.3048)
			(stroke
				(width 0.1)
				(type default)
			)
			(layer "F.Fab")
		)
		(fp_line
			(start -0.12065 0.3048)
			(end -0.67945 0.3048)
			(stroke
				(width 0.1)
				(type default)
			)
			(layer "F.Fab")
		)
		(fp_line
			(start 0.120396 0.2794)
			(end -0.12065 0.2794)
			(stroke
				(width 0.1)
				(type default)
			)
			(layer "F.Fab")
		)
		(fp_line
			(start 0.120396 0.3048)
			(end 0.120396 0.2794)
			(stroke
				(width 0.1)
				(type default)
			)
			(layer "F.Fab")
		)
		(fp_line
			(start 0.12065 -0.3048)
			(end 0.67945 -0.3048)
			(stroke
				(width 0.1)
				(type default)
			)
			(layer "F.Fab")
		)
		(fp_line
			(start 0.12065 -0.2794)
			(end 0.12065 -0.3048)
			(stroke
				(width 0.1)
				(type default)
			)
			(layer "F.Fab")
		)
		(fp_line
			(start 0.67945 -0.3048)
			(end 0.67945 0.3048)
			(stroke
				(width 0.1)
				(type default)
			)
			(layer "F.Fab")
		)
		(fp_line
			(start 0.67945 0.3048)
			(end 0.120396 0.3048)
			(stroke
				(width 0.1)
				(type default)
			)
			(layer "F.Fab")
		)
		(pad "1" smd circle
			(at -0.40005 0)
			(size 0 0)
			(layers "F.Cu" "F.Mask" "F.Paste")
			(net "P3V3_AUX")
		)
		(pad "2" smd circle
			(at 0.40005 0)
			(size 0 0)
			(layers "F.Cu" "F.Mask" "F.Paste")
			(net "RST_SWB_BIC_R_N")
		)
	)
	(footprint ""
		(layer "F.Cu")
		(at 360.482642 -392.04265)
		(property "Reference" "R4168"
			(at 0 0 0)
			(layer "F.SilkS")
			(hide yes)
			(effects
				(font
					(size 1.27 1.27)
				)
			)
		)
		(property "Value" ""
			(at 0 0 0)
			(layer "F.Fab")
			(effects
				(font
					(size 1.27 1.27)
				)
			)
		)
		(duplicate_pad_numbers_are_jumpers no)
		(fp_line
			(start -0.7874 -0.4064)
			(end 0.7874 -0.4064)
			(stroke
				(width 0.1524)
				(type default)
			)
			(layer "F.SilkS")
		)
		(fp_line
			(start -0.7874 0.4064)
			(end -0.7874 -0.4064)
			(stroke
				(width 0.1524)
				(type default)
			)
			(layer "F.SilkS")
		)
		(fp_line
			(start 0.7874 -0.4064)
			(end 0.7874 0.4064)
			(stroke
				(width 0.1524)
				(type default)
			)
			(layer "F.SilkS")
		)
		(fp_line
			(start 0.7874 0.4064)
			(end -0.7874 0.4064)
			(stroke
				(width 0.1524)
				(type default)
			)
			(layer "F.SilkS")
		)
		(fp_line
			(start -0.67945 -0.305054)
			(end -0.12065 -0.305054)
			(stroke
				(width 0.1)
				(type default)
			)
			(layer "F.Fab")
		)
		(fp_line
			(start -0.67945 0.3048)
			(end -0.67945 -0.305054)
			(stroke
				(width 0.1)
				(type default)
			)
			(layer "F.Fab")
		)
		(fp_line
			(start -0.12065 -0.305054)
			(end -0.12065 -0.2794)
			(stroke
				(width 0.1)
				(type default)
			)
			(layer "F.Fab")
		)
		(fp_line
			(start -0.12065 -0.2794)
			(end 0.12065 -0.2794)
			(stroke
				(width 0.1)
				(type default)
			)
			(layer "F.Fab")
		)
		(fp_line
			(start -0.12065 0.2794)
			(end -0.12065 0.3048)
			(stroke
				(width 0.1)
				(type default)
			)
			(layer "F.Fab")
		)
		(fp_line
			(start -0.12065 0.3048)
			(end -0.67945 0.3048)
			(stroke
				(width 0.1)
				(type default)
			)
			(layer "F.Fab")
		)
		(fp_line
			(start 0.120396 0.2794)
			(end -0.12065 0.2794)
			(stroke
				(width 0.1)
				(type default)
			)
			(layer "F.Fab")
		)
		(fp_line
			(start 0.120396 0.3048)
			(end 0.120396 0.2794)
			(stroke
				(width 0.1)
				(type default)
			)
			(layer "F.Fab")
		)
		(fp_line
			(start 0.12065 -0.3048)
			(end 0.67945 -0.3048)
			(stroke
				(width 0.1)
				(type default)
			)
			(layer "F.Fab")
		)
		(fp_line
			(start 0.12065 -0.2794)
			(end 0.12065 -0.3048)
			(stroke
				(width 0.1)
				(type default)
			)
			(layer "F.Fab")
		)
		(fp_line
			(start 0.67945 -0.3048)
			(end 0.67945 0.3048)
			(stroke
				(width 0.1)
				(type default)
			)
			(layer "F.Fab")
		)
		(fp_line
			(start 0.67945 0.3048)
			(end 0.120396 0.3048)
			(stroke
				(width 0.1)
				(type default)
			)
			(layer "F.Fab")
		)
		(pad "1" smd circle
			(at -0.40005 0)
			(size 0 0)
			(layers "F.Cu" "F.Mask" "F.Paste")
			(net "P3V3_AUX")
		)
		(pad "2" smd circle
			(at 0.40005 0)
			(size 0 0)
			(layers "F.Cu" "F.Mask" "F.Paste")
			(net "GPU_3V3IO_RSVD4_ISO")
		)
	)
	(footprint ""
		(layer "F.Cu")
		(at 55.427118 -408.517344 -90)
		(property "Reference" "C704"
			(at 0 0 270)
			(layer "F.SilkS")
			(hide yes)
			(effects
				(font
					(size 1.27 1.27)
				)
			)
		)
		(property "Value" ""
			(at 0 0 270)
			(layer "F.Fab")
			(effects
				(font
					(size 1.27 1.27)
				)
			)
		)
		(duplicate_pad_numbers_are_jumpers no)
		(fp_line
			(start -0.299974 0.150114)
			(end -0.299974 -0.150114)
			(stroke
				(width 0.1)
				(type default)
			)
			(layer "F.Fab")
		)
		(fp_line
			(start 0.299974 0.150114)
			(end -0.299974 0.150114)
			(stroke
				(width 0.1)
				(type default)
			)
			(layer "F.Fab")
		)
		(fp_line
			(start -0.299974 -0.150114)
			(end 0.299974 -0.150114)
			(stroke
				(width 0.1)
				(type default)
			)
			(layer "F.Fab")
		)
		(fp_line
			(start 0.299974 -0.150114)
			(end 0.299974 0.150114)
			(stroke
				(width 0.1)
				(type default)
			)
			(layer "F.Fab")
		)
		(pad "1" smd rect
			(at -0.2667 0 270)
			(size 0.3048 0.381)
			(layers "F.Cu" "F.Mask" "F.Paste")
			(net "P5E_CPU1_PE4_TX_C_DN<2>")
		)
		(pad "2" smd rect
			(at 0.2667 0 270)
			(size 0.3048 0.381)
			(layers "F.Cu" "F.Mask" "F.Paste")
			(net "P5E_CPU1_PE4_TX_DN<2>")
		)
	)
	(footprint ""
		(layer "F.Cu")
		(at 442.353192 -28.175458 -90)
		(property "Reference" "PU204"
			(at 1.50749 -4.241038 0)
			(unlocked yes)
			(layer "F.SilkS")
			(effects
				(font
					(size 0.7874 0.5842)
					(thickness 0.1524)
				)
				(justify left)
			)
		)
		(property "Value" ""
			(at 0 0 270)
			(layer "F.Fab")
			(effects
				(font
					(size 1.27 1.27)
				)
			)
		)
		(duplicate_pad_numbers_are_jumpers no)
		(fp_line
			(start -1.549908 2.549906)
			(end -0.753872 2.549906)
			(stroke
				(width 0.1524)
				(type default)
			)
			(layer "F.SilkS")
		)
		(fp_line
			(start -0.245872 2.549906)
			(end 0.245872 2.549906)
			(stroke
				(width 0.1524)
				(type default)
			)
			(layer "F.SilkS")
		)
		(fp_line
			(start 0.753872 2.549906)
			(end 1.549908 2.549906)
			(stroke
				(width 0.1524)
				(type default)
			)
			(layer "F.SilkS")
		)
		(fp_line
			(start 1.549908 2.549906)
			(end 1.549908 2.253996)
			(stroke
				(width 0.1524)
				(type default)
			)
			(layer "F.SilkS")
		)
		(fp_line
			(start -1.549908 2.253996)
			(end -1.549908 2.549906)
			(stroke
				(width 0.1524)
				(type default)
			)
			(layer "F.SilkS")
		)
		(fp_line
			(start 1.549908 -2.253996)
			(end 1.549908 -2.549906)
			(stroke
				(width 0.1524)
				(type default)
			)
			(layer "F.SilkS")
		)
		(fp_line
			(start -1.549908 -2.549906)
			(end -1.549908 -2.251964)
			(stroke
				(width 0.1524)
				(type default)
			)
			(layer "F.SilkS")
		)
		(fp_line
			(start -0.752094 -2.549906)
			(end -1.549908 -2.549906)
			(stroke
				(width 0.1524)
				(type default)
			)
			(layer "F.SilkS")
		)
		(fp_line
			(start 0.2413 -2.549906)
			(end -0.2413 -2.549906)
			(stroke
				(width 0.1524)
				(type default)
			)
			(layer "F.SilkS")
		)
		(fp_line
			(start 1.549908 -2.549906)
			(end 0.752094 -2.549906)
			(stroke
				(width 0.1524)
				(type default)
			)
			(layer "F.SilkS")
		)
		(fp_poly
			(pts
				(xy -2.7432 -1.574292) (xy -2.7432 -2.4257) (xy -1.891538 -1.999996)
			)
			(stroke
				(width 0)
				(type default)
			)
			(fill yes)
			(layer "F.SilkS")
		)
		(fp_line
			(start -1.549908 2.549906)
			(end 1.549908 2.549906)
			(stroke
				(width 0.1)
				(type default)
			)
			(layer "F.Fab")
		)
		(fp_line
			(start 1.549908 2.549906)
			(end 1.549908 -2.549906)
			(stroke
				(width 0.1)
				(type default)
			)
			(layer "F.Fab")
		)
		(fp_line
			(start -1.549908 -2.549906)
			(end -1.549908 2.549906)
			(stroke
				(width 0.1)
				(type default)
			)
			(layer "F.Fab")
		)
		(fp_line
			(start 1.549908 -2.549906)
			(end -1.549908 -2.549906)
			(stroke
				(width 0.1)
				(type default)
			)
			(layer "F.Fab")
		)
		(fp_poly
			(pts
				(xy -1.891538 -1.999996) (xy -2.7432 -1.574292) (xy -2.7432 -2.4257)
			)
			(stroke
				(width 0)
				(type default)
			)
			(fill yes)
			(layer "F.Fab")
		)
		(fp_text user "11"
			(at 2.33934 5.998972 0)
			(unlocked yes)
			(layer "F.SilkS")
			(effects
				(font
					(size 0.635 0.4064)
					(thickness 0.1524)
				)
			)
		)
		(fp_text user "10"
			(at -2.46126 2.928112 0)
			(unlocked yes)
			(layer "F.SilkS")
			(effects
				(font
					(size 0.635 0.4064)
					(thickness 0.1524)
				)
			)
		)
		(fp_text user "9"
			(at -2.50698 1.411732 0)
			(unlocked yes)
			(layer "F.SilkS")
			(effects
				(font
					(size 0.635 0.4064)
					(thickness 0.1524)
				)
			)
		)
		(fp_text user "12"
			(at 3.9624 0.611632 0)
			(unlocked yes)
			(layer "F.SilkS")
			(effects
				(font
					(size 0.635 0.4064)
					(thickness 0.1524)
				)
			)
		)
		(fp_text user "20"
			(at 1.58496 -3.434588 0)
			(unlocked yes)
			(layer "F.SilkS")
			(effects
				(font
					(size 0.635 0.4064)
					(thickness 0.1524)
				)
			)
		)
		(fp_text user "21_22"
			(at -0.53086 -4.237228 0)
			(unlocked yes)
			(layer "F.SilkS")
			(effects
				(font
					(size 0.635 0.4064)
					(thickness 0.1524)
				)
			)
		)
		(fp_text user "11"
			(at 1.1938 3.329432 270)
			(unlocked yes)
			(layer "F.Fab")
			(effects
				(font
					(size 0.635 0.4064)
					(thickness 0.1524)
				)
			)
		)
		(fp_text user "10"
			(at -1.4224 3.253232 270)
			(unlocked yes)
			(layer "F.Fab")
			(effects
				(font
					(size 0.635 0.4064)
					(thickness 0.1524)
				)
			)
		)
		(fp_text user "12"
			(at 2.207768 2.7178 180)
			(unlocked yes)
			(layer "F.Fab")
			(effects
				(font
					(size 0.635 0.4064)
					(thickness 0.1524)
				)
			)
		)
		(fp_text user "9"
			(at -2.338832 2.5908 180)
			(unlocked yes)
			(layer "F.Fab")
			(effects
				(font
					(size 0.635 0.4064)
					(thickness 0.1524)
				)
			)
		)
		(fp_text user "20"
			(at 2.055368 -2.7686 180)
			(unlocked yes)
			(layer "F.Fab")
			(effects
				(font
					(size 0.635 0.4064)
					(thickness 0.1524)
				)
			)
		)
		(fp_text user "21_22"
			(at -0.0762 -3.401568 270)
			(unlocked yes)
			(layer "F.Fab")
			(effects
				(font
					(size 0.635 0.4064)
					(thickness 0.1524)
				)
			)
		)
		(pad "1" smd circle
			(at -1.374902 -1.999996 180)
			(size 0 0)
			(layers "F.Cu" "F.Mask" "F.Paste")
			(net "P12V_OCP_EN_1_R2")
		)
		(pad "2" smd rect
			(at -1.400048 -1.500124 180)
			(size 0.254 0.8128)
			(layers "F.Cu" "F.Mask" "F.Paste")
			(net "GND")
		)
		(pad "3" smd rect
			(at -1.400048 -0.999998 180)
			(size 0.254 0.8128)
			(layers "F.Cu" "F.Mask" "F.Paste")
			(net "GND")
		)
		(pad "4" smd rect
			(at -1.400048 -0.499872 180)
			(size 0.254 0.8128)
			(layers "F.Cu" "F.Mask" "F.Paste")
			(net "P12V_OCP_TIMER_1")
		)
		(pad "5" smd rect
			(at -1.400048 0 180)
			(size 0.254 0.8128)
			(layers "F.Cu" "F.Mask" "F.Paste")
			(net "P12V_OCP_ISET_1")
		)
		(pad "6" smd rect
			(at -1.400048 0.499872 180)
			(size 0.254 0.8128)
			(layers "F.Cu" "F.Mask" "F.Paste")
			(net "P12V_OCP_SS_1")
		)
		(pad "7" smd rect
			(at -1.400048 0.999998 180)
			(size 0.254 0.8128)
			(layers "F.Cu" "F.Mask" "F.Paste")
			(net "GND")
		)
		(pad "8" smd rect
			(at -1.400048 1.500124 180)
			(size 0.254 0.8128)
			(layers "F.Cu" "F.Mask" "F.Paste")
			(net "P12V_OCP_IMON_1")
		)
		(pad "9" smd rect
			(at -1.400048 1.999996 180)
			(size 0.254 0.8128)
			(layers "F.Cu" "F.Mask" "F.Paste")
			(net "P12V_OCP_FLTB_1")
		)
		(pad "10" smd rect
			(at -0.499872 2.400046 270)
			(size 0.254 0.8128)
			(layers "F.Cu" "F.Mask" "F.Paste")
			(net "HP_LVC3_OCP_V3_1_P12V_PWRGD")
		)
		(pad "11" smd rect
			(at 0.499872 2.400046 270)
			(size 0.254 0.8128)
			(layers "F.Cu" "F.Mask" "F.Paste")
			(net "P12V_OCP_OV_FB_1")
		)
		(pad "12" smd rect
			(at 1.400048 1.999996 180)
			(size 0.254 0.8128)
			(layers "F.Cu" "F.Mask" "F.Paste")
			(net "P12V_OCP_AVIN_PD_1")
		)
		(pad "13" smd rect
			(at 1.400048 1.500124 180)
			(size 0.254 0.8128)
			(layers "F.Cu" "F.Mask" "F.Paste")
			(net "P12V_OCP_SFF")
		)
		(pad "14" smd rect
			(at 1.400048 0.999998 180)
			(size 0.254 0.8128)
			(layers "F.Cu" "F.Mask" "F.Paste")
			(net "P12V_OCP_SFF")
		)
		(pad "15" smd rect
			(at 1.400048 0.499872 180)
			(size 0.254 0.8128)
			(layers "F.Cu" "F.Mask" "F.Paste")
			(net "P12V_OCP_SFF")
		)
		(pad "16" smd rect
			(at 1.400048 0 180)
			(size 0.254 0.8128)
			(layers "F.Cu" "F.Mask" "F.Paste")
			(net "P12V_OCP_SFF")
		)
		(pad "17" smd rect
			(at 1.400048 -0.499872 180)
			(size 0.254 0.8128)
			(layers "F.Cu" "F.Mask" "F.Paste")
			(net "P12V_OCP_SFF")
		)
		(pad "18" smd rect
			(at 1.400048 -0.999998 180)
			(size 0.254 0.8128)
			(layers "F.Cu" "F.Mask" "F.Paste")
			(net "P12V_OCP_SFF")
		)
		(pad "19" smd rect
			(at 1.400048 -1.500124 180)
			(size 0.254 0.8128)
			(layers "F.Cu" "F.Mask" "F.Paste")
			(net "P12V_OCP_SFF")
		)
		(pad "20" smd rect
			(at 1.400048 -1.999996 180)
			(size 0.254 0.8128)
			(layers "F.Cu" "F.Mask" "F.Paste")
			(net "P12V_OCP_SFF")
		)
		(pad "21_22" smd circle
			(at 0.499872 -2.337562 180)
			(size 0 0)
			(layers "F.Cu" "F.Mask" "F.Paste")
			(net "P12V_AUX")
		)
		(pad "23" smd rect
			(at 0 -1.100074 180)
			(size 0.254 1.27)
			(layers "F.Cu" "F.Mask" "F.Paste")
			(net "P12V_AUX")
		)
		(pad "24" smd rect
			(at 0 -0.199898 180)
			(size 0.254 1.27)
			(layers "F.Cu" "F.Mask" "F.Paste")
			(net "P12V_AUX")
		)
		(pad "25" smd rect
			(at 0 0.700024 180)
			(size 0.254 1.27)
			(layers "F.Cu" "F.Mask" "F.Paste")
			(net "P12V_AUX")
		)
		(pad "26" smd rect
			(at 0 1.599946 180)
			(size 0.254 1.27)
			(layers "F.Cu" "F.Mask" "F.Paste")
			(net "P12V_AUX")
		)
	)
	(footprint ""
		(layer "F.Cu")
		(at 267.38707 -92.63253 -90)
		(property "Reference" "R1305"
			(at 0 0 270)
			(layer "F.SilkS")
			(hide yes)
			(effects
				(font
					(size 1.27 1.27)
				)
			)
		)
		(property "Value" ""
			(at 0 0 270)
			(layer "F.Fab")
			(effects
				(font
					(size 1.27 1.27)
				)
			)
		)
		(duplicate_pad_numbers_are_jumpers no)
		(fp_line
			(start -0.7874 0.4064)
			(end -0.7874 -0.4064)
			(stroke
				(width 0.1524)
				(type default)
			)
			(layer "F.SilkS")
		)
		(fp_line
			(start 0.7874 0.4064)
			(end -0.7874 0.4064)
			(stroke
				(width 0.1524)
				(type default)
			)
			(layer "F.SilkS")
		)
		(fp_line
			(start -0.7874 -0.4064)
			(end 0.7874 -0.4064)
			(stroke
				(width 0.1524)
				(type default)
			)
			(layer "F.SilkS")
		)
		(fp_line
			(start 0.7874 -0.4064)
			(end 0.7874 0.4064)
			(stroke
				(width 0.1524)
				(type default)
			)
			(layer "F.SilkS")
		)
		(fp_line
			(start -0.67945 0.3048)
			(end -0.67945 -0.305054)
			(stroke
				(width 0.1)
				(type default)
			)
			(layer "F.Fab")
		)
		(fp_line
			(start -0.12065 0.3048)
			(end -0.67945 0.3048)
			(stroke
				(width 0.1)
				(type default)
			)
			(layer "F.Fab")
		)
		(fp_line
			(start 0.120396 0.3048)
			(end 0.120396 0.2794)
			(stroke
				(width 0.1)
				(type default)
			)
			(layer "F.Fab")
		)
		(fp_line
			(start 0.67945 0.3048)
			(end 0.120396 0.3048)
			(stroke
				(width 0.1)
				(type default)
			)
			(layer "F.Fab")
		)
		(fp_line
			(start -0.12065 0.2794)
			(end -0.12065 0.3048)
			(stroke
				(width 0.1)
				(type default)
			)
			(layer "F.Fab")
		)
		(fp_line
			(start 0.120396 0.2794)
			(end -0.12065 0.2794)
			(stroke
				(width 0.1)
				(type default)
			)
			(layer "F.Fab")
		)
		(fp_line
			(start -0.12065 -0.2794)
			(end 0.12065 -0.2794)
			(stroke
				(width 0.1)
				(type default)
			)
			(layer "F.Fab")
		)
		(fp_line
			(start 0.12065 -0.2794)
			(end 0.12065 -0.3048)
			(stroke
				(width 0.1)
				(type default)
			)
			(layer "F.Fab")
		)
		(fp_line
			(start 0.12065 -0.3048)
			(end 0.67945 -0.3048)
			(stroke
				(width 0.1)
				(type default)
			)
			(layer "F.Fab")
		)
		(fp_line
			(start 0.67945 -0.3048)
			(end 0.67945 0.3048)
			(stroke
				(width 0.1)
				(type default)
			)
			(layer "F.Fab")
		)
		(fp_line
			(start -0.67945 -0.305054)
			(end -0.12065 -0.305054)
			(stroke
				(width 0.1)
				(type default)
			)
			(layer "F.Fab")
		)
		(fp_line
			(start -0.12065 -0.305054)
			(end -0.12065 -0.2794)
			(stroke
				(width 0.1)
				(type default)
			)
			(layer "F.Fab")
		)
		(pad "1" smd circle
			(at -0.40005 0 270)
			(size 0 0)
			(layers "F.Cu" "F.Mask" "F.Paste")
			(net "P3V3_AUX")
		)
		(pad "2" smd circle
			(at 0.40005 0 270)
			(size 0 0)
			(layers "F.Cu" "F.Mask" "F.Paste")
			(net "FM_PLD_CLKS_DEV_EN")
		)
	)
	(footprint ""
		(layer "F.Cu")
		(at 115.951 -56.479948 180)
		(property "Reference" "R4633"
			(at 0 0 180)
			(layer "F.SilkS")
			(hide yes)
			(effects
				(font
					(size 1.27 1.27)
				)
			)
		)
		(property "Value" ""
			(at 0 0 180)
			(layer "F.Fab")
			(effects
				(font
					(size 1.27 1.27)
				)
			)
		)
		(duplicate_pad_numbers_are_jumpers no)
		(fp_line
			(start 0.7874 0.4064)
			(end -0.7874 0.4064)
			(stroke
				(width 0.1524)
				(type default)
			)
			(layer "F.SilkS")
		)
		(fp_line
			(start 0.7874 -0.4064)
			(end 0.7874 0.4064)
			(stroke
				(width 0.1524)
				(type default)
			)
			(layer "F.SilkS")
		)
		(fp_line
			(start -0.7874 0.4064)
			(end -0.7874 -0.4064)
			(stroke
				(width 0.1524)
				(type default)
			)
			(layer "F.SilkS")
		)
		(fp_line
			(start -0.7874 -0.4064)
			(end 0.7874 -0.4064)
			(stroke
				(width 0.1524)
				(type default)
			)
			(layer "F.SilkS")
		)
		(fp_line
			(start 0.67945 0.3048)
			(end 0.120396 0.3048)
			(stroke
				(width 0.1)
				(type default)
			)
			(layer "F.Fab")
		)
		(fp_line
			(start 0.67945 -0.3048)
			(end 0.67945 0.3048)
			(stroke
				(width 0.1)
				(type default)
			)
			(layer "F.Fab")
		)
		(fp_line
			(start 0.12065 -0.2794)
			(end 0.12065 -0.3048)
			(stroke
				(width 0.1)
				(type default)
			)
			(layer "F.Fab")
		)
		(fp_line
			(start 0.12065 -0.3048)
			(end 0.67945 -0.3048)
			(stroke
				(width 0.1)
				(type default)
			)
			(layer "F.Fab")
		)
		(fp_line
			(start 0.120396 0.3048)
			(end 0.120396 0.2794)
			(stroke
				(width 0.1)
				(type default)
			)
			(layer "F.Fab")
		)
		(fp_line
			(start 0.120396 0.2794)
			(end -0.12065 0.2794)
			(stroke
				(width 0.1)
				(type default)
			)
			(layer "F.Fab")
		)
		(fp_line
			(start -0.12065 0.3048)
			(end -0.67945 0.3048)
			(stroke
				(width 0.1)
				(type default)
			)
			(layer "F.Fab")
		)
		(fp_line
			(start -0.12065 0.2794)
			(end -0.12065 0.3048)
			(stroke
				(width 0.1)
				(type default)
			)
			(layer "F.Fab")
		)
		(fp_line
			(start -0.12065 -0.2794)
			(end 0.12065 -0.2794)
			(stroke
				(width 0.1)
				(type default)
			)
			(layer "F.Fab")
		)
		(fp_line
			(start -0.12065 -0.305054)
			(end -0.12065 -0.2794)
			(stroke
				(width 0.1)
				(type default)
			)
			(layer "F.Fab")
		)
		(fp_line
			(start -0.67945 0.3048)
			(end -0.67945 -0.305054)
			(stroke
				(width 0.1)
				(type default)
			)
			(layer "F.Fab")
		)
		(fp_line
			(start -0.67945 -0.305054)
			(end -0.12065 -0.305054)
			(stroke
				(width 0.1)
				(type default)
			)
			(layer "F.Fab")
		)
		(pad "1" smd circle
			(at -0.40005 0 180)
			(size 0 0)
			(layers "F.Cu" "F.Mask" "F.Paste")
			(net "JTAG_BMC_SW_TCK_R")
		)
		(pad "2" smd circle
			(at 0.40005 0 180)
			(size 0 0)
			(layers "F.Cu" "F.Mask" "F.Paste")
			(net "JTAG_BMC_SW_TCK")
		)
	)
	(footprint ""
		(layer "F.Cu")
		(at 114.706654 -362.618528)
		(property "Reference" "PC552"
			(at 0 0 0)
			(layer "F.SilkS")
			(hide yes)
			(effects
				(font
					(size 1.27 1.27)
				)
			)
		)
		(property "Value" ""
			(at 0 0 0)
			(layer "F.Fab")
			(effects
				(font
					(size 1.27 1.27)
				)
			)
		)
		(duplicate_pad_numbers_are_jumpers no)
		(fp_line
			(start -0.7874 -0.4064)
			(end 0.7874 -0.4064)
			(stroke
				(width 0.1524)
				(type default)
			)
			(layer "F.SilkS")
		)
		(fp_line
			(start -0.7874 0.4064)
			(end -0.7874 -0.4064)
			(stroke
				(width 0.1524)
				(type default)
			)
			(layer "F.SilkS")
		)
		(fp_line
			(start 0.7874 -0.4064)
			(end 0.7874 0.4064)
			(stroke
				(width 0.1524)
				(type default)
			)
			(layer "F.SilkS")
		)
		(fp_line
			(start 0.7874 0.4064)
			(end -0.7874 0.4064)
			(stroke
				(width 0.1524)
				(type default)
			)
			(layer "F.SilkS")
		)
		(fp_line
			(start -0.67945 -0.305054)
			(end -0.12065 -0.305054)
			(stroke
				(width 0.1)
				(type default)
			)
			(layer "F.Fab")
		)
		(fp_line
			(start -0.67945 0.3048)
			(end -0.67945 -0.305054)
			(stroke
				(width 0.1)
				(type default)
			)
			(layer "F.Fab")
		)
		(fp_line
			(start -0.12065 -0.305054)
			(end -0.12065 -0.2794)
			(stroke
				(width 0.1)
				(type default)
			)
			(layer "F.Fab")
		)
		(fp_line
			(start -0.12065 -0.2794)
			(end 0.12065 -0.2794)
			(stroke
				(width 0.1)
				(type default)
			)
			(layer "F.Fab")
		)
		(fp_line
			(start -0.12065 0.2794)
			(end -0.12065 0.3048)
			(stroke
				(width 0.1)
				(type default)
			)
			(layer "F.Fab")
		)
		(fp_line
			(start -0.12065 0.3048)
			(end -0.67945 0.3048)
			(stroke
				(width 0.1)
				(type default)
			)
			(layer "F.Fab")
		)
		(fp_line
			(start 0.120396 0.2794)
			(end -0.12065 0.2794)
			(stroke
				(width 0.1)
				(type default)
			)
			(layer "F.Fab")
		)
		(fp_line
			(start 0.120396 0.3048)
			(end 0.120396 0.2794)
			(stroke
				(width 0.1)
				(type default)
			)
			(layer "F.Fab")
		)
		(fp_line
			(start 0.12065 -0.3048)
			(end 0.67945 -0.3048)
			(stroke
				(width 0.1)
				(type default)
			)
			(layer "F.Fab")
		)
		(fp_line
			(start 0.12065 -0.2794)
			(end 0.12065 -0.3048)
			(stroke
				(width 0.1)
				(type default)
			)
			(layer "F.Fab")
		)
		(fp_line
			(start 0.67945 -0.3048)
			(end 0.67945 0.3048)
			(stroke
				(width 0.1)
				(type default)
			)
			(layer "F.Fab")
		)
		(fp_line
			(start 0.67945 0.3048)
			(end 0.120396 0.3048)
			(stroke
				(width 0.1)
				(type default)
			)
			(layer "F.Fab")
		)
		(pad "1" smd circle
			(at -0.40005 0)
			(size 0 0)
			(layers "F.Cu" "F.Mask" "F.Paste")
			(net "PVCCIN_CPU1_VCC")
		)
		(pad "2" smd circle
			(at 0.40005 0)
			(size 0 0)
			(layers "F.Cu" "F.Mask" "F.Paste")
			(net "GND")
		)
	)
	(footprint ""
		(layer "F.Cu")
		(at 27.628596 -391.310876)
		(property "Reference" "R3287"
			(at 0 0 0)
			(layer "F.SilkS")
			(hide yes)
			(effects
				(font
					(size 1.27 1.27)
				)
			)
		)
		(property "Value" ""
			(at 0 0 0)
			(layer "F.Fab")
			(effects
				(font
					(size 1.27 1.27)
				)
			)
		)
		(duplicate_pad_numbers_are_jumpers no)
		(fp_line
			(start -0.7874 -0.4064)
			(end 0.7874 -0.4064)
			(stroke
				(width 0.1524)
				(type default)
			)
			(layer "F.SilkS")
		)
		(fp_line
			(start -0.7874 0.4064)
			(end -0.7874 -0.4064)
			(stroke
				(width 0.1524)
				(type default)
			)
			(layer "F.SilkS")
		)
		(fp_line
			(start 0.7874 -0.4064)
			(end 0.7874 0.4064)
			(stroke
				(width 0.1524)
				(type default)
			)
			(layer "F.SilkS")
		)
		(fp_line
			(start 0.7874 0.4064)
			(end -0.7874 0.4064)
			(stroke
				(width 0.1524)
				(type default)
			)
			(layer "F.SilkS")
		)
		(fp_line
			(start -0.67945 -0.305054)
			(end -0.12065 -0.305054)
			(stroke
				(width 0.1)
				(type default)
			)
			(layer "F.Fab")
		)
		(fp_line
			(start -0.67945 0.3048)
			(end -0.67945 -0.305054)
			(stroke
				(width 0.1)
				(type default)
			)
			(layer "F.Fab")
		)
		(fp_line
			(start -0.12065 -0.305054)
			(end -0.12065 -0.2794)
			(stroke
				(width 0.1)
				(type default)
			)
			(layer "F.Fab")
		)
		(fp_line
			(start -0.12065 -0.2794)
			(end 0.12065 -0.2794)
			(stroke
				(width 0.1)
				(type default)
			)
			(layer "F.Fab")
		)
		(fp_line
			(start -0.12065 0.2794)
			(end -0.12065 0.3048)
			(stroke
				(width 0.1)
				(type default)
			)
			(layer "F.Fab")
		)
		(fp_line
			(start -0.12065 0.3048)
			(end -0.67945 0.3048)
			(stroke
				(width 0.1)
				(type default)
			)
			(layer "F.Fab")
		)
		(fp_line
			(start 0.120396 0.2794)
			(end -0.12065 0.2794)
			(stroke
				(width 0.1)
				(type default)
			)
			(layer "F.Fab")
		)
		(fp_line
			(start 0.120396 0.3048)
			(end 0.120396 0.2794)
			(stroke
				(width 0.1)
				(type default)
			)
			(layer "F.Fab")
		)
		(fp_line
			(start 0.12065 -0.3048)
			(end 0.67945 -0.3048)
			(stroke
				(width 0.1)
				(type default)
			)
			(layer "F.Fab")
		)
		(fp_line
			(start 0.12065 -0.2794)
			(end 0.12065 -0.3048)
			(stroke
				(width 0.1)
				(type default)
			)
			(layer "F.Fab")
		)
		(fp_line
			(start 0.67945 -0.3048)
			(end 0.67945 0.3048)
			(stroke
				(width 0.1)
				(type default)
			)
			(layer "F.Fab")
		)
		(fp_line
			(start 0.67945 0.3048)
			(end 0.120396 0.3048)
			(stroke
				(width 0.1)
				(type default)
			)
			(layer "F.Fab")
		)
		(pad "1" smd circle
			(at -0.40005 0)
			(size 0 0)
			(layers "F.Cu" "F.Mask" "F.Paste")
			(net "FM_P2E_SWB")
		)
		(pad "2" smd circle
			(at 0.40005 0)
			(size 0 0)
			(layers "F.Cu" "F.Mask" "F.Paste")
			(net "GND")
		)
	)
	(footprint ""
		(layer "F.Cu")
		(at 323.72808 -21.046948 -90)
		(property "Reference" "R4099"
			(at 0 0 270)
			(layer "F.SilkS")
			(hide yes)
			(effects
				(font
					(size 1.27 1.27)
				)
			)
		)
		(property "Value" ""
			(at 0 0 270)
			(layer "F.Fab")
			(effects
				(font
					(size 1.27 1.27)
				)
			)
		)
		(duplicate_pad_numbers_are_jumpers no)
		(fp_line
			(start -0.7874 0.4064)
			(end -0.7874 -0.4064)
			(stroke
				(width 0.1524)
				(type default)
			)
			(layer "F.SilkS")
		)
		(fp_line
			(start 0.7874 0.4064)
			(end -0.7874 0.4064)
			(stroke
				(width 0.1524)
				(type default)
			)
			(layer "F.SilkS")
		)
		(fp_line
			(start -0.7874 -0.4064)
			(end 0.7874 -0.4064)
			(stroke
				(width 0.1524)
				(type default)
			)
			(layer "F.SilkS")
		)
		(fp_line
			(start 0.7874 -0.4064)
			(end 0.7874 0.4064)
			(stroke
				(width 0.1524)
				(type default)
			)
			(layer "F.SilkS")
		)
		(fp_line
			(start -0.67945 0.3048)
			(end -0.67945 -0.305054)
			(stroke
				(width 0.1)
				(type default)
			)
			(layer "F.Fab")
		)
		(fp_line
			(start -0.12065 0.3048)
			(end -0.67945 0.3048)
			(stroke
				(width 0.1)
				(type default)
			)
			(layer "F.Fab")
		)
		(fp_line
			(start 0.120396 0.3048)
			(end 0.120396 0.2794)
			(stroke
				(width 0.1)
				(type default)
			)
			(layer "F.Fab")
		)
		(fp_line
			(start 0.67945 0.3048)
			(end 0.120396 0.3048)
			(stroke
				(width 0.1)
				(type default)
			)
			(layer "F.Fab")
		)
		(fp_line
			(start -0.12065 0.2794)
			(end -0.12065 0.3048)
			(stroke
				(width 0.1)
				(type default)
			)
			(layer "F.Fab")
		)
		(fp_line
			(start 0.120396 0.2794)
			(end -0.12065 0.2794)
			(stroke
				(width 0.1)
				(type default)
			)
			(layer "F.Fab")
		)
		(fp_line
			(start -0.12065 -0.2794)
			(end 0.12065 -0.2794)
			(stroke
				(width 0.1)
				(type default)
			)
			(layer "F.Fab")
		)
		(fp_line
			(start 0.12065 -0.2794)
			(end 0.12065 -0.3048)
			(stroke
				(width 0.1)
				(type default)
			)
			(layer "F.Fab")
		)
		(fp_line
			(start 0.12065 -0.3048)
			(end 0.67945 -0.3048)
			(stroke
				(width 0.1)
				(type default)
			)
			(layer "F.Fab")
		)
		(fp_line
			(start 0.67945 -0.3048)
			(end 0.67945 0.3048)
			(stroke
				(width 0.1)
				(type default)
			)
			(layer "F.Fab")
		)
		(fp_line
			(start -0.67945 -0.305054)
			(end -0.12065 -0.305054)
			(stroke
				(width 0.1)
				(type default)
			)
			(layer "F.Fab")
		)
		(fp_line
			(start -0.12065 -0.305054)
			(end -0.12065 -0.2794)
			(stroke
				(width 0.1)
				(type default)
			)
			(layer "F.Fab")
		)
		(pad "1" smd circle
			(at -0.40005 0 270)
			(size 0 0)
			(layers "F.Cu" "F.Mask" "F.Paste")
			(net "PD_PCH_GPPC_A_10")
		)
		(pad "2" smd circle
			(at 0.40005 0 270)
			(size 0 0)
			(layers "F.Cu" "F.Mask" "F.Paste")
			(net "GND")
		)
	)
	(footprint ""
		(layer "F.Cu")
		(at 66.0654 -39.487348 90)
		(property "Reference" "R3827"
			(at 0 0 90)
			(layer "F.SilkS")
			(hide yes)
			(effects
				(font
					(size 1.27 1.27)
				)
			)
		)
		(property "Value" ""
			(at 0 0 90)
			(layer "F.Fab")
			(effects
				(font
					(size 1.27 1.27)
				)
			)
		)
		(duplicate_pad_numbers_are_jumpers no)
		(fp_line
			(start 0.7874 -0.4064)
			(end 0.7874 0.4064)
			(stroke
				(width 0.1524)
				(type default)
			)
			(layer "F.SilkS")
		)
		(fp_line
			(start -0.7874 -0.4064)
			(end 0.7874 -0.4064)
			(stroke
				(width 0.1524)
				(type default)
			)
			(layer "F.SilkS")
		)
		(fp_line
			(start 0.7874 0.4064)
			(end -0.7874 0.4064)
			(stroke
				(width 0.1524)
				(type default)
			)
			(layer "F.SilkS")
		)
		(fp_line
			(start -0.7874 0.4064)
			(end -0.7874 -0.4064)
			(stroke
				(width 0.1524)
				(type default)
			)
			(layer "F.SilkS")
		)
		(fp_line
			(start -0.12065 -0.305054)
			(end -0.12065 -0.2794)
			(stroke
				(width 0.1)
				(type default)
			)
			(layer "F.Fab")
		)
		(fp_line
			(start -0.67945 -0.305054)
			(end -0.12065 -0.305054)
			(stroke
				(width 0.1)
				(type default)
			)
			(layer "F.Fab")
		)
		(fp_line
			(start 0.67945 -0.3048)
			(end 0.67945 0.3048)
			(stroke
				(width 0.1)
				(type default)
			)
			(layer "F.Fab")
		)
		(fp_line
			(start 0.12065 -0.3048)
			(end 0.67945 -0.3048)
			(stroke
				(width 0.1)
				(type default)
			)
			(layer "F.Fab")
		)
		(fp_line
			(start 0.12065 -0.2794)
			(end 0.12065 -0.3048)
			(stroke
				(width 0.1)
				(type default)
			)
			(layer "F.Fab")
		)
		(fp_line
			(start -0.12065 -0.2794)
			(end 0.12065 -0.2794)
			(stroke
				(width 0.1)
				(type default)
			)
			(layer "F.Fab")
		)
		(fp_line
			(start 0.120396 0.2794)
			(end -0.12065 0.2794)
			(stroke
				(width 0.1)
				(type default)
			)
			(layer "F.Fab")
		)
		(fp_line
			(start -0.12065 0.2794)
			(end -0.12065 0.3048)
			(stroke
				(width 0.1)
				(type default)
			)
			(layer "F.Fab")
		)
		(fp_line
			(start 0.67945 0.3048)
			(end 0.120396 0.3048)
			(stroke
				(width 0.1)
				(type default)
			)
			(layer "F.Fab")
		)
		(fp_line
			(start 0.120396 0.3048)
			(end 0.120396 0.2794)
			(stroke
				(width 0.1)
				(type default)
			)
			(layer "F.Fab")
		)
		(fp_line
			(start -0.12065 0.3048)
			(end -0.67945 0.3048)
			(stroke
				(width 0.1)
				(type default)
			)
			(layer "F.Fab")
		)
		(fp_line
			(start -0.67945 0.3048)
			(end -0.67945 -0.305054)
			(stroke
				(width 0.1)
				(type default)
			)
			(layer "F.Fab")
		)
		(pad "1" smd circle
			(at -0.40005 0 90)
			(size 0 0)
			(layers "F.Cu" "F.Mask" "F.Paste")
			(net "P12V_OCP_UV_2_R")
		)
		(pad "2" smd circle
			(at 0.40005 0 90)
			(size 0 0)
			(layers "F.Cu" "F.Mask" "F.Paste")
			(net "P12V_OCP_UV_2")
		)
	)
	(footprint ""
		(layer "F.Cu")
		(at 100.92182 -99.423982)
		(property "Reference" "Q88"
			(at 1.62814 -0.742188 0)
			(unlocked yes)
			(layer "F.SilkS")
			(effects
				(font
					(size 0.7874 0.5842)
					(thickness 0.1524)
				)
				(justify left)
			)
		)
		(property "Value" ""
			(at 0 0 0)
			(layer "F.Fab")
			(effects
				(font
					(size 1.27 1.27)
				)
			)
		)
		(duplicate_pad_numbers_are_jumpers no)
		(fp_line
			(start -1.332738 -1.100074)
			(end -0.4826 -1.100074)
			(stroke
				(width 0.1524)
				(type default)
			)
			(layer "F.SilkS")
		)
		(fp_line
			(start -1.332738 1.100074)
			(end -1.332738 -1.100074)
			(stroke
				(width 0.1524)
				(type default)
			)
			(layer "F.SilkS")
		)
		(fp_line
			(start -0.4826 -1.100074)
			(end 0 -0.541274)
			(stroke
				(width 0.1524)
				(type default)
			)
			(layer "F.SilkS")
		)
		(fp_line
			(start 0 -0.541274)
			(end 0.4826 -1.100074)
			(stroke
				(width 0.1524)
				(type default)
			)
			(layer "F.SilkS")
		)
		(fp_line
			(start 0.4826 -1.100074)
			(end 1.332738 -1.100074)
			(stroke
				(width 0.1524)
				(type default)
			)
			(layer "F.SilkS")
		)
		(fp_line
			(start 1.332738 -1.100074)
			(end 1.332738 1.100074)
			(stroke
				(width 0.1524)
				(type default)
			)
			(layer "F.SilkS")
		)
		(fp_line
			(start 1.332738 1.100074)
			(end -1.332738 1.100074)
			(stroke
				(width 0.1524)
				(type default)
			)
			(layer "F.SilkS")
		)
		(fp_poly
			(pts
				(xy -0.588772 -1.917446) (xy -0.9398 -1.21539) (xy -1.290828 -1.917446)
			)
			(stroke
				(width 0)
				(type default)
			)
			(fill yes)
			(layer "F.SilkS")
		)
		(fp_line
			(start -0.674878 -1.100074)
			(end 0.674878 -1.100074)
			(stroke
				(width 0.1)
				(type default)
			)
			(layer "F.Fab")
		)
		(fp_line
			(start -0.674878 1.100074)
			(end -0.674878 -1.100074)
			(stroke
				(width 0.1)
				(type default)
			)
			(layer "F.Fab")
		)
		(fp_line
			(start 0.674878 -1.100074)
			(end 0.674878 1.100074)
			(stroke
				(width 0.1)
				(type default)
			)
			(layer "F.Fab")
		)
		(fp_line
			(start 0.674878 1.100074)
			(end -0.674878 1.100074)
			(stroke
				(width 0.1)
				(type default)
			)
			(layer "F.Fab")
		)
		(fp_poly
			(pts
				(xy -2.2352 -0.298958) (xy -2.2352 -1.001014) (xy -1.533144 -0.649986)
			)
			(stroke
				(width 0)
				(type default)
			)
			(fill yes)
			(layer "F.Fab")
		)
		(pad "1" smd rect
			(at -0.94996 -0.649986 90)
			(size 0.4318 0.508)
			(layers "F.Cu" "F.Mask" "F.Paste")
			(net "GND")
		)
		(pad "2" smd rect
			(at -0.94996 0 90)
			(size 0.4318 0.508)
			(layers "F.Cu" "F.Mask" "F.Paste")
			(net "PWRGD_CPUPWRGD_LVC2_R1")
		)
		(pad "3" smd rect
			(at -0.94996 0.649986 90)
			(size 0.4318 0.508)
			(layers "F.Cu" "F.Mask" "F.Paste")
			(net "LED_RST_PLTRST_N_D")
		)
		(pad "4" smd rect
			(at 0.94996 0.649986 90)
			(size 0.4318 0.508)
			(layers "F.Cu" "F.Mask" "F.Paste")
			(net "GND")
		)
		(pad "5" smd rect
			(at 0.94996 0 90)
			(size 0.4318 0.508)
			(layers "F.Cu" "F.Mask" "F.Paste")
			(net "RST_PLTRST_N")
		)
		(pad "6" smd rect
			(at 0.94996 -0.649986 90)
			(size 0.4318 0.508)
			(layers "F.Cu" "F.Mask" "F.Paste")
			(net "LED_PWRGD_CPUPWRGD_GTL_D")
		)
	)
	(footprint ""
		(layer "F.Cu")
		(at 106.3117 -255.0541 90)
		(property "Reference" "C283"
			(at 0 0 90)
			(layer "F.SilkS")
			(hide yes)
			(effects
				(font
					(size 1.27 1.27)
				)
			)
		)
		(property "Value" ""
			(at 0 0 90)
			(layer "F.Fab")
			(effects
				(font
					(size 1.27 1.27)
				)
			)
		)
		(duplicate_pad_numbers_are_jumpers no)
		(fp_line
			(start 0.7874 -0.4064)
			(end 0.7874 0.4064)
			(stroke
				(width 0.1524)
				(type default)
			)
			(layer "F.SilkS")
		)
		(fp_line
			(start -0.7874 -0.4064)
			(end 0.7874 -0.4064)
			(stroke
				(width 0.1524)
				(type default)
			)
			(layer "F.SilkS")
		)
		(fp_line
			(start 0.7874 0.4064)
			(end -0.7874 0.4064)
			(stroke
				(width 0.1524)
				(type default)
			)
			(layer "F.SilkS")
		)
		(fp_line
			(start -0.7874 0.4064)
			(end -0.7874 -0.4064)
			(stroke
				(width 0.1524)
				(type default)
			)
			(layer "F.SilkS")
		)
		(fp_line
			(start -0.12065 -0.305054)
			(end -0.12065 -0.2794)
			(stroke
				(width 0.1)
				(type default)
			)
			(layer "F.Fab")
		)
		(fp_line
			(start -0.67945 -0.305054)
			(end -0.12065 -0.305054)
			(stroke
				(width 0.1)
				(type default)
			)
			(layer "F.Fab")
		)
		(fp_line
			(start 0.67945 -0.3048)
			(end 0.67945 0.3048)
			(stroke
				(width 0.1)
				(type default)
			)
			(layer "F.Fab")
		)
		(fp_line
			(start 0.12065 -0.3048)
			(end 0.67945 -0.3048)
			(stroke
				(width 0.1)
				(type default)
			)
			(layer "F.Fab")
		)
		(fp_line
			(start 0.12065 -0.2794)
			(end 0.12065 -0.3048)
			(stroke
				(width 0.1)
				(type default)
			)
			(layer "F.Fab")
		)
		(fp_line
			(start -0.12065 -0.2794)
			(end 0.12065 -0.2794)
			(stroke
				(width 0.1)
				(type default)
			)
			(layer "F.Fab")
		)
		(fp_line
			(start 0.120396 0.2794)
			(end -0.12065 0.2794)
			(stroke
				(width 0.1)
				(type default)
			)
			(layer "F.Fab")
		)
		(fp_line
			(start -0.12065 0.2794)
			(end -0.12065 0.3048)
			(stroke
				(width 0.1)
				(type default)
			)
			(layer "F.Fab")
		)
		(fp_line
			(start 0.67945 0.3048)
			(end 0.120396 0.3048)
			(stroke
				(width 0.1)
				(type default)
			)
			(layer "F.Fab")
		)
		(fp_line
			(start 0.120396 0.3048)
			(end 0.120396 0.2794)
			(stroke
				(width 0.1)
				(type default)
			)
			(layer "F.Fab")
		)
		(fp_line
			(start -0.12065 0.3048)
			(end -0.67945 0.3048)
			(stroke
				(width 0.1)
				(type default)
			)
			(layer "F.Fab")
		)
		(fp_line
			(start -0.67945 0.3048)
			(end -0.67945 -0.305054)
			(stroke
				(width 0.1)
				(type default)
			)
			(layer "F.Fab")
		)
		(pad "1" smd circle
			(at -0.40005 0 90)
			(size 0 0)
			(layers "F.Cu" "F.Mask" "F.Paste")
			(net "PVCCIN_CPU1")
		)
		(pad "2" smd circle
			(at 0.40005 0 90)
			(size 0 0)
			(layers "F.Cu" "F.Mask" "F.Paste")
			(net "GND")
		)
	)
	(footprint ""
		(layer "F.Cu")
		(at 348.393004 -360.012996)
		(property "Reference" "R2376"
			(at 0 0 0)
			(layer "F.SilkS")
			(hide yes)
			(effects
				(font
					(size 1.27 1.27)
				)
			)
		)
		(property "Value" ""
			(at 0 0 0)
			(layer "F.Fab")
			(effects
				(font
					(size 1.27 1.27)
				)
			)
		)
		(duplicate_pad_numbers_are_jumpers no)
		(fp_line
			(start -0.7874 -0.4064)
			(end 0.7874 -0.4064)
			(stroke
				(width 0.1524)
				(type default)
			)
			(layer "F.SilkS")
		)
		(fp_line
			(start -0.7874 0.4064)
			(end -0.7874 -0.4064)
			(stroke
				(width 0.1524)
				(type default)
			)
			(layer "F.SilkS")
		)
		(fp_line
			(start 0.7874 -0.4064)
			(end 0.7874 0.4064)
			(stroke
				(width 0.1524)
				(type default)
			)
			(layer "F.SilkS")
		)
		(fp_line
			(start 0.7874 0.4064)
			(end -0.7874 0.4064)
			(stroke
				(width 0.1524)
				(type default)
			)
			(layer "F.SilkS")
		)
		(fp_line
			(start -0.67945 -0.305054)
			(end -0.12065 -0.305054)
			(stroke
				(width 0.1)
				(type default)
			)
			(layer "F.Fab")
		)
		(fp_line
			(start -0.67945 0.3048)
			(end -0.67945 -0.305054)
			(stroke
				(width 0.1)
				(type default)
			)
			(layer "F.Fab")
		)
		(fp_line
			(start -0.12065 -0.305054)
			(end -0.12065 -0.2794)
			(stroke
				(width 0.1)
				(type default)
			)
			(layer "F.Fab")
		)
		(fp_line
			(start -0.12065 -0.2794)
			(end 0.12065 -0.2794)
			(stroke
				(width 0.1)
				(type default)
			)
			(layer "F.Fab")
		)
		(fp_line
			(start -0.12065 0.2794)
			(end -0.12065 0.3048)
			(stroke
				(width 0.1)
				(type default)
			)
			(layer "F.Fab")
		)
		(fp_line
			(start -0.12065 0.3048)
			(end -0.67945 0.3048)
			(stroke
				(width 0.1)
				(type default)
			)
			(layer "F.Fab")
		)
		(fp_line
			(start 0.120396 0.2794)
			(end -0.12065 0.2794)
			(stroke
				(width 0.1)
				(type default)
			)
			(layer "F.Fab")
		)
		(fp_line
			(start 0.120396 0.3048)
			(end 0.120396 0.2794)
			(stroke
				(width 0.1)
				(type default)
			)
			(layer "F.Fab")
		)
		(fp_line
			(start 0.12065 -0.3048)
			(end 0.67945 -0.3048)
			(stroke
				(width 0.1)
				(type default)
			)
			(layer "F.Fab")
		)
		(fp_line
			(start 0.12065 -0.2794)
			(end 0.12065 -0.3048)
			(stroke
				(width 0.1)
				(type default)
			)
			(layer "F.Fab")
		)
		(fp_line
			(start 0.67945 -0.3048)
			(end 0.67945 0.3048)
			(stroke
				(width 0.1)
				(type default)
			)
			(layer "F.Fab")
		)
		(fp_line
			(start 0.67945 0.3048)
			(end 0.120396 0.3048)
			(stroke
				(width 0.1)
				(type default)
			)
			(layer "F.Fab")
		)
		(pad "1" smd circle
			(at -0.40005 0)
			(size 0 0)
			(layers "F.Cu" "F.Mask" "F.Paste")
			(net "IRQ_PSYS_CRIT_N")
		)
		(pad "2" smd circle
			(at 0.40005 0)
			(size 0 0)
			(layers "F.Cu" "F.Mask" "F.Paste")
			(net "PVCCIN_CPU0_PIN_ALERT")
		)
	)
	(footprint ""
		(layer "F.Cu")
		(at 128.45288 -100.167948 -90)
		(property "Reference" "R200"
			(at 0 0 270)
			(layer "F.SilkS")
			(hide yes)
			(effects
				(font
					(size 1.27 1.27)
				)
			)
		)
		(property "Value" ""
			(at 0 0 270)
			(layer "F.Fab")
			(effects
				(font
					(size 1.27 1.27)
				)
			)
		)
		(duplicate_pad_numbers_are_jumpers no)
		(fp_line
			(start -0.7874 0.4064)
			(end -0.7874 -0.4064)
			(stroke
				(width 0.1524)
				(type default)
			)
			(layer "F.SilkS")
		)
		(fp_line
			(start 0.7874 0.4064)
			(end -0.7874 0.4064)
			(stroke
				(width 0.1524)
				(type default)
			)
			(layer "F.SilkS")
		)
		(fp_line
			(start -0.7874 -0.4064)
			(end 0.7874 -0.4064)
			(stroke
				(width 0.1524)
				(type default)
			)
			(layer "F.SilkS")
		)
		(fp_line
			(start 0.7874 -0.4064)
			(end 0.7874 0.4064)
			(stroke
				(width 0.1524)
				(type default)
			)
			(layer "F.SilkS")
		)
		(fp_line
			(start -0.67945 0.3048)
			(end -0.67945 -0.305054)
			(stroke
				(width 0.1)
				(type default)
			)
			(layer "F.Fab")
		)
		(fp_line
			(start -0.12065 0.3048)
			(end -0.67945 0.3048)
			(stroke
				(width 0.1)
				(type default)
			)
			(layer "F.Fab")
		)
		(fp_line
			(start 0.120396 0.3048)
			(end 0.120396 0.2794)
			(stroke
				(width 0.1)
				(type default)
			)
			(layer "F.Fab")
		)
		(fp_line
			(start 0.67945 0.3048)
			(end 0.120396 0.3048)
			(stroke
				(width 0.1)
				(type default)
			)
			(layer "F.Fab")
		)
		(fp_line
			(start -0.12065 0.2794)
			(end -0.12065 0.3048)
			(stroke
				(width 0.1)
				(type default)
			)
			(layer "F.Fab")
		)
		(fp_line
			(start 0.120396 0.2794)
			(end -0.12065 0.2794)
			(stroke
				(width 0.1)
				(type default)
			)
			(layer "F.Fab")
		)
		(fp_line
			(start -0.12065 -0.2794)
			(end 0.12065 -0.2794)
			(stroke
				(width 0.1)
				(type default)
			)
			(layer "F.Fab")
		)
		(fp_line
			(start 0.12065 -0.2794)
			(end 0.12065 -0.3048)
			(stroke
				(width 0.1)
				(type default)
			)
			(layer "F.Fab")
		)
		(fp_line
			(start 0.12065 -0.3048)
			(end 0.67945 -0.3048)
			(stroke
				(width 0.1)
				(type default)
			)
			(layer "F.Fab")
		)
		(fp_line
			(start 0.67945 -0.3048)
			(end 0.67945 0.3048)
			(stroke
				(width 0.1)
				(type default)
			)
			(layer "F.Fab")
		)
		(fp_line
			(start -0.67945 -0.305054)
			(end -0.12065 -0.305054)
			(stroke
				(width 0.1)
				(type default)
			)
			(layer "F.Fab")
		)
		(fp_line
			(start -0.12065 -0.305054)
			(end -0.12065 -0.2794)
			(stroke
				(width 0.1)
				(type default)
			)
			(layer "F.Fab")
		)
		(pad "1" smd circle
			(at -0.40005 0 270)
			(size 0 0)
			(layers "F.Cu" "F.Mask" "F.Paste")
			(net "PVNN_TERM_CPU0")
		)
		(pad "2" smd circle
			(at 0.40005 0 270)
			(size 0 0)
			(layers "F.Cu" "F.Mask" "F.Paste")
			(net "H_CPU0_MEMTRIP_LVC1_R_N")
		)
	)
	(footprint ""
		(layer "F.Cu")
		(at 364.50143 -244.03177 90)
		(property "Reference" "C1009"
			(at 0 0 90)
			(layer "F.SilkS")
			(hide yes)
			(effects
				(font
					(size 1.27 1.27)
				)
			)
		)
		(property "Value" ""
			(at 0 0 90)
			(layer "F.Fab")
			(effects
				(font
					(size 1.27 1.27)
				)
			)
		)
		(duplicate_pad_numbers_are_jumpers no)
		(fp_line
			(start 0.7874 -0.4064)
			(end 0.7874 0.4064)
			(stroke
				(width 0.1524)
				(type default)
			)
			(layer "F.SilkS")
		)
		(fp_line
			(start -0.7874 -0.4064)
			(end 0.7874 -0.4064)
			(stroke
				(width 0.1524)
				(type default)
			)
			(layer "F.SilkS")
		)
		(fp_line
			(start 0.7874 0.4064)
			(end -0.7874 0.4064)
			(stroke
				(width 0.1524)
				(type default)
			)
			(layer "F.SilkS")
		)
		(fp_line
			(start -0.7874 0.4064)
			(end -0.7874 -0.4064)
			(stroke
				(width 0.1524)
				(type default)
			)
			(layer "F.SilkS")
		)
		(fp_line
			(start -0.12065 -0.305054)
			(end -0.12065 -0.2794)
			(stroke
				(width 0.1)
				(type default)
			)
			(layer "F.Fab")
		)
		(fp_line
			(start -0.67945 -0.305054)
			(end -0.12065 -0.305054)
			(stroke
				(width 0.1)
				(type default)
			)
			(layer "F.Fab")
		)
		(fp_line
			(start 0.67945 -0.3048)
			(end 0.67945 0.3048)
			(stroke
				(width 0.1)
				(type default)
			)
			(layer "F.Fab")
		)
		(fp_line
			(start 0.12065 -0.3048)
			(end 0.67945 -0.3048)
			(stroke
				(width 0.1)
				(type default)
			)
			(layer "F.Fab")
		)
		(fp_line
			(start 0.12065 -0.2794)
			(end 0.12065 -0.3048)
			(stroke
				(width 0.1)
				(type default)
			)
			(layer "F.Fab")
		)
		(fp_line
			(start -0.12065 -0.2794)
			(end 0.12065 -0.2794)
			(stroke
				(width 0.1)
				(type default)
			)
			(layer "F.Fab")
		)
		(fp_line
			(start 0.120396 0.2794)
			(end -0.12065 0.2794)
			(stroke
				(width 0.1)
				(type default)
			)
			(layer "F.Fab")
		)
		(fp_line
			(start -0.12065 0.2794)
			(end -0.12065 0.3048)
			(stroke
				(width 0.1)
				(type default)
			)
			(layer "F.Fab")
		)
		(fp_line
			(start 0.67945 0.3048)
			(end 0.120396 0.3048)
			(stroke
				(width 0.1)
				(type default)
			)
			(layer "F.Fab")
		)
		(fp_line
			(start 0.120396 0.3048)
			(end 0.120396 0.2794)
			(stroke
				(width 0.1)
				(type default)
			)
			(layer "F.Fab")
		)
		(fp_line
			(start -0.12065 0.3048)
			(end -0.67945 0.3048)
			(stroke
				(width 0.1)
				(type default)
			)
			(layer "F.Fab")
		)
		(fp_line
			(start -0.67945 0.3048)
			(end -0.67945 -0.305054)
			(stroke
				(width 0.1)
				(type default)
			)
			(layer "F.Fab")
		)
		(pad "1" smd circle
			(at -0.40005 0 90)
			(size 0 0)
			(layers "F.Cu" "F.Mask" "F.Paste")
			(net "PVCCIN_CPU0")
		)
		(pad "2" smd circle
			(at 0.40005 0 90)
			(size 0 0)
			(layers "F.Cu" "F.Mask" "F.Paste")
			(net "GND")
		)
	)
	(footprint ""
		(layer "F.Cu")
		(at 218.694 -96.103948 180)
		(property "Reference" "R4620"
			(at 0 0 180)
			(layer "F.SilkS")
			(hide yes)
			(effects
				(font
					(size 1.27 1.27)
				)
			)
		)
		(property "Value" ""
			(at 0 0 180)
			(layer "F.Fab")
			(effects
				(font
					(size 1.27 1.27)
				)
			)
		)
		(duplicate_pad_numbers_are_jumpers no)
		(fp_line
			(start 0.7874 0.4064)
			(end -0.7874 0.4064)
			(stroke
				(width 0.1524)
				(type default)
			)
			(layer "F.SilkS")
		)
		(fp_line
			(start 0.7874 -0.4064)
			(end 0.7874 0.4064)
			(stroke
				(width 0.1524)
				(type default)
			)
			(layer "F.SilkS")
		)
		(fp_line
			(start -0.7874 0.4064)
			(end -0.7874 -0.4064)
			(stroke
				(width 0.1524)
				(type default)
			)
			(layer "F.SilkS")
		)
		(fp_line
			(start -0.7874 -0.4064)
			(end 0.7874 -0.4064)
			(stroke
				(width 0.1524)
				(type default)
			)
			(layer "F.SilkS")
		)
		(fp_line
			(start 0.67945 0.3048)
			(end 0.120396 0.3048)
			(stroke
				(width 0.1)
				(type default)
			)
			(layer "F.Fab")
		)
		(fp_line
			(start 0.67945 -0.3048)
			(end 0.67945 0.3048)
			(stroke
				(width 0.1)
				(type default)
			)
			(layer "F.Fab")
		)
		(fp_line
			(start 0.12065 -0.2794)
			(end 0.12065 -0.3048)
			(stroke
				(width 0.1)
				(type default)
			)
			(layer "F.Fab")
		)
		(fp_line
			(start 0.12065 -0.3048)
			(end 0.67945 -0.3048)
			(stroke
				(width 0.1)
				(type default)
			)
			(layer "F.Fab")
		)
		(fp_line
			(start 0.120396 0.3048)
			(end 0.120396 0.2794)
			(stroke
				(width 0.1)
				(type default)
			)
			(layer "F.Fab")
		)
		(fp_line
			(start 0.120396 0.2794)
			(end -0.12065 0.2794)
			(stroke
				(width 0.1)
				(type default)
			)
			(layer "F.Fab")
		)
		(fp_line
			(start -0.12065 0.3048)
			(end -0.67945 0.3048)
			(stroke
				(width 0.1)
				(type default)
			)
			(layer "F.Fab")
		)
		(fp_line
			(start -0.12065 0.2794)
			(end -0.12065 0.3048)
			(stroke
				(width 0.1)
				(type default)
			)
			(layer "F.Fab")
		)
		(fp_line
			(start -0.12065 -0.2794)
			(end 0.12065 -0.2794)
			(stroke
				(width 0.1)
				(type default)
			)
			(layer "F.Fab")
		)
		(fp_line
			(start -0.12065 -0.305054)
			(end -0.12065 -0.2794)
			(stroke
				(width 0.1)
				(type default)
			)
			(layer "F.Fab")
		)
		(fp_line
			(start -0.67945 0.3048)
			(end -0.67945 -0.305054)
			(stroke
				(width 0.1)
				(type default)
			)
			(layer "F.Fab")
		)
		(fp_line
			(start -0.67945 -0.305054)
			(end -0.12065 -0.305054)
			(stroke
				(width 0.1)
				(type default)
			)
			(layer "F.Fab")
		)
		(pad "1" smd circle
			(at -0.40005 0 180)
			(size 0 0)
			(layers "F.Cu" "F.Mask" "F.Paste")
			(net "P3V3_AUX")
		)
		(pad "2" smd circle
			(at 0.40005 0 180)
			(size 0 0)
			(layers "F.Cu" "F.Mask" "F.Paste")
			(net "IRQ_UV_DETECT_N")
		)
	)
	(footprint ""
		(layer "F.Cu")
		(at 220.087444 -102.255574 180)
		(property "Reference" "R2230"
			(at 0 0 180)
			(layer "F.SilkS")
			(hide yes)
			(effects
				(font
					(size 1.27 1.27)
				)
			)
		)
		(property "Value" ""
			(at 0 0 180)
			(layer "F.Fab")
			(effects
				(font
					(size 1.27 1.27)
				)
			)
		)
		(duplicate_pad_numbers_are_jumpers no)
		(fp_line
			(start 0.7874 0.4064)
			(end -0.7874 0.4064)
			(stroke
				(width 0.1524)
				(type default)
			)
			(layer "F.SilkS")
		)
		(fp_line
			(start 0.7874 -0.4064)
			(end 0.7874 0.4064)
			(stroke
				(width 0.1524)
				(type default)
			)
			(layer "F.SilkS")
		)
		(fp_line
			(start -0.7874 0.4064)
			(end -0.7874 -0.4064)
			(stroke
				(width 0.1524)
				(type default)
			)
			(layer "F.SilkS")
		)
		(fp_line
			(start -0.7874 -0.4064)
			(end 0.7874 -0.4064)
			(stroke
				(width 0.1524)
				(type default)
			)
			(layer "F.SilkS")
		)
		(fp_line
			(start 0.67945 0.3048)
			(end 0.120396 0.3048)
			(stroke
				(width 0.1)
				(type default)
			)
			(layer "F.Fab")
		)
		(fp_line
			(start 0.67945 -0.3048)
			(end 0.67945 0.3048)
			(stroke
				(width 0.1)
				(type default)
			)
			(layer "F.Fab")
		)
		(fp_line
			(start 0.12065 -0.2794)
			(end 0.12065 -0.3048)
			(stroke
				(width 0.1)
				(type default)
			)
			(layer "F.Fab")
		)
		(fp_line
			(start 0.12065 -0.3048)
			(end 0.67945 -0.3048)
			(stroke
				(width 0.1)
				(type default)
			)
			(layer "F.Fab")
		)
		(fp_line
			(start 0.120396 0.3048)
			(end 0.120396 0.2794)
			(stroke
				(width 0.1)
				(type default)
			)
			(layer "F.Fab")
		)
		(fp_line
			(start 0.120396 0.2794)
			(end -0.12065 0.2794)
			(stroke
				(width 0.1)
				(type default)
			)
			(layer "F.Fab")
		)
		(fp_line
			(start -0.12065 0.3048)
			(end -0.67945 0.3048)
			(stroke
				(width 0.1)
				(type default)
			)
			(layer "F.Fab")
		)
		(fp_line
			(start -0.12065 0.2794)
			(end -0.12065 0.3048)
			(stroke
				(width 0.1)
				(type default)
			)
			(layer "F.Fab")
		)
		(fp_line
			(start -0.12065 -0.2794)
			(end 0.12065 -0.2794)
			(stroke
				(width 0.1)
				(type default)
			)
			(layer "F.Fab")
		)
		(fp_line
			(start -0.12065 -0.305054)
			(end -0.12065 -0.2794)
			(stroke
				(width 0.1)
				(type default)
			)
			(layer "F.Fab")
		)
		(fp_line
			(start -0.67945 0.3048)
			(end -0.67945 -0.305054)
			(stroke
				(width 0.1)
				(type default)
			)
			(layer "F.Fab")
		)
		(fp_line
			(start -0.67945 -0.305054)
			(end -0.12065 -0.305054)
			(stroke
				(width 0.1)
				(type default)
			)
			(layer "F.Fab")
		)
		(pad "1" smd circle
			(at -0.40005 0 180)
			(size 0 0)
			(layers "F.Cu" "F.Mask" "F.Paste")
			(net "P3V3_AUX")
		)
		(pad "2" smd circle
			(at 0.40005 0 180)
			(size 0 0)
			(layers "F.Cu" "F.Mask" "F.Paste")
			(net "A_P12V_STBY_FPH_GATE")
		)
	)
	(footprint ""
		(layer "F.Cu")
		(at 450.43725 -44.171362 180)
		(property "Reference" "R3501"
			(at 0 0 180)
			(layer "F.SilkS")
			(hide yes)
			(effects
				(font
					(size 1.27 1.27)
				)
			)
		)
		(property "Value" ""
			(at 0 0 180)
			(layer "F.Fab")
			(effects
				(font
					(size 1.27 1.27)
				)
			)
		)
		(duplicate_pad_numbers_are_jumpers no)
		(fp_line
			(start 0.7874 0.4064)
			(end -0.7874 0.4064)
			(stroke
				(width 0.1524)
				(type default)
			)
			(layer "F.SilkS")
		)
		(fp_line
			(start 0.7874 -0.4064)
			(end 0.7874 0.4064)
			(stroke
				(width 0.1524)
				(type default)
			)
			(layer "F.SilkS")
		)
		(fp_line
			(start -0.7874 0.4064)
			(end -0.7874 -0.4064)
			(stroke
				(width 0.1524)
				(type default)
			)
			(layer "F.SilkS")
		)
		(fp_line
			(start -0.7874 -0.4064)
			(end 0.7874 -0.4064)
			(stroke
				(width 0.1524)
				(type default)
			)
			(layer "F.SilkS")
		)
		(fp_line
			(start 0.67945 0.3048)
			(end 0.120396 0.3048)
			(stroke
				(width 0.1)
				(type default)
			)
			(layer "F.Fab")
		)
		(fp_line
			(start 0.67945 -0.3048)
			(end 0.67945 0.3048)
			(stroke
				(width 0.1)
				(type default)
			)
			(layer "F.Fab")
		)
		(fp_line
			(start 0.12065 -0.2794)
			(end 0.12065 -0.3048)
			(stroke
				(width 0.1)
				(type default)
			)
			(layer "F.Fab")
		)
		(fp_line
			(start 0.12065 -0.3048)
			(end 0.67945 -0.3048)
			(stroke
				(width 0.1)
				(type default)
			)
			(layer "F.Fab")
		)
		(fp_line
			(start 0.120396 0.3048)
			(end 0.120396 0.2794)
			(stroke
				(width 0.1)
				(type default)
			)
			(layer "F.Fab")
		)
		(fp_line
			(start 0.120396 0.2794)
			(end -0.12065 0.2794)
			(stroke
				(width 0.1)
				(type default)
			)
			(layer "F.Fab")
		)
		(fp_line
			(start -0.12065 0.3048)
			(end -0.67945 0.3048)
			(stroke
				(width 0.1)
				(type default)
			)
			(layer "F.Fab")
		)
		(fp_line
			(start -0.12065 0.2794)
			(end -0.12065 0.3048)
			(stroke
				(width 0.1)
				(type default)
			)
			(layer "F.Fab")
		)
		(fp_line
			(start -0.12065 -0.2794)
			(end 0.12065 -0.2794)
			(stroke
				(width 0.1)
				(type default)
			)
			(layer "F.Fab")
		)
		(fp_line
			(start -0.12065 -0.305054)
			(end -0.12065 -0.2794)
			(stroke
				(width 0.1)
				(type default)
			)
			(layer "F.Fab")
		)
		(fp_line
			(start -0.67945 0.3048)
			(end -0.67945 -0.305054)
			(stroke
				(width 0.1)
				(type default)
			)
			(layer "F.Fab")
		)
		(fp_line
			(start -0.67945 -0.305054)
			(end -0.12065 -0.305054)
			(stroke
				(width 0.1)
				(type default)
			)
			(layer "F.Fab")
		)
		(pad "1" smd circle
			(at -0.40005 0 180)
			(size 0 0)
			(layers "F.Cu" "F.Mask" "F.Paste")
			(net "P3V3_OCP_SFF")
		)
		(pad "2" smd circle
			(at 0.40005 0 180)
			(size 0 0)
			(layers "F.Cu" "F.Mask" "F.Paste")
			(net "SMB_OCP_SFF_3V3AUX_BUF_SDA")
		)
	)
	(footprint ""
		(layer "F.Cu")
		(at 413.520382 -32.925258)
		(property "Reference" "R1325"
			(at 0 0 0)
			(layer "F.SilkS")
			(hide yes)
			(effects
				(font
					(size 1.27 1.27)
				)
			)
		)
		(property "Value" ""
			(at 0 0 0)
			(layer "F.Fab")
			(effects
				(font
					(size 1.27 1.27)
				)
			)
		)
		(duplicate_pad_numbers_are_jumpers no)
		(fp_line
			(start -0.7874 -0.4064)
			(end 0.7874 -0.4064)
			(stroke
				(width 0.1524)
				(type default)
			)
			(layer "F.SilkS")
		)
		(fp_line
			(start -0.7874 0.4064)
			(end -0.7874 -0.4064)
			(stroke
				(width 0.1524)
				(type default)
			)
			(layer "F.SilkS")
		)
		(fp_line
			(start 0.7874 -0.4064)
			(end 0.7874 0.4064)
			(stroke
				(width 0.1524)
				(type default)
			)
			(layer "F.SilkS")
		)
		(fp_line
			(start 0.7874 0.4064)
			(end -0.7874 0.4064)
			(stroke
				(width 0.1524)
				(type default)
			)
			(layer "F.SilkS")
		)
		(fp_line
			(start -0.67945 -0.305054)
			(end -0.12065 -0.305054)
			(stroke
				(width 0.1)
				(type default)
			)
			(layer "F.Fab")
		)
		(fp_line
			(start -0.67945 0.3048)
			(end -0.67945 -0.305054)
			(stroke
				(width 0.1)
				(type default)
			)
			(layer "F.Fab")
		)
		(fp_line
			(start -0.12065 -0.305054)
			(end -0.12065 -0.2794)
			(stroke
				(width 0.1)
				(type default)
			)
			(layer "F.Fab")
		)
		(fp_line
			(start -0.12065 -0.2794)
			(end 0.12065 -0.2794)
			(stroke
				(width 0.1)
				(type default)
			)
			(layer "F.Fab")
		)
		(fp_line
			(start -0.12065 0.2794)
			(end -0.12065 0.3048)
			(stroke
				(width 0.1)
				(type default)
			)
			(layer "F.Fab")
		)
		(fp_line
			(start -0.12065 0.3048)
			(end -0.67945 0.3048)
			(stroke
				(width 0.1)
				(type default)
			)
			(layer "F.Fab")
		)
		(fp_line
			(start 0.120396 0.2794)
			(end -0.12065 0.2794)
			(stroke
				(width 0.1)
				(type default)
			)
			(layer "F.Fab")
		)
		(fp_line
			(start 0.120396 0.3048)
			(end 0.120396 0.2794)
			(stroke
				(width 0.1)
				(type default)
			)
			(layer "F.Fab")
		)
		(fp_line
			(start 0.12065 -0.3048)
			(end 0.67945 -0.3048)
			(stroke
				(width 0.1)
				(type default)
			)
			(layer "F.Fab")
		)
		(fp_line
			(start 0.12065 -0.2794)
			(end 0.12065 -0.3048)
			(stroke
				(width 0.1)
				(type default)
			)
			(layer "F.Fab")
		)
		(fp_line
			(start 0.67945 -0.3048)
			(end 0.67945 0.3048)
			(stroke
				(width 0.1)
				(type default)
			)
			(layer "F.Fab")
		)
		(fp_line
			(start 0.67945 0.3048)
			(end 0.120396 0.3048)
			(stroke
				(width 0.1)
				(type default)
			)
			(layer "F.Fab")
		)
		(pad "1" smd circle
			(at -0.40005 0)
			(size 0 0)
			(layers "F.Cu" "F.Mask" "F.Paste")
			(net "P3V3_AUX")
		)
		(pad "2" smd circle
			(at 0.40005 0)
			(size 0 0)
			(layers "F.Cu" "F.Mask" "F.Paste")
			(net "PU_FLASH_SECURITY_STRAP")
		)
	)
	(footprint ""
		(layer "F.Cu")
		(at 322.334128 -402.371052 -90)
		(property "Reference" "C1566"
			(at 0 0 270)
			(layer "F.SilkS")
			(hide yes)
			(effects
				(font
					(size 1.27 1.27)
				)
			)
		)
		(property "Value" ""
			(at 0 0 270)
			(layer "F.Fab")
			(effects
				(font
					(size 1.27 1.27)
				)
			)
		)
		(duplicate_pad_numbers_are_jumpers no)
		(fp_line
			(start -0.299974 0.150114)
			(end -0.299974 -0.150114)
			(stroke
				(width 0.1)
				(type default)
			)
			(layer "F.Fab")
		)
		(fp_line
			(start 0.299974 0.150114)
			(end -0.299974 0.150114)
			(stroke
				(width 0.1)
				(type default)
			)
			(layer "F.Fab")
		)
		(fp_line
			(start -0.299974 -0.150114)
			(end 0.299974 -0.150114)
			(stroke
				(width 0.1)
				(type default)
			)
			(layer "F.Fab")
		)
		(fp_line
			(start 0.299974 -0.150114)
			(end 0.299974 0.150114)
			(stroke
				(width 0.1)
				(type default)
			)
			(layer "F.Fab")
		)
		(pad "1" smd rect
			(at -0.2667 0 270)
			(size 0.3048 0.381)
			(layers "F.Cu" "F.Mask" "F.Paste")
			(net "P5E_CPU0_PE4_TX_C_DN<6>")
		)
		(pad "2" smd rect
			(at 0.2667 0 270)
			(size 0.3048 0.381)
			(layers "F.Cu" "F.Mask" "F.Paste")
			(net "P5E_CPU0_PE4_TX_DN<6>")
		)
	)
	(footprint ""
		(layer "F.Cu")
		(at 125.715014 -358.460548)
		(property "Reference" "PU80"
			(at 3.758946 -0.80772 0)
			(unlocked yes)
			(layer "F.SilkS")
			(effects
				(font
					(size 0.7874 0.5842)
					(thickness 0.1524)
				)
				(justify left)
			)
		)
		(property "Value" ""
			(at 0 0 0)
			(layer "F.Fab")
			(effects
				(font
					(size 1.27 1.27)
				)
			)
		)
		(duplicate_pad_numbers_are_jumpers no)
		(fp_line
			(start -1.549908 -2.050034)
			(end -1.549908 -1.9812)
			(stroke
				(width 0.1524)
				(type default)
			)
			(layer "F.SilkS")
		)
		(fp_line
			(start -1.549908 1.9812)
			(end -1.549908 2.050034)
			(stroke
				(width 0.1524)
				(type default)
			)
			(layer "F.SilkS")
		)
		(fp_line
			(start -1.549908 2.050034)
			(end -0.5842 2.050034)
			(stroke
				(width 0.1524)
				(type default)
			)
			(layer "F.SilkS")
		)
		(fp_line
			(start -0.5842 -2.050034)
			(end -1.549908 -2.050034)
			(stroke
				(width 0.1524)
				(type default)
			)
			(layer "F.SilkS")
		)
		(fp_line
			(start 0 2.050034)
			(end 1.549908 2.050034)
			(stroke
				(width 0.1524)
				(type default)
			)
			(layer "F.SilkS")
		)
		(fp_line
			(start 1.549908 -2.050034)
			(end 0.5842 -2.050034)
			(stroke
				(width 0.1524)
				(type default)
			)
			(layer "F.SilkS")
		)
		(fp_line
			(start 1.549908 -1.9812)
			(end 1.549908 -2.050034)
			(stroke
				(width 0.1524)
				(type default)
			)
			(layer "F.SilkS")
		)
		(fp_line
			(start 1.549908 2.050034)
			(end 1.549908 1.9304)
			(stroke
				(width 0.1524)
				(type default)
			)
			(layer "F.SilkS")
		)
		(fp_poly
			(pts
				(xy -3.216402 -2.241042) (xy -3.216402 -1.225042) (xy -2.200402 -1.733042)
			)
			(stroke
				(width 0)
				(type default)
			)
			(fill yes)
			(layer "F.SilkS")
		)
		(fp_line
			(start -1.549908 -2.050034)
			(end -1.549908 2.050034)
			(stroke
				(width 0.1)
				(type default)
			)
			(layer "F.Fab")
		)
		(fp_line
			(start -1.549908 2.050034)
			(end 1.549908 2.050034)
			(stroke
				(width 0.1)
				(type default)
			)
			(layer "F.Fab")
		)
		(fp_line
			(start 1.549908 -2.050034)
			(end -1.549908 -2.050034)
			(stroke
				(width 0.1)
				(type default)
			)
			(layer "F.Fab")
		)
		(fp_line
			(start 1.549908 2.050034)
			(end 1.549908 -2.050034)
			(stroke
				(width 0.1)
				(type default)
			)
			(layer "F.Fab")
		)
		(fp_poly
			(pts
				(xy -2.9464 -2.208022) (xy -2.9464 -1.192022) (xy -1.9304 -1.700022)
			)
			(stroke
				(width 0)
				(type default)
			)
			(fill yes)
			(layer "F.Fab")
		)
		(pad "1" smd circle
			(at -1.35001 -1.700022)
			(size 0 0)
			(layers "F.Cu" "F.Mask" "F.Paste")
			(net "SW_PVPP_HBM_CPU1_BST")
		)
		(pad "2" smd rect
			(at -1.400048 -1.199896 90)
			(size 0.1778 0.8128)
			(layers "F.Cu" "F.Mask" "F.Paste")
			(net "GND")
		)
		(pad "3" smd rect
			(at -1.400048 -0.8001 90)
			(size 0.1778 0.8128)
			(layers "F.Cu" "F.Mask" "F.Paste")
			(net "PVPP_HBM_CPU1_CS")
		)
		(pad "4" smd rect
			(at -1.400048 -0.40005 90)
			(size 0.1778 0.8128)
			(layers "F.Cu" "F.Mask" "F.Paste")
			(net "PVPP_HBM_CPU1_MODE")
		)
		(pad "5" smd rect
			(at -1.400048 0 90)
			(size 0.1778 0.8128)
			(layers "F.Cu" "F.Mask" "F.Paste")
			(net "PVPP_HBM_CPU1_REF")
		)
		(pad "6" smd rect
			(at -1.400048 0.40005 90)
			(size 0.1778 0.8128)
			(layers "F.Cu" "F.Mask" "F.Paste")
			(net "SH_PVPP_HBM_CPU1_N")
		)
		(pad "7" smd rect
			(at -1.400048 0.8001 90)
			(size 0.1778 0.8128)
			(layers "F.Cu" "F.Mask" "F.Paste")
			(net "PVPP_HBM_CPU1_FB")
		)
		(pad "8" smd rect
			(at -1.400048 1.199896 90)
			(size 0.1778 0.8128)
			(layers "F.Cu" "F.Mask" "F.Paste")
			(net "FM_PVPP_HBM_CPU1_EN")
		)
		(pad "9" smd rect
			(at -1.400048 1.700022 90)
			(size 0.3048 0.8128)
			(layers "F.Cu" "F.Mask" "F.Paste")
			(net "PWRGD_PVPP_HBM_CPU1_R")
		)
		(pad "10" smd rect
			(at -0.299974 1.299972)
			(size 0.3048 2.0066)
			(layers "F.Cu" "F.Mask" "F.Paste")
			(net "SW_P12V_PVCCIN_CPU1_FLT")
		)
		(pad "11_18" smd circle
			(at 1.175004 0.275082)
			(size 0 0)
			(layers "F.Cu" "F.Mask" "F.Paste")
			(net "GND")
		)
		(pad "19" smd rect
			(at 1.400048 -1.700022 270)
			(size 0.3048 0.8128)
			(layers "F.Cu" "F.Mask" "F.Paste")
			(net "PVPP_HBM_CPU1_VCC")
		)
		(pad "20" smd rect
			(at 0.299974 -1.299972)
			(size 0.3048 2.0066)
			(layers "F.Cu" "F.Mask" "F.Paste")
			(net "SW_PVPP_HBM_CPU1_SW")
		)
		(pad "21" smd rect
			(at -0.299974 -1.299972)
			(size 0.3048 2.0066)
			(layers "F.Cu" "F.Mask" "F.Paste")
			(net "SW_P12V_PVCCIN_CPU1_FLT")
		)
	)
	(footprint ""
		(layer "F.Cu")
		(at 105.30713 -240.277142 90)
		(property "Reference" "C267"
			(at 0 0 90)
			(layer "F.SilkS")
			(hide yes)
			(effects
				(font
					(size 1.27 1.27)
				)
			)
		)
		(property "Value" ""
			(at 0 0 90)
			(layer "F.Fab")
			(effects
				(font
					(size 1.27 1.27)
				)
			)
		)
		(duplicate_pad_numbers_are_jumpers no)
		(fp_line
			(start 0.7874 -0.4064)
			(end 0.7874 0.4064)
			(stroke
				(width 0.1524)
				(type default)
			)
			(layer "F.SilkS")
		)
		(fp_line
			(start -0.7874 -0.4064)
			(end 0.7874 -0.4064)
			(stroke
				(width 0.1524)
				(type default)
			)
			(layer "F.SilkS")
		)
		(fp_line
			(start 0.7874 0.4064)
			(end -0.7874 0.4064)
			(stroke
				(width 0.1524)
				(type default)
			)
			(layer "F.SilkS")
		)
		(fp_line
			(start -0.7874 0.4064)
			(end -0.7874 -0.4064)
			(stroke
				(width 0.1524)
				(type default)
			)
			(layer "F.SilkS")
		)
		(fp_line
			(start -0.12065 -0.305054)
			(end -0.12065 -0.2794)
			(stroke
				(width 0.1)
				(type default)
			)
			(layer "F.Fab")
		)
		(fp_line
			(start -0.67945 -0.305054)
			(end -0.12065 -0.305054)
			(stroke
				(width 0.1)
				(type default)
			)
			(layer "F.Fab")
		)
		(fp_line
			(start 0.67945 -0.3048)
			(end 0.67945 0.3048)
			(stroke
				(width 0.1)
				(type default)
			)
			(layer "F.Fab")
		)
		(fp_line
			(start 0.12065 -0.3048)
			(end 0.67945 -0.3048)
			(stroke
				(width 0.1)
				(type default)
			)
			(layer "F.Fab")
		)
		(fp_line
			(start 0.12065 -0.2794)
			(end 0.12065 -0.3048)
			(stroke
				(width 0.1)
				(type default)
			)
			(layer "F.Fab")
		)
		(fp_line
			(start -0.12065 -0.2794)
			(end 0.12065 -0.2794)
			(stroke
				(width 0.1)
				(type default)
			)
			(layer "F.Fab")
		)
		(fp_line
			(start 0.120396 0.2794)
			(end -0.12065 0.2794)
			(stroke
				(width 0.1)
				(type default)
			)
			(layer "F.Fab")
		)
		(fp_line
			(start -0.12065 0.2794)
			(end -0.12065 0.3048)
			(stroke
				(width 0.1)
				(type default)
			)
			(layer "F.Fab")
		)
		(fp_line
			(start 0.67945 0.3048)
			(end 0.120396 0.3048)
			(stroke
				(width 0.1)
				(type default)
			)
			(layer "F.Fab")
		)
		(fp_line
			(start 0.120396 0.3048)
			(end 0.120396 0.2794)
			(stroke
				(width 0.1)
				(type default)
			)
			(layer "F.Fab")
		)
		(fp_line
			(start -0.12065 0.3048)
			(end -0.67945 0.3048)
			(stroke
				(width 0.1)
				(type default)
			)
			(layer "F.Fab")
		)
		(fp_line
			(start -0.67945 0.3048)
			(end -0.67945 -0.305054)
			(stroke
				(width 0.1)
				(type default)
			)
			(layer "F.Fab")
		)
		(pad "1" smd circle
			(at -0.40005 0 90)
			(size 0 0)
			(layers "F.Cu" "F.Mask" "F.Paste")
			(net "PVCCIN_CPU1")
		)
		(pad "2" smd circle
			(at 0.40005 0 90)
			(size 0 0)
			(layers "F.Cu" "F.Mask" "F.Paste")
			(net "GND")
		)
	)
	(footprint ""
		(layer "F.Cu")
		(at 66.149982 -15.32763 180)
		(property "Reference" "C1833"
			(at 0 0 180)
			(layer "F.SilkS")
			(hide yes)
			(effects
				(font
					(size 1.27 1.27)
				)
			)
		)
		(property "Value" ""
			(at 0 0 180)
			(layer "F.Fab")
			(effects
				(font
					(size 1.27 1.27)
				)
			)
		)
		(duplicate_pad_numbers_are_jumpers no)
		(fp_line
			(start 0.7874 0.4064)
			(end -0.7874 0.4064)
			(stroke
				(width 0.1524)
				(type default)
			)
			(layer "F.SilkS")
		)
		(fp_line
			(start 0.7874 -0.4064)
			(end 0.7874 0.4064)
			(stroke
				(width 0.1524)
				(type default)
			)
			(layer "F.SilkS")
		)
		(fp_line
			(start -0.7874 0.4064)
			(end -0.7874 -0.4064)
			(stroke
				(width 0.1524)
				(type default)
			)
			(layer "F.SilkS")
		)
		(fp_line
			(start -0.7874 -0.4064)
			(end 0.7874 -0.4064)
			(stroke
				(width 0.1524)
				(type default)
			)
			(layer "F.SilkS")
		)
		(fp_line
			(start 0.67945 0.3048)
			(end 0.120396 0.3048)
			(stroke
				(width 0.1)
				(type default)
			)
			(layer "F.Fab")
		)
		(fp_line
			(start 0.67945 -0.3048)
			(end 0.67945 0.3048)
			(stroke
				(width 0.1)
				(type default)
			)
			(layer "F.Fab")
		)
		(fp_line
			(start 0.12065 -0.2794)
			(end 0.12065 -0.3048)
			(stroke
				(width 0.1)
				(type default)
			)
			(layer "F.Fab")
		)
		(fp_line
			(start 0.12065 -0.3048)
			(end 0.67945 -0.3048)
			(stroke
				(width 0.1)
				(type default)
			)
			(layer "F.Fab")
		)
		(fp_line
			(start 0.120396 0.3048)
			(end 0.120396 0.2794)
			(stroke
				(width 0.1)
				(type default)
			)
			(layer "F.Fab")
		)
		(fp_line
			(start 0.120396 0.2794)
			(end -0.12065 0.2794)
			(stroke
				(width 0.1)
				(type default)
			)
			(layer "F.Fab")
		)
		(fp_line
			(start -0.12065 0.3048)
			(end -0.67945 0.3048)
			(stroke
				(width 0.1)
				(type default)
			)
			(layer "F.Fab")
		)
		(fp_line
			(start -0.12065 0.2794)
			(end -0.12065 0.3048)
			(stroke
				(width 0.1)
				(type default)
			)
			(layer "F.Fab")
		)
		(fp_line
			(start -0.12065 -0.2794)
			(end 0.12065 -0.2794)
			(stroke
				(width 0.1)
				(type default)
			)
			(layer "F.Fab")
		)
		(fp_line
			(start -0.12065 -0.305054)
			(end -0.12065 -0.2794)
			(stroke
				(width 0.1)
				(type default)
			)
			(layer "F.Fab")
		)
		(fp_line
			(start -0.67945 0.3048)
			(end -0.67945 -0.305054)
			(stroke
				(width 0.1)
				(type default)
			)
			(layer "F.Fab")
		)
		(fp_line
			(start -0.67945 -0.305054)
			(end -0.12065 -0.305054)
			(stroke
				(width 0.1)
				(type default)
			)
			(layer "F.Fab")
		)
		(pad "1" smd circle
			(at -0.40005 0 180)
			(size 0 0)
			(layers "F.Cu" "F.Mask" "F.Paste")
			(net "P12V_OCP_V3_2")
		)
		(pad "2" smd circle
			(at 0.40005 0 180)
			(size 0 0)
			(layers "F.Cu" "F.Mask" "F.Paste")
			(net "GND")
		)
	)
	(footprint ""
		(layer "F.Cu")
		(at 157.02788 -120.106948 180)
		(property "Reference" "R983"
			(at 0 0 180)
			(layer "F.SilkS")
			(hide yes)
			(effects
				(font
					(size 1.27 1.27)
				)
			)
		)
		(property "Value" ""
			(at 0 0 180)
			(layer "F.Fab")
			(effects
				(font
					(size 1.27 1.27)
				)
			)
		)
		(duplicate_pad_numbers_are_jumpers no)
		(fp_line
			(start 0.7874 0.4064)
			(end -0.7874 0.4064)
			(stroke
				(width 0.1524)
				(type default)
			)
			(layer "F.SilkS")
		)
		(fp_line
			(start 0.7874 -0.4064)
			(end 0.7874 0.4064)
			(stroke
				(width 0.1524)
				(type default)
			)
			(layer "F.SilkS")
		)
		(fp_line
			(start -0.7874 0.4064)
			(end -0.7874 -0.4064)
			(stroke
				(width 0.1524)
				(type default)
			)
			(layer "F.SilkS")
		)
		(fp_line
			(start -0.7874 -0.4064)
			(end 0.7874 -0.4064)
			(stroke
				(width 0.1524)
				(type default)
			)
			(layer "F.SilkS")
		)
		(fp_line
			(start 0.67945 0.3048)
			(end 0.120396 0.3048)
			(stroke
				(width 0.1)
				(type default)
			)
			(layer "F.Fab")
		)
		(fp_line
			(start 0.67945 -0.3048)
			(end 0.67945 0.3048)
			(stroke
				(width 0.1)
				(type default)
			)
			(layer "F.Fab")
		)
		(fp_line
			(start 0.12065 -0.2794)
			(end 0.12065 -0.3048)
			(stroke
				(width 0.1)
				(type default)
			)
			(layer "F.Fab")
		)
		(fp_line
			(start 0.12065 -0.3048)
			(end 0.67945 -0.3048)
			(stroke
				(width 0.1)
				(type default)
			)
			(layer "F.Fab")
		)
		(fp_line
			(start 0.120396 0.3048)
			(end 0.120396 0.2794)
			(stroke
				(width 0.1)
				(type default)
			)
			(layer "F.Fab")
		)
		(fp_line
			(start 0.120396 0.2794)
			(end -0.12065 0.2794)
			(stroke
				(width 0.1)
				(type default)
			)
			(layer "F.Fab")
		)
		(fp_line
			(start -0.12065 0.3048)
			(end -0.67945 0.3048)
			(stroke
				(width 0.1)
				(type default)
			)
			(layer "F.Fab")
		)
		(fp_line
			(start -0.12065 0.2794)
			(end -0.12065 0.3048)
			(stroke
				(width 0.1)
				(type default)
			)
			(layer "F.Fab")
		)
		(fp_line
			(start -0.12065 -0.2794)
			(end 0.12065 -0.2794)
			(stroke
				(width 0.1)
				(type default)
			)
			(layer "F.Fab")
		)
		(fp_line
			(start -0.12065 -0.305054)
			(end -0.12065 -0.2794)
			(stroke
				(width 0.1)
				(type default)
			)
			(layer "F.Fab")
		)
		(fp_line
			(start -0.67945 0.3048)
			(end -0.67945 -0.305054)
			(stroke
				(width 0.1)
				(type default)
			)
			(layer "F.Fab")
		)
		(fp_line
			(start -0.67945 -0.305054)
			(end -0.12065 -0.305054)
			(stroke
				(width 0.1)
				(type default)
			)
			(layer "F.Fab")
		)
		(pad "1" smd circle
			(at -0.40005 0 180)
			(size 0 0)
			(layers "F.Cu" "F.Mask" "F.Paste")
			(net "FM_PVCCINFAON_CPU0_R_EN")
		)
		(pad "2" smd circle
			(at 0.40005 0 180)
			(size 0 0)
			(layers "F.Cu" "F.Mask" "F.Paste")
			(net "FM_PVCCINFAON_CPU0_EN")
		)
	)
	(footprint ""
		(layer "F.Cu")
		(at 96.48444 -65.143634 -90)
		(property "Reference" "R3098"
			(at 0 0 270)
			(layer "F.SilkS")
			(hide yes)
			(effects
				(font
					(size 1.27 1.27)
				)
			)
		)
		(property "Value" ""
			(at 0 0 270)
			(layer "F.Fab")
			(effects
				(font
					(size 1.27 1.27)
				)
			)
		)
		(duplicate_pad_numbers_are_jumpers no)
		(fp_line
			(start -0.7874 0.4064)
			(end -0.7874 -0.4064)
			(stroke
				(width 0.1524)
				(type default)
			)
			(layer "F.SilkS")
		)
		(fp_line
			(start 0.7874 0.4064)
			(end -0.7874 0.4064)
			(stroke
				(width 0.1524)
				(type default)
			)
			(layer "F.SilkS")
		)
		(fp_line
			(start -0.7874 -0.4064)
			(end 0.7874 -0.4064)
			(stroke
				(width 0.1524)
				(type default)
			)
			(layer "F.SilkS")
		)
		(fp_line
			(start 0.7874 -0.4064)
			(end 0.7874 0.4064)
			(stroke
				(width 0.1524)
				(type default)
			)
			(layer "F.SilkS")
		)
		(fp_line
			(start -0.67945 0.3048)
			(end -0.67945 -0.305054)
			(stroke
				(width 0.1)
				(type default)
			)
			(layer "F.Fab")
		)
		(fp_line
			(start -0.12065 0.3048)
			(end -0.67945 0.3048)
			(stroke
				(width 0.1)
				(type default)
			)
			(layer "F.Fab")
		)
		(fp_line
			(start 0.120396 0.3048)
			(end 0.120396 0.2794)
			(stroke
				(width 0.1)
				(type default)
			)
			(layer "F.Fab")
		)
		(fp_line
			(start 0.67945 0.3048)
			(end 0.120396 0.3048)
			(stroke
				(width 0.1)
				(type default)
			)
			(layer "F.Fab")
		)
		(fp_line
			(start -0.12065 0.2794)
			(end -0.12065 0.3048)
			(stroke
				(width 0.1)
				(type default)
			)
			(layer "F.Fab")
		)
		(fp_line
			(start 0.120396 0.2794)
			(end -0.12065 0.2794)
			(stroke
				(width 0.1)
				(type default)
			)
			(layer "F.Fab")
		)
		(fp_line
			(start -0.12065 -0.2794)
			(end 0.12065 -0.2794)
			(stroke
				(width 0.1)
				(type default)
			)
			(layer "F.Fab")
		)
		(fp_line
			(start 0.12065 -0.2794)
			(end 0.12065 -0.3048)
			(stroke
				(width 0.1)
				(type default)
			)
			(layer "F.Fab")
		)
		(fp_line
			(start 0.12065 -0.3048)
			(end 0.67945 -0.3048)
			(stroke
				(width 0.1)
				(type default)
			)
			(layer "F.Fab")
		)
		(fp_line
			(start 0.67945 -0.3048)
			(end 0.67945 0.3048)
			(stroke
				(width 0.1)
				(type default)
			)
			(layer "F.Fab")
		)
		(fp_line
			(start -0.67945 -0.305054)
			(end -0.12065 -0.305054)
			(stroke
				(width 0.1)
				(type default)
			)
			(layer "F.Fab")
		)
		(fp_line
			(start -0.12065 -0.305054)
			(end -0.12065 -0.2794)
			(stroke
				(width 0.1)
				(type default)
			)
			(layer "F.Fab")
		)
		(pad "1" smd circle
			(at -0.40005 0 270)
			(size 0 0)
			(layers "F.Cu" "F.Mask" "F.Paste")
			(net "LED_PWRGD_PVCCIN_CPU1")
		)
		(pad "2" smd circle
			(at 0.40005 0 270)
			(size 0 0)
			(layers "F.Cu" "F.Mask" "F.Paste")
			(net "P3V3_AUX")
		)
	)
	(footprint ""
		(layer "F.Cu")
		(at 24.7015 -182.59552)
		(property "Reference" "PR2220"
			(at 0 0 0)
			(layer "F.SilkS")
			(hide yes)
			(effects
				(font
					(size 1.27 1.27)
				)
			)
		)
		(property "Value" ""
			(at 0 0 0)
			(layer "F.Fab")
			(effects
				(font
					(size 1.27 1.27)
				)
			)
		)
		(duplicate_pad_numbers_are_jumpers no)
		(fp_line
			(start -0.7874 -0.4064)
			(end 0.7874 -0.4064)
			(stroke
				(width 0.1524)
				(type default)
			)
			(layer "F.SilkS")
		)
		(fp_line
			(start -0.7874 0.4064)
			(end -0.7874 -0.4064)
			(stroke
				(width 0.1524)
				(type default)
			)
			(layer "F.SilkS")
		)
		(fp_line
			(start 0.7874 -0.4064)
			(end 0.7874 0.4064)
			(stroke
				(width 0.1524)
				(type default)
			)
			(layer "F.SilkS")
		)
		(fp_line
			(start 0.7874 0.4064)
			(end -0.7874 0.4064)
			(stroke
				(width 0.1524)
				(type default)
			)
			(layer "F.SilkS")
		)
		(fp_line
			(start -0.67945 -0.305054)
			(end -0.12065 -0.305054)
			(stroke
				(width 0.1)
				(type default)
			)
			(layer "F.Fab")
		)
		(fp_line
			(start -0.67945 0.3048)
			(end -0.67945 -0.305054)
			(stroke
				(width 0.1)
				(type default)
			)
			(layer "F.Fab")
		)
		(fp_line
			(start -0.12065 -0.305054)
			(end -0.12065 -0.2794)
			(stroke
				(width 0.1)
				(type default)
			)
			(layer "F.Fab")
		)
		(fp_line
			(start -0.12065 -0.2794)
			(end 0.12065 -0.2794)
			(stroke
				(width 0.1)
				(type default)
			)
			(layer "F.Fab")
		)
		(fp_line
			(start -0.12065 0.2794)
			(end -0.12065 0.3048)
			(stroke
				(width 0.1)
				(type default)
			)
			(layer "F.Fab")
		)
		(fp_line
			(start -0.12065 0.3048)
			(end -0.67945 0.3048)
			(stroke
				(width 0.1)
				(type default)
			)
			(layer "F.Fab")
		)
		(fp_line
			(start 0.120396 0.2794)
			(end -0.12065 0.2794)
			(stroke
				(width 0.1)
				(type default)
			)
			(layer "F.Fab")
		)
		(fp_line
			(start 0.120396 0.3048)
			(end 0.120396 0.2794)
			(stroke
				(width 0.1)
				(type default)
			)
			(layer "F.Fab")
		)
		(fp_line
			(start 0.12065 -0.3048)
			(end 0.67945 -0.3048)
			(stroke
				(width 0.1)
				(type default)
			)
			(layer "F.Fab")
		)
		(fp_line
			(start 0.12065 -0.2794)
			(end 0.12065 -0.3048)
			(stroke
				(width 0.1)
				(type default)
			)
			(layer "F.Fab")
		)
		(fp_line
			(start 0.67945 -0.3048)
			(end 0.67945 0.3048)
			(stroke
				(width 0.1)
				(type default)
			)
			(layer "F.Fab")
		)
		(fp_line
			(start 0.67945 0.3048)
			(end 0.120396 0.3048)
			(stroke
				(width 0.1)
				(type default)
			)
			(layer "F.Fab")
		)
		(pad "1" smd circle
			(at -0.40005 0)
			(size 0 0)
			(layers "F.Cu" "F.Mask" "F.Paste")
			(net "PVNN_MAIN_CPU1_MODE")
		)
		(pad "2" smd circle
			(at 0.40005 0)
			(size 0 0)
			(layers "F.Cu" "F.Mask" "F.Paste")
			(net "GND")
		)
	)
	(footprint ""
		(layer "F.Cu")
		(at 420.473632 -161.490914)
		(property "Reference" "PR1784"
			(at 0 0 0)
			(layer "F.SilkS")
			(hide yes)
			(effects
				(font
					(size 1.27 1.27)
				)
			)
		)
		(property "Value" ""
			(at 0 0 0)
			(layer "F.Fab")
			(effects
				(font
					(size 1.27 1.27)
				)
			)
		)
		(duplicate_pad_numbers_are_jumpers no)
		(fp_line
			(start -0.7874 -0.4064)
			(end 0.7874 -0.4064)
			(stroke
				(width 0.1524)
				(type default)
			)
			(layer "F.SilkS")
		)
		(fp_line
			(start -0.7874 0.4064)
			(end -0.7874 -0.4064)
			(stroke
				(width 0.1524)
				(type default)
			)
			(layer "F.SilkS")
		)
		(fp_line
			(start 0.7874 -0.4064)
			(end 0.7874 0.4064)
			(stroke
				(width 0.1524)
				(type default)
			)
			(layer "F.SilkS")
		)
		(fp_line
			(start 0.7874 0.4064)
			(end -0.7874 0.4064)
			(stroke
				(width 0.1524)
				(type default)
			)
			(layer "F.SilkS")
		)
		(fp_line
			(start -0.67945 -0.305054)
			(end -0.12065 -0.305054)
			(stroke
				(width 0.1)
				(type default)
			)
			(layer "F.Fab")
		)
		(fp_line
			(start -0.67945 0.3048)
			(end -0.67945 -0.305054)
			(stroke
				(width 0.1)
				(type default)
			)
			(layer "F.Fab")
		)
		(fp_line
			(start -0.12065 -0.305054)
			(end -0.12065 -0.2794)
			(stroke
				(width 0.1)
				(type default)
			)
			(layer "F.Fab")
		)
		(fp_line
			(start -0.12065 -0.2794)
			(end 0.12065 -0.2794)
			(stroke
				(width 0.1)
				(type default)
			)
			(layer "F.Fab")
		)
		(fp_line
			(start -0.12065 0.2794)
			(end -0.12065 0.3048)
			(stroke
				(width 0.1)
				(type default)
			)
			(layer "F.Fab")
		)
		(fp_line
			(start -0.12065 0.3048)
			(end -0.67945 0.3048)
			(stroke
				(width 0.1)
				(type default)
			)
			(layer "F.Fab")
		)
		(fp_line
			(start 0.120396 0.2794)
			(end -0.12065 0.2794)
			(stroke
				(width 0.1)
				(type default)
			)
			(layer "F.Fab")
		)
		(fp_line
			(start 0.120396 0.3048)
			(end 0.120396 0.2794)
			(stroke
				(width 0.1)
				(type default)
			)
			(layer "F.Fab")
		)
		(fp_line
			(start 0.12065 -0.3048)
			(end 0.67945 -0.3048)
			(stroke
				(width 0.1)
				(type default)
			)
			(layer "F.Fab")
		)
		(fp_line
			(start 0.12065 -0.2794)
			(end 0.12065 -0.3048)
			(stroke
				(width 0.1)
				(type default)
			)
			(layer "F.Fab")
		)
		(fp_line
			(start 0.67945 -0.3048)
			(end 0.67945 0.3048)
			(stroke
				(width 0.1)
				(type default)
			)
			(layer "F.Fab")
		)
		(fp_line
			(start 0.67945 0.3048)
			(end 0.120396 0.3048)
			(stroke
				(width 0.1)
				(type default)
			)
			(layer "F.Fab")
		)
		(pad "1" smd circle
			(at -0.40005 0)
			(size 0 0)
			(layers "F.Cu" "F.Mask" "F.Paste")
			(net "SW_PVCCD_HV_CPU0_BOOT1")
		)
		(pad "2" smd circle
			(at 0.40005 0)
			(size 0 0)
			(layers "F.Cu" "F.Mask" "F.Paste")
			(net "SW_PVCCD_HV_CPU0_BOOT1_R")
		)
	)
	(footprint ""
		(layer "F.Cu")
		(at 376.2883 -342.270334)
		(property "Reference" "PR139"
			(at 0 0 0)
			(layer "F.SilkS")
			(hide yes)
			(effects
				(font
					(size 1.27 1.27)
				)
			)
		)
		(property "Value" ""
			(at 0 0 0)
			(layer "F.Fab")
			(effects
				(font
					(size 1.27 1.27)
				)
			)
		)
		(duplicate_pad_numbers_are_jumpers no)
		(fp_line
			(start -0.7874 -0.4064)
			(end 0.7874 -0.4064)
			(stroke
				(width 0.1524)
				(type default)
			)
			(layer "F.SilkS")
		)
		(fp_line
			(start -0.7874 0.4064)
			(end -0.7874 -0.4064)
			(stroke
				(width 0.1524)
				(type default)
			)
			(layer "F.SilkS")
		)
		(fp_line
			(start 0.7874 -0.4064)
			(end 0.7874 0.4064)
			(stroke
				(width 0.1524)
				(type default)
			)
			(layer "F.SilkS")
		)
		(fp_line
			(start 0.7874 0.4064)
			(end -0.7874 0.4064)
			(stroke
				(width 0.1524)
				(type default)
			)
			(layer "F.SilkS")
		)
		(fp_line
			(start -0.67945 -0.305054)
			(end -0.12065 -0.305054)
			(stroke
				(width 0.1)
				(type default)
			)
			(layer "F.Fab")
		)
		(fp_line
			(start -0.67945 0.3048)
			(end -0.67945 -0.305054)
			(stroke
				(width 0.1)
				(type default)
			)
			(layer "F.Fab")
		)
		(fp_line
			(start -0.12065 -0.305054)
			(end -0.12065 -0.2794)
			(stroke
				(width 0.1)
				(type default)
			)
			(layer "F.Fab")
		)
		(fp_line
			(start -0.12065 -0.2794)
			(end 0.12065 -0.2794)
			(stroke
				(width 0.1)
				(type default)
			)
			(layer "F.Fab")
		)
		(fp_line
			(start -0.12065 0.2794)
			(end -0.12065 0.3048)
			(stroke
				(width 0.1)
				(type default)
			)
			(layer "F.Fab")
		)
		(fp_line
			(start -0.12065 0.3048)
			(end -0.67945 0.3048)
			(stroke
				(width 0.1)
				(type default)
			)
			(layer "F.Fab")
		)
		(fp_line
			(start 0.120396 0.2794)
			(end -0.12065 0.2794)
			(stroke
				(width 0.1)
				(type default)
			)
			(layer "F.Fab")
		)
		(fp_line
			(start 0.120396 0.3048)
			(end 0.120396 0.2794)
			(stroke
				(width 0.1)
				(type default)
			)
			(layer "F.Fab")
		)
		(fp_line
			(start 0.12065 -0.3048)
			(end 0.67945 -0.3048)
			(stroke
				(width 0.1)
				(type default)
			)
			(layer "F.Fab")
		)
		(fp_line
			(start 0.12065 -0.2794)
			(end 0.12065 -0.3048)
			(stroke
				(width 0.1)
				(type default)
			)
			(layer "F.Fab")
		)
		(fp_line
			(start 0.67945 -0.3048)
			(end 0.67945 0.3048)
			(stroke
				(width 0.1)
				(type default)
			)
			(layer "F.Fab")
		)
		(fp_line
			(start 0.67945 0.3048)
			(end 0.120396 0.3048)
			(stroke
				(width 0.1)
				(type default)
			)
			(layer "F.Fab")
		)
		(pad "1" smd circle
			(at -0.40005 0)
			(size 0 0)
			(layers "F.Cu" "F.Mask" "F.Paste")
			(net "PVCCIN_CPU0_LSET5")
		)
		(pad "2" smd circle
			(at 0.40005 0)
			(size 0 0)
			(layers "F.Cu" "F.Mask" "F.Paste")
			(net "GND")
		)
	)
	(footprint ""
		(layer "F.Cu")
		(at 75.738736 -74.901552 -90)
		(property "Reference" "R3089"
			(at 0 0 270)
			(layer "F.SilkS")
			(hide yes)
			(effects
				(font
					(size 1.27 1.27)
				)
			)
		)
		(property "Value" ""
			(at 0 0 270)
			(layer "F.Fab")
			(effects
				(font
					(size 1.27 1.27)
				)
			)
		)
		(duplicate_pad_numbers_are_jumpers no)
		(fp_line
			(start -0.7874 0.4064)
			(end -0.7874 -0.4064)
			(stroke
				(width 0.1524)
				(type default)
			)
			(layer "F.SilkS")
		)
		(fp_line
			(start 0.7874 0.4064)
			(end -0.7874 0.4064)
			(stroke
				(width 0.1524)
				(type default)
			)
			(layer "F.SilkS")
		)
		(fp_line
			(start -0.7874 -0.4064)
			(end 0.7874 -0.4064)
			(stroke
				(width 0.1524)
				(type default)
			)
			(layer "F.SilkS")
		)
		(fp_line
			(start 0.7874 -0.4064)
			(end 0.7874 0.4064)
			(stroke
				(width 0.1524)
				(type default)
			)
			(layer "F.SilkS")
		)
		(fp_line
			(start -0.67945 0.3048)
			(end -0.67945 -0.305054)
			(stroke
				(width 0.1)
				(type default)
			)
			(layer "F.Fab")
		)
		(fp_line
			(start -0.12065 0.3048)
			(end -0.67945 0.3048)
			(stroke
				(width 0.1)
				(type default)
			)
			(layer "F.Fab")
		)
		(fp_line
			(start 0.120396 0.3048)
			(end 0.120396 0.2794)
			(stroke
				(width 0.1)
				(type default)
			)
			(layer "F.Fab")
		)
		(fp_line
			(start 0.67945 0.3048)
			(end 0.120396 0.3048)
			(stroke
				(width 0.1)
				(type default)
			)
			(layer "F.Fab")
		)
		(fp_line
			(start -0.12065 0.2794)
			(end -0.12065 0.3048)
			(stroke
				(width 0.1)
				(type default)
			)
			(layer "F.Fab")
		)
		(fp_line
			(start 0.120396 0.2794)
			(end -0.12065 0.2794)
			(stroke
				(width 0.1)
				(type default)
			)
			(layer "F.Fab")
		)
		(fp_line
			(start -0.12065 -0.2794)
			(end 0.12065 -0.2794)
			(stroke
				(width 0.1)
				(type default)
			)
			(layer "F.Fab")
		)
		(fp_line
			(start 0.12065 -0.2794)
			(end 0.12065 -0.3048)
			(stroke
				(width 0.1)
				(type default)
			)
			(layer "F.Fab")
		)
		(fp_line
			(start 0.12065 -0.3048)
			(end 0.67945 -0.3048)
			(stroke
				(width 0.1)
				(type default)
			)
			(layer "F.Fab")
		)
		(fp_line
			(start 0.67945 -0.3048)
			(end 0.67945 0.3048)
			(stroke
				(width 0.1)
				(type default)
			)
			(layer "F.Fab")
		)
		(fp_line
			(start -0.67945 -0.305054)
			(end -0.12065 -0.305054)
			(stroke
				(width 0.1)
				(type default)
			)
			(layer "F.Fab")
		)
		(fp_line
			(start -0.12065 -0.305054)
			(end -0.12065 -0.2794)
			(stroke
				(width 0.1)
				(type default)
			)
			(layer "F.Fab")
		)
		(pad "1" smd circle
			(at -0.40005 0 270)
			(size 0 0)
			(layers "F.Cu" "F.Mask" "F.Paste")
			(net "LED_PWRGD_PVCCFA_EHV_CPU0")
		)
		(pad "2" smd circle
			(at 0.40005 0 270)
			(size 0 0)
			(layers "F.Cu" "F.Mask" "F.Paste")
			(net "P3V3_AUX")
		)
	)
	(footprint ""
		(layer "F.Cu")
		(at 360.444542 -390.43737)
		(property "Reference" "R4162"
			(at 0 0 0)
			(layer "F.SilkS")
			(hide yes)
			(effects
				(font
					(size 1.27 1.27)
				)
			)
		)
		(property "Value" ""
			(at 0 0 0)
			(layer "F.Fab")
			(effects
				(font
					(size 1.27 1.27)
				)
			)
		)
		(duplicate_pad_numbers_are_jumpers no)
		(fp_line
			(start -0.7874 -0.4064)
			(end 0.7874 -0.4064)
			(stroke
				(width 0.1524)
				(type default)
			)
			(layer "F.SilkS")
		)
		(fp_line
			(start -0.7874 0.4064)
			(end -0.7874 -0.4064)
			(stroke
				(width 0.1524)
				(type default)
			)
			(layer "F.SilkS")
		)
		(fp_line
			(start 0.7874 -0.4064)
			(end 0.7874 0.4064)
			(stroke
				(width 0.1524)
				(type default)
			)
			(layer "F.SilkS")
		)
		(fp_line
			(start 0.7874 0.4064)
			(end -0.7874 0.4064)
			(stroke
				(width 0.1524)
				(type default)
			)
			(layer "F.SilkS")
		)
		(fp_line
			(start -0.67945 -0.305054)
			(end -0.12065 -0.305054)
			(stroke
				(width 0.1)
				(type default)
			)
			(layer "F.Fab")
		)
		(fp_line
			(start -0.67945 0.3048)
			(end -0.67945 -0.305054)
			(stroke
				(width 0.1)
				(type default)
			)
			(layer "F.Fab")
		)
		(fp_line
			(start -0.12065 -0.305054)
			(end -0.12065 -0.2794)
			(stroke
				(width 0.1)
				(type default)
			)
			(layer "F.Fab")
		)
		(fp_line
			(start -0.12065 -0.2794)
			(end 0.12065 -0.2794)
			(stroke
				(width 0.1)
				(type default)
			)
			(layer "F.Fab")
		)
		(fp_line
			(start -0.12065 0.2794)
			(end -0.12065 0.3048)
			(stroke
				(width 0.1)
				(type default)
			)
			(layer "F.Fab")
		)
		(fp_line
			(start -0.12065 0.3048)
			(end -0.67945 0.3048)
			(stroke
				(width 0.1)
				(type default)
			)
			(layer "F.Fab")
		)
		(fp_line
			(start 0.120396 0.2794)
			(end -0.12065 0.2794)
			(stroke
				(width 0.1)
				(type default)
			)
			(layer "F.Fab")
		)
		(fp_line
			(start 0.120396 0.3048)
			(end 0.120396 0.2794)
			(stroke
				(width 0.1)
				(type default)
			)
			(layer "F.Fab")
		)
		(fp_line
			(start 0.12065 -0.3048)
			(end 0.67945 -0.3048)
			(stroke
				(width 0.1)
				(type default)
			)
			(layer "F.Fab")
		)
		(fp_line
			(start 0.12065 -0.2794)
			(end 0.12065 -0.3048)
			(stroke
				(width 0.1)
				(type default)
			)
			(layer "F.Fab")
		)
		(fp_line
			(start 0.67945 -0.3048)
			(end 0.67945 0.3048)
			(stroke
				(width 0.1)
				(type default)
			)
			(layer "F.Fab")
		)
		(fp_line
			(start 0.67945 0.3048)
			(end 0.120396 0.3048)
			(stroke
				(width 0.1)
				(type default)
			)
			(layer "F.Fab")
		)
		(pad "1" smd circle
			(at -0.40005 0)
			(size 0 0)
			(layers "F.Cu" "F.Mask" "F.Paste")
			(net "P3V3_AUX")
		)
		(pad "2" smd circle
			(at 0.40005 0)
			(size 0 0)
			(layers "F.Cu" "F.Mask" "F.Paste")
			(net "GPU_3V3IO_RSVD3")
		)
	)
	(footprint ""
		(layer "F.Cu")
		(at 374.112282 -57.263792)
		(property "Reference" "R746"
			(at 0 0 0)
			(layer "F.SilkS")
			(hide yes)
			(effects
				(font
					(size 1.27 1.27)
				)
			)
		)
		(property "Value" ""
			(at 0 0 0)
			(layer "F.Fab")
			(effects
				(font
					(size 1.27 1.27)
				)
			)
		)
		(duplicate_pad_numbers_are_jumpers no)
		(fp_line
			(start -0.7874 -0.4064)
			(end 0.7874 -0.4064)
			(stroke
				(width 0.1524)
				(type default)
			)
			(layer "F.SilkS")
		)
		(fp_line
			(start -0.7874 0.4064)
			(end -0.7874 -0.4064)
			(stroke
				(width 0.1524)
				(type default)
			)
			(layer "F.SilkS")
		)
		(fp_line
			(start 0.7874 -0.4064)
			(end 0.7874 0.4064)
			(stroke
				(width 0.1524)
				(type default)
			)
			(layer "F.SilkS")
		)
		(fp_line
			(start 0.7874 0.4064)
			(end -0.7874 0.4064)
			(stroke
				(width 0.1524)
				(type default)
			)
			(layer "F.SilkS")
		)
		(fp_line
			(start -0.67945 -0.305054)
			(end -0.12065 -0.305054)
			(stroke
				(width 0.1)
				(type default)
			)
			(layer "F.Fab")
		)
		(fp_line
			(start -0.67945 0.3048)
			(end -0.67945 -0.305054)
			(stroke
				(width 0.1)
				(type default)
			)
			(layer "F.Fab")
		)
		(fp_line
			(start -0.12065 -0.305054)
			(end -0.12065 -0.2794)
			(stroke
				(width 0.1)
				(type default)
			)
			(layer "F.Fab")
		)
		(fp_line
			(start -0.12065 -0.2794)
			(end 0.12065 -0.2794)
			(stroke
				(width 0.1)
				(type default)
			)
			(layer "F.Fab")
		)
		(fp_line
			(start -0.12065 0.2794)
			(end -0.12065 0.3048)
			(stroke
				(width 0.1)
				(type default)
			)
			(layer "F.Fab")
		)
		(fp_line
			(start -0.12065 0.3048)
			(end -0.67945 0.3048)
			(stroke
				(width 0.1)
				(type default)
			)
			(layer "F.Fab")
		)
		(fp_line
			(start 0.120396 0.2794)
			(end -0.12065 0.2794)
			(stroke
				(width 0.1)
				(type default)
			)
			(layer "F.Fab")
		)
		(fp_line
			(start 0.120396 0.3048)
			(end 0.120396 0.2794)
			(stroke
				(width 0.1)
				(type default)
			)
			(layer "F.Fab")
		)
		(fp_line
			(start 0.12065 -0.3048)
			(end 0.67945 -0.3048)
			(stroke
				(width 0.1)
				(type default)
			)
			(layer "F.Fab")
		)
		(fp_line
			(start 0.12065 -0.2794)
			(end 0.12065 -0.3048)
			(stroke
				(width 0.1)
				(type default)
			)
			(layer "F.Fab")
		)
		(fp_line
			(start 0.67945 -0.3048)
			(end 0.67945 0.3048)
			(stroke
				(width 0.1)
				(type default)
			)
			(layer "F.Fab")
		)
		(fp_line
			(start 0.67945 0.3048)
			(end 0.120396 0.3048)
			(stroke
				(width 0.1)
				(type default)
			)
			(layer "F.Fab")
		)
		(pad "1" smd circle
			(at -0.40005 0)
			(size 0 0)
			(layers "F.Cu" "F.Mask" "F.Paste")
			(net "PD_74CB_A9")
		)
		(pad "2" smd circle
			(at 0.40005 0)
			(size 0 0)
			(layers "F.Cu" "F.Mask" "F.Paste")
			(net "GND")
		)
	)
	(footprint ""
		(layer "F.Cu")
		(at 307.725826 -43.589194 180)
		(property "Reference" "R474"
			(at 0 0 180)
			(layer "F.SilkS")
			(hide yes)
			(effects
				(font
					(size 1.27 1.27)
				)
			)
		)
		(property "Value" ""
			(at 0 0 180)
			(layer "F.Fab")
			(effects
				(font
					(size 1.27 1.27)
				)
			)
		)
		(duplicate_pad_numbers_are_jumpers no)
		(fp_line
			(start 0.7874 0.4064)
			(end -0.7874 0.4064)
			(stroke
				(width 0.1524)
				(type default)
			)
			(layer "F.SilkS")
		)
		(fp_line
			(start 0.7874 -0.4064)
			(end 0.7874 0.4064)
			(stroke
				(width 0.1524)
				(type default)
			)
			(layer "F.SilkS")
		)
		(fp_line
			(start -0.7874 0.4064)
			(end -0.7874 -0.4064)
			(stroke
				(width 0.1524)
				(type default)
			)
			(layer "F.SilkS")
		)
		(fp_line
			(start -0.7874 -0.4064)
			(end 0.7874 -0.4064)
			(stroke
				(width 0.1524)
				(type default)
			)
			(layer "F.SilkS")
		)
		(fp_line
			(start 0.67945 0.3048)
			(end 0.120396 0.3048)
			(stroke
				(width 0.1)
				(type default)
			)
			(layer "F.Fab")
		)
		(fp_line
			(start 0.67945 -0.3048)
			(end 0.67945 0.3048)
			(stroke
				(width 0.1)
				(type default)
			)
			(layer "F.Fab")
		)
		(fp_line
			(start 0.12065 -0.2794)
			(end 0.12065 -0.3048)
			(stroke
				(width 0.1)
				(type default)
			)
			(layer "F.Fab")
		)
		(fp_line
			(start 0.12065 -0.3048)
			(end 0.67945 -0.3048)
			(stroke
				(width 0.1)
				(type default)
			)
			(layer "F.Fab")
		)
		(fp_line
			(start 0.120396 0.3048)
			(end 0.120396 0.2794)
			(stroke
				(width 0.1)
				(type default)
			)
			(layer "F.Fab")
		)
		(fp_line
			(start 0.120396 0.2794)
			(end -0.12065 0.2794)
			(stroke
				(width 0.1)
				(type default)
			)
			(layer "F.Fab")
		)
		(fp_line
			(start -0.12065 0.3048)
			(end -0.67945 0.3048)
			(stroke
				(width 0.1)
				(type default)
			)
			(layer "F.Fab")
		)
		(fp_line
			(start -0.12065 0.2794)
			(end -0.12065 0.3048)
			(stroke
				(width 0.1)
				(type default)
			)
			(layer "F.Fab")
		)
		(fp_line
			(start -0.12065 -0.2794)
			(end 0.12065 -0.2794)
			(stroke
				(width 0.1)
				(type default)
			)
			(layer "F.Fab")
		)
		(fp_line
			(start -0.12065 -0.305054)
			(end -0.12065 -0.2794)
			(stroke
				(width 0.1)
				(type default)
			)
			(layer "F.Fab")
		)
		(fp_line
			(start -0.67945 0.3048)
			(end -0.67945 -0.305054)
			(stroke
				(width 0.1)
				(type default)
			)
			(layer "F.Fab")
		)
		(fp_line
			(start -0.67945 -0.305054)
			(end -0.12065 -0.305054)
			(stroke
				(width 0.1)
				(type default)
			)
			(layer "F.Fab")
		)
		(pad "1" smd circle
			(at -0.40005 0 180)
			(size 0 0)
			(layers "F.Cu" "F.Mask" "F.Paste")
			(net "FM_PCHHOT_N")
		)
		(pad "2" smd circle
			(at 0.40005 0 180)
			(size 0 0)
			(layers "F.Cu" "F.Mask" "F.Paste")
			(net "FM_PCHHOT_R_N")
		)
	)
	(footprint ""
		(layer "F.Cu")
		(at 220.04528 -109.591348)
		(property "Reference" "R1195"
			(at 0 0 0)
			(layer "F.SilkS")
			(hide yes)
			(effects
				(font
					(size 1.27 1.27)
				)
			)
		)
		(property "Value" ""
			(at 0 0 0)
			(layer "F.Fab")
			(effects
				(font
					(size 1.27 1.27)
				)
			)
		)
		(duplicate_pad_numbers_are_jumpers no)
		(fp_line
			(start -0.7874 -0.4064)
			(end 0.7874 -0.4064)
			(stroke
				(width 0.1524)
				(type default)
			)
			(layer "F.SilkS")
		)
		(fp_line
			(start -0.7874 0.4064)
			(end -0.7874 -0.4064)
			(stroke
				(width 0.1524)
				(type default)
			)
			(layer "F.SilkS")
		)
		(fp_line
			(start 0.7874 -0.4064)
			(end 0.7874 0.4064)
			(stroke
				(width 0.1524)
				(type default)
			)
			(layer "F.SilkS")
		)
		(fp_line
			(start 0.7874 0.4064)
			(end -0.7874 0.4064)
			(stroke
				(width 0.1524)
				(type default)
			)
			(layer "F.SilkS")
		)
		(fp_line
			(start -0.67945 -0.305054)
			(end -0.12065 -0.305054)
			(stroke
				(width 0.1)
				(type default)
			)
			(layer "F.Fab")
		)
		(fp_line
			(start -0.67945 0.3048)
			(end -0.67945 -0.305054)
			(stroke
				(width 0.1)
				(type default)
			)
			(layer "F.Fab")
		)
		(fp_line
			(start -0.12065 -0.305054)
			(end -0.12065 -0.2794)
			(stroke
				(width 0.1)
				(type default)
			)
			(layer "F.Fab")
		)
		(fp_line
			(start -0.12065 -0.2794)
			(end 0.12065 -0.2794)
			(stroke
				(width 0.1)
				(type default)
			)
			(layer "F.Fab")
		)
		(fp_line
			(start -0.12065 0.2794)
			(end -0.12065 0.3048)
			(stroke
				(width 0.1)
				(type default)
			)
			(layer "F.Fab")
		)
		(fp_line
			(start -0.12065 0.3048)
			(end -0.67945 0.3048)
			(stroke
				(width 0.1)
				(type default)
			)
			(layer "F.Fab")
		)
		(fp_line
			(start 0.120396 0.2794)
			(end -0.12065 0.2794)
			(stroke
				(width 0.1)
				(type default)
			)
			(layer "F.Fab")
		)
		(fp_line
			(start 0.120396 0.3048)
			(end 0.120396 0.2794)
			(stroke
				(width 0.1)
				(type default)
			)
			(layer "F.Fab")
		)
		(fp_line
			(start 0.12065 -0.3048)
			(end 0.67945 -0.3048)
			(stroke
				(width 0.1)
				(type default)
			)
			(layer "F.Fab")
		)
		(fp_line
			(start 0.12065 -0.2794)
			(end 0.12065 -0.3048)
			(stroke
				(width 0.1)
				(type default)
			)
			(layer "F.Fab")
		)
		(fp_line
			(start 0.67945 -0.3048)
			(end 0.67945 0.3048)
			(stroke
				(width 0.1)
				(type default)
			)
			(layer "F.Fab")
		)
		(fp_line
			(start 0.67945 0.3048)
			(end 0.120396 0.3048)
			(stroke
				(width 0.1)
				(type default)
			)
			(layer "F.Fab")
		)
		(pad "1" smd circle
			(at -0.40005 0)
			(size 0 0)
			(layers "F.Cu" "F.Mask" "F.Paste")
			(net "P3V3_AUX")
		)
		(pad "2" smd circle
			(at 0.40005 0)
			(size 0 0)
			(layers "F.Cu" "F.Mask" "F.Paste")
			(net "PU_PLD_HEARTBEAT_LVC3")
		)
	)
	(footprint ""
		(layer "F.Cu")
		(at 102.845616 -355.773736)
		(property "Reference" "R312"
			(at 0 0 0)
			(layer "F.SilkS")
			(hide yes)
			(effects
				(font
					(size 1.27 1.27)
				)
			)
		)
		(property "Value" ""
			(at 0 0 0)
			(layer "F.Fab")
			(effects
				(font
					(size 1.27 1.27)
				)
			)
		)
		(duplicate_pad_numbers_are_jumpers no)
		(fp_line
			(start -0.7874 -0.4064)
			(end 0.7874 -0.4064)
			(stroke
				(width 0.1524)
				(type default)
			)
			(layer "F.SilkS")
		)
		(fp_line
			(start -0.7874 0.4064)
			(end -0.7874 -0.4064)
			(stroke
				(width 0.1524)
				(type default)
			)
			(layer "F.SilkS")
		)
		(fp_line
			(start 0.7874 -0.4064)
			(end 0.7874 0.4064)
			(stroke
				(width 0.1524)
				(type default)
			)
			(layer "F.SilkS")
		)
		(fp_line
			(start 0.7874 0.4064)
			(end -0.7874 0.4064)
			(stroke
				(width 0.1524)
				(type default)
			)
			(layer "F.SilkS")
		)
		(fp_line
			(start -0.67945 -0.305054)
			(end -0.12065 -0.305054)
			(stroke
				(width 0.1)
				(type default)
			)
			(layer "F.Fab")
		)
		(fp_line
			(start -0.67945 0.3048)
			(end -0.67945 -0.305054)
			(stroke
				(width 0.1)
				(type default)
			)
			(layer "F.Fab")
		)
		(fp_line
			(start -0.12065 -0.305054)
			(end -0.12065 -0.2794)
			(stroke
				(width 0.1)
				(type default)
			)
			(layer "F.Fab")
		)
		(fp_line
			(start -0.12065 -0.2794)
			(end 0.12065 -0.2794)
			(stroke
				(width 0.1)
				(type default)
			)
			(layer "F.Fab")
		)
		(fp_line
			(start -0.12065 0.2794)
			(end -0.12065 0.3048)
			(stroke
				(width 0.1)
				(type default)
			)
			(layer "F.Fab")
		)
		(fp_line
			(start -0.12065 0.3048)
			(end -0.67945 0.3048)
			(stroke
				(width 0.1)
				(type default)
			)
			(layer "F.Fab")
		)
		(fp_line
			(start 0.120396 0.2794)
			(end -0.12065 0.2794)
			(stroke
				(width 0.1)
				(type default)
			)
			(layer "F.Fab")
		)
		(fp_line
			(start 0.120396 0.3048)
			(end 0.120396 0.2794)
			(stroke
				(width 0.1)
				(type default)
			)
			(layer "F.Fab")
		)
		(fp_line
			(start 0.12065 -0.3048)
			(end 0.67945 -0.3048)
			(stroke
				(width 0.1)
				(type default)
			)
			(layer "F.Fab")
		)
		(fp_line
			(start 0.12065 -0.2794)
			(end 0.12065 -0.3048)
			(stroke
				(width 0.1)
				(type default)
			)
			(layer "F.Fab")
		)
		(fp_line
			(start 0.67945 -0.3048)
			(end 0.67945 0.3048)
			(stroke
				(width 0.1)
				(type default)
			)
			(layer "F.Fab")
		)
		(fp_line
			(start 0.67945 0.3048)
			(end 0.120396 0.3048)
			(stroke
				(width 0.1)
				(type default)
			)
			(layer "F.Fab")
		)
		(pad "1" smd circle
			(at -0.40005 0)
			(size 0 0)
			(layers "F.Cu" "F.Mask" "F.Paste")
			(net "SVID_ALERT0_CPU1_R_N")
		)
		(pad "2" smd circle
			(at 0.40005 0)
			(size 0 0)
			(layers "F.Cu" "F.Mask" "F.Paste")
			(net "SVID_ALERT_PVCCIN_CPU1_R")
		)
	)
	(footprint ""
		(layer "F.Cu")
		(at 128.548384 -359.871518 -90)
		(property "Reference" "PC644"
			(at 0 0 270)
			(layer "F.SilkS")
			(hide yes)
			(effects
				(font
					(size 1.27 1.27)
				)
			)
		)
		(property "Value" ""
			(at 0 0 270)
			(layer "F.Fab")
			(effects
				(font
					(size 1.27 1.27)
				)
			)
		)
		(duplicate_pad_numbers_are_jumpers no)
		(fp_line
			(start -0.7874 0.4064)
			(end -0.7874 -0.4064)
			(stroke
				(width 0.1524)
				(type default)
			)
			(layer "F.SilkS")
		)
		(fp_line
			(start 0.7874 0.4064)
			(end -0.7874 0.4064)
			(stroke
				(width 0.1524)
				(type default)
			)
			(layer "F.SilkS")
		)
		(fp_line
			(start -0.7874 -0.4064)
			(end 0.7874 -0.4064)
			(stroke
				(width 0.1524)
				(type default)
			)
			(layer "F.SilkS")
		)
		(fp_line
			(start 0.7874 -0.4064)
			(end 0.7874 0.4064)
			(stroke
				(width 0.1524)
				(type default)
			)
			(layer "F.SilkS")
		)
		(fp_line
			(start -0.67945 0.3048)
			(end -0.67945 -0.305054)
			(stroke
				(width 0.1)
				(type default)
			)
			(layer "F.Fab")
		)
		(fp_line
			(start -0.12065 0.3048)
			(end -0.67945 0.3048)
			(stroke
				(width 0.1)
				(type default)
			)
			(layer "F.Fab")
		)
		(fp_line
			(start 0.120396 0.3048)
			(end 0.120396 0.2794)
			(stroke
				(width 0.1)
				(type default)
			)
			(layer "F.Fab")
		)
		(fp_line
			(start 0.67945 0.3048)
			(end 0.120396 0.3048)
			(stroke
				(width 0.1)
				(type default)
			)
			(layer "F.Fab")
		)
		(fp_line
			(start -0.12065 0.2794)
			(end -0.12065 0.3048)
			(stroke
				(width 0.1)
				(type default)
			)
			(layer "F.Fab")
		)
		(fp_line
			(start 0.120396 0.2794)
			(end -0.12065 0.2794)
			(stroke
				(width 0.1)
				(type default)
			)
			(layer "F.Fab")
		)
		(fp_line
			(start -0.12065 -0.2794)
			(end 0.12065 -0.2794)
			(stroke
				(width 0.1)
				(type default)
			)
			(layer "F.Fab")
		)
		(fp_line
			(start 0.12065 -0.2794)
			(end 0.12065 -0.3048)
			(stroke
				(width 0.1)
				(type default)
			)
			(layer "F.Fab")
		)
		(fp_line
			(start 0.12065 -0.3048)
			(end 0.67945 -0.3048)
			(stroke
				(width 0.1)
				(type default)
			)
			(layer "F.Fab")
		)
		(fp_line
			(start 0.67945 -0.3048)
			(end 0.67945 0.3048)
			(stroke
				(width 0.1)
				(type default)
			)
			(layer "F.Fab")
		)
		(fp_line
			(start -0.67945 -0.305054)
			(end -0.12065 -0.305054)
			(stroke
				(width 0.1)
				(type default)
			)
			(layer "F.Fab")
		)
		(fp_line
			(start -0.12065 -0.305054)
			(end -0.12065 -0.2794)
			(stroke
				(width 0.1)
				(type default)
			)
			(layer "F.Fab")
		)
		(pad "1" smd circle
			(at -0.40005 0 270)
			(size 0 0)
			(layers "F.Cu" "F.Mask" "F.Paste")
			(net "PVPP_HBM_CPU1_VCC")
		)
		(pad "2" smd circle
			(at 0.40005 0 270)
			(size 0 0)
			(layers "F.Cu" "F.Mask" "F.Paste")
			(net "GND")
		)
	)
	(footprint ""
		(layer "F.Cu")
		(at 213.54288 -32.857948 180)
		(property "Reference" "R3577"
			(at 0 0 180)
			(layer "F.SilkS")
			(hide yes)
			(effects
				(font
					(size 1.27 1.27)
				)
			)
		)
		(property "Value" ""
			(at 0 0 180)
			(layer "F.Fab")
			(effects
				(font
					(size 1.27 1.27)
				)
			)
		)
		(duplicate_pad_numbers_are_jumpers no)
		(fp_line
			(start 0.7874 0.4064)
			(end -0.7874 0.4064)
			(stroke
				(width 0.1524)
				(type default)
			)
			(layer "F.SilkS")
		)
		(fp_line
			(start 0.7874 -0.4064)
			(end 0.7874 0.4064)
			(stroke
				(width 0.1524)
				(type default)
			)
			(layer "F.SilkS")
		)
		(fp_line
			(start -0.7874 0.4064)
			(end -0.7874 -0.4064)
			(stroke
				(width 0.1524)
				(type default)
			)
			(layer "F.SilkS")
		)
		(fp_line
			(start -0.7874 -0.4064)
			(end 0.7874 -0.4064)
			(stroke
				(width 0.1524)
				(type default)
			)
			(layer "F.SilkS")
		)
		(fp_line
			(start 0.67945 0.3048)
			(end 0.120396 0.3048)
			(stroke
				(width 0.1)
				(type default)
			)
			(layer "F.Fab")
		)
		(fp_line
			(start 0.67945 -0.3048)
			(end 0.67945 0.3048)
			(stroke
				(width 0.1)
				(type default)
			)
			(layer "F.Fab")
		)
		(fp_line
			(start 0.12065 -0.2794)
			(end 0.12065 -0.3048)
			(stroke
				(width 0.1)
				(type default)
			)
			(layer "F.Fab")
		)
		(fp_line
			(start 0.12065 -0.3048)
			(end 0.67945 -0.3048)
			(stroke
				(width 0.1)
				(type default)
			)
			(layer "F.Fab")
		)
		(fp_line
			(start 0.120396 0.3048)
			(end 0.120396 0.2794)
			(stroke
				(width 0.1)
				(type default)
			)
			(layer "F.Fab")
		)
		(fp_line
			(start 0.120396 0.2794)
			(end -0.12065 0.2794)
			(stroke
				(width 0.1)
				(type default)
			)
			(layer "F.Fab")
		)
		(fp_line
			(start -0.12065 0.3048)
			(end -0.67945 0.3048)
			(stroke
				(width 0.1)
				(type default)
			)
			(layer "F.Fab")
		)
		(fp_line
			(start -0.12065 0.2794)
			(end -0.12065 0.3048)
			(stroke
				(width 0.1)
				(type default)
			)
			(layer "F.Fab")
		)
		(fp_line
			(start -0.12065 -0.2794)
			(end 0.12065 -0.2794)
			(stroke
				(width 0.1)
				(type default)
			)
			(layer "F.Fab")
		)
		(fp_line
			(start -0.12065 -0.305054)
			(end -0.12065 -0.2794)
			(stroke
				(width 0.1)
				(type default)
			)
			(layer "F.Fab")
		)
		(fp_line
			(start -0.67945 0.3048)
			(end -0.67945 -0.305054)
			(stroke
				(width 0.1)
				(type default)
			)
			(layer "F.Fab")
		)
		(fp_line
			(start -0.67945 -0.305054)
			(end -0.12065 -0.305054)
			(stroke
				(width 0.1)
				(type default)
			)
			(layer "F.Fab")
		)
		(pad "1" smd circle
			(at -0.40005 0 180)
			(size 0 0)
			(layers "F.Cu" "F.Mask" "F.Paste")
			(net "SMB_INA230_5_3V3AUX_SDA_R")
		)
		(pad "2" smd circle
			(at 0.40005 0 180)
			(size 0 0)
			(layers "F.Cu" "F.Mask" "F.Paste")
			(net "SMB_INA230_5_3V3AUX_SDA_R1")
		)
	)
	(footprint ""
		(layer "F.Cu")
		(at 366.3696 -405.9936 180)
		(property "Reference" "C2374"
			(at 0 0 180)
			(layer "F.SilkS")
			(hide yes)
			(effects
				(font
					(size 1.27 1.27)
				)
			)
		)
		(property "Value" ""
			(at 0 0 180)
			(layer "F.Fab")
			(effects
				(font
					(size 1.27 1.27)
				)
			)
		)
		(duplicate_pad_numbers_are_jumpers no)
		(fp_line
			(start 0.7874 0.4064)
			(end -0.7874 0.4064)
			(stroke
				(width 0.1524)
				(type default)
			)
			(layer "F.SilkS")
		)
		(fp_line
			(start 0.7874 -0.4064)
			(end 0.7874 0.4064)
			(stroke
				(width 0.1524)
				(type default)
			)
			(layer "F.SilkS")
		)
		(fp_line
			(start -0.7874 0.4064)
			(end -0.7874 -0.4064)
			(stroke
				(width 0.1524)
				(type default)
			)
			(layer "F.SilkS")
		)
		(fp_line
			(start -0.7874 -0.4064)
			(end 0.7874 -0.4064)
			(stroke
				(width 0.1524)
				(type default)
			)
			(layer "F.SilkS")
		)
		(fp_line
			(start 0.67945 0.3048)
			(end 0.120396 0.3048)
			(stroke
				(width 0.1)
				(type default)
			)
			(layer "F.Fab")
		)
		(fp_line
			(start 0.67945 -0.3048)
			(end 0.67945 0.3048)
			(stroke
				(width 0.1)
				(type default)
			)
			(layer "F.Fab")
		)
		(fp_line
			(start 0.12065 -0.2794)
			(end 0.12065 -0.3048)
			(stroke
				(width 0.1)
				(type default)
			)
			(layer "F.Fab")
		)
		(fp_line
			(start 0.12065 -0.3048)
			(end 0.67945 -0.3048)
			(stroke
				(width 0.1)
				(type default)
			)
			(layer "F.Fab")
		)
		(fp_line
			(start 0.120396 0.3048)
			(end 0.120396 0.2794)
			(stroke
				(width 0.1)
				(type default)
			)
			(layer "F.Fab")
		)
		(fp_line
			(start 0.120396 0.2794)
			(end -0.12065 0.2794)
			(stroke
				(width 0.1)
				(type default)
			)
			(layer "F.Fab")
		)
		(fp_line
			(start -0.12065 0.3048)
			(end -0.67945 0.3048)
			(stroke
				(width 0.1)
				(type default)
			)
			(layer "F.Fab")
		)
		(fp_line
			(start -0.12065 0.2794)
			(end -0.12065 0.3048)
			(stroke
				(width 0.1)
				(type default)
			)
			(layer "F.Fab")
		)
		(fp_line
			(start -0.12065 -0.2794)
			(end 0.12065 -0.2794)
			(stroke
				(width 0.1)
				(type default)
			)
			(layer "F.Fab")
		)
		(fp_line
			(start -0.12065 -0.305054)
			(end -0.12065 -0.2794)
			(stroke
				(width 0.1)
				(type default)
			)
			(layer "F.Fab")
		)
		(fp_line
			(start -0.67945 0.3048)
			(end -0.67945 -0.305054)
			(stroke
				(width 0.1)
				(type default)
			)
			(layer "F.Fab")
		)
		(fp_line
			(start -0.67945 -0.305054)
			(end -0.12065 -0.305054)
			(stroke
				(width 0.1)
				(type default)
			)
			(layer "F.Fab")
		)
		(pad "1" smd circle
			(at -0.40005 0 180)
			(size 0 0)
			(layers "F.Cu" "F.Mask" "F.Paste")
			(net "PRSNT_CABLE_SWB_B1_ISO_N")
		)
		(pad "2" smd circle
			(at 0.40005 0 180)
			(size 0 0)
			(layers "F.Cu" "F.Mask" "F.Paste")
			(net "GND")
		)
	)
	(footprint ""
		(layer "F.Cu")
		(at 274.436078 -420.1033 180)
		(property "Reference" "U329"
			(at 2.276856 -2.56921 0)
			(unlocked yes)
			(layer "F.SilkS")
			(effects
				(font
					(size 0.7874 0.5842)
					(thickness 0.1524)
				)
				(justify left)
			)
		)
		(property "Value" ""
			(at 0 0 180)
			(layer "F.Fab")
			(effects
				(font
					(size 1.27 1.27)
				)
			)
		)
		(duplicate_pad_numbers_are_jumpers no)
		(fp_line
			(start 1.603248 1.500124)
			(end -1.603248 1.500124)
			(stroke
				(width 0.1524)
				(type default)
			)
			(layer "F.SilkS")
		)
		(fp_line
			(start 1.603248 -1.500124)
			(end 1.603248 1.500124)
			(stroke
				(width 0.1524)
				(type default)
			)
			(layer "F.SilkS")
		)
		(fp_line
			(start -1.603248 1.500124)
			(end -1.603248 -1.500124)
			(stroke
				(width 0.1524)
				(type default)
			)
			(layer "F.SilkS")
		)
		(fp_line
			(start -1.603248 -1.500124)
			(end 1.603248 -1.500124)
			(stroke
				(width 0.1524)
				(type default)
			)
			(layer "F.SilkS")
		)
		(fp_line
			(start 1.249934 0.219964)
			(end 1.249934 -0.219964)
			(stroke
				(width 0.1)
				(type default)
			)
			(layer "F.Fab")
		)
		(fp_line
			(start 1.249934 -0.219964)
			(end 0.700024 -0.219964)
			(stroke
				(width 0.1)
				(type default)
			)
			(layer "F.Fab")
		)
		(fp_line
			(start 0.700024 1.500124)
			(end 0.700024 0.219964)
			(stroke
				(width 0.1)
				(type default)
			)
			(layer "F.Fab")
		)
		(fp_line
			(start 0.700024 0.219964)
			(end 1.249934 0.219964)
			(stroke
				(width 0.1)
				(type default)
			)
			(layer "F.Fab")
		)
		(fp_line
			(start 0.700024 -0.219964)
			(end 0.700024 -1.500124)
			(stroke
				(width 0.1)
				(type default)
			)
			(layer "F.Fab")
		)
		(fp_line
			(start 0.700024 -1.500124)
			(end -0.700024 -1.500124)
			(stroke
				(width 0.1)
				(type default)
			)
			(layer "F.Fab")
		)
		(fp_line
			(start -0.6985 0.729996)
			(end -1.249934 0.729996)
			(stroke
				(width 0.1)
				(type default)
			)
			(layer "F.Fab")
		)
		(fp_line
			(start -0.6985 -0.729996)
			(end -0.6985 0.729996)
			(stroke
				(width 0.1)
				(type default)
			)
			(layer "F.Fab")
		)
		(fp_line
			(start -0.700024 1.500124)
			(end 0.700024 1.500124)
			(stroke
				(width 0.1)
				(type default)
			)
			(layer "F.Fab")
		)
		(fp_line
			(start -0.700024 1.169924)
			(end -0.700024 1.500124)
			(stroke
				(width 0.1)
				(type default)
			)
			(layer "F.Fab")
		)
		(fp_line
			(start -0.700024 -1.169924)
			(end -1.249934 -1.169924)
			(stroke
				(width 0.1)
				(type default)
			)
			(layer "F.Fab")
		)
		(fp_line
			(start -0.700024 -1.500124)
			(end -0.700024 -1.169924)
			(stroke
				(width 0.1)
				(type default)
			)
			(layer "F.Fab")
		)
		(fp_line
			(start -1.249934 1.169924)
			(end -0.700024 1.169924)
			(stroke
				(width 0.1)
				(type default)
			)
			(layer "F.Fab")
		)
		(fp_line
			(start -1.249934 0.729996)
			(end -1.249934 1.169924)
			(stroke
				(width 0.1)
				(type default)
			)
			(layer "F.Fab")
		)
		(fp_line
			(start -1.249934 -0.729996)
			(end -0.6985 -0.729996)
			(stroke
				(width 0.1)
				(type default)
			)
			(layer "F.Fab")
		)
		(fp_line
			(start -1.249934 -1.169924)
			(end -1.249934 -0.729996)
			(stroke
				(width 0.1)
				(type default)
			)
			(layer "F.Fab")
		)
		(fp_rect
			(start -0.700024 1.500124)
			(end 0.700024 -1.500124)
			(stroke
				(width 0)
				(type default)
			)
			(fill no)
			(layer "F.Fab")
		)
		(pad "D" smd rect
			(at 0.999998 0 90)
			(size 0.8128 0.9144)
			(layers "F.Cu" "F.Mask" "F.Paste")
			(net "A_HSC_LOW_DRAIN")
		)
		(pad "G" smd rect
			(at -0.999998 -0.94996 90)
			(size 0.8128 0.9144)
			(layers "F.Cu" "F.Mask" "F.Paste")
			(net "A_HSC_LOW_GATE")
		)
		(pad "S" smd rect
			(at -0.999998 0.94996 90)
			(size 0.8128 0.9144)
			(layers "F.Cu" "F.Mask" "F.Paste")
			(net "GND")
		)
	)
	(footprint ""
		(layer "F.Cu")
		(at 282.452826 -18.491962 180)
		(property "Reference" "R3183"
			(at 0 0 180)
			(layer "F.SilkS")
			(hide yes)
			(effects
				(font
					(size 1.27 1.27)
				)
			)
		)
		(property "Value" ""
			(at 0 0 180)
			(layer "F.Fab")
			(effects
				(font
					(size 1.27 1.27)
				)
			)
		)
		(duplicate_pad_numbers_are_jumpers no)
		(fp_line
			(start 0.7874 0.4064)
			(end -0.7874 0.4064)
			(stroke
				(width 0.1524)
				(type default)
			)
			(layer "F.SilkS")
		)
		(fp_line
			(start 0.7874 -0.4064)
			(end 0.7874 0.4064)
			(stroke
				(width 0.1524)
				(type default)
			)
			(layer "F.SilkS")
		)
		(fp_line
			(start -0.7874 0.4064)
			(end -0.7874 -0.4064)
			(stroke
				(width 0.1524)
				(type default)
			)
			(layer "F.SilkS")
		)
		(fp_line
			(start -0.7874 -0.4064)
			(end 0.7874 -0.4064)
			(stroke
				(width 0.1524)
				(type default)
			)
			(layer "F.SilkS")
		)
		(fp_line
			(start 0.67945 0.3048)
			(end 0.120396 0.3048)
			(stroke
				(width 0.1)
				(type default)
			)
			(layer "F.Fab")
		)
		(fp_line
			(start 0.67945 -0.3048)
			(end 0.67945 0.3048)
			(stroke
				(width 0.1)
				(type default)
			)
			(layer "F.Fab")
		)
		(fp_line
			(start 0.12065 -0.2794)
			(end 0.12065 -0.3048)
			(stroke
				(width 0.1)
				(type default)
			)
			(layer "F.Fab")
		)
		(fp_line
			(start 0.12065 -0.3048)
			(end 0.67945 -0.3048)
			(stroke
				(width 0.1)
				(type default)
			)
			(layer "F.Fab")
		)
		(fp_line
			(start 0.120396 0.3048)
			(end 0.120396 0.2794)
			(stroke
				(width 0.1)
				(type default)
			)
			(layer "F.Fab")
		)
		(fp_line
			(start 0.120396 0.2794)
			(end -0.12065 0.2794)
			(stroke
				(width 0.1)
				(type default)
			)
			(layer "F.Fab")
		)
		(fp_line
			(start -0.12065 0.3048)
			(end -0.67945 0.3048)
			(stroke
				(width 0.1)
				(type default)
			)
			(layer "F.Fab")
		)
		(fp_line
			(start -0.12065 0.2794)
			(end -0.12065 0.3048)
			(stroke
				(width 0.1)
				(type default)
			)
			(layer "F.Fab")
		)
		(fp_line
			(start -0.12065 -0.2794)
			(end 0.12065 -0.2794)
			(stroke
				(width 0.1)
				(type default)
			)
			(layer "F.Fab")
		)
		(fp_line
			(start -0.12065 -0.305054)
			(end -0.12065 -0.2794)
			(stroke
				(width 0.1)
				(type default)
			)
			(layer "F.Fab")
		)
		(fp_line
			(start -0.67945 0.3048)
			(end -0.67945 -0.305054)
			(stroke
				(width 0.1)
				(type default)
			)
			(layer "F.Fab")
		)
		(fp_line
			(start -0.67945 -0.305054)
			(end -0.12065 -0.305054)
			(stroke
				(width 0.1)
				(type default)
			)
			(layer "F.Fab")
		)
		(pad "1" smd circle
			(at -0.40005 0 180)
			(size 0 0)
			(layers "F.Cu" "F.Mask" "F.Paste")
			(net "P3V3_OCP_V3_2")
		)
		(pad "2" smd circle
			(at 0.40005 0 180)
			(size 0 0)
			(layers "F.Cu" "F.Mask" "F.Paste")
			(net "PU_OCP_V3_2_WAKE_OE")
		)
	)
	(footprint ""
		(layer "F.Cu")
		(at 301.45482 -421.41521 90)
		(property "Reference" "R4129"
			(at 0 0 90)
			(layer "F.SilkS")
			(hide yes)
			(effects
				(font
					(size 1.27 1.27)
				)
			)
		)
		(property "Value" ""
			(at 0 0 90)
			(layer "F.Fab")
			(effects
				(font
					(size 1.27 1.27)
				)
			)
		)
		(duplicate_pad_numbers_are_jumpers no)
		(fp_line
			(start 0.7874 -0.4064)
			(end 0.7874 0.4064)
			(stroke
				(width 0.1524)
				(type default)
			)
			(layer "F.SilkS")
		)
		(fp_line
			(start -0.7874 -0.4064)
			(end 0.7874 -0.4064)
			(stroke
				(width 0.1524)
				(type default)
			)
			(layer "F.SilkS")
		)
		(fp_line
			(start 0.7874 0.4064)
			(end -0.7874 0.4064)
			(stroke
				(width 0.1524)
				(type default)
			)
			(layer "F.SilkS")
		)
		(fp_line
			(start -0.7874 0.4064)
			(end -0.7874 -0.4064)
			(stroke
				(width 0.1524)
				(type default)
			)
			(layer "F.SilkS")
		)
		(fp_line
			(start -0.12065 -0.305054)
			(end -0.12065 -0.2794)
			(stroke
				(width 0.1)
				(type default)
			)
			(layer "F.Fab")
		)
		(fp_line
			(start -0.67945 -0.305054)
			(end -0.12065 -0.305054)
			(stroke
				(width 0.1)
				(type default)
			)
			(layer "F.Fab")
		)
		(fp_line
			(start 0.67945 -0.3048)
			(end 0.67945 0.3048)
			(stroke
				(width 0.1)
				(type default)
			)
			(layer "F.Fab")
		)
		(fp_line
			(start 0.12065 -0.3048)
			(end 0.67945 -0.3048)
			(stroke
				(width 0.1)
				(type default)
			)
			(layer "F.Fab")
		)
		(fp_line
			(start 0.12065 -0.2794)
			(end 0.12065 -0.3048)
			(stroke
				(width 0.1)
				(type default)
			)
			(layer "F.Fab")
		)
		(fp_line
			(start -0.12065 -0.2794)
			(end 0.12065 -0.2794)
			(stroke
				(width 0.1)
				(type default)
			)
			(layer "F.Fab")
		)
		(fp_line
			(start 0.120396 0.2794)
			(end -0.12065 0.2794)
			(stroke
				(width 0.1)
				(type default)
			)
			(layer "F.Fab")
		)
		(fp_line
			(start -0.12065 0.2794)
			(end -0.12065 0.3048)
			(stroke
				(width 0.1)
				(type default)
			)
			(layer "F.Fab")
		)
		(fp_line
			(start 0.67945 0.3048)
			(end 0.120396 0.3048)
			(stroke
				(width 0.1)
				(type default)
			)
			(layer "F.Fab")
		)
		(fp_line
			(start 0.120396 0.3048)
			(end 0.120396 0.2794)
			(stroke
				(width 0.1)
				(type default)
			)
			(layer "F.Fab")
		)
		(fp_line
			(start -0.12065 0.3048)
			(end -0.67945 0.3048)
			(stroke
				(width 0.1)
				(type default)
			)
			(layer "F.Fab")
		)
		(fp_line
			(start -0.67945 0.3048)
			(end -0.67945 -0.305054)
			(stroke
				(width 0.1)
				(type default)
			)
			(layer "F.Fab")
		)
		(pad "1" smd circle
			(at -0.40005 0 90)
			(size 0 0)
			(layers "F.Cu" "F.Mask" "F.Paste")
			(net "P3V3_AUX")
		)
		(pad "2" smd circle
			(at 0.40005 0 90)
			(size 0 0)
			(layers "F.Cu" "F.Mask" "F.Paste")
			(net "PRSNT_CABLE_GPU_B3_ISO_N")
		)
	)
	(footprint ""
		(layer "F.Cu")
		(at 221.821502 -70.870318)
		(property "Reference" "PU295"
			(at 4.473448 0.014478 0)
			(unlocked yes)
			(layer "F.SilkS")
			(effects
				(font
					(size 0.7874 0.5842)
					(thickness 0.1524)
				)
				(justify left)
			)
		)
		(property "Value" ""
			(at 0 0 0)
			(layer "F.Fab")
			(effects
				(font
					(size 1.27 1.27)
				)
			)
		)
		(duplicate_pad_numbers_are_jumpers no)
		(fp_line
			(start -1.774952 -1.039876)
			(end -1.774952 1.039876)
			(stroke
				(width 0.1524)
				(type default)
			)
			(layer "F.SilkS")
		)
		(fp_line
			(start -1.774952 1.039876)
			(end 1.774952 1.039876)
			(stroke
				(width 0.1524)
				(type default)
			)
			(layer "F.SilkS")
		)
		(fp_line
			(start 1.774952 -1.039876)
			(end -1.774952 -1.039876)
			(stroke
				(width 0.1524)
				(type default)
			)
			(layer "F.SilkS")
		)
		(fp_line
			(start 1.774952 1.039876)
			(end 1.774952 -1.039876)
			(stroke
				(width 0.1524)
				(type default)
			)
			(layer "F.SilkS")
		)
		(fp_poly
			(pts
				(xy -1.769872 -1.039876) (xy -1.769872 -0.249936) (xy -2.531872 -0.249936) (xy -2.531872 -1.801876)
				(xy -0.999998 -1.801876) (xy -0.999998 -1.039876)
			)
			(stroke
				(width 0)
				(type default)
			)
			(fill yes)
			(layer "F.SilkS")
		)
		(fp_line
			(start -1.769872 -1.039876)
			(end -1.769872 1.039876)
			(stroke
				(width 0.1)
				(type default)
			)
			(layer "F.Fab")
		)
		(fp_line
			(start -1.769872 1.039876)
			(end 1.769872 1.039876)
			(stroke
				(width 0.1)
				(type default)
			)
			(layer "F.Fab")
		)
		(fp_line
			(start 1.769872 -1.039876)
			(end -1.769872 -1.039876)
			(stroke
				(width 0.1)
				(type default)
			)
			(layer "F.Fab")
		)
		(fp_line
			(start 1.769872 1.039876)
			(end 1.769872 -1.039876)
			(stroke
				(width 0.1)
				(type default)
			)
			(layer "F.Fab")
		)
		(fp_poly
			(pts
				(xy -1.769872 -1.039876) (xy -0.999998 -1.039876) (xy -0.999998 -1.801876) (xy -2.531872 -1.801876)
				(xy -2.531872 -0.249936) (xy -1.769872 -0.249936)
			)
			(stroke
				(width 0)
				(type default)
			)
			(fill yes)
			(layer "F.Fab")
		)
		(pad "A1" smd circle
			(at -1.500124 -0.750062)
			(size 0.2286 0.2286)
			(layers "F.Cu" "F.Mask" "F.Paste")
			(net "P3V3_E1S_SENSE_0")
		)
		(pad "A2" smd circle
			(at -0.999998 -0.750062)
			(size 0.2286 0.2286)
			(layers "F.Cu" "F.Mask" "F.Paste")
			(net "P3V3_E1S_VCC_0")
		)
		(pad "A3" smd circle
			(at -0.499872 -0.750062)
			(size 0.2286 0.2286)
			(layers "F.Cu" "F.Mask" "F.Paste")
			(net "P3V3_AUX")
		)
		(pad "A4" smd circle
			(at 0 -0.750062)
			(size 0.2286 0.2286)
			(layers "F.Cu" "F.Mask" "F.Paste")
			(net "P3V3_E1S_0_R")
		)
		(pad "A5" smd circle
			(at 0.499872 -0.750062)
			(size 0.2286 0.2286)
			(layers "F.Cu" "F.Mask" "F.Paste")
			(net "P3V3_AUX")
		)
		(pad "A6" smd circle
			(at 0.999998 -0.750062)
			(size 0.2286 0.2286)
			(layers "F.Cu" "F.Mask" "F.Paste")
			(net "P3V3_E1S_GATE_0")
		)
		(pad "A7" smd circle
			(at 1.500124 -0.750062)
			(size 0.2286 0.2286)
			(layers "F.Cu" "F.Mask" "F.Paste")
			(net "GND")
		)
		(pad "B1" smd circle
			(at -1.500124 -0.249936)
			(size 0.2286 0.2286)
			(layers "F.Cu" "F.Mask" "F.Paste")
			(net "P3V3_E1S_CB_0")
		)
		(pad "B2" smd circle
			(at -0.999998 -0.249936)
			(size 0.2286 0.2286)
			(layers "F.Cu" "F.Mask" "F.Paste")
			(net "GND")
		)
		(pad "B3" smd circle
			(at -0.499872 -0.249936)
			(size 0.2286 0.2286)
			(layers "F.Cu" "F.Mask" "F.Paste")
			(net "P3V3_AUX")
		)
		(pad "B4" smd circle
			(at 0 -0.249936)
			(size 0.2286 0.2286)
			(layers "F.Cu" "F.Mask" "F.Paste")
			(net "P3V3_E1S_0_R")
		)
		(pad "B5" smd circle
			(at 0.499872 -0.249936)
			(size 0.2286 0.2286)
			(layers "F.Cu" "F.Mask" "F.Paste")
			(net "P3V3_AUX")
		)
		(pad "B6" smd circle
			(at 0.999998 -0.249936)
			(size 0.2286 0.2286)
			(layers "F.Cu" "F.Mask" "F.Paste")
			(net "P3V3_E1S_0_R")
		)
		(pad "B7" smd circle
			(at 1.500124 -0.249936)
			(size 0.2286 0.2286)
			(layers "F.Cu" "F.Mask" "F.Paste")
			(net "GND")
		)
		(pad "C1" smd circle
			(at -1.500124 0.249936)
			(size 0.2286 0.2286)
			(layers "F.Cu" "F.Mask" "F.Paste")
			(net "GND")
		)
		(pad "C2" smd circle
			(at -0.999998 0.249936)
			(size 0.2286 0.2286)
			(layers "F.Cu" "F.Mask" "F.Paste")
			(net "GND")
		)
		(pad "C3" smd circle
			(at -0.499872 0.249936)
			(size 0.2286 0.2286)
			(layers "F.Cu" "F.Mask" "F.Paste")
			(net "P3V3_AUX")
		)
		(pad "C4" smd circle
			(at 0 0.249936)
			(size 0.2286 0.2286)
			(layers "F.Cu" "F.Mask" "F.Paste")
			(net "P3V3_E1S_0_R")
		)
		(pad "C5" smd circle
			(at 0.499872 0.249936)
			(size 0.2286 0.2286)
			(layers "F.Cu" "F.Mask" "F.Paste")
			(net "P3V3_AUX")
		)
		(pad "C6" smd circle
			(at 0.999998 0.249936)
			(size 0.2286 0.2286)
			(layers "F.Cu" "F.Mask" "F.Paste")
			(net "P3V3_E1S_0_R")
		)
		(pad "C7" smd circle
			(at 1.500124 0.249936)
			(size 0.2286 0.2286)
			(layers "F.Cu" "F.Mask" "F.Paste")
			(net "P3V3_E1S_FAULT_0")
		)
		(pad "D1" smd circle
			(at -1.500124 0.750062)
			(size 0.2286 0.2286)
			(layers "F.Cu" "F.Mask" "F.Paste")
			(net "P3V3_E1S_REG_0")
		)
		(pad "D2" smd circle
			(at -0.999998 0.750062)
			(size 0.2286 0.2286)
			(layers "F.Cu" "F.Mask" "F.Paste")
			(net "P3V3_E1S_UV_0")
		)
		(pad "D3" smd circle
			(at -0.499872 0.750062)
			(size 0.2286 0.2286)
			(layers "F.Cu" "F.Mask" "F.Paste")
			(net "P3V3_E1S_OV_0")
		)
		(pad "D4" smd circle
			(at 0 0.750062)
			(size 0.2286 0.2286)
			(layers "F.Cu" "F.Mask" "F.Paste")
			(net "P3V3_E1S_0_R")
		)
		(pad "D5" smd circle
			(at 0.499872 0.750062)
			(size 0.2286 0.2286)
			(layers "F.Cu" "F.Mask" "F.Paste")
			(net "P3V3_AUX")
		)
		(pad "D6" smd circle
			(at 0.999998 0.750062)
			(size 0.2286 0.2286)
			(layers "F.Cu" "F.Mask" "F.Paste")
			(net "P3V3_E1S_0_R")
		)
		(pad "D7" smd circle
			(at 1.500124 0.750062)
			(size 0.2286 0.2286)
			(layers "F.Cu" "F.Mask" "F.Paste")
			(net "P3V3_E1S_PWRGD_0")
		)
	)
	(footprint ""
		(layer "F.Cu")
		(at 81.82737 -59.364626 -90)
		(property "Reference" "PC2147"
			(at 0 0 270)
			(layer "F.SilkS")
			(hide yes)
			(effects
				(font
					(size 1.27 1.27)
				)
			)
		)
		(property "Value" ""
			(at 0 0 270)
			(layer "F.Fab")
			(effects
				(font
					(size 1.27 1.27)
				)
			)
		)
		(duplicate_pad_numbers_are_jumpers no)
		(fp_line
			(start -0.7874 0.4064)
			(end -0.7874 -0.4064)
			(stroke
				(width 0.1524)
				(type default)
			)
			(layer "F.SilkS")
		)
		(fp_line
			(start 0.7874 0.4064)
			(end -0.7874 0.4064)
			(stroke
				(width 0.1524)
				(type default)
			)
			(layer "F.SilkS")
		)
		(fp_line
			(start -0.7874 -0.4064)
			(end 0.7874 -0.4064)
			(stroke
				(width 0.1524)
				(type default)
			)
			(layer "F.SilkS")
		)
		(fp_line
			(start 0.7874 -0.4064)
			(end 0.7874 0.4064)
			(stroke
				(width 0.1524)
				(type default)
			)
			(layer "F.SilkS")
		)
		(fp_line
			(start -0.67945 0.3048)
			(end -0.67945 -0.305054)
			(stroke
				(width 0.1)
				(type default)
			)
			(layer "F.Fab")
		)
		(fp_line
			(start -0.12065 0.3048)
			(end -0.67945 0.3048)
			(stroke
				(width 0.1)
				(type default)
			)
			(layer "F.Fab")
		)
		(fp_line
			(start 0.120396 0.3048)
			(end 0.120396 0.2794)
			(stroke
				(width 0.1)
				(type default)
			)
			(layer "F.Fab")
		)
		(fp_line
			(start 0.67945 0.3048)
			(end 0.120396 0.3048)
			(stroke
				(width 0.1)
				(type default)
			)
			(layer "F.Fab")
		)
		(fp_line
			(start -0.12065 0.2794)
			(end -0.12065 0.3048)
			(stroke
				(width 0.1)
				(type default)
			)
			(layer "F.Fab")
		)
		(fp_line
			(start 0.120396 0.2794)
			(end -0.12065 0.2794)
			(stroke
				(width 0.1)
				(type default)
			)
			(layer "F.Fab")
		)
		(fp_line
			(start -0.12065 -0.2794)
			(end 0.12065 -0.2794)
			(stroke
				(width 0.1)
				(type default)
			)
			(layer "F.Fab")
		)
		(fp_line
			(start 0.12065 -0.2794)
			(end 0.12065 -0.3048)
			(stroke
				(width 0.1)
				(type default)
			)
			(layer "F.Fab")
		)
		(fp_line
			(start 0.12065 -0.3048)
			(end 0.67945 -0.3048)
			(stroke
				(width 0.1)
				(type default)
			)
			(layer "F.Fab")
		)
		(fp_line
			(start 0.67945 -0.3048)
			(end 0.67945 0.3048)
			(stroke
				(width 0.1)
				(type default)
			)
			(layer "F.Fab")
		)
		(fp_line
			(start -0.67945 -0.305054)
			(end -0.12065 -0.305054)
			(stroke
				(width 0.1)
				(type default)
			)
			(layer "F.Fab")
		)
		(fp_line
			(start -0.12065 -0.305054)
			(end -0.12065 -0.2794)
			(stroke
				(width 0.1)
				(type default)
			)
			(layer "F.Fab")
		)
		(pad "1" smd circle
			(at -0.40005 0 270)
			(size 0 0)
			(layers "F.Cu" "F.Mask" "F.Paste")
			(net "GND")
		)
		(pad "2" smd circle
			(at 0.40005 0 270)
			(size 0 0)
			(layers "F.Cu" "F.Mask" "F.Paste")
			(net "P3V3_OCP_REG_2")
		)
	)
	(footprint ""
		(layer "F.Cu")
		(at 292.236398 -18.714466 180)
		(property "Reference" "C2276"
			(at 0 0 180)
			(layer "F.SilkS")
			(hide yes)
			(effects
				(font
					(size 1.27 1.27)
				)
			)
		)
		(property "Value" ""
			(at 0 0 180)
			(layer "F.Fab")
			(effects
				(font
					(size 1.27 1.27)
				)
			)
		)
		(duplicate_pad_numbers_are_jumpers no)
		(fp_line
			(start 0.7874 0.4064)
			(end -0.7874 0.4064)
			(stroke
				(width 0.1524)
				(type default)
			)
			(layer "F.SilkS")
		)
		(fp_line
			(start 0.7874 -0.4064)
			(end 0.7874 0.4064)
			(stroke
				(width 0.1524)
				(type default)
			)
			(layer "F.SilkS")
		)
		(fp_line
			(start -0.7874 0.4064)
			(end -0.7874 -0.4064)
			(stroke
				(width 0.1524)
				(type default)
			)
			(layer "F.SilkS")
		)
		(fp_line
			(start -0.7874 -0.4064)
			(end 0.7874 -0.4064)
			(stroke
				(width 0.1524)
				(type default)
			)
			(layer "F.SilkS")
		)
		(fp_line
			(start 0.67945 0.3048)
			(end 0.120396 0.3048)
			(stroke
				(width 0.1)
				(type default)
			)
			(layer "F.Fab")
		)
		(fp_line
			(start 0.67945 -0.3048)
			(end 0.67945 0.3048)
			(stroke
				(width 0.1)
				(type default)
			)
			(layer "F.Fab")
		)
		(fp_line
			(start 0.12065 -0.2794)
			(end 0.12065 -0.3048)
			(stroke
				(width 0.1)
				(type default)
			)
			(layer "F.Fab")
		)
		(fp_line
			(start 0.12065 -0.3048)
			(end 0.67945 -0.3048)
			(stroke
				(width 0.1)
				(type default)
			)
			(layer "F.Fab")
		)
		(fp_line
			(start 0.120396 0.3048)
			(end 0.120396 0.2794)
			(stroke
				(width 0.1)
				(type default)
			)
			(layer "F.Fab")
		)
		(fp_line
			(start 0.120396 0.2794)
			(end -0.12065 0.2794)
			(stroke
				(width 0.1)
				(type default)
			)
			(layer "F.Fab")
		)
		(fp_line
			(start -0.12065 0.3048)
			(end -0.67945 0.3048)
			(stroke
				(width 0.1)
				(type default)
			)
			(layer "F.Fab")
		)
		(fp_line
			(start -0.12065 0.2794)
			(end -0.12065 0.3048)
			(stroke
				(width 0.1)
				(type default)
			)
			(layer "F.Fab")
		)
		(fp_line
			(start -0.12065 -0.2794)
			(end 0.12065 -0.2794)
			(stroke
				(width 0.1)
				(type default)
			)
			(layer "F.Fab")
		)
		(fp_line
			(start -0.12065 -0.305054)
			(end -0.12065 -0.2794)
			(stroke
				(width 0.1)
				(type default)
			)
			(layer "F.Fab")
		)
		(fp_line
			(start -0.67945 0.3048)
			(end -0.67945 -0.305054)
			(stroke
				(width 0.1)
				(type default)
			)
			(layer "F.Fab")
		)
		(fp_line
			(start -0.67945 -0.305054)
			(end -0.12065 -0.305054)
			(stroke
				(width 0.1)
				(type default)
			)
			(layer "F.Fab")
		)
		(pad "1" smd circle
			(at -0.40005 0 180)
			(size 0 0)
			(layers "F.Cu" "F.Mask" "F.Paste")
			(net "P3V3_AUX")
		)
		(pad "2" smd circle
			(at 0.40005 0 180)
			(size 0 0)
			(layers "F.Cu" "F.Mask" "F.Paste")
			(net "GND")
		)
	)
	(footprint ""
		(layer "F.Cu")
		(at 54.242716 -108.89869 180)
		(property "Reference" "R3717"
			(at 0 0 180)
			(layer "F.SilkS")
			(hide yes)
			(effects
				(font
					(size 1.27 1.27)
				)
			)
		)
		(property "Value" ""
			(at 0 0 180)
			(layer "F.Fab")
			(effects
				(font
					(size 1.27 1.27)
				)
			)
		)
		(duplicate_pad_numbers_are_jumpers no)
		(fp_line
			(start 0.7874 0.4064)
			(end -0.7874 0.4064)
			(stroke
				(width 0.1524)
				(type default)
			)
			(layer "F.SilkS")
		)
		(fp_line
			(start 0.7874 -0.4064)
			(end 0.7874 0.4064)
			(stroke
				(width 0.1524)
				(type default)
			)
			(layer "F.SilkS")
		)
		(fp_line
			(start -0.7874 0.4064)
			(end -0.7874 -0.4064)
			(stroke
				(width 0.1524)
				(type default)
			)
			(layer "F.SilkS")
		)
		(fp_line
			(start -0.7874 -0.4064)
			(end 0.7874 -0.4064)
			(stroke
				(width 0.1524)
				(type default)
			)
			(layer "F.SilkS")
		)
		(fp_line
			(start 0.67945 0.3048)
			(end 0.120396 0.3048)
			(stroke
				(width 0.1)
				(type default)
			)
			(layer "F.Fab")
		)
		(fp_line
			(start 0.67945 -0.3048)
			(end 0.67945 0.3048)
			(stroke
				(width 0.1)
				(type default)
			)
			(layer "F.Fab")
		)
		(fp_line
			(start 0.12065 -0.2794)
			(end 0.12065 -0.3048)
			(stroke
				(width 0.1)
				(type default)
			)
			(layer "F.Fab")
		)
		(fp_line
			(start 0.12065 -0.3048)
			(end 0.67945 -0.3048)
			(stroke
				(width 0.1)
				(type default)
			)
			(layer "F.Fab")
		)
		(fp_line
			(start 0.120396 0.3048)
			(end 0.120396 0.2794)
			(stroke
				(width 0.1)
				(type default)
			)
			(layer "F.Fab")
		)
		(fp_line
			(start 0.120396 0.2794)
			(end -0.12065 0.2794)
			(stroke
				(width 0.1)
				(type default)
			)
			(layer "F.Fab")
		)
		(fp_line
			(start -0.12065 0.3048)
			(end -0.67945 0.3048)
			(stroke
				(width 0.1)
				(type default)
			)
			(layer "F.Fab")
		)
		(fp_line
			(start -0.12065 0.2794)
			(end -0.12065 0.3048)
			(stroke
				(width 0.1)
				(type default)
			)
			(layer "F.Fab")
		)
		(fp_line
			(start -0.12065 -0.2794)
			(end 0.12065 -0.2794)
			(stroke
				(width 0.1)
				(type default)
			)
			(layer "F.Fab")
		)
		(fp_line
			(start -0.12065 -0.305054)
			(end -0.12065 -0.2794)
			(stroke
				(width 0.1)
				(type default)
			)
			(layer "F.Fab")
		)
		(fp_line
			(start -0.67945 0.3048)
			(end -0.67945 -0.305054)
			(stroke
				(width 0.1)
				(type default)
			)
			(layer "F.Fab")
		)
		(fp_line
			(start -0.67945 -0.305054)
			(end -0.12065 -0.305054)
			(stroke
				(width 0.1)
				(type default)
			)
			(layer "F.Fab")
		)
		(pad "1" smd circle
			(at -0.40005 0 180)
			(size 0 0)
			(layers "F.Cu" "F.Mask" "F.Paste")
			(net "SMB_LM75_1_3V3AUX_SCL_R")
		)
		(pad "2" smd circle
			(at 0.40005 0 180)
			(size 0 0)
			(layers "F.Cu" "F.Mask" "F.Paste")
			(net "SMB_LM75_1_3V3AUX_SCL")
		)
	)
	(footprint ""
		(layer "F.Cu")
		(at 294.82288 -46.954948 -90)
		(property "Reference" "R4073"
			(at 0 0 270)
			(layer "F.SilkS")
			(hide yes)
			(effects
				(font
					(size 1.27 1.27)
				)
			)
		)
		(property "Value" ""
			(at 0 0 270)
			(layer "F.Fab")
			(effects
				(font
					(size 1.27 1.27)
				)
			)
		)
		(duplicate_pad_numbers_are_jumpers no)
		(fp_line
			(start -0.7874 0.4064)
			(end -0.7874 -0.4064)
			(stroke
				(width 0.1524)
				(type default)
			)
			(layer "F.SilkS")
		)
		(fp_line
			(start 0.7874 0.4064)
			(end -0.7874 0.4064)
			(stroke
				(width 0.1524)
				(type default)
			)
			(layer "F.SilkS")
		)
		(fp_line
			(start -0.7874 -0.4064)
			(end 0.7874 -0.4064)
			(stroke
				(width 0.1524)
				(type default)
			)
			(layer "F.SilkS")
		)
		(fp_line
			(start 0.7874 -0.4064)
			(end 0.7874 0.4064)
			(stroke
				(width 0.1524)
				(type default)
			)
			(layer "F.SilkS")
		)
		(fp_line
			(start -0.67945 0.3048)
			(end -0.67945 -0.305054)
			(stroke
				(width 0.1)
				(type default)
			)
			(layer "F.Fab")
		)
		(fp_line
			(start -0.12065 0.3048)
			(end -0.67945 0.3048)
			(stroke
				(width 0.1)
				(type default)
			)
			(layer "F.Fab")
		)
		(fp_line
			(start 0.120396 0.3048)
			(end 0.120396 0.2794)
			(stroke
				(width 0.1)
				(type default)
			)
			(layer "F.Fab")
		)
		(fp_line
			(start 0.67945 0.3048)
			(end 0.120396 0.3048)
			(stroke
				(width 0.1)
				(type default)
			)
			(layer "F.Fab")
		)
		(fp_line
			(start -0.12065 0.2794)
			(end -0.12065 0.3048)
			(stroke
				(width 0.1)
				(type default)
			)
			(layer "F.Fab")
		)
		(fp_line
			(start 0.120396 0.2794)
			(end -0.12065 0.2794)
			(stroke
				(width 0.1)
				(type default)
			)
			(layer "F.Fab")
		)
		(fp_line
			(start -0.12065 -0.2794)
			(end 0.12065 -0.2794)
			(stroke
				(width 0.1)
				(type default)
			)
			(layer "F.Fab")
		)
		(fp_line
			(start 0.12065 -0.2794)
			(end 0.12065 -0.3048)
			(stroke
				(width 0.1)
				(type default)
			)
			(layer "F.Fab")
		)
		(fp_line
			(start 0.12065 -0.3048)
			(end 0.67945 -0.3048)
			(stroke
				(width 0.1)
				(type default)
			)
			(layer "F.Fab")
		)
		(fp_line
			(start 0.67945 -0.3048)
			(end 0.67945 0.3048)
			(stroke
				(width 0.1)
				(type default)
			)
			(layer "F.Fab")
		)
		(fp_line
			(start -0.67945 -0.305054)
			(end -0.12065 -0.305054)
			(stroke
				(width 0.1)
				(type default)
			)
			(layer "F.Fab")
		)
		(fp_line
			(start -0.12065 -0.305054)
			(end -0.12065 -0.2794)
			(stroke
				(width 0.1)
				(type default)
			)
			(layer "F.Fab")
		)
		(pad "1" smd circle
			(at -0.40005 0 270)
			(size 0 0)
			(layers "F.Cu" "F.Mask" "F.Paste")
			(net "P12V_E1S_EN_0_R")
		)
		(pad "2" smd circle
			(at 0.40005 0 270)
			(size 0 0)
			(layers "F.Cu" "F.Mask" "F.Paste")
			(net "GND")
		)
	)
	(footprint ""
		(layer "F.Cu")
		(at 136.3853 -114.38382)
		(property "Reference" "R4754"
			(at 0 0 0)
			(layer "F.SilkS")
			(hide yes)
			(effects
				(font
					(size 1.27 1.27)
				)
			)
		)
		(property "Value" ""
			(at 0 0 0)
			(layer "F.Fab")
			(effects
				(font
					(size 1.27 1.27)
				)
			)
		)
		(duplicate_pad_numbers_are_jumpers no)
		(fp_line
			(start -0.7874 -0.4064)
			(end 0.7874 -0.4064)
			(stroke
				(width 0.1524)
				(type default)
			)
			(layer "F.SilkS")
		)
		(fp_line
			(start -0.7874 0.4064)
			(end -0.7874 -0.4064)
			(stroke
				(width 0.1524)
				(type default)
			)
			(layer "F.SilkS")
		)
		(fp_line
			(start 0.7874 -0.4064)
			(end 0.7874 0.4064)
			(stroke
				(width 0.1524)
				(type default)
			)
			(layer "F.SilkS")
		)
		(fp_line
			(start 0.7874 0.4064)
			(end -0.7874 0.4064)
			(stroke
				(width 0.1524)
				(type default)
			)
			(layer "F.SilkS")
		)
		(fp_line
			(start -0.67945 -0.305054)
			(end -0.12065 -0.305054)
			(stroke
				(width 0.1)
				(type default)
			)
			(layer "F.Fab")
		)
		(fp_line
			(start -0.67945 0.3048)
			(end -0.67945 -0.305054)
			(stroke
				(width 0.1)
				(type default)
			)
			(layer "F.Fab")
		)
		(fp_line
			(start -0.12065 -0.305054)
			(end -0.12065 -0.2794)
			(stroke
				(width 0.1)
				(type default)
			)
			(layer "F.Fab")
		)
		(fp_line
			(start -0.12065 -0.2794)
			(end 0.12065 -0.2794)
			(stroke
				(width 0.1)
				(type default)
			)
			(layer "F.Fab")
		)
		(fp_line
			(start -0.12065 0.2794)
			(end -0.12065 0.3048)
			(stroke
				(width 0.1)
				(type default)
			)
			(layer "F.Fab")
		)
		(fp_line
			(start -0.12065 0.3048)
			(end -0.67945 0.3048)
			(stroke
				(width 0.1)
				(type default)
			)
			(layer "F.Fab")
		)
		(fp_line
			(start 0.120396 0.2794)
			(end -0.12065 0.2794)
			(stroke
				(width 0.1)
				(type default)
			)
			(layer "F.Fab")
		)
		(fp_line
			(start 0.120396 0.3048)
			(end 0.120396 0.2794)
			(stroke
				(width 0.1)
				(type default)
			)
			(layer "F.Fab")
		)
		(fp_line
			(start 0.12065 -0.3048)
			(end 0.67945 -0.3048)
			(stroke
				(width 0.1)
				(type default)
			)
			(layer "F.Fab")
		)
		(fp_line
			(start 0.12065 -0.2794)
			(end 0.12065 -0.3048)
			(stroke
				(width 0.1)
				(type default)
			)
			(layer "F.Fab")
		)
		(fp_line
			(start 0.67945 -0.3048)
			(end 0.67945 0.3048)
			(stroke
				(width 0.1)
				(type default)
			)
			(layer "F.Fab")
		)
		(fp_line
			(start 0.67945 0.3048)
			(end 0.120396 0.3048)
			(stroke
				(width 0.1)
				(type default)
			)
			(layer "F.Fab")
		)
		(pad "1" smd circle
			(at -0.40005 0)
			(size 0 0)
			(layers "F.Cu" "F.Mask" "F.Paste")
			(net "HP_LVC3_OCP_V3_2_PWRGD_R")
		)
		(pad "2" smd circle
			(at 0.40005 0)
			(size 0 0)
			(layers "F.Cu" "F.Mask" "F.Paste")
			(net "HP_LVC3_OCP_V3_2_PWRGD_R2")
		)
	)
	(footprint ""
		(layer "F.Cu")
		(at 80.46847 -38.693852 180)
		(property "Reference" "U216"
			(at 1.35636 -2.19202 0)
			(unlocked yes)
			(layer "F.SilkS")
			(effects
				(font
					(size 0.7874 0.5842)
					(thickness 0.1524)
				)
				(justify left)
			)
		)
		(property "Value" ""
			(at 0 0 180)
			(layer "F.Fab")
			(effects
				(font
					(size 1.27 1.27)
				)
			)
		)
		(duplicate_pad_numbers_are_jumpers no)
		(fp_line
			(start 1.759712 1.500124)
			(end -1.759712 1.500124)
			(stroke
				(width 0.1524)
				(type default)
			)
			(layer "F.SilkS")
		)
		(fp_line
			(start 1.759712 -1.500124)
			(end 1.759712 1.500124)
			(stroke
				(width 0.1524)
				(type default)
			)
			(layer "F.SilkS")
		)
		(fp_line
			(start -1.759712 1.500124)
			(end -1.759712 -1.500124)
			(stroke
				(width 0.1524)
				(type default)
			)
			(layer "F.SilkS")
		)
		(fp_line
			(start -1.759712 -1.500124)
			(end 1.759712 -1.500124)
			(stroke
				(width 0.1524)
				(type default)
			)
			(layer "F.SilkS")
		)
		(fp_line
			(start 0.700024 1.500124)
			(end -0.700024 1.500124)
			(stroke
				(width 0.1)
				(type default)
			)
			(layer "F.Fab")
		)
		(fp_line
			(start 0.700024 -1.500124)
			(end 0.700024 1.500124)
			(stroke
				(width 0.1)
				(type default)
			)
			(layer "F.Fab")
		)
		(fp_line
			(start -0.700024 1.500124)
			(end -0.700024 -1.500124)
			(stroke
				(width 0.1)
				(type default)
			)
			(layer "F.Fab")
		)
		(fp_line
			(start -0.700024 -1.500124)
			(end 0.700024 -1.500124)
			(stroke
				(width 0.1)
				(type default)
			)
			(layer "F.Fab")
		)
		(pad "1" smd rect
			(at -1.150112 -0.94996 90)
			(size 0.6604 0.9652)
			(layers "F.Cu" "F.Mask" "F.Paste")
			(net "GND")
		)
		(pad "2" smd rect
			(at -1.150112 0.94996 90)
			(size 0.6604 0.9652)
			(layers "F.Cu" "F.Mask" "F.Paste")
			(net "HP_OCP_V3_2_RST")
		)
		(pad "3" smd rect
			(at 1.150112 0 90)
			(size 0.6604 0.9652)
			(layers "F.Cu" "F.Mask" "F.Paste")
			(net "P3V3_OCP_V3_2")
		)
	)
	(footprint ""
		(layer "F.Cu")
		(at 333.155544 -18.797524 -90)
		(property "Reference" "C606"
			(at 0 0 270)
			(layer "F.SilkS")
			(hide yes)
			(effects
				(font
					(size 1.27 1.27)
				)
			)
		)
		(property "Value" ""
			(at 0 0 270)
			(layer "F.Fab")
			(effects
				(font
					(size 1.27 1.27)
				)
			)
		)
		(duplicate_pad_numbers_are_jumpers no)
		(fp_line
			(start -0.7874 0.4064)
			(end -0.7874 -0.4064)
			(stroke
				(width 0.1524)
				(type default)
			)
			(layer "F.SilkS")
		)
		(fp_line
			(start 0.7874 0.4064)
			(end -0.7874 0.4064)
			(stroke
				(width 0.1524)
				(type default)
			)
			(layer "F.SilkS")
		)
		(fp_line
			(start -0.7874 -0.4064)
			(end 0.7874 -0.4064)
			(stroke
				(width 0.1524)
				(type default)
			)
			(layer "F.SilkS")
		)
		(fp_line
			(start 0.7874 -0.4064)
			(end 0.7874 0.4064)
			(stroke
				(width 0.1524)
				(type default)
			)
			(layer "F.SilkS")
		)
		(fp_line
			(start -0.67945 0.3048)
			(end -0.67945 -0.305054)
			(stroke
				(width 0.1)
				(type default)
			)
			(layer "F.Fab")
		)
		(fp_line
			(start -0.12065 0.3048)
			(end -0.67945 0.3048)
			(stroke
				(width 0.1)
				(type default)
			)
			(layer "F.Fab")
		)
		(fp_line
			(start 0.120396 0.3048)
			(end 0.120396 0.2794)
			(stroke
				(width 0.1)
				(type default)
			)
			(layer "F.Fab")
		)
		(fp_line
			(start 0.67945 0.3048)
			(end 0.120396 0.3048)
			(stroke
				(width 0.1)
				(type default)
			)
			(layer "F.Fab")
		)
		(fp_line
			(start -0.12065 0.2794)
			(end -0.12065 0.3048)
			(stroke
				(width 0.1)
				(type default)
			)
			(layer "F.Fab")
		)
		(fp_line
			(start 0.120396 0.2794)
			(end -0.12065 0.2794)
			(stroke
				(width 0.1)
				(type default)
			)
			(layer "F.Fab")
		)
		(fp_line
			(start -0.12065 -0.2794)
			(end 0.12065 -0.2794)
			(stroke
				(width 0.1)
				(type default)
			)
			(layer "F.Fab")
		)
		(fp_line
			(start 0.12065 -0.2794)
			(end 0.12065 -0.3048)
			(stroke
				(width 0.1)
				(type default)
			)
			(layer "F.Fab")
		)
		(fp_line
			(start 0.12065 -0.3048)
			(end 0.67945 -0.3048)
			(stroke
				(width 0.1)
				(type default)
			)
			(layer "F.Fab")
		)
		(fp_line
			(start 0.67945 -0.3048)
			(end 0.67945 0.3048)
			(stroke
				(width 0.1)
				(type default)
			)
			(layer "F.Fab")
		)
		(fp_line
			(start -0.67945 -0.305054)
			(end -0.12065 -0.305054)
			(stroke
				(width 0.1)
				(type default)
			)
			(layer "F.Fab")
		)
		(fp_line
			(start -0.12065 -0.305054)
			(end -0.12065 -0.2794)
			(stroke
				(width 0.1)
				(type default)
			)
			(layer "F.Fab")
		)
		(pad "1" smd circle
			(at -0.40005 0 270)
			(size 0 0)
			(layers "F.Cu" "F.Mask" "F.Paste")
			(net "PGPPA_AUX")
		)
		(pad "2" smd circle
			(at 0.40005 0 270)
			(size 0 0)
			(layers "F.Cu" "F.Mask" "F.Paste")
			(net "GND")
		)
	)
	(footprint ""
		(layer "F.Cu")
		(at 124.66574 -79.649828)
		(property "Reference" "R4630"
			(at 0 0 0)
			(layer "F.SilkS")
			(hide yes)
			(effects
				(font
					(size 1.27 1.27)
				)
			)
		)
		(property "Value" ""
			(at 0 0 0)
			(layer "F.Fab")
			(effects
				(font
					(size 1.27 1.27)
				)
			)
		)
		(duplicate_pad_numbers_are_jumpers no)
		(fp_line
			(start -0.7874 -0.4064)
			(end 0.7874 -0.4064)
			(stroke
				(width 0.1524)
				(type default)
			)
			(layer "F.SilkS")
		)
		(fp_line
			(start -0.7874 0.4064)
			(end -0.7874 -0.4064)
			(stroke
				(width 0.1524)
				(type default)
			)
			(layer "F.SilkS")
		)
		(fp_line
			(start 0.7874 -0.4064)
			(end 0.7874 0.4064)
			(stroke
				(width 0.1524)
				(type default)
			)
			(layer "F.SilkS")
		)
		(fp_line
			(start 0.7874 0.4064)
			(end -0.7874 0.4064)
			(stroke
				(width 0.1524)
				(type default)
			)
			(layer "F.SilkS")
		)
		(fp_line
			(start -0.67945 -0.305054)
			(end -0.12065 -0.305054)
			(stroke
				(width 0.1)
				(type default)
			)
			(layer "F.Fab")
		)
		(fp_line
			(start -0.67945 0.3048)
			(end -0.67945 -0.305054)
			(stroke
				(width 0.1)
				(type default)
			)
			(layer "F.Fab")
		)
		(fp_line
			(start -0.12065 -0.305054)
			(end -0.12065 -0.2794)
			(stroke
				(width 0.1)
				(type default)
			)
			(layer "F.Fab")
		)
		(fp_line
			(start -0.12065 -0.2794)
			(end 0.12065 -0.2794)
			(stroke
				(width 0.1)
				(type default)
			)
			(layer "F.Fab")
		)
		(fp_line
			(start -0.12065 0.2794)
			(end -0.12065 0.3048)
			(stroke
				(width 0.1)
				(type default)
			)
			(layer "F.Fab")
		)
		(fp_line
			(start -0.12065 0.3048)
			(end -0.67945 0.3048)
			(stroke
				(width 0.1)
				(type default)
			)
			(layer "F.Fab")
		)
		(fp_line
			(start 0.120396 0.2794)
			(end -0.12065 0.2794)
			(stroke
				(width 0.1)
				(type default)
			)
			(layer "F.Fab")
		)
		(fp_line
			(start 0.120396 0.3048)
			(end 0.120396 0.2794)
			(stroke
				(width 0.1)
				(type default)
			)
			(layer "F.Fab")
		)
		(fp_line
			(start 0.12065 -0.3048)
			(end 0.67945 -0.3048)
			(stroke
				(width 0.1)
				(type default)
			)
			(layer "F.Fab")
		)
		(fp_line
			(start 0.12065 -0.2794)
			(end 0.12065 -0.3048)
			(stroke
				(width 0.1)
				(type default)
			)
			(layer "F.Fab")
		)
		(fp_line
			(start 0.67945 -0.3048)
			(end 0.67945 0.3048)
			(stroke
				(width 0.1)
				(type default)
			)
			(layer "F.Fab")
		)
		(fp_line
			(start 0.67945 0.3048)
			(end 0.120396 0.3048)
			(stroke
				(width 0.1)
				(type default)
			)
			(layer "F.Fab")
		)
		(pad "1" smd circle
			(at -0.40005 0)
			(size 0 0)
			(layers "F.Cu" "F.Mask" "F.Paste")
			(net "JTAG_BMC_SW_TDO_R")
		)
		(pad "2" smd circle
			(at 0.40005 0)
			(size 0 0)
			(layers "F.Cu" "F.Mask" "F.Paste")
			(net "JTAG_BMC_SW_TDO")
		)
	)
	(footprint ""
		(layer "F.Cu")
		(at 201.02068 -101.145848 180)
		(property "Reference" "R220"
			(at 0 0 180)
			(layer "F.SilkS")
			(hide yes)
			(effects
				(font
					(size 1.27 1.27)
				)
			)
		)
		(property "Value" ""
			(at 0 0 180)
			(layer "F.Fab")
			(effects
				(font
					(size 1.27 1.27)
				)
			)
		)
		(duplicate_pad_numbers_are_jumpers no)
		(fp_line
			(start 0.7874 0.4064)
			(end -0.7874 0.4064)
			(stroke
				(width 0.1524)
				(type default)
			)
			(layer "F.SilkS")
		)
		(fp_line
			(start 0.7874 -0.4064)
			(end 0.7874 0.4064)
			(stroke
				(width 0.1524)
				(type default)
			)
			(layer "F.SilkS")
		)
		(fp_line
			(start -0.7874 0.4064)
			(end -0.7874 -0.4064)
			(stroke
				(width 0.1524)
				(type default)
			)
			(layer "F.SilkS")
		)
		(fp_line
			(start -0.7874 -0.4064)
			(end 0.7874 -0.4064)
			(stroke
				(width 0.1524)
				(type default)
			)
			(layer "F.SilkS")
		)
		(fp_line
			(start 0.67945 0.3048)
			(end 0.120396 0.3048)
			(stroke
				(width 0.1)
				(type default)
			)
			(layer "F.Fab")
		)
		(fp_line
			(start 0.67945 -0.3048)
			(end 0.67945 0.3048)
			(stroke
				(width 0.1)
				(type default)
			)
			(layer "F.Fab")
		)
		(fp_line
			(start 0.12065 -0.2794)
			(end 0.12065 -0.3048)
			(stroke
				(width 0.1)
				(type default)
			)
			(layer "F.Fab")
		)
		(fp_line
			(start 0.12065 -0.3048)
			(end 0.67945 -0.3048)
			(stroke
				(width 0.1)
				(type default)
			)
			(layer "F.Fab")
		)
		(fp_line
			(start 0.120396 0.3048)
			(end 0.120396 0.2794)
			(stroke
				(width 0.1)
				(type default)
			)
			(layer "F.Fab")
		)
		(fp_line
			(start 0.120396 0.2794)
			(end -0.12065 0.2794)
			(stroke
				(width 0.1)
				(type default)
			)
			(layer "F.Fab")
		)
		(fp_line
			(start -0.12065 0.3048)
			(end -0.67945 0.3048)
			(stroke
				(width 0.1)
				(type default)
			)
			(layer "F.Fab")
		)
		(fp_line
			(start -0.12065 0.2794)
			(end -0.12065 0.3048)
			(stroke
				(width 0.1)
				(type default)
			)
			(layer "F.Fab")
		)
		(fp_line
			(start -0.12065 -0.2794)
			(end 0.12065 -0.2794)
			(stroke
				(width 0.1)
				(type default)
			)
			(layer "F.Fab")
		)
		(fp_line
			(start -0.12065 -0.305054)
			(end -0.12065 -0.2794)
			(stroke
				(width 0.1)
				(type default)
			)
			(layer "F.Fab")
		)
		(fp_line
			(start -0.67945 0.3048)
			(end -0.67945 -0.305054)
			(stroke
				(width 0.1)
				(type default)
			)
			(layer "F.Fab")
		)
		(fp_line
			(start -0.67945 -0.305054)
			(end -0.12065 -0.305054)
			(stroke
				(width 0.1)
				(type default)
			)
			(layer "F.Fab")
		)
		(pad "1" smd circle
			(at -0.40005 0 180)
			(size 0 0)
			(layers "F.Cu" "F.Mask" "F.Paste")
			(net "PVNN_TERM_CPU1")
		)
		(pad "2" smd circle
			(at 0.40005 0 180)
			(size 0 0)
			(layers "F.Cu" "F.Mask" "F.Paste")
			(net "H_CPU1_MEMHOT_IN_LVC1_R1_N")
		)
	)
	(footprint ""
		(layer "F.Cu")
		(at 258.10845 -70.40626 -90)
		(property "Reference" "PC1218"
			(at 0 0 270)
			(layer "F.SilkS")
			(hide yes)
			(effects
				(font
					(size 1.27 1.27)
				)
			)
		)
		(property "Value" ""
			(at 0 0 270)
			(layer "F.Fab")
			(effects
				(font
					(size 1.27 1.27)
				)
			)
		)
		(duplicate_pad_numbers_are_jumpers no)
		(fp_line
			(start -1.524 0.762)
			(end -1.524 -0.762)
			(stroke
				(width 0.1524)
				(type default)
			)
			(layer "F.SilkS")
		)
		(fp_line
			(start 1.524 0.762)
			(end -1.524 0.762)
			(stroke
				(width 0.1524)
				(type default)
			)
			(layer "F.SilkS")
		)
		(fp_line
			(start -1.524 -0.762)
			(end 1.524 -0.762)
			(stroke
				(width 0.1524)
				(type default)
			)
			(layer "F.SilkS")
		)
		(fp_line
			(start 1.524 -0.762)
			(end 1.524 0.762)
			(stroke
				(width 0.1524)
				(type default)
			)
			(layer "F.SilkS")
		)
		(fp_line
			(start -1.1049 0.724916)
			(end 1.1049 0.724916)
			(stroke
				(width 0.1)
				(type default)
			)
			(layer "F.Fab")
		)
		(fp_line
			(start 1.1049 0.724916)
			(end 1.1049 -0.724916)
			(stroke
				(width 0.1)
				(type default)
			)
			(layer "F.Fab")
		)
		(fp_line
			(start -1.1049 -0.724916)
			(end -1.1049 0.724916)
			(stroke
				(width 0.1)
				(type default)
			)
			(layer "F.Fab")
		)
		(fp_line
			(start 1.1049 -0.724916)
			(end -1.1049 -0.724916)
			(stroke
				(width 0.1)
				(type default)
			)
			(layer "F.Fab")
		)
		(pad "1" smd rect
			(at -0.889 0 90)
			(size 1.016 1.27)
			(layers "F.Cu" "F.Mask" "F.Paste")
			(net "SW_P12V_AUX_P1V05_PCH_AUX_FLT")
		)
		(pad "2" smd rect
			(at 0.889 0 90)
			(size 1.016 1.27)
			(layers "F.Cu" "F.Mask" "F.Paste")
			(net "GND")
		)
	)
	(footprint ""
		(layer "F.Cu")
		(at 456.621388 -381.264922 -90)
		(property "Reference" "PR89"
			(at 0 0 270)
			(layer "F.SilkS")
			(hide yes)
			(effects
				(font
					(size 1.27 1.27)
				)
			)
		)
		(property "Value" ""
			(at 0 0 270)
			(layer "F.Fab")
			(effects
				(font
					(size 1.27 1.27)
				)
			)
		)
		(duplicate_pad_numbers_are_jumpers no)
		(fp_line
			(start -0.7874 0.4064)
			(end -0.7874 -0.4064)
			(stroke
				(width 0.1524)
				(type default)
			)
			(layer "F.SilkS")
		)
		(fp_line
			(start 0.7874 0.4064)
			(end -0.7874 0.4064)
			(stroke
				(width 0.1524)
				(type default)
			)
			(layer "F.SilkS")
		)
		(fp_line
			(start -0.7874 -0.4064)
			(end 0.7874 -0.4064)
			(stroke
				(width 0.1524)
				(type default)
			)
			(layer "F.SilkS")
		)
		(fp_line
			(start 0.7874 -0.4064)
			(end 0.7874 0.4064)
			(stroke
				(width 0.1524)
				(type default)
			)
			(layer "F.SilkS")
		)
		(fp_line
			(start -0.67945 0.3048)
			(end -0.67945 -0.305054)
			(stroke
				(width 0.1)
				(type default)
			)
			(layer "F.Fab")
		)
		(fp_line
			(start -0.12065 0.3048)
			(end -0.67945 0.3048)
			(stroke
				(width 0.1)
				(type default)
			)
			(layer "F.Fab")
		)
		(fp_line
			(start 0.120396 0.3048)
			(end 0.120396 0.2794)
			(stroke
				(width 0.1)
				(type default)
			)
			(layer "F.Fab")
		)
		(fp_line
			(start 0.67945 0.3048)
			(end 0.120396 0.3048)
			(stroke
				(width 0.1)
				(type default)
			)
			(layer "F.Fab")
		)
		(fp_line
			(start -0.12065 0.2794)
			(end -0.12065 0.3048)
			(stroke
				(width 0.1)
				(type default)
			)
			(layer "F.Fab")
		)
		(fp_line
			(start 0.120396 0.2794)
			(end -0.12065 0.2794)
			(stroke
				(width 0.1)
				(type default)
			)
			(layer "F.Fab")
		)
		(fp_line
			(start -0.12065 -0.2794)
			(end 0.12065 -0.2794)
			(stroke
				(width 0.1)
				(type default)
			)
			(layer "F.Fab")
		)
		(fp_line
			(start 0.12065 -0.2794)
			(end 0.12065 -0.3048)
			(stroke
				(width 0.1)
				(type default)
			)
			(layer "F.Fab")
		)
		(fp_line
			(start 0.12065 -0.3048)
			(end 0.67945 -0.3048)
			(stroke
				(width 0.1)
				(type default)
			)
			(layer "F.Fab")
		)
		(fp_line
			(start 0.67945 -0.3048)
			(end 0.67945 0.3048)
			(stroke
				(width 0.1)
				(type default)
			)
			(layer "F.Fab")
		)
		(fp_line
			(start -0.67945 -0.305054)
			(end -0.12065 -0.305054)
			(stroke
				(width 0.1)
				(type default)
			)
			(layer "F.Fab")
		)
		(fp_line
			(start -0.12065 -0.305054)
			(end -0.12065 -0.2794)
			(stroke
				(width 0.1)
				(type default)
			)
			(layer "F.Fab")
		)
		(pad "1" smd circle
			(at -0.40005 0 270)
			(size 0 0)
			(layers "F.Cu" "F.Mask" "F.Paste")
			(net "P5V_AUX_CS")
		)
		(pad "2" smd circle
			(at 0.40005 0 270)
			(size 0 0)
			(layers "F.Cu" "F.Mask" "F.Paste")
			(net "GND")
		)
	)
	(footprint ""
		(layer "F.Cu")
		(at 105.21188 -425.795948 180)
		(property "Reference" "R4213"
			(at 0 0 180)
			(layer "F.SilkS")
			(hide yes)
			(effects
				(font
					(size 1.27 1.27)
				)
			)
		)
		(property "Value" ""
			(at 0 0 180)
			(layer "F.Fab")
			(effects
				(font
					(size 1.27 1.27)
				)
			)
		)
		(duplicate_pad_numbers_are_jumpers no)
		(fp_line
			(start 0.7874 0.4064)
			(end -0.7874 0.4064)
			(stroke
				(width 0.1524)
				(type default)
			)
			(layer "F.SilkS")
		)
		(fp_line
			(start 0.7874 -0.4064)
			(end 0.7874 0.4064)
			(stroke
				(width 0.1524)
				(type default)
			)
			(layer "F.SilkS")
		)
		(fp_line
			(start -0.7874 0.4064)
			(end -0.7874 -0.4064)
			(stroke
				(width 0.1524)
				(type default)
			)
			(layer "F.SilkS")
		)
		(fp_line
			(start -0.7874 -0.4064)
			(end 0.7874 -0.4064)
			(stroke
				(width 0.1524)
				(type default)
			)
			(layer "F.SilkS")
		)
		(fp_line
			(start 0.67945 0.3048)
			(end 0.120396 0.3048)
			(stroke
				(width 0.1)
				(type default)
			)
			(layer "F.Fab")
		)
		(fp_line
			(start 0.67945 -0.3048)
			(end 0.67945 0.3048)
			(stroke
				(width 0.1)
				(type default)
			)
			(layer "F.Fab")
		)
		(fp_line
			(start 0.12065 -0.2794)
			(end 0.12065 -0.3048)
			(stroke
				(width 0.1)
				(type default)
			)
			(layer "F.Fab")
		)
		(fp_line
			(start 0.12065 -0.3048)
			(end 0.67945 -0.3048)
			(stroke
				(width 0.1)
				(type default)
			)
			(layer "F.Fab")
		)
		(fp_line
			(start 0.120396 0.3048)
			(end 0.120396 0.2794)
			(stroke
				(width 0.1)
				(type default)
			)
			(layer "F.Fab")
		)
		(fp_line
			(start 0.120396 0.2794)
			(end -0.12065 0.2794)
			(stroke
				(width 0.1)
				(type default)
			)
			(layer "F.Fab")
		)
		(fp_line
			(start -0.12065 0.3048)
			(end -0.67945 0.3048)
			(stroke
				(width 0.1)
				(type default)
			)
			(layer "F.Fab")
		)
		(fp_line
			(start -0.12065 0.2794)
			(end -0.12065 0.3048)
			(stroke
				(width 0.1)
				(type default)
			)
			(layer "F.Fab")
		)
		(fp_line
			(start -0.12065 -0.2794)
			(end 0.12065 -0.2794)
			(stroke
				(width 0.1)
				(type default)
			)
			(layer "F.Fab")
		)
		(fp_line
			(start -0.12065 -0.305054)
			(end -0.12065 -0.2794)
			(stroke
				(width 0.1)
				(type default)
			)
			(layer "F.Fab")
		)
		(fp_line
			(start -0.67945 0.3048)
			(end -0.67945 -0.305054)
			(stroke
				(width 0.1)
				(type default)
			)
			(layer "F.Fab")
		)
		(fp_line
			(start -0.67945 -0.305054)
			(end -0.12065 -0.305054)
			(stroke
				(width 0.1)
				(type default)
			)
			(layer "F.Fab")
		)
		(pad "1" smd circle
			(at -0.40005 0 180)
			(size 0 0)
			(layers "F.Cu" "F.Mask" "F.Paste")
			(net "FM_THERMAL_ALERT_N")
		)
		(pad "2" smd circle
			(at 0.40005 0 180)
			(size 0 0)
			(layers "F.Cu" "F.Mask" "F.Paste")
			(net "FM_LM75_2_ALERT_N")
		)
	)
	(footprint ""
		(layer "F.Cu")
		(at 201.00036 -115.534948 180)
		(property "Reference" "R4144"
			(at 0 0 180)
			(layer "F.SilkS")
			(hide yes)
			(effects
				(font
					(size 1.27 1.27)
				)
			)
		)
		(property "Value" ""
			(at 0 0 180)
			(layer "F.Fab")
			(effects
				(font
					(size 1.27 1.27)
				)
			)
		)
		(duplicate_pad_numbers_are_jumpers no)
		(fp_line
			(start 0.7874 0.4064)
			(end -0.7874 0.4064)
			(stroke
				(width 0.1524)
				(type default)
			)
			(layer "F.SilkS")
		)
		(fp_line
			(start 0.7874 -0.4064)
			(end 0.7874 0.4064)
			(stroke
				(width 0.1524)
				(type default)
			)
			(layer "F.SilkS")
		)
		(fp_line
			(start -0.7874 0.4064)
			(end -0.7874 -0.4064)
			(stroke
				(width 0.1524)
				(type default)
			)
			(layer "F.SilkS")
		)
		(fp_line
			(start -0.7874 -0.4064)
			(end 0.7874 -0.4064)
			(stroke
				(width 0.1524)
				(type default)
			)
			(layer "F.SilkS")
		)
		(fp_line
			(start 0.67945 0.3048)
			(end 0.120396 0.3048)
			(stroke
				(width 0.1)
				(type default)
			)
			(layer "F.Fab")
		)
		(fp_line
			(start 0.67945 -0.3048)
			(end 0.67945 0.3048)
			(stroke
				(width 0.1)
				(type default)
			)
			(layer "F.Fab")
		)
		(fp_line
			(start 0.12065 -0.2794)
			(end 0.12065 -0.3048)
			(stroke
				(width 0.1)
				(type default)
			)
			(layer "F.Fab")
		)
		(fp_line
			(start 0.12065 -0.3048)
			(end 0.67945 -0.3048)
			(stroke
				(width 0.1)
				(type default)
			)
			(layer "F.Fab")
		)
		(fp_line
			(start 0.120396 0.3048)
			(end 0.120396 0.2794)
			(stroke
				(width 0.1)
				(type default)
			)
			(layer "F.Fab")
		)
		(fp_line
			(start 0.120396 0.2794)
			(end -0.12065 0.2794)
			(stroke
				(width 0.1)
				(type default)
			)
			(layer "F.Fab")
		)
		(fp_line
			(start -0.12065 0.3048)
			(end -0.67945 0.3048)
			(stroke
				(width 0.1)
				(type default)
			)
			(layer "F.Fab")
		)
		(fp_line
			(start -0.12065 0.2794)
			(end -0.12065 0.3048)
			(stroke
				(width 0.1)
				(type default)
			)
			(layer "F.Fab")
		)
		(fp_line
			(start -0.12065 -0.2794)
			(end 0.12065 -0.2794)
			(stroke
				(width 0.1)
				(type default)
			)
			(layer "F.Fab")
		)
		(fp_line
			(start -0.12065 -0.305054)
			(end -0.12065 -0.2794)
			(stroke
				(width 0.1)
				(type default)
			)
			(layer "F.Fab")
		)
		(fp_line
			(start -0.67945 0.3048)
			(end -0.67945 -0.305054)
			(stroke
				(width 0.1)
				(type default)
			)
			(layer "F.Fab")
		)
		(fp_line
			(start -0.67945 -0.305054)
			(end -0.12065 -0.305054)
			(stroke
				(width 0.1)
				(type default)
			)
			(layer "F.Fab")
		)
		(pad "1" smd circle
			(at -0.40005 0 180)
			(size 0 0)
			(layers "F.Cu" "F.Mask" "F.Paste")
			(net "GPU_3V3IO_RSVD1_FFU_ISO")
		)
		(pad "2" smd circle
			(at 0.40005 0 180)
			(size 0 0)
			(layers "F.Cu" "F.Mask" "F.Paste")
			(net "GPU_3V3IO_RSVD1_FFU_ISO_R")
		)
	)
	(footprint ""
		(layer "F.Cu")
		(at 191.29629 -30.269688 180)
		(property "Reference" "PR4526"
			(at 0 0 180)
			(layer "F.SilkS")
			(hide yes)
			(effects
				(font
					(size 1.27 1.27)
				)
			)
		)
		(property "Value" ""
			(at 0 0 180)
			(layer "F.Fab")
			(effects
				(font
					(size 1.27 1.27)
				)
			)
		)
		(duplicate_pad_numbers_are_jumpers no)
		(fp_line
			(start 0.7874 0.4064)
			(end -0.7874 0.4064)
			(stroke
				(width 0.1524)
				(type default)
			)
			(layer "F.SilkS")
		)
		(fp_line
			(start 0.7874 -0.4064)
			(end 0.7874 0.4064)
			(stroke
				(width 0.1524)
				(type default)
			)
			(layer "F.SilkS")
		)
		(fp_line
			(start -0.7874 0.4064)
			(end -0.7874 -0.4064)
			(stroke
				(width 0.1524)
				(type default)
			)
			(layer "F.SilkS")
		)
		(fp_line
			(start -0.7874 -0.4064)
			(end 0.7874 -0.4064)
			(stroke
				(width 0.1524)
				(type default)
			)
			(layer "F.SilkS")
		)
		(fp_line
			(start 0.67945 0.3048)
			(end 0.120396 0.3048)
			(stroke
				(width 0.1)
				(type default)
			)
			(layer "F.Fab")
		)
		(fp_line
			(start 0.67945 -0.3048)
			(end 0.67945 0.3048)
			(stroke
				(width 0.1)
				(type default)
			)
			(layer "F.Fab")
		)
		(fp_line
			(start 0.12065 -0.2794)
			(end 0.12065 -0.3048)
			(stroke
				(width 0.1)
				(type default)
			)
			(layer "F.Fab")
		)
		(fp_line
			(start 0.12065 -0.3048)
			(end 0.67945 -0.3048)
			(stroke
				(width 0.1)
				(type default)
			)
			(layer "F.Fab")
		)
		(fp_line
			(start 0.120396 0.3048)
			(end 0.120396 0.2794)
			(stroke
				(width 0.1)
				(type default)
			)
			(layer "F.Fab")
		)
		(fp_line
			(start 0.120396 0.2794)
			(end -0.12065 0.2794)
			(stroke
				(width 0.1)
				(type default)
			)
			(layer "F.Fab")
		)
		(fp_line
			(start -0.12065 0.3048)
			(end -0.67945 0.3048)
			(stroke
				(width 0.1)
				(type default)
			)
			(layer "F.Fab")
		)
		(fp_line
			(start -0.12065 0.2794)
			(end -0.12065 0.3048)
			(stroke
				(width 0.1)
				(type default)
			)
			(layer "F.Fab")
		)
		(fp_line
			(start -0.12065 -0.2794)
			(end 0.12065 -0.2794)
			(stroke
				(width 0.1)
				(type default)
			)
			(layer "F.Fab")
		)
		(fp_line
			(start -0.12065 -0.305054)
			(end -0.12065 -0.2794)
			(stroke
				(width 0.1)
				(type default)
			)
			(layer "F.Fab")
		)
		(fp_line
			(start -0.67945 0.3048)
			(end -0.67945 -0.305054)
			(stroke
				(width 0.1)
				(type default)
			)
			(layer "F.Fab")
		)
		(fp_line
			(start -0.67945 -0.305054)
			(end -0.12065 -0.305054)
			(stroke
				(width 0.1)
				(type default)
			)
			(layer "F.Fab")
		)
		(pad "1" smd circle
			(at -0.40005 0 180)
			(size 0 0)
			(layers "F.Cu" "F.Mask" "F.Paste")
			(net "P12V_SCM_R")
		)
		(pad "2" smd circle
			(at 0.40005 0 180)
			(size 0 0)
			(layers "F.Cu" "F.Mask" "F.Paste")
			(net "P12V_SCM_GATE")
		)
	)
	(footprint ""
		(layer "F.Cu")
		(at 139.505944 -366.066578 90)
		(property "Reference" "PJP1"
			(at 3.7973 4.352036 0)
			(unlocked yes)
			(layer "F.SilkS")
			(effects
				(font
					(size 0.7874 0.5842)
					(thickness 0.1524)
				)
				(justify left)
			)
		)
		(property "Value" ""
			(at 0 0 90)
			(layer "F.Fab")
			(effects
				(font
					(size 1.27 1.27)
				)
			)
		)
		(duplicate_pad_numbers_are_jumpers no)
		(fp_line
			(start 1.249934 -1.320038)
			(end 1.249934 6.400038)
			(stroke
				(width 0.1524)
				(type default)
			)
			(layer "F.SilkS")
		)
		(fp_line
			(start -1.249934 -1.320038)
			(end 1.249934 -1.320038)
			(stroke
				(width 0.1524)
				(type default)
			)
			(layer "F.SilkS")
		)
		(fp_line
			(start 1.249934 6.400038)
			(end -1.249934 6.400038)
			(stroke
				(width 0.1524)
				(type default)
			)
			(layer "F.SilkS")
		)
		(fp_line
			(start -1.249934 6.400038)
			(end -1.249934 -1.320038)
			(stroke
				(width 0.1524)
				(type default)
			)
			(layer "F.SilkS")
		)
		(fp_poly
			(pts
				(xy -1.668272 -0.08636) (xy -2.7813 0.470154) (xy -2.7813 -0.642874)
			)
			(stroke
				(width 0)
				(type default)
			)
			(fill yes)
			(layer "F.SilkS")
		)
		(fp_line
			(start 1.249934 -1.320038)
			(end 1.249934 6.400038)
			(stroke
				(width 0.1)
				(type default)
			)
			(layer "F.Fab")
		)
		(fp_line
			(start -1.249934 -1.320038)
			(end 1.249934 -1.320038)
			(stroke
				(width 0.1)
				(type default)
			)
			(layer "F.Fab")
		)
		(fp_line
			(start 1.249934 6.400038)
			(end -1.249934 6.400038)
			(stroke
				(width 0.1)
				(type default)
			)
			(layer "F.Fab")
		)
		(fp_line
			(start -1.249934 6.400038)
			(end -1.249934 -1.320038)
			(stroke
				(width 0.1)
				(type default)
			)
			(layer "F.Fab")
		)
		(fp_poly
			(pts
				(xy -2.5654 -0.556514) (xy -1.452372 0) (xy -2.5654 0.556514)
			)
			(stroke
				(width 0)
				(type default)
			)
			(fill yes)
			(layer "F.Fab")
		)
		(fp_text user "3"
			(at -2.01676 5.393436 0)
			(unlocked yes)
			(layer "F.SilkS")
			(effects
				(font
					(size 0.7874 0.5842)
					(thickness 0.1524)
				)
			)
		)
		(fp_text user "1"
			(at -1.143 0.02667 90)
			(unlocked yes)
			(layer "B.SilkS")
			(effects
				(font
					(size 0.7874 0.5842)
					(thickness 0.1524)
				)
				(justify mirror)
			)
		)
		(fp_text user "3"
			(at -1.1557 5.18287 90)
			(unlocked yes)
			(layer "B.SilkS")
			(effects
				(font
					(size 0.7874 0.5842)
					(thickness 0.1524)
				)
				(justify mirror)
			)
		)
		(fp_text user "1"
			(at -1.143 0.02667 90)
			(unlocked yes)
			(layer "B.Fab")
			(effects
				(font
					(size 0.7874 0.5842)
					(thickness 0.1524)
				)
				(justify mirror)
			)
		)
		(fp_text user "3"
			(at -1.1557 5.18287 90)
			(unlocked yes)
			(layer "B.Fab")
			(effects
				(font
					(size 0.7874 0.5842)
					(thickness 0.1524)
				)
				(justify mirror)
			)
		)
		(fp_text user "3"
			(at -1.778 5.13207 90)
			(unlocked yes)
			(layer "F.Fab")
			(effects
				(font
					(size 0.7874 0.5842)
					(thickness 0.1524)
				)
			)
		)
		(pad "1" thru_hole rect
			(at 0 0 90)
			(size 1.5494 1.5494)
			(drill 1.0414)
			(layers "*.Cu" "*.Mask")
			(remove_unused_layers no)
			(net "SMB_VR_3V3AUX_SCL_R3")
			(clearance 0)
			(padstack
				(mode front_inner_back)
				(layer "Inner"
					(shape circle)
					(size 1.5494 1.5494)
					(clearance 0)
				)
				(layer "B.Cu"
					(shape rect)
					(size 1.5494 1.5494)
					(clearance 0)
				)
			)
		)
		(pad "2" thru_hole circle
			(at 0 2.54 90)
			(size 1.5494 1.5494)
			(drill 1.0414)
			(layers "*.Cu" "*.Mask")
			(remove_unused_layers no)
			(net "GND")
			(clearance 0)
		)
		(pad "3" thru_hole circle
			(at 0 5.08 90)
			(size 1.5494 1.5494)
			(drill 1.0414)
			(layers "*.Cu" "*.Mask")
			(remove_unused_layers no)
			(net "SMB_VR_3V3AUX_SDA_R3")
			(clearance 0)
		)
	)
	(footprint ""
		(layer "F.Cu")
		(at 12.51712 -85.700108)
		(property "Reference" "H28"
			(at -5.94614 -2.116328 0)
			(unlocked yes)
			(layer "F.SilkS")
			(effects
				(font
					(size 0.7874 0.5842)
					(thickness 0.1524)
				)
				(justify left)
			)
		)
		(property "Value" ""
			(at 0 0 0)
			(layer "F.Fab")
			(effects
				(font
					(size 1.27 1.27)
				)
			)
		)
		(duplicate_pad_numbers_are_jumpers no)
		(fp_circle
			(center 0 0)
			(end 2.4003 0)
			(stroke
				(width 0.1524)
				(type default)
			)
			(fill no)
			(layer "F.SilkS")
		)
		(fp_circle
			(center 0 0)
			(end 6.5913 0)
			(stroke
				(width 0.1524)
				(type default)
			)
			(fill no)
			(layer "B.SilkS")
		)
		(fp_circle
			(center 0 0)
			(end 6.5913 0)
			(stroke
				(width 0.1)
				(type default)
			)
			(fill no)
			(layer "B.Fab")
		)
		(fp_circle
			(center 0 0)
			(end 2.4003 0)
			(stroke
				(width 0.1)
				(type default)
			)
			(fill no)
			(layer "F.Fab")
		)
		(pad "" np_thru_hole circle
			(at 0 0)
			(size 3.175 3.175)
			(drill 3.175)
			(layers "*.Cu" "*.Mask")
			(clearance 0.381)
			(thermal_gap 0.381)
		)
		(zone
			(layers "F.Cu" "B.Cu" "In1.Cu" "In2.Cu" "In3.Cu" "In4.Cu" "In5.Cu" "In6.Cu"
				"In7.Cu" "In8.Cu" "In9.Cu" "In10.Cu" "In11.Cu" "In12.Cu" "In13.Cu" "In14.Cu"
				"In15.Cu" "In16.Cu"
			)
			(hatch none 0.5)
			(connect_pads
				(clearance 0)
			)
			(min_thickness 0.25)
			(keepout
				(tracks not_allowed)
				(vias allowed)
				(pads allowed)
				(copperpour not_allowed)
				(footprints allowed)
			)
			(placement
				(enabled no)
				(sheetname "")
			)
			(fill
				(thermal_gap 0.5)
				(thermal_bridge_width 0.5)
				(island_removal_mode 0)
			)
			(polygon
				(pts
					(arc
						(start 14.61262 -85.700108)
						(mid 10.42162 -85.700108)
						(end 14.61262 -85.700108)
					)
				)
			)
		)
	)
	(footprint ""
		(layer "F.Cu")
		(at 116.888006 -333.804514 -90)
		(property "Reference" "PC530_P1_3"
			(at 0 0 270)
			(layer "F.SilkS")
			(hide yes)
			(effects
				(font
					(size 1.27 1.27)
				)
			)
		)
		(property "Value" ""
			(at 0 0 270)
			(layer "F.Fab")
			(effects
				(font
					(size 1.27 1.27)
				)
			)
		)
		(duplicate_pad_numbers_are_jumpers no)
		(fp_line
			(start -0.7874 0.4064)
			(end -0.7874 -0.4064)
			(stroke
				(width 0.1524)
				(type default)
			)
			(layer "F.SilkS")
		)
		(fp_line
			(start 0.7874 0.4064)
			(end -0.7874 0.4064)
			(stroke
				(width 0.1524)
				(type default)
			)
			(layer "F.SilkS")
		)
		(fp_line
			(start -0.7874 -0.4064)
			(end 0.7874 -0.4064)
			(stroke
				(width 0.1524)
				(type default)
			)
			(layer "F.SilkS")
		)
		(fp_line
			(start 0.7874 -0.4064)
			(end 0.7874 0.4064)
			(stroke
				(width 0.1524)
				(type default)
			)
			(layer "F.SilkS")
		)
		(fp_line
			(start -0.67945 0.3048)
			(end -0.67945 -0.305054)
			(stroke
				(width 0.1)
				(type default)
			)
			(layer "F.Fab")
		)
		(fp_line
			(start -0.12065 0.3048)
			(end -0.67945 0.3048)
			(stroke
				(width 0.1)
				(type default)
			)
			(layer "F.Fab")
		)
		(fp_line
			(start 0.120396 0.3048)
			(end 0.120396 0.2794)
			(stroke
				(width 0.1)
				(type default)
			)
			(layer "F.Fab")
		)
		(fp_line
			(start 0.67945 0.3048)
			(end 0.120396 0.3048)
			(stroke
				(width 0.1)
				(type default)
			)
			(layer "F.Fab")
		)
		(fp_line
			(start -0.12065 0.2794)
			(end -0.12065 0.3048)
			(stroke
				(width 0.1)
				(type default)
			)
			(layer "F.Fab")
		)
		(fp_line
			(start 0.120396 0.2794)
			(end -0.12065 0.2794)
			(stroke
				(width 0.1)
				(type default)
			)
			(layer "F.Fab")
		)
		(fp_line
			(start -0.12065 -0.2794)
			(end 0.12065 -0.2794)
			(stroke
				(width 0.1)
				(type default)
			)
			(layer "F.Fab")
		)
		(fp_line
			(start 0.12065 -0.2794)
			(end 0.12065 -0.3048)
			(stroke
				(width 0.1)
				(type default)
			)
			(layer "F.Fab")
		)
		(fp_line
			(start 0.12065 -0.3048)
			(end 0.67945 -0.3048)
			(stroke
				(width 0.1)
				(type default)
			)
			(layer "F.Fab")
		)
		(fp_line
			(start 0.67945 -0.3048)
			(end 0.67945 0.3048)
			(stroke
				(width 0.1)
				(type default)
			)
			(layer "F.Fab")
		)
		(fp_line
			(start -0.67945 -0.305054)
			(end -0.12065 -0.305054)
			(stroke
				(width 0.1)
				(type default)
			)
			(layer "F.Fab")
		)
		(fp_line
			(start -0.12065 -0.305054)
			(end -0.12065 -0.2794)
			(stroke
				(width 0.1)
				(type default)
			)
			(layer "F.Fab")
		)
		(pad "1" smd circle
			(at -0.40005 0 270)
			(size 0 0)
			(layers "F.Cu" "F.Mask" "F.Paste")
			(net "SW_P12V_PVCCIN_CPU1_FLT")
		)
		(pad "2" smd circle
			(at 0.40005 0 270)
			(size 0 0)
			(layers "F.Cu" "F.Mask" "F.Paste")
			(net "GND")
		)
	)
	(footprint ""
		(layer "F.Cu")
		(at 359.71988 -296.05478 180)
		(property "Reference" "C218"
			(at 0 0 180)
			(layer "F.SilkS")
			(hide yes)
			(effects
				(font
					(size 1.27 1.27)
				)
			)
		)
		(property "Value" ""
			(at 0 0 180)
			(layer "F.Fab")
			(effects
				(font
					(size 1.27 1.27)
				)
			)
		)
		(duplicate_pad_numbers_are_jumpers no)
		(fp_line
			(start 1.524 0.762)
			(end -1.524 0.762)
			(stroke
				(width 0.1524)
				(type default)
			)
			(layer "F.SilkS")
		)
		(fp_line
			(start 1.524 -0.762)
			(end 1.524 0.762)
			(stroke
				(width 0.1524)
				(type default)
			)
			(layer "F.SilkS")
		)
		(fp_line
			(start -1.524 0.762)
			(end -1.524 -0.762)
			(stroke
				(width 0.1524)
				(type default)
			)
			(layer "F.SilkS")
		)
		(fp_line
			(start -1.524 -0.762)
			(end 1.524 -0.762)
			(stroke
				(width 0.1524)
				(type default)
			)
			(layer "F.SilkS")
		)
		(fp_line
			(start 1.1049 0.724916)
			(end 1.1049 -0.724916)
			(stroke
				(width 0.1)
				(type default)
			)
			(layer "F.Fab")
		)
		(fp_line
			(start 1.1049 -0.724916)
			(end -1.1049 -0.724916)
			(stroke
				(width 0.1)
				(type default)
			)
			(layer "F.Fab")
		)
		(fp_line
			(start -1.1049 0.724916)
			(end 1.1049 0.724916)
			(stroke
				(width 0.1)
				(type default)
			)
			(layer "F.Fab")
		)
		(fp_line
			(start -1.1049 -0.724916)
			(end -1.1049 0.724916)
			(stroke
				(width 0.1)
				(type default)
			)
			(layer "F.Fab")
		)
		(pad "1" smd rect
			(at -0.889 0)
			(size 1.016 1.27)
			(layers "F.Cu" "F.Mask" "F.Paste")
			(net "PVCCIN_CPU0")
		)
		(pad "2" smd rect
			(at 0.889 0)
			(size 1.016 1.27)
			(layers "F.Cu" "F.Mask" "F.Paste")
			(net "GND")
		)
	)
	(footprint ""
		(layer "F.Cu")
		(at 31.8516 -69.7992 180)
		(property "Reference" "R4761"
			(at 0 0 180)
			(layer "F.SilkS")
			(hide yes)
			(effects
				(font
					(size 1.27 1.27)
				)
			)
		)
		(property "Value" ""
			(at 0 0 180)
			(layer "F.Fab")
			(effects
				(font
					(size 1.27 1.27)
				)
			)
		)
		(duplicate_pad_numbers_are_jumpers no)
		(fp_line
			(start 0.7874 0.4064)
			(end -0.7874 0.4064)
			(stroke
				(width 0.1524)
				(type default)
			)
			(layer "F.SilkS")
		)
		(fp_line
			(start 0.7874 -0.4064)
			(end 0.7874 0.4064)
			(stroke
				(width 0.1524)
				(type default)
			)
			(layer "F.SilkS")
		)
		(fp_line
			(start -0.7874 0.4064)
			(end -0.7874 -0.4064)
			(stroke
				(width 0.1524)
				(type default)
			)
			(layer "F.SilkS")
		)
		(fp_line
			(start -0.7874 -0.4064)
			(end 0.7874 -0.4064)
			(stroke
				(width 0.1524)
				(type default)
			)
			(layer "F.SilkS")
		)
		(fp_line
			(start 0.67945 0.3048)
			(end 0.120396 0.3048)
			(stroke
				(width 0.1)
				(type default)
			)
			(layer "F.Fab")
		)
		(fp_line
			(start 0.67945 -0.3048)
			(end 0.67945 0.3048)
			(stroke
				(width 0.1)
				(type default)
			)
			(layer "F.Fab")
		)
		(fp_line
			(start 0.12065 -0.2794)
			(end 0.12065 -0.3048)
			(stroke
				(width 0.1)
				(type default)
			)
			(layer "F.Fab")
		)
		(fp_line
			(start 0.12065 -0.3048)
			(end 0.67945 -0.3048)
			(stroke
				(width 0.1)
				(type default)
			)
			(layer "F.Fab")
		)
		(fp_line
			(start 0.120396 0.3048)
			(end 0.120396 0.2794)
			(stroke
				(width 0.1)
				(type default)
			)
			(layer "F.Fab")
		)
		(fp_line
			(start 0.120396 0.2794)
			(end -0.12065 0.2794)
			(stroke
				(width 0.1)
				(type default)
			)
			(layer "F.Fab")
		)
		(fp_line
			(start -0.12065 0.3048)
			(end -0.67945 0.3048)
			(stroke
				(width 0.1)
				(type default)
			)
			(layer "F.Fab")
		)
		(fp_line
			(start -0.12065 0.2794)
			(end -0.12065 0.3048)
			(stroke
				(width 0.1)
				(type default)
			)
			(layer "F.Fab")
		)
		(fp_line
			(start -0.12065 -0.2794)
			(end 0.12065 -0.2794)
			(stroke
				(width 0.1)
				(type default)
			)
			(layer "F.Fab")
		)
		(fp_line
			(start -0.12065 -0.305054)
			(end -0.12065 -0.2794)
			(stroke
				(width 0.1)
				(type default)
			)
			(layer "F.Fab")
		)
		(fp_line
			(start -0.67945 0.3048)
			(end -0.67945 -0.305054)
			(stroke
				(width 0.1)
				(type default)
			)
			(layer "F.Fab")
		)
		(fp_line
			(start -0.67945 -0.305054)
			(end -0.12065 -0.305054)
			(stroke
				(width 0.1)
				(type default)
			)
			(layer "F.Fab")
		)
		(pad "1" smd circle
			(at -0.40005 0 180)
			(size 0 0)
			(layers "F.Cu" "F.Mask" "F.Paste")
			(net "P3V3_AUX")
		)
		(pad "2" smd circle
			(at 0.40005 0 180)
			(size 0 0)
			(layers "F.Cu" "F.Mask" "F.Paste")
			(net "HP_LVC3_OCP_V3_2_PRSNT2_PLD_N")
		)
	)
	(footprint ""
		(layer "F.Cu")
		(at 66.94932 -56.540908 -90)
		(property "Reference" "PC2169"
			(at 0 0 270)
			(layer "F.SilkS")
			(hide yes)
			(effects
				(font
					(size 1.27 1.27)
				)
			)
		)
		(property "Value" ""
			(at 0 0 270)
			(layer "F.Fab")
			(effects
				(font
					(size 1.27 1.27)
				)
			)
		)
		(duplicate_pad_numbers_are_jumpers no)
		(fp_line
			(start -0.7874 0.4064)
			(end -0.7874 -0.4064)
			(stroke
				(width 0.1524)
				(type default)
			)
			(layer "F.SilkS")
		)
		(fp_line
			(start 0.7874 0.4064)
			(end -0.7874 0.4064)
			(stroke
				(width 0.1524)
				(type default)
			)
			(layer "F.SilkS")
		)
		(fp_line
			(start -0.7874 -0.4064)
			(end 0.7874 -0.4064)
			(stroke
				(width 0.1524)
				(type default)
			)
			(layer "F.SilkS")
		)
		(fp_line
			(start 0.7874 -0.4064)
			(end 0.7874 0.4064)
			(stroke
				(width 0.1524)
				(type default)
			)
			(layer "F.SilkS")
		)
		(fp_line
			(start -0.67945 0.3048)
			(end -0.67945 -0.305054)
			(stroke
				(width 0.1)
				(type default)
			)
			(layer "F.Fab")
		)
		(fp_line
			(start -0.12065 0.3048)
			(end -0.67945 0.3048)
			(stroke
				(width 0.1)
				(type default)
			)
			(layer "F.Fab")
		)
		(fp_line
			(start 0.120396 0.3048)
			(end 0.120396 0.2794)
			(stroke
				(width 0.1)
				(type default)
			)
			(layer "F.Fab")
		)
		(fp_line
			(start 0.67945 0.3048)
			(end 0.120396 0.3048)
			(stroke
				(width 0.1)
				(type default)
			)
			(layer "F.Fab")
		)
		(fp_line
			(start -0.12065 0.2794)
			(end -0.12065 0.3048)
			(stroke
				(width 0.1)
				(type default)
			)
			(layer "F.Fab")
		)
		(fp_line
			(start 0.120396 0.2794)
			(end -0.12065 0.2794)
			(stroke
				(width 0.1)
				(type default)
			)
			(layer "F.Fab")
		)
		(fp_line
			(start -0.12065 -0.2794)
			(end 0.12065 -0.2794)
			(stroke
				(width 0.1)
				(type default)
			)
			(layer "F.Fab")
		)
		(fp_line
			(start 0.12065 -0.2794)
			(end 0.12065 -0.3048)
			(stroke
				(width 0.1)
				(type default)
			)
			(layer "F.Fab")
		)
		(fp_line
			(start 0.12065 -0.3048)
			(end 0.67945 -0.3048)
			(stroke
				(width 0.1)
				(type default)
			)
			(layer "F.Fab")
		)
		(fp_line
			(start 0.67945 -0.3048)
			(end 0.67945 0.3048)
			(stroke
				(width 0.1)
				(type default)
			)
			(layer "F.Fab")
		)
		(fp_line
			(start -0.67945 -0.305054)
			(end -0.12065 -0.305054)
			(stroke
				(width 0.1)
				(type default)
			)
			(layer "F.Fab")
		)
		(fp_line
			(start -0.12065 -0.305054)
			(end -0.12065 -0.2794)
			(stroke
				(width 0.1)
				(type default)
			)
			(layer "F.Fab")
		)
		(pad "1" smd circle
			(at -0.40005 0 270)
			(size 0 0)
			(layers "F.Cu" "F.Mask" "F.Paste")
			(net "P3V3_AUX")
		)
		(pad "2" smd circle
			(at 0.40005 0 270)
			(size 0 0)
			(layers "F.Cu" "F.Mask" "F.Paste")
			(net "GND")
		)
	)
	(footprint ""
		(layer "F.Cu")
		(at 435.997858 -107.78236 180)
		(property "Reference" "PC5328"
			(at 0 0 180)
			(layer "F.SilkS")
			(hide yes)
			(effects
				(font
					(size 1.27 1.27)
				)
			)
		)
		(property "Value" ""
			(at 0 0 180)
			(layer "F.Fab")
			(effects
				(font
					(size 1.27 1.27)
				)
			)
		)
		(duplicate_pad_numbers_are_jumpers no)
		(fp_line
			(start 0.7874 0.4064)
			(end -0.7874 0.4064)
			(stroke
				(width 0.1524)
				(type default)
			)
			(layer "F.SilkS")
		)
		(fp_line
			(start 0.7874 -0.4064)
			(end 0.7874 0.4064)
			(stroke
				(width 0.1524)
				(type default)
			)
			(layer "F.SilkS")
		)
		(fp_line
			(start -0.7874 0.4064)
			(end -0.7874 -0.4064)
			(stroke
				(width 0.1524)
				(type default)
			)
			(layer "F.SilkS")
		)
		(fp_line
			(start -0.7874 -0.4064)
			(end 0.7874 -0.4064)
			(stroke
				(width 0.1524)
				(type default)
			)
			(layer "F.SilkS")
		)
		(fp_line
			(start 0.67945 0.3048)
			(end 0.120396 0.3048)
			(stroke
				(width 0.1)
				(type default)
			)
			(layer "F.Fab")
		)
		(fp_line
			(start 0.67945 -0.3048)
			(end 0.67945 0.3048)
			(stroke
				(width 0.1)
				(type default)
			)
			(layer "F.Fab")
		)
		(fp_line
			(start 0.12065 -0.2794)
			(end 0.12065 -0.3048)
			(stroke
				(width 0.1)
				(type default)
			)
			(layer "F.Fab")
		)
		(fp_line
			(start 0.12065 -0.3048)
			(end 0.67945 -0.3048)
			(stroke
				(width 0.1)
				(type default)
			)
			(layer "F.Fab")
		)
		(fp_line
			(start 0.120396 0.3048)
			(end 0.120396 0.2794)
			(stroke
				(width 0.1)
				(type default)
			)
			(layer "F.Fab")
		)
		(fp_line
			(start 0.120396 0.2794)
			(end -0.12065 0.2794)
			(stroke
				(width 0.1)
				(type default)
			)
			(layer "F.Fab")
		)
		(fp_line
			(start -0.12065 0.3048)
			(end -0.67945 0.3048)
			(stroke
				(width 0.1)
				(type default)
			)
			(layer "F.Fab")
		)
		(fp_line
			(start -0.12065 0.2794)
			(end -0.12065 0.3048)
			(stroke
				(width 0.1)
				(type default)
			)
			(layer "F.Fab")
		)
		(fp_line
			(start -0.12065 -0.2794)
			(end 0.12065 -0.2794)
			(stroke
				(width 0.1)
				(type default)
			)
			(layer "F.Fab")
		)
		(fp_line
			(start -0.12065 -0.305054)
			(end -0.12065 -0.2794)
			(stroke
				(width 0.1)
				(type default)
			)
			(layer "F.Fab")
		)
		(fp_line
			(start -0.67945 0.3048)
			(end -0.67945 -0.305054)
			(stroke
				(width 0.1)
				(type default)
			)
			(layer "F.Fab")
		)
		(fp_line
			(start -0.67945 -0.305054)
			(end -0.12065 -0.305054)
			(stroke
				(width 0.1)
				(type default)
			)
			(layer "F.Fab")
		)
		(pad "1" smd circle
			(at -0.40005 0 180)
			(size 0 0)
			(layers "F.Cu" "F.Mask" "F.Paste")
			(net "P3V3_AUX")
		)
		(pad "2" smd circle
			(at 0.40005 0 180)
			(size 0 0)
			(layers "F.Cu" "F.Mask" "F.Paste")
			(net "GND")
		)
	)
	(footprint ""
		(layer "F.Cu")
		(at 113.494312 -139.069826 180)
		(property "Reference" "R587"
			(at 0 0 180)
			(layer "F.SilkS")
			(hide yes)
			(effects
				(font
					(size 1.27 1.27)
				)
			)
		)
		(property "Value" ""
			(at 0 0 180)
			(layer "F.Fab")
			(effects
				(font
					(size 1.27 1.27)
				)
			)
		)
		(duplicate_pad_numbers_are_jumpers no)
		(fp_line
			(start 0.7874 0.4064)
			(end -0.7874 0.4064)
			(stroke
				(width 0.1524)
				(type default)
			)
			(layer "F.SilkS")
		)
		(fp_line
			(start 0.7874 -0.4064)
			(end 0.7874 0.4064)
			(stroke
				(width 0.1524)
				(type default)
			)
			(layer "F.SilkS")
		)
		(fp_line
			(start -0.7874 0.4064)
			(end -0.7874 -0.4064)
			(stroke
				(width 0.1524)
				(type default)
			)
			(layer "F.SilkS")
		)
		(fp_line
			(start -0.7874 -0.4064)
			(end 0.7874 -0.4064)
			(stroke
				(width 0.1524)
				(type default)
			)
			(layer "F.SilkS")
		)
		(fp_line
			(start 0.67945 0.3048)
			(end 0.120396 0.3048)
			(stroke
				(width 0.1)
				(type default)
			)
			(layer "F.Fab")
		)
		(fp_line
			(start 0.67945 -0.3048)
			(end 0.67945 0.3048)
			(stroke
				(width 0.1)
				(type default)
			)
			(layer "F.Fab")
		)
		(fp_line
			(start 0.12065 -0.2794)
			(end 0.12065 -0.3048)
			(stroke
				(width 0.1)
				(type default)
			)
			(layer "F.Fab")
		)
		(fp_line
			(start 0.12065 -0.3048)
			(end 0.67945 -0.3048)
			(stroke
				(width 0.1)
				(type default)
			)
			(layer "F.Fab")
		)
		(fp_line
			(start 0.120396 0.3048)
			(end 0.120396 0.2794)
			(stroke
				(width 0.1)
				(type default)
			)
			(layer "F.Fab")
		)
		(fp_line
			(start 0.120396 0.2794)
			(end -0.12065 0.2794)
			(stroke
				(width 0.1)
				(type default)
			)
			(layer "F.Fab")
		)
		(fp_line
			(start -0.12065 0.3048)
			(end -0.67945 0.3048)
			(stroke
				(width 0.1)
				(type default)
			)
			(layer "F.Fab")
		)
		(fp_line
			(start -0.12065 0.2794)
			(end -0.12065 0.3048)
			(stroke
				(width 0.1)
				(type default)
			)
			(layer "F.Fab")
		)
		(fp_line
			(start -0.12065 -0.2794)
			(end 0.12065 -0.2794)
			(stroke
				(width 0.1)
				(type default)
			)
			(layer "F.Fab")
		)
		(fp_line
			(start -0.12065 -0.305054)
			(end -0.12065 -0.2794)
			(stroke
				(width 0.1)
				(type default)
			)
			(layer "F.Fab")
		)
		(fp_line
			(start -0.67945 0.3048)
			(end -0.67945 -0.305054)
			(stroke
				(width 0.1)
				(type default)
			)
			(layer "F.Fab")
		)
		(fp_line
			(start -0.67945 -0.305054)
			(end -0.12065 -0.305054)
			(stroke
				(width 0.1)
				(type default)
			)
			(layer "F.Fab")
		)
		(pad "1" smd circle
			(at -0.40005 0 180)
			(size 0 0)
			(layers "F.Cu" "F.Mask" "F.Paste")
			(net "PCA9548_PCIE3_ADDR0")
		)
		(pad "2" smd circle
			(at 0.40005 0 180)
			(size 0 0)
			(layers "F.Cu" "F.Mask" "F.Paste")
			(net "GND")
		)
	)
	(footprint ""
		(layer "F.Cu")
		(at 69.923406 -148.228304)
		(property "Reference" "PC1593"
			(at 0 0 0)
			(layer "F.SilkS")
			(hide yes)
			(effects
				(font
					(size 1.27 1.27)
				)
			)
		)
		(property "Value" ""
			(at 0 0 0)
			(layer "F.Fab")
			(effects
				(font
					(size 1.27 1.27)
				)
			)
		)
		(duplicate_pad_numbers_are_jumpers no)
		(fp_line
			(start 2.750058 0.999998)
			(end -2.750058 0.999998)
			(stroke
				(width 0.1524)
				(type default)
			)
			(layer "F.SilkS")
		)
		(fp_circle
			(center 0 0.999998)
			(end 2.750058 0.999998)
			(stroke
				(width 0.1524)
				(type default)
			)
			(fill no)
			(layer "F.SilkS")
		)
		(fp_poly
			(pts
				(arc
					(start 2.750058 0.999998)
					(mid 0 3.750056)
					(end -2.750058 0.999998)
				)
			)
			(stroke
				(width 0)
				(type default)
			)
			(fill yes)
			(layer "F.SilkS")
		)
		(fp_circle
			(center 0 0.999998)
			(end 2.750058 0.999998)
			(stroke
				(width 0.1)
				(type default)
			)
			(fill no)
			(layer "F.Fab")
		)
		(pad "1" thru_hole rect
			(at 0 0)
			(size 1.5748 1.5748)
			(drill 1.0668)
			(layers "*.Cu" "*.Mask")
			(remove_unused_layers no)
			(net "PVCCINFAON_CPU1")
			(clearance 0)
			(padstack
				(mode front_inner_back)
				(layer "Inner"
					(shape circle)
					(size 1.5748 1.5748)
					(clearance 0)
				)
				(layer "B.Cu"
					(shape rect)
					(size 1.5748 1.5748)
					(clearance 0)
				)
			)
		)
		(pad "2" thru_hole circle
			(at 0 1.999996)
			(size 1.5748 1.5748)
			(drill 1.0668)
			(layers "*.Cu" "*.Mask")
			(remove_unused_layers no)
			(net "GND")
			(clearance 0)
		)
	)
	(footprint ""
		(layer "F.Cu")
		(at 22.460204 -384.978148 90)
		(property "Reference" "C2354"
			(at 0 0 90)
			(layer "F.SilkS")
			(hide yes)
			(effects
				(font
					(size 1.27 1.27)
				)
			)
		)
		(property "Value" ""
			(at 0 0 90)
			(layer "F.Fab")
			(effects
				(font
					(size 1.27 1.27)
				)
			)
		)
		(duplicate_pad_numbers_are_jumpers no)
		(fp_line
			(start 0.7874 -0.4064)
			(end 0.7874 0.4064)
			(stroke
				(width 0.1524)
				(type default)
			)
			(layer "F.SilkS")
		)
		(fp_line
			(start -0.7874 -0.4064)
			(end 0.7874 -0.4064)
			(stroke
				(width 0.1524)
				(type default)
			)
			(layer "F.SilkS")
		)
		(fp_line
			(start -0.005588 0.4064)
			(end -0.7874 0.4064)
			(stroke
				(width 0.1524)
				(type default)
			)
			(layer "F.SilkS")
		)
		(fp_line
			(start 0.6858 -0.3048)
			(end 0.6858 0.3048)
			(stroke
				(width 0.1)
				(type default)
			)
			(layer "F.Fab")
		)
		(fp_line
			(start 0.1016 -0.3048)
			(end 0.6858 -0.3048)
			(stroke
				(width 0.1)
				(type default)
			)
			(layer "F.Fab")
		)
		(fp_line
			(start -0.1016 -0.3048)
			(end -0.1016 -0.2794)
			(stroke
				(width 0.1)
				(type default)
			)
			(layer "F.Fab")
		)
		(fp_line
			(start -0.6858 -0.3048)
			(end -0.1016 -0.3048)
			(stroke
				(width 0.1)
				(type default)
			)
			(layer "F.Fab")
		)
		(fp_line
			(start 0.1016 -0.2794)
			(end 0.1016 -0.3048)
			(stroke
				(width 0.1)
				(type default)
			)
			(layer "F.Fab")
		)
		(fp_line
			(start -0.1016 -0.2794)
			(end 0.1016 -0.2794)
			(stroke
				(width 0.1)
				(type default)
			)
			(layer "F.Fab")
		)
		(fp_line
			(start 0.1016 0.2794)
			(end -0.1016 0.2794)
			(stroke
				(width 0.1)
				(type default)
			)
			(layer "F.Fab")
		)
		(fp_line
			(start -0.1016 0.2794)
			(end -0.1016 0.3048)
			(stroke
				(width 0.1)
				(type default)
			)
			(layer "F.Fab")
		)
		(fp_line
			(start 0.6858 0.3048)
			(end 0.1016 0.3048)
			(stroke
				(width 0.1)
				(type default)
			)
			(layer "F.Fab")
		)
		(fp_line
			(start 0.1016 0.3048)
			(end 0.1016 0.2794)
			(stroke
				(width 0.1)
				(type default)
			)
			(layer "F.Fab")
		)
		(fp_line
			(start -0.1016 0.3048)
			(end -0.6858 0.3048)
			(stroke
				(width 0.1)
				(type default)
			)
			(layer "F.Fab")
		)
		(fp_line
			(start -0.6858 0.3048)
			(end -0.6858 -0.3048)
			(stroke
				(width 0.1)
				(type default)
			)
			(layer "F.Fab")
		)
		(pad "1" smd rect
			(at -0.40005 0 270)
			(size 0.4572 0.508)
			(layers "F.Cu" "F.Mask" "F.Paste")
			(net "P2E_MB_BMC_RX_BUF2_C_DN<0>")
		)
		(pad "2" smd rect
			(at 0.40005 0 270)
			(size 0.4572 0.508)
			(layers "F.Cu" "F.Mask" "F.Paste")
			(net "P2E_MB_BMC_RX_BUF_DN<0>")
		)
	)
	(footprint ""
		(layer "F.Cu")
		(at 54.112414 -171.129198)
		(property "Reference" "PR1728"
			(at 0 0 0)
			(layer "F.SilkS")
			(hide yes)
			(effects
				(font
					(size 1.27 1.27)
				)
			)
		)
		(property "Value" ""
			(at 0 0 0)
			(layer "F.Fab")
			(effects
				(font
					(size 1.27 1.27)
				)
			)
		)
		(duplicate_pad_numbers_are_jumpers no)
		(fp_line
			(start -0.7874 -0.4064)
			(end 0.7874 -0.4064)
			(stroke
				(width 0.1524)
				(type default)
			)
			(layer "F.SilkS")
		)
		(fp_line
			(start -0.7874 0.4064)
			(end -0.7874 -0.4064)
			(stroke
				(width 0.1524)
				(type default)
			)
			(layer "F.SilkS")
		)
		(fp_line
			(start 0.7874 -0.4064)
			(end 0.7874 0.4064)
			(stroke
				(width 0.1524)
				(type default)
			)
			(layer "F.SilkS")
		)
		(fp_line
			(start 0.7874 0.4064)
			(end -0.7874 0.4064)
			(stroke
				(width 0.1524)
				(type default)
			)
			(layer "F.SilkS")
		)
		(fp_line
			(start -0.67945 -0.305054)
			(end -0.12065 -0.305054)
			(stroke
				(width 0.1)
				(type default)
			)
			(layer "F.Fab")
		)
		(fp_line
			(start -0.67945 0.3048)
			(end -0.67945 -0.305054)
			(stroke
				(width 0.1)
				(type default)
			)
			(layer "F.Fab")
		)
		(fp_line
			(start -0.12065 -0.305054)
			(end -0.12065 -0.2794)
			(stroke
				(width 0.1)
				(type default)
			)
			(layer "F.Fab")
		)
		(fp_line
			(start -0.12065 -0.2794)
			(end 0.12065 -0.2794)
			(stroke
				(width 0.1)
				(type default)
			)
			(layer "F.Fab")
		)
		(fp_line
			(start -0.12065 0.2794)
			(end -0.12065 0.3048)
			(stroke
				(width 0.1)
				(type default)
			)
			(layer "F.Fab")
		)
		(fp_line
			(start -0.12065 0.3048)
			(end -0.67945 0.3048)
			(stroke
				(width 0.1)
				(type default)
			)
			(layer "F.Fab")
		)
		(fp_line
			(start 0.120396 0.2794)
			(end -0.12065 0.2794)
			(stroke
				(width 0.1)
				(type default)
			)
			(layer "F.Fab")
		)
		(fp_line
			(start 0.120396 0.3048)
			(end 0.120396 0.2794)
			(stroke
				(width 0.1)
				(type default)
			)
			(layer "F.Fab")
		)
		(fp_line
			(start 0.12065 -0.3048)
			(end 0.67945 -0.3048)
			(stroke
				(width 0.1)
				(type default)
			)
			(layer "F.Fab")
		)
		(fp_line
			(start 0.12065 -0.2794)
			(end 0.12065 -0.3048)
			(stroke
				(width 0.1)
				(type default)
			)
			(layer "F.Fab")
		)
		(fp_line
			(start 0.67945 -0.3048)
			(end 0.67945 0.3048)
			(stroke
				(width 0.1)
				(type default)
			)
			(layer "F.Fab")
		)
		(fp_line
			(start 0.67945 0.3048)
			(end 0.120396 0.3048)
			(stroke
				(width 0.1)
				(type default)
			)
			(layer "F.Fab")
		)
		(pad "1" smd circle
			(at -0.40005 0)
			(size 0 0)
			(layers "F.Cu" "F.Mask" "F.Paste")
			(net "PVCCFA_EHV_CPU1_LSET1")
		)
		(pad "2" smd circle
			(at 0.40005 0)
			(size 0 0)
			(layers "F.Cu" "F.Mask" "F.Paste")
			(net "GND")
		)
	)
	(footprint ""
		(layer "F.Cu")
		(at 164.67328 -21.783548 -90)
		(property "Reference" "R142"
			(at 0 0 270)
			(layer "F.SilkS")
			(hide yes)
			(effects
				(font
					(size 1.27 1.27)
				)
			)
		)
		(property "Value" ""
			(at 0 0 270)
			(layer "F.Fab")
			(effects
				(font
					(size 1.27 1.27)
				)
			)
		)
		(duplicate_pad_numbers_are_jumpers no)
		(fp_line
			(start -0.7874 0.4064)
			(end -0.7874 -0.4064)
			(stroke
				(width 0.1524)
				(type default)
			)
			(layer "F.SilkS")
		)
		(fp_line
			(start 0.7874 0.4064)
			(end -0.7874 0.4064)
			(stroke
				(width 0.1524)
				(type default)
			)
			(layer "F.SilkS")
		)
		(fp_line
			(start -0.7874 -0.4064)
			(end 0.7874 -0.4064)
			(stroke
				(width 0.1524)
				(type default)
			)
			(layer "F.SilkS")
		)
		(fp_line
			(start 0.7874 -0.4064)
			(end 0.7874 0.4064)
			(stroke
				(width 0.1524)
				(type default)
			)
			(layer "F.SilkS")
		)
		(fp_line
			(start -0.67945 0.3048)
			(end -0.67945 -0.305054)
			(stroke
				(width 0.1)
				(type default)
			)
			(layer "F.Fab")
		)
		(fp_line
			(start -0.12065 0.3048)
			(end -0.67945 0.3048)
			(stroke
				(width 0.1)
				(type default)
			)
			(layer "F.Fab")
		)
		(fp_line
			(start 0.120396 0.3048)
			(end 0.120396 0.2794)
			(stroke
				(width 0.1)
				(type default)
			)
			(layer "F.Fab")
		)
		(fp_line
			(start 0.67945 0.3048)
			(end 0.120396 0.3048)
			(stroke
				(width 0.1)
				(type default)
			)
			(layer "F.Fab")
		)
		(fp_line
			(start -0.12065 0.2794)
			(end -0.12065 0.3048)
			(stroke
				(width 0.1)
				(type default)
			)
			(layer "F.Fab")
		)
		(fp_line
			(start 0.120396 0.2794)
			(end -0.12065 0.2794)
			(stroke
				(width 0.1)
				(type default)
			)
			(layer "F.Fab")
		)
		(fp_line
			(start -0.12065 -0.2794)
			(end 0.12065 -0.2794)
			(stroke
				(width 0.1)
				(type default)
			)
			(layer "F.Fab")
		)
		(fp_line
			(start 0.12065 -0.2794)
			(end 0.12065 -0.3048)
			(stroke
				(width 0.1)
				(type default)
			)
			(layer "F.Fab")
		)
		(fp_line
			(start 0.12065 -0.3048)
			(end 0.67945 -0.3048)
			(stroke
				(width 0.1)
				(type default)
			)
			(layer "F.Fab")
		)
		(fp_line
			(start 0.67945 -0.3048)
			(end 0.67945 0.3048)
			(stroke
				(width 0.1)
				(type default)
			)
			(layer "F.Fab")
		)
		(fp_line
			(start -0.67945 -0.305054)
			(end -0.12065 -0.305054)
			(stroke
				(width 0.1)
				(type default)
			)
			(layer "F.Fab")
		)
		(fp_line
			(start -0.12065 -0.305054)
			(end -0.12065 -0.2794)
			(stroke
				(width 0.1)
				(type default)
			)
			(layer "F.Fab")
		)
		(pad "1" smd circle
			(at -0.40005 0 270)
			(size 0 0)
			(layers "F.Cu" "F.Mask" "F.Paste")
			(net "PVNN_TERM_CPU0")
		)
		(pad "2" smd circle
			(at 0.40005 0 270)
			(size 0 0)
			(layers "F.Cu" "F.Mask" "F.Paste")
			(net "PVCCIO_PECI_BMC")
		)
	)
	(footprint ""
		(layer "F.Cu")
		(at 36.930584 -105.425748)
		(property "Reference" "C2194"
			(at 0 0 0)
			(layer "F.SilkS")
			(hide yes)
			(effects
				(font
					(size 1.27 1.27)
				)
			)
		)
		(property "Value" ""
			(at 0 0 0)
			(layer "F.Fab")
			(effects
				(font
					(size 1.27 1.27)
				)
			)
		)
		(duplicate_pad_numbers_are_jumpers no)
		(fp_line
			(start -0.7874 -0.4064)
			(end 0.7874 -0.4064)
			(stroke
				(width 0.1524)
				(type default)
			)
			(layer "F.SilkS")
		)
		(fp_line
			(start -0.7874 0.4064)
			(end -0.7874 -0.4064)
			(stroke
				(width 0.1524)
				(type default)
			)
			(layer "F.SilkS")
		)
		(fp_line
			(start 0.7874 -0.4064)
			(end 0.7874 0.4064)
			(stroke
				(width 0.1524)
				(type default)
			)
			(layer "F.SilkS")
		)
		(fp_line
			(start 0.7874 0.4064)
			(end -0.7874 0.4064)
			(stroke
				(width 0.1524)
				(type default)
			)
			(layer "F.SilkS")
		)
		(fp_line
			(start -0.67945 -0.305054)
			(end -0.12065 -0.305054)
			(stroke
				(width 0.1)
				(type default)
			)
			(layer "F.Fab")
		)
		(fp_line
			(start -0.67945 0.3048)
			(end -0.67945 -0.305054)
			(stroke
				(width 0.1)
				(type default)
			)
			(layer "F.Fab")
		)
		(fp_line
			(start -0.12065 -0.305054)
			(end -0.12065 -0.2794)
			(stroke
				(width 0.1)
				(type default)
			)
			(layer "F.Fab")
		)
		(fp_line
			(start -0.12065 -0.2794)
			(end 0.12065 -0.2794)
			(stroke
				(width 0.1)
				(type default)
			)
			(layer "F.Fab")
		)
		(fp_line
			(start -0.12065 0.2794)
			(end -0.12065 0.3048)
			(stroke
				(width 0.1)
				(type default)
			)
			(layer "F.Fab")
		)
		(fp_line
			(start -0.12065 0.3048)
			(end -0.67945 0.3048)
			(stroke
				(width 0.1)
				(type default)
			)
			(layer "F.Fab")
		)
		(fp_line
			(start 0.120396 0.2794)
			(end -0.12065 0.2794)
			(stroke
				(width 0.1)
				(type default)
			)
			(layer "F.Fab")
		)
		(fp_line
			(start 0.120396 0.3048)
			(end 0.120396 0.2794)
			(stroke
				(width 0.1)
				(type default)
			)
			(layer "F.Fab")
		)
		(fp_line
			(start 0.12065 -0.3048)
			(end 0.67945 -0.3048)
			(stroke
				(width 0.1)
				(type default)
			)
			(layer "F.Fab")
		)
		(fp_line
			(start 0.12065 -0.2794)
			(end 0.12065 -0.3048)
			(stroke
				(width 0.1)
				(type default)
			)
			(layer "F.Fab")
		)
		(fp_line
			(start 0.67945 -0.3048)
			(end 0.67945 0.3048)
			(stroke
				(width 0.1)
				(type default)
			)
			(layer "F.Fab")
		)
		(fp_line
			(start 0.67945 0.3048)
			(end 0.120396 0.3048)
			(stroke
				(width 0.1)
				(type default)
			)
			(layer "F.Fab")
		)
		(pad "1" smd circle
			(at -0.40005 0)
			(size 0 0)
			(layers "F.Cu" "F.Mask" "F.Paste")
			(net "P12V_E1S_0_ISENSE_TIC")
		)
		(pad "2" smd circle
			(at 0.40005 0)
			(size 0 0)
			(layers "F.Cu" "F.Mask" "F.Paste")
			(net "GND")
		)
	)
	(footprint ""
		(layer "F.Cu")
		(at 406.124664 -366.437926 180)
		(property "Reference" "R650"
			(at 0 0 180)
			(layer "F.SilkS")
			(hide yes)
			(effects
				(font
					(size 1.27 1.27)
				)
			)
		)
		(property "Value" ""
			(at 0 0 180)
			(layer "F.Fab")
			(effects
				(font
					(size 1.27 1.27)
				)
			)
		)
		(duplicate_pad_numbers_are_jumpers no)
		(fp_line
			(start 0.7874 0.4064)
			(end -0.7874 0.4064)
			(stroke
				(width 0.1524)
				(type default)
			)
			(layer "F.SilkS")
		)
		(fp_line
			(start 0.7874 -0.4064)
			(end 0.7874 0.4064)
			(stroke
				(width 0.1524)
				(type default)
			)
			(layer "F.SilkS")
		)
		(fp_line
			(start -0.7874 0.4064)
			(end -0.7874 -0.4064)
			(stroke
				(width 0.1524)
				(type default)
			)
			(layer "F.SilkS")
		)
		(fp_line
			(start -0.7874 -0.4064)
			(end 0.7874 -0.4064)
			(stroke
				(width 0.1524)
				(type default)
			)
			(layer "F.SilkS")
		)
		(fp_line
			(start 0.67945 0.3048)
			(end 0.120396 0.3048)
			(stroke
				(width 0.1)
				(type default)
			)
			(layer "F.Fab")
		)
		(fp_line
			(start 0.67945 -0.3048)
			(end 0.67945 0.3048)
			(stroke
				(width 0.1)
				(type default)
			)
			(layer "F.Fab")
		)
		(fp_line
			(start 0.12065 -0.2794)
			(end 0.12065 -0.3048)
			(stroke
				(width 0.1)
				(type default)
			)
			(layer "F.Fab")
		)
		(fp_line
			(start 0.12065 -0.3048)
			(end 0.67945 -0.3048)
			(stroke
				(width 0.1)
				(type default)
			)
			(layer "F.Fab")
		)
		(fp_line
			(start 0.120396 0.3048)
			(end 0.120396 0.2794)
			(stroke
				(width 0.1)
				(type default)
			)
			(layer "F.Fab")
		)
		(fp_line
			(start 0.120396 0.2794)
			(end -0.12065 0.2794)
			(stroke
				(width 0.1)
				(type default)
			)
			(layer "F.Fab")
		)
		(fp_line
			(start -0.12065 0.3048)
			(end -0.67945 0.3048)
			(stroke
				(width 0.1)
				(type default)
			)
			(layer "F.Fab")
		)
		(fp_line
			(start -0.12065 0.2794)
			(end -0.12065 0.3048)
			(stroke
				(width 0.1)
				(type default)
			)
			(layer "F.Fab")
		)
		(fp_line
			(start -0.12065 -0.2794)
			(end 0.12065 -0.2794)
			(stroke
				(width 0.1)
				(type default)
			)
			(layer "F.Fab")
		)
		(fp_line
			(start -0.12065 -0.305054)
			(end -0.12065 -0.2794)
			(stroke
				(width 0.1)
				(type default)
			)
			(layer "F.Fab")
		)
		(fp_line
			(start -0.67945 0.3048)
			(end -0.67945 -0.305054)
			(stroke
				(width 0.1)
				(type default)
			)
			(layer "F.Fab")
		)
		(fp_line
			(start -0.67945 -0.305054)
			(end -0.12065 -0.305054)
			(stroke
				(width 0.1)
				(type default)
			)
			(layer "F.Fab")
		)
		(pad "1" smd circle
			(at -0.40005 0 180)
			(size 0 0)
			(layers "F.Cu" "F.Mask" "F.Paste")
			(net "P3V3_AUX")
		)
		(pad "2" smd circle
			(at 0.40005 0 180)
			(size 0 0)
			(layers "F.Cu" "F.Mask" "F.Paste")
			(net "PU_PIROM_CPU0_SM_WP")
		)
	)
	(footprint ""
		(layer "F.Cu")
		(at 68.085716 -114.74069 180)
		(property "Reference" "R3712"
			(at 0 0 180)
			(layer "F.SilkS")
			(hide yes)
			(effects
				(font
					(size 1.27 1.27)
				)
			)
		)
		(property "Value" ""
			(at 0 0 180)
			(layer "F.Fab")
			(effects
				(font
					(size 1.27 1.27)
				)
			)
		)
		(duplicate_pad_numbers_are_jumpers no)
		(fp_line
			(start 0.7874 0.4064)
			(end -0.7874 0.4064)
			(stroke
				(width 0.1524)
				(type default)
			)
			(layer "F.SilkS")
		)
		(fp_line
			(start 0.7874 -0.4064)
			(end 0.7874 0.4064)
			(stroke
				(width 0.1524)
				(type default)
			)
			(layer "F.SilkS")
		)
		(fp_line
			(start -0.7874 0.4064)
			(end -0.7874 -0.4064)
			(stroke
				(width 0.1524)
				(type default)
			)
			(layer "F.SilkS")
		)
		(fp_line
			(start -0.7874 -0.4064)
			(end 0.7874 -0.4064)
			(stroke
				(width 0.1524)
				(type default)
			)
			(layer "F.SilkS")
		)
		(fp_line
			(start 0.67945 0.3048)
			(end 0.120396 0.3048)
			(stroke
				(width 0.1)
				(type default)
			)
			(layer "F.Fab")
		)
		(fp_line
			(start 0.67945 -0.3048)
			(end 0.67945 0.3048)
			(stroke
				(width 0.1)
				(type default)
			)
			(layer "F.Fab")
		)
		(fp_line
			(start 0.12065 -0.2794)
			(end 0.12065 -0.3048)
			(stroke
				(width 0.1)
				(type default)
			)
			(layer "F.Fab")
		)
		(fp_line
			(start 0.12065 -0.3048)
			(end 0.67945 -0.3048)
			(stroke
				(width 0.1)
				(type default)
			)
			(layer "F.Fab")
		)
		(fp_line
			(start 0.120396 0.3048)
			(end 0.120396 0.2794)
			(stroke
				(width 0.1)
				(type default)
			)
			(layer "F.Fab")
		)
		(fp_line
			(start 0.120396 0.2794)
			(end -0.12065 0.2794)
			(stroke
				(width 0.1)
				(type default)
			)
			(layer "F.Fab")
		)
		(fp_line
			(start -0.12065 0.3048)
			(end -0.67945 0.3048)
			(stroke
				(width 0.1)
				(type default)
			)
			(layer "F.Fab")
		)
		(fp_line
			(start -0.12065 0.2794)
			(end -0.12065 0.3048)
			(stroke
				(width 0.1)
				(type default)
			)
			(layer "F.Fab")
		)
		(fp_line
			(start -0.12065 -0.2794)
			(end 0.12065 -0.2794)
			(stroke
				(width 0.1)
				(type default)
			)
			(layer "F.Fab")
		)
		(fp_line
			(start -0.12065 -0.305054)
			(end -0.12065 -0.2794)
			(stroke
				(width 0.1)
				(type default)
			)
			(layer "F.Fab")
		)
		(fp_line
			(start -0.67945 0.3048)
			(end -0.67945 -0.305054)
			(stroke
				(width 0.1)
				(type default)
			)
			(layer "F.Fab")
		)
		(fp_line
			(start -0.67945 -0.305054)
			(end -0.12065 -0.305054)
			(stroke
				(width 0.1)
				(type default)
			)
			(layer "F.Fab")
		)
		(pad "1" smd circle
			(at -0.40005 0 180)
			(size 0 0)
			(layers "F.Cu" "F.Mask" "F.Paste")
			(net "SMB_VR_SENSOR_3V3AUX_SDA")
		)
		(pad "2" smd circle
			(at 0.40005 0 180)
			(size 0 0)
			(layers "F.Cu" "F.Mask" "F.Paste")
			(net "SMB_VR_SENSOR_3V3AUX_SDA_R")
		)
	)
	(footprint ""
		(layer "F.Cu")
		(at 175.4124 -93.538548 90)
		(property "Reference" "R4582"
			(at 0 0 90)
			(layer "F.SilkS")
			(hide yes)
			(effects
				(font
					(size 1.27 1.27)
				)
			)
		)
		(property "Value" ""
			(at 0 0 90)
			(layer "F.Fab")
			(effects
				(font
					(size 1.27 1.27)
				)
			)
		)
		(duplicate_pad_numbers_are_jumpers no)
		(fp_line
			(start 0.7874 -0.4064)
			(end 0.7874 0.4064)
			(stroke
				(width 0.1524)
				(type default)
			)
			(layer "F.SilkS")
		)
		(fp_line
			(start -0.7874 -0.4064)
			(end 0.7874 -0.4064)
			(stroke
				(width 0.1524)
				(type default)
			)
			(layer "F.SilkS")
		)
		(fp_line
			(start 0.7874 0.4064)
			(end -0.7874 0.4064)
			(stroke
				(width 0.1524)
				(type default)
			)
			(layer "F.SilkS")
		)
		(fp_line
			(start -0.7874 0.4064)
			(end -0.7874 -0.4064)
			(stroke
				(width 0.1524)
				(type default)
			)
			(layer "F.SilkS")
		)
		(fp_line
			(start -0.12065 -0.305054)
			(end -0.12065 -0.2794)
			(stroke
				(width 0.1)
				(type default)
			)
			(layer "F.Fab")
		)
		(fp_line
			(start -0.67945 -0.305054)
			(end -0.12065 -0.305054)
			(stroke
				(width 0.1)
				(type default)
			)
			(layer "F.Fab")
		)
		(fp_line
			(start 0.67945 -0.3048)
			(end 0.67945 0.3048)
			(stroke
				(width 0.1)
				(type default)
			)
			(layer "F.Fab")
		)
		(fp_line
			(start 0.12065 -0.3048)
			(end 0.67945 -0.3048)
			(stroke
				(width 0.1)
				(type default)
			)
			(layer "F.Fab")
		)
		(fp_line
			(start 0.12065 -0.2794)
			(end 0.12065 -0.3048)
			(stroke
				(width 0.1)
				(type default)
			)
			(layer "F.Fab")
		)
		(fp_line
			(start -0.12065 -0.2794)
			(end 0.12065 -0.2794)
			(stroke
				(width 0.1)
				(type default)
			)
			(layer "F.Fab")
		)
		(fp_line
			(start 0.120396 0.2794)
			(end -0.12065 0.2794)
			(stroke
				(width 0.1)
				(type default)
			)
			(layer "F.Fab")
		)
		(fp_line
			(start -0.12065 0.2794)
			(end -0.12065 0.3048)
			(stroke
				(width 0.1)
				(type default)
			)
			(layer "F.Fab")
		)
		(fp_line
			(start 0.67945 0.3048)
			(end 0.120396 0.3048)
			(stroke
				(width 0.1)
				(type default)
			)
			(layer "F.Fab")
		)
		(fp_line
			(start 0.120396 0.3048)
			(end 0.120396 0.2794)
			(stroke
				(width 0.1)
				(type default)
			)
			(layer "F.Fab")
		)
		(fp_line
			(start -0.12065 0.3048)
			(end -0.67945 0.3048)
			(stroke
				(width 0.1)
				(type default)
			)
			(layer "F.Fab")
		)
		(fp_line
			(start -0.67945 0.3048)
			(end -0.67945 -0.305054)
			(stroke
				(width 0.1)
				(type default)
			)
			(layer "F.Fab")
		)
		(pad "1" smd rect
			(at -0.40005 0 270)
			(size 0.4572 0.508)
			(layers "F.Cu" "F.Mask" "F.Paste")
			(net "P3V3_AUX")
		)
		(pad "2" smd rect
			(at 0.40005 0 270)
			(size 0.4572 0.508)
			(layers "F.Cu" "F.Mask" "F.Paste")
			(net "FM_BOARD_BMC_SKU_ID1")
		)
	)
	(footprint ""
		(layer "F.Cu")
		(at 30.094428 -102.761034 180)
		(property "Reference" "C1347"
			(at 0 0 180)
			(layer "F.SilkS")
			(hide yes)
			(effects
				(font
					(size 1.27 1.27)
				)
			)
		)
		(property "Value" ""
			(at 0 0 180)
			(layer "F.Fab")
			(effects
				(font
					(size 1.27 1.27)
				)
			)
		)
		(duplicate_pad_numbers_are_jumpers no)
		(fp_line
			(start 0.7874 0.4064)
			(end -0.7874 0.4064)
			(stroke
				(width 0.1524)
				(type default)
			)
			(layer "F.SilkS")
		)
		(fp_line
			(start 0.7874 -0.4064)
			(end 0.7874 0.4064)
			(stroke
				(width 0.1524)
				(type default)
			)
			(layer "F.SilkS")
		)
		(fp_line
			(start -0.7874 0.4064)
			(end -0.7874 -0.4064)
			(stroke
				(width 0.1524)
				(type default)
			)
			(layer "F.SilkS")
		)
		(fp_line
			(start -0.7874 -0.4064)
			(end 0.7874 -0.4064)
			(stroke
				(width 0.1524)
				(type default)
			)
			(layer "F.SilkS")
		)
		(fp_line
			(start 0.67945 0.3048)
			(end 0.120396 0.3048)
			(stroke
				(width 0.1)
				(type default)
			)
			(layer "F.Fab")
		)
		(fp_line
			(start 0.67945 -0.3048)
			(end 0.67945 0.3048)
			(stroke
				(width 0.1)
				(type default)
			)
			(layer "F.Fab")
		)
		(fp_line
			(start 0.12065 -0.2794)
			(end 0.12065 -0.3048)
			(stroke
				(width 0.1)
				(type default)
			)
			(layer "F.Fab")
		)
		(fp_line
			(start 0.12065 -0.3048)
			(end 0.67945 -0.3048)
			(stroke
				(width 0.1)
				(type default)
			)
			(layer "F.Fab")
		)
		(fp_line
			(start 0.120396 0.3048)
			(end 0.120396 0.2794)
			(stroke
				(width 0.1)
				(type default)
			)
			(layer "F.Fab")
		)
		(fp_line
			(start 0.120396 0.2794)
			(end -0.12065 0.2794)
			(stroke
				(width 0.1)
				(type default)
			)
			(layer "F.Fab")
		)
		(fp_line
			(start -0.12065 0.3048)
			(end -0.67945 0.3048)
			(stroke
				(width 0.1)
				(type default)
			)
			(layer "F.Fab")
		)
		(fp_line
			(start -0.12065 0.2794)
			(end -0.12065 0.3048)
			(stroke
				(width 0.1)
				(type default)
			)
			(layer "F.Fab")
		)
		(fp_line
			(start -0.12065 -0.2794)
			(end 0.12065 -0.2794)
			(stroke
				(width 0.1)
				(type default)
			)
			(layer "F.Fab")
		)
		(fp_line
			(start -0.12065 -0.305054)
			(end -0.12065 -0.2794)
			(stroke
				(width 0.1)
				(type default)
			)
			(layer "F.Fab")
		)
		(fp_line
			(start -0.67945 0.3048)
			(end -0.67945 -0.305054)
			(stroke
				(width 0.1)
				(type default)
			)
			(layer "F.Fab")
		)
		(fp_line
			(start -0.67945 -0.305054)
			(end -0.12065 -0.305054)
			(stroke
				(width 0.1)
				(type default)
			)
			(layer "F.Fab")
		)
		(pad "1" smd circle
			(at -0.40005 0 180)
			(size 0 0)
			(layers "F.Cu" "F.Mask" "F.Paste")
			(net "MAX11617_VREF")
		)
		(pad "2" smd circle
			(at 0.40005 0 180)
			(size 0 0)
			(layers "F.Cu" "F.Mask" "F.Paste")
			(net "GND")
		)
	)
	(footprint ""
		(layer "F.Cu")
		(at 11.421618 -106.28249 -90)
		(property "Reference" "R2788"
			(at 0 0 270)
			(layer "F.SilkS")
			(hide yes)
			(effects
				(font
					(size 1.27 1.27)
				)
			)
		)
		(property "Value" ""
			(at 0 0 270)
			(layer "F.Fab")
			(effects
				(font
					(size 1.27 1.27)
				)
			)
		)
		(duplicate_pad_numbers_are_jumpers no)
		(fp_line
			(start 0.7874 0.4064)
			(end -0.7874 0.4064)
			(stroke
				(width 0.1524)
				(type default)
			)
			(layer "F.SilkS")
		)
		(fp_line
			(start -0.7874 -0.4064)
			(end 0.00889 -0.4064)
			(stroke
				(width 0.1524)
				(type default)
			)
			(layer "F.SilkS")
		)
		(fp_line
			(start 0.7874 -0.4064)
			(end 0.7874 0.4064)
			(stroke
				(width 0.1524)
				(type default)
			)
			(layer "F.SilkS")
		)
		(fp_line
			(start -0.67945 0.3048)
			(end -0.67945 -0.305054)
			(stroke
				(width 0.1)
				(type default)
			)
			(layer "F.Fab")
		)
		(fp_line
			(start -0.12065 0.3048)
			(end -0.67945 0.3048)
			(stroke
				(width 0.1)
				(type default)
			)
			(layer "F.Fab")
		)
		(fp_line
			(start 0.120396 0.3048)
			(end 0.120396 0.2794)
			(stroke
				(width 0.1)
				(type default)
			)
			(layer "F.Fab")
		)
		(fp_line
			(start 0.67945 0.3048)
			(end 0.120396 0.3048)
			(stroke
				(width 0.1)
				(type default)
			)
			(layer "F.Fab")
		)
		(fp_line
			(start -0.12065 0.2794)
			(end -0.12065 0.3048)
			(stroke
				(width 0.1)
				(type default)
			)
			(layer "F.Fab")
		)
		(fp_line
			(start 0.120396 0.2794)
			(end -0.12065 0.2794)
			(stroke
				(width 0.1)
				(type default)
			)
			(layer "F.Fab")
		)
		(fp_line
			(start -0.12065 -0.2794)
			(end 0.12065 -0.2794)
			(stroke
				(width 0.1)
				(type default)
			)
			(layer "F.Fab")
		)
		(fp_line
			(start 0.12065 -0.2794)
			(end 0.12065 -0.3048)
			(stroke
				(width 0.1)
				(type default)
			)
			(layer "F.Fab")
		)
		(fp_line
			(start 0.12065 -0.3048)
			(end 0.67945 -0.3048)
			(stroke
				(width 0.1)
				(type default)
			)
			(layer "F.Fab")
		)
		(fp_line
			(start 0.67945 -0.3048)
			(end 0.67945 0.3048)
			(stroke
				(width 0.1)
				(type default)
			)
			(layer "F.Fab")
		)
		(fp_line
			(start -0.67945 -0.305054)
			(end -0.12065 -0.305054)
			(stroke
				(width 0.1)
				(type default)
			)
			(layer "F.Fab")
		)
		(fp_line
			(start -0.12065 -0.305054)
			(end -0.12065 -0.2794)
			(stroke
				(width 0.1)
				(type default)
			)
			(layer "F.Fab")
		)
		(pad "1" smd rect
			(at -0.40005 0 90)
			(size 0.4572 0.508)
			(layers "F.Cu" "F.Mask" "F.Paste")
			(net "USB2_HOST_BMC_B_BUF_DP")
		)
		(pad "2" smd rect
			(at 0.40005 0 90)
			(size 0.4572 0.508)
			(layers "F.Cu" "F.Mask" "F.Paste")
			(net "USB2_HUB_BUF_SWB_R_DP")
		)
	)
	(footprint ""
		(layer "F.Cu")
		(at 118.542816 -255.0541 90)
		(property "Reference" "C244"
			(at 0 0 90)
			(layer "F.SilkS")
			(hide yes)
			(effects
				(font
					(size 1.27 1.27)
				)
			)
		)
		(property "Value" ""
			(at 0 0 90)
			(layer "F.Fab")
			(effects
				(font
					(size 1.27 1.27)
				)
			)
		)
		(duplicate_pad_numbers_are_jumpers no)
		(fp_line
			(start 0.7874 -0.4064)
			(end 0.7874 0.4064)
			(stroke
				(width 0.1524)
				(type default)
			)
			(layer "F.SilkS")
		)
		(fp_line
			(start -0.7874 -0.4064)
			(end 0.7874 -0.4064)
			(stroke
				(width 0.1524)
				(type default)
			)
			(layer "F.SilkS")
		)
		(fp_line
			(start 0.7874 0.4064)
			(end -0.7874 0.4064)
			(stroke
				(width 0.1524)
				(type default)
			)
			(layer "F.SilkS")
		)
		(fp_line
			(start -0.7874 0.4064)
			(end -0.7874 -0.4064)
			(stroke
				(width 0.1524)
				(type default)
			)
			(layer "F.SilkS")
		)
		(fp_line
			(start -0.12065 -0.305054)
			(end -0.12065 -0.2794)
			(stroke
				(width 0.1)
				(type default)
			)
			(layer "F.Fab")
		)
		(fp_line
			(start -0.67945 -0.305054)
			(end -0.12065 -0.305054)
			(stroke
				(width 0.1)
				(type default)
			)
			(layer "F.Fab")
		)
		(fp_line
			(start 0.67945 -0.3048)
			(end 0.67945 0.3048)
			(stroke
				(width 0.1)
				(type default)
			)
			(layer "F.Fab")
		)
		(fp_line
			(start 0.12065 -0.3048)
			(end 0.67945 -0.3048)
			(stroke
				(width 0.1)
				(type default)
			)
			(layer "F.Fab")
		)
		(fp_line
			(start 0.12065 -0.2794)
			(end 0.12065 -0.3048)
			(stroke
				(width 0.1)
				(type default)
			)
			(layer "F.Fab")
		)
		(fp_line
			(start -0.12065 -0.2794)
			(end 0.12065 -0.2794)
			(stroke
				(width 0.1)
				(type default)
			)
			(layer "F.Fab")
		)
		(fp_line
			(start 0.120396 0.2794)
			(end -0.12065 0.2794)
			(stroke
				(width 0.1)
				(type default)
			)
			(layer "F.Fab")
		)
		(fp_line
			(start -0.12065 0.2794)
			(end -0.12065 0.3048)
			(stroke
				(width 0.1)
				(type default)
			)
			(layer "F.Fab")
		)
		(fp_line
			(start 0.67945 0.3048)
			(end 0.120396 0.3048)
			(stroke
				(width 0.1)
				(type default)
			)
			(layer "F.Fab")
		)
		(fp_line
			(start 0.120396 0.3048)
			(end 0.120396 0.2794)
			(stroke
				(width 0.1)
				(type default)
			)
			(layer "F.Fab")
		)
		(fp_line
			(start -0.12065 0.3048)
			(end -0.67945 0.3048)
			(stroke
				(width 0.1)
				(type default)
			)
			(layer "F.Fab")
		)
		(fp_line
			(start -0.67945 0.3048)
			(end -0.67945 -0.305054)
			(stroke
				(width 0.1)
				(type default)
			)
			(layer "F.Fab")
		)
		(pad "1" smd circle
			(at -0.40005 0 90)
			(size 0 0)
			(layers "F.Cu" "F.Mask" "F.Paste")
			(net "PVCCIN_CPU1")
		)
		(pad "2" smd circle
			(at 0.40005 0 90)
			(size 0 0)
			(layers "F.Cu" "F.Mask" "F.Paste")
			(net "GND")
		)
	)
	(footprint ""
		(layer "F.Cu")
		(at 302.768 -46.319948)
		(property "Reference" "C1248"
			(at 0 0 0)
			(layer "F.SilkS")
			(hide yes)
			(effects
				(font
					(size 1.27 1.27)
				)
			)
		)
		(property "Value" ""
			(at 0 0 0)
			(layer "F.Fab")
			(effects
				(font
					(size 1.27 1.27)
				)
			)
		)
		(duplicate_pad_numbers_are_jumpers no)
		(fp_line
			(start -1.524 -0.762)
			(end 1.524 -0.762)
			(stroke
				(width 0.1524)
				(type default)
			)
			(layer "F.SilkS")
		)
		(fp_line
			(start -1.524 0.762)
			(end -1.524 -0.762)
			(stroke
				(width 0.1524)
				(type default)
			)
			(layer "F.SilkS")
		)
		(fp_line
			(start 1.524 -0.762)
			(end 1.524 0.762)
			(stroke
				(width 0.1524)
				(type default)
			)
			(layer "F.SilkS")
		)
		(fp_line
			(start 1.524 0.762)
			(end -1.524 0.762)
			(stroke
				(width 0.1524)
				(type default)
			)
			(layer "F.SilkS")
		)
		(fp_line
			(start -1.1049 -0.724916)
			(end -1.1049 0.724916)
			(stroke
				(width 0.1)
				(type default)
			)
			(layer "F.Fab")
		)
		(fp_line
			(start -1.1049 0.724916)
			(end 1.1049 0.724916)
			(stroke
				(width 0.1)
				(type default)
			)
			(layer "F.Fab")
		)
		(fp_line
			(start 1.1049 -0.724916)
			(end -1.1049 -0.724916)
			(stroke
				(width 0.1)
				(type default)
			)
			(layer "F.Fab")
		)
		(fp_line
			(start 1.1049 0.724916)
			(end 1.1049 -0.724916)
			(stroke
				(width 0.1)
				(type default)
			)
			(layer "F.Fab")
		)
		(pad "1" smd rect
			(at -0.889 0 180)
			(size 1.016 1.27)
			(layers "F.Cu" "F.Mask" "F.Paste")
			(net "P1V05_PCH_AUX")
		)
		(pad "2" smd rect
			(at 0.889 0 180)
			(size 1.016 1.27)
			(layers "F.Cu" "F.Mask" "F.Paste")
			(net "GND")
		)
	)
	(footprint ""
		(layer "F.Cu")
		(at 160.86328 -258.091686)
		(property "Reference" "J26"
			(at -3.683 -81.702148 0)
			(unlocked yes)
			(layer "F.SilkS")
			(effects
				(font
					(size 0.7874 0.5842)
					(thickness 0.1524)
				)
				(justify left)
			)
		)
		(property "Value" ""
			(at 0 0 0)
			(layer "F.Fab")
			(effects
				(font
					(size 1.27 1.27)
				)
			)
		)
		(duplicate_pad_numbers_are_jumpers no)
		(fp_line
			(start -3.24993 -81.000092)
			(end -3.24993 81.000092)
			(stroke
				(width 0.1524)
				(type default)
			)
			(layer "F.SilkS")
		)
		(fp_line
			(start -3.24993 81.000092)
			(end 3.24993 81.000092)
			(stroke
				(width 0.1524)
				(type default)
			)
			(layer "F.SilkS")
		)
		(fp_line
			(start 3.24993 -81.000092)
			(end -3.24993 -81.000092)
			(stroke
				(width 0.1524)
				(type default)
			)
			(layer "F.SilkS")
		)
		(fp_line
			(start 3.24993 -72.00011)
			(end -3.24993 -72.00011)
			(stroke
				(width 0.1524)
				(type default)
			)
			(layer "F.SilkS")
		)
		(fp_line
			(start 3.24993 72.00011)
			(end -3.24993 72.00011)
			(stroke
				(width 0.1524)
				(type default)
			)
			(layer "F.SilkS")
		)
		(fp_line
			(start 3.24993 81.000092)
			(end 3.24993 -81.000092)
			(stroke
				(width 0.1524)
				(type default)
			)
			(layer "F.SilkS")
		)
		(fp_poly
			(pts
				(xy -4.445 -63.832994) (xy -4.445 -62.816994) (xy -3.429 -63.324994)
			)
			(stroke
				(width 0)
				(type default)
			)
			(fill yes)
			(layer "F.SilkS")
		)
		(fp_line
			(start -3.24993 -81.000092)
			(end -3.24993 81.000092)
			(stroke
				(width 0.1)
				(type default)
			)
			(layer "F.Fab")
		)
		(fp_line
			(start -3.24993 81.000092)
			(end 3.24993 81.000092)
			(stroke
				(width 0.1)
				(type default)
			)
			(layer "F.Fab")
		)
		(fp_line
			(start 3.24993 -81.000092)
			(end -3.24993 -81.000092)
			(stroke
				(width 0.1)
				(type default)
			)
			(layer "F.Fab")
		)
		(fp_line
			(start 3.24993 -72.00011)
			(end -3.24993 -72.00011)
			(stroke
				(width 0.1)
				(type default)
			)
			(layer "F.Fab")
		)
		(fp_line
			(start 3.24993 -71.000112)
			(end -3.24993 -71.000112)
			(stroke
				(width 0.1)
				(type default)
			)
			(layer "F.Fab")
		)
		(fp_line
			(start 3.24993 71.000112)
			(end -3.24993 71.000112)
			(stroke
				(width 0.1)
				(type default)
			)
			(layer "F.Fab")
		)
		(fp_line
			(start 3.24993 72.00011)
			(end -3.24993 72.00011)
			(stroke
				(width 0.1)
				(type default)
			)
			(layer "F.Fab")
		)
		(fp_line
			(start 3.24993 81.000092)
			(end 3.24993 -81.000092)
			(stroke
				(width 0.1)
				(type default)
			)
			(layer "F.Fab")
		)
		(fp_poly
			(pts
				(xy -4.445 -63.832994) (xy -4.445 -62.816994) (xy -3.429 -63.324994)
			)
			(stroke
				(width 0)
				(type default)
			)
			(fill yes)
			(layer "F.Fab")
		)
		(pad "1" smd rect
			(at -2.050034 -63.324994 270)
			(size 0.519938 1.4986)
			(layers "F.Cu" "F.Mask" "F.Paste")
			(net "P12V_S3_AUX_CPU1_NVDIMM")
		)
		(pad "2" smd rect
			(at -2.050034 -62.47511 270)
			(size 0.519938 1.4986)
			(layers "F.Cu" "F.Mask" "F.Paste")
			(net "TP_CHE_CPU1_DIMM2_FRU_0")
		)
		(pad "3" smd rect
			(at -2.050034 -61.624972 270)
			(size 0.519938 1.4986)
			(layers "F.Cu" "F.Mask" "F.Paste")
			(net "P3V3_AUX")
		)
		(pad "4" smd rect
			(at -2.050034 -60.775088 270)
			(size 0.519938 1.4986)
			(layers "F.Cu" "F.Mask" "F.Paste")
			(net "I3C_SPD_DDREFGH_CPU1_LVC1_SCL_1")
		)
		(pad "5" smd rect
			(at -2.050034 -59.92495 270)
			(size 0.519938 1.4986)
			(layers "F.Cu" "F.Mask" "F.Paste")
			(net "I3C_SPD_DDREFGH_CPU1_LVC1_SDA")
		)
		(pad "6" smd rect
			(at -2.050034 -59.075066 270)
			(size 0.519938 1.4986)
			(layers "F.Cu" "F.Mask" "F.Paste")
			(net "GND")
		)
		(pad "7" smd rect
			(at -2.050034 -58.224928 270)
			(size 0.519938 1.4986)
			(layers "F.Cu" "F.Mask" "F.Paste")
			(net "M_E_CPU1_SA_DQ<0>")
		)
		(pad "8" smd rect
			(at -2.050034 -57.375044 270)
			(size 0.519938 1.4986)
			(layers "F.Cu" "F.Mask" "F.Paste")
			(net "GND")
		)
		(pad "9" smd rect
			(at -2.050034 -56.524906 270)
			(size 0.519938 1.4986)
			(layers "F.Cu" "F.Mask" "F.Paste")
			(net "M_E_CPU1_SA_DQ<1>")
		)
		(pad "10" smd rect
			(at -2.050034 -55.675022 270)
			(size 0.519938 1.4986)
			(layers "F.Cu" "F.Mask" "F.Paste")
			(net "GND")
		)
		(pad "11" smd rect
			(at -2.050034 -54.824884 270)
			(size 0.519938 1.4986)
			(layers "F.Cu" "F.Mask" "F.Paste")
			(net "M_E_CPU1_SA_DQS_DP<0>")
		)
		(pad "12" smd rect
			(at -2.050034 -53.975 270)
			(size 0.519938 1.4986)
			(layers "F.Cu" "F.Mask" "F.Paste")
			(net "M_E_CPU1_SA_DQS_DN<0>")
		)
		(pad "13" smd rect
			(at -2.050034 -53.125116 270)
			(size 0.519938 1.4986)
			(layers "F.Cu" "F.Mask" "F.Paste")
			(net "GND")
		)
		(pad "14" smd rect
			(at -2.050034 -52.274978 270)
			(size 0.519938 1.4986)
			(layers "F.Cu" "F.Mask" "F.Paste")
			(net "M_E_CPU1_SA_DQ<4>")
		)
		(pad "15" smd rect
			(at -2.050034 -51.425094 270)
			(size 0.519938 1.4986)
			(layers "F.Cu" "F.Mask" "F.Paste")
			(net "GND")
		)
		(pad "16" smd rect
			(at -2.050034 -50.574956 270)
			(size 0.519938 1.4986)
			(layers "F.Cu" "F.Mask" "F.Paste")
			(net "M_E_CPU1_SA_DQ<5>")
		)
		(pad "17" smd rect
			(at -2.050034 -49.725072 270)
			(size 0.519938 1.4986)
			(layers "F.Cu" "F.Mask" "F.Paste")
			(net "GND")
		)
		(pad "18" smd rect
			(at -2.050034 -48.874934 270)
			(size 0.519938 1.4986)
			(layers "F.Cu" "F.Mask" "F.Paste")
			(net "M_E_CPU1_SA_DQ<8>")
		)
		(pad "19" smd rect
			(at -2.050034 -48.02505 270)
			(size 0.519938 1.4986)
			(layers "F.Cu" "F.Mask" "F.Paste")
			(net "GND")
		)
		(pad "20" smd rect
			(at -2.050034 -47.174912 270)
			(size 0.519938 1.4986)
			(layers "F.Cu" "F.Mask" "F.Paste")
			(net "M_E_CPU1_SA_DQ<9>")
		)
		(pad "21" smd rect
			(at -2.050034 -46.325028 270)
			(size 0.519938 1.4986)
			(layers "F.Cu" "F.Mask" "F.Paste")
			(net "GND")
		)
		(pad "22" smd rect
			(at -2.050034 -45.47489 270)
			(size 0.519938 1.4986)
			(layers "F.Cu" "F.Mask" "F.Paste")
			(net "M_E_CPU1_SA_DQS_DP<1>")
		)
		(pad "23" smd rect
			(at -2.050034 -44.625006 270)
			(size 0.519938 1.4986)
			(layers "F.Cu" "F.Mask" "F.Paste")
			(net "M_E_CPU1_SA_DQS_DN<1>")
		)
		(pad "24" smd rect
			(at -2.050034 -43.775122 270)
			(size 0.519938 1.4986)
			(layers "F.Cu" "F.Mask" "F.Paste")
			(net "GND")
		)
		(pad "25" smd rect
			(at -2.050034 -42.924984 270)
			(size 0.519938 1.4986)
			(layers "F.Cu" "F.Mask" "F.Paste")
			(net "M_E_CPU1_SA_DQ<12>")
		)
		(pad "26" smd rect
			(at -2.050034 -42.0751 270)
			(size 0.519938 1.4986)
			(layers "F.Cu" "F.Mask" "F.Paste")
			(net "GND")
		)
		(pad "27" smd rect
			(at -2.050034 -41.224962 270)
			(size 0.519938 1.4986)
			(layers "F.Cu" "F.Mask" "F.Paste")
			(net "M_E_CPU1_SA_DQ<13>")
		)
		(pad "28" smd rect
			(at -2.050034 -40.375078 270)
			(size 0.519938 1.4986)
			(layers "F.Cu" "F.Mask" "F.Paste")
			(net "GND")
		)
		(pad "29" smd rect
			(at -2.050034 -39.52494 270)
			(size 0.519938 1.4986)
			(layers "F.Cu" "F.Mask" "F.Paste")
			(net "M_E_CPU1_SA_DQ<16>")
		)
		(pad "30" smd rect
			(at -2.050034 -38.675056 270)
			(size 0.519938 1.4986)
			(layers "F.Cu" "F.Mask" "F.Paste")
			(net "GND")
		)
		(pad "31" smd rect
			(at -2.050034 -37.824918 270)
			(size 0.519938 1.4986)
			(layers "F.Cu" "F.Mask" "F.Paste")
			(net "M_E_CPU1_SA_DQ<17>")
		)
		(pad "32" smd rect
			(at -2.050034 -36.975034 270)
			(size 0.519938 1.4986)
			(layers "F.Cu" "F.Mask" "F.Paste")
			(net "GND")
		)
		(pad "33" smd rect
			(at -2.050034 -36.124896 270)
			(size 0.519938 1.4986)
			(layers "F.Cu" "F.Mask" "F.Paste")
			(net "M_E_CPU1_SA_DQS_DP<2>")
		)
		(pad "34" smd rect
			(at -2.050034 -35.275012 270)
			(size 0.519938 1.4986)
			(layers "F.Cu" "F.Mask" "F.Paste")
			(net "M_E_CPU1_SA_DQS_DN<2>")
		)
		(pad "35" smd rect
			(at -2.050034 -34.425128 270)
			(size 0.519938 1.4986)
			(layers "F.Cu" "F.Mask" "F.Paste")
			(net "GND")
		)
		(pad "36" smd rect
			(at -2.050034 -33.57499 270)
			(size 0.519938 1.4986)
			(layers "F.Cu" "F.Mask" "F.Paste")
			(net "M_E_CPU1_SA_DQ<20>")
		)
		(pad "37" smd rect
			(at -2.050034 -32.725106 270)
			(size 0.519938 1.4986)
			(layers "F.Cu" "F.Mask" "F.Paste")
			(net "GND")
		)
		(pad "38" smd rect
			(at -2.050034 -31.874968 270)
			(size 0.519938 1.4986)
			(layers "F.Cu" "F.Mask" "F.Paste")
			(net "M_E_CPU1_SA_DQ<21>")
		)
		(pad "39" smd rect
			(at -2.050034 -31.025084 270)
			(size 0.519938 1.4986)
			(layers "F.Cu" "F.Mask" "F.Paste")
			(net "GND")
		)
		(pad "40" smd rect
			(at -2.050034 -30.174946 270)
			(size 0.519938 1.4986)
			(layers "F.Cu" "F.Mask" "F.Paste")
			(net "M_E_CPU1_SA_DQ<24>")
		)
		(pad "41" smd rect
			(at -2.050034 -29.325062 270)
			(size 0.519938 1.4986)
			(layers "F.Cu" "F.Mask" "F.Paste")
			(net "GND")
		)
		(pad "42" smd rect
			(at -2.050034 -28.474924 270)
			(size 0.519938 1.4986)
			(layers "F.Cu" "F.Mask" "F.Paste")
			(net "M_E_CPU1_SA_DQ<25>")
		)
		(pad "43" smd rect
			(at -2.050034 -27.62504 270)
			(size 0.519938 1.4986)
			(layers "F.Cu" "F.Mask" "F.Paste")
			(net "GND")
		)
		(pad "44" smd rect
			(at -2.050034 -26.774902 270)
			(size 0.519938 1.4986)
			(layers "F.Cu" "F.Mask" "F.Paste")
			(net "M_E_CPU1_SA_DQS_DP<3>")
		)
		(pad "45" smd rect
			(at -2.050034 -25.925018 270)
			(size 0.519938 1.4986)
			(layers "F.Cu" "F.Mask" "F.Paste")
			(net "M_E_CPU1_SA_DQS_DN<3>")
		)
		(pad "46" smd rect
			(at -2.050034 -25.07488 270)
			(size 0.519938 1.4986)
			(layers "F.Cu" "F.Mask" "F.Paste")
			(net "GND")
		)
		(pad "47" smd rect
			(at -2.050034 -24.224996 270)
			(size 0.519938 1.4986)
			(layers "F.Cu" "F.Mask" "F.Paste")
			(net "M_E_CPU1_SA_DQ<28>")
		)
		(pad "48" smd rect
			(at -2.050034 -23.375112 270)
			(size 0.519938 1.4986)
			(layers "F.Cu" "F.Mask" "F.Paste")
			(net "GND")
		)
		(pad "49" smd rect
			(at -2.050034 -22.524974 270)
			(size 0.519938 1.4986)
			(layers "F.Cu" "F.Mask" "F.Paste")
			(net "M_E_CPU1_SA_DQ<29>")
		)
		(pad "50" smd rect
			(at -2.050034 -21.67509 270)
			(size 0.519938 1.4986)
			(layers "F.Cu" "F.Mask" "F.Paste")
			(net "GND")
		)
		(pad "51" smd rect
			(at -2.050034 -20.824952 270)
			(size 0.519938 1.4986)
			(layers "F.Cu" "F.Mask" "F.Paste")
			(net "M_E_CPU1_SA_CB<0>")
		)
		(pad "52" smd rect
			(at -2.050034 -19.975068 270)
			(size 0.519938 1.4986)
			(layers "F.Cu" "F.Mask" "F.Paste")
			(net "GND")
		)
		(pad "53" smd rect
			(at -2.050034 -19.12493 270)
			(size 0.519938 1.4986)
			(layers "F.Cu" "F.Mask" "F.Paste")
			(net "M_E_CPU1_SA_CB<1>")
		)
		(pad "54" smd rect
			(at -2.050034 -18.275046 270)
			(size 0.519938 1.4986)
			(layers "F.Cu" "F.Mask" "F.Paste")
			(net "GND")
		)
		(pad "55" smd rect
			(at -2.050034 -17.424908 270)
			(size 0.519938 1.4986)
			(layers "F.Cu" "F.Mask" "F.Paste")
			(net "M_E_CPU1_SA_DQS_DP<4>")
		)
		(pad "56" smd rect
			(at -2.050034 -16.575024 270)
			(size 0.519938 1.4986)
			(layers "F.Cu" "F.Mask" "F.Paste")
			(net "M_E_CPU1_SA_DQS_DN<4>")
		)
		(pad "57" smd rect
			(at -2.050034 -15.724886 270)
			(size 0.519938 1.4986)
			(layers "F.Cu" "F.Mask" "F.Paste")
			(net "GND")
		)
		(pad "58" smd rect
			(at -2.050034 -14.875002 270)
			(size 0.519938 1.4986)
			(layers "F.Cu" "F.Mask" "F.Paste")
			(net "M_E_CPU1_SA_CB<4>")
		)
		(pad "59" smd rect
			(at -2.050034 -14.025118 270)
			(size 0.519938 1.4986)
			(layers "F.Cu" "F.Mask" "F.Paste")
			(net "GND")
		)
		(pad "60" smd rect
			(at -2.050034 -13.17498 270)
			(size 0.519938 1.4986)
			(layers "F.Cu" "F.Mask" "F.Paste")
			(net "M_E_CPU1_SA_CB<5>")
		)
		(pad "61" smd rect
			(at -2.050034 -12.325096 270)
			(size 0.519938 1.4986)
			(layers "F.Cu" "F.Mask" "F.Paste")
			(net "GND")
		)
		(pad "62" smd rect
			(at -2.050034 -11.474958 270)
			(size 0.519938 1.4986)
			(layers "F.Cu" "F.Mask" "F.Paste")
			(net "M_E_CPU1_ALERT_N")
		)
		(pad "63" smd rect
			(at -2.050034 -10.625074 270)
			(size 0.519938 1.4986)
			(layers "F.Cu" "F.Mask" "F.Paste")
			(net "GND")
		)
		(pad "64" smd rect
			(at -2.050034 -9.774936 270)
			(size 0.519938 1.4986)
			(layers "F.Cu" "F.Mask" "F.Paste")
			(net "M_E_CPU1_SA_CS_N<2>")
		)
		(pad "65" smd rect
			(at -2.050034 -8.925052 270)
			(size 0.519938 1.4986)
			(layers "F.Cu" "F.Mask" "F.Paste")
			(net "GND")
		)
		(pad "66" smd rect
			(at -2.050034 -8.074914 270)
			(size 0.519938 1.4986)
			(layers "F.Cu" "F.Mask" "F.Paste")
			(net "M_E_CPU1_SA_CA<0>")
		)
		(pad "67" smd rect
			(at -2.050034 -7.22503 270)
			(size 0.519938 1.4986)
			(layers "F.Cu" "F.Mask" "F.Paste")
			(net "GND")
		)
		(pad "68" smd rect
			(at -2.050034 -6.374892 270)
			(size 0.519938 1.4986)
			(layers "F.Cu" "F.Mask" "F.Paste")
			(net "M_E_CPU1_SA_CA<2>")
		)
		(pad "69" smd rect
			(at -2.050034 -5.525008 270)
			(size 0.519938 1.4986)
			(layers "F.Cu" "F.Mask" "F.Paste")
			(net "GND")
		)
		(pad "70" smd rect
			(at -2.050034 -4.675124 270)
			(size 0.519938 1.4986)
			(layers "F.Cu" "F.Mask" "F.Paste")
			(net "M_E_CPU1_SA_CA<4>")
		)
		(pad "71" smd rect
			(at -2.050034 -3.824986 270)
			(size 0.519938 1.4986)
			(layers "F.Cu" "F.Mask" "F.Paste")
			(net "GND")
		)
		(pad "72" smd rect
			(at -2.050034 -2.975102 270)
			(size 0.519938 1.4986)
			(layers "F.Cu" "F.Mask" "F.Paste")
			(net "M_E_CPU1_SA_CA<6>")
		)
		(pad "73" smd rect
			(at -2.050034 -2.124964 270)
			(size 0.519938 1.4986)
			(layers "F.Cu" "F.Mask" "F.Paste")
			(net "GND")
		)
		(pad "74" smd rect
			(at -2.050034 -1.27508 270)
			(size 0.519938 1.4986)
			(layers "F.Cu" "F.Mask" "F.Paste")
			(net "M_E_CPU1_SA_PAR")
		)
		(pad "75" smd rect
			(at -2.050034 -0.424942 270)
			(size 0.519938 1.4986)
			(layers "F.Cu" "F.Mask" "F.Paste")
			(net "GND")
		)
		(pad "76" smd rect
			(at -2.050034 5.525008 270)
			(size 0.519938 1.4986)
			(layers "F.Cu" "F.Mask" "F.Paste")
			(net "M_E_CPU1_SB_CA<0>")
		)
		(pad "77" smd rect
			(at -2.050034 6.374892 270)
			(size 0.519938 1.4986)
			(layers "F.Cu" "F.Mask" "F.Paste")
			(net "GND")
		)
		(pad "78" smd rect
			(at -2.050034 7.22503 270)
			(size 0.519938 1.4986)
			(layers "F.Cu" "F.Mask" "F.Paste")
			(net "M_E_CPU1_SB_CA<2>")
		)
		(pad "79" smd rect
			(at -2.050034 8.074914 270)
			(size 0.519938 1.4986)
			(layers "F.Cu" "F.Mask" "F.Paste")
			(net "GND")
		)
		(pad "80" smd rect
			(at -2.050034 8.925052 270)
			(size 0.519938 1.4986)
			(layers "F.Cu" "F.Mask" "F.Paste")
			(net "M_E_CPU1_SB_CA<4>")
		)
		(pad "81" smd rect
			(at -2.050034 9.774936 270)
			(size 0.519938 1.4986)
			(layers "F.Cu" "F.Mask" "F.Paste")
			(net "GND")
		)
		(pad "82" smd rect
			(at -2.050034 10.625074 270)
			(size 0.519938 1.4986)
			(layers "F.Cu" "F.Mask" "F.Paste")
			(net "M_E_CPU1_SB_CA<6>")
		)
		(pad "83" smd rect
			(at -2.050034 11.474958 270)
			(size 0.519938 1.4986)
			(layers "F.Cu" "F.Mask" "F.Paste")
			(net "GND")
		)
		(pad "84" smd rect
			(at -2.050034 12.325096 270)
			(size 0.519938 1.4986)
			(layers "F.Cu" "F.Mask" "F.Paste")
			(net "M_E_CPU1_SB_CS_N<2>")
		)
		(pad "85" smd rect
			(at -2.050034 13.17498 270)
			(size 0.519938 1.4986)
			(layers "F.Cu" "F.Mask" "F.Paste")
			(net "GND")
		)
		(pad "86" smd rect
			(at -2.050034 14.025118 270)
			(size 0.519938 1.4986)
			(layers "F.Cu" "F.Mask" "F.Paste")
			(net "M_E_CPU1_SA_RSP<1>")
		)
		(pad "87" smd rect
			(at -2.050034 14.875002 270)
			(size 0.519938 1.4986)
			(layers "F.Cu" "F.Mask" "F.Paste")
			(net "M_E_CPU1_SB_RSP<1>")
		)
		(pad "88" smd rect
			(at -2.050034 15.724886 270)
			(size 0.519938 1.4986)
			(layers "F.Cu" "F.Mask" "F.Paste")
			(net "GND")
		)
		(pad "89" smd rect
			(at -2.050034 16.575024 270)
			(size 0.519938 1.4986)
			(layers "F.Cu" "F.Mask" "F.Paste")
			(net "M_E_CPU1_SB_CB<4>")
		)
		(pad "90" smd rect
			(at -2.050034 17.424908 270)
			(size 0.519938 1.4986)
			(layers "F.Cu" "F.Mask" "F.Paste")
			(net "GND")
		)
		(pad "91" smd rect
			(at -2.050034 18.275046 270)
			(size 0.519938 1.4986)
			(layers "F.Cu" "F.Mask" "F.Paste")
			(net "M_E_CPU1_SB_CB<5>")
		)
		(pad "92" smd rect
			(at -2.050034 19.12493 270)
			(size 0.519938 1.4986)
			(layers "F.Cu" "F.Mask" "F.Paste")
			(net "GND")
		)
		(pad "93" smd rect
			(at -2.050034 19.975068 270)
			(size 0.519938 1.4986)
			(layers "F.Cu" "F.Mask" "F.Paste")
			(net "M_E_CPU1_SB_DQS_DP<9>")
		)
		(pad "94" smd rect
			(at -2.050034 20.824952 270)
			(size 0.519938 1.4986)
			(layers "F.Cu" "F.Mask" "F.Paste")
			(net "M_E_CPU1_SB_DQS_DN<9>")
		)
		(pad "95" smd rect
			(at -2.050034 21.67509 270)
			(size 0.519938 1.4986)
			(layers "F.Cu" "F.Mask" "F.Paste")
			(net "GND")
		)
		(pad "96" smd rect
			(at -2.050034 22.524974 270)
			(size 0.519938 1.4986)
			(layers "F.Cu" "F.Mask" "F.Paste")
			(net "M_E_CPU1_SB_CB<0>")
		)
		(pad "97" smd rect
			(at -2.050034 23.375112 270)
			(size 0.519938 1.4986)
			(layers "F.Cu" "F.Mask" "F.Paste")
			(net "GND")
		)
		(pad "98" smd rect
			(at -2.050034 24.224996 270)
			(size 0.519938 1.4986)
			(layers "F.Cu" "F.Mask" "F.Paste")
			(net "M_E_CPU1_SB_CB<1>")
		)
		(pad "99" smd rect
			(at -2.050034 25.07488 270)
			(size 0.519938 1.4986)
			(layers "F.Cu" "F.Mask" "F.Paste")
			(net "GND")
		)
		(pad "100" smd rect
			(at -2.050034 25.925018 270)
			(size 0.519938 1.4986)
			(layers "F.Cu" "F.Mask" "F.Paste")
			(net "M_E_CPU1_SB_DQ<0>")
		)
		(pad "101" smd rect
			(at -2.050034 26.774902 270)
			(size 0.519938 1.4986)
			(layers "F.Cu" "F.Mask" "F.Paste")
			(net "GND")
		)
		(pad "102" smd rect
			(at -2.050034 27.62504 270)
			(size 0.519938 1.4986)
			(layers "F.Cu" "F.Mask" "F.Paste")
			(net "M_E_CPU1_SB_DQ<1>")
		)
		(pad "103" smd rect
			(at -2.050034 28.474924 270)
			(size 0.519938 1.4986)
			(layers "F.Cu" "F.Mask" "F.Paste")
			(net "GND")
		)
		(pad "104" smd rect
			(at -2.050034 29.325062 270)
			(size 0.519938 1.4986)
			(layers "F.Cu" "F.Mask" "F.Paste")
			(net "M_E_CPU1_SB_DQS_DP<0>")
		)
		(pad "105" smd rect
			(at -2.050034 30.174946 270)
			(size 0.519938 1.4986)
			(layers "F.Cu" "F.Mask" "F.Paste")
			(net "M_E_CPU1_SB_DQS_DN<0>")
		)
		(pad "106" smd rect
			(at -2.050034 31.025084 270)
			(size 0.519938 1.4986)
			(layers "F.Cu" "F.Mask" "F.Paste")
			(net "GND")
		)
		(pad "107" smd rect
			(at -2.050034 31.874968 270)
			(size 0.519938 1.4986)
			(layers "F.Cu" "F.Mask" "F.Paste")
			(net "M_E_CPU1_SB_DQ<4>")
		)
		(pad "108" smd rect
			(at -2.050034 32.725106 270)
			(size 0.519938 1.4986)
			(layers "F.Cu" "F.Mask" "F.Paste")
			(net "GND")
		)
		(pad "109" smd rect
			(at -2.050034 33.57499 270)
			(size 0.519938 1.4986)
			(layers "F.Cu" "F.Mask" "F.Paste")
			(net "M_E_CPU1_SB_DQ<5>")
		)
		(pad "110" smd rect
			(at -2.050034 34.425128 270)
			(size 0.519938 1.4986)
			(layers "F.Cu" "F.Mask" "F.Paste")
			(net "GND")
		)
		(pad "111" smd rect
			(at -2.050034 35.275012 270)
			(size 0.519938 1.4986)
			(layers "F.Cu" "F.Mask" "F.Paste")
			(net "M_E_CPU1_SB_DQ<8>")
		)
		(pad "112" smd rect
			(at -2.050034 36.124896 270)
			(size 0.519938 1.4986)
			(layers "F.Cu" "F.Mask" "F.Paste")
			(net "GND")
		)
		(pad "113" smd rect
			(at -2.050034 36.975034 270)
			(size 0.519938 1.4986)
			(layers "F.Cu" "F.Mask" "F.Paste")
			(net "M_E_CPU1_SB_DQ<9>")
		)
		(pad "114" smd rect
			(at -2.050034 37.824918 270)
			(size 0.519938 1.4986)
			(layers "F.Cu" "F.Mask" "F.Paste")
			(net "GND")
		)
		(pad "115" smd rect
			(at -2.050034 38.675056 270)
			(size 0.519938 1.4986)
			(layers "F.Cu" "F.Mask" "F.Paste")
			(net "M_E_CPU1_SB_DQS_DP<1>")
		)
		(pad "116" smd rect
			(at -2.050034 39.52494 270)
			(size 0.519938 1.4986)
			(layers "F.Cu" "F.Mask" "F.Paste")
			(net "M_E_CPU1_SB_DQS_DN<1>")
		)
		(pad "117" smd rect
			(at -2.050034 40.375078 270)
			(size 0.519938 1.4986)
			(layers "F.Cu" "F.Mask" "F.Paste")
			(net "GND")
		)
		(pad "118" smd rect
			(at -2.050034 41.224962 270)
			(size 0.519938 1.4986)
			(layers "F.Cu" "F.Mask" "F.Paste")
			(net "M_E_CPU1_SB_DQ<12>")
		)
		(pad "119" smd rect
			(at -2.050034 42.0751 270)
			(size 0.519938 1.4986)
			(layers "F.Cu" "F.Mask" "F.Paste")
			(net "GND")
		)
		(pad "120" smd rect
			(at -2.050034 42.924984 270)
			(size 0.519938 1.4986)
			(layers "F.Cu" "F.Mask" "F.Paste")
			(net "M_E_CPU1_SB_DQ<13>")
		)
		(pad "121" smd rect
			(at -2.050034 43.775122 270)
			(size 0.519938 1.4986)
			(layers "F.Cu" "F.Mask" "F.Paste")
			(net "GND")
		)
		(pad "122" smd rect
			(at -2.050034 44.625006 270)
			(size 0.519938 1.4986)
			(layers "F.Cu" "F.Mask" "F.Paste")
			(net "M_E_CPU1_SB_DQ<16>")
		)
		(pad "123" smd rect
			(at -2.050034 45.47489 270)
			(size 0.519938 1.4986)
			(layers "F.Cu" "F.Mask" "F.Paste")
			(net "GND")
		)
		(pad "124" smd rect
			(at -2.050034 46.325028 270)
			(size 0.519938 1.4986)
			(layers "F.Cu" "F.Mask" "F.Paste")
			(net "M_E_CPU1_SB_DQ<17>")
		)
		(pad "125" smd rect
			(at -2.050034 47.174912 270)
			(size 0.519938 1.4986)
			(layers "F.Cu" "F.Mask" "F.Paste")
			(net "GND")
		)
		(pad "126" smd rect
			(at -2.050034 48.02505 270)
			(size 0.519938 1.4986)
			(layers "F.Cu" "F.Mask" "F.Paste")
			(net "M_E_CPU1_SB_DQS_DP<2>")
		)
		(pad "127" smd rect
			(at -2.050034 48.874934 270)
			(size 0.519938 1.4986)
			(layers "F.Cu" "F.Mask" "F.Paste")
			(net "M_E_CPU1_SB_DQS_DN<2>")
		)
		(pad "128" smd rect
			(at -2.050034 49.725072 270)
			(size 0.519938 1.4986)
			(layers "F.Cu" "F.Mask" "F.Paste")
			(net "GND")
		)
		(pad "129" smd rect
			(at -2.050034 50.574956 270)
			(size 0.519938 1.4986)
			(layers "F.Cu" "F.Mask" "F.Paste")
			(net "M_E_CPU1_SB_DQ<20>")
		)
		(pad "130" smd rect
			(at -2.050034 51.425094 270)
			(size 0.519938 1.4986)
			(layers "F.Cu" "F.Mask" "F.Paste")
			(net "GND")
		)
		(pad "131" smd rect
			(at -2.050034 52.274978 270)
			(size 0.519938 1.4986)
			(layers "F.Cu" "F.Mask" "F.Paste")
			(net "M_E_CPU1_SB_DQ<21>")
		)
		(pad "132" smd rect
			(at -2.050034 53.125116 270)
			(size 0.519938 1.4986)
			(layers "F.Cu" "F.Mask" "F.Paste")
			(net "GND")
		)
		(pad "133" smd rect
			(at -2.050034 53.975 270)
			(size 0.519938 1.4986)
			(layers "F.Cu" "F.Mask" "F.Paste")
			(net "M_E_CPU1_SB_DQ<24>")
		)
		(pad "134" smd rect
			(at -2.050034 54.824884 270)
			(size 0.519938 1.4986)
			(layers "F.Cu" "F.Mask" "F.Paste")
			(net "GND")
		)
		(pad "135" smd rect
			(at -2.050034 55.675022 270)
			(size 0.519938 1.4986)
			(layers "F.Cu" "F.Mask" "F.Paste")
			(net "M_E_CPU1_SB_DQ<25>")
		)
		(pad "136" smd rect
			(at -2.050034 56.524906 270)
			(size 0.519938 1.4986)
			(layers "F.Cu" "F.Mask" "F.Paste")
			(net "GND")
		)
		(pad "137" smd rect
			(at -2.050034 57.375044 270)
			(size 0.519938 1.4986)
			(layers "F.Cu" "F.Mask" "F.Paste")
			(net "M_E_CPU1_SB_DQS_DP<3>")
		)
		(pad "138" smd rect
			(at -2.050034 58.224928 270)
			(size 0.519938 1.4986)
			(layers "F.Cu" "F.Mask" "F.Paste")
			(net "M_E_CPU1_SB_DQS_DN<3>")
		)
		(pad "139" smd rect
			(at -2.050034 59.075066 270)
			(size 0.519938 1.4986)
			(layers "F.Cu" "F.Mask" "F.Paste")
			(net "GND")
		)
		(pad "140" smd rect
			(at -2.050034 59.92495 270)
			(size 0.519938 1.4986)
			(layers "F.Cu" "F.Mask" "F.Paste")
			(net "M_E_CPU1_SB_DQ<28>")
		)
		(pad "141" smd rect
			(at -2.050034 60.775088 270)
			(size 0.519938 1.4986)
			(layers "F.Cu" "F.Mask" "F.Paste")
			(net "GND")
		)
		(pad "142" smd rect
			(at -2.050034 61.624972 270)
			(size 0.519938 1.4986)
			(layers "F.Cu" "F.Mask" "F.Paste")
			(net "M_E_CPU1_SB_DQ<29>")
		)
		(pad "143" smd rect
			(at -2.050034 62.47511 270)
			(size 0.519938 1.4986)
			(layers "F.Cu" "F.Mask" "F.Paste")
			(net "GND")
		)
		(pad "144" smd rect
			(at -2.050034 63.324994 270)
			(size 0.519938 1.4986)
			(layers "F.Cu" "F.Mask" "F.Paste")
			(net "TP_CHE_CPU1_DIMM2_FRU_1")
		)
		(pad "145" smd rect
			(at 2.050034 -63.324994 270)
			(size 0.519938 1.4986)
			(layers "F.Cu" "F.Mask" "F.Paste")
			(net "P12V_S3_AUX_CPU1_NVDIMM")
		)
		(pad "146" smd rect
			(at 2.050034 -62.47511 270)
			(size 0.519938 1.4986)
			(layers "F.Cu" "F.Mask" "F.Paste")
			(net "P12V_S3_AUX_CPU1_NVDIMM")
		)
		(pad "147" smd rect
			(at 2.050034 -61.624972 270)
			(size 0.519938 1.4986)
			(layers "F.Cu" "F.Mask" "F.Paste")
			(net "PWRGD_CHE_CPU1_DIMM2")
		)
		(pad "148" smd rect
			(at 2.050034 -60.775088 270)
			(size 0.519938 1.4986)
			(layers "F.Cu" "F.Mask" "F.Paste")
			(net "PD_CHE_CPU1_DIMM2_SAA")
		)
		(pad "149" smd rect
			(at 2.050034 -59.92495 270)
			(size 0.519938 1.4986)
			(layers "F.Cu" "F.Mask" "F.Paste")
			(net "TP_CHE_CPU1_DIMM2_FRU_2")
		)
		(pad "150" smd rect
			(at 2.050034 -59.075066 270)
			(size 0.519938 1.4986)
			(layers "F.Cu" "F.Mask" "F.Paste")
			(net "TP_CHE_CPU1_DIMM2_FRU_3")
		)
		(pad "151" smd rect
			(at 2.050034 -58.224928 270)
			(size 0.519938 1.4986)
			(layers "F.Cu" "F.Mask" "F.Paste")
			(net "GND")
		)
		(pad "152" smd rect
			(at 2.050034 -57.375044 270)
			(size 0.519938 1.4986)
			(layers "F.Cu" "F.Mask" "F.Paste")
			(net "M_E_CPU1_SA_DQ<2>")
		)
		(pad "153" smd rect
			(at 2.050034 -56.524906 270)
			(size 0.519938 1.4986)
			(layers "F.Cu" "F.Mask" "F.Paste")
			(net "GND")
		)
		(pad "154" smd rect
			(at 2.050034 -55.675022 270)
			(size 0.519938 1.4986)
			(layers "F.Cu" "F.Mask" "F.Paste")
			(net "M_E_CPU1_SA_DQ<3>")
		)
		(pad "155" smd rect
			(at 2.050034 -54.824884 270)
			(size 0.519938 1.4986)
			(layers "F.Cu" "F.Mask" "F.Paste")
			(net "GND")
		)
		(pad "156" smd rect
			(at 2.050034 -53.975 270)
			(size 0.519938 1.4986)
			(layers "F.Cu" "F.Mask" "F.Paste")
			(net "M_E_CPU1_SA_DQS_DN<5>")
		)
		(pad "157" smd rect
			(at 2.050034 -53.125116 270)
			(size 0.519938 1.4986)
			(layers "F.Cu" "F.Mask" "F.Paste")
			(net "M_E_CPU1_SA_DQS_DP<5>")
		)
		(pad "158" smd rect
			(at 2.050034 -52.274978 270)
			(size 0.519938 1.4986)
			(layers "F.Cu" "F.Mask" "F.Paste")
			(net "GND")
		)
		(pad "159" smd rect
			(at 2.050034 -51.425094 270)
			(size 0.519938 1.4986)
			(layers "F.Cu" "F.Mask" "F.Paste")
			(net "M_E_CPU1_SA_DQ<6>")
		)
		(pad "160" smd rect
			(at 2.050034 -50.574956 270)
			(size 0.519938 1.4986)
			(layers "F.Cu" "F.Mask" "F.Paste")
			(net "GND")
		)
		(pad "161" smd rect
			(at 2.050034 -49.725072 270)
			(size 0.519938 1.4986)
			(layers "F.Cu" "F.Mask" "F.Paste")
			(net "M_E_CPU1_SA_DQ<7>")
		)
		(pad "162" smd rect
			(at 2.050034 -48.874934 270)
			(size 0.519938 1.4986)
			(layers "F.Cu" "F.Mask" "F.Paste")
			(net "GND")
		)
		(pad "163" smd rect
			(at 2.050034 -48.02505 270)
			(size 0.519938 1.4986)
			(layers "F.Cu" "F.Mask" "F.Paste")
			(net "M_E_CPU1_SA_DQ<10>")
		)
		(pad "164" smd rect
			(at 2.050034 -47.174912 270)
			(size 0.519938 1.4986)
			(layers "F.Cu" "F.Mask" "F.Paste")
			(net "GND")
		)
		(pad "165" smd rect
			(at 2.050034 -46.325028 270)
			(size 0.519938 1.4986)
			(layers "F.Cu" "F.Mask" "F.Paste")
			(net "M_E_CPU1_SA_DQ<11>")
		)
		(pad "166" smd rect
			(at 2.050034 -45.47489 270)
			(size 0.519938 1.4986)
			(layers "F.Cu" "F.Mask" "F.Paste")
			(net "GND")
		)
		(pad "167" smd rect
			(at 2.050034 -44.625006 270)
			(size 0.519938 1.4986)
			(layers "F.Cu" "F.Mask" "F.Paste")
			(net "M_E_CPU1_SA_DQS_DN<6>")
		)
		(pad "168" smd rect
			(at 2.050034 -43.775122 270)
			(size 0.519938 1.4986)
			(layers "F.Cu" "F.Mask" "F.Paste")
			(net "M_E_CPU1_SA_DQS_DP<6>")
		)
		(pad "169" smd rect
			(at 2.050034 -42.924984 270)
			(size 0.519938 1.4986)
			(layers "F.Cu" "F.Mask" "F.Paste")
			(net "GND")
		)
		(pad "170" smd rect
			(at 2.050034 -42.0751 270)
			(size 0.519938 1.4986)
			(layers "F.Cu" "F.Mask" "F.Paste")
			(net "M_E_CPU1_SA_DQ<14>")
		)
		(pad "171" smd rect
			(at 2.050034 -41.224962 270)
			(size 0.519938 1.4986)
			(layers "F.Cu" "F.Mask" "F.Paste")
			(net "GND")
		)
		(pad "172" smd rect
			(at 2.050034 -40.375078 270)
			(size 0.519938 1.4986)
			(layers "F.Cu" "F.Mask" "F.Paste")
			(net "M_E_CPU1_SA_DQ<15>")
		)
		(pad "173" smd rect
			(at 2.050034 -39.52494 270)
			(size 0.519938 1.4986)
			(layers "F.Cu" "F.Mask" "F.Paste")
			(net "GND")
		)
		(pad "174" smd rect
			(at 2.050034 -38.675056 270)
			(size 0.519938 1.4986)
			(layers "F.Cu" "F.Mask" "F.Paste")
			(net "M_E_CPU1_SA_DQ<18>")
		)
		(pad "175" smd rect
			(at 2.050034 -37.824918 270)
			(size 0.519938 1.4986)
			(layers "F.Cu" "F.Mask" "F.Paste")
			(net "GND")
		)
		(pad "176" smd rect
			(at 2.050034 -36.975034 270)
			(size 0.519938 1.4986)
			(layers "F.Cu" "F.Mask" "F.Paste")
			(net "M_E_CPU1_SA_DQ<19>")
		)
		(pad "177" smd rect
			(at 2.050034 -36.124896 270)
			(size 0.519938 1.4986)
			(layers "F.Cu" "F.Mask" "F.Paste")
			(net "GND")
		)
		(pad "178" smd rect
			(at 2.050034 -35.275012 270)
			(size 0.519938 1.4986)
			(layers "F.Cu" "F.Mask" "F.Paste")
			(net "M_E_CPU1_SA_DQS_DN<7>")
		)
		(pad "179" smd rect
			(at 2.050034 -34.425128 270)
			(size 0.519938 1.4986)
			(layers "F.Cu" "F.Mask" "F.Paste")
			(net "M_E_CPU1_SA_DQS_DP<7>")
		)
		(pad "180" smd rect
			(at 2.050034 -33.57499 270)
			(size 0.519938 1.4986)
			(layers "F.Cu" "F.Mask" "F.Paste")
			(net "GND")
		)
		(pad "181" smd rect
			(at 2.050034 -32.725106 270)
			(size 0.519938 1.4986)
			(layers "F.Cu" "F.Mask" "F.Paste")
			(net "M_E_CPU1_SA_DQ<22>")
		)
		(pad "182" smd rect
			(at 2.050034 -31.874968 270)
			(size 0.519938 1.4986)
			(layers "F.Cu" "F.Mask" "F.Paste")
			(net "GND")
		)
		(pad "183" smd rect
			(at 2.050034 -31.025084 270)
			(size 0.519938 1.4986)
			(layers "F.Cu" "F.Mask" "F.Paste")
			(net "M_E_CPU1_SA_DQ<23>")
		)
		(pad "184" smd rect
			(at 2.050034 -30.174946 270)
			(size 0.519938 1.4986)
			(layers "F.Cu" "F.Mask" "F.Paste")
			(net "GND")
		)
		(pad "185" smd rect
			(at 2.050034 -29.325062 270)
			(size 0.519938 1.4986)
			(layers "F.Cu" "F.Mask" "F.Paste")
			(net "M_E_CPU1_SA_DQ<26>")
		)
		(pad "186" smd rect
			(at 2.050034 -28.474924 270)
			(size 0.519938 1.4986)
			(layers "F.Cu" "F.Mask" "F.Paste")
			(net "GND")
		)
		(pad "187" smd rect
			(at 2.050034 -27.62504 270)
			(size 0.519938 1.4986)
			(layers "F.Cu" "F.Mask" "F.Paste")
			(net "M_E_CPU1_SA_DQ<27>")
		)
		(pad "188" smd rect
			(at 2.050034 -26.774902 270)
			(size 0.519938 1.4986)
			(layers "F.Cu" "F.Mask" "F.Paste")
			(net "GND")
		)
		(pad "189" smd rect
			(at 2.050034 -25.925018 270)
			(size 0.519938 1.4986)
			(layers "F.Cu" "F.Mask" "F.Paste")
			(net "M_E_CPU1_SA_DQS_DN<8>")
		)
		(pad "190" smd rect
			(at 2.050034 -25.07488 270)
			(size 0.519938 1.4986)
			(layers "F.Cu" "F.Mask" "F.Paste")
			(net "M_E_CPU1_SA_DQS_DP<8>")
		)
		(pad "191" smd rect
			(at 2.050034 -24.224996 270)
			(size 0.519938 1.4986)
			(layers "F.Cu" "F.Mask" "F.Paste")
			(net "GND")
		)
		(pad "192" smd rect
			(at 2.050034 -23.375112 270)
			(size 0.519938 1.4986)
			(layers "F.Cu" "F.Mask" "F.Paste")
			(net "M_E_CPU1_SA_DQ<30>")
		)
		(pad "193" smd rect
			(at 2.050034 -22.524974 270)
			(size 0.519938 1.4986)
			(layers "F.Cu" "F.Mask" "F.Paste")
			(net "GND")
		)
		(pad "194" smd rect
			(at 2.050034 -21.67509 270)
			(size 0.519938 1.4986)
			(layers "F.Cu" "F.Mask" "F.Paste")
			(net "M_E_CPU1_SA_DQ<31>")
		)
		(pad "195" smd rect
			(at 2.050034 -20.824952 270)
			(size 0.519938 1.4986)
			(layers "F.Cu" "F.Mask" "F.Paste")
			(net "GND")
		)
		(pad "196" smd rect
			(at 2.050034 -19.975068 270)
			(size 0.519938 1.4986)
			(layers "F.Cu" "F.Mask" "F.Paste")
			(net "M_E_CPU1_SA_CB<2>")
		)
		(pad "197" smd rect
			(at 2.050034 -19.12493 270)
			(size 0.519938 1.4986)
			(layers "F.Cu" "F.Mask" "F.Paste")
			(net "GND")
		)
		(pad "198" smd rect
			(at 2.050034 -18.275046 270)
			(size 0.519938 1.4986)
			(layers "F.Cu" "F.Mask" "F.Paste")
			(net "M_E_CPU1_SA_CB<3>")
		)
		(pad "199" smd rect
			(at 2.050034 -17.424908 270)
			(size 0.519938 1.4986)
			(layers "F.Cu" "F.Mask" "F.Paste")
			(net "GND")
		)
		(pad "200" smd rect
			(at 2.050034 -16.575024 270)
			(size 0.519938 1.4986)
			(layers "F.Cu" "F.Mask" "F.Paste")
			(net "M_E_CPU1_SA_DQS_DN<9>")
		)
		(pad "201" smd rect
			(at 2.050034 -15.724886 270)
			(size 0.519938 1.4986)
			(layers "F.Cu" "F.Mask" "F.Paste")
			(net "M_E_CPU1_SA_DQS_DP<9>")
		)
		(pad "202" smd rect
			(at 2.050034 -14.875002 270)
			(size 0.519938 1.4986)
			(layers "F.Cu" "F.Mask" "F.Paste")
			(net "GND")
		)
		(pad "203" smd rect
			(at 2.050034 -14.025118 270)
			(size 0.519938 1.4986)
			(layers "F.Cu" "F.Mask" "F.Paste")
			(net "M_E_CPU1_SA_CB<6>")
		)
		(pad "204" smd rect
			(at 2.050034 -13.17498 270)
			(size 0.519938 1.4986)
			(layers "F.Cu" "F.Mask" "F.Paste")
			(net "GND")
		)
		(pad "205" smd rect
			(at 2.050034 -12.325096 270)
			(size 0.519938 1.4986)
			(layers "F.Cu" "F.Mask" "F.Paste")
			(net "M_E_CPU1_SA_CB<7>")
		)
		(pad "206" smd rect
			(at 2.050034 -11.474958 270)
			(size 0.519938 1.4986)
			(layers "F.Cu" "F.Mask" "F.Paste")
			(net "GND")
		)
		(pad "207" smd rect
			(at 2.050034 -10.625074 270)
			(size 0.519938 1.4986)
			(layers "F.Cu" "F.Mask" "F.Paste")
			(net "RST_M_EF_CPU1_FPGA_N")
		)
		(pad "208" smd rect
			(at 2.050034 -9.774936 270)
			(size 0.519938 1.4986)
			(layers "F.Cu" "F.Mask" "F.Paste")
			(net "GND")
		)
		(pad "209" smd rect
			(at 2.050034 -8.925052 270)
			(size 0.519938 1.4986)
			(layers "F.Cu" "F.Mask" "F.Paste")
			(net "M_E_CPU1_SA_CS_N<3>")
		)
		(pad "210" smd rect
			(at 2.050034 -8.074914 270)
			(size 0.519938 1.4986)
			(layers "F.Cu" "F.Mask" "F.Paste")
			(net "GND")
		)
		(pad "211" smd rect
			(at 2.050034 -7.22503 270)
			(size 0.519938 1.4986)
			(layers "F.Cu" "F.Mask" "F.Paste")
			(net "M_E_CPU1_SA_CA<1>")
		)
		(pad "212" smd rect
			(at 2.050034 -6.374892 270)
			(size 0.519938 1.4986)
			(layers "F.Cu" "F.Mask" "F.Paste")
			(net "GND")
		)
		(pad "213" smd rect
			(at 2.050034 -5.525008 270)
			(size 0.519938 1.4986)
			(layers "F.Cu" "F.Mask" "F.Paste")
			(net "M_E_CPU1_SA_CA<3>")
		)
		(pad "214" smd rect
			(at 2.050034 -4.675124 270)
			(size 0.519938 1.4986)
			(layers "F.Cu" "F.Mask" "F.Paste")
			(net "GND")
		)
		(pad "215" smd rect
			(at 2.050034 -3.824986 270)
			(size 0.519938 1.4986)
			(layers "F.Cu" "F.Mask" "F.Paste")
			(net "M_E_CPU1_SA_CA<5>")
		)
		(pad "216" smd rect
			(at 2.050034 -2.975102 270)
			(size 0.519938 1.4986)
			(layers "F.Cu" "F.Mask" "F.Paste")
			(net "GND")
		)
		(pad "217" smd rect
			(at 2.050034 -2.124964 270)
			(size 0.519938 1.4986)
			(layers "F.Cu" "F.Mask" "F.Paste")
			(net "M_E_CPU1_CLK_DP<1>")
		)
		(pad "218" smd rect
			(at 2.050034 -1.27508 270)
			(size 0.519938 1.4986)
			(layers "F.Cu" "F.Mask" "F.Paste")
			(net "M_E_CPU1_CLK_DN<1>")
		)
		(pad "219" smd rect
			(at 2.050034 -0.424942 270)
			(size 0.519938 1.4986)
			(layers "F.Cu" "F.Mask" "F.Paste")
			(net "GND")
		)
		(pad "220" smd rect
			(at 2.050034 5.525008 270)
			(size 0.519938 1.4986)
			(layers "F.Cu" "F.Mask" "F.Paste")
			(net "TP_CHE_CPU1_DIMM2_FRU_4")
		)
		(pad "221" smd rect
			(at 2.050034 6.374892 270)
			(size 0.519938 1.4986)
			(layers "F.Cu" "F.Mask" "F.Paste")
			(net "M_E_CPU1_SB_CA<1>")
		)
		(pad "222" smd rect
			(at 2.050034 7.22503 270)
			(size 0.519938 1.4986)
			(layers "F.Cu" "F.Mask" "F.Paste")
			(net "GND")
		)
		(pad "223" smd rect
			(at 2.050034 8.074914 270)
			(size 0.519938 1.4986)
			(layers "F.Cu" "F.Mask" "F.Paste")
			(net "M_E_CPU1_SB_CA<3>")
		)
		(pad "224" smd rect
			(at 2.050034 8.925052 270)
			(size 0.519938 1.4986)
			(layers "F.Cu" "F.Mask" "F.Paste")
			(net "GND")
		)
		(pad "225" smd rect
			(at 2.050034 9.774936 270)
			(size 0.519938 1.4986)
			(layers "F.Cu" "F.Mask" "F.Paste")
			(net "M_E_CPU1_SB_CA<5>")
		)
		(pad "226" smd rect
			(at 2.050034 10.625074 270)
			(size 0.519938 1.4986)
			(layers "F.Cu" "F.Mask" "F.Paste")
			(net "GND")
		)
		(pad "227" smd rect
			(at 2.050034 11.474958 270)
			(size 0.519938 1.4986)
			(layers "F.Cu" "F.Mask" "F.Paste")
			(net "M_E_CPU1_SB_PAR")
		)
		(pad "228" smd rect
			(at 2.050034 12.325096 270)
			(size 0.519938 1.4986)
			(layers "F.Cu" "F.Mask" "F.Paste")
			(net "GND")
		)
		(pad "229" smd rect
			(at 2.050034 13.17498 270)
			(size 0.519938 1.4986)
			(layers "F.Cu" "F.Mask" "F.Paste")
			(net "M_E_CPU1_SB_CS_N<3>")
		)
		(pad "230" smd rect
			(at 2.050034 14.025118 270)
			(size 0.519938 1.4986)
			(layers "F.Cu" "F.Mask" "F.Paste")
			(net "GND")
		)
		(pad "231" smd rect
			(at 2.050034 14.875002 270)
			(size 0.519938 1.4986)
			(layers "F.Cu" "F.Mask" "F.Paste")
			(net "TP_CHE_CPU1_DIMM2_FRU_5")
		)
		(pad "232" smd rect
			(at 2.050034 15.724886 270)
			(size 0.519938 1.4986)
			(layers "F.Cu" "F.Mask" "F.Paste")
			(net "TP_CHE_CPU1_DIMM2_FRU_6")
		)
		(pad "233" smd rect
			(at 2.050034 16.575024 270)
			(size 0.519938 1.4986)
			(layers "F.Cu" "F.Mask" "F.Paste")
			(net "GND")
		)
		(pad "234" smd rect
			(at 2.050034 17.424908 270)
			(size 0.519938 1.4986)
			(layers "F.Cu" "F.Mask" "F.Paste")
			(net "M_E_CPU1_SB_CB<6>")
		)
		(pad "235" smd rect
			(at 2.050034 18.275046 270)
			(size 0.519938 1.4986)
			(layers "F.Cu" "F.Mask" "F.Paste")
			(net "GND")
		)
		(pad "236" smd rect
			(at 2.050034 19.12493 270)
			(size 0.519938 1.4986)
			(layers "F.Cu" "F.Mask" "F.Paste")
			(net "M_E_CPU1_SB_CB<7>")
		)
		(pad "237" smd rect
			(at 2.050034 19.975068 270)
			(size 0.519938 1.4986)
			(layers "F.Cu" "F.Mask" "F.Paste")
			(net "GND")
		)
		(pad "238" smd rect
			(at 2.050034 20.824952 270)
			(size 0.519938 1.4986)
			(layers "F.Cu" "F.Mask" "F.Paste")
			(net "M_E_CPU1_SB_DQS_DN<4>")
		)
		(pad "239" smd rect
			(at 2.050034 21.67509 270)
			(size 0.519938 1.4986)
			(layers "F.Cu" "F.Mask" "F.Paste")
			(net "M_E_CPU1_SB_DQS_DP<4>")
		)
		(pad "240" smd rect
			(at 2.050034 22.524974 270)
			(size 0.519938 1.4986)
			(layers "F.Cu" "F.Mask" "F.Paste")
			(net "GND")
		)
		(pad "241" smd rect
			(at 2.050034 23.375112 270)
			(size 0.519938 1.4986)
			(layers "F.Cu" "F.Mask" "F.Paste")
			(net "M_E_CPU1_SB_CB<2>")
		)
		(pad "242" smd rect
			(at 2.050034 24.224996 270)
			(size 0.519938 1.4986)
			(layers "F.Cu" "F.Mask" "F.Paste")
			(net "GND")
		)
		(pad "243" smd rect
			(at 2.050034 25.07488 270)
			(size 0.519938 1.4986)
			(layers "F.Cu" "F.Mask" "F.Paste")
			(net "M_E_CPU1_SB_CB<3>")
		)
		(pad "244" smd rect
			(at 2.050034 25.925018 270)
			(size 0.519938 1.4986)
			(layers "F.Cu" "F.Mask" "F.Paste")
			(net "GND")
		)
		(pad "245" smd rect
			(at 2.050034 26.774902 270)
			(size 0.519938 1.4986)
			(layers "F.Cu" "F.Mask" "F.Paste")
			(net "M_E_CPU1_SB_DQ<2>")
		)
		(pad "246" smd rect
			(at 2.050034 27.62504 270)
			(size 0.519938 1.4986)
			(layers "F.Cu" "F.Mask" "F.Paste")
			(net "GND")
		)
		(pad "247" smd rect
			(at 2.050034 28.474924 270)
			(size 0.519938 1.4986)
			(layers "F.Cu" "F.Mask" "F.Paste")
			(net "M_E_CPU1_SB_DQ<3>")
		)
		(pad "248" smd rect
			(at 2.050034 29.325062 270)
			(size 0.519938 1.4986)
			(layers "F.Cu" "F.Mask" "F.Paste")
			(net "GND")
		)
		(pad "249" smd rect
			(at 2.050034 30.174946 270)
			(size 0.519938 1.4986)
			(layers "F.Cu" "F.Mask" "F.Paste")
			(net "M_E_CPU1_SB_DQS_DN<5>")
		)
		(pad "250" smd rect
			(at 2.050034 31.025084 270)
			(size 0.519938 1.4986)
			(layers "F.Cu" "F.Mask" "F.Paste")
			(net "M_E_CPU1_SB_DQS_DP<5>")
		)
		(pad "251" smd rect
			(at 2.050034 31.874968 270)
			(size 0.519938 1.4986)
			(layers "F.Cu" "F.Mask" "F.Paste")
			(net "GND")
		)
		(pad "252" smd rect
			(at 2.050034 32.725106 270)
			(size 0.519938 1.4986)
			(layers "F.Cu" "F.Mask" "F.Paste")
			(net "M_E_CPU1_SB_DQ<6>")
		)
		(pad "253" smd rect
			(at 2.050034 33.57499 270)
			(size 0.519938 1.4986)
			(layers "F.Cu" "F.Mask" "F.Paste")
			(net "GND")
		)
		(pad "254" smd rect
			(at 2.050034 34.425128 270)
			(size 0.519938 1.4986)
			(layers "F.Cu" "F.Mask" "F.Paste")
			(net "M_E_CPU1_SB_DQ<7>")
		)
		(pad "255" smd rect
			(at 2.050034 35.275012 270)
			(size 0.519938 1.4986)
			(layers "F.Cu" "F.Mask" "F.Paste")
			(net "GND")
		)
		(pad "256" smd rect
			(at 2.050034 36.124896 270)
			(size 0.519938 1.4986)
			(layers "F.Cu" "F.Mask" "F.Paste")
			(net "M_E_CPU1_SB_DQ<10>")
		)
		(pad "257" smd rect
			(at 2.050034 36.975034 270)
			(size 0.519938 1.4986)
			(layers "F.Cu" "F.Mask" "F.Paste")
			(net "GND")
		)
		(pad "258" smd rect
			(at 2.050034 37.824918 270)
			(size 0.519938 1.4986)
			(layers "F.Cu" "F.Mask" "F.Paste")
			(net "M_E_CPU1_SB_DQ<11>")
		)
		(pad "259" smd rect
			(at 2.050034 38.675056 270)
			(size 0.519938 1.4986)
			(layers "F.Cu" "F.Mask" "F.Paste")
			(net "GND")
		)
		(pad "260" smd rect
			(at 2.050034 39.52494 270)
			(size 0.519938 1.4986)
			(layers "F.Cu" "F.Mask" "F.Paste")
			(net "M_E_CPU1_SB_DQS_DN<6>")
		)
		(pad "261" smd rect
			(at 2.050034 40.375078 270)
			(size 0.519938 1.4986)
			(layers "F.Cu" "F.Mask" "F.Paste")
			(net "M_E_CPU1_SB_DQS_DP<6>")
		)
		(pad "262" smd rect
			(at 2.050034 41.224962 270)
			(size 0.519938 1.4986)
			(layers "F.Cu" "F.Mask" "F.Paste")
			(net "GND")
		)
		(pad "263" smd rect
			(at 2.050034 42.0751 270)
			(size 0.519938 1.4986)
			(layers "F.Cu" "F.Mask" "F.Paste")
			(net "M_E_CPU1_SB_DQ<14>")
		)
		(pad "264" smd rect
			(at 2.050034 42.924984 270)
			(size 0.519938 1.4986)
			(layers "F.Cu" "F.Mask" "F.Paste")
			(net "GND")
		)
		(pad "265" smd rect
			(at 2.050034 43.775122 270)
			(size 0.519938 1.4986)
			(layers "F.Cu" "F.Mask" "F.Paste")
			(net "M_E_CPU1_SB_DQ<15>")
		)
		(pad "266" smd rect
			(at 2.050034 44.625006 270)
			(size 0.519938 1.4986)
			(layers "F.Cu" "F.Mask" "F.Paste")
			(net "GND")
		)
		(pad "267" smd rect
			(at 2.050034 45.47489 270)
			(size 0.519938 1.4986)
			(layers "F.Cu" "F.Mask" "F.Paste")
			(net "M_E_CPU1_SB_DQ<18>")
		)
		(pad "268" smd rect
			(at 2.050034 46.325028 270)
			(size 0.519938 1.4986)
			(layers "F.Cu" "F.Mask" "F.Paste")
			(net "GND")
		)
		(pad "269" smd rect
			(at 2.050034 47.174912 270)
			(size 0.519938 1.4986)
			(layers "F.Cu" "F.Mask" "F.Paste")
			(net "M_E_CPU1_SB_DQ<19>")
		)
		(pad "270" smd rect
			(at 2.050034 48.02505 270)
			(size 0.519938 1.4986)
			(layers "F.Cu" "F.Mask" "F.Paste")
			(net "GND")
		)
		(pad "271" smd rect
			(at 2.050034 48.874934 270)
			(size 0.519938 1.4986)
			(layers "F.Cu" "F.Mask" "F.Paste")
			(net "M_E_CPU1_SB_DQS_DN<7>")
		)
		(pad "272" smd rect
			(at 2.050034 49.725072 270)
			(size 0.519938 1.4986)
			(layers "F.Cu" "F.Mask" "F.Paste")
			(net "M_E_CPU1_SB_DQS_DP<7>")
		)
		(pad "273" smd rect
			(at 2.050034 50.574956 270)
			(size 0.519938 1.4986)
			(layers "F.Cu" "F.Mask" "F.Paste")
			(net "GND")
		)
		(pad "274" smd rect
			(at 2.050034 51.425094 270)
			(size 0.519938 1.4986)
			(layers "F.Cu" "F.Mask" "F.Paste")
			(net "M_E_CPU1_SB_DQ<22>")
		)
		(pad "275" smd rect
			(at 2.050034 52.274978 270)
			(size 0.519938 1.4986)
			(layers "F.Cu" "F.Mask" "F.Paste")
			(net "GND")
		)
		(pad "276" smd rect
			(at 2.050034 53.125116 270)
			(size 0.519938 1.4986)
			(layers "F.Cu" "F.Mask" "F.Paste")
			(net "M_E_CPU1_SB_DQ<23>")
		)
		(pad "277" smd rect
			(at 2.050034 53.975 270)
			(size 0.519938 1.4986)
			(layers "F.Cu" "F.Mask" "F.Paste")
			(net "GND")
		)
		(pad "278" smd rect
			(at 2.050034 54.824884 270)
			(size 0.519938 1.4986)
			(layers "F.Cu" "F.Mask" "F.Paste")
			(net "M_E_CPU1_SB_DQ<26>")
		)
		(pad "279" smd rect
			(at 2.050034 55.675022 270)
			(size 0.519938 1.4986)
			(layers "F.Cu" "F.Mask" "F.Paste")
			(net "GND")
		)
		(pad "280" smd rect
			(at 2.050034 56.524906 270)
			(size 0.519938 1.4986)
			(layers "F.Cu" "F.Mask" "F.Paste")
			(net "M_E_CPU1_SB_DQ<27>")
		)
		(pad "281" smd rect
			(at 2.050034 57.375044 270)
			(size 0.519938 1.4986)
			(layers "F.Cu" "F.Mask" "F.Paste")
			(net "GND")
		)
		(pad "282" smd rect
			(at 2.050034 58.224928 270)
			(size 0.519938 1.4986)
			(layers "F.Cu" "F.Mask" "F.Paste")
			(net "M_E_CPU1_SB_DQS_DN<8>")
		)
		(pad "283" smd rect
			(at 2.050034 59.075066 270)
			(size 0.519938 1.4986)
			(layers "F.Cu" "F.Mask" "F.Paste")
			(net "M_E_CPU1_SB_DQS_DP<8>")
		)
		(pad "284" smd rect
			(at 2.050034 59.92495 270)
			(size 0.519938 1.4986)
			(layers "F.Cu" "F.Mask" "F.Paste")
			(net "GND")
		)
		(pad "285" smd rect
			(at 2.050034 60.775088 270)
			(size 0.519938 1.4986)
			(layers "F.Cu" "F.Mask" "F.Paste")
			(net "M_E_CPU1_SB_DQ<30>")
		)
		(pad "286" smd rect
			(at 2.050034 61.624972 270)
			(size 0.519938 1.4986)
			(layers "F.Cu" "F.Mask" "F.Paste")
			(net "GND")
		)
		(pad "287" smd rect
			(at 2.050034 62.47511 270)
			(size 0.519938 1.4986)
			(layers "F.Cu" "F.Mask" "F.Paste")
			(net "M_E_CPU1_SB_DQ<31>")
		)
		(pad "288" smd rect
			(at 2.050034 63.324994 270)
			(size 0.519938 1.4986)
			(layers "F.Cu" "F.Mask" "F.Paste")
			(net "GND")
		)
		(pad "G1" thru_hole oval
			(at 0 -68.97497)
			(size 2.8194 1.5748)
			(drill oval 2.4384 1.1938)
			(layers "*.Cu" "*.Mask")
			(remove_unused_layers no)
			(net "GND")
			(clearance 0.127)
			(thermal_gap 0.127)
		)
		(pad "G2" thru_hole oval
			(at 0 3.875024)
			(size 2.8194 1.5748)
			(drill oval 2.4384 1.1938)
			(layers "*.Cu" "*.Mask")
			(remove_unused_layers no)
			(net "GND")
			(clearance 0.127)
			(thermal_gap 0.127)
		)
		(pad "G3" thru_hole oval
			(at 0 68.97497)
			(size 2.8194 1.5748)
			(drill oval 2.4384 1.1938)
			(layers "*.Cu" "*.Mask")
			(remove_unused_layers no)
			(net "GND")
			(clearance 0.127)
			(thermal_gap 0.127)
		)
	)
	(footprint ""
		(layer "F.Cu")
		(at 180.528468 -53.065934 180)
		(property "Reference" "C1105"
			(at 0 0 180)
			(layer "F.SilkS")
			(hide yes)
			(effects
				(font
					(size 1.27 1.27)
				)
			)
		)
		(property "Value" ""
			(at 0 0 180)
			(layer "F.Fab")
			(effects
				(font
					(size 1.27 1.27)
				)
			)
		)
		(duplicate_pad_numbers_are_jumpers no)
		(fp_line
			(start 0.299974 0.150114)
			(end -0.299974 0.150114)
			(stroke
				(width 0.1)
				(type default)
			)
			(layer "F.Fab")
		)
		(fp_line
			(start 0.299974 -0.150114)
			(end 0.299974 0.150114)
			(stroke
				(width 0.1)
				(type default)
			)
			(layer "F.Fab")
		)
		(fp_line
			(start -0.299974 0.150114)
			(end -0.299974 -0.150114)
			(stroke
				(width 0.1)
				(type default)
			)
			(layer "F.Fab")
		)
		(fp_line
			(start -0.299974 -0.150114)
			(end 0.299974 -0.150114)
			(stroke
				(width 0.1)
				(type default)
			)
			(layer "F.Fab")
		)
		(pad "1" smd rect
			(at -0.2667 0 180)
			(size 0.3048 0.381)
			(layers "F.Cu" "F.Mask" "F.Paste")
			(net "P3E_PCH_M2_TX_DN<0>")
		)
		(pad "2" smd rect
			(at 0.2667 0 180)
			(size 0.3048 0.381)
			(layers "F.Cu" "F.Mask" "F.Paste")
			(net "P3E_PCH_M2_TX_C_DN<0>")
		)
		(zone
			(layer "In1.Cu")
			(hatch none 0.5)
			(connect_pads
				(clearance 0)
			)
			(min_thickness 0.25)
			(keepout
				(tracks not_allowed)
				(vias allowed)
				(pads allowed)
				(copperpour not_allowed)
				(footprints allowed)
			)
			(placement
				(enabled no)
				(sheetname "")
			)
			(fill
				(thermal_gap 0.5)
				(thermal_bridge_width 0.5)
				(island_removal_mode 0)
			)
			(polygon
				(pts
					(arc
						(start 180.388768 -53.307234)
						(mid 180.44265 -53.284916)
						(end 180.464968 -53.231034)
					)
					(arc
						(start 180.464968 -52.900834)
						(mid 180.44265 -52.846952)
						(end 180.388768 -52.824634)
					)
					(arc
						(start 180.134768 -52.824634)
						(mid 180.080886 -52.846952)
						(end 180.058568 -52.900834)
					)
					(arc
						(start 180.058568 -53.231034)
						(mid 180.080886 -53.284916)
						(end 180.134768 -53.307234)
					)
				)
			)
		)
		(zone
			(layer "In1.Cu")
			(hatch none 0.5)
			(connect_pads
				(clearance 0)
			)
			(min_thickness 0.25)
			(keepout
				(tracks not_allowed)
				(vias allowed)
				(pads allowed)
				(copperpour not_allowed)
				(footprints allowed)
			)
			(placement
				(enabled no)
				(sheetname "")
			)
			(fill
				(thermal_gap 0.5)
				(thermal_bridge_width 0.5)
				(island_removal_mode 0)
			)
			(polygon
				(pts
					(arc
						(start 180.922168 -53.307234)
						(mid 180.97605 -53.284916)
						(end 180.998368 -53.231034)
					)
					(arc
						(start 180.998368 -52.900834)
						(mid 180.97605 -52.846952)
						(end 180.922168 -52.824634)
					)
					(arc
						(start 180.668168 -52.824634)
						(mid 180.614286 -52.846952)
						(end 180.591968 -52.900834)
					)
					(arc
						(start 180.591968 -53.231034)
						(mid 180.614286 -53.284916)
						(end 180.668168 -53.307234)
					)
				)
			)
		)
	)
	(footprint ""
		(layer "F.Cu")
		(at 120.129554 -402.371052 -90)
		(property "Reference" "C743"
			(at 0 0 270)
			(layer "F.SilkS")
			(hide yes)
			(effects
				(font
					(size 1.27 1.27)
				)
			)
		)
		(property "Value" ""
			(at 0 0 270)
			(layer "F.Fab")
			(effects
				(font
					(size 1.27 1.27)
				)
			)
		)
		(duplicate_pad_numbers_are_jumpers no)
		(fp_line
			(start -0.299974 0.150114)
			(end -0.299974 -0.150114)
			(stroke
				(width 0.1)
				(type default)
			)
			(layer "F.Fab")
		)
		(fp_line
			(start 0.299974 0.150114)
			(end -0.299974 0.150114)
			(stroke
				(width 0.1)
				(type default)
			)
			(layer "F.Fab")
		)
		(fp_line
			(start -0.299974 -0.150114)
			(end 0.299974 -0.150114)
			(stroke
				(width 0.1)
				(type default)
			)
			(layer "F.Fab")
		)
		(fp_line
			(start 0.299974 -0.150114)
			(end 0.299974 0.150114)
			(stroke
				(width 0.1)
				(type default)
			)
			(layer "F.Fab")
		)
		(pad "1" smd rect
			(at -0.2667 0 270)
			(size 0.3048 0.381)
			(layers "F.Cu" "F.Mask" "F.Paste")
			(net "P5E_CPU1_PE2_TX_C_DP<15>")
		)
		(pad "2" smd rect
			(at 0.2667 0 270)
			(size 0.3048 0.381)
			(layers "F.Cu" "F.Mask" "F.Paste")
			(net "P5E_CPU1_PE2_TX_DP<15>")
		)
	)
	(footprint ""
		(layer "F.Cu")
		(at 41.565068 -353.547934)
		(property "Reference" "PU78_P1_4"
			(at -13.965428 -4.667504 0)
			(unlocked yes)
			(layer "F.SilkS")
			(effects
				(font
					(size 0.7874 0.5842)
					(thickness 0.1524)
				)
				(justify left)
			)
		)
		(property "Value" ""
			(at 0 0 0)
			(layer "F.Fab")
			(effects
				(font
					(size 1.27 1.27)
				)
			)
		)
		(duplicate_pad_numbers_are_jumpers no)
		(fp_line
			(start -2.500122 -2.999994)
			(end -2.24409 -2.999994)
			(stroke
				(width 0.1524)
				(type default)
			)
			(layer "F.SilkS")
		)
		(fp_line
			(start -2.500122 -2.529078)
			(end -2.500122 -2.999994)
			(stroke
				(width 0.1524)
				(type default)
			)
			(layer "F.SilkS")
		)
		(fp_line
			(start -2.500122 0.6604)
			(end -2.500122 0.229108)
			(stroke
				(width 0.1524)
				(type default)
			)
			(layer "F.SilkS")
		)
		(fp_line
			(start -2.500122 2.999994)
			(end -2.500122 2.339594)
			(stroke
				(width 0.1524)
				(type default)
			)
			(layer "F.SilkS")
		)
		(fp_line
			(start -2.2987 2.999994)
			(end -2.500122 2.999994)
			(stroke
				(width 0.1524)
				(type default)
			)
			(layer "F.SilkS")
		)
		(fp_line
			(start 2.31394 -2.999994)
			(end 2.500122 -2.999994)
			(stroke
				(width 0.1524)
				(type default)
			)
			(layer "F.SilkS")
		)
		(fp_line
			(start 2.500122 -2.999994)
			(end 2.500122 -2.44348)
			(stroke
				(width 0.1524)
				(type default)
			)
			(layer "F.SilkS")
		)
		(fp_line
			(start 2.500122 2.339594)
			(end 2.500122 2.999994)
			(stroke
				(width 0.1524)
				(type default)
			)
			(layer "F.SilkS")
		)
		(fp_line
			(start 2.500122 2.999994)
			(end 2.2987 2.999994)
			(stroke
				(width 0.1524)
				(type default)
			)
			(layer "F.SilkS")
		)
		(fp_poly
			(pts
				(xy -5.457952 -2.871978) (xy -4.441952 -2.363978) (xy -5.457952 -1.855978)
			)
			(stroke
				(width 0)
				(type default)
			)
			(fill yes)
			(layer "F.SilkS")
		)
		(fp_line
			(start -2.500122 -2.999994)
			(end 2.500122 -2.999994)
			(stroke
				(width 0.1)
				(type default)
			)
			(layer "F.Fab")
		)
		(fp_line
			(start -2.500122 2.999994)
			(end -2.500122 -2.999994)
			(stroke
				(width 0.1)
				(type default)
			)
			(layer "F.Fab")
		)
		(fp_line
			(start 2.500122 -2.999994)
			(end 2.500122 2.999994)
			(stroke
				(width 0.1)
				(type default)
			)
			(layer "F.Fab")
		)
		(fp_line
			(start 2.500122 2.999994)
			(end -2.500122 2.999994)
			(stroke
				(width 0.1)
				(type default)
			)
			(layer "F.Fab")
		)
		(fp_poly
			(pts
				(xy -4.218432 -2.783078) (xy -4.218432 -1.767078) (xy -3.202432 -2.275078)
			)
			(stroke
				(width 0)
				(type default)
			)
			(fill yes)
			(layer "F.Fab")
		)
		(pad "1" smd rect
			(at -2.400046 -2.275078 90)
			(size 0.2286 0.6096)
			(layers "F.Cu" "F.Mask" "F.Paste")
			(net "PVCCFA_EHV_FIVRA_CPU1_VOS4")
		)
		(pad "2" smd rect
			(at -2.400046 -1.82499 90)
			(size 0.2286 0.6096)
			(layers "F.Cu" "F.Mask" "F.Paste")
			(net "GND")
		)
		(pad "3" smd rect
			(at -2.400046 -1.374902 90)
			(size 0.2286 0.6096)
			(layers "F.Cu" "F.Mask" "F.Paste")
			(net "PVCCFA_EHV_FIVRA_CPU1_VDD4")
		)
		(pad "4" smd rect
			(at -2.400046 -0.925068 90)
			(size 0.2286 0.6096)
			(layers "F.Cu" "F.Mask" "F.Paste")
			(net "PVCCFA_EHV_FIVRA_CPU1_PVCC2")
		)
		(pad "5" smd rect
			(at -2.400046 -0.47498 90)
			(size 0.2286 0.6096)
			(layers "F.Cu" "F.Mask" "F.Paste")
			(net "GND")
		)
		(pad "6" smd rect
			(at -2.400046 -0.024892 90)
			(size 0.2286 0.6096)
			(layers "F.Cu" "F.Mask" "F.Paste")
			(net "Net_8496")
		)
		(pad "7_9-20_24" smd circle
			(at 0 1.150112 90)
			(size 0 0)
			(layers "F.Cu" "F.Mask" "F.Paste")
			(net "GND")
		)
		(pad "10_19" smd rect
			(at 0 2.899918 90)
			(size 0.6096 4.318)
			(layers "F.Cu" "F.Mask" "F.Paste")
			(net "SW_PVCCFA_EHV_FIVRA_CPU1_SW4")
		)
		(pad "25_29" smd rect
			(at 1.549908 -1.279906 270)
			(size 2.0574 2.3114)
			(layers "F.Cu" "F.Mask" "F.Paste")
			(net "SW_P12V_PVCCFA_EHV_FIVRA_CPU1_L")
		)
		(pad "30" smd rect
			(at 2.05994 -2.899918)
			(size 0.2286 0.6096)
			(layers "F.Cu" "F.Mask" "F.Paste")
			(net "SW_P12V_PVCCFA_EHV_FIVRA_CPU1_L")
		)
		(pad "31" smd rect
			(at 1.610106 -2.899918)
			(size 0.2286 0.6096)
			(layers "F.Cu" "F.Mask" "F.Paste")
			(net "Net_8497")
		)
		(pad "32" smd rect
			(at 1.160018 -2.899918)
			(size 0.2286 0.6096)
			(layers "F.Cu" "F.Mask" "F.Paste")
			(net "SW_PVCCFA_EHV_FIVRA_CPU1_BOOTR4")
		)
		(pad "33" smd rect
			(at 0.70993 -2.899918)
			(size 0.2286 0.6096)
			(layers "F.Cu" "F.Mask" "F.Paste")
			(net "SW_PVCCFA_EHV_FIVRA_CPU1_BOOT4")
		)
		(pad "34" smd rect
			(at 0.260096 -2.899918)
			(size 0.2286 0.6096)
			(layers "F.Cu" "F.Mask" "F.Paste")
			(net "PVCCFA_EHV_FIVRA_CPU1_PWM4")
		)
		(pad "35" smd rect
			(at -0.189992 -2.899918)
			(size 0.2286 0.6096)
			(layers "F.Cu" "F.Mask" "F.Paste")
			(net "PVCCFA_EHV_FIVRA_CPU1_VDD4")
		)
		(pad "36" smd rect
			(at -0.64008 -2.899918)
			(size 0.2286 0.6096)
			(layers "F.Cu" "F.Mask" "F.Paste")
			(net "PVCCFA_EHV_FIVRA_CPU1_BTSEN")
		)
		(pad "37" smd rect
			(at -1.089914 -2.899918)
			(size 0.2286 0.6096)
			(layers "F.Cu" "F.Mask" "F.Paste")
			(net "PVCCFA_EHV_FIVRA_CPU1_LSET4")
		)
		(pad "38" smd rect
			(at -1.540002 -2.899918)
			(size 0.2286 0.6096)
			(layers "F.Cu" "F.Mask" "F.Paste")
			(net "PVCCFA_EHV_FIVRA_CPU1_IMON4")
		)
		(pad "39" smd rect
			(at -1.99009 -2.899918)
			(size 0.2286 0.6096)
			(layers "F.Cu" "F.Mask" "F.Paste")
			(net "PVCCIN_CPU1_VREF")
		)
		(pad "40" smd rect
			(at -0.87503 -1.27508)
			(size 1.7526 1.9558)
			(layers "F.Cu" "F.Mask" "F.Paste")
			(net "GND")
		)
		(pad "41" smd rect
			(at -1.525016 0.249936 270)
			(size 0.3048 0.4572)
			(layers "F.Cu" "F.Mask" "F.Paste")
			(net "Net_8495")
		)
		(zone
			(layer "F.Cu")
			(hatch none 0.5)
			(connect_pads
				(clearance 0)
			)
			(min_thickness 0.25)
			(keepout
				(tracks not_allowed)
				(vias allowed)
				(pads allowed)
				(copperpour not_allowed)
				(footprints allowed)
			)
			(placement
				(enabled no)
				(sheetname "")
			)
			(fill
				(thermal_gap 0.5)
				(thermal_bridge_width 0.5)
				(island_removal_mode 0)
			)
			(polygon
				(pts
					(xy 39.064946 -350.54794) (xy 39.064946 -351.267268) (xy 44.06519 -351.267268) (xy 44.06519 -350.54794)
					(xy 43.774868 -350.54794) (xy 43.774868 -351.003616) (xy 39.355268 -351.003616) (xy 39.355268 -350.54794)
				)
			)
		)
		(zone
			(layer "F.Cu")
			(hatch none 0.5)
			(connect_pads
				(clearance 0)
			)
			(min_thickness 0.25)
			(keepout
				(tracks not_allowed)
				(vias allowed)
				(pads allowed)
				(copperpour not_allowed)
				(footprints allowed)
			)
			(placement
				(enabled no)
				(sheetname "")
			)
			(fill
				(thermal_gap 0.5)
				(thermal_bridge_width 0.5)
				(island_removal_mode 0)
			)
			(polygon
				(pts
					(xy 39.520622 -353.794568) (xy 39.762938 -353.794568) (xy 39.762938 -353.794314) (xy 40.54602 -353.794314)
					(xy 40.54602 -353.438968) (xy 40.614346 -353.438968) (xy 40.614346 -352.86696) (xy 40.54602 -352.798634)
					(xy 39.064946 -352.798634) (xy 39.064946 -353.255326) (xy 39.760652 -353.255326) (xy 39.760652 -353.094798)
					(xy 40.319452 -353.094798) (xy 40.319452 -353.501198) (xy 39.760652 -353.501198) (xy 39.760652 -353.280726)
					(xy 39.064946 -353.280726) (xy 39.064946 -353.407726) (xy 39.520622 -353.407726)
				)
			)
		)
	)
	(footprint ""
		(layer "F.Cu")
		(at 44.169584 -112.619282)
		(property "Reference" "R1800"
			(at 0 0 0)
			(layer "F.SilkS")
			(hide yes)
			(effects
				(font
					(size 1.27 1.27)
				)
			)
		)
		(property "Value" ""
			(at 0 0 0)
			(layer "F.Fab")
			(effects
				(font
					(size 1.27 1.27)
				)
			)
		)
		(duplicate_pad_numbers_are_jumpers no)
		(fp_line
			(start -0.7874 -0.4064)
			(end 0.7874 -0.4064)
			(stroke
				(width 0.1524)
				(type default)
			)
			(layer "F.SilkS")
		)
		(fp_line
			(start -0.7874 0.4064)
			(end -0.7874 -0.4064)
			(stroke
				(width 0.1524)
				(type default)
			)
			(layer "F.SilkS")
		)
		(fp_line
			(start 0.7874 -0.4064)
			(end 0.7874 0.4064)
			(stroke
				(width 0.1524)
				(type default)
			)
			(layer "F.SilkS")
		)
		(fp_line
			(start 0.7874 0.4064)
			(end -0.7874 0.4064)
			(stroke
				(width 0.1524)
				(type default)
			)
			(layer "F.SilkS")
		)
		(fp_line
			(start -0.67945 -0.305054)
			(end -0.12065 -0.305054)
			(stroke
				(width 0.1)
				(type default)
			)
			(layer "F.Fab")
		)
		(fp_line
			(start -0.67945 0.3048)
			(end -0.67945 -0.305054)
			(stroke
				(width 0.1)
				(type default)
			)
			(layer "F.Fab")
		)
		(fp_line
			(start -0.12065 -0.305054)
			(end -0.12065 -0.2794)
			(stroke
				(width 0.1)
				(type default)
			)
			(layer "F.Fab")
		)
		(fp_line
			(start -0.12065 -0.2794)
			(end 0.12065 -0.2794)
			(stroke
				(width 0.1)
				(type default)
			)
			(layer "F.Fab")
		)
		(fp_line
			(start -0.12065 0.2794)
			(end -0.12065 0.3048)
			(stroke
				(width 0.1)
				(type default)
			)
			(layer "F.Fab")
		)
		(fp_line
			(start -0.12065 0.3048)
			(end -0.67945 0.3048)
			(stroke
				(width 0.1)
				(type default)
			)
			(layer "F.Fab")
		)
		(fp_line
			(start 0.120396 0.2794)
			(end -0.12065 0.2794)
			(stroke
				(width 0.1)
				(type default)
			)
			(layer "F.Fab")
		)
		(fp_line
			(start 0.120396 0.3048)
			(end 0.120396 0.2794)
			(stroke
				(width 0.1)
				(type default)
			)
			(layer "F.Fab")
		)
		(fp_line
			(start 0.12065 -0.3048)
			(end 0.67945 -0.3048)
			(stroke
				(width 0.1)
				(type default)
			)
			(layer "F.Fab")
		)
		(fp_line
			(start 0.12065 -0.2794)
			(end 0.12065 -0.3048)
			(stroke
				(width 0.1)
				(type default)
			)
			(layer "F.Fab")
		)
		(fp_line
			(start 0.67945 -0.3048)
			(end 0.67945 0.3048)
			(stroke
				(width 0.1)
				(type default)
			)
			(layer "F.Fab")
		)
		(fp_line
			(start 0.67945 0.3048)
			(end 0.120396 0.3048)
			(stroke
				(width 0.1)
				(type default)
			)
			(layer "F.Fab")
		)
		(pad "1" smd circle
			(at -0.40005 0)
			(size 0 0)
			(layers "F.Cu" "F.Mask" "F.Paste")
			(net "P12V_AUX_ADC")
		)
		(pad "2" smd circle
			(at 0.40005 0)
			(size 0 0)
			(layers "F.Cu" "F.Mask" "F.Paste")
			(net "GND")
		)
	)
	(footprint ""
		(layer "F.Cu")
		(at 415.818828 -165.760654 180)
		(property "Reference" "PC2948"
			(at 0 0 180)
			(layer "F.SilkS")
			(hide yes)
			(effects
				(font
					(size 1.27 1.27)
				)
			)
		)
		(property "Value" ""
			(at 0 0 180)
			(layer "F.Fab")
			(effects
				(font
					(size 1.27 1.27)
				)
			)
		)
		(duplicate_pad_numbers_are_jumpers no)
		(fp_line
			(start 0.7874 0.4064)
			(end -0.7874 0.4064)
			(stroke
				(width 0.1524)
				(type default)
			)
			(layer "F.SilkS")
		)
		(fp_line
			(start 0.7874 -0.4064)
			(end 0.7874 0.4064)
			(stroke
				(width 0.1524)
				(type default)
			)
			(layer "F.SilkS")
		)
		(fp_line
			(start -0.7874 0.4064)
			(end -0.7874 -0.4064)
			(stroke
				(width 0.1524)
				(type default)
			)
			(layer "F.SilkS")
		)
		(fp_line
			(start -0.7874 -0.4064)
			(end 0.7874 -0.4064)
			(stroke
				(width 0.1524)
				(type default)
			)
			(layer "F.SilkS")
		)
		(fp_line
			(start 0.67945 0.3048)
			(end 0.120396 0.3048)
			(stroke
				(width 0.1)
				(type default)
			)
			(layer "F.Fab")
		)
		(fp_line
			(start 0.67945 -0.3048)
			(end 0.67945 0.3048)
			(stroke
				(width 0.1)
				(type default)
			)
			(layer "F.Fab")
		)
		(fp_line
			(start 0.12065 -0.2794)
			(end 0.12065 -0.3048)
			(stroke
				(width 0.1)
				(type default)
			)
			(layer "F.Fab")
		)
		(fp_line
			(start 0.12065 -0.3048)
			(end 0.67945 -0.3048)
			(stroke
				(width 0.1)
				(type default)
			)
			(layer "F.Fab")
		)
		(fp_line
			(start 0.120396 0.3048)
			(end 0.120396 0.2794)
			(stroke
				(width 0.1)
				(type default)
			)
			(layer "F.Fab")
		)
		(fp_line
			(start 0.120396 0.2794)
			(end -0.12065 0.2794)
			(stroke
				(width 0.1)
				(type default)
			)
			(layer "F.Fab")
		)
		(fp_line
			(start -0.12065 0.3048)
			(end -0.67945 0.3048)
			(stroke
				(width 0.1)
				(type default)
			)
			(layer "F.Fab")
		)
		(fp_line
			(start -0.12065 0.2794)
			(end -0.12065 0.3048)
			(stroke
				(width 0.1)
				(type default)
			)
			(layer "F.Fab")
		)
		(fp_line
			(start -0.12065 -0.2794)
			(end 0.12065 -0.2794)
			(stroke
				(width 0.1)
				(type default)
			)
			(layer "F.Fab")
		)
		(fp_line
			(start -0.12065 -0.305054)
			(end -0.12065 -0.2794)
			(stroke
				(width 0.1)
				(type default)
			)
			(layer "F.Fab")
		)
		(fp_line
			(start -0.67945 0.3048)
			(end -0.67945 -0.305054)
			(stroke
				(width 0.1)
				(type default)
			)
			(layer "F.Fab")
		)
		(fp_line
			(start -0.67945 -0.305054)
			(end -0.12065 -0.305054)
			(stroke
				(width 0.1)
				(type default)
			)
			(layer "F.Fab")
		)
		(pad "1" smd circle
			(at -0.40005 0 180)
			(size 0 0)
			(layers "F.Cu" "F.Mask" "F.Paste")
			(net "PVCCFA_EHV_CPU0_PVCC")
		)
		(pad "2" smd circle
			(at 0.40005 0 180)
			(size 0 0)
			(layers "F.Cu" "F.Mask" "F.Paste")
			(net "GND")
		)
	)
	(footprint ""
		(layer "F.Cu")
		(at 254.161544 -398.78 90)
		(property "Reference" "PPQ5"
			(at -8.245856 -1.914144 0)
			(unlocked yes)
			(layer "F.SilkS")
			(effects
				(font
					(size 0.7874 0.5842)
					(thickness 0.1524)
				)
				(justify left)
			)
		)
		(property "Value" ""
			(at 0 0 90)
			(layer "F.Fab")
			(effects
				(font
					(size 1.27 1.27)
				)
			)
		)
		(duplicate_pad_numbers_are_jumpers no)
		(fp_line
			(start 2.350008 -2.649982)
			(end 2.350008 -2.4892)
			(stroke
				(width 0.1524)
				(type default)
			)
			(layer "F.SilkS")
		)
		(fp_line
			(start -2.350008 -2.649982)
			(end 2.350008 -2.649982)
			(stroke
				(width 0.1524)
				(type default)
			)
			(layer "F.SilkS")
		)
		(fp_line
			(start -2.350008 -2.4384)
			(end -2.350008 -2.649982)
			(stroke
				(width 0.1524)
				(type default)
			)
			(layer "F.SilkS")
		)
		(fp_line
			(start 2.350008 2.4892)
			(end 2.350008 2.649982)
			(stroke
				(width 0.1524)
				(type default)
			)
			(layer "F.SilkS")
		)
		(fp_line
			(start 2.350008 2.649982)
			(end -2.350008 2.649982)
			(stroke
				(width 0.1524)
				(type default)
			)
			(layer "F.SilkS")
		)
		(fp_line
			(start -2.350008 2.649982)
			(end -2.350008 2.413)
			(stroke
				(width 0.1524)
				(type default)
			)
			(layer "F.SilkS")
		)
		(fp_poly
			(pts
				(xy -3.717544 -1.905) (xy -4.758944 -2.3241) (xy -4.758944 -1.524)
			)
			(stroke
				(width 0)
				(type default)
			)
			(fill yes)
			(layer "F.SilkS")
		)
		(fp_line
			(start 2.350008 -2.649982)
			(end 2.350008 2.649982)
			(stroke
				(width 0.1)
				(type default)
			)
			(layer "F.Fab")
		)
		(fp_line
			(start -2.350008 -2.649982)
			(end 2.350008 -2.649982)
			(stroke
				(width 0.1)
				(type default)
			)
			(layer "F.Fab")
		)
		(fp_line
			(start 2.350008 2.649982)
			(end -2.350008 2.649982)
			(stroke
				(width 0.1)
				(type default)
			)
			(layer "F.Fab")
		)
		(fp_line
			(start -2.350008 2.649982)
			(end -2.350008 -2.649982)
			(stroke
				(width 0.1)
				(type default)
			)
			(layer "F.Fab")
		)
		(fp_poly
			(pts
				(xy -3.717544 -1.905) (xy -4.758944 -2.3241) (xy -4.758944 -1.524)
			)
			(stroke
				(width 0)
				(type default)
			)
			(fill yes)
			(layer "F.Fab")
		)
		(pad "1" smd rect
			(at -2.999994 -1.905)
			(size 0.7112 1.1684)
			(layers "F.Cu" "F.Mask" "F.Paste")
			(net "P12V_AUX")
		)
		(pad "2" smd rect
			(at -2.999994 -0.635)
			(size 0.7112 1.1684)
			(layers "F.Cu" "F.Mask" "F.Paste")
			(net "P12V_AUX")
		)
		(pad "3" smd rect
			(at -2.999994 0.635)
			(size 0.7112 1.1684)
			(layers "F.Cu" "F.Mask" "F.Paste")
			(net "P12V_AUX")
		)
		(pad "4" smd rect
			(at -2.999994 1.905)
			(size 0.7112 1.1684)
			(layers "F.Cu" "F.Mask" "F.Paste")
			(net "P12V_HSC_GATE_G1")
		)
		(pad "5" smd circle
			(at 0.925068 0)
			(size 0 0)
			(layers "F.Cu" "F.Mask" "F.Paste")
			(net "P12V_MAIN_R")
		)
		(zone
			(layer "F.Cu")
			(hatch none 0.5)
			(connect_pads
				(clearance 0)
			)
			(min_thickness 0.25)
			(keepout
				(tracks not_allowed)
				(vias allowed)
				(pads allowed)
				(copperpour not_allowed)
				(footprints allowed)
			)
			(placement
				(enabled no)
				(sheetname "")
			)
			(fill
				(thermal_gap 0.5)
				(thermal_bridge_width 0.5)
				(island_removal_mode 0)
			)
			(polygon
				(pts
					(xy 252.002544 -397.3322) (xy 256.320544 -397.3322) (xy 256.320544 -397.33982) (xy 256.803144 -397.33982)
					(xy 256.803144 -396.4305) (xy 251.519944 -396.4305) (xy 251.519944 -397.3322)
				)
			)
		)
	)
	(footprint ""
		(layer "F.Cu")
		(at 120.315482 -14.20749)
		(property "Reference" "R4185"
			(at 0 0 0)
			(layer "F.SilkS")
			(hide yes)
			(effects
				(font
					(size 1.27 1.27)
				)
			)
		)
		(property "Value" ""
			(at 0 0 0)
			(layer "F.Fab")
			(effects
				(font
					(size 1.27 1.27)
				)
			)
		)
		(duplicate_pad_numbers_are_jumpers no)
		(fp_line
			(start -0.7874 -0.4064)
			(end 0.7874 -0.4064)
			(stroke
				(width 0.1524)
				(type default)
			)
			(layer "F.SilkS")
		)
		(fp_line
			(start -0.7874 0.4064)
			(end -0.7874 -0.4064)
			(stroke
				(width 0.1524)
				(type default)
			)
			(layer "F.SilkS")
		)
		(fp_line
			(start 0.7874 -0.4064)
			(end 0.7874 0.4064)
			(stroke
				(width 0.1524)
				(type default)
			)
			(layer "F.SilkS")
		)
		(fp_line
			(start 0.7874 0.4064)
			(end -0.7874 0.4064)
			(stroke
				(width 0.1524)
				(type default)
			)
			(layer "F.SilkS")
		)
		(fp_line
			(start -0.67945 -0.305054)
			(end -0.12065 -0.305054)
			(stroke
				(width 0.1)
				(type default)
			)
			(layer "F.Fab")
		)
		(fp_line
			(start -0.67945 0.3048)
			(end -0.67945 -0.305054)
			(stroke
				(width 0.1)
				(type default)
			)
			(layer "F.Fab")
		)
		(fp_line
			(start -0.12065 -0.305054)
			(end -0.12065 -0.2794)
			(stroke
				(width 0.1)
				(type default)
			)
			(layer "F.Fab")
		)
		(fp_line
			(start -0.12065 -0.2794)
			(end 0.12065 -0.2794)
			(stroke
				(width 0.1)
				(type default)
			)
			(layer "F.Fab")
		)
		(fp_line
			(start -0.12065 0.2794)
			(end -0.12065 0.3048)
			(stroke
				(width 0.1)
				(type default)
			)
			(layer "F.Fab")
		)
		(fp_line
			(start -0.12065 0.3048)
			(end -0.67945 0.3048)
			(stroke
				(width 0.1)
				(type default)
			)
			(layer "F.Fab")
		)
		(fp_line
			(start 0.120396 0.2794)
			(end -0.12065 0.2794)
			(stroke
				(width 0.1)
				(type default)
			)
			(layer "F.Fab")
		)
		(fp_line
			(start 0.120396 0.3048)
			(end 0.120396 0.2794)
			(stroke
				(width 0.1)
				(type default)
			)
			(layer "F.Fab")
		)
		(fp_line
			(start 0.12065 -0.3048)
			(end 0.67945 -0.3048)
			(stroke
				(width 0.1)
				(type default)
			)
			(layer "F.Fab")
		)
		(fp_line
			(start 0.12065 -0.2794)
			(end 0.12065 -0.3048)
			(stroke
				(width 0.1)
				(type default)
			)
			(layer "F.Fab")
		)
		(fp_line
			(start 0.67945 -0.3048)
			(end 0.67945 0.3048)
			(stroke
				(width 0.1)
				(type default)
			)
			(layer "F.Fab")
		)
		(fp_line
			(start 0.67945 0.3048)
			(end 0.120396 0.3048)
			(stroke
				(width 0.1)
				(type default)
			)
			(layer "F.Fab")
		)
		(pad "1" smd circle
			(at -0.40005 0)
			(size 0 0)
			(layers "F.Cu" "F.Mask" "F.Paste")
			(net "U273_3_ADD2")
		)
		(pad "2" smd circle
			(at 0.40005 0)
			(size 0 0)
			(layers "F.Cu" "F.Mask" "F.Paste")
			(net "GND")
		)
	)
	(footprint ""
		(layer "F.Cu")
		(at 220.100652 -106.384344)
		(property "Reference" "R2238"
			(at 0 0 0)
			(layer "F.SilkS")
			(hide yes)
			(effects
				(font
					(size 1.27 1.27)
				)
			)
		)
		(property "Value" ""
			(at 0 0 0)
			(layer "F.Fab")
			(effects
				(font
					(size 1.27 1.27)
				)
			)
		)
		(duplicate_pad_numbers_are_jumpers no)
		(fp_line
			(start -0.7874 -0.4064)
			(end 0.7874 -0.4064)
			(stroke
				(width 0.1524)
				(type default)
			)
			(layer "F.SilkS")
		)
		(fp_line
			(start -0.7874 0.4064)
			(end -0.7874 -0.4064)
			(stroke
				(width 0.1524)
				(type default)
			)
			(layer "F.SilkS")
		)
		(fp_line
			(start 0.7874 -0.4064)
			(end 0.7874 0.4064)
			(stroke
				(width 0.1524)
				(type default)
			)
			(layer "F.SilkS")
		)
		(fp_line
			(start 0.7874 0.4064)
			(end -0.7874 0.4064)
			(stroke
				(width 0.1524)
				(type default)
			)
			(layer "F.SilkS")
		)
		(fp_line
			(start -0.67945 -0.305054)
			(end -0.12065 -0.305054)
			(stroke
				(width 0.1)
				(type default)
			)
			(layer "F.Fab")
		)
		(fp_line
			(start -0.67945 0.3048)
			(end -0.67945 -0.305054)
			(stroke
				(width 0.1)
				(type default)
			)
			(layer "F.Fab")
		)
		(fp_line
			(start -0.12065 -0.305054)
			(end -0.12065 -0.2794)
			(stroke
				(width 0.1)
				(type default)
			)
			(layer "F.Fab")
		)
		(fp_line
			(start -0.12065 -0.2794)
			(end 0.12065 -0.2794)
			(stroke
				(width 0.1)
				(type default)
			)
			(layer "F.Fab")
		)
		(fp_line
			(start -0.12065 0.2794)
			(end -0.12065 0.3048)
			(stroke
				(width 0.1)
				(type default)
			)
			(layer "F.Fab")
		)
		(fp_line
			(start -0.12065 0.3048)
			(end -0.67945 0.3048)
			(stroke
				(width 0.1)
				(type default)
			)
			(layer "F.Fab")
		)
		(fp_line
			(start 0.120396 0.2794)
			(end -0.12065 0.2794)
			(stroke
				(width 0.1)
				(type default)
			)
			(layer "F.Fab")
		)
		(fp_line
			(start 0.120396 0.3048)
			(end 0.120396 0.2794)
			(stroke
				(width 0.1)
				(type default)
			)
			(layer "F.Fab")
		)
		(fp_line
			(start 0.12065 -0.3048)
			(end 0.67945 -0.3048)
			(stroke
				(width 0.1)
				(type default)
			)
			(layer "F.Fab")
		)
		(fp_line
			(start 0.12065 -0.2794)
			(end 0.12065 -0.3048)
			(stroke
				(width 0.1)
				(type default)
			)
			(layer "F.Fab")
		)
		(fp_line
			(start 0.67945 -0.3048)
			(end 0.67945 0.3048)
			(stroke
				(width 0.1)
				(type default)
			)
			(layer "F.Fab")
		)
		(fp_line
			(start 0.67945 0.3048)
			(end 0.120396 0.3048)
			(stroke
				(width 0.1)
				(type default)
			)
			(layer "F.Fab")
		)
		(pad "1" smd circle
			(at -0.40005 0)
			(size 0 0)
			(layers "F.Cu" "F.Mask" "F.Paste")
			(net "A_HSC_INAP")
		)
		(pad "2" smd circle
			(at 0.40005 0)
			(size 0 0)
			(layers "F.Cu" "F.Mask" "F.Paste")
			(net "GND")
		)
	)
	(footprint ""
		(layer "F.Cu")
		(at 213.1568 -110.617 90)
		(property "Reference" "U340"
			(at 4.54533 -0.5588 0)
			(unlocked yes)
			(layer "F.SilkS")
			(effects
				(font
					(size 0.7874 0.5842)
					(thickness 0.1524)
				)
			)
		)
		(property "Value" ""
			(at 0 0 90)
			(layer "F.Fab")
			(effects
				(font
					(size 1.27 1.27)
				)
			)
		)
		(duplicate_pad_numbers_are_jumpers no)
		(fp_line
			(start 2.032 -1.549908)
			(end 2.032 1.549908)
			(stroke
				(width 0.1524)
				(type default)
			)
			(layer "F.SilkS")
		)
		(fp_line
			(start 0.508 -1.549908)
			(end 2.032 -1.549908)
			(stroke
				(width 0.1524)
				(type default)
			)
			(layer "F.SilkS")
		)
		(fp_line
			(start -0.508 -1.549908)
			(end 0 -0.762)
			(stroke
				(width 0.1524)
				(type default)
			)
			(layer "F.SilkS")
		)
		(fp_line
			(start -2.032 -1.549908)
			(end -0.508 -1.549908)
			(stroke
				(width 0.1524)
				(type default)
			)
			(layer "F.SilkS")
		)
		(fp_line
			(start 0 -0.762)
			(end 0.508 -1.549908)
			(stroke
				(width 0.1524)
				(type default)
			)
			(layer "F.SilkS")
		)
		(fp_line
			(start 2.032 1.549908)
			(end -2.032 1.549908)
			(stroke
				(width 0.1524)
				(type default)
			)
			(layer "F.SilkS")
		)
		(fp_line
			(start -2.032 1.549908)
			(end -2.032 -1.549908)
			(stroke
				(width 0.1524)
				(type default)
			)
			(layer "F.SilkS")
		)
		(fp_poly
			(pts
				(xy -2.37363 -1.825244) (xy -1.764538 -1.622298) (xy -1.967738 -2.231136)
			)
			(stroke
				(width 0)
				(type default)
			)
			(fill yes)
			(layer "F.SilkS")
		)
		(fp_line
			(start 0.849884 -1.549908)
			(end 0.849884 1.549908)
			(stroke
				(width 0.1)
				(type default)
			)
			(layer "F.Fab")
		)
		(fp_line
			(start -0.849884 -1.549908)
			(end 0.849884 -1.549908)
			(stroke
				(width 0.1)
				(type default)
			)
			(layer "F.Fab")
		)
		(fp_line
			(start 0.849884 1.549908)
			(end -0.849884 1.549908)
			(stroke
				(width 0.1)
				(type default)
			)
			(layer "F.Fab")
		)
		(fp_line
			(start -0.849884 1.549908)
			(end -0.849884 -1.549908)
			(stroke
				(width 0.1)
				(type default)
			)
			(layer "F.Fab")
		)
		(fp_poly
			(pts
				(xy -3.2004 -1.45796) (xy -3.2004 -0.44196) (xy -2.1844 -0.94996)
			)
			(stroke
				(width 0)
				(type default)
			)
			(fill yes)
			(layer "F.Fab")
		)
		(pad "1" smd rect
			(at -1.35001 -0.94996)
			(size 0.6096 1.0668)
			(layers "F.Cu" "F.Mask" "F.Paste")
			(net "UV_P2V5_COMP")
		)
		(pad "2" smd rect
			(at -1.35001 0)
			(size 0.6096 1.0668)
			(layers "F.Cu" "F.Mask" "F.Paste")
			(net "GND")
		)
		(pad "3" smd rect
			(at -1.35001 0.94996)
			(size 0.6096 1.0668)
			(layers "F.Cu" "F.Mask" "F.Paste")
			(net "P12V_AUX_UV_TRIGGER")
		)
		(pad "4" smd rect
			(at 1.35001 0.94996)
			(size 0.6096 1.0668)
			(layers "F.Cu" "F.Mask" "F.Paste")
			(net "IRQ_UV_DETECT_R2_N")
		)
		(pad "5" smd rect
			(at 1.35001 -0.94996)
			(size 0.6096 1.0668)
			(layers "F.Cu" "F.Mask" "F.Paste")
			(net "P12V_AUX")
		)
	)
	(footprint ""
		(layer "F.Cu")
		(at 382.168908 -78.424024 90)
		(property "Reference" "PR1330"
			(at 0 0 90)
			(layer "F.SilkS")
			(hide yes)
			(effects
				(font
					(size 1.27 1.27)
				)
			)
		)
		(property "Value" ""
			(at 0 0 90)
			(layer "F.Fab")
			(effects
				(font
					(size 1.27 1.27)
				)
			)
		)
		(duplicate_pad_numbers_are_jumpers no)
		(fp_line
			(start 0.7874 -0.4064)
			(end 0.7874 0.4064)
			(stroke
				(width 0.1524)
				(type default)
			)
			(layer "F.SilkS")
		)
		(fp_line
			(start -0.7874 -0.4064)
			(end 0.7874 -0.4064)
			(stroke
				(width 0.1524)
				(type default)
			)
			(layer "F.SilkS")
		)
		(fp_line
			(start 0.7874 0.4064)
			(end -0.7874 0.4064)
			(stroke
				(width 0.1524)
				(type default)
			)
			(layer "F.SilkS")
		)
		(fp_line
			(start -0.7874 0.4064)
			(end -0.7874 -0.4064)
			(stroke
				(width 0.1524)
				(type default)
			)
			(layer "F.SilkS")
		)
		(fp_line
			(start -0.12065 -0.305054)
			(end -0.12065 -0.2794)
			(stroke
				(width 0.1)
				(type default)
			)
			(layer "F.Fab")
		)
		(fp_line
			(start -0.67945 -0.305054)
			(end -0.12065 -0.305054)
			(stroke
				(width 0.1)
				(type default)
			)
			(layer "F.Fab")
		)
		(fp_line
			(start 0.67945 -0.3048)
			(end 0.67945 0.3048)
			(stroke
				(width 0.1)
				(type default)
			)
			(layer "F.Fab")
		)
		(fp_line
			(start 0.12065 -0.3048)
			(end 0.67945 -0.3048)
			(stroke
				(width 0.1)
				(type default)
			)
			(layer "F.Fab")
		)
		(fp_line
			(start 0.12065 -0.2794)
			(end 0.12065 -0.3048)
			(stroke
				(width 0.1)
				(type default)
			)
			(layer "F.Fab")
		)
		(fp_line
			(start -0.12065 -0.2794)
			(end 0.12065 -0.2794)
			(stroke
				(width 0.1)
				(type default)
			)
			(layer "F.Fab")
		)
		(fp_line
			(start 0.120396 0.2794)
			(end -0.12065 0.2794)
			(stroke
				(width 0.1)
				(type default)
			)
			(layer "F.Fab")
		)
		(fp_line
			(start -0.12065 0.2794)
			(end -0.12065 0.3048)
			(stroke
				(width 0.1)
				(type default)
			)
			(layer "F.Fab")
		)
		(fp_line
			(start 0.67945 0.3048)
			(end 0.120396 0.3048)
			(stroke
				(width 0.1)
				(type default)
			)
			(layer "F.Fab")
		)
		(fp_line
			(start 0.120396 0.3048)
			(end 0.120396 0.2794)
			(stroke
				(width 0.1)
				(type default)
			)
			(layer "F.Fab")
		)
		(fp_line
			(start -0.12065 0.3048)
			(end -0.67945 0.3048)
			(stroke
				(width 0.1)
				(type default)
			)
			(layer "F.Fab")
		)
		(fp_line
			(start -0.67945 0.3048)
			(end -0.67945 -0.305054)
			(stroke
				(width 0.1)
				(type default)
			)
			(layer "F.Fab")
		)
		(pad "1" smd circle
			(at -0.40005 0 90)
			(size 0 0)
			(layers "F.Cu" "F.Mask" "F.Paste")
			(net "P1V8_PCH_AUX_MODE")
		)
		(pad "2" smd circle
			(at 0.40005 0 90)
			(size 0 0)
			(layers "F.Cu" "F.Mask" "F.Paste")
			(net "GND")
		)
	)
	(footprint ""
		(layer "F.Cu")
		(at 37.990272 -353.35718 -90)
		(property "Reference" "PC1245_P1_4"
			(at 0 0 270)
			(layer "F.SilkS")
			(hide yes)
			(effects
				(font
					(size 1.27 1.27)
				)
			)
		)
		(property "Value" ""
			(at 0 0 270)
			(layer "F.Fab")
			(effects
				(font
					(size 1.27 1.27)
				)
			)
		)
		(duplicate_pad_numbers_are_jumpers no)
		(fp_line
			(start -0.7874 0.4064)
			(end -0.7874 -0.4064)
			(stroke
				(width 0.1524)
				(type default)
			)
			(layer "F.SilkS")
		)
		(fp_line
			(start 0.7874 0.4064)
			(end -0.7874 0.4064)
			(stroke
				(width 0.1524)
				(type default)
			)
			(layer "F.SilkS")
		)
		(fp_line
			(start -0.7874 -0.4064)
			(end 0.7874 -0.4064)
			(stroke
				(width 0.1524)
				(type default)
			)
			(layer "F.SilkS")
		)
		(fp_line
			(start 0.7874 -0.4064)
			(end 0.7874 0.4064)
			(stroke
				(width 0.1524)
				(type default)
			)
			(layer "F.SilkS")
		)
		(fp_line
			(start -0.67945 0.3048)
			(end -0.67945 -0.305054)
			(stroke
				(width 0.1)
				(type default)
			)
			(layer "F.Fab")
		)
		(fp_line
			(start -0.12065 0.3048)
			(end -0.67945 0.3048)
			(stroke
				(width 0.1)
				(type default)
			)
			(layer "F.Fab")
		)
		(fp_line
			(start 0.120396 0.3048)
			(end 0.120396 0.2794)
			(stroke
				(width 0.1)
				(type default)
			)
			(layer "F.Fab")
		)
		(fp_line
			(start 0.67945 0.3048)
			(end 0.120396 0.3048)
			(stroke
				(width 0.1)
				(type default)
			)
			(layer "F.Fab")
		)
		(fp_line
			(start -0.12065 0.2794)
			(end -0.12065 0.3048)
			(stroke
				(width 0.1)
				(type default)
			)
			(layer "F.Fab")
		)
		(fp_line
			(start 0.120396 0.2794)
			(end -0.12065 0.2794)
			(stroke
				(width 0.1)
				(type default)
			)
			(layer "F.Fab")
		)
		(fp_line
			(start -0.12065 -0.2794)
			(end 0.12065 -0.2794)
			(stroke
				(width 0.1)
				(type default)
			)
			(layer "F.Fab")
		)
		(fp_line
			(start 0.12065 -0.2794)
			(end 0.12065 -0.3048)
			(stroke
				(width 0.1)
				(type default)
			)
			(layer "F.Fab")
		)
		(fp_line
			(start 0.12065 -0.3048)
			(end 0.67945 -0.3048)
			(stroke
				(width 0.1)
				(type default)
			)
			(layer "F.Fab")
		)
		(fp_line
			(start 0.67945 -0.3048)
			(end 0.67945 0.3048)
			(stroke
				(width 0.1)
				(type default)
			)
			(layer "F.Fab")
		)
		(fp_line
			(start -0.67945 -0.305054)
			(end -0.12065 -0.305054)
			(stroke
				(width 0.1)
				(type default)
			)
			(layer "F.Fab")
		)
		(fp_line
			(start -0.12065 -0.305054)
			(end -0.12065 -0.2794)
			(stroke
				(width 0.1)
				(type default)
			)
			(layer "F.Fab")
		)
		(pad "1" smd circle
			(at -0.40005 0 270)
			(size 0 0)
			(layers "F.Cu" "F.Mask" "F.Paste")
			(net "PVCCFA_EHV_FIVRA_CPU1_PVCC2")
		)
		(pad "2" smd circle
			(at 0.40005 0 270)
			(size 0 0)
			(layers "F.Cu" "F.Mask" "F.Paste")
			(net "GND")
		)
	)
	(footprint ""
		(layer "F.Cu")
		(at 20.11426 -163.719256)
		(property "Reference" "R2593"
			(at 0 0 0)
			(layer "F.SilkS")
			(hide yes)
			(effects
				(font
					(size 1.27 1.27)
				)
			)
		)
		(property "Value" ""
			(at 0 0 0)
			(layer "F.Fab")
			(effects
				(font
					(size 1.27 1.27)
				)
			)
		)
		(duplicate_pad_numbers_are_jumpers no)
		(fp_line
			(start -0.7874 -0.4064)
			(end 0.7874 -0.4064)
			(stroke
				(width 0.1524)
				(type default)
			)
			(layer "F.SilkS")
		)
		(fp_line
			(start -0.7874 0.4064)
			(end -0.7874 -0.4064)
			(stroke
				(width 0.1524)
				(type default)
			)
			(layer "F.SilkS")
		)
		(fp_line
			(start 0.7874 -0.4064)
			(end 0.7874 0.4064)
			(stroke
				(width 0.1524)
				(type default)
			)
			(layer "F.SilkS")
		)
		(fp_line
			(start 0.7874 0.4064)
			(end -0.7874 0.4064)
			(stroke
				(width 0.1524)
				(type default)
			)
			(layer "F.SilkS")
		)
		(fp_line
			(start -0.67945 -0.305054)
			(end -0.12065 -0.305054)
			(stroke
				(width 0.1)
				(type default)
			)
			(layer "F.Fab")
		)
		(fp_line
			(start -0.67945 0.3048)
			(end -0.67945 -0.305054)
			(stroke
				(width 0.1)
				(type default)
			)
			(layer "F.Fab")
		)
		(fp_line
			(start -0.12065 -0.305054)
			(end -0.12065 -0.2794)
			(stroke
				(width 0.1)
				(type default)
			)
			(layer "F.Fab")
		)
		(fp_line
			(start -0.12065 -0.2794)
			(end 0.12065 -0.2794)
			(stroke
				(width 0.1)
				(type default)
			)
			(layer "F.Fab")
		)
		(fp_line
			(start -0.12065 0.2794)
			(end -0.12065 0.3048)
			(stroke
				(width 0.1)
				(type default)
			)
			(layer "F.Fab")
		)
		(fp_line
			(start -0.12065 0.3048)
			(end -0.67945 0.3048)
			(stroke
				(width 0.1)
				(type default)
			)
			(layer "F.Fab")
		)
		(fp_line
			(start 0.120396 0.2794)
			(end -0.12065 0.2794)
			(stroke
				(width 0.1)
				(type default)
			)
			(layer "F.Fab")
		)
		(fp_line
			(start 0.120396 0.3048)
			(end 0.120396 0.2794)
			(stroke
				(width 0.1)
				(type default)
			)
			(layer "F.Fab")
		)
		(fp_line
			(start 0.12065 -0.3048)
			(end 0.67945 -0.3048)
			(stroke
				(width 0.1)
				(type default)
			)
			(layer "F.Fab")
		)
		(fp_line
			(start 0.12065 -0.2794)
			(end 0.12065 -0.3048)
			(stroke
				(width 0.1)
				(type default)
			)
			(layer "F.Fab")
		)
		(fp_line
			(start 0.67945 -0.3048)
			(end 0.67945 0.3048)
			(stroke
				(width 0.1)
				(type default)
			)
			(layer "F.Fab")
		)
		(fp_line
			(start 0.67945 0.3048)
			(end 0.120396 0.3048)
			(stroke
				(width 0.1)
				(type default)
			)
			(layer "F.Fab")
		)
		(pad "1" smd circle
			(at -0.40005 0)
			(size 0 0)
			(layers "F.Cu" "F.Mask" "F.Paste")
			(net "PVNN_TERM_CPU1")
		)
		(pad "2" smd circle
			(at 0.40005 0)
			(size 0 0)
			(layers "F.Cu" "F.Mask" "F.Paste")
			(net "SVID_DIO1_CPU1_R")
		)
	)
	(footprint ""
		(layer "F.Cu")
		(at 312.443622 -41.519348 180)
		(property "Reference" "R1581"
			(at 0 0 180)
			(layer "F.SilkS")
			(hide yes)
			(effects
				(font
					(size 1.27 1.27)
				)
			)
		)
		(property "Value" ""
			(at 0 0 180)
			(layer "F.Fab")
			(effects
				(font
					(size 1.27 1.27)
				)
			)
		)
		(duplicate_pad_numbers_are_jumpers no)
		(fp_line
			(start 0.7874 0.4064)
			(end -0.7874 0.4064)
			(stroke
				(width 0.1524)
				(type default)
			)
			(layer "F.SilkS")
		)
		(fp_line
			(start 0.7874 -0.4064)
			(end 0.7874 0.4064)
			(stroke
				(width 0.1524)
				(type default)
			)
			(layer "F.SilkS")
		)
		(fp_line
			(start -0.7874 0.4064)
			(end -0.7874 -0.4064)
			(stroke
				(width 0.1524)
				(type default)
			)
			(layer "F.SilkS")
		)
		(fp_line
			(start -0.7874 -0.4064)
			(end 0.7874 -0.4064)
			(stroke
				(width 0.1524)
				(type default)
			)
			(layer "F.SilkS")
		)
		(fp_line
			(start 0.67945 0.3048)
			(end 0.120396 0.3048)
			(stroke
				(width 0.1)
				(type default)
			)
			(layer "F.Fab")
		)
		(fp_line
			(start 0.67945 -0.3048)
			(end 0.67945 0.3048)
			(stroke
				(width 0.1)
				(type default)
			)
			(layer "F.Fab")
		)
		(fp_line
			(start 0.12065 -0.2794)
			(end 0.12065 -0.3048)
			(stroke
				(width 0.1)
				(type default)
			)
			(layer "F.Fab")
		)
		(fp_line
			(start 0.12065 -0.3048)
			(end 0.67945 -0.3048)
			(stroke
				(width 0.1)
				(type default)
			)
			(layer "F.Fab")
		)
		(fp_line
			(start 0.120396 0.3048)
			(end 0.120396 0.2794)
			(stroke
				(width 0.1)
				(type default)
			)
			(layer "F.Fab")
		)
		(fp_line
			(start 0.120396 0.2794)
			(end -0.12065 0.2794)
			(stroke
				(width 0.1)
				(type default)
			)
			(layer "F.Fab")
		)
		(fp_line
			(start -0.12065 0.3048)
			(end -0.67945 0.3048)
			(stroke
				(width 0.1)
				(type default)
			)
			(layer "F.Fab")
		)
		(fp_line
			(start -0.12065 0.2794)
			(end -0.12065 0.3048)
			(stroke
				(width 0.1)
				(type default)
			)
			(layer "F.Fab")
		)
		(fp_line
			(start -0.12065 -0.2794)
			(end 0.12065 -0.2794)
			(stroke
				(width 0.1)
				(type default)
			)
			(layer "F.Fab")
		)
		(fp_line
			(start -0.12065 -0.305054)
			(end -0.12065 -0.2794)
			(stroke
				(width 0.1)
				(type default)
			)
			(layer "F.Fab")
		)
		(fp_line
			(start -0.67945 0.3048)
			(end -0.67945 -0.305054)
			(stroke
				(width 0.1)
				(type default)
			)
			(layer "F.Fab")
		)
		(fp_line
			(start -0.67945 -0.305054)
			(end -0.12065 -0.305054)
			(stroke
				(width 0.1)
				(type default)
			)
			(layer "F.Fab")
		)
		(pad "1" smd circle
			(at -0.40005 0 180)
			(size 0 0)
			(layers "F.Cu" "F.Mask" "F.Paste")
			(net "PU_SMB_PCH_PLD_3V3AUX_SCL")
		)
		(pad "2" smd circle
			(at 0.40005 0 180)
			(size 0 0)
			(layers "F.Cu" "F.Mask" "F.Paste")
			(net "P3V3_AUX")
		)
	)
	(footprint ""
		(layer "F.Cu")
		(at 14.689582 -423.629836 -90)
		(property "Reference" "R2695"
			(at 0 0 270)
			(layer "F.SilkS")
			(hide yes)
			(effects
				(font
					(size 1.27 1.27)
				)
			)
		)
		(property "Value" ""
			(at 0 0 270)
			(layer "F.Fab")
			(effects
				(font
					(size 1.27 1.27)
				)
			)
		)
		(duplicate_pad_numbers_are_jumpers no)
		(fp_line
			(start -0.7874 0.4064)
			(end -0.7874 -0.4064)
			(stroke
				(width 0.1524)
				(type default)
			)
			(layer "F.SilkS")
		)
		(fp_line
			(start 0.7874 0.4064)
			(end -0.7874 0.4064)
			(stroke
				(width 0.1524)
				(type default)
			)
			(layer "F.SilkS")
		)
		(fp_line
			(start -0.7874 -0.4064)
			(end 0.7874 -0.4064)
			(stroke
				(width 0.1524)
				(type default)
			)
			(layer "F.SilkS")
		)
		(fp_line
			(start 0.7874 -0.4064)
			(end 0.7874 0.4064)
			(stroke
				(width 0.1524)
				(type default)
			)
			(layer "F.SilkS")
		)
		(fp_line
			(start -0.67945 0.3048)
			(end -0.67945 -0.305054)
			(stroke
				(width 0.1)
				(type default)
			)
			(layer "F.Fab")
		)
		(fp_line
			(start -0.12065 0.3048)
			(end -0.67945 0.3048)
			(stroke
				(width 0.1)
				(type default)
			)
			(layer "F.Fab")
		)
		(fp_line
			(start 0.120396 0.3048)
			(end 0.120396 0.2794)
			(stroke
				(width 0.1)
				(type default)
			)
			(layer "F.Fab")
		)
		(fp_line
			(start 0.67945 0.3048)
			(end 0.120396 0.3048)
			(stroke
				(width 0.1)
				(type default)
			)
			(layer "F.Fab")
		)
		(fp_line
			(start -0.12065 0.2794)
			(end -0.12065 0.3048)
			(stroke
				(width 0.1)
				(type default)
			)
			(layer "F.Fab")
		)
		(fp_line
			(start 0.120396 0.2794)
			(end -0.12065 0.2794)
			(stroke
				(width 0.1)
				(type default)
			)
			(layer "F.Fab")
		)
		(fp_line
			(start -0.12065 -0.2794)
			(end 0.12065 -0.2794)
			(stroke
				(width 0.1)
				(type default)
			)
			(layer "F.Fab")
		)
		(fp_line
			(start 0.12065 -0.2794)
			(end 0.12065 -0.3048)
			(stroke
				(width 0.1)
				(type default)
			)
			(layer "F.Fab")
		)
		(fp_line
			(start 0.12065 -0.3048)
			(end 0.67945 -0.3048)
			(stroke
				(width 0.1)
				(type default)
			)
			(layer "F.Fab")
		)
		(fp_line
			(start 0.67945 -0.3048)
			(end 0.67945 0.3048)
			(stroke
				(width 0.1)
				(type default)
			)
			(layer "F.Fab")
		)
		(fp_line
			(start -0.67945 -0.305054)
			(end -0.12065 -0.305054)
			(stroke
				(width 0.1)
				(type default)
			)
			(layer "F.Fab")
		)
		(fp_line
			(start -0.12065 -0.305054)
			(end -0.12065 -0.2794)
			(stroke
				(width 0.1)
				(type default)
			)
			(layer "F.Fab")
		)
		(pad "1" smd circle
			(at -0.40005 0 270)
			(size 0 0)
			(layers "F.Cu" "F.Mask" "F.Paste")
			(net "P3V3_AUX")
		)
		(pad "2" smd circle
			(at 0.40005 0 270)
			(size 0 0)
			(layers "F.Cu" "F.Mask" "F.Paste")
			(net "TCA9539_0_ADD0")
		)
	)
	(footprint ""
		(layer "F.Cu")
		(at 97.821242 -414.771586 -90)
		(property "Reference" "R4195"
			(at 0 0 270)
			(layer "F.SilkS")
			(hide yes)
			(effects
				(font
					(size 1.27 1.27)
				)
			)
		)
		(property "Value" ""
			(at 0 0 270)
			(layer "F.Fab")
			(effects
				(font
					(size 1.27 1.27)
				)
			)
		)
		(duplicate_pad_numbers_are_jumpers no)
		(fp_line
			(start -0.7874 0.4064)
			(end -0.7874 -0.4064)
			(stroke
				(width 0.1524)
				(type default)
			)
			(layer "F.SilkS")
		)
		(fp_line
			(start 0.7874 0.4064)
			(end -0.7874 0.4064)
			(stroke
				(width 0.1524)
				(type default)
			)
			(layer "F.SilkS")
		)
		(fp_line
			(start -0.7874 -0.4064)
			(end 0.7874 -0.4064)
			(stroke
				(width 0.1524)
				(type default)
			)
			(layer "F.SilkS")
		)
		(fp_line
			(start 0.7874 -0.4064)
			(end 0.7874 0.4064)
			(stroke
				(width 0.1524)
				(type default)
			)
			(layer "F.SilkS")
		)
		(fp_line
			(start -0.67945 0.3048)
			(end -0.67945 -0.305054)
			(stroke
				(width 0.1)
				(type default)
			)
			(layer "F.Fab")
		)
		(fp_line
			(start -0.12065 0.3048)
			(end -0.67945 0.3048)
			(stroke
				(width 0.1)
				(type default)
			)
			(layer "F.Fab")
		)
		(fp_line
			(start 0.120396 0.3048)
			(end 0.120396 0.2794)
			(stroke
				(width 0.1)
				(type default)
			)
			(layer "F.Fab")
		)
		(fp_line
			(start 0.67945 0.3048)
			(end 0.120396 0.3048)
			(stroke
				(width 0.1)
				(type default)
			)
			(layer "F.Fab")
		)
		(fp_line
			(start -0.12065 0.2794)
			(end -0.12065 0.3048)
			(stroke
				(width 0.1)
				(type default)
			)
			(layer "F.Fab")
		)
		(fp_line
			(start 0.120396 0.2794)
			(end -0.12065 0.2794)
			(stroke
				(width 0.1)
				(type default)
			)
			(layer "F.Fab")
		)
		(fp_line
			(start -0.12065 -0.2794)
			(end 0.12065 -0.2794)
			(stroke
				(width 0.1)
				(type default)
			)
			(layer "F.Fab")
		)
		(fp_line
			(start 0.12065 -0.2794)
			(end 0.12065 -0.3048)
			(stroke
				(width 0.1)
				(type default)
			)
			(layer "F.Fab")
		)
		(fp_line
			(start 0.12065 -0.3048)
			(end 0.67945 -0.3048)
			(stroke
				(width 0.1)
				(type default)
			)
			(layer "F.Fab")
		)
		(fp_line
			(start 0.67945 -0.3048)
			(end 0.67945 0.3048)
			(stroke
				(width 0.1)
				(type default)
			)
			(layer "F.Fab")
		)
		(fp_line
			(start -0.67945 -0.305054)
			(end -0.12065 -0.305054)
			(stroke
				(width 0.1)
				(type default)
			)
			(layer "F.Fab")
		)
		(fp_line
			(start -0.12065 -0.305054)
			(end -0.12065 -0.2794)
			(stroke
				(width 0.1)
				(type default)
			)
			(layer "F.Fab")
		)
		(pad "1" smd circle
			(at -0.40005 0 270)
			(size 0 0)
			(layers "F.Cu" "F.Mask" "F.Paste")
			(net "U272_2_ADD1")
		)
		(pad "2" smd circle
			(at 0.40005 0 270)
			(size 0 0)
			(layers "F.Cu" "F.Mask" "F.Paste")
			(net "GND")
		)
	)
	(footprint ""
		(layer "F.Cu")
		(at 39.827454 -110.587282)
		(property "Reference" "R3861"
			(at 0 0 0)
			(layer "F.SilkS")
			(hide yes)
			(effects
				(font
					(size 1.27 1.27)
				)
			)
		)
		(property "Value" ""
			(at 0 0 0)
			(layer "F.Fab")
			(effects
				(font
					(size 1.27 1.27)
				)
			)
		)
		(duplicate_pad_numbers_are_jumpers no)
		(fp_line
			(start -0.7874 -0.4064)
			(end 0.7874 -0.4064)
			(stroke
				(width 0.1524)
				(type default)
			)
			(layer "F.SilkS")
		)
		(fp_line
			(start -0.7874 0.4064)
			(end -0.7874 -0.4064)
			(stroke
				(width 0.1524)
				(type default)
			)
			(layer "F.SilkS")
		)
		(fp_line
			(start 0.7874 -0.4064)
			(end 0.7874 0.4064)
			(stroke
				(width 0.1524)
				(type default)
			)
			(layer "F.SilkS")
		)
		(fp_line
			(start 0.7874 0.4064)
			(end -0.7874 0.4064)
			(stroke
				(width 0.1524)
				(type default)
			)
			(layer "F.SilkS")
		)
		(fp_line
			(start -0.67945 -0.305054)
			(end -0.12065 -0.305054)
			(stroke
				(width 0.1)
				(type default)
			)
			(layer "F.Fab")
		)
		(fp_line
			(start -0.67945 0.3048)
			(end -0.67945 -0.305054)
			(stroke
				(width 0.1)
				(type default)
			)
			(layer "F.Fab")
		)
		(fp_line
			(start -0.12065 -0.305054)
			(end -0.12065 -0.2794)
			(stroke
				(width 0.1)
				(type default)
			)
			(layer "F.Fab")
		)
		(fp_line
			(start -0.12065 -0.2794)
			(end 0.12065 -0.2794)
			(stroke
				(width 0.1)
				(type default)
			)
			(layer "F.Fab")
		)
		(fp_line
			(start -0.12065 0.2794)
			(end -0.12065 0.3048)
			(stroke
				(width 0.1)
				(type default)
			)
			(layer "F.Fab")
		)
		(fp_line
			(start -0.12065 0.3048)
			(end -0.67945 0.3048)
			(stroke
				(width 0.1)
				(type default)
			)
			(layer "F.Fab")
		)
		(fp_line
			(start 0.120396 0.2794)
			(end -0.12065 0.2794)
			(stroke
				(width 0.1)
				(type default)
			)
			(layer "F.Fab")
		)
		(fp_line
			(start 0.120396 0.3048)
			(end 0.120396 0.2794)
			(stroke
				(width 0.1)
				(type default)
			)
			(layer "F.Fab")
		)
		(fp_line
			(start 0.12065 -0.3048)
			(end 0.67945 -0.3048)
			(stroke
				(width 0.1)
				(type default)
			)
			(layer "F.Fab")
		)
		(fp_line
			(start 0.12065 -0.2794)
			(end 0.12065 -0.3048)
			(stroke
				(width 0.1)
				(type default)
			)
			(layer "F.Fab")
		)
		(fp_line
			(start 0.67945 -0.3048)
			(end 0.67945 0.3048)
			(stroke
				(width 0.1)
				(type default)
			)
			(layer "F.Fab")
		)
		(fp_line
			(start 0.67945 0.3048)
			(end 0.120396 0.3048)
			(stroke
				(width 0.1)
				(type default)
			)
			(layer "F.Fab")
		)
		(pad "1" smd rect
			(at -0.40005 0 180)
			(size 0.4572 0.508)
			(layers "F.Cu" "F.Mask" "F.Paste")
			(net "P12V_OCP_V3_2_ISENSE_MAM_TIC")
		)
		(pad "2" smd rect
			(at 0.40005 0 180)
			(size 0.4572 0.508)
			(layers "F.Cu" "F.Mask" "F.Paste")
			(net "P12V_OCP_V3_2_ISENSE_TIC")
		)
	)
	(footprint ""
		(layer "F.Cu")
		(at 428.880016 -102.37724 -90)
		(property "Reference" "R3794"
			(at 0 0 270)
			(layer "F.SilkS")
			(hide yes)
			(effects
				(font
					(size 1.27 1.27)
				)
			)
		)
		(property "Value" ""
			(at 0 0 270)
			(layer "F.Fab")
			(effects
				(font
					(size 1.27 1.27)
				)
			)
		)
		(duplicate_pad_numbers_are_jumpers no)
		(fp_line
			(start -0.7874 0.4064)
			(end -0.7874 -0.4064)
			(stroke
				(width 0.1524)
				(type default)
			)
			(layer "F.SilkS")
		)
		(fp_line
			(start 0.7874 0.4064)
			(end -0.7874 0.4064)
			(stroke
				(width 0.1524)
				(type default)
			)
			(layer "F.SilkS")
		)
		(fp_line
			(start -0.7874 -0.4064)
			(end 0.7874 -0.4064)
			(stroke
				(width 0.1524)
				(type default)
			)
			(layer "F.SilkS")
		)
		(fp_line
			(start 0.7874 -0.4064)
			(end 0.7874 0.4064)
			(stroke
				(width 0.1524)
				(type default)
			)
			(layer "F.SilkS")
		)
		(fp_line
			(start -0.67945 0.3048)
			(end -0.67945 -0.305054)
			(stroke
				(width 0.1)
				(type default)
			)
			(layer "F.Fab")
		)
		(fp_line
			(start -0.12065 0.3048)
			(end -0.67945 0.3048)
			(stroke
				(width 0.1)
				(type default)
			)
			(layer "F.Fab")
		)
		(fp_line
			(start 0.120396 0.3048)
			(end 0.120396 0.2794)
			(stroke
				(width 0.1)
				(type default)
			)
			(layer "F.Fab")
		)
		(fp_line
			(start 0.67945 0.3048)
			(end 0.120396 0.3048)
			(stroke
				(width 0.1)
				(type default)
			)
			(layer "F.Fab")
		)
		(fp_line
			(start -0.12065 0.2794)
			(end -0.12065 0.3048)
			(stroke
				(width 0.1)
				(type default)
			)
			(layer "F.Fab")
		)
		(fp_line
			(start 0.120396 0.2794)
			(end -0.12065 0.2794)
			(stroke
				(width 0.1)
				(type default)
			)
			(layer "F.Fab")
		)
		(fp_line
			(start -0.12065 -0.2794)
			(end 0.12065 -0.2794)
			(stroke
				(width 0.1)
				(type default)
			)
			(layer "F.Fab")
		)
		(fp_line
			(start 0.12065 -0.2794)
			(end 0.12065 -0.3048)
			(stroke
				(width 0.1)
				(type default)
			)
			(layer "F.Fab")
		)
		(fp_line
			(start 0.12065 -0.3048)
			(end 0.67945 -0.3048)
			(stroke
				(width 0.1)
				(type default)
			)
			(layer "F.Fab")
		)
		(fp_line
			(start 0.67945 -0.3048)
			(end 0.67945 0.3048)
			(stroke
				(width 0.1)
				(type default)
			)
			(layer "F.Fab")
		)
		(fp_line
			(start -0.67945 -0.305054)
			(end -0.12065 -0.305054)
			(stroke
				(width 0.1)
				(type default)
			)
			(layer "F.Fab")
		)
		(fp_line
			(start -0.12065 -0.305054)
			(end -0.12065 -0.2794)
			(stroke
				(width 0.1)
				(type default)
			)
			(layer "F.Fab")
		)
		(pad "1" smd circle
			(at -0.40005 0 270)
			(size 0 0)
			(layers "F.Cu" "F.Mask" "F.Paste")
			(net "P3V3_OCP_PWRGD_1")
		)
		(pad "2" smd circle
			(at 0.40005 0 270)
			(size 0 0)
			(layers "F.Cu" "F.Mask" "F.Paste")
			(net "OCP_V3_1_P3V3_PWRGD")
		)
	)
	(footprint ""
		(layer "F.Cu")
		(at 116.561616 -244.032024 90)
		(property "Reference" "C298"
			(at 0 0 90)
			(layer "F.SilkS")
			(hide yes)
			(effects
				(font
					(size 1.27 1.27)
				)
			)
		)
		(property "Value" ""
			(at 0 0 90)
			(layer "F.Fab")
			(effects
				(font
					(size 1.27 1.27)
				)
			)
		)
		(duplicate_pad_numbers_are_jumpers no)
		(fp_line
			(start 0.7874 -0.4064)
			(end 0.7874 0.4064)
			(stroke
				(width 0.1524)
				(type default)
			)
			(layer "F.SilkS")
		)
		(fp_line
			(start -0.7874 -0.4064)
			(end 0.7874 -0.4064)
			(stroke
				(width 0.1524)
				(type default)
			)
			(layer "F.SilkS")
		)
		(fp_line
			(start 0.7874 0.4064)
			(end -0.7874 0.4064)
			(stroke
				(width 0.1524)
				(type default)
			)
			(layer "F.SilkS")
		)
		(fp_line
			(start -0.7874 0.4064)
			(end -0.7874 -0.4064)
			(stroke
				(width 0.1524)
				(type default)
			)
			(layer "F.SilkS")
		)
		(fp_line
			(start -0.12065 -0.305054)
			(end -0.12065 -0.2794)
			(stroke
				(width 0.1)
				(type default)
			)
			(layer "F.Fab")
		)
		(fp_line
			(start -0.67945 -0.305054)
			(end -0.12065 -0.305054)
			(stroke
				(width 0.1)
				(type default)
			)
			(layer "F.Fab")
		)
		(fp_line
			(start 0.67945 -0.3048)
			(end 0.67945 0.3048)
			(stroke
				(width 0.1)
				(type default)
			)
			(layer "F.Fab")
		)
		(fp_line
			(start 0.12065 -0.3048)
			(end 0.67945 -0.3048)
			(stroke
				(width 0.1)
				(type default)
			)
			(layer "F.Fab")
		)
		(fp_line
			(start 0.12065 -0.2794)
			(end 0.12065 -0.3048)
			(stroke
				(width 0.1)
				(type default)
			)
			(layer "F.Fab")
		)
		(fp_line
			(start -0.12065 -0.2794)
			(end 0.12065 -0.2794)
			(stroke
				(width 0.1)
				(type default)
			)
			(layer "F.Fab")
		)
		(fp_line
			(start 0.120396 0.2794)
			(end -0.12065 0.2794)
			(stroke
				(width 0.1)
				(type default)
			)
			(layer "F.Fab")
		)
		(fp_line
			(start -0.12065 0.2794)
			(end -0.12065 0.3048)
			(stroke
				(width 0.1)
				(type default)
			)
			(layer "F.Fab")
		)
		(fp_line
			(start 0.67945 0.3048)
			(end 0.120396 0.3048)
			(stroke
				(width 0.1)
				(type default)
			)
			(layer "F.Fab")
		)
		(fp_line
			(start 0.120396 0.3048)
			(end 0.120396 0.2794)
			(stroke
				(width 0.1)
				(type default)
			)
			(layer "F.Fab")
		)
		(fp_line
			(start -0.12065 0.3048)
			(end -0.67945 0.3048)
			(stroke
				(width 0.1)
				(type default)
			)
			(layer "F.Fab")
		)
		(fp_line
			(start -0.67945 0.3048)
			(end -0.67945 -0.305054)
			(stroke
				(width 0.1)
				(type default)
			)
			(layer "F.Fab")
		)
		(pad "1" smd circle
			(at -0.40005 0 90)
			(size 0 0)
			(layers "F.Cu" "F.Mask" "F.Paste")
			(net "PVCCIN_CPU1")
		)
		(pad "2" smd circle
			(at 0.40005 0 90)
			(size 0 0)
			(layers "F.Cu" "F.Mask" "F.Paste")
			(net "GND")
		)
	)
	(footprint ""
		(layer "F.Cu")
		(at 24.069802 -409.402534 180)
		(property "Reference" "C1988"
			(at 0 0 180)
			(layer "F.SilkS")
			(hide yes)
			(effects
				(font
					(size 1.27 1.27)
				)
			)
		)
		(property "Value" ""
			(at 0 0 180)
			(layer "F.Fab")
			(effects
				(font
					(size 1.27 1.27)
				)
			)
		)
		(duplicate_pad_numbers_are_jumpers no)
		(fp_line
			(start 0.7874 0.4064)
			(end -0.7874 0.4064)
			(stroke
				(width 0.1524)
				(type default)
			)
			(layer "F.SilkS")
		)
		(fp_line
			(start 0.7874 -0.4064)
			(end 0.7874 0.4064)
			(stroke
				(width 0.1524)
				(type default)
			)
			(layer "F.SilkS")
		)
		(fp_line
			(start -0.7874 0.4064)
			(end -0.7874 -0.4064)
			(stroke
				(width 0.1524)
				(type default)
			)
			(layer "F.SilkS")
		)
		(fp_line
			(start -0.7874 -0.4064)
			(end 0.7874 -0.4064)
			(stroke
				(width 0.1524)
				(type default)
			)
			(layer "F.SilkS")
		)
		(fp_line
			(start 0.67945 0.3048)
			(end 0.120396 0.3048)
			(stroke
				(width 0.1)
				(type default)
			)
			(layer "F.Fab")
		)
		(fp_line
			(start 0.67945 -0.3048)
			(end 0.67945 0.3048)
			(stroke
				(width 0.1)
				(type default)
			)
			(layer "F.Fab")
		)
		(fp_line
			(start 0.12065 -0.2794)
			(end 0.12065 -0.3048)
			(stroke
				(width 0.1)
				(type default)
			)
			(layer "F.Fab")
		)
		(fp_line
			(start 0.12065 -0.3048)
			(end 0.67945 -0.3048)
			(stroke
				(width 0.1)
				(type default)
			)
			(layer "F.Fab")
		)
		(fp_line
			(start 0.120396 0.3048)
			(end 0.120396 0.2794)
			(stroke
				(width 0.1)
				(type default)
			)
			(layer "F.Fab")
		)
		(fp_line
			(start 0.120396 0.2794)
			(end -0.12065 0.2794)
			(stroke
				(width 0.1)
				(type default)
			)
			(layer "F.Fab")
		)
		(fp_line
			(start -0.12065 0.3048)
			(end -0.67945 0.3048)
			(stroke
				(width 0.1)
				(type default)
			)
			(layer "F.Fab")
		)
		(fp_line
			(start -0.12065 0.2794)
			(end -0.12065 0.3048)
			(stroke
				(width 0.1)
				(type default)
			)
			(layer "F.Fab")
		)
		(fp_line
			(start -0.12065 -0.2794)
			(end 0.12065 -0.2794)
			(stroke
				(width 0.1)
				(type default)
			)
			(layer "F.Fab")
		)
		(fp_line
			(start -0.12065 -0.305054)
			(end -0.12065 -0.2794)
			(stroke
				(width 0.1)
				(type default)
			)
			(layer "F.Fab")
		)
		(fp_line
			(start -0.67945 0.3048)
			(end -0.67945 -0.305054)
			(stroke
				(width 0.1)
				(type default)
			)
			(layer "F.Fab")
		)
		(fp_line
			(start -0.67945 -0.305054)
			(end -0.12065 -0.305054)
			(stroke
				(width 0.1)
				(type default)
			)
			(layer "F.Fab")
		)
		(pad "1" smd circle
			(at -0.40005 0 180)
			(size 0 0)
			(layers "F.Cu" "F.Mask" "F.Paste")
			(net "GPU_FPGA_EROT_FATALERR_ISO_N")
		)
		(pad "2" smd circle
			(at 0.40005 0 180)
			(size 0 0)
			(layers "F.Cu" "F.Mask" "F.Paste")
			(net "GND")
		)
	)
	(footprint ""
		(layer "F.Cu")
		(at 153.13914 -119.001032 90)
		(property "Reference" "Q50"
			(at 0.792226 -2.610104 0)
			(unlocked yes)
			(layer "F.SilkS")
			(effects
				(font
					(size 0.7874 0.5842)
					(thickness 0.1524)
				)
			)
		)
		(property "Value" ""
			(at 0 0 90)
			(layer "F.Fab")
			(effects
				(font
					(size 1.27 1.27)
				)
			)
		)
		(duplicate_pad_numbers_are_jumpers no)
		(fp_line
			(start 1.332738 -1.100074)
			(end 1.332738 1.100074)
			(stroke
				(width 0.1524)
				(type default)
			)
			(layer "F.SilkS")
		)
		(fp_line
			(start 0.4826 -1.100074)
			(end 1.332738 -1.100074)
			(stroke
				(width 0.1524)
				(type default)
			)
			(layer "F.SilkS")
		)
		(fp_line
			(start -0.4826 -1.100074)
			(end 0 -0.541274)
			(stroke
				(width 0.1524)
				(type default)
			)
			(layer "F.SilkS")
		)
		(fp_line
			(start -1.332738 -1.100074)
			(end -0.4826 -1.100074)
			(stroke
				(width 0.1524)
				(type default)
			)
			(layer "F.SilkS")
		)
		(fp_line
			(start 0 -0.541274)
			(end 0.4826 -1.100074)
			(stroke
				(width 0.1524)
				(type default)
			)
			(layer "F.SilkS")
		)
		(fp_line
			(start 1.332738 1.100074)
			(end -1.332738 1.100074)
			(stroke
				(width 0.1524)
				(type default)
			)
			(layer "F.SilkS")
		)
		(fp_line
			(start -1.332738 1.100074)
			(end -1.332738 -1.100074)
			(stroke
				(width 0.1524)
				(type default)
			)
			(layer "F.SilkS")
		)
		(fp_poly
			(pts
				(xy -1.442466 -2.226056) (xy -0.74041 -2.226056) (xy -1.091438 -1.524)
			)
			(stroke
				(width 0)
				(type default)
			)
			(fill yes)
			(layer "F.SilkS")
		)
		(fp_line
			(start 0.674878 -1.100074)
			(end 0.674878 1.100074)
			(stroke
				(width 0.1)
				(type default)
			)
			(layer "F.Fab")
		)
		(fp_line
			(start -0.674878 -1.100074)
			(end 0.674878 -1.100074)
			(stroke
				(width 0.1)
				(type default)
			)
			(layer "F.Fab")
		)
		(fp_line
			(start 0.674878 1.100074)
			(end -0.674878 1.100074)
			(stroke
				(width 0.1)
				(type default)
			)
			(layer "F.Fab")
		)
		(fp_line
			(start -0.674878 1.100074)
			(end -0.674878 -1.100074)
			(stroke
				(width 0.1)
				(type default)
			)
			(layer "F.Fab")
		)
		(fp_poly
			(pts
				(xy -2.2352 -0.298958) (xy -2.2352 -1.001014) (xy -1.533144 -0.649986)
			)
			(stroke
				(width 0)
				(type default)
			)
			(fill yes)
			(layer "F.Fab")
		)
		(pad "1" smd rect
			(at -0.94996 -0.649986 180)
			(size 0.4318 0.508)
			(layers "F.Cu" "F.Mask" "F.Paste")
			(net "GND")
		)
		(pad "2" smd rect
			(at -0.94996 0 180)
			(size 0.4318 0.508)
			(layers "F.Cu" "F.Mask" "F.Paste")
			(net "PWRGD_P5V_AUX")
		)
		(pad "3" smd rect
			(at -0.94996 0.649986 180)
			(size 0.4318 0.508)
			(layers "F.Cu" "F.Mask" "F.Paste")
			(net "PWRGD_P5V_AUX_R2")
		)
		(pad "4" smd rect
			(at 0.94996 0.649986 180)
			(size 0.4318 0.508)
			(layers "F.Cu" "F.Mask" "F.Paste")
			(net "GND")
		)
		(pad "5" smd rect
			(at 0.94996 0 180)
			(size 0.4318 0.508)
			(layers "F.Cu" "F.Mask" "F.Paste")
			(net "PWRGD_P5V_AUX_R1")
		)
		(pad "6" smd rect
			(at 0.94996 -0.649986 180)
			(size 0.4318 0.508)
			(layers "F.Cu" "F.Mask" "F.Paste")
			(net "PWRGD_P5V_AUX_R1")
		)
	)
	(footprint ""
		(layer "F.Cu")
		(at 431.989992 -381.218948 180)
		(property "Reference" "R2834"
			(at 0 0 180)
			(layer "F.SilkS")
			(hide yes)
			(effects
				(font
					(size 1.27 1.27)
				)
			)
		)
		(property "Value" ""
			(at 0 0 180)
			(layer "F.Fab")
			(effects
				(font
					(size 1.27 1.27)
				)
			)
		)
		(duplicate_pad_numbers_are_jumpers no)
		(fp_line
			(start 0.7874 0.4064)
			(end -0.7874 0.4064)
			(stroke
				(width 0.1524)
				(type default)
			)
			(layer "F.SilkS")
		)
		(fp_line
			(start 0.7874 -0.4064)
			(end 0.7874 0.4064)
			(stroke
				(width 0.1524)
				(type default)
			)
			(layer "F.SilkS")
		)
		(fp_line
			(start -0.7874 0.4064)
			(end -0.7874 -0.4064)
			(stroke
				(width 0.1524)
				(type default)
			)
			(layer "F.SilkS")
		)
		(fp_line
			(start -0.7874 -0.4064)
			(end 0.7874 -0.4064)
			(stroke
				(width 0.1524)
				(type default)
			)
			(layer "F.SilkS")
		)
		(fp_line
			(start 0.67945 0.3048)
			(end 0.120396 0.3048)
			(stroke
				(width 0.1)
				(type default)
			)
			(layer "F.Fab")
		)
		(fp_line
			(start 0.67945 -0.3048)
			(end 0.67945 0.3048)
			(stroke
				(width 0.1)
				(type default)
			)
			(layer "F.Fab")
		)
		(fp_line
			(start 0.12065 -0.2794)
			(end 0.12065 -0.3048)
			(stroke
				(width 0.1)
				(type default)
			)
			(layer "F.Fab")
		)
		(fp_line
			(start 0.12065 -0.3048)
			(end 0.67945 -0.3048)
			(stroke
				(width 0.1)
				(type default)
			)
			(layer "F.Fab")
		)
		(fp_line
			(start 0.120396 0.3048)
			(end 0.120396 0.2794)
			(stroke
				(width 0.1)
				(type default)
			)
			(layer "F.Fab")
		)
		(fp_line
			(start 0.120396 0.2794)
			(end -0.12065 0.2794)
			(stroke
				(width 0.1)
				(type default)
			)
			(layer "F.Fab")
		)
		(fp_line
			(start -0.12065 0.3048)
			(end -0.67945 0.3048)
			(stroke
				(width 0.1)
				(type default)
			)
			(layer "F.Fab")
		)
		(fp_line
			(start -0.12065 0.2794)
			(end -0.12065 0.3048)
			(stroke
				(width 0.1)
				(type default)
			)
			(layer "F.Fab")
		)
		(fp_line
			(start -0.12065 -0.2794)
			(end 0.12065 -0.2794)
			(stroke
				(width 0.1)
				(type default)
			)
			(layer "F.Fab")
		)
		(fp_line
			(start -0.12065 -0.305054)
			(end -0.12065 -0.2794)
			(stroke
				(width 0.1)
				(type default)
			)
			(layer "F.Fab")
		)
		(fp_line
			(start -0.67945 0.3048)
			(end -0.67945 -0.305054)
			(stroke
				(width 0.1)
				(type default)
			)
			(layer "F.Fab")
		)
		(fp_line
			(start -0.67945 -0.305054)
			(end -0.12065 -0.305054)
			(stroke
				(width 0.1)
				(type default)
			)
			(layer "F.Fab")
		)
		(pad "1" smd circle
			(at -0.40005 0 180)
			(size 0 0)
			(layers "F.Cu" "F.Mask" "F.Paste")
			(net "P3V3_AUX")
		)
		(pad "2" smd circle
			(at 0.40005 0 180)
			(size 0 0)
			(layers "F.Cu" "F.Mask" "F.Paste")
			(net "RST_BMC_FROM_SWB")
		)
	)
	(footprint ""
		(layer "F.Cu")
		(at 299.02023 -47.288196)
		(property "Reference" "R2972"
			(at 0 0 0)
			(layer "F.SilkS")
			(hide yes)
			(effects
				(font
					(size 1.27 1.27)
				)
			)
		)
		(property "Value" ""
			(at 0 0 0)
			(layer "F.Fab")
			(effects
				(font
					(size 1.27 1.27)
				)
			)
		)
		(duplicate_pad_numbers_are_jumpers no)
		(fp_line
			(start -0.7874 -0.4064)
			(end 0.7874 -0.4064)
			(stroke
				(width 0.1524)
				(type default)
			)
			(layer "F.SilkS")
		)
		(fp_line
			(start -0.7874 0.4064)
			(end -0.7874 -0.4064)
			(stroke
				(width 0.1524)
				(type default)
			)
			(layer "F.SilkS")
		)
		(fp_line
			(start 0.7874 -0.4064)
			(end 0.7874 0.4064)
			(stroke
				(width 0.1524)
				(type default)
			)
			(layer "F.SilkS")
		)
		(fp_line
			(start 0.7874 0.4064)
			(end -0.7874 0.4064)
			(stroke
				(width 0.1524)
				(type default)
			)
			(layer "F.SilkS")
		)
		(fp_line
			(start -0.67945 -0.305054)
			(end -0.12065 -0.305054)
			(stroke
				(width 0.1)
				(type default)
			)
			(layer "F.Fab")
		)
		(fp_line
			(start -0.67945 0.3048)
			(end -0.67945 -0.305054)
			(stroke
				(width 0.1)
				(type default)
			)
			(layer "F.Fab")
		)
		(fp_line
			(start -0.12065 -0.305054)
			(end -0.12065 -0.2794)
			(stroke
				(width 0.1)
				(type default)
			)
			(layer "F.Fab")
		)
		(fp_line
			(start -0.12065 -0.2794)
			(end 0.12065 -0.2794)
			(stroke
				(width 0.1)
				(type default)
			)
			(layer "F.Fab")
		)
		(fp_line
			(start -0.12065 0.2794)
			(end -0.12065 0.3048)
			(stroke
				(width 0.1)
				(type default)
			)
			(layer "F.Fab")
		)
		(fp_line
			(start -0.12065 0.3048)
			(end -0.67945 0.3048)
			(stroke
				(width 0.1)
				(type default)
			)
			(layer "F.Fab")
		)
		(fp_line
			(start 0.120396 0.2794)
			(end -0.12065 0.2794)
			(stroke
				(width 0.1)
				(type default)
			)
			(layer "F.Fab")
		)
		(fp_line
			(start 0.120396 0.3048)
			(end 0.120396 0.2794)
			(stroke
				(width 0.1)
				(type default)
			)
			(layer "F.Fab")
		)
		(fp_line
			(start 0.12065 -0.3048)
			(end 0.67945 -0.3048)
			(stroke
				(width 0.1)
				(type default)
			)
			(layer "F.Fab")
		)
		(fp_line
			(start 0.12065 -0.2794)
			(end 0.12065 -0.3048)
			(stroke
				(width 0.1)
				(type default)
			)
			(layer "F.Fab")
		)
		(fp_line
			(start 0.67945 -0.3048)
			(end 0.67945 0.3048)
			(stroke
				(width 0.1)
				(type default)
			)
			(layer "F.Fab")
		)
		(fp_line
			(start 0.67945 0.3048)
			(end 0.120396 0.3048)
			(stroke
				(width 0.1)
				(type default)
			)
			(layer "F.Fab")
		)
		(pad "1" smd circle
			(at -0.40005 0)
			(size 0 0)
			(layers "F.Cu" "F.Mask" "F.Paste")
			(net "P1V05_PCH_AUX")
		)
		(pad "2" smd circle
			(at 0.40005 0)
			(size 0 0)
			(layers "F.Cu" "F.Mask" "F.Paste")
			(net "FAB_REV_ID2")
		)
	)
	(footprint ""
		(layer "F.Cu")
		(at 179.360068 -397.188182)
		(property "Reference" "PR3930"
			(at 0 0 0)
			(layer "F.SilkS")
			(hide yes)
			(effects
				(font
					(size 1.27 1.27)
				)
			)
		)
		(property "Value" ""
			(at 0 0 0)
			(layer "F.Fab")
			(effects
				(font
					(size 1.27 1.27)
				)
			)
		)
		(duplicate_pad_numbers_are_jumpers no)
		(fp_line
			(start -0.7874 -0.4064)
			(end 0.7874 -0.4064)
			(stroke
				(width 0.1524)
				(type default)
			)
			(layer "F.SilkS")
		)
		(fp_line
			(start -0.7874 0.4064)
			(end -0.7874 -0.4064)
			(stroke
				(width 0.1524)
				(type default)
			)
			(layer "F.SilkS")
		)
		(fp_line
			(start 0.7874 -0.4064)
			(end 0.7874 0.4064)
			(stroke
				(width 0.1524)
				(type default)
			)
			(layer "F.SilkS")
		)
		(fp_line
			(start 0.7874 0.4064)
			(end -0.7874 0.4064)
			(stroke
				(width 0.1524)
				(type default)
			)
			(layer "F.SilkS")
		)
		(fp_line
			(start -0.67945 -0.305054)
			(end -0.12065 -0.305054)
			(stroke
				(width 0.1)
				(type default)
			)
			(layer "F.Fab")
		)
		(fp_line
			(start -0.67945 0.3048)
			(end -0.67945 -0.305054)
			(stroke
				(width 0.1)
				(type default)
			)
			(layer "F.Fab")
		)
		(fp_line
			(start -0.12065 -0.305054)
			(end -0.12065 -0.2794)
			(stroke
				(width 0.1)
				(type default)
			)
			(layer "F.Fab")
		)
		(fp_line
			(start -0.12065 -0.2794)
			(end 0.12065 -0.2794)
			(stroke
				(width 0.1)
				(type default)
			)
			(layer "F.Fab")
		)
		(fp_line
			(start -0.12065 0.2794)
			(end -0.12065 0.3048)
			(stroke
				(width 0.1)
				(type default)
			)
			(layer "F.Fab")
		)
		(fp_line
			(start -0.12065 0.3048)
			(end -0.67945 0.3048)
			(stroke
				(width 0.1)
				(type default)
			)
			(layer "F.Fab")
		)
		(fp_line
			(start 0.120396 0.2794)
			(end -0.12065 0.2794)
			(stroke
				(width 0.1)
				(type default)
			)
			(layer "F.Fab")
		)
		(fp_line
			(start 0.120396 0.3048)
			(end 0.120396 0.2794)
			(stroke
				(width 0.1)
				(type default)
			)
			(layer "F.Fab")
		)
		(fp_line
			(start 0.12065 -0.3048)
			(end 0.67945 -0.3048)
			(stroke
				(width 0.1)
				(type default)
			)
			(layer "F.Fab")
		)
		(fp_line
			(start 0.12065 -0.2794)
			(end 0.12065 -0.3048)
			(stroke
				(width 0.1)
				(type default)
			)
			(layer "F.Fab")
		)
		(fp_line
			(start 0.67945 -0.3048)
			(end 0.67945 0.3048)
			(stroke
				(width 0.1)
				(type default)
			)
			(layer "F.Fab")
		)
		(fp_line
			(start 0.67945 0.3048)
			(end 0.120396 0.3048)
			(stroke
				(width 0.1)
				(type default)
			)
			(layer "F.Fab")
		)
		(pad "1" smd circle
			(at -0.40005 0)
			(size 0 0)
			(layers "F.Cu" "F.Mask" "F.Paste")
			(net "AGND_HSC")
		)
		(pad "2" smd circle
			(at 0.40005 0)
			(size 0 0)
			(layers "F.Cu" "F.Mask" "F.Paste")
			(net "HSC_ADDR")
		)
	)
	(footprint ""
		(layer "F.Cu")
		(at 86.084918 -341.707978 -90)
		(property "Reference" "PC1360"
			(at 0 0 270)
			(layer "F.SilkS")
			(hide yes)
			(effects
				(font
					(size 1.27 1.27)
				)
			)
		)
		(property "Value" ""
			(at 0 0 270)
			(layer "F.Fab")
			(effects
				(font
					(size 1.27 1.27)
				)
			)
		)
		(duplicate_pad_numbers_are_jumpers no)
		(fp_line
			(start -0.7874 0.4064)
			(end -0.7874 -0.4064)
			(stroke
				(width 0.1524)
				(type default)
			)
			(layer "F.SilkS")
		)
		(fp_line
			(start 0.7874 0.4064)
			(end -0.7874 0.4064)
			(stroke
				(width 0.1524)
				(type default)
			)
			(layer "F.SilkS")
		)
		(fp_line
			(start -0.7874 -0.4064)
			(end 0.7874 -0.4064)
			(stroke
				(width 0.1524)
				(type default)
			)
			(layer "F.SilkS")
		)
		(fp_line
			(start 0.7874 -0.4064)
			(end 0.7874 0.4064)
			(stroke
				(width 0.1524)
				(type default)
			)
			(layer "F.SilkS")
		)
		(fp_line
			(start -0.67945 0.3048)
			(end -0.67945 -0.305054)
			(stroke
				(width 0.1)
				(type default)
			)
			(layer "F.Fab")
		)
		(fp_line
			(start -0.12065 0.3048)
			(end -0.67945 0.3048)
			(stroke
				(width 0.1)
				(type default)
			)
			(layer "F.Fab")
		)
		(fp_line
			(start 0.120396 0.3048)
			(end 0.120396 0.2794)
			(stroke
				(width 0.1)
				(type default)
			)
			(layer "F.Fab")
		)
		(fp_line
			(start 0.67945 0.3048)
			(end 0.120396 0.3048)
			(stroke
				(width 0.1)
				(type default)
			)
			(layer "F.Fab")
		)
		(fp_line
			(start -0.12065 0.2794)
			(end -0.12065 0.3048)
			(stroke
				(width 0.1)
				(type default)
			)
			(layer "F.Fab")
		)
		(fp_line
			(start 0.120396 0.2794)
			(end -0.12065 0.2794)
			(stroke
				(width 0.1)
				(type default)
			)
			(layer "F.Fab")
		)
		(fp_line
			(start -0.12065 -0.2794)
			(end 0.12065 -0.2794)
			(stroke
				(width 0.1)
				(type default)
			)
			(layer "F.Fab")
		)
		(fp_line
			(start 0.12065 -0.2794)
			(end 0.12065 -0.3048)
			(stroke
				(width 0.1)
				(type default)
			)
			(layer "F.Fab")
		)
		(fp_line
			(start 0.12065 -0.3048)
			(end 0.67945 -0.3048)
			(stroke
				(width 0.1)
				(type default)
			)
			(layer "F.Fab")
		)
		(fp_line
			(start 0.67945 -0.3048)
			(end 0.67945 0.3048)
			(stroke
				(width 0.1)
				(type default)
			)
			(layer "F.Fab")
		)
		(fp_line
			(start -0.67945 -0.305054)
			(end -0.12065 -0.305054)
			(stroke
				(width 0.1)
				(type default)
			)
			(layer "F.Fab")
		)
		(fp_line
			(start -0.12065 -0.305054)
			(end -0.12065 -0.2794)
			(stroke
				(width 0.1)
				(type default)
			)
			(layer "F.Fab")
		)
		(pad "1" smd circle
			(at -0.40005 0 270)
			(size 0 0)
			(layers "F.Cu" "F.Mask" "F.Paste")
			(net "GND")
		)
		(pad "2" smd circle
			(at 0.40005 0 270)
			(size 0 0)
			(layers "F.Cu" "F.Mask" "F.Paste")
			(net "PVCCIN_CPU1_VREF")
		)
	)
	(footprint ""
		(layer "F.Cu")
		(at 316.207648 -402.371052 -90)
		(property "Reference" "C1570"
			(at 0 0 270)
			(layer "F.SilkS")
			(hide yes)
			(effects
				(font
					(size 1.27 1.27)
				)
			)
		)
		(property "Value" ""
			(at 0 0 270)
			(layer "F.Fab")
			(effects
				(font
					(size 1.27 1.27)
				)
			)
		)
		(duplicate_pad_numbers_are_jumpers no)
		(fp_line
			(start -0.299974 0.150114)
			(end -0.299974 -0.150114)
			(stroke
				(width 0.1)
				(type default)
			)
			(layer "F.Fab")
		)
		(fp_line
			(start 0.299974 0.150114)
			(end -0.299974 0.150114)
			(stroke
				(width 0.1)
				(type default)
			)
			(layer "F.Fab")
		)
		(fp_line
			(start -0.299974 -0.150114)
			(end 0.299974 -0.150114)
			(stroke
				(width 0.1)
				(type default)
			)
			(layer "F.Fab")
		)
		(fp_line
			(start 0.299974 -0.150114)
			(end 0.299974 0.150114)
			(stroke
				(width 0.1)
				(type default)
			)
			(layer "F.Fab")
		)
		(pad "1" smd rect
			(at -0.2667 0 270)
			(size 0.3048 0.381)
			(layers "F.Cu" "F.Mask" "F.Paste")
			(net "P5E_CPU0_PE4_TX_C_DN<4>")
		)
		(pad "2" smd rect
			(at 0.2667 0 270)
			(size 0.3048 0.381)
			(layers "F.Cu" "F.Mask" "F.Paste")
			(net "P5E_CPU0_PE4_TX_DN<4>")
		)
	)
	(footprint ""
		(layer "F.Cu")
		(at 108.079286 -93.015562)
		(property "Reference" "Q81"
			(at -1.19126 1.843532 0)
			(unlocked yes)
			(layer "F.SilkS")
			(effects
				(font
					(size 0.7874 0.5842)
					(thickness 0.1524)
				)
				(justify left)
			)
		)
		(property "Value" ""
			(at 0 0 0)
			(layer "F.Fab")
			(effects
				(font
					(size 1.27 1.27)
				)
			)
		)
		(duplicate_pad_numbers_are_jumpers no)
		(fp_line
			(start -1.332738 -1.100074)
			(end -0.4826 -1.100074)
			(stroke
				(width 0.1524)
				(type default)
			)
			(layer "F.SilkS")
		)
		(fp_line
			(start -1.332738 1.100074)
			(end -1.332738 -1.100074)
			(stroke
				(width 0.1524)
				(type default)
			)
			(layer "F.SilkS")
		)
		(fp_line
			(start -0.4826 -1.100074)
			(end 0 -0.541274)
			(stroke
				(width 0.1524)
				(type default)
			)
			(layer "F.SilkS")
		)
		(fp_line
			(start 0 -0.541274)
			(end 0.4826 -1.100074)
			(stroke
				(width 0.1524)
				(type default)
			)
			(layer "F.SilkS")
		)
		(fp_line
			(start 0.4826 -1.100074)
			(end 1.332738 -1.100074)
			(stroke
				(width 0.1524)
				(type default)
			)
			(layer "F.SilkS")
		)
		(fp_line
			(start 1.332738 -1.100074)
			(end 1.332738 1.100074)
			(stroke
				(width 0.1524)
				(type default)
			)
			(layer "F.SilkS")
		)
		(fp_line
			(start 1.332738 1.100074)
			(end -1.332738 1.100074)
			(stroke
				(width 0.1524)
				(type default)
			)
			(layer "F.SilkS")
		)
		(fp_poly
			(pts
				(xy -0.649478 -1.9685) (xy -1.000506 -1.266444) (xy -1.351534 -1.9685)
			)
			(stroke
				(width 0)
				(type default)
			)
			(fill yes)
			(layer "F.SilkS")
		)
		(fp_line
			(start -0.674878 -1.100074)
			(end 0.674878 -1.100074)
			(stroke
				(width 0.1)
				(type default)
			)
			(layer "F.Fab")
		)
		(fp_line
			(start -0.674878 1.100074)
			(end -0.674878 -1.100074)
			(stroke
				(width 0.1)
				(type default)
			)
			(layer "F.Fab")
		)
		(fp_line
			(start 0.674878 -1.100074)
			(end 0.674878 1.100074)
			(stroke
				(width 0.1)
				(type default)
			)
			(layer "F.Fab")
		)
		(fp_line
			(start 0.674878 1.100074)
			(end -0.674878 1.100074)
			(stroke
				(width 0.1)
				(type default)
			)
			(layer "F.Fab")
		)
		(fp_poly
			(pts
				(xy -2.2352 -0.298958) (xy -2.2352 -1.001014) (xy -1.533144 -0.649986)
			)
			(stroke
				(width 0)
				(type default)
			)
			(fill yes)
			(layer "F.Fab")
		)
		(pad "1" smd rect
			(at -0.94996 -0.649986 90)
			(size 0.4318 0.508)
			(layers "F.Cu" "F.Mask" "F.Paste")
			(net "GND")
		)
		(pad "2" smd rect
			(at -0.94996 0 90)
			(size 0.4318 0.508)
			(layers "F.Cu" "F.Mask" "F.Paste")
			(net "PWRGD_PVCCINFAON_CPU0")
		)
		(pad "3" smd rect
			(at -0.94996 0.649986 90)
			(size 0.4318 0.508)
			(layers "F.Cu" "F.Mask" "F.Paste")
			(net "LED_PWRGD_PVNN_MAIN_CPU0_D")
		)
		(pad "4" smd rect
			(at 0.94996 0.649986 90)
			(size 0.4318 0.508)
			(layers "F.Cu" "F.Mask" "F.Paste")
			(net "GND")
		)
		(pad "5" smd rect
			(at 0.94996 0 90)
			(size 0.4318 0.508)
			(layers "F.Cu" "F.Mask" "F.Paste")
			(net "PWRGD_PVNN_MAIN_CPU0")
		)
		(pad "6" smd rect
			(at 0.94996 -0.649986 90)
			(size 0.4318 0.508)
			(layers "F.Cu" "F.Mask" "F.Paste")
			(net "LED_PWRGD_PVCCINFAON_CPU0_D")
		)
	)
	(footprint ""
		(layer "F.Cu")
		(at 280.830528 -14.09827)
		(property "Reference" "R3193"
			(at 0 0 0)
			(layer "F.SilkS")
			(hide yes)
			(effects
				(font
					(size 1.27 1.27)
				)
			)
		)
		(property "Value" ""
			(at 0 0 0)
			(layer "F.Fab")
			(effects
				(font
					(size 1.27 1.27)
				)
			)
		)
		(duplicate_pad_numbers_are_jumpers no)
		(fp_line
			(start -0.7874 -0.4064)
			(end 0.7874 -0.4064)
			(stroke
				(width 0.1524)
				(type default)
			)
			(layer "F.SilkS")
		)
		(fp_line
			(start -0.7874 0.4064)
			(end -0.7874 -0.4064)
			(stroke
				(width 0.1524)
				(type default)
			)
			(layer "F.SilkS")
		)
		(fp_line
			(start 0.7874 -0.4064)
			(end 0.7874 0.4064)
			(stroke
				(width 0.1524)
				(type default)
			)
			(layer "F.SilkS")
		)
		(fp_line
			(start 0.7874 0.4064)
			(end -0.7874 0.4064)
			(stroke
				(width 0.1524)
				(type default)
			)
			(layer "F.SilkS")
		)
		(fp_line
			(start -0.67945 -0.305054)
			(end -0.12065 -0.305054)
			(stroke
				(width 0.1)
				(type default)
			)
			(layer "F.Fab")
		)
		(fp_line
			(start -0.67945 0.3048)
			(end -0.67945 -0.305054)
			(stroke
				(width 0.1)
				(type default)
			)
			(layer "F.Fab")
		)
		(fp_line
			(start -0.12065 -0.305054)
			(end -0.12065 -0.2794)
			(stroke
				(width 0.1)
				(type default)
			)
			(layer "F.Fab")
		)
		(fp_line
			(start -0.12065 -0.2794)
			(end 0.12065 -0.2794)
			(stroke
				(width 0.1)
				(type default)
			)
			(layer "F.Fab")
		)
		(fp_line
			(start -0.12065 0.2794)
			(end -0.12065 0.3048)
			(stroke
				(width 0.1)
				(type default)
			)
			(layer "F.Fab")
		)
		(fp_line
			(start -0.12065 0.3048)
			(end -0.67945 0.3048)
			(stroke
				(width 0.1)
				(type default)
			)
			(layer "F.Fab")
		)
		(fp_line
			(start 0.120396 0.2794)
			(end -0.12065 0.2794)
			(stroke
				(width 0.1)
				(type default)
			)
			(layer "F.Fab")
		)
		(fp_line
			(start 0.120396 0.3048)
			(end 0.120396 0.2794)
			(stroke
				(width 0.1)
				(type default)
			)
			(layer "F.Fab")
		)
		(fp_line
			(start 0.12065 -0.3048)
			(end 0.67945 -0.3048)
			(stroke
				(width 0.1)
				(type default)
			)
			(layer "F.Fab")
		)
		(fp_line
			(start 0.12065 -0.2794)
			(end 0.12065 -0.3048)
			(stroke
				(width 0.1)
				(type default)
			)
			(layer "F.Fab")
		)
		(fp_line
			(start 0.67945 -0.3048)
			(end 0.67945 0.3048)
			(stroke
				(width 0.1)
				(type default)
			)
			(layer "F.Fab")
		)
		(fp_line
			(start 0.67945 0.3048)
			(end 0.120396 0.3048)
			(stroke
				(width 0.1)
				(type default)
			)
			(layer "F.Fab")
		)
		(pad "1" smd circle
			(at -0.40005 0)
			(size 0 0)
			(layers "F.Cu" "F.Mask" "F.Paste")
			(net "IRQ_LVC3_V3_2_WAKE_BUF_N")
		)
		(pad "2" smd circle
			(at 0.40005 0)
			(size 0 0)
			(layers "F.Cu" "F.Mask" "F.Paste")
			(net "IRQ_LVC3_WAKE_N")
		)
	)
	(footprint ""
		(layer "F.Cu")
		(at 180.528468 -45.005498 180)
		(property "Reference" "C1098"
			(at 0 0 180)
			(layer "F.SilkS")
			(hide yes)
			(effects
				(font
					(size 1.27 1.27)
				)
			)
		)
		(property "Value" ""
			(at 0 0 180)
			(layer "F.Fab")
			(effects
				(font
					(size 1.27 1.27)
				)
			)
		)
		(duplicate_pad_numbers_are_jumpers no)
		(fp_line
			(start 0.299974 0.150114)
			(end -0.299974 0.150114)
			(stroke
				(width 0.1)
				(type default)
			)
			(layer "F.Fab")
		)
		(fp_line
			(start 0.299974 -0.150114)
			(end 0.299974 0.150114)
			(stroke
				(width 0.1)
				(type default)
			)
			(layer "F.Fab")
		)
		(fp_line
			(start -0.299974 0.150114)
			(end -0.299974 -0.150114)
			(stroke
				(width 0.1)
				(type default)
			)
			(layer "F.Fab")
		)
		(fp_line
			(start -0.299974 -0.150114)
			(end 0.299974 -0.150114)
			(stroke
				(width 0.1)
				(type default)
			)
			(layer "F.Fab")
		)
		(pad "1" smd rect
			(at -0.2667 0 180)
			(size 0.3048 0.381)
			(layers "F.Cu" "F.Mask" "F.Paste")
			(net "P3E_PCH_M2_TX_DP<3>")
		)
		(pad "2" smd rect
			(at 0.2667 0 180)
			(size 0.3048 0.381)
			(layers "F.Cu" "F.Mask" "F.Paste")
			(net "P3E_PCH_M2_TX_C_DP<3>")
		)
		(zone
			(layer "In1.Cu")
			(hatch none 0.5)
			(connect_pads
				(clearance 0)
			)
			(min_thickness 0.25)
			(keepout
				(tracks not_allowed)
				(vias allowed)
				(pads allowed)
				(copperpour not_allowed)
				(footprints allowed)
			)
			(placement
				(enabled no)
				(sheetname "")
			)
			(fill
				(thermal_gap 0.5)
				(thermal_bridge_width 0.5)
				(island_removal_mode 0)
			)
			(polygon
				(pts
					(arc
						(start 180.388768 -45.246798)
						(mid 180.44265 -45.22448)
						(end 180.464968 -45.170598)
					)
					(arc
						(start 180.464968 -44.840398)
						(mid 180.44265 -44.786516)
						(end 180.388768 -44.764198)
					)
					(arc
						(start 180.134768 -44.764198)
						(mid 180.080886 -44.786516)
						(end 180.058568 -44.840398)
					)
					(arc
						(start 180.058568 -45.170598)
						(mid 180.080886 -45.22448)
						(end 180.134768 -45.246798)
					)
				)
			)
		)
		(zone
			(layer "In1.Cu")
			(hatch none 0.5)
			(connect_pads
				(clearance 0)
			)
			(min_thickness 0.25)
			(keepout
				(tracks not_allowed)
				(vias allowed)
				(pads allowed)
				(copperpour not_allowed)
				(footprints allowed)
			)
			(placement
				(enabled no)
				(sheetname "")
			)
			(fill
				(thermal_gap 0.5)
				(thermal_bridge_width 0.5)
				(island_removal_mode 0)
			)
			(polygon
				(pts
					(arc
						(start 180.922168 -45.246798)
						(mid 180.97605 -45.22448)
						(end 180.998368 -45.170598)
					)
					(arc
						(start 180.998368 -44.840398)
						(mid 180.97605 -44.786516)
						(end 180.922168 -44.764198)
					)
					(arc
						(start 180.668168 -44.764198)
						(mid 180.614286 -44.786516)
						(end 180.591968 -44.840398)
					)
					(arc
						(start 180.591968 -45.170598)
						(mid 180.614286 -45.22448)
						(end 180.668168 -45.246798)
					)
				)
			)
		)
	)
	(footprint ""
		(layer "F.Cu")
		(at 289.545268 -367.378996 90)
		(property "Reference" "PR1783"
			(at 0 0 90)
			(layer "F.SilkS")
			(hide yes)
			(effects
				(font
					(size 1.27 1.27)
				)
			)
		)
		(property "Value" ""
			(at 0 0 90)
			(layer "F.Fab")
			(effects
				(font
					(size 1.27 1.27)
				)
			)
		)
		(duplicate_pad_numbers_are_jumpers no)
		(fp_line
			(start 0.7874 -0.4064)
			(end 0.7874 0.4064)
			(stroke
				(width 0.1524)
				(type default)
			)
			(layer "F.SilkS")
		)
		(fp_line
			(start -0.7874 -0.4064)
			(end 0.7874 -0.4064)
			(stroke
				(width 0.1524)
				(type default)
			)
			(layer "F.SilkS")
		)
		(fp_line
			(start 0.7874 0.4064)
			(end -0.7874 0.4064)
			(stroke
				(width 0.1524)
				(type default)
			)
			(layer "F.SilkS")
		)
		(fp_line
			(start -0.7874 0.4064)
			(end -0.7874 -0.4064)
			(stroke
				(width 0.1524)
				(type default)
			)
			(layer "F.SilkS")
		)
		(fp_line
			(start -0.12065 -0.305054)
			(end -0.12065 -0.2794)
			(stroke
				(width 0.1)
				(type default)
			)
			(layer "F.Fab")
		)
		(fp_line
			(start -0.67945 -0.305054)
			(end -0.12065 -0.305054)
			(stroke
				(width 0.1)
				(type default)
			)
			(layer "F.Fab")
		)
		(fp_line
			(start 0.67945 -0.3048)
			(end 0.67945 0.3048)
			(stroke
				(width 0.1)
				(type default)
			)
			(layer "F.Fab")
		)
		(fp_line
			(start 0.12065 -0.3048)
			(end 0.67945 -0.3048)
			(stroke
				(width 0.1)
				(type default)
			)
			(layer "F.Fab")
		)
		(fp_line
			(start 0.12065 -0.2794)
			(end 0.12065 -0.3048)
			(stroke
				(width 0.1)
				(type default)
			)
			(layer "F.Fab")
		)
		(fp_line
			(start -0.12065 -0.2794)
			(end 0.12065 -0.2794)
			(stroke
				(width 0.1)
				(type default)
			)
			(layer "F.Fab")
		)
		(fp_line
			(start 0.120396 0.2794)
			(end -0.12065 0.2794)
			(stroke
				(width 0.1)
				(type default)
			)
			(layer "F.Fab")
		)
		(fp_line
			(start -0.12065 0.2794)
			(end -0.12065 0.3048)
			(stroke
				(width 0.1)
				(type default)
			)
			(layer "F.Fab")
		)
		(fp_line
			(start 0.67945 0.3048)
			(end 0.120396 0.3048)
			(stroke
				(width 0.1)
				(type default)
			)
			(layer "F.Fab")
		)
		(fp_line
			(start 0.120396 0.3048)
			(end 0.120396 0.2794)
			(stroke
				(width 0.1)
				(type default)
			)
			(layer "F.Fab")
		)
		(fp_line
			(start -0.12065 0.3048)
			(end -0.67945 0.3048)
			(stroke
				(width 0.1)
				(type default)
			)
			(layer "F.Fab")
		)
		(fp_line
			(start -0.67945 0.3048)
			(end -0.67945 -0.305054)
			(stroke
				(width 0.1)
				(type default)
			)
			(layer "F.Fab")
		)
		(pad "1" smd circle
			(at -0.40005 0 90)
			(size 0 0)
			(layers "F.Cu" "F.Mask" "F.Paste")
			(net "SW_PVCCFA_EHV_FIVRA_CPU0_BOOT4")
		)
		(pad "2" smd circle
			(at 0.40005 0 90)
			(size 0 0)
			(layers "F.Cu" "F.Mask" "F.Paste")
			(net "SW_PVCCFA_EHV_FIVRA_CPU0_BOOT4_")
		)
	)
	(footprint ""
		(layer "F.Cu")
		(at 358.64546 -407.233628)
		(property "Reference" "U316"
			(at -2.84988 -2.53873 0)
			(unlocked yes)
			(layer "F.SilkS")
			(effects
				(font
					(size 0.7874 0.5842)
					(thickness 0.1524)
				)
				(justify left)
			)
		)
		(property "Value" ""
			(at 0 0 0)
			(layer "F.Fab")
			(effects
				(font
					(size 1.27 1.27)
				)
			)
		)
		(duplicate_pad_numbers_are_jumpers no)
		(fp_line
			(start -1.38176 -1.100074)
			(end -1.38176 1.100074)
			(stroke
				(width 0.1524)
				(type default)
			)
			(layer "F.SilkS")
		)
		(fp_line
			(start -1.38176 1.100074)
			(end 1.38176 1.100074)
			(stroke
				(width 0.1524)
				(type default)
			)
			(layer "F.SilkS")
		)
		(fp_line
			(start -0.592074 -1.100074)
			(end -1.38176 -1.100074)
			(stroke
				(width 0.1524)
				(type default)
			)
			(layer "F.SilkS")
		)
		(fp_line
			(start 0 -0.508)
			(end -0.592074 -1.100074)
			(stroke
				(width 0.1524)
				(type default)
			)
			(layer "F.SilkS")
		)
		(fp_line
			(start 0.592074 -1.100074)
			(end 0 -0.508)
			(stroke
				(width 0.1524)
				(type default)
			)
			(layer "F.SilkS")
		)
		(fp_line
			(start 1.38176 -1.100074)
			(end 0.592074 -1.100074)
			(stroke
				(width 0.1524)
				(type default)
			)
			(layer "F.SilkS")
		)
		(fp_line
			(start 1.38176 1.100074)
			(end 1.38176 -1.100074)
			(stroke
				(width 0.1524)
				(type default)
			)
			(layer "F.SilkS")
		)
		(fp_poly
			(pts
				(xy -1.50241 -0.649986) (xy -1.9431 -0.429768) (xy -1.9431 -0.870204)
			)
			(stroke
				(width 0)
				(type default)
			)
			(fill yes)
			(layer "F.SilkS")
		)
		(fp_line
			(start -1.100074 -0.8001)
			(end -0.670052 -0.8001)
			(stroke
				(width 0.1)
				(type default)
			)
			(layer "F.Fab")
		)
		(fp_line
			(start -1.100074 0.8001)
			(end -1.100074 -0.8001)
			(stroke
				(width 0.1)
				(type default)
			)
			(layer "F.Fab")
		)
		(fp_line
			(start -0.670052 -1.100074)
			(end 0.670052 -1.100074)
			(stroke
				(width 0.1)
				(type default)
			)
			(layer "F.Fab")
		)
		(fp_line
			(start -0.670052 -0.8001)
			(end -0.670052 -1.100074)
			(stroke
				(width 0.1)
				(type default)
			)
			(layer "F.Fab")
		)
		(fp_line
			(start -0.670052 0.8001)
			(end -1.100074 0.8001)
			(stroke
				(width 0.1)
				(type default)
			)
			(layer "F.Fab")
		)
		(fp_line
			(start -0.670052 0.8001)
			(end -0.670052 -0.8001)
			(stroke
				(width 0.1)
				(type default)
			)
			(layer "F.Fab")
		)
		(fp_line
			(start -0.670052 1.100074)
			(end -0.670052 0.8001)
			(stroke
				(width 0.1)
				(type default)
			)
			(layer "F.Fab")
		)
		(fp_line
			(start 0.670052 -1.100074)
			(end 0.670052 -0.8001)
			(stroke
				(width 0.1)
				(type default)
			)
			(layer "F.Fab")
		)
		(fp_line
			(start 0.670052 -0.8001)
			(end 0.670052 0.8001)
			(stroke
				(width 0.1)
				(type default)
			)
			(layer "F.Fab")
		)
		(fp_line
			(start 0.670052 -0.8001)
			(end 1.100074 -0.8001)
			(stroke
				(width 0.1)
				(type default)
			)
			(layer "F.Fab")
		)
		(fp_line
			(start 0.670052 0.8001)
			(end 0.670052 1.100074)
			(stroke
				(width 0.1)
				(type default)
			)
			(layer "F.Fab")
		)
		(fp_line
			(start 0.670052 1.100074)
			(end -0.670052 1.100074)
			(stroke
				(width 0.1)
				(type default)
			)
			(layer "F.Fab")
		)
		(fp_line
			(start 1.100074 -0.8001)
			(end 1.100074 0.8001)
			(stroke
				(width 0.1)
				(type default)
			)
			(layer "F.Fab")
		)
		(fp_line
			(start 1.100074 0.8001)
			(end 0.670052 0.8001)
			(stroke
				(width 0.1)
				(type default)
			)
			(layer "F.Fab")
		)
		(fp_poly
			(pts
				(xy -1.524 -0.649986) (xy -2.286 -1.030986) (xy -2.286 -0.268986)
			)
			(stroke
				(width 0)
				(type default)
			)
			(fill yes)
			(layer "F.Fab")
		)
		(pad "1" smd rect
			(at -0.94996 -0.649986 270)
			(size 0.4064 0.508)
			(layers "F.Cu" "F.Mask" "F.Paste")
			(net "SWB_HSC_EN")
		)
		(pad "2" smd rect
			(at -0.94996 0 270)
			(size 0.4064 0.508)
			(layers "F.Cu" "F.Mask" "F.Paste")
			(net "GND")
		)
		(pad "3" smd rect
			(at -0.94996 0.649986 270)
			(size 0.4064 0.508)
			(layers "F.Cu" "F.Mask" "F.Paste")
			(net "GND")
		)
		(pad "4" smd rect
			(at 0.94996 0.649986 270)
			(size 0.4064 0.508)
			(layers "F.Cu" "F.Mask" "F.Paste")
			(net "NC_U316_2Y")
		)
		(pad "5" smd rect
			(at 0.94996 0 270)
			(size 0.4064 0.508)
			(layers "F.Cu" "F.Mask" "F.Paste")
			(net "P3V3_AUX")
		)
		(pad "6" smd rect
			(at 0.94996 -0.649986 270)
			(size 0.4064 0.508)
			(layers "F.Cu" "F.Mask" "F.Paste")
			(net "SWB_HSC_EN_BUF_R")
		)
	)
	(footprint ""
		(layer "F.Cu")
		(at 463.465926 -97.523808)
		(property "Reference" "R2473"
			(at 0 0 0)
			(layer "F.SilkS")
			(hide yes)
			(effects
				(font
					(size 1.27 1.27)
				)
			)
		)
		(property "Value" ""
			(at 0 0 0)
			(layer "F.Fab")
			(effects
				(font
					(size 1.27 1.27)
				)
			)
		)
		(duplicate_pad_numbers_are_jumpers no)
		(fp_line
			(start -0.7874 -0.4064)
			(end 0.7874 -0.4064)
			(stroke
				(width 0.1524)
				(type default)
			)
			(layer "F.SilkS")
		)
		(fp_line
			(start -0.7874 0.4064)
			(end -0.7874 -0.4064)
			(stroke
				(width 0.1524)
				(type default)
			)
			(layer "F.SilkS")
		)
		(fp_line
			(start 0.7874 -0.4064)
			(end 0.7874 0.4064)
			(stroke
				(width 0.1524)
				(type default)
			)
			(layer "F.SilkS")
		)
		(fp_line
			(start 0.7874 0.4064)
			(end -0.7874 0.4064)
			(stroke
				(width 0.1524)
				(type default)
			)
			(layer "F.SilkS")
		)
		(fp_line
			(start -0.67945 -0.305054)
			(end -0.12065 -0.305054)
			(stroke
				(width 0.1)
				(type default)
			)
			(layer "F.Fab")
		)
		(fp_line
			(start -0.67945 0.3048)
			(end -0.67945 -0.305054)
			(stroke
				(width 0.1)
				(type default)
			)
			(layer "F.Fab")
		)
		(fp_line
			(start -0.12065 -0.305054)
			(end -0.12065 -0.2794)
			(stroke
				(width 0.1)
				(type default)
			)
			(layer "F.Fab")
		)
		(fp_line
			(start -0.12065 -0.2794)
			(end 0.12065 -0.2794)
			(stroke
				(width 0.1)
				(type default)
			)
			(layer "F.Fab")
		)
		(fp_line
			(start -0.12065 0.2794)
			(end -0.12065 0.3048)
			(stroke
				(width 0.1)
				(type default)
			)
			(layer "F.Fab")
		)
		(fp_line
			(start -0.12065 0.3048)
			(end -0.67945 0.3048)
			(stroke
				(width 0.1)
				(type default)
			)
			(layer "F.Fab")
		)
		(fp_line
			(start 0.120396 0.2794)
			(end -0.12065 0.2794)
			(stroke
				(width 0.1)
				(type default)
			)
			(layer "F.Fab")
		)
		(fp_line
			(start 0.120396 0.3048)
			(end 0.120396 0.2794)
			(stroke
				(width 0.1)
				(type default)
			)
			(layer "F.Fab")
		)
		(fp_line
			(start 0.12065 -0.3048)
			(end 0.67945 -0.3048)
			(stroke
				(width 0.1)
				(type default)
			)
			(layer "F.Fab")
		)
		(fp_line
			(start 0.12065 -0.2794)
			(end 0.12065 -0.3048)
			(stroke
				(width 0.1)
				(type default)
			)
			(layer "F.Fab")
		)
		(fp_line
			(start 0.67945 -0.3048)
			(end 0.67945 0.3048)
			(stroke
				(width 0.1)
				(type default)
			)
			(layer "F.Fab")
		)
		(fp_line
			(start 0.67945 0.3048)
			(end 0.120396 0.3048)
			(stroke
				(width 0.1)
				(type default)
			)
			(layer "F.Fab")
		)
		(pad "1" smd circle
			(at -0.40005 0)
			(size 0 0)
			(layers "F.Cu" "F.Mask" "F.Paste")
			(net "FB_BMC_ISOLATE_R1")
		)
		(pad "2" smd circle
			(at 0.40005 0)
			(size 0 0)
			(layers "F.Cu" "F.Mask" "F.Paste")
			(net "FB_BMC_ISOLATE")
		)
	)
	(footprint ""
		(layer "F.Cu")
		(at 128.716278 -80.112616)
		(property "Reference" "R1380"
			(at 0 0 0)
			(layer "F.SilkS")
			(hide yes)
			(effects
				(font
					(size 1.27 1.27)
				)
			)
		)
		(property "Value" ""
			(at 0 0 0)
			(layer "F.Fab")
			(effects
				(font
					(size 1.27 1.27)
				)
			)
		)
		(duplicate_pad_numbers_are_jumpers no)
		(fp_line
			(start -0.7874 -0.4064)
			(end 0.7874 -0.4064)
			(stroke
				(width 0.1524)
				(type default)
			)
			(layer "F.SilkS")
		)
		(fp_line
			(start -0.7874 0.4064)
			(end -0.7874 -0.4064)
			(stroke
				(width 0.1524)
				(type default)
			)
			(layer "F.SilkS")
		)
		(fp_line
			(start 0.7874 -0.4064)
			(end 0.7874 0.4064)
			(stroke
				(width 0.1524)
				(type default)
			)
			(layer "F.SilkS")
		)
		(fp_line
			(start 0.7874 0.4064)
			(end -0.7874 0.4064)
			(stroke
				(width 0.1524)
				(type default)
			)
			(layer "F.SilkS")
		)
		(fp_line
			(start -0.67945 -0.305054)
			(end -0.12065 -0.305054)
			(stroke
				(width 0.1)
				(type default)
			)
			(layer "F.Fab")
		)
		(fp_line
			(start -0.67945 0.3048)
			(end -0.67945 -0.305054)
			(stroke
				(width 0.1)
				(type default)
			)
			(layer "F.Fab")
		)
		(fp_line
			(start -0.12065 -0.305054)
			(end -0.12065 -0.2794)
			(stroke
				(width 0.1)
				(type default)
			)
			(layer "F.Fab")
		)
		(fp_line
			(start -0.12065 -0.2794)
			(end 0.12065 -0.2794)
			(stroke
				(width 0.1)
				(type default)
			)
			(layer "F.Fab")
		)
		(fp_line
			(start -0.12065 0.2794)
			(end -0.12065 0.3048)
			(stroke
				(width 0.1)
				(type default)
			)
			(layer "F.Fab")
		)
		(fp_line
			(start -0.12065 0.3048)
			(end -0.67945 0.3048)
			(stroke
				(width 0.1)
				(type default)
			)
			(layer "F.Fab")
		)
		(fp_line
			(start 0.120396 0.2794)
			(end -0.12065 0.2794)
			(stroke
				(width 0.1)
				(type default)
			)
			(layer "F.Fab")
		)
		(fp_line
			(start 0.120396 0.3048)
			(end 0.120396 0.2794)
			(stroke
				(width 0.1)
				(type default)
			)
			(layer "F.Fab")
		)
		(fp_line
			(start 0.12065 -0.3048)
			(end 0.67945 -0.3048)
			(stroke
				(width 0.1)
				(type default)
			)
			(layer "F.Fab")
		)
		(fp_line
			(start 0.12065 -0.2794)
			(end 0.12065 -0.3048)
			(stroke
				(width 0.1)
				(type default)
			)
			(layer "F.Fab")
		)
		(fp_line
			(start 0.67945 -0.3048)
			(end 0.67945 0.3048)
			(stroke
				(width 0.1)
				(type default)
			)
			(layer "F.Fab")
		)
		(fp_line
			(start 0.67945 0.3048)
			(end 0.120396 0.3048)
			(stroke
				(width 0.1)
				(type default)
			)
			(layer "F.Fab")
		)
		(pad "1" smd circle
			(at -0.40005 0)
			(size 0 0)
			(layers "F.Cu" "F.Mask" "F.Paste")
			(net "P3V3_AUX")
		)
		(pad "2" smd circle
			(at 0.40005 0)
			(size 0 0)
			(layers "F.Cu" "F.Mask" "F.Paste")
			(net "JTAG_BMC_DBP_TDO")
		)
	)
	(footprint ""
		(layer "F.Cu")
		(at 18.640806 -396.810738 -90)
		(property "Reference" "C2351"
			(at 0 0 270)
			(layer "F.SilkS")
			(hide yes)
			(effects
				(font
					(size 1.27 1.27)
				)
			)
		)
		(property "Value" ""
			(at 0 0 270)
			(layer "F.Fab")
			(effects
				(font
					(size 1.27 1.27)
				)
			)
		)
		(duplicate_pad_numbers_are_jumpers no)
		(fp_line
			(start 0.7874 0.4064)
			(end -0.7874 0.4064)
			(stroke
				(width 0.1524)
				(type default)
			)
			(layer "F.SilkS")
		)
		(fp_line
			(start -0.7874 -0.4064)
			(end 0.001778 -0.4064)
			(stroke
				(width 0.1524)
				(type default)
			)
			(layer "F.SilkS")
		)
		(fp_line
			(start 0.7874 -0.4064)
			(end 0.7874 0.4064)
			(stroke
				(width 0.1524)
				(type default)
			)
			(layer "F.SilkS")
		)
		(fp_line
			(start -0.6858 0.3048)
			(end -0.6858 -0.3048)
			(stroke
				(width 0.1)
				(type default)
			)
			(layer "F.Fab")
		)
		(fp_line
			(start -0.1016 0.3048)
			(end -0.6858 0.3048)
			(stroke
				(width 0.1)
				(type default)
			)
			(layer "F.Fab")
		)
		(fp_line
			(start 0.1016 0.3048)
			(end 0.1016 0.2794)
			(stroke
				(width 0.1)
				(type default)
			)
			(layer "F.Fab")
		)
		(fp_line
			(start 0.6858 0.3048)
			(end 0.1016 0.3048)
			(stroke
				(width 0.1)
				(type default)
			)
			(layer "F.Fab")
		)
		(fp_line
			(start -0.1016 0.2794)
			(end -0.1016 0.3048)
			(stroke
				(width 0.1)
				(type default)
			)
			(layer "F.Fab")
		)
		(fp_line
			(start 0.1016 0.2794)
			(end -0.1016 0.2794)
			(stroke
				(width 0.1)
				(type default)
			)
			(layer "F.Fab")
		)
		(fp_line
			(start -0.1016 -0.2794)
			(end 0.1016 -0.2794)
			(stroke
				(width 0.1)
				(type default)
			)
			(layer "F.Fab")
		)
		(fp_line
			(start 0.1016 -0.2794)
			(end 0.1016 -0.3048)
			(stroke
				(width 0.1)
				(type default)
			)
			(layer "F.Fab")
		)
		(fp_line
			(start -0.6858 -0.3048)
			(end -0.1016 -0.3048)
			(stroke
				(width 0.1)
				(type default)
			)
			(layer "F.Fab")
		)
		(fp_line
			(start -0.1016 -0.3048)
			(end -0.1016 -0.2794)
			(stroke
				(width 0.1)
				(type default)
			)
			(layer "F.Fab")
		)
		(fp_line
			(start 0.1016 -0.3048)
			(end 0.6858 -0.3048)
			(stroke
				(width 0.1)
				(type default)
			)
			(layer "F.Fab")
		)
		(fp_line
			(start 0.6858 -0.3048)
			(end 0.6858 0.3048)
			(stroke
				(width 0.1)
				(type default)
			)
			(layer "F.Fab")
		)
		(pad "1" smd rect
			(at -0.40005 0 90)
			(size 0.4572 0.508)
			(layers "F.Cu" "F.Mask" "F.Paste")
			(net "P2E_MB_BMC_TX_BUF2_DP<0>")
		)
		(pad "2" smd rect
			(at 0.40005 0 90)
			(size 0.4572 0.508)
			(layers "F.Cu" "F.Mask" "F.Paste")
			(net "P2E_MB_BMC_TX_BUF_C_DP<0>")
		)
	)
	(footprint ""
		(layer "F.Cu")
		(at 312.443622 -34.102548 180)
		(property "Reference" "R1601"
			(at 0 0 180)
			(layer "F.SilkS")
			(hide yes)
			(effects
				(font
					(size 1.27 1.27)
				)
			)
		)
		(property "Value" ""
			(at 0 0 180)
			(layer "F.Fab")
			(effects
				(font
					(size 1.27 1.27)
				)
			)
		)
		(duplicate_pad_numbers_are_jumpers no)
		(fp_line
			(start 0.7874 0.4064)
			(end -0.7874 0.4064)
			(stroke
				(width 0.1524)
				(type default)
			)
			(layer "F.SilkS")
		)
		(fp_line
			(start 0.7874 -0.4064)
			(end 0.7874 0.4064)
			(stroke
				(width 0.1524)
				(type default)
			)
			(layer "F.SilkS")
		)
		(fp_line
			(start -0.7874 0.4064)
			(end -0.7874 -0.4064)
			(stroke
				(width 0.1524)
				(type default)
			)
			(layer "F.SilkS")
		)
		(fp_line
			(start -0.7874 -0.4064)
			(end 0.7874 -0.4064)
			(stroke
				(width 0.1524)
				(type default)
			)
			(layer "F.SilkS")
		)
		(fp_line
			(start 0.67945 0.3048)
			(end 0.120396 0.3048)
			(stroke
				(width 0.1)
				(type default)
			)
			(layer "F.Fab")
		)
		(fp_line
			(start 0.67945 -0.3048)
			(end 0.67945 0.3048)
			(stroke
				(width 0.1)
				(type default)
			)
			(layer "F.Fab")
		)
		(fp_line
			(start 0.12065 -0.2794)
			(end 0.12065 -0.3048)
			(stroke
				(width 0.1)
				(type default)
			)
			(layer "F.Fab")
		)
		(fp_line
			(start 0.12065 -0.3048)
			(end 0.67945 -0.3048)
			(stroke
				(width 0.1)
				(type default)
			)
			(layer "F.Fab")
		)
		(fp_line
			(start 0.120396 0.3048)
			(end 0.120396 0.2794)
			(stroke
				(width 0.1)
				(type default)
			)
			(layer "F.Fab")
		)
		(fp_line
			(start 0.120396 0.2794)
			(end -0.12065 0.2794)
			(stroke
				(width 0.1)
				(type default)
			)
			(layer "F.Fab")
		)
		(fp_line
			(start -0.12065 0.3048)
			(end -0.67945 0.3048)
			(stroke
				(width 0.1)
				(type default)
			)
			(layer "F.Fab")
		)
		(fp_line
			(start -0.12065 0.2794)
			(end -0.12065 0.3048)
			(stroke
				(width 0.1)
				(type default)
			)
			(layer "F.Fab")
		)
		(fp_line
			(start -0.12065 -0.2794)
			(end 0.12065 -0.2794)
			(stroke
				(width 0.1)
				(type default)
			)
			(layer "F.Fab")
		)
		(fp_line
			(start -0.12065 -0.305054)
			(end -0.12065 -0.2794)
			(stroke
				(width 0.1)
				(type default)
			)
			(layer "F.Fab")
		)
		(fp_line
			(start -0.67945 0.3048)
			(end -0.67945 -0.305054)
			(stroke
				(width 0.1)
				(type default)
			)
			(layer "F.Fab")
		)
		(fp_line
			(start -0.67945 -0.305054)
			(end -0.12065 -0.305054)
			(stroke
				(width 0.1)
				(type default)
			)
			(layer "F.Fab")
		)
		(pad "1" smd circle
			(at -0.40005 0 180)
			(size 0 0)
			(layers "F.Cu" "F.Mask" "F.Paste")
			(net "IRQ_SML0_ALERT_N")
		)
		(pad "2" smd circle
			(at 0.40005 0 180)
			(size 0 0)
			(layers "F.Cu" "F.Mask" "F.Paste")
			(net "P3V3_AUX")
		)
	)
	(footprint ""
		(layer "F.Cu")
		(at 403.946106 -65.085976 180)
		(property "Reference" "R767"
			(at 0 0 180)
			(layer "F.SilkS")
			(hide yes)
			(effects
				(font
					(size 1.27 1.27)
				)
			)
		)
		(property "Value" ""
			(at 0 0 180)
			(layer "F.Fab")
			(effects
				(font
					(size 1.27 1.27)
				)
			)
		)
		(duplicate_pad_numbers_are_jumpers no)
		(fp_line
			(start 0.7874 0.4064)
			(end -0.7874 0.4064)
			(stroke
				(width 0.1524)
				(type default)
			)
			(layer "F.SilkS")
		)
		(fp_line
			(start 0.7874 -0.4064)
			(end 0.7874 0.4064)
			(stroke
				(width 0.1524)
				(type default)
			)
			(layer "F.SilkS")
		)
		(fp_line
			(start -0.7874 0.4064)
			(end -0.7874 -0.4064)
			(stroke
				(width 0.1524)
				(type default)
			)
			(layer "F.SilkS")
		)
		(fp_line
			(start -0.7874 -0.4064)
			(end 0.7874 -0.4064)
			(stroke
				(width 0.1524)
				(type default)
			)
			(layer "F.SilkS")
		)
		(fp_line
			(start 0.67945 0.3048)
			(end 0.120396 0.3048)
			(stroke
				(width 0.1)
				(type default)
			)
			(layer "F.Fab")
		)
		(fp_line
			(start 0.67945 -0.3048)
			(end 0.67945 0.3048)
			(stroke
				(width 0.1)
				(type default)
			)
			(layer "F.Fab")
		)
		(fp_line
			(start 0.12065 -0.2794)
			(end 0.12065 -0.3048)
			(stroke
				(width 0.1)
				(type default)
			)
			(layer "F.Fab")
		)
		(fp_line
			(start 0.12065 -0.3048)
			(end 0.67945 -0.3048)
			(stroke
				(width 0.1)
				(type default)
			)
			(layer "F.Fab")
		)
		(fp_line
			(start 0.120396 0.3048)
			(end 0.120396 0.2794)
			(stroke
				(width 0.1)
				(type default)
			)
			(layer "F.Fab")
		)
		(fp_line
			(start 0.120396 0.2794)
			(end -0.12065 0.2794)
			(stroke
				(width 0.1)
				(type default)
			)
			(layer "F.Fab")
		)
		(fp_line
			(start -0.12065 0.3048)
			(end -0.67945 0.3048)
			(stroke
				(width 0.1)
				(type default)
			)
			(layer "F.Fab")
		)
		(fp_line
			(start -0.12065 0.2794)
			(end -0.12065 0.3048)
			(stroke
				(width 0.1)
				(type default)
			)
			(layer "F.Fab")
		)
		(fp_line
			(start -0.12065 -0.2794)
			(end 0.12065 -0.2794)
			(stroke
				(width 0.1)
				(type default)
			)
			(layer "F.Fab")
		)
		(fp_line
			(start -0.12065 -0.305054)
			(end -0.12065 -0.2794)
			(stroke
				(width 0.1)
				(type default)
			)
			(layer "F.Fab")
		)
		(fp_line
			(start -0.67945 0.3048)
			(end -0.67945 -0.305054)
			(stroke
				(width 0.1)
				(type default)
			)
			(layer "F.Fab")
		)
		(fp_line
			(start -0.67945 -0.305054)
			(end -0.12065 -0.305054)
			(stroke
				(width 0.1)
				(type default)
			)
			(layer "F.Fab")
		)
		(pad "1" smd circle
			(at -0.40005 0 180)
			(size 0 0)
			(layers "F.Cu" "F.Mask" "F.Paste")
			(net "P3V3_AUX")
		)
		(pad "2" smd circle
			(at 0.40005 0 180)
			(size 0 0)
			(layers "F.Cu" "F.Mask" "F.Paste")
			(net "JTAG_RST_DBP_RST_CO_N")
		)
	)
	(footprint ""
		(layer "F.Cu")
		(at 96.797876 -79.078836)
		(property "Reference" "D95"
			(at -48.49241 38.649402 90)
			(unlocked yes)
			(layer "F.SilkS")
			(effects
				(font
					(size 0.635 0.4064)
					(thickness 0.1524)
				)
				(justify left)
			)
		)
		(property "Value" ""
			(at 0 0 0)
			(layer "F.Fab")
			(effects
				(font
					(size 1.27 1.27)
				)
			)
		)
		(duplicate_pad_numbers_are_jumpers no)
		(fp_line
			(start -0.90678 0.4826)
			(end -0.90678 -0.4699)
			(stroke
				(width 0.1524)
				(type default)
			)
			(layer "F.SilkS")
		)
		(fp_line
			(start -0.89408 -0.4826)
			(end 0.90678 -0.4826)
			(stroke
				(width 0.1524)
				(type default)
			)
			(layer "F.SilkS")
		)
		(fp_line
			(start -0.79248 -0.4826)
			(end 1.03378 -0.4826)
			(stroke
				(width 0.1524)
				(type default)
			)
			(layer "F.SilkS")
		)
		(fp_line
			(start -0.64008 -0.4826)
			(end 1.16078 -0.4826)
			(stroke
				(width 0.1524)
				(type default)
			)
			(layer "F.SilkS")
		)
		(fp_line
			(start 0.90678 -0.4826)
			(end 0.90678 0.4826)
			(stroke
				(width 0.1524)
				(type default)
			)
			(layer "F.SilkS")
		)
		(fp_line
			(start 0.90678 0.4826)
			(end -0.90678 0.4826)
			(stroke
				(width 0.1524)
				(type default)
			)
			(layer "F.SilkS")
		)
		(fp_line
			(start 1.03378 -0.4826)
			(end 1.03378 0.4826)
			(stroke
				(width 0.1524)
				(type default)
			)
			(layer "F.SilkS")
		)
		(fp_line
			(start 1.03378 0.4826)
			(end -0.79248 0.4826)
			(stroke
				(width 0.1524)
				(type default)
			)
			(layer "F.SilkS")
		)
		(fp_line
			(start 1.16078 -0.4826)
			(end 1.16078 0.4826)
			(stroke
				(width 0.1524)
				(type default)
			)
			(layer "F.SilkS")
		)
		(fp_line
			(start 1.16078 0.4826)
			(end -0.64008 0.4826)
			(stroke
				(width 0.1524)
				(type default)
			)
			(layer "F.SilkS")
		)
		(fp_line
			(start -0.499872 -0.249936)
			(end 0.499872 -0.249936)
			(stroke
				(width 0.1)
				(type default)
			)
			(layer "F.Fab")
		)
		(fp_line
			(start -0.499872 0.249936)
			(end -0.499872 -0.249936)
			(stroke
				(width 0.1)
				(type default)
			)
			(layer "F.Fab")
		)
		(fp_line
			(start 0.499872 -0.249936)
			(end 0.499872 0.249936)
			(stroke
				(width 0.1)
				(type default)
			)
			(layer "F.Fab")
		)
		(fp_line
			(start 0.499872 0.249936)
			(end -0.499872 0.249936)
			(stroke
				(width 0.1)
				(type default)
			)
			(layer "F.Fab")
		)
		(pad "A" smd rect
			(at -0.47498 0)
			(size 0.6096 0.7112)
			(layers "F.Cu" "F.Mask" "F.Paste")
			(net "LED_FM_PCH_SLP_S3_N")
		)
		(pad "C" smd rect
			(at 0.47498 0)
			(size 0.6096 0.7112)
			(layers "F.Cu" "F.Mask" "F.Paste")
			(net "LED_FM_PCH_SLP_S3_N_D")
		)
	)
	(footprint ""
		(layer "F.Cu")
		(at 356.28072 -406.850088 90)
		(property "Reference" "R4547"
			(at 0 0 90)
			(layer "F.SilkS")
			(hide yes)
			(effects
				(font
					(size 1.27 1.27)
				)
			)
		)
		(property "Value" ""
			(at 0 0 90)
			(layer "F.Fab")
			(effects
				(font
					(size 1.27 1.27)
				)
			)
		)
		(duplicate_pad_numbers_are_jumpers no)
		(fp_line
			(start 0.7874 -0.4064)
			(end 0.7874 0.4064)
			(stroke
				(width 0.1524)
				(type default)
			)
			(layer "F.SilkS")
		)
		(fp_line
			(start -0.7874 -0.4064)
			(end 0.7874 -0.4064)
			(stroke
				(width 0.1524)
				(type default)
			)
			(layer "F.SilkS")
		)
		(fp_line
			(start 0.7874 0.4064)
			(end -0.7874 0.4064)
			(stroke
				(width 0.1524)
				(type default)
			)
			(layer "F.SilkS")
		)
		(fp_line
			(start -0.7874 0.4064)
			(end -0.7874 -0.4064)
			(stroke
				(width 0.1524)
				(type default)
			)
			(layer "F.SilkS")
		)
		(fp_line
			(start -0.12065 -0.305054)
			(end -0.12065 -0.2794)
			(stroke
				(width 0.1)
				(type default)
			)
			(layer "F.Fab")
		)
		(fp_line
			(start -0.67945 -0.305054)
			(end -0.12065 -0.305054)
			(stroke
				(width 0.1)
				(type default)
			)
			(layer "F.Fab")
		)
		(fp_line
			(start 0.67945 -0.3048)
			(end 0.67945 0.3048)
			(stroke
				(width 0.1)
				(type default)
			)
			(layer "F.Fab")
		)
		(fp_line
			(start 0.12065 -0.3048)
			(end 0.67945 -0.3048)
			(stroke
				(width 0.1)
				(type default)
			)
			(layer "F.Fab")
		)
		(fp_line
			(start 0.12065 -0.2794)
			(end 0.12065 -0.3048)
			(stroke
				(width 0.1)
				(type default)
			)
			(layer "F.Fab")
		)
		(fp_line
			(start -0.12065 -0.2794)
			(end 0.12065 -0.2794)
			(stroke
				(width 0.1)
				(type default)
			)
			(layer "F.Fab")
		)
		(fp_line
			(start 0.120396 0.2794)
			(end -0.12065 0.2794)
			(stroke
				(width 0.1)
				(type default)
			)
			(layer "F.Fab")
		)
		(fp_line
			(start -0.12065 0.2794)
			(end -0.12065 0.3048)
			(stroke
				(width 0.1)
				(type default)
			)
			(layer "F.Fab")
		)
		(fp_line
			(start 0.67945 0.3048)
			(end 0.120396 0.3048)
			(stroke
				(width 0.1)
				(type default)
			)
			(layer "F.Fab")
		)
		(fp_line
			(start 0.120396 0.3048)
			(end 0.120396 0.2794)
			(stroke
				(width 0.1)
				(type default)
			)
			(layer "F.Fab")
		)
		(fp_line
			(start -0.12065 0.3048)
			(end -0.67945 0.3048)
			(stroke
				(width 0.1)
				(type default)
			)
			(layer "F.Fab")
		)
		(fp_line
			(start -0.67945 0.3048)
			(end -0.67945 -0.305054)
			(stroke
				(width 0.1)
				(type default)
			)
			(layer "F.Fab")
		)
		(pad "1" smd circle
			(at -0.40005 0 90)
			(size 0 0)
			(layers "F.Cu" "F.Mask" "F.Paste")
			(net "P3V3_AUX")
		)
		(pad "2" smd circle
			(at 0.40005 0 90)
			(size 0 0)
			(layers "F.Cu" "F.Mask" "F.Paste")
			(net "SWB_HSC_EN")
		)
	)
	(footprint ""
		(layer "F.Cu")
		(at 125.453394 -408.517344 -90)
		(property "Reference" "C1519"
			(at 0 0 270)
			(layer "F.SilkS")
			(hide yes)
			(effects
				(font
					(size 1.27 1.27)
				)
			)
		)
		(property "Value" ""
			(at 0 0 270)
			(layer "F.Fab")
			(effects
				(font
					(size 1.27 1.27)
				)
			)
		)
		(duplicate_pad_numbers_are_jumpers no)
		(fp_line
			(start -0.299974 0.150114)
			(end -0.299974 -0.150114)
			(stroke
				(width 0.1)
				(type default)
			)
			(layer "F.Fab")
		)
		(fp_line
			(start 0.299974 0.150114)
			(end -0.299974 0.150114)
			(stroke
				(width 0.1)
				(type default)
			)
			(layer "F.Fab")
		)
		(fp_line
			(start -0.299974 -0.150114)
			(end 0.299974 -0.150114)
			(stroke
				(width 0.1)
				(type default)
			)
			(layer "F.Fab")
		)
		(fp_line
			(start 0.299974 -0.150114)
			(end 0.299974 0.150114)
			(stroke
				(width 0.1)
				(type default)
			)
			(layer "F.Fab")
		)
		(pad "1" smd rect
			(at -0.2667 0 270)
			(size 0.3048 0.381)
			(layers "F.Cu" "F.Mask" "F.Paste")
			(net "P5E_CPU1_PE3_TX_C_DP<14>")
		)
		(pad "2" smd rect
			(at 0.2667 0 270)
			(size 0.3048 0.381)
			(layers "F.Cu" "F.Mask" "F.Paste")
			(net "P5E_CPU1_PE3_TX_DP<14>")
		)
	)
	(footprint ""
		(layer "F.Cu")
		(at 430.277016 -101.97719 180)
		(property "Reference" "R3783"
			(at 0 0 180)
			(layer "F.SilkS")
			(hide yes)
			(effects
				(font
					(size 1.27 1.27)
				)
			)
		)
		(property "Value" ""
			(at 0 0 180)
			(layer "F.Fab")
			(effects
				(font
					(size 1.27 1.27)
				)
			)
		)
		(duplicate_pad_numbers_are_jumpers no)
		(fp_line
			(start 0.7874 0.4064)
			(end -0.7874 0.4064)
			(stroke
				(width 0.1524)
				(type default)
			)
			(layer "F.SilkS")
		)
		(fp_line
			(start 0.7874 -0.4064)
			(end 0.7874 0.4064)
			(stroke
				(width 0.1524)
				(type default)
			)
			(layer "F.SilkS")
		)
		(fp_line
			(start -0.7874 0.4064)
			(end -0.7874 -0.4064)
			(stroke
				(width 0.1524)
				(type default)
			)
			(layer "F.SilkS")
		)
		(fp_line
			(start -0.7874 -0.4064)
			(end 0.7874 -0.4064)
			(stroke
				(width 0.1524)
				(type default)
			)
			(layer "F.SilkS")
		)
		(fp_line
			(start 0.67945 0.3048)
			(end 0.120396 0.3048)
			(stroke
				(width 0.1)
				(type default)
			)
			(layer "F.Fab")
		)
		(fp_line
			(start 0.67945 -0.3048)
			(end 0.67945 0.3048)
			(stroke
				(width 0.1)
				(type default)
			)
			(layer "F.Fab")
		)
		(fp_line
			(start 0.12065 -0.2794)
			(end 0.12065 -0.3048)
			(stroke
				(width 0.1)
				(type default)
			)
			(layer "F.Fab")
		)
		(fp_line
			(start 0.12065 -0.3048)
			(end 0.67945 -0.3048)
			(stroke
				(width 0.1)
				(type default)
			)
			(layer "F.Fab")
		)
		(fp_line
			(start 0.120396 0.3048)
			(end 0.120396 0.2794)
			(stroke
				(width 0.1)
				(type default)
			)
			(layer "F.Fab")
		)
		(fp_line
			(start 0.120396 0.2794)
			(end -0.12065 0.2794)
			(stroke
				(width 0.1)
				(type default)
			)
			(layer "F.Fab")
		)
		(fp_line
			(start -0.12065 0.3048)
			(end -0.67945 0.3048)
			(stroke
				(width 0.1)
				(type default)
			)
			(layer "F.Fab")
		)
		(fp_line
			(start -0.12065 0.2794)
			(end -0.12065 0.3048)
			(stroke
				(width 0.1)
				(type default)
			)
			(layer "F.Fab")
		)
		(fp_line
			(start -0.12065 -0.2794)
			(end 0.12065 -0.2794)
			(stroke
				(width 0.1)
				(type default)
			)
			(layer "F.Fab")
		)
		(fp_line
			(start -0.12065 -0.305054)
			(end -0.12065 -0.2794)
			(stroke
				(width 0.1)
				(type default)
			)
			(layer "F.Fab")
		)
		(fp_line
			(start -0.67945 0.3048)
			(end -0.67945 -0.305054)
			(stroke
				(width 0.1)
				(type default)
			)
			(layer "F.Fab")
		)
		(fp_line
			(start -0.67945 -0.305054)
			(end -0.12065 -0.305054)
			(stroke
				(width 0.1)
				(type default)
			)
			(layer "F.Fab")
		)
		(pad "1" smd circle
			(at -0.40005 0 180)
			(size 0 0)
			(layers "F.Cu" "F.Mask" "F.Paste")
			(net "P3V3_AUX")
		)
		(pad "2" smd circle
			(at 0.40005 0 180)
			(size 0 0)
			(layers "F.Cu" "F.Mask" "F.Paste")
			(net "OCP_V3_1_P3V3_PWRGD")
		)
	)
	(footprint ""
		(layer "F.Cu")
		(at 37.860478 -16.099536 90)
		(property "Reference" "C823"
			(at 0 0 90)
			(layer "F.SilkS")
			(hide yes)
			(effects
				(font
					(size 1.27 1.27)
				)
			)
		)
		(property "Value" ""
			(at 0 0 90)
			(layer "F.Fab")
			(effects
				(font
					(size 1.27 1.27)
				)
			)
		)
		(duplicate_pad_numbers_are_jumpers no)
		(fp_line
			(start 0.299974 -0.150114)
			(end 0.299974 0.150114)
			(stroke
				(width 0.1)
				(type default)
			)
			(layer "F.Fab")
		)
		(fp_line
			(start -0.299974 -0.150114)
			(end 0.299974 -0.150114)
			(stroke
				(width 0.1)
				(type default)
			)
			(layer "F.Fab")
		)
		(fp_line
			(start 0.299974 0.150114)
			(end -0.299974 0.150114)
			(stroke
				(width 0.1)
				(type default)
			)
			(layer "F.Fab")
		)
		(fp_line
			(start -0.299974 0.150114)
			(end -0.299974 -0.150114)
			(stroke
				(width 0.1)
				(type default)
			)
			(layer "F.Fab")
		)
		(pad "1" smd rect
			(at -0.2667 0 90)
			(size 0.3048 0.381)
			(layers "F.Cu" "F.Mask" "F.Paste")
			(net "P5E_CPU1_PE1_TX_C_DP<7>")
		)
		(pad "2" smd rect
			(at 0.2667 0 90)
			(size 0.3048 0.381)
			(layers "F.Cu" "F.Mask" "F.Paste")
			(net "P5E_CPU1_PE1_TX_DP<7>")
		)
	)
	(footprint ""
		(layer "F.Cu")
		(at 388.72541 -35.731196 90)
		(property "Reference" "U52"
			(at 3.957828 -0.994918 0)
			(unlocked yes)
			(layer "F.SilkS")
			(effects
				(font
					(size 0.7874 0.5842)
					(thickness 0.1524)
				)
				(justify left)
			)
		)
		(property "Value" ""
			(at 0 0 90)
			(layer "F.Fab")
			(effects
				(font
					(size 1.27 1.27)
				)
			)
		)
		(duplicate_pad_numbers_are_jumpers no)
		(fp_line
			(start 1.759712 -1.500124)
			(end 1.759712 1.500124)
			(stroke
				(width 0.1524)
				(type default)
			)
			(layer "F.SilkS")
		)
		(fp_line
			(start -1.759712 -1.500124)
			(end 1.759712 -1.500124)
			(stroke
				(width 0.1524)
				(type default)
			)
			(layer "F.SilkS")
		)
		(fp_line
			(start 1.759712 1.500124)
			(end -1.759712 1.500124)
			(stroke
				(width 0.1524)
				(type default)
			)
			(layer "F.SilkS")
		)
		(fp_line
			(start -1.759712 1.500124)
			(end -1.759712 -1.500124)
			(stroke
				(width 0.1524)
				(type default)
			)
			(layer "F.SilkS")
		)
		(fp_line
			(start 0.700024 -1.500124)
			(end 0.700024 1.500124)
			(stroke
				(width 0.1)
				(type default)
			)
			(layer "F.Fab")
		)
		(fp_line
			(start -0.700024 -1.500124)
			(end 0.700024 -1.500124)
			(stroke
				(width 0.1)
				(type default)
			)
			(layer "F.Fab")
		)
		(fp_line
			(start 0.700024 1.500124)
			(end -0.700024 1.500124)
			(stroke
				(width 0.1)
				(type default)
			)
			(layer "F.Fab")
		)
		(fp_line
			(start -0.700024 1.500124)
			(end -0.700024 -1.500124)
			(stroke
				(width 0.1)
				(type default)
			)
			(layer "F.Fab")
		)
		(pad "1" smd rect
			(at -1.150112 -0.94996)
			(size 0.6604 0.9652)
			(layers "F.Cu" "F.Mask" "F.Paste")
			(net "GND")
		)
		(pad "2" smd rect
			(at -1.150112 0.94996)
			(size 0.6604 0.9652)
			(layers "F.Cu" "F.Mask" "F.Paste")
			(net "HP_OCP_V3_1_RST")
		)
		(pad "3" smd rect
			(at 1.150112 0)
			(size 0.6604 0.9652)
			(layers "F.Cu" "F.Mask" "F.Paste")
			(net "P3V3_OCP_SFF")
		)
	)
	(footprint ""
		(layer "F.Cu")
		(at 54.242716 -110.93069 180)
		(property "Reference" "R3715"
			(at 0 0 180)
			(layer "F.SilkS")
			(hide yes)
			(effects
				(font
					(size 1.27 1.27)
				)
			)
		)
		(property "Value" ""
			(at 0 0 180)
			(layer "F.Fab")
			(effects
				(font
					(size 1.27 1.27)
				)
			)
		)
		(duplicate_pad_numbers_are_jumpers no)
		(fp_line
			(start 0.7874 0.4064)
			(end -0.7874 0.4064)
			(stroke
				(width 0.1524)
				(type default)
			)
			(layer "F.SilkS")
		)
		(fp_line
			(start 0.7874 -0.4064)
			(end 0.7874 0.4064)
			(stroke
				(width 0.1524)
				(type default)
			)
			(layer "F.SilkS")
		)
		(fp_line
			(start -0.7874 0.4064)
			(end -0.7874 -0.4064)
			(stroke
				(width 0.1524)
				(type default)
			)
			(layer "F.SilkS")
		)
		(fp_line
			(start -0.7874 -0.4064)
			(end 0.7874 -0.4064)
			(stroke
				(width 0.1524)
				(type default)
			)
			(layer "F.SilkS")
		)
		(fp_line
			(start 0.67945 0.3048)
			(end 0.120396 0.3048)
			(stroke
				(width 0.1)
				(type default)
			)
			(layer "F.Fab")
		)
		(fp_line
			(start 0.67945 -0.3048)
			(end 0.67945 0.3048)
			(stroke
				(width 0.1)
				(type default)
			)
			(layer "F.Fab")
		)
		(fp_line
			(start 0.12065 -0.2794)
			(end 0.12065 -0.3048)
			(stroke
				(width 0.1)
				(type default)
			)
			(layer "F.Fab")
		)
		(fp_line
			(start 0.12065 -0.3048)
			(end 0.67945 -0.3048)
			(stroke
				(width 0.1)
				(type default)
			)
			(layer "F.Fab")
		)
		(fp_line
			(start 0.120396 0.3048)
			(end 0.120396 0.2794)
			(stroke
				(width 0.1)
				(type default)
			)
			(layer "F.Fab")
		)
		(fp_line
			(start 0.120396 0.2794)
			(end -0.12065 0.2794)
			(stroke
				(width 0.1)
				(type default)
			)
			(layer "F.Fab")
		)
		(fp_line
			(start -0.12065 0.3048)
			(end -0.67945 0.3048)
			(stroke
				(width 0.1)
				(type default)
			)
			(layer "F.Fab")
		)
		(fp_line
			(start -0.12065 0.2794)
			(end -0.12065 0.3048)
			(stroke
				(width 0.1)
				(type default)
			)
			(layer "F.Fab")
		)
		(fp_line
			(start -0.12065 -0.2794)
			(end 0.12065 -0.2794)
			(stroke
				(width 0.1)
				(type default)
			)
			(layer "F.Fab")
		)
		(fp_line
			(start -0.12065 -0.305054)
			(end -0.12065 -0.2794)
			(stroke
				(width 0.1)
				(type default)
			)
			(layer "F.Fab")
		)
		(fp_line
			(start -0.67945 0.3048)
			(end -0.67945 -0.305054)
			(stroke
				(width 0.1)
				(type default)
			)
			(layer "F.Fab")
		)
		(fp_line
			(start -0.67945 -0.305054)
			(end -0.12065 -0.305054)
			(stroke
				(width 0.1)
				(type default)
			)
			(layer "F.Fab")
		)
		(pad "1" smd circle
			(at -0.40005 0 180)
			(size 0 0)
			(layers "F.Cu" "F.Mask" "F.Paste")
			(net "SMB_LM75_0_3V3AUX_SCL_R")
		)
		(pad "2" smd circle
			(at 0.40005 0 180)
			(size 0 0)
			(layers "F.Cu" "F.Mask" "F.Paste")
			(net "SMB_LM75_0_3V3AUX_SCL")
		)
	)
	(footprint ""
		(layer "F.Cu")
		(at 274.495006 -19.952462)
		(property "Reference" "R3184"
			(at 0 0 0)
			(layer "F.SilkS")
			(hide yes)
			(effects
				(font
					(size 1.27 1.27)
				)
			)
		)
		(property "Value" ""
			(at 0 0 0)
			(layer "F.Fab")
			(effects
				(font
					(size 1.27 1.27)
				)
			)
		)
		(duplicate_pad_numbers_are_jumpers no)
		(fp_line
			(start -0.7874 -0.4064)
			(end 0.7874 -0.4064)
			(stroke
				(width 0.1524)
				(type default)
			)
			(layer "F.SilkS")
		)
		(fp_line
			(start -0.7874 0.4064)
			(end -0.7874 -0.4064)
			(stroke
				(width 0.1524)
				(type default)
			)
			(layer "F.SilkS")
		)
		(fp_line
			(start 0.7874 -0.4064)
			(end 0.7874 0.4064)
			(stroke
				(width 0.1524)
				(type default)
			)
			(layer "F.SilkS")
		)
		(fp_line
			(start 0.7874 0.4064)
			(end -0.7874 0.4064)
			(stroke
				(width 0.1524)
				(type default)
			)
			(layer "F.SilkS")
		)
		(fp_line
			(start -0.67945 -0.305054)
			(end -0.12065 -0.305054)
			(stroke
				(width 0.1)
				(type default)
			)
			(layer "F.Fab")
		)
		(fp_line
			(start -0.67945 0.3048)
			(end -0.67945 -0.305054)
			(stroke
				(width 0.1)
				(type default)
			)
			(layer "F.Fab")
		)
		(fp_line
			(start -0.12065 -0.305054)
			(end -0.12065 -0.2794)
			(stroke
				(width 0.1)
				(type default)
			)
			(layer "F.Fab")
		)
		(fp_line
			(start -0.12065 -0.2794)
			(end 0.12065 -0.2794)
			(stroke
				(width 0.1)
				(type default)
			)
			(layer "F.Fab")
		)
		(fp_line
			(start -0.12065 0.2794)
			(end -0.12065 0.3048)
			(stroke
				(width 0.1)
				(type default)
			)
			(layer "F.Fab")
		)
		(fp_line
			(start -0.12065 0.3048)
			(end -0.67945 0.3048)
			(stroke
				(width 0.1)
				(type default)
			)
			(layer "F.Fab")
		)
		(fp_line
			(start 0.120396 0.2794)
			(end -0.12065 0.2794)
			(stroke
				(width 0.1)
				(type default)
			)
			(layer "F.Fab")
		)
		(fp_line
			(start 0.120396 0.3048)
			(end 0.120396 0.2794)
			(stroke
				(width 0.1)
				(type default)
			)
			(layer "F.Fab")
		)
		(fp_line
			(start 0.12065 -0.3048)
			(end 0.67945 -0.3048)
			(stroke
				(width 0.1)
				(type default)
			)
			(layer "F.Fab")
		)
		(fp_line
			(start 0.12065 -0.2794)
			(end 0.12065 -0.3048)
			(stroke
				(width 0.1)
				(type default)
			)
			(layer "F.Fab")
		)
		(fp_line
			(start 0.67945 -0.3048)
			(end 0.67945 0.3048)
			(stroke
				(width 0.1)
				(type default)
			)
			(layer "F.Fab")
		)
		(fp_line
			(start 0.67945 0.3048)
			(end 0.120396 0.3048)
			(stroke
				(width 0.1)
				(type default)
			)
			(layer "F.Fab")
		)
		(pad "1" smd circle
			(at -0.40005 0)
			(size 0 0)
			(layers "F.Cu" "F.Mask" "F.Paste")
			(net "P3V3_AUX")
		)
		(pad "2" smd circle
			(at 0.40005 0)
			(size 0 0)
			(layers "F.Cu" "F.Mask" "F.Paste")
			(net "OCP_V3_2_WAKE_BUFF_N")
		)
	)
	(footprint ""
		(layer "F.Cu")
		(at 9.58088 -56.982868)
		(property "Reference" "R3060"
			(at 0 0 0)
			(layer "F.SilkS")
			(hide yes)
			(effects
				(font
					(size 1.27 1.27)
				)
			)
		)
		(property "Value" ""
			(at 0 0 0)
			(layer "F.Fab")
			(effects
				(font
					(size 1.27 1.27)
				)
			)
		)
		(duplicate_pad_numbers_are_jumpers no)
		(fp_line
			(start -0.7874 -0.4064)
			(end 0.7874 -0.4064)
			(stroke
				(width 0.1524)
				(type default)
			)
			(layer "F.SilkS")
		)
		(fp_line
			(start -0.7874 0.4064)
			(end -0.7874 -0.4064)
			(stroke
				(width 0.1524)
				(type default)
			)
			(layer "F.SilkS")
		)
		(fp_line
			(start 0.7874 -0.4064)
			(end 0.7874 0.4064)
			(stroke
				(width 0.1524)
				(type default)
			)
			(layer "F.SilkS")
		)
		(fp_line
			(start 0.7874 0.4064)
			(end -0.7874 0.4064)
			(stroke
				(width 0.1524)
				(type default)
			)
			(layer "F.SilkS")
		)
		(fp_line
			(start -0.67945 -0.305054)
			(end -0.12065 -0.305054)
			(stroke
				(width 0.1)
				(type default)
			)
			(layer "F.Fab")
		)
		(fp_line
			(start -0.67945 0.3048)
			(end -0.67945 -0.305054)
			(stroke
				(width 0.1)
				(type default)
			)
			(layer "F.Fab")
		)
		(fp_line
			(start -0.12065 -0.305054)
			(end -0.12065 -0.2794)
			(stroke
				(width 0.1)
				(type default)
			)
			(layer "F.Fab")
		)
		(fp_line
			(start -0.12065 -0.2794)
			(end 0.12065 -0.2794)
			(stroke
				(width 0.1)
				(type default)
			)
			(layer "F.Fab")
		)
		(fp_line
			(start -0.12065 0.2794)
			(end -0.12065 0.3048)
			(stroke
				(width 0.1)
				(type default)
			)
			(layer "F.Fab")
		)
		(fp_line
			(start -0.12065 0.3048)
			(end -0.67945 0.3048)
			(stroke
				(width 0.1)
				(type default)
			)
			(layer "F.Fab")
		)
		(fp_line
			(start 0.120396 0.2794)
			(end -0.12065 0.2794)
			(stroke
				(width 0.1)
				(type default)
			)
			(layer "F.Fab")
		)
		(fp_line
			(start 0.120396 0.3048)
			(end 0.120396 0.2794)
			(stroke
				(width 0.1)
				(type default)
			)
			(layer "F.Fab")
		)
		(fp_line
			(start 0.12065 -0.3048)
			(end 0.67945 -0.3048)
			(stroke
				(width 0.1)
				(type default)
			)
			(layer "F.Fab")
		)
		(fp_line
			(start 0.12065 -0.2794)
			(end 0.12065 -0.3048)
			(stroke
				(width 0.1)
				(type default)
			)
			(layer "F.Fab")
		)
		(fp_line
			(start 0.67945 -0.3048)
			(end 0.67945 0.3048)
			(stroke
				(width 0.1)
				(type default)
			)
			(layer "F.Fab")
		)
		(fp_line
			(start 0.67945 0.3048)
			(end 0.120396 0.3048)
			(stroke
				(width 0.1)
				(type default)
			)
			(layer "F.Fab")
		)
		(pad "1" smd circle
			(at -0.40005 0)
			(size 0 0)
			(layers "F.Cu" "F.Mask" "F.Paste")
			(net "SMB_SML1_PMBUS_3V3AUX_PCH_SCL")
		)
		(pad "2" smd circle
			(at 0.40005 0)
			(size 0 0)
			(layers "F.Cu" "F.Mask" "F.Paste")
			(net "SMB_PMBUS_SML1_ME_SCL")
		)
	)
	(footprint ""
		(layer "F.Cu")
		(at 393.316206 -155.356052 -90)
		(property "Reference" "U30"
			(at 0.617474 -3.043174 0)
			(unlocked yes)
			(layer "F.SilkS")
			(effects
				(font
					(size 0.7874 0.5842)
					(thickness 0.1524)
				)
				(justify left)
			)
		)
		(property "Value" ""
			(at 0 0 270)
			(layer "F.Fab")
			(effects
				(font
					(size 1.27 1.27)
				)
			)
		)
		(duplicate_pad_numbers_are_jumpers no)
		(fp_line
			(start -1.4224 2.5146)
			(end 1.4224 2.5146)
			(stroke
				(width 0.1524)
				(type default)
			)
			(layer "F.SilkS")
		)
		(fp_line
			(start 1.4224 2.5146)
			(end 1.4224 -2.5146)
			(stroke
				(width 0.1524)
				(type default)
			)
			(layer "F.SilkS")
		)
		(fp_line
			(start 0 -2.0574)
			(end -0.4572 -2.5146)
			(stroke
				(width 0.1524)
				(type default)
			)
			(layer "F.SilkS")
		)
		(fp_line
			(start -1.4224 -2.5146)
			(end -1.4224 2.5146)
			(stroke
				(width 0.1524)
				(type default)
			)
			(layer "F.SilkS")
		)
		(fp_line
			(start -0.4572 -2.5146)
			(end -1.4224 -2.5146)
			(stroke
				(width 0.1524)
				(type default)
			)
			(layer "F.SilkS")
		)
		(fp_line
			(start 0.4572 -2.5146)
			(end 0 -2.0574)
			(stroke
				(width 0.1524)
				(type default)
			)
			(layer "F.SilkS")
		)
		(fp_line
			(start 1.4224 -2.5146)
			(end 0.4572 -2.5146)
			(stroke
				(width 0.1524)
				(type default)
			)
			(layer "F.SilkS")
		)
		(fp_poly
			(pts
				(xy -3.080004 -3.230118) (xy -2.318004 -3.230118) (xy -2.699004 -2.468118)
			)
			(stroke
				(width 0)
				(type default)
			)
			(fill yes)
			(layer "F.SilkS")
		)
		(fp_line
			(start -2.0066 2.5146)
			(end 2.0066 2.5146)
			(stroke
				(width 0.1)
				(type default)
			)
			(layer "F.Fab")
		)
		(fp_line
			(start 2.0066 2.5146)
			(end 2.0066 2.112264)
			(stroke
				(width 0.1)
				(type default)
			)
			(layer "F.Fab")
		)
		(fp_line
			(start -2.648712 2.112264)
			(end -2.0066 2.112264)
			(stroke
				(width 0.1)
				(type default)
			)
			(layer "F.Fab")
		)
		(fp_line
			(start -2.0066 2.112264)
			(end -2.0066 2.5146)
			(stroke
				(width 0.1)
				(type default)
			)
			(layer "F.Fab")
		)
		(fp_line
			(start 2.0066 2.112264)
			(end 2.642616 2.112264)
			(stroke
				(width 0.1)
				(type default)
			)
			(layer "F.Fab")
		)
		(fp_line
			(start 2.642616 2.112264)
			(end 2.642616 -2.112264)
			(stroke
				(width 0.1)
				(type default)
			)
			(layer "F.Fab")
		)
		(fp_line
			(start 2.0066 -2.112264)
			(end 2.0066 -2.5146)
			(stroke
				(width 0.1)
				(type default)
			)
			(layer "F.Fab")
		)
		(fp_line
			(start 2.642616 -2.112264)
			(end 2.0066 -2.112264)
			(stroke
				(width 0.1)
				(type default)
			)
			(layer "F.Fab")
		)
		(fp_line
			(start -2.648712 -2.114804)
			(end -2.648712 2.112264)
			(stroke
				(width 0.1)
				(type default)
			)
			(layer "F.Fab")
		)
		(fp_line
			(start -2.0066 -2.114804)
			(end -2.648712 -2.114804)
			(stroke
				(width 0.1)
				(type default)
			)
			(layer "F.Fab")
		)
		(fp_line
			(start -2.0066 -2.5146)
			(end -2.0066 -2.114804)
			(stroke
				(width 0.1)
				(type default)
			)
			(layer "F.Fab")
		)
		(fp_line
			(start 2.0066 -2.5146)
			(end -2.0066 -2.5146)
			(stroke
				(width 0.1)
				(type default)
			)
			(layer "F.Fab")
		)
		(fp_poly
			(pts
				(xy -3.6322 -1.869186) (xy -4.3942 -1.488186) (xy -4.3942 -2.250186)
			)
			(stroke
				(width 0)
				(type default)
			)
			(fill yes)
			(layer "F.Fab")
		)
		(pad "1" smd rect
			(at -2.6416 -1.905 180)
			(size 0.5588 1.7272)
			(layers "F.Cu" "F.Mask" "F.Paste")
			(net "PVNN_TERM_CPU0")
		)
		(pad "2" smd rect
			(at -2.6416 -0.635 180)
			(size 0.5588 1.7272)
			(layers "F.Cu" "F.Mask" "F.Paste")
			(net "SMB_S3M_CPU0_R_SCL")
		)
		(pad "3" smd rect
			(at -2.6416 0.635 180)
			(size 0.5588 1.7272)
			(layers "F.Cu" "F.Mask" "F.Paste")
			(net "SMB_S3M_CPU0_R_SDA")
		)
		(pad "4" smd rect
			(at -2.6416 1.905 180)
			(size 0.5588 1.7272)
			(layers "F.Cu" "F.Mask" "F.Paste")
			(net "GND")
		)
		(pad "5" smd rect
			(at 2.6416 1.905 180)
			(size 0.5588 1.7272)
			(layers "F.Cu" "F.Mask" "F.Paste")
			(net "TP_SMB_S3M_CPU0_EN")
		)
		(pad "6" smd rect
			(at 2.6416 0.635 180)
			(size 0.5588 1.7272)
			(layers "F.Cu" "F.Mask" "F.Paste")
			(net "SMB_S3M_CPU0_3V3AUX_SDA")
		)
		(pad "7" smd rect
			(at 2.6416 -0.635 180)
			(size 0.5588 1.7272)
			(layers "F.Cu" "F.Mask" "F.Paste")
			(net "SMB_S3M_CPU0_3V3AUX_SCL")
		)
		(pad "8" smd rect
			(at 2.6416 -1.905 180)
			(size 0.5588 1.7272)
			(layers "F.Cu" "F.Mask" "F.Paste")
			(net "P3V3_AUX")
		)
	)
	(footprint ""
		(layer "F.Cu")
		(at 170.23588 -126.964948 90)
		(property "Reference" "R984"
			(at 0 0 90)
			(layer "F.SilkS")
			(hide yes)
			(effects
				(font
					(size 1.27 1.27)
				)
			)
		)
		(property "Value" ""
			(at 0 0 90)
			(layer "F.Fab")
			(effects
				(font
					(size 1.27 1.27)
				)
			)
		)
		(duplicate_pad_numbers_are_jumpers no)
		(fp_line
			(start 0.7874 -0.4064)
			(end 0.7874 0.4064)
			(stroke
				(width 0.1524)
				(type default)
			)
			(layer "F.SilkS")
		)
		(fp_line
			(start -0.7874 -0.4064)
			(end 0.7874 -0.4064)
			(stroke
				(width 0.1524)
				(type default)
			)
			(layer "F.SilkS")
		)
		(fp_line
			(start 0.7874 0.4064)
			(end -0.7874 0.4064)
			(stroke
				(width 0.1524)
				(type default)
			)
			(layer "F.SilkS")
		)
		(fp_line
			(start -0.7874 0.4064)
			(end -0.7874 -0.4064)
			(stroke
				(width 0.1524)
				(type default)
			)
			(layer "F.SilkS")
		)
		(fp_line
			(start -0.12065 -0.305054)
			(end -0.12065 -0.2794)
			(stroke
				(width 0.1)
				(type default)
			)
			(layer "F.Fab")
		)
		(fp_line
			(start -0.67945 -0.305054)
			(end -0.12065 -0.305054)
			(stroke
				(width 0.1)
				(type default)
			)
			(layer "F.Fab")
		)
		(fp_line
			(start 0.67945 -0.3048)
			(end 0.67945 0.3048)
			(stroke
				(width 0.1)
				(type default)
			)
			(layer "F.Fab")
		)
		(fp_line
			(start 0.12065 -0.3048)
			(end 0.67945 -0.3048)
			(stroke
				(width 0.1)
				(type default)
			)
			(layer "F.Fab")
		)
		(fp_line
			(start 0.12065 -0.2794)
			(end 0.12065 -0.3048)
			(stroke
				(width 0.1)
				(type default)
			)
			(layer "F.Fab")
		)
		(fp_line
			(start -0.12065 -0.2794)
			(end 0.12065 -0.2794)
			(stroke
				(width 0.1)
				(type default)
			)
			(layer "F.Fab")
		)
		(fp_line
			(start 0.120396 0.2794)
			(end -0.12065 0.2794)
			(stroke
				(width 0.1)
				(type default)
			)
			(layer "F.Fab")
		)
		(fp_line
			(start -0.12065 0.2794)
			(end -0.12065 0.3048)
			(stroke
				(width 0.1)
				(type default)
			)
			(layer "F.Fab")
		)
		(fp_line
			(start 0.67945 0.3048)
			(end 0.120396 0.3048)
			(stroke
				(width 0.1)
				(type default)
			)
			(layer "F.Fab")
		)
		(fp_line
			(start 0.120396 0.3048)
			(end 0.120396 0.2794)
			(stroke
				(width 0.1)
				(type default)
			)
			(layer "F.Fab")
		)
		(fp_line
			(start -0.12065 0.3048)
			(end -0.67945 0.3048)
			(stroke
				(width 0.1)
				(type default)
			)
			(layer "F.Fab")
		)
		(fp_line
			(start -0.67945 0.3048)
			(end -0.67945 -0.305054)
			(stroke
				(width 0.1)
				(type default)
			)
			(layer "F.Fab")
		)
		(pad "1" smd circle
			(at -0.40005 0 90)
			(size 0 0)
			(layers "F.Cu" "F.Mask" "F.Paste")
			(net "FM_PVCCFA_EHV_FIVRA_CPU0_R_EN")
		)
		(pad "2" smd circle
			(at 0.40005 0 90)
			(size 0 0)
			(layers "F.Cu" "F.Mask" "F.Paste")
			(net "FM_PVCCFA_EHV_FIVRA_CPU0_EN")
		)
	)
	(footprint ""
		(layer "F.Cu")
		(at 449.350638 -335.460594 -90)
		(property "Reference" "R1838"
			(at 0 0 270)
			(layer "F.SilkS")
			(hide yes)
			(effects
				(font
					(size 1.27 1.27)
				)
			)
		)
		(property "Value" ""
			(at 0 0 270)
			(layer "F.Fab")
			(effects
				(font
					(size 1.27 1.27)
				)
			)
		)
		(duplicate_pad_numbers_are_jumpers no)
		(fp_line
			(start -4.0386 1.7526)
			(end -4.0386 -1.7526)
			(stroke
				(width 0.1524)
				(type default)
			)
			(layer "F.SilkS")
		)
		(fp_line
			(start 4.0386 1.7526)
			(end -4.0386 1.7526)
			(stroke
				(width 0.1524)
				(type default)
			)
			(layer "F.SilkS")
		)
		(fp_line
			(start -4.0386 -1.7526)
			(end 4.0386 -1.7526)
			(stroke
				(width 0.1524)
				(type default)
			)
			(layer "F.SilkS")
		)
		(fp_line
			(start 4.0386 -1.7526)
			(end 4.0386 1.7526)
			(stroke
				(width 0.1524)
				(type default)
			)
			(layer "F.SilkS")
		)
		(fp_line
			(start -4.0386 1.7526)
			(end -4.0386 -1.7526)
			(stroke
				(width 0.1)
				(type default)
			)
			(layer "F.Fab")
		)
		(fp_line
			(start 4.0386 1.7526)
			(end -4.0386 1.7526)
			(stroke
				(width 0.1)
				(type default)
			)
			(layer "F.Fab")
		)
		(fp_line
			(start -4.0386 -1.7526)
			(end 4.0386 -1.7526)
			(stroke
				(width 0.1)
				(type default)
			)
			(layer "F.Fab")
		)
		(fp_line
			(start 4.0386 -1.7526)
			(end 4.0386 1.7526)
			(stroke
				(width 0.1)
				(type default)
			)
			(layer "F.Fab")
		)
		(pad "1" smd circle
			(at -3.700018 0 180)
			(size 0 0)
			(layers "F.Cu" "F.Mask" "F.Paste")
			(net "P12V_AUX")
		)
		(pad "2" smd circle
			(at 3.700018 0)
			(size 0 0)
			(layers "F.Cu" "F.Mask" "F.Paste")
			(net "P12V_S3_AUX_CPU0_NVDIMM")
		)
		(pad "3" smd rect
			(at -2.70002 0)
			(size 0.4064 1.1176)
			(layers "F.Cu" "F.Mask" "F.Paste")
			(net "P12V_AUX_CPU0_DIMM_ISEN_P")
		)
		(pad "4" smd rect
			(at 2.70002 0)
			(size 0.4064 1.1176)
			(layers "F.Cu" "F.Mask" "F.Paste")
			(net "P12V_AUX_CPU0_DIMM_ISEN_N")
		)
	)
	(footprint ""
		(layer "F.Cu")
		(at 496.64493 -470.91219)
		(property "Reference" "U2_BL"
			(at 0.11049 -3.433318 0)
			(unlocked yes)
			(layer "F.SilkS")
			(effects
				(font
					(size 0.7874 0.5842)
					(thickness 0.1524)
				)
				(justify left)
			)
		)
		(property "Value" ""
			(at 0 0 0)
			(layer "F.Fab")
			(effects
				(font
					(size 1.27 1.27)
				)
			)
		)
		(duplicate_pad_numbers_are_jumpers no)
		(pad "1" smd circle
			(at 0 0)
			(size 0.762 0.762)
			(layers "F.Cu" "F.Mask" "F.Paste")
			(net "Net_8485")
		)
	)
	(footprint ""
		(layer "F.Cu")
		(at 49.648618 -178.060604 90)
		(property "Reference" "PC429"
			(at 0 0 90)
			(layer "F.SilkS")
			(hide yes)
			(effects
				(font
					(size 1.27 1.27)
				)
			)
		)
		(property "Value" ""
			(at 0 0 90)
			(layer "F.Fab")
			(effects
				(font
					(size 1.27 1.27)
				)
			)
		)
		(duplicate_pad_numbers_are_jumpers no)
		(fp_line
			(start 0.7874 -0.4064)
			(end 0.7874 0.4064)
			(stroke
				(width 0.1524)
				(type default)
			)
			(layer "F.SilkS")
		)
		(fp_line
			(start -0.7874 -0.4064)
			(end 0.7874 -0.4064)
			(stroke
				(width 0.1524)
				(type default)
			)
			(layer "F.SilkS")
		)
		(fp_line
			(start 0.7874 0.4064)
			(end -0.7874 0.4064)
			(stroke
				(width 0.1524)
				(type default)
			)
			(layer "F.SilkS")
		)
		(fp_line
			(start -0.7874 0.4064)
			(end -0.7874 -0.4064)
			(stroke
				(width 0.1524)
				(type default)
			)
			(layer "F.SilkS")
		)
		(fp_line
			(start -0.12065 -0.305054)
			(end -0.12065 -0.2794)
			(stroke
				(width 0.1)
				(type default)
			)
			(layer "F.Fab")
		)
		(fp_line
			(start -0.67945 -0.305054)
			(end -0.12065 -0.305054)
			(stroke
				(width 0.1)
				(type default)
			)
			(layer "F.Fab")
		)
		(fp_line
			(start 0.67945 -0.3048)
			(end 0.67945 0.3048)
			(stroke
				(width 0.1)
				(type default)
			)
			(layer "F.Fab")
		)
		(fp_line
			(start 0.12065 -0.3048)
			(end 0.67945 -0.3048)
			(stroke
				(width 0.1)
				(type default)
			)
			(layer "F.Fab")
		)
		(fp_line
			(start 0.12065 -0.2794)
			(end 0.12065 -0.3048)
			(stroke
				(width 0.1)
				(type default)
			)
			(layer "F.Fab")
		)
		(fp_line
			(start -0.12065 -0.2794)
			(end 0.12065 -0.2794)
			(stroke
				(width 0.1)
				(type default)
			)
			(layer "F.Fab")
		)
		(fp_line
			(start 0.120396 0.2794)
			(end -0.12065 0.2794)
			(stroke
				(width 0.1)
				(type default)
			)
			(layer "F.Fab")
		)
		(fp_line
			(start -0.12065 0.2794)
			(end -0.12065 0.3048)
			(stroke
				(width 0.1)
				(type default)
			)
			(layer "F.Fab")
		)
		(fp_line
			(start 0.67945 0.3048)
			(end 0.120396 0.3048)
			(stroke
				(width 0.1)
				(type default)
			)
			(layer "F.Fab")
		)
		(fp_line
			(start 0.120396 0.3048)
			(end 0.120396 0.2794)
			(stroke
				(width 0.1)
				(type default)
			)
			(layer "F.Fab")
		)
		(fp_line
			(start -0.12065 0.3048)
			(end -0.67945 0.3048)
			(stroke
				(width 0.1)
				(type default)
			)
			(layer "F.Fab")
		)
		(fp_line
			(start -0.67945 0.3048)
			(end -0.67945 -0.305054)
			(stroke
				(width 0.1)
				(type default)
			)
			(layer "F.Fab")
		)
		(pad "1" smd circle
			(at -0.40005 0 90)
			(size 0 0)
			(layers "F.Cu" "F.Mask" "F.Paste")
			(net "SW_P12V_PVCCINFAON_CPU1_FLT")
		)
		(pad "2" smd circle
			(at 0.40005 0 90)
			(size 0 0)
			(layers "F.Cu" "F.Mask" "F.Paste")
			(net "GND")
		)
	)
	(footprint ""
		(layer "F.Cu")
		(at 152.70988 -105.755948 180)
		(property "Reference" "R3234"
			(at 0 0 180)
			(layer "F.SilkS")
			(hide yes)
			(effects
				(font
					(size 1.27 1.27)
				)
			)
		)
		(property "Value" ""
			(at 0 0 180)
			(layer "F.Fab")
			(effects
				(font
					(size 1.27 1.27)
				)
			)
		)
		(duplicate_pad_numbers_are_jumpers no)
		(fp_line
			(start 0.7874 0.4064)
			(end -0.7874 0.4064)
			(stroke
				(width 0.1524)
				(type default)
			)
			(layer "F.SilkS")
		)
		(fp_line
			(start 0.7874 -0.4064)
			(end 0.7874 0.4064)
			(stroke
				(width 0.1524)
				(type default)
			)
			(layer "F.SilkS")
		)
		(fp_line
			(start -0.7874 0.4064)
			(end -0.7874 -0.4064)
			(stroke
				(width 0.1524)
				(type default)
			)
			(layer "F.SilkS")
		)
		(fp_line
			(start -0.7874 -0.4064)
			(end 0.7874 -0.4064)
			(stroke
				(width 0.1524)
				(type default)
			)
			(layer "F.SilkS")
		)
		(fp_line
			(start 0.67945 0.3048)
			(end 0.120396 0.3048)
			(stroke
				(width 0.1)
				(type default)
			)
			(layer "F.Fab")
		)
		(fp_line
			(start 0.67945 -0.3048)
			(end 0.67945 0.3048)
			(stroke
				(width 0.1)
				(type default)
			)
			(layer "F.Fab")
		)
		(fp_line
			(start 0.12065 -0.2794)
			(end 0.12065 -0.3048)
			(stroke
				(width 0.1)
				(type default)
			)
			(layer "F.Fab")
		)
		(fp_line
			(start 0.12065 -0.3048)
			(end 0.67945 -0.3048)
			(stroke
				(width 0.1)
				(type default)
			)
			(layer "F.Fab")
		)
		(fp_line
			(start 0.120396 0.3048)
			(end 0.120396 0.2794)
			(stroke
				(width 0.1)
				(type default)
			)
			(layer "F.Fab")
		)
		(fp_line
			(start 0.120396 0.2794)
			(end -0.12065 0.2794)
			(stroke
				(width 0.1)
				(type default)
			)
			(layer "F.Fab")
		)
		(fp_line
			(start -0.12065 0.3048)
			(end -0.67945 0.3048)
			(stroke
				(width 0.1)
				(type default)
			)
			(layer "F.Fab")
		)
		(fp_line
			(start -0.12065 0.2794)
			(end -0.12065 0.3048)
			(stroke
				(width 0.1)
				(type default)
			)
			(layer "F.Fab")
		)
		(fp_line
			(start -0.12065 -0.2794)
			(end 0.12065 -0.2794)
			(stroke
				(width 0.1)
				(type default)
			)
			(layer "F.Fab")
		)
		(fp_line
			(start -0.12065 -0.305054)
			(end -0.12065 -0.2794)
			(stroke
				(width 0.1)
				(type default)
			)
			(layer "F.Fab")
		)
		(fp_line
			(start -0.67945 0.3048)
			(end -0.67945 -0.305054)
			(stroke
				(width 0.1)
				(type default)
			)
			(layer "F.Fab")
		)
		(fp_line
			(start -0.67945 -0.305054)
			(end -0.12065 -0.305054)
			(stroke
				(width 0.1)
				(type default)
			)
			(layer "F.Fab")
		)
		(pad "1" smd circle
			(at -0.40005 0 180)
			(size 0 0)
			(layers "F.Cu" "F.Mask" "F.Paste")
			(net "OCP_V3_2_AUX_PWR_EN")
		)
		(pad "2" smd circle
			(at 0.40005 0 180)
			(size 0 0)
			(layers "F.Cu" "F.Mask" "F.Paste")
			(net "OCP_V3_2_AUX_PWR_EN_R3")
		)
	)
	(footprint ""
		(layer "F.Cu")
		(at 327.29678 -34.201608 45)
		(property "Reference" "R1721"
			(at 0 0 45)
			(layer "F.SilkS")
			(hide yes)
			(effects
				(font
					(size 1.27 1.27)
				)
			)
		)
		(property "Value" ""
			(at 0 0 45)
			(layer "F.Fab")
			(effects
				(font
					(size 1.27 1.27)
				)
			)
		)
		(duplicate_pad_numbers_are_jumpers no)
		(fp_line
			(start -0.787389 -0.406267)
			(end 0.787389 -0.406267)
			(stroke
				(width 0.1524)
				(type default)
			)
			(layer "F.SilkS")
		)
		(fp_line
			(start -0.787389 0.406267)
			(end -0.787389 -0.406267)
			(stroke
				(width 0.1524)
				(type default)
			)
			(layer "F.SilkS")
		)
		(fp_line
			(start 0.787389 -0.406267)
			(end 0.787389 0.406267)
			(stroke
				(width 0.1524)
				(type default)
			)
			(layer "F.SilkS")
		)
		(fp_line
			(start 0.787389 0.406267)
			(end -0.787389 0.406267)
			(stroke
				(width 0.1524)
				(type default)
			)
			(layer "F.SilkS")
		)
		(fp_line
			(start -0.679446 -0.305149)
			(end -0.120695 -0.304969)
			(stroke
				(width 0.1)
				(type default)
			)
			(layer "F.Fab")
		)
		(fp_line
			(start -0.120695 -0.304969)
			(end -0.120695 -0.279466)
			(stroke
				(width 0.1)
				(type default)
			)
			(layer "F.Fab")
		)
		(fp_line
			(start -0.120695 -0.279466)
			(end 0.120695 -0.279466)
			(stroke
				(width 0.1)
				(type default)
			)
			(layer "F.Fab")
		)
		(fp_line
			(start -0.679446 0.30479)
			(end -0.679446 -0.305149)
			(stroke
				(width 0.1)
				(type default)
			)
			(layer "F.Fab")
		)
		(fp_line
			(start 0.120515 -0.30479)
			(end 0.679446 -0.30479)
			(stroke
				(width 0.1)
				(type default)
			)
			(layer "F.Fab")
		)
		(fp_line
			(start 0.120695 -0.279466)
			(end 0.120515 -0.30479)
			(stroke
				(width 0.1)
				(type default)
			)
			(layer "F.Fab")
		)
		(fp_line
			(start -0.120695 0.279466)
			(end -0.120515 0.30479)
			(stroke
				(width 0.1)
				(type default)
			)
			(layer "F.Fab")
		)
		(fp_line
			(start -0.120515 0.30479)
			(end -0.679446 0.30479)
			(stroke
				(width 0.1)
				(type default)
			)
			(layer "F.Fab")
		)
		(fp_line
			(start 0.679446 -0.30479)
			(end 0.679446 0.30479)
			(stroke
				(width 0.1)
				(type default)
			)
			(layer "F.Fab")
		)
		(fp_line
			(start 0.120335 0.279466)
			(end -0.120695 0.279466)
			(stroke
				(width 0.1)
				(type default)
			)
			(layer "F.Fab")
		)
		(fp_line
			(start 0.120515 0.30479)
			(end 0.120335 0.279466)
			(stroke
				(width 0.1)
				(type default)
			)
			(layer "F.Fab")
		)
		(fp_line
			(start 0.679446 0.30479)
			(end 0.120515 0.30479)
			(stroke
				(width 0.1)
				(type default)
			)
			(layer "F.Fab")
		)
		(pad "1" smd circle
			(at -0.40005 0 45)
			(size 0 0)
			(layers "F.Cu" "F.Mask" "F.Paste")
			(net "XTAL_PCH_RTC2_R")
		)
		(pad "2" smd circle
			(at 0.40005 0 45)
			(size 0 0)
			(layers "F.Cu" "F.Mask" "F.Paste")
			(net "XTAL_PCH_RTC2")
		)
	)
	(footprint ""
		(layer "F.Cu")
		(at 26.97988 -428.081948)
		(property "Reference" "U252"
			(at -2.56286 1.98247 0)
			(unlocked yes)
			(layer "F.SilkS")
			(effects
				(font
					(size 0.7874 0.5842)
					(thickness 0.1524)
				)
				(justify left)
			)
		)
		(property "Value" ""
			(at 0 0 0)
			(layer "F.Fab")
			(effects
				(font
					(size 1.27 1.27)
				)
			)
		)
		(duplicate_pad_numbers_are_jumpers no)
		(fp_line
			(start -1.3462 -1.100074)
			(end -0.670052 -1.100074)
			(stroke
				(width 0.1524)
				(type default)
			)
			(layer "F.SilkS")
		)
		(fp_line
			(start -1.3462 1.100074)
			(end -1.3462 -1.100074)
			(stroke
				(width 0.1524)
				(type default)
			)
			(layer "F.SilkS")
		)
		(fp_line
			(start -0.670052 -1.100074)
			(end 0 -0.381)
			(stroke
				(width 0.1524)
				(type default)
			)
			(layer "F.SilkS")
		)
		(fp_line
			(start 0 -0.381)
			(end 0.670052 -1.100074)
			(stroke
				(width 0.1524)
				(type default)
			)
			(layer "F.SilkS")
		)
		(fp_line
			(start 0.670052 -1.100074)
			(end 1.3462 -1.100074)
			(stroke
				(width 0.1524)
				(type default)
			)
			(layer "F.SilkS")
		)
		(fp_line
			(start 1.3462 -1.100074)
			(end 1.3462 1.100074)
			(stroke
				(width 0.1524)
				(type default)
			)
			(layer "F.SilkS")
		)
		(fp_line
			(start 1.3462 1.100074)
			(end -1.3462 1.100074)
			(stroke
				(width 0.1524)
				(type default)
			)
			(layer "F.SilkS")
		)
		(fp_poly
			(pts
				(xy -2.0574 -0.634746) (xy -2.8194 -0.253746) (xy -2.8194 -1.015746)
			)
			(stroke
				(width 0)
				(type default)
			)
			(fill yes)
			(layer "F.SilkS")
		)
		(fp_line
			(start -1.100074 -0.8001)
			(end -0.670052 -0.8001)
			(stroke
				(width 0.1)
				(type default)
			)
			(layer "F.Fab")
		)
		(fp_line
			(start -1.100074 0.8001)
			(end -1.100074 -0.8001)
			(stroke
				(width 0.1)
				(type default)
			)
			(layer "F.Fab")
		)
		(fp_line
			(start -0.670052 -1.100074)
			(end 0.670052 -1.100074)
			(stroke
				(width 0.1)
				(type default)
			)
			(layer "F.Fab")
		)
		(fp_line
			(start -0.670052 -0.8001)
			(end -0.670052 -1.100074)
			(stroke
				(width 0.1)
				(type default)
			)
			(layer "F.Fab")
		)
		(fp_line
			(start -0.670052 0.8001)
			(end -1.100074 0.8001)
			(stroke
				(width 0.1)
				(type default)
			)
			(layer "F.Fab")
		)
		(fp_line
			(start -0.670052 0.8001)
			(end -0.670052 -0.8001)
			(stroke
				(width 0.1)
				(type default)
			)
			(layer "F.Fab")
		)
		(fp_line
			(start -0.670052 1.100074)
			(end -0.670052 0.8001)
			(stroke
				(width 0.1)
				(type default)
			)
			(layer "F.Fab")
		)
		(fp_line
			(start 0.670052 -1.100074)
			(end 0.670052 -0.8001)
			(stroke
				(width 0.1)
				(type default)
			)
			(layer "F.Fab")
		)
		(fp_line
			(start 0.670052 -0.8001)
			(end 0.670052 0.8001)
			(stroke
				(width 0.1)
				(type default)
			)
			(layer "F.Fab")
		)
		(fp_line
			(start 0.670052 -0.8001)
			(end 1.100074 -0.8001)
			(stroke
				(width 0.1)
				(type default)
			)
			(layer "F.Fab")
		)
		(fp_line
			(start 0.670052 0.8001)
			(end 0.670052 1.100074)
			(stroke
				(width 0.1)
				(type default)
			)
			(layer "F.Fab")
		)
		(fp_line
			(start 0.670052 1.100074)
			(end -0.670052 1.100074)
			(stroke
				(width 0.1)
				(type default)
			)
			(layer "F.Fab")
		)
		(fp_line
			(start 1.100074 -0.8001)
			(end 1.100074 0.8001)
			(stroke
				(width 0.1)
				(type default)
			)
			(layer "F.Fab")
		)
		(fp_line
			(start 1.100074 0.8001)
			(end 0.670052 0.8001)
			(stroke
				(width 0.1)
				(type default)
			)
			(layer "F.Fab")
		)
		(fp_poly
			(pts
				(xy -1.524 -0.649986) (xy -2.286 -1.030986) (xy -2.286 -0.268986)
			)
			(stroke
				(width 0)
				(type default)
			)
			(fill yes)
			(layer "F.Fab")
		)
		(pad "1" smd rect
			(at -0.94996 -0.649986 270)
			(size 0.4064 0.508)
			(layers "F.Cu" "F.Mask" "F.Paste")
			(net "RST_PERST_SWB_R_N")
		)
		(pad "2" smd rect
			(at -0.94996 0 270)
			(size 0.4064 0.508)
			(layers "F.Cu" "F.Mask" "F.Paste")
			(net "GND")
		)
		(pad "3" smd rect
			(at -0.94996 0.649986 270)
			(size 0.4064 0.508)
			(layers "F.Cu" "F.Mask" "F.Paste")
			(net "RST_PERST_SWB_R_N")
		)
		(pad "4" smd rect
			(at 0.94996 0.649986 270)
			(size 0.4064 0.508)
			(layers "F.Cu" "F.Mask" "F.Paste")
			(net "RST_PERST_1_SWB_BUF_R_N")
		)
		(pad "5" smd rect
			(at 0.94996 0 270)
			(size 0.4064 0.508)
			(layers "F.Cu" "F.Mask" "F.Paste")
			(net "P3V3_AUX")
		)
		(pad "6" smd rect
			(at 0.94996 -0.649986 270)
			(size 0.4064 0.508)
			(layers "F.Cu" "F.Mask" "F.Paste")
			(net "RST_PERST_0_SWB_BUF_R_N")
		)
	)
	(footprint ""
		(layer "F.Cu")
		(at 209.4992 -111.4298 -90)
		(property "Reference" "U338"
			(at -4.24053 1.8542 0)
			(unlocked yes)
			(layer "F.SilkS")
			(effects
				(font
					(size 0.7874 0.5842)
					(thickness 0.1524)
				)
				(justify left)
			)
		)
		(property "Value" ""
			(at 0 0 270)
			(layer "F.Fab")
			(effects
				(font
					(size 1.27 1.27)
				)
			)
		)
		(duplicate_pad_numbers_are_jumpers no)
		(fp_line
			(start -1.868424 1.519936)
			(end 1.868424 1.519936)
			(stroke
				(width 0.1524)
				(type default)
			)
			(layer "F.SilkS")
		)
		(fp_line
			(start 1.868424 1.519936)
			(end 1.868424 -1.519936)
			(stroke
				(width 0.1524)
				(type default)
			)
			(layer "F.SilkS")
		)
		(fp_line
			(start -1.868424 -1.519936)
			(end -1.868424 1.519936)
			(stroke
				(width 0.1524)
				(type default)
			)
			(layer "F.SilkS")
		)
		(fp_line
			(start 1.868424 -1.519936)
			(end -1.868424 -1.519936)
			(stroke
				(width 0.1524)
				(type default)
			)
			(layer "F.SilkS")
		)
		(fp_line
			(start -0.700024 1.519936)
			(end 0.700024 1.519936)
			(stroke
				(width 0.1)
				(type default)
			)
			(layer "F.Fab")
		)
		(fp_line
			(start 0.700024 1.519936)
			(end 0.700024 -1.519936)
			(stroke
				(width 0.1)
				(type default)
			)
			(layer "F.Fab")
		)
		(fp_line
			(start -0.700024 -1.519936)
			(end -0.700024 1.519936)
			(stroke
				(width 0.1)
				(type default)
			)
			(layer "F.Fab")
		)
		(fp_line
			(start 0.700024 -1.519936)
			(end -0.700024 -1.519936)
			(stroke
				(width 0.1)
				(type default)
			)
			(layer "F.Fab")
		)
		(pad "1" smd rect
			(at -1.18491 -0.94996 180)
			(size 0.6096 1.0668)
			(layers "F.Cu" "F.Mask" "F.Paste")
			(net "UV_P2V5_COMP")
		)
		(pad "2" smd rect
			(at -1.18491 0.94996 180)
			(size 0.6096 1.0668)
			(layers "F.Cu" "F.Mask" "F.Paste")
			(net "GND")
		)
		(pad "3" smd rect
			(at 1.18491 0 180)
			(size 0.6096 1.0668)
			(layers "F.Cu" "F.Mask" "F.Paste")
			(net "Net_8627")
		)
	)
	(footprint ""
		(layer "F.Cu")
		(at 205.968092 -104.715056)
		(property "Reference" "Q35"
			(at -1.651 -2.25933 0)
			(unlocked yes)
			(layer "F.SilkS")
			(effects
				(font
					(size 0.7874 0.5842)
					(thickness 0.1524)
				)
				(justify left)
			)
		)
		(property "Value" ""
			(at 0 0 0)
			(layer "F.Fab")
			(effects
				(font
					(size 1.27 1.27)
				)
			)
		)
		(duplicate_pad_numbers_are_jumpers no)
		(fp_line
			(start -1.603248 -1.500124)
			(end 1.603248 -1.500124)
			(stroke
				(width 0.1524)
				(type default)
			)
			(layer "F.SilkS")
		)
		(fp_line
			(start -1.603248 1.500124)
			(end -1.603248 -1.500124)
			(stroke
				(width 0.1524)
				(type default)
			)
			(layer "F.SilkS")
		)
		(fp_line
			(start 1.603248 -1.500124)
			(end 1.603248 1.500124)
			(stroke
				(width 0.1524)
				(type default)
			)
			(layer "F.SilkS")
		)
		(fp_line
			(start 1.603248 1.500124)
			(end -1.603248 1.500124)
			(stroke
				(width 0.1524)
				(type default)
			)
			(layer "F.SilkS")
		)
		(fp_line
			(start -1.249934 -1.169924)
			(end -1.249934 -0.729996)
			(stroke
				(width 0.1)
				(type default)
			)
			(layer "F.Fab")
		)
		(fp_line
			(start -1.249934 -0.729996)
			(end -0.6985 -0.729996)
			(stroke
				(width 0.1)
				(type default)
			)
			(layer "F.Fab")
		)
		(fp_line
			(start -1.249934 0.729996)
			(end -1.249934 1.169924)
			(stroke
				(width 0.1)
				(type default)
			)
			(layer "F.Fab")
		)
		(fp_line
			(start -1.249934 1.169924)
			(end -0.700024 1.169924)
			(stroke
				(width 0.1)
				(type default)
			)
			(layer "F.Fab")
		)
		(fp_line
			(start -0.700024 -1.500124)
			(end -0.700024 -1.169924)
			(stroke
				(width 0.1)
				(type default)
			)
			(layer "F.Fab")
		)
		(fp_line
			(start -0.700024 -1.169924)
			(end -1.249934 -1.169924)
			(stroke
				(width 0.1)
				(type default)
			)
			(layer "F.Fab")
		)
		(fp_line
			(start -0.700024 1.169924)
			(end -0.700024 1.500124)
			(stroke
				(width 0.1)
				(type default)
			)
			(layer "F.Fab")
		)
		(fp_line
			(start -0.700024 1.500124)
			(end 0.700024 1.500124)
			(stroke
				(width 0.1)
				(type default)
			)
			(layer "F.Fab")
		)
		(fp_line
			(start -0.6985 -0.729996)
			(end -0.6985 0.729996)
			(stroke
				(width 0.1)
				(type default)
			)
			(layer "F.Fab")
		)
		(fp_line
			(start -0.6985 0.729996)
			(end -1.249934 0.729996)
			(stroke
				(width 0.1)
				(type default)
			)
			(layer "F.Fab")
		)
		(fp_line
			(start 0.700024 -1.500124)
			(end -0.700024 -1.500124)
			(stroke
				(width 0.1)
				(type default)
			)
			(layer "F.Fab")
		)
		(fp_line
			(start 0.700024 -0.219964)
			(end 0.700024 -1.500124)
			(stroke
				(width 0.1)
				(type default)
			)
			(layer "F.Fab")
		)
		(fp_line
			(start 0.700024 0.219964)
			(end 1.249934 0.219964)
			(stroke
				(width 0.1)
				(type default)
			)
			(layer "F.Fab")
		)
		(fp_line
			(start 0.700024 1.500124)
			(end 0.700024 0.219964)
			(stroke
				(width 0.1)
				(type default)
			)
			(layer "F.Fab")
		)
		(fp_line
			(start 1.249934 -0.219964)
			(end 0.700024 -0.219964)
			(stroke
				(width 0.1)
				(type default)
			)
			(layer "F.Fab")
		)
		(fp_line
			(start 1.249934 0.219964)
			(end 1.249934 -0.219964)
			(stroke
				(width 0.1)
				(type default)
			)
			(layer "F.Fab")
		)
		(fp_rect
			(start -0.700024 1.500124)
			(end 0.700024 -1.500124)
			(stroke
				(width 0)
				(type default)
			)
			(fill no)
			(layer "F.Fab")
		)
		(pad "D" smd rect
			(at 0.999998 0 270)
			(size 0.8128 0.9144)
			(layers "F.Cu" "F.Mask" "F.Paste")
			(net "RST_SRTCRST_N")
		)
		(pad "G" smd rect
			(at -0.999998 -0.94996 270)
			(size 0.8128 0.9144)
			(layers "F.Cu" "F.Mask" "F.Paste")
			(net "RST_PFR_OVR_SRTC")
		)
		(pad "S" smd rect
			(at -0.999998 0.94996 270)
			(size 0.8128 0.9144)
			(layers "F.Cu" "F.Mask" "F.Paste")
			(net "GND")
		)
	)
	(footprint ""
		(layer "F.Cu")
		(at 120.0912 -415.276538 180)
		(property "Reference" "R4481"
			(at 0 0 180)
			(layer "F.SilkS")
			(hide yes)
			(effects
				(font
					(size 1.27 1.27)
				)
			)
		)
		(property "Value" ""
			(at 0 0 180)
			(layer "F.Fab")
			(effects
				(font
					(size 1.27 1.27)
				)
			)
		)
		(duplicate_pad_numbers_are_jumpers no)
		(fp_line
			(start 0.7874 0.4064)
			(end -0.7874 0.4064)
			(stroke
				(width 0.1524)
				(type default)
			)
			(layer "F.SilkS")
		)
		(fp_line
			(start 0.7874 -0.4064)
			(end 0.7874 0.4064)
			(stroke
				(width 0.1524)
				(type default)
			)
			(layer "F.SilkS")
		)
		(fp_line
			(start -0.7874 0.4064)
			(end -0.7874 -0.4064)
			(stroke
				(width 0.1524)
				(type default)
			)
			(layer "F.SilkS")
		)
		(fp_line
			(start -0.7874 -0.4064)
			(end 0.7874 -0.4064)
			(stroke
				(width 0.1524)
				(type default)
			)
			(layer "F.SilkS")
		)
		(fp_line
			(start 0.67945 0.3048)
			(end 0.120396 0.3048)
			(stroke
				(width 0.1)
				(type default)
			)
			(layer "F.Fab")
		)
		(fp_line
			(start 0.67945 -0.3048)
			(end 0.67945 0.3048)
			(stroke
				(width 0.1)
				(type default)
			)
			(layer "F.Fab")
		)
		(fp_line
			(start 0.12065 -0.2794)
			(end 0.12065 -0.3048)
			(stroke
				(width 0.1)
				(type default)
			)
			(layer "F.Fab")
		)
		(fp_line
			(start 0.12065 -0.3048)
			(end 0.67945 -0.3048)
			(stroke
				(width 0.1)
				(type default)
			)
			(layer "F.Fab")
		)
		(fp_line
			(start 0.120396 0.3048)
			(end 0.120396 0.2794)
			(stroke
				(width 0.1)
				(type default)
			)
			(layer "F.Fab")
		)
		(fp_line
			(start 0.120396 0.2794)
			(end -0.12065 0.2794)
			(stroke
				(width 0.1)
				(type default)
			)
			(layer "F.Fab")
		)
		(fp_line
			(start -0.12065 0.3048)
			(end -0.67945 0.3048)
			(stroke
				(width 0.1)
				(type default)
			)
			(layer "F.Fab")
		)
		(fp_line
			(start -0.12065 0.2794)
			(end -0.12065 0.3048)
			(stroke
				(width 0.1)
				(type default)
			)
			(layer "F.Fab")
		)
		(fp_line
			(start -0.12065 -0.2794)
			(end 0.12065 -0.2794)
			(stroke
				(width 0.1)
				(type default)
			)
			(layer "F.Fab")
		)
		(fp_line
			(start -0.12065 -0.305054)
			(end -0.12065 -0.2794)
			(stroke
				(width 0.1)
				(type default)
			)
			(layer "F.Fab")
		)
		(fp_line
			(start -0.67945 0.3048)
			(end -0.67945 -0.305054)
			(stroke
				(width 0.1)
				(type default)
			)
			(layer "F.Fab")
		)
		(fp_line
			(start -0.67945 -0.305054)
			(end -0.12065 -0.305054)
			(stroke
				(width 0.1)
				(type default)
			)
			(layer "F.Fab")
		)
		(pad "1" smd circle
			(at -0.40005 0 180)
			(size 0 0)
			(layers "F.Cu" "F.Mask" "F.Paste")
			(net "SMB_HOST_CLK_BUF_ISO_3V3AUX_SDA")
		)
		(pad "2" smd circle
			(at 0.40005 0 180)
			(size 0 0)
			(layers "F.Cu" "F.Mask" "F.Paste")
			(net "SMB_HOST_9ZXL045_3V3AUX_SDA")
		)
	)
	(footprint ""
		(layer "F.Cu")
		(at 447.589402 -77.829918 90)
		(property "Reference" "PR830"
			(at 0 0 90)
			(layer "F.SilkS")
			(hide yes)
			(effects
				(font
					(size 1.27 1.27)
				)
			)
		)
		(property "Value" ""
			(at 0 0 90)
			(layer "F.Fab")
			(effects
				(font
					(size 1.27 1.27)
				)
			)
		)
		(duplicate_pad_numbers_are_jumpers no)
		(fp_line
			(start 0.7874 -0.4064)
			(end 0.7874 0.4064)
			(stroke
				(width 0.1524)
				(type default)
			)
			(layer "F.SilkS")
		)
		(fp_line
			(start -0.7874 -0.4064)
			(end 0.7874 -0.4064)
			(stroke
				(width 0.1524)
				(type default)
			)
			(layer "F.SilkS")
		)
		(fp_line
			(start 0.7874 0.4064)
			(end -0.7874 0.4064)
			(stroke
				(width 0.1524)
				(type default)
			)
			(layer "F.SilkS")
		)
		(fp_line
			(start -0.7874 0.4064)
			(end -0.7874 -0.4064)
			(stroke
				(width 0.1524)
				(type default)
			)
			(layer "F.SilkS")
		)
		(fp_line
			(start -0.12065 -0.305054)
			(end -0.12065 -0.2794)
			(stroke
				(width 0.1)
				(type default)
			)
			(layer "F.Fab")
		)
		(fp_line
			(start -0.67945 -0.305054)
			(end -0.12065 -0.305054)
			(stroke
				(width 0.1)
				(type default)
			)
			(layer "F.Fab")
		)
		(fp_line
			(start 0.67945 -0.3048)
			(end 0.67945 0.3048)
			(stroke
				(width 0.1)
				(type default)
			)
			(layer "F.Fab")
		)
		(fp_line
			(start 0.12065 -0.3048)
			(end 0.67945 -0.3048)
			(stroke
				(width 0.1)
				(type default)
			)
			(layer "F.Fab")
		)
		(fp_line
			(start 0.12065 -0.2794)
			(end 0.12065 -0.3048)
			(stroke
				(width 0.1)
				(type default)
			)
			(layer "F.Fab")
		)
		(fp_line
			(start -0.12065 -0.2794)
			(end 0.12065 -0.2794)
			(stroke
				(width 0.1)
				(type default)
			)
			(layer "F.Fab")
		)
		(fp_line
			(start 0.120396 0.2794)
			(end -0.12065 0.2794)
			(stroke
				(width 0.1)
				(type default)
			)
			(layer "F.Fab")
		)
		(fp_line
			(start -0.12065 0.2794)
			(end -0.12065 0.3048)
			(stroke
				(width 0.1)
				(type default)
			)
			(layer "F.Fab")
		)
		(fp_line
			(start 0.67945 0.3048)
			(end 0.120396 0.3048)
			(stroke
				(width 0.1)
				(type default)
			)
			(layer "F.Fab")
		)
		(fp_line
			(start 0.120396 0.3048)
			(end 0.120396 0.2794)
			(stroke
				(width 0.1)
				(type default)
			)
			(layer "F.Fab")
		)
		(fp_line
			(start -0.12065 0.3048)
			(end -0.67945 0.3048)
			(stroke
				(width 0.1)
				(type default)
			)
			(layer "F.Fab")
		)
		(fp_line
			(start -0.67945 0.3048)
			(end -0.67945 -0.305054)
			(stroke
				(width 0.1)
				(type default)
			)
			(layer "F.Fab")
		)
		(pad "1" smd circle
			(at -0.40005 0 90)
			(size 0 0)
			(layers "F.Cu" "F.Mask" "F.Paste")
			(net "P3V3_AUX_FB")
		)
		(pad "2" smd circle
			(at 0.40005 0 90)
			(size 0 0)
			(layers "F.Cu" "F.Mask" "F.Paste")
			(net "GND")
		)
	)
	(footprint ""
		(layer "F.Cu")
		(at 430.600104 -133.478778)
		(property "Reference" "C3273"
			(at 0 0 0)
			(layer "F.SilkS")
			(hide yes)
			(effects
				(font
					(size 1.27 1.27)
				)
			)
		)
		(property "Value" ""
			(at 0 0 0)
			(layer "F.Fab")
			(effects
				(font
					(size 1.27 1.27)
				)
			)
		)
		(duplicate_pad_numbers_are_jumpers no)
		(fp_line
			(start -0.7874 -0.4064)
			(end 0.7874 -0.4064)
			(stroke
				(width 0.1524)
				(type default)
			)
			(layer "F.SilkS")
		)
		(fp_line
			(start -0.7874 0.4064)
			(end -0.7874 -0.4064)
			(stroke
				(width 0.1524)
				(type default)
			)
			(layer "F.SilkS")
		)
		(fp_line
			(start 0.7874 -0.4064)
			(end 0.7874 0.4064)
			(stroke
				(width 0.1524)
				(type default)
			)
			(layer "F.SilkS")
		)
		(fp_line
			(start 0.7874 0.4064)
			(end -0.7874 0.4064)
			(stroke
				(width 0.1524)
				(type default)
			)
			(layer "F.SilkS")
		)
		(fp_line
			(start -0.67945 -0.305054)
			(end -0.12065 -0.305054)
			(stroke
				(width 0.1)
				(type default)
			)
			(layer "F.Fab")
		)
		(fp_line
			(start -0.67945 0.3048)
			(end -0.67945 -0.305054)
			(stroke
				(width 0.1)
				(type default)
			)
			(layer "F.Fab")
		)
		(fp_line
			(start -0.12065 -0.305054)
			(end -0.12065 -0.2794)
			(stroke
				(width 0.1)
				(type default)
			)
			(layer "F.Fab")
		)
		(fp_line
			(start -0.12065 -0.2794)
			(end 0.12065 -0.2794)
			(stroke
				(width 0.1)
				(type default)
			)
			(layer "F.Fab")
		)
		(fp_line
			(start -0.12065 0.2794)
			(end -0.12065 0.3048)
			(stroke
				(width 0.1)
				(type default)
			)
			(layer "F.Fab")
		)
		(fp_line
			(start -0.12065 0.3048)
			(end -0.67945 0.3048)
			(stroke
				(width 0.1)
				(type default)
			)
			(layer "F.Fab")
		)
		(fp_line
			(start 0.120396 0.2794)
			(end -0.12065 0.2794)
			(stroke
				(width 0.1)
				(type default)
			)
			(layer "F.Fab")
		)
		(fp_line
			(start 0.120396 0.3048)
			(end 0.120396 0.2794)
			(stroke
				(width 0.1)
				(type default)
			)
			(layer "F.Fab")
		)
		(fp_line
			(start 0.12065 -0.3048)
			(end 0.67945 -0.3048)
			(stroke
				(width 0.1)
				(type default)
			)
			(layer "F.Fab")
		)
		(fp_line
			(start 0.12065 -0.2794)
			(end 0.12065 -0.3048)
			(stroke
				(width 0.1)
				(type default)
			)
			(layer "F.Fab")
		)
		(fp_line
			(start 0.67945 -0.3048)
			(end 0.67945 0.3048)
			(stroke
				(width 0.1)
				(type default)
			)
			(layer "F.Fab")
		)
		(fp_line
			(start 0.67945 0.3048)
			(end 0.120396 0.3048)
			(stroke
				(width 0.1)
				(type default)
			)
			(layer "F.Fab")
		)
		(pad "1" smd circle
			(at -0.40005 0)
			(size 0 0)
			(layers "F.Cu" "F.Mask" "F.Paste")
			(net "PWRGD_PVCCINFAON_CPU0_R")
		)
		(pad "2" smd circle
			(at 0.40005 0)
			(size 0 0)
			(layers "F.Cu" "F.Mask" "F.Paste")
			(net "GND")
		)
	)
	(footprint ""
		(layer "F.Cu")
		(at 123.265184 -338.17814 -90)
		(property "Reference" "PC531"
			(at 0 0 270)
			(layer "F.SilkS")
			(hide yes)
			(effects
				(font
					(size 1.27 1.27)
				)
			)
		)
		(property "Value" ""
			(at 0 0 270)
			(layer "F.Fab")
			(effects
				(font
					(size 1.27 1.27)
				)
			)
		)
		(duplicate_pad_numbers_are_jumpers no)
		(fp_line
			(start -0.7874 0.4064)
			(end -0.7874 -0.4064)
			(stroke
				(width 0.1524)
				(type default)
			)
			(layer "F.SilkS")
		)
		(fp_line
			(start 0.7874 0.4064)
			(end -0.7874 0.4064)
			(stroke
				(width 0.1524)
				(type default)
			)
			(layer "F.SilkS")
		)
		(fp_line
			(start -0.7874 -0.4064)
			(end 0.7874 -0.4064)
			(stroke
				(width 0.1524)
				(type default)
			)
			(layer "F.SilkS")
		)
		(fp_line
			(start 0.7874 -0.4064)
			(end 0.7874 0.4064)
			(stroke
				(width 0.1524)
				(type default)
			)
			(layer "F.SilkS")
		)
		(fp_line
			(start -0.67945 0.3048)
			(end -0.67945 -0.305054)
			(stroke
				(width 0.1)
				(type default)
			)
			(layer "F.Fab")
		)
		(fp_line
			(start -0.12065 0.3048)
			(end -0.67945 0.3048)
			(stroke
				(width 0.1)
				(type default)
			)
			(layer "F.Fab")
		)
		(fp_line
			(start 0.120396 0.3048)
			(end 0.120396 0.2794)
			(stroke
				(width 0.1)
				(type default)
			)
			(layer "F.Fab")
		)
		(fp_line
			(start 0.67945 0.3048)
			(end 0.120396 0.3048)
			(stroke
				(width 0.1)
				(type default)
			)
			(layer "F.Fab")
		)
		(fp_line
			(start -0.12065 0.2794)
			(end -0.12065 0.3048)
			(stroke
				(width 0.1)
				(type default)
			)
			(layer "F.Fab")
		)
		(fp_line
			(start 0.120396 0.2794)
			(end -0.12065 0.2794)
			(stroke
				(width 0.1)
				(type default)
			)
			(layer "F.Fab")
		)
		(fp_line
			(start -0.12065 -0.2794)
			(end 0.12065 -0.2794)
			(stroke
				(width 0.1)
				(type default)
			)
			(layer "F.Fab")
		)
		(fp_line
			(start 0.12065 -0.2794)
			(end 0.12065 -0.3048)
			(stroke
				(width 0.1)
				(type default)
			)
			(layer "F.Fab")
		)
		(fp_line
			(start 0.12065 -0.3048)
			(end 0.67945 -0.3048)
			(stroke
				(width 0.1)
				(type default)
			)
			(layer "F.Fab")
		)
		(fp_line
			(start 0.67945 -0.3048)
			(end 0.67945 0.3048)
			(stroke
				(width 0.1)
				(type default)
			)
			(layer "F.Fab")
		)
		(fp_line
			(start -0.67945 -0.305054)
			(end -0.12065 -0.305054)
			(stroke
				(width 0.1)
				(type default)
			)
			(layer "F.Fab")
		)
		(fp_line
			(start -0.12065 -0.305054)
			(end -0.12065 -0.2794)
			(stroke
				(width 0.1)
				(type default)
			)
			(layer "F.Fab")
		)
		(pad "1" smd circle
			(at -0.40005 0 270)
			(size 0 0)
			(layers "F.Cu" "F.Mask" "F.Paste")
			(net "SW_PVCCIN_CPU1_BOOT4_R")
		)
		(pad "2" smd circle
			(at 0.40005 0 270)
			(size 0 0)
			(layers "F.Cu" "F.Mask" "F.Paste")
			(net "SW_PVCCIN_CPU1_BOOTR4")
		)
	)
	(footprint ""
		(layer "F.Cu")
		(at 183.49849 -358.15778 -90)
		(property "Reference" "PC1197"
			(at 0 0 270)
			(layer "F.SilkS")
			(hide yes)
			(effects
				(font
					(size 1.27 1.27)
				)
			)
		)
		(property "Value" ""
			(at 0 0 270)
			(layer "F.Fab")
			(effects
				(font
					(size 1.27 1.27)
				)
			)
		)
		(duplicate_pad_numbers_are_jumpers no)
		(fp_line
			(start -0.7874 0.4064)
			(end -0.7874 -0.4064)
			(stroke
				(width 0.1524)
				(type default)
			)
			(layer "F.SilkS")
		)
		(fp_line
			(start 0.7874 0.4064)
			(end -0.7874 0.4064)
			(stroke
				(width 0.1524)
				(type default)
			)
			(layer "F.SilkS")
		)
		(fp_line
			(start -0.7874 -0.4064)
			(end 0.7874 -0.4064)
			(stroke
				(width 0.1524)
				(type default)
			)
			(layer "F.SilkS")
		)
		(fp_line
			(start 0.7874 -0.4064)
			(end 0.7874 0.4064)
			(stroke
				(width 0.1524)
				(type default)
			)
			(layer "F.SilkS")
		)
		(fp_line
			(start -0.67945 0.3048)
			(end -0.67945 -0.305054)
			(stroke
				(width 0.1)
				(type default)
			)
			(layer "F.Fab")
		)
		(fp_line
			(start -0.12065 0.3048)
			(end -0.67945 0.3048)
			(stroke
				(width 0.1)
				(type default)
			)
			(layer "F.Fab")
		)
		(fp_line
			(start 0.120396 0.3048)
			(end 0.120396 0.2794)
			(stroke
				(width 0.1)
				(type default)
			)
			(layer "F.Fab")
		)
		(fp_line
			(start 0.67945 0.3048)
			(end 0.120396 0.3048)
			(stroke
				(width 0.1)
				(type default)
			)
			(layer "F.Fab")
		)
		(fp_line
			(start -0.12065 0.2794)
			(end -0.12065 0.3048)
			(stroke
				(width 0.1)
				(type default)
			)
			(layer "F.Fab")
		)
		(fp_line
			(start 0.120396 0.2794)
			(end -0.12065 0.2794)
			(stroke
				(width 0.1)
				(type default)
			)
			(layer "F.Fab")
		)
		(fp_line
			(start -0.12065 -0.2794)
			(end 0.12065 -0.2794)
			(stroke
				(width 0.1)
				(type default)
			)
			(layer "F.Fab")
		)
		(fp_line
			(start 0.12065 -0.2794)
			(end 0.12065 -0.3048)
			(stroke
				(width 0.1)
				(type default)
			)
			(layer "F.Fab")
		)
		(fp_line
			(start 0.12065 -0.3048)
			(end 0.67945 -0.3048)
			(stroke
				(width 0.1)
				(type default)
			)
			(layer "F.Fab")
		)
		(fp_line
			(start 0.67945 -0.3048)
			(end 0.67945 0.3048)
			(stroke
				(width 0.1)
				(type default)
			)
			(layer "F.Fab")
		)
		(fp_line
			(start -0.67945 -0.305054)
			(end -0.12065 -0.305054)
			(stroke
				(width 0.1)
				(type default)
			)
			(layer "F.Fab")
		)
		(fp_line
			(start -0.12065 -0.305054)
			(end -0.12065 -0.2794)
			(stroke
				(width 0.1)
				(type default)
			)
			(layer "F.Fab")
		)
		(pad "1" smd circle
			(at -0.40005 0 270)
			(size 0 0)
			(layers "F.Cu" "F.Mask" "F.Paste")
			(net "SW_PVCCFA_EHV_FIVRA_CPU1_BOOT3_")
		)
		(pad "2" smd circle
			(at 0.40005 0 270)
			(size 0 0)
			(layers "F.Cu" "F.Mask" "F.Paste")
			(net "SW_PVCCFA_EHV_FIVRA_CPU1_BOOTR3")
		)
	)
	(footprint ""
		(layer "F.Cu")
		(at 117.526816 -238.162592 90)
		(property "Reference" "C436"
			(at 0 0 90)
			(layer "F.SilkS")
			(hide yes)
			(effects
				(font
					(size 1.27 1.27)
				)
			)
		)
		(property "Value" ""
			(at 0 0 90)
			(layer "F.Fab")
			(effects
				(font
					(size 1.27 1.27)
				)
			)
		)
		(duplicate_pad_numbers_are_jumpers no)
		(fp_line
			(start 0.7874 -0.4064)
			(end 0.7874 0.4064)
			(stroke
				(width 0.1524)
				(type default)
			)
			(layer "F.SilkS")
		)
		(fp_line
			(start -0.7874 -0.4064)
			(end 0.7874 -0.4064)
			(stroke
				(width 0.1524)
				(type default)
			)
			(layer "F.SilkS")
		)
		(fp_line
			(start 0.7874 0.4064)
			(end -0.7874 0.4064)
			(stroke
				(width 0.1524)
				(type default)
			)
			(layer "F.SilkS")
		)
		(fp_line
			(start -0.7874 0.4064)
			(end -0.7874 -0.4064)
			(stroke
				(width 0.1524)
				(type default)
			)
			(layer "F.SilkS")
		)
		(fp_line
			(start -0.12065 -0.305054)
			(end -0.12065 -0.2794)
			(stroke
				(width 0.1)
				(type default)
			)
			(layer "F.Fab")
		)
		(fp_line
			(start -0.67945 -0.305054)
			(end -0.12065 -0.305054)
			(stroke
				(width 0.1)
				(type default)
			)
			(layer "F.Fab")
		)
		(fp_line
			(start 0.67945 -0.3048)
			(end 0.67945 0.3048)
			(stroke
				(width 0.1)
				(type default)
			)
			(layer "F.Fab")
		)
		(fp_line
			(start 0.12065 -0.3048)
			(end 0.67945 -0.3048)
			(stroke
				(width 0.1)
				(type default)
			)
			(layer "F.Fab")
		)
		(fp_line
			(start 0.12065 -0.2794)
			(end 0.12065 -0.3048)
			(stroke
				(width 0.1)
				(type default)
			)
			(layer "F.Fab")
		)
		(fp_line
			(start -0.12065 -0.2794)
			(end 0.12065 -0.2794)
			(stroke
				(width 0.1)
				(type default)
			)
			(layer "F.Fab")
		)
		(fp_line
			(start 0.120396 0.2794)
			(end -0.12065 0.2794)
			(stroke
				(width 0.1)
				(type default)
			)
			(layer "F.Fab")
		)
		(fp_line
			(start -0.12065 0.2794)
			(end -0.12065 0.3048)
			(stroke
				(width 0.1)
				(type default)
			)
			(layer "F.Fab")
		)
		(fp_line
			(start 0.67945 0.3048)
			(end 0.120396 0.3048)
			(stroke
				(width 0.1)
				(type default)
			)
			(layer "F.Fab")
		)
		(fp_line
			(start 0.120396 0.3048)
			(end 0.120396 0.2794)
			(stroke
				(width 0.1)
				(type default)
			)
			(layer "F.Fab")
		)
		(fp_line
			(start -0.12065 0.3048)
			(end -0.67945 0.3048)
			(stroke
				(width 0.1)
				(type default)
			)
			(layer "F.Fab")
		)
		(fp_line
			(start -0.67945 0.3048)
			(end -0.67945 -0.305054)
			(stroke
				(width 0.1)
				(type default)
			)
			(layer "F.Fab")
		)
		(pad "1" smd circle
			(at -0.40005 0 90)
			(size 0 0)
			(layers "F.Cu" "F.Mask" "F.Paste")
			(net "PVCCINFAON_CPU1")
		)
		(pad "2" smd circle
			(at 0.40005 0 90)
			(size 0 0)
			(layers "F.Cu" "F.Mask" "F.Paste")
			(net "GND")
		)
	)
	(footprint ""
		(layer "F.Cu")
		(at 50.215038 -408.517344 -90)
		(property "Reference" "C709"
			(at 0 0 270)
			(layer "F.SilkS")
			(hide yes)
			(effects
				(font
					(size 1.27 1.27)
				)
			)
		)
		(property "Value" ""
			(at 0 0 270)
			(layer "F.Fab")
			(effects
				(font
					(size 1.27 1.27)
				)
			)
		)
		(duplicate_pad_numbers_are_jumpers no)
		(fp_line
			(start -0.299974 0.150114)
			(end -0.299974 -0.150114)
			(stroke
				(width 0.1)
				(type default)
			)
			(layer "F.Fab")
		)
		(fp_line
			(start 0.299974 0.150114)
			(end -0.299974 0.150114)
			(stroke
				(width 0.1)
				(type default)
			)
			(layer "F.Fab")
		)
		(fp_line
			(start -0.299974 -0.150114)
			(end 0.299974 -0.150114)
			(stroke
				(width 0.1)
				(type default)
			)
			(layer "F.Fab")
		)
		(fp_line
			(start 0.299974 -0.150114)
			(end 0.299974 0.150114)
			(stroke
				(width 0.1)
				(type default)
			)
			(layer "F.Fab")
		)
		(pad "1" smd rect
			(at -0.2667 0 270)
			(size 0.3048 0.381)
			(layers "F.Cu" "F.Mask" "F.Paste")
			(net "P5E_CPU1_PE4_TX_C_DP<0>")
		)
		(pad "2" smd rect
			(at 0.2667 0 270)
			(size 0.3048 0.381)
			(layers "F.Cu" "F.Mask" "F.Paste")
			(net "P5E_CPU1_PE4_TX_DP<0>")
		)
	)
	(footprint ""
		(layer "F.Cu")
		(at 68.093844 -109.483906)
		(property "Reference" "R3731"
			(at 0 0 0)
			(layer "F.SilkS")
			(hide yes)
			(effects
				(font
					(size 1.27 1.27)
				)
			)
		)
		(property "Value" ""
			(at 0 0 0)
			(layer "F.Fab")
			(effects
				(font
					(size 1.27 1.27)
				)
			)
		)
		(duplicate_pad_numbers_are_jumpers no)
		(fp_line
			(start -0.7874 -0.4064)
			(end 0.7874 -0.4064)
			(stroke
				(width 0.1524)
				(type default)
			)
			(layer "F.SilkS")
		)
		(fp_line
			(start -0.7874 0.4064)
			(end -0.7874 -0.4064)
			(stroke
				(width 0.1524)
				(type default)
			)
			(layer "F.SilkS")
		)
		(fp_line
			(start 0.7874 -0.4064)
			(end 0.7874 0.4064)
			(stroke
				(width 0.1524)
				(type default)
			)
			(layer "F.SilkS")
		)
		(fp_line
			(start 0.7874 0.4064)
			(end -0.7874 0.4064)
			(stroke
				(width 0.1524)
				(type default)
			)
			(layer "F.SilkS")
		)
		(fp_line
			(start -0.67945 -0.305054)
			(end -0.12065 -0.305054)
			(stroke
				(width 0.1)
				(type default)
			)
			(layer "F.Fab")
		)
		(fp_line
			(start -0.67945 0.3048)
			(end -0.67945 -0.305054)
			(stroke
				(width 0.1)
				(type default)
			)
			(layer "F.Fab")
		)
		(fp_line
			(start -0.12065 -0.305054)
			(end -0.12065 -0.2794)
			(stroke
				(width 0.1)
				(type default)
			)
			(layer "F.Fab")
		)
		(fp_line
			(start -0.12065 -0.2794)
			(end 0.12065 -0.2794)
			(stroke
				(width 0.1)
				(type default)
			)
			(layer "F.Fab")
		)
		(fp_line
			(start -0.12065 0.2794)
			(end -0.12065 0.3048)
			(stroke
				(width 0.1)
				(type default)
			)
			(layer "F.Fab")
		)
		(fp_line
			(start -0.12065 0.3048)
			(end -0.67945 0.3048)
			(stroke
				(width 0.1)
				(type default)
			)
			(layer "F.Fab")
		)
		(fp_line
			(start 0.120396 0.2794)
			(end -0.12065 0.2794)
			(stroke
				(width 0.1)
				(type default)
			)
			(layer "F.Fab")
		)
		(fp_line
			(start 0.120396 0.3048)
			(end 0.120396 0.2794)
			(stroke
				(width 0.1)
				(type default)
			)
			(layer "F.Fab")
		)
		(fp_line
			(start 0.12065 -0.3048)
			(end 0.67945 -0.3048)
			(stroke
				(width 0.1)
				(type default)
			)
			(layer "F.Fab")
		)
		(fp_line
			(start 0.12065 -0.2794)
			(end 0.12065 -0.3048)
			(stroke
				(width 0.1)
				(type default)
			)
			(layer "F.Fab")
		)
		(fp_line
			(start 0.67945 -0.3048)
			(end 0.67945 0.3048)
			(stroke
				(width 0.1)
				(type default)
			)
			(layer "F.Fab")
		)
		(fp_line
			(start 0.67945 0.3048)
			(end 0.120396 0.3048)
			(stroke
				(width 0.1)
				(type default)
			)
			(layer "F.Fab")
		)
		(pad "1" smd circle
			(at -0.40005 0)
			(size 0 0)
			(layers "F.Cu" "F.Mask" "F.Paste")
			(net "P3V3_AUX")
		)
		(pad "2" smd circle
			(at 0.40005 0)
			(size 0 0)
			(layers "F.Cu" "F.Mask" "F.Paste")
			(net "SMB_LM75_3_3V3AUX_SCL")
		)
	)
	(footprint ""
		(layer "F.Cu")
		(at 193.60388 -102.415848 180)
		(property "Reference" "R269"
			(at 0 0 180)
			(layer "F.SilkS")
			(hide yes)
			(effects
				(font
					(size 1.27 1.27)
				)
			)
		)
		(property "Value" ""
			(at 0 0 180)
			(layer "F.Fab")
			(effects
				(font
					(size 1.27 1.27)
				)
			)
		)
		(duplicate_pad_numbers_are_jumpers no)
		(fp_line
			(start 0.7874 0.4064)
			(end -0.7874 0.4064)
			(stroke
				(width 0.1524)
				(type default)
			)
			(layer "F.SilkS")
		)
		(fp_line
			(start 0.7874 -0.4064)
			(end 0.7874 0.4064)
			(stroke
				(width 0.1524)
				(type default)
			)
			(layer "F.SilkS")
		)
		(fp_line
			(start -0.7874 0.4064)
			(end -0.7874 -0.4064)
			(stroke
				(width 0.1524)
				(type default)
			)
			(layer "F.SilkS")
		)
		(fp_line
			(start -0.7874 -0.4064)
			(end 0.7874 -0.4064)
			(stroke
				(width 0.1524)
				(type default)
			)
			(layer "F.SilkS")
		)
		(fp_line
			(start 0.67945 0.3048)
			(end 0.120396 0.3048)
			(stroke
				(width 0.1)
				(type default)
			)
			(layer "F.Fab")
		)
		(fp_line
			(start 0.67945 -0.3048)
			(end 0.67945 0.3048)
			(stroke
				(width 0.1)
				(type default)
			)
			(layer "F.Fab")
		)
		(fp_line
			(start 0.12065 -0.2794)
			(end 0.12065 -0.3048)
			(stroke
				(width 0.1)
				(type default)
			)
			(layer "F.Fab")
		)
		(fp_line
			(start 0.12065 -0.3048)
			(end 0.67945 -0.3048)
			(stroke
				(width 0.1)
				(type default)
			)
			(layer "F.Fab")
		)
		(fp_line
			(start 0.120396 0.3048)
			(end 0.120396 0.2794)
			(stroke
				(width 0.1)
				(type default)
			)
			(layer "F.Fab")
		)
		(fp_line
			(start 0.120396 0.2794)
			(end -0.12065 0.2794)
			(stroke
				(width 0.1)
				(type default)
			)
			(layer "F.Fab")
		)
		(fp_line
			(start -0.12065 0.3048)
			(end -0.67945 0.3048)
			(stroke
				(width 0.1)
				(type default)
			)
			(layer "F.Fab")
		)
		(fp_line
			(start -0.12065 0.2794)
			(end -0.12065 0.3048)
			(stroke
				(width 0.1)
				(type default)
			)
			(layer "F.Fab")
		)
		(fp_line
			(start -0.12065 -0.2794)
			(end 0.12065 -0.2794)
			(stroke
				(width 0.1)
				(type default)
			)
			(layer "F.Fab")
		)
		(fp_line
			(start -0.12065 -0.305054)
			(end -0.12065 -0.2794)
			(stroke
				(width 0.1)
				(type default)
			)
			(layer "F.Fab")
		)
		(fp_line
			(start -0.67945 0.3048)
			(end -0.67945 -0.305054)
			(stroke
				(width 0.1)
				(type default)
			)
			(layer "F.Fab")
		)
		(fp_line
			(start -0.67945 -0.305054)
			(end -0.12065 -0.305054)
			(stroke
				(width 0.1)
				(type default)
			)
			(layer "F.Fab")
		)
		(pad "1" smd circle
			(at -0.40005 0 180)
			(size 0 0)
			(layers "F.Cu" "F.Mask" "F.Paste")
			(net "FM_ADR_MODE1")
		)
		(pad "2" smd circle
			(at 0.40005 0 180)
			(size 0 0)
			(layers "F.Cu" "F.Mask" "F.Paste")
			(net "FM_ADR_MODE1_R")
		)
	)
	(footprint ""
		(layer "F.Cu")
		(at 122.978926 -122.096784 90)
		(property "Reference" "R4040"
			(at 0 0 90)
			(layer "F.SilkS")
			(hide yes)
			(effects
				(font
					(size 1.27 1.27)
				)
			)
		)
		(property "Value" ""
			(at 0 0 90)
			(layer "F.Fab")
			(effects
				(font
					(size 1.27 1.27)
				)
			)
		)
		(duplicate_pad_numbers_are_jumpers no)
		(fp_line
			(start 0.7874 -0.4064)
			(end 0.7874 0.4064)
			(stroke
				(width 0.1524)
				(type default)
			)
			(layer "F.SilkS")
		)
		(fp_line
			(start -0.7874 -0.4064)
			(end 0.7874 -0.4064)
			(stroke
				(width 0.1524)
				(type default)
			)
			(layer "F.SilkS")
		)
		(fp_line
			(start 0.7874 0.4064)
			(end -0.7874 0.4064)
			(stroke
				(width 0.1524)
				(type default)
			)
			(layer "F.SilkS")
		)
		(fp_line
			(start -0.7874 0.4064)
			(end -0.7874 -0.4064)
			(stroke
				(width 0.1524)
				(type default)
			)
			(layer "F.SilkS")
		)
		(fp_line
			(start -0.12065 -0.305054)
			(end -0.12065 -0.2794)
			(stroke
				(width 0.1)
				(type default)
			)
			(layer "F.Fab")
		)
		(fp_line
			(start -0.67945 -0.305054)
			(end -0.12065 -0.305054)
			(stroke
				(width 0.1)
				(type default)
			)
			(layer "F.Fab")
		)
		(fp_line
			(start 0.67945 -0.3048)
			(end 0.67945 0.3048)
			(stroke
				(width 0.1)
				(type default)
			)
			(layer "F.Fab")
		)
		(fp_line
			(start 0.12065 -0.3048)
			(end 0.67945 -0.3048)
			(stroke
				(width 0.1)
				(type default)
			)
			(layer "F.Fab")
		)
		(fp_line
			(start 0.12065 -0.2794)
			(end 0.12065 -0.3048)
			(stroke
				(width 0.1)
				(type default)
			)
			(layer "F.Fab")
		)
		(fp_line
			(start -0.12065 -0.2794)
			(end 0.12065 -0.2794)
			(stroke
				(width 0.1)
				(type default)
			)
			(layer "F.Fab")
		)
		(fp_line
			(start 0.120396 0.2794)
			(end -0.12065 0.2794)
			(stroke
				(width 0.1)
				(type default)
			)
			(layer "F.Fab")
		)
		(fp_line
			(start -0.12065 0.2794)
			(end -0.12065 0.3048)
			(stroke
				(width 0.1)
				(type default)
			)
			(layer "F.Fab")
		)
		(fp_line
			(start 0.67945 0.3048)
			(end 0.120396 0.3048)
			(stroke
				(width 0.1)
				(type default)
			)
			(layer "F.Fab")
		)
		(fp_line
			(start 0.120396 0.3048)
			(end 0.120396 0.2794)
			(stroke
				(width 0.1)
				(type default)
			)
			(layer "F.Fab")
		)
		(fp_line
			(start -0.12065 0.3048)
			(end -0.67945 0.3048)
			(stroke
				(width 0.1)
				(type default)
			)
			(layer "F.Fab")
		)
		(fp_line
			(start -0.67945 0.3048)
			(end -0.67945 -0.305054)
			(stroke
				(width 0.1)
				(type default)
			)
			(layer "F.Fab")
		)
		(pad "1" smd circle
			(at -0.40005 0 90)
			(size 0 0)
			(layers "F.Cu" "F.Mask" "F.Paste")
			(net "P0V62_CPU1_RST_DDR_VREF")
		)
		(pad "2" smd circle
			(at 0.40005 0 90)
			(size 0 0)
			(layers "F.Cu" "F.Mask" "F.Paste")
			(net "GND")
		)
	)
	(footprint ""
		(layer "F.Cu")
		(at 291.83203 -15.348204)
		(property "Reference" "U271"
			(at -3.98018 -3.442208 0)
			(unlocked yes)
			(layer "F.SilkS")
			(effects
				(font
					(size 0.7874 0.5842)
					(thickness 0.1524)
				)
				(justify left)
			)
		)
		(property "Value" ""
			(at 0 0 0)
			(layer "F.Fab")
			(effects
				(font
					(size 1.27 1.27)
				)
			)
		)
		(duplicate_pad_numbers_are_jumpers no)
		(fp_line
			(start -3.447796 -2.500122)
			(end -3.447796 2.500122)
			(stroke
				(width 0.1524)
				(type default)
			)
			(layer "F.SilkS")
		)
		(fp_line
			(start -3.447796 2.500122)
			(end 3.447796 2.500122)
			(stroke
				(width 0.1524)
				(type default)
			)
			(layer "F.SilkS")
		)
		(fp_line
			(start -1.484122 -2.500122)
			(end -3.447796 -2.500122)
			(stroke
				(width 0.1524)
				(type default)
			)
			(layer "F.SilkS")
		)
		(fp_line
			(start 0 -1.016)
			(end -1.484122 -2.500122)
			(stroke
				(width 0.1524)
				(type default)
			)
			(layer "F.SilkS")
		)
		(fp_line
			(start 1.484122 -2.500122)
			(end 0 -1.016)
			(stroke
				(width 0.1524)
				(type default)
			)
			(layer "F.SilkS")
		)
		(fp_line
			(start 3.447796 -2.500122)
			(end 1.484122 -2.500122)
			(stroke
				(width 0.1524)
				(type default)
			)
			(layer "F.SilkS")
		)
		(fp_line
			(start 3.447796 2.500122)
			(end 3.447796 -2.500122)
			(stroke
				(width 0.1524)
				(type default)
			)
			(layer "F.SilkS")
		)
		(fp_poly
			(pts
				(xy -4.5974 -2.413) (xy -3.5814 -1.905) (xy -4.5974 -1.397)
			)
			(stroke
				(width 0)
				(type default)
			)
			(fill yes)
			(layer "F.SilkS")
		)
		(fp_line
			(start -1.999996 -2.500122)
			(end -1.999996 2.500122)
			(stroke
				(width 0.1)
				(type default)
			)
			(layer "F.Fab")
		)
		(fp_line
			(start -1.999996 2.500122)
			(end 1.999996 2.500122)
			(stroke
				(width 0.1)
				(type default)
			)
			(layer "F.Fab")
		)
		(fp_line
			(start 1.999996 -2.500122)
			(end -1.999996 -2.500122)
			(stroke
				(width 0.1)
				(type default)
			)
			(layer "F.Fab")
		)
		(fp_line
			(start 1.999996 2.500122)
			(end 1.999996 -2.500122)
			(stroke
				(width 0.1)
				(type default)
			)
			(layer "F.Fab")
		)
		(fp_poly
			(pts
				(xy -4.5974 -2.413) (xy -4.5974 -1.397) (xy -3.5814 -1.905)
			)
			(stroke
				(width 0)
				(type default)
			)
			(fill yes)
			(layer "F.Fab")
		)
		(pad "1" smd rect
			(at -2.649982 -1.905 270)
			(size 0.6096 1.3208)
			(layers "F.Cu" "F.Mask" "F.Paste")
			(net "SMB_LM75_1_3V3AUX_SDA_R1")
		)
		(pad "2" smd rect
			(at -2.649982 -0.635 270)
			(size 0.6096 1.3208)
			(layers "F.Cu" "F.Mask" "F.Paste")
			(net "SMB_LM75_1_3V3AUX_SCL_R1")
		)
		(pad "3" smd rect
			(at -2.649982 0.635 270)
			(size 0.6096 1.3208)
			(layers "F.Cu" "F.Mask" "F.Paste")
			(net "FM_G751_1_ALERT_N")
		)
		(pad "4" smd rect
			(at -2.649982 1.905 270)
			(size 0.6096 1.3208)
			(layers "F.Cu" "F.Mask" "F.Paste")
			(net "GND")
		)
		(pad "5" smd rect
			(at 2.649982 1.905 270)
			(size 0.6096 1.3208)
			(layers "F.Cu" "F.Mask" "F.Paste")
			(net "U271_1_ADD2")
		)
		(pad "6" smd rect
			(at 2.649982 0.635 270)
			(size 0.6096 1.3208)
			(layers "F.Cu" "F.Mask" "F.Paste")
			(net "U271_1_ADD1")
		)
		(pad "7" smd rect
			(at 2.649982 -0.635 270)
			(size 0.6096 1.3208)
			(layers "F.Cu" "F.Mask" "F.Paste")
			(net "U271_1_ADD0")
		)
		(pad "8" smd rect
			(at 2.649982 -1.905 270)
			(size 0.6096 1.3208)
			(layers "F.Cu" "F.Mask" "F.Paste")
			(net "P3V3_AUX")
		)
	)
	(footprint ""
		(layer "F.Cu")
		(at 210.74888 -42.382948)
		(property "Reference" "R3529"
			(at 0 0 0)
			(layer "F.SilkS")
			(hide yes)
			(effects
				(font
					(size 1.27 1.27)
				)
			)
		)
		(property "Value" ""
			(at 0 0 0)
			(layer "F.Fab")
			(effects
				(font
					(size 1.27 1.27)
				)
			)
		)
		(duplicate_pad_numbers_are_jumpers no)
		(fp_line
			(start -0.7874 -0.4064)
			(end 0.7874 -0.4064)
			(stroke
				(width 0.1524)
				(type default)
			)
			(layer "F.SilkS")
		)
		(fp_line
			(start -0.7874 0.4064)
			(end -0.7874 -0.4064)
			(stroke
				(width 0.1524)
				(type default)
			)
			(layer "F.SilkS")
		)
		(fp_line
			(start 0.7874 -0.4064)
			(end 0.7874 0.4064)
			(stroke
				(width 0.1524)
				(type default)
			)
			(layer "F.SilkS")
		)
		(fp_line
			(start 0.7874 0.4064)
			(end -0.7874 0.4064)
			(stroke
				(width 0.1524)
				(type default)
			)
			(layer "F.SilkS")
		)
		(fp_line
			(start -0.67945 -0.305054)
			(end -0.12065 -0.305054)
			(stroke
				(width 0.1)
				(type default)
			)
			(layer "F.Fab")
		)
		(fp_line
			(start -0.67945 0.3048)
			(end -0.67945 -0.305054)
			(stroke
				(width 0.1)
				(type default)
			)
			(layer "F.Fab")
		)
		(fp_line
			(start -0.12065 -0.305054)
			(end -0.12065 -0.2794)
			(stroke
				(width 0.1)
				(type default)
			)
			(layer "F.Fab")
		)
		(fp_line
			(start -0.12065 -0.2794)
			(end 0.12065 -0.2794)
			(stroke
				(width 0.1)
				(type default)
			)
			(layer "F.Fab")
		)
		(fp_line
			(start -0.12065 0.2794)
			(end -0.12065 0.3048)
			(stroke
				(width 0.1)
				(type default)
			)
			(layer "F.Fab")
		)
		(fp_line
			(start -0.12065 0.3048)
			(end -0.67945 0.3048)
			(stroke
				(width 0.1)
				(type default)
			)
			(layer "F.Fab")
		)
		(fp_line
			(start 0.120396 0.2794)
			(end -0.12065 0.2794)
			(stroke
				(width 0.1)
				(type default)
			)
			(layer "F.Fab")
		)
		(fp_line
			(start 0.120396 0.3048)
			(end 0.120396 0.2794)
			(stroke
				(width 0.1)
				(type default)
			)
			(layer "F.Fab")
		)
		(fp_line
			(start 0.12065 -0.3048)
			(end 0.67945 -0.3048)
			(stroke
				(width 0.1)
				(type default)
			)
			(layer "F.Fab")
		)
		(fp_line
			(start 0.12065 -0.2794)
			(end 0.12065 -0.3048)
			(stroke
				(width 0.1)
				(type default)
			)
			(layer "F.Fab")
		)
		(fp_line
			(start 0.67945 -0.3048)
			(end 0.67945 0.3048)
			(stroke
				(width 0.1)
				(type default)
			)
			(layer "F.Fab")
		)
		(fp_line
			(start 0.67945 0.3048)
			(end 0.120396 0.3048)
			(stroke
				(width 0.1)
				(type default)
			)
			(layer "F.Fab")
		)
		(pad "1" smd circle
			(at -0.40005 0)
			(size 0 0)
			(layers "F.Cu" "F.Mask" "F.Paste")
			(net "P3V3_AUX")
		)
		(pad "2" smd circle
			(at 0.40005 0)
			(size 0 0)
			(layers "F.Cu" "F.Mask" "F.Paste")
			(net "SMB_PCIE_E1S_ISO_EN_R")
		)
	)
	(footprint ""
		(layer "F.Cu")
		(at 517.258808 -153.2128 -90)
		(property "Reference" "X2"
			(at -1.37668 2.83083 90)
			(unlocked yes)
			(layer "F.SilkS")
			(effects
				(font
					(size 0.7874 0.5842)
					(thickness 0.1524)
				)
				(justify left)
			)
		)
		(property "Value" ""
			(at 0 0 270)
			(layer "F.Fab")
			(effects
				(font
					(size 1.27 1.27)
				)
			)
		)
		(property "Device Type" "TP_TDR_4P_FTS_MPKT4_H025P0200_I"
			(at 1.30175 1.27 0)
			(unlocked yes)
			(layer "F.Fab")
			(hide yes)
			(effects
				(font
					(size 0.635 0.4064)
					(thickness 0.1524)
				)
			)
		)
		(property "User Part Number" "TP15"
			(at 1.30175 1.27 0)
			(unlocked yes)
			(layer "Cmts.User")
			(hide yes)
			(effects
				(font
					(size 0.635 0.4064)
					(thickness 0.1524)
				)
			)
		)
		(duplicate_pad_numbers_are_jumpers no)
		(fp_line
			(start 0 3.81)
			(end 2.54 3.81)
			(stroke
				(width 0.1524)
				(type default)
			)
			(layer "F.SilkS")
		)
		(fp_line
			(start 2.54 3.81)
			(end 2.54 3.6703)
			(stroke
				(width 0.1524)
				(type default)
			)
			(layer "F.SilkS")
		)
		(fp_line
			(start 0 3.175)
			(end 0 3.81)
			(stroke
				(width 0.1524)
				(type default)
			)
			(layer "F.SilkS")
		)
		(fp_line
			(start 2.54 1.4097)
			(end 2.54 1.1303)
			(stroke
				(width 0.1524)
				(type default)
			)
			(layer "F.SilkS")
		)
		(fp_line
			(start 0 0.635)
			(end 0 1.905)
			(stroke
				(width 0.1524)
				(type default)
			)
			(layer "F.SilkS")
		)
		(fp_line
			(start 2.54 -1.1303)
			(end 2.54 -1.27)
			(stroke
				(width 0.1524)
				(type default)
			)
			(layer "F.SilkS")
		)
		(fp_line
			(start 0 -1.27)
			(end 0 -0.635)
			(stroke
				(width 0.1524)
				(type default)
			)
			(layer "F.SilkS")
		)
		(fp_line
			(start 2.54 -1.27)
			(end 0 -1.27)
			(stroke
				(width 0.1524)
				(type default)
			)
			(layer "F.SilkS")
		)
		(fp_poly
			(pts
				(xy -1.224026 0.0635) (xy -2.748026 0.8255) (xy -2.748026 -0.6985)
			)
			(stroke
				(width 0)
				(type default)
			)
			(fill yes)
			(layer "F.SilkS")
		)
		(fp_line
			(start 0 3.81)
			(end 2.54 3.81)
			(stroke
				(width 0.1)
				(type default)
			)
			(layer "F.Fab")
		)
		(fp_line
			(start 2.54 3.81)
			(end 2.54 -1.27)
			(stroke
				(width 0.1)
				(type default)
			)
			(layer "F.Fab")
		)
		(fp_line
			(start 0 -1.27)
			(end 0 3.81)
			(stroke
				(width 0.1)
				(type default)
			)
			(layer "F.Fab")
		)
		(fp_line
			(start 2.54 -1.27)
			(end 0 -1.27)
			(stroke
				(width 0.1)
				(type default)
			)
			(layer "F.Fab")
		)
		(fp_poly
			(pts
				(xy -0.761746 0) (xy -2.285746 -0.762) (xy -2.285746 0.762)
			)
			(stroke
				(width 0)
				(type default)
			)
			(fill yes)
			(layer "F.Fab")
		)
		(pad "1" thru_hole circle
			(at 0 0 270)
			(size 1.0033 1.0033)
			(drill 0.249936)
			(layers "*.Cu" "*.Mask")
			(remove_unused_layers no)
			(net "TDR_DIFF_85_IN1_DP")
			(clearance 0.10795)
			(thermal_gap 0.10795)
			(padstack
				(mode front_inner_back)
				(layer "Inner"
					(shape circle)
					(size 0.8001 0.8001)
					(clearance 0.1524)
				)
				(layer "B.Cu"
					(shape circle)
					(size 1.0033 1.0033)
					(clearance 0.10795)
				)
			)
		)
		(pad "2" thru_hole circle
			(at 2.54 0 270)
			(size 1.9939 1.9939)
			(drill 0.249936)
			(layers "*.Cu" "*.Mask")
			(remove_unused_layers no)
			(net "T1_GND")
			(clearance 0.10795)
			(thermal_gap 0.10795)
			(padstack
				(mode front_inner_back)
				(layer "Inner"
					(shape circle)
					(size 0.8001 0.8001)
					(clearance 0.1524)
				)
				(layer "B.Cu"
					(shape circle)
					(size 1.9939 1.9939)
					(clearance 0.10795)
				)
			)
		)
		(pad "3" thru_hole circle
			(at 2.54 2.54 270)
			(size 1.9939 1.9939)
			(drill 0.249936)
			(layers "*.Cu" "*.Mask")
			(remove_unused_layers no)
			(net "T1_GND")
			(clearance 0.10795)
			(thermal_gap 0.10795)
			(padstack
				(mode front_inner_back)
				(layer "Inner"
					(shape circle)
					(size 0.8001 0.8001)
					(clearance 0.1524)
				)
				(layer "B.Cu"
					(shape circle)
					(size 1.9939 1.9939)
					(clearance 0.10795)
				)
			)
		)
		(pad "4" thru_hole circle
			(at 0 2.54 270)
			(size 1.0033 1.0033)
			(drill 0.249936)
			(layers "*.Cu" "*.Mask")
			(remove_unused_layers no)
			(net "TDR_DIFF_85_IN1_DN")
			(clearance 0.10795)
			(thermal_gap 0.10795)
			(padstack
				(mode front_inner_back)
				(layer "Inner"
					(shape circle)
					(size 0.8001 0.8001)
					(clearance 0.1524)
				)
				(layer "B.Cu"
					(shape circle)
					(size 1.0033 1.0033)
					(clearance 0.10795)
				)
			)
		)
	)
	(footprint ""
		(layer "F.Cu")
		(at 165.53815 -418.514276 -90)
		(property "Reference" "R2672"
			(at 0 0 270)
			(layer "F.SilkS")
			(hide yes)
			(effects
				(font
					(size 1.27 1.27)
				)
			)
		)
		(property "Value" ""
			(at 0 0 270)
			(layer "F.Fab")
			(effects
				(font
					(size 1.27 1.27)
				)
			)
		)
		(duplicate_pad_numbers_are_jumpers no)
		(fp_line
			(start -0.7874 0.4064)
			(end -0.7874 -0.4064)
			(stroke
				(width 0.1524)
				(type default)
			)
			(layer "F.SilkS")
		)
		(fp_line
			(start 0.7874 0.4064)
			(end -0.7874 0.4064)
			(stroke
				(width 0.1524)
				(type default)
			)
			(layer "F.SilkS")
		)
		(fp_line
			(start -0.7874 -0.4064)
			(end 0.7874 -0.4064)
			(stroke
				(width 0.1524)
				(type default)
			)
			(layer "F.SilkS")
		)
		(fp_line
			(start 0.7874 -0.4064)
			(end 0.7874 0.4064)
			(stroke
				(width 0.1524)
				(type default)
			)
			(layer "F.SilkS")
		)
		(fp_line
			(start -0.67945 0.3048)
			(end -0.67945 -0.305054)
			(stroke
				(width 0.1)
				(type default)
			)
			(layer "F.Fab")
		)
		(fp_line
			(start -0.12065 0.3048)
			(end -0.67945 0.3048)
			(stroke
				(width 0.1)
				(type default)
			)
			(layer "F.Fab")
		)
		(fp_line
			(start 0.120396 0.3048)
			(end 0.120396 0.2794)
			(stroke
				(width 0.1)
				(type default)
			)
			(layer "F.Fab")
		)
		(fp_line
			(start 0.67945 0.3048)
			(end 0.120396 0.3048)
			(stroke
				(width 0.1)
				(type default)
			)
			(layer "F.Fab")
		)
		(fp_line
			(start -0.12065 0.2794)
			(end -0.12065 0.3048)
			(stroke
				(width 0.1)
				(type default)
			)
			(layer "F.Fab")
		)
		(fp_line
			(start 0.120396 0.2794)
			(end -0.12065 0.2794)
			(stroke
				(width 0.1)
				(type default)
			)
			(layer "F.Fab")
		)
		(fp_line
			(start -0.12065 -0.2794)
			(end 0.12065 -0.2794)
			(stroke
				(width 0.1)
				(type default)
			)
			(layer "F.Fab")
		)
		(fp_line
			(start 0.12065 -0.2794)
			(end 0.12065 -0.3048)
			(stroke
				(width 0.1)
				(type default)
			)
			(layer "F.Fab")
		)
		(fp_line
			(start 0.12065 -0.3048)
			(end 0.67945 -0.3048)
			(stroke
				(width 0.1)
				(type default)
			)
			(layer "F.Fab")
		)
		(fp_line
			(start 0.67945 -0.3048)
			(end 0.67945 0.3048)
			(stroke
				(width 0.1)
				(type default)
			)
			(layer "F.Fab")
		)
		(fp_line
			(start -0.67945 -0.305054)
			(end -0.12065 -0.305054)
			(stroke
				(width 0.1)
				(type default)
			)
			(layer "F.Fab")
		)
		(fp_line
			(start -0.12065 -0.305054)
			(end -0.12065 -0.2794)
			(stroke
				(width 0.1)
				(type default)
			)
			(layer "F.Fab")
		)
		(pad "1" smd circle
			(at -0.40005 0 270)
			(size 0 0)
			(layers "F.Cu" "F.Mask" "F.Paste")
			(net "SMB_BMC_SWB_BUF_R_SDA")
		)
		(pad "2" smd circle
			(at 0.40005 0 270)
			(size 0 0)
			(layers "F.Cu" "F.Mask" "F.Paste")
			(net "SMB_BMC_SWB_BUF_SDA")
		)
	)
	(footprint ""
		(layer "F.Cu")
		(at 360.383582 -385.17449)
		(property "Reference" "R4167"
			(at 0 0 0)
			(layer "F.SilkS")
			(hide yes)
			(effects
				(font
					(size 1.27 1.27)
				)
			)
		)
		(property "Value" ""
			(at 0 0 0)
			(layer "F.Fab")
			(effects
				(font
					(size 1.27 1.27)
				)
			)
		)
		(duplicate_pad_numbers_are_jumpers no)
		(fp_line
			(start -0.7874 -0.4064)
			(end 0.7874 -0.4064)
			(stroke
				(width 0.1524)
				(type default)
			)
			(layer "F.SilkS")
		)
		(fp_line
			(start -0.7874 0.4064)
			(end -0.7874 -0.4064)
			(stroke
				(width 0.1524)
				(type default)
			)
			(layer "F.SilkS")
		)
		(fp_line
			(start 0.7874 -0.4064)
			(end 0.7874 0.4064)
			(stroke
				(width 0.1524)
				(type default)
			)
			(layer "F.SilkS")
		)
		(fp_line
			(start 0.7874 0.4064)
			(end -0.7874 0.4064)
			(stroke
				(width 0.1524)
				(type default)
			)
			(layer "F.SilkS")
		)
		(fp_line
			(start -0.67945 -0.305054)
			(end -0.12065 -0.305054)
			(stroke
				(width 0.1)
				(type default)
			)
			(layer "F.Fab")
		)
		(fp_line
			(start -0.67945 0.3048)
			(end -0.67945 -0.305054)
			(stroke
				(width 0.1)
				(type default)
			)
			(layer "F.Fab")
		)
		(fp_line
			(start -0.12065 -0.305054)
			(end -0.12065 -0.2794)
			(stroke
				(width 0.1)
				(type default)
			)
			(layer "F.Fab")
		)
		(fp_line
			(start -0.12065 -0.2794)
			(end 0.12065 -0.2794)
			(stroke
				(width 0.1)
				(type default)
			)
			(layer "F.Fab")
		)
		(fp_line
			(start -0.12065 0.2794)
			(end -0.12065 0.3048)
			(stroke
				(width 0.1)
				(type default)
			)
			(layer "F.Fab")
		)
		(fp_line
			(start -0.12065 0.3048)
			(end -0.67945 0.3048)
			(stroke
				(width 0.1)
				(type default)
			)
			(layer "F.Fab")
		)
		(fp_line
			(start 0.120396 0.2794)
			(end -0.12065 0.2794)
			(stroke
				(width 0.1)
				(type default)
			)
			(layer "F.Fab")
		)
		(fp_line
			(start 0.120396 0.3048)
			(end 0.120396 0.2794)
			(stroke
				(width 0.1)
				(type default)
			)
			(layer "F.Fab")
		)
		(fp_line
			(start 0.12065 -0.3048)
			(end 0.67945 -0.3048)
			(stroke
				(width 0.1)
				(type default)
			)
			(layer "F.Fab")
		)
		(fp_line
			(start 0.12065 -0.2794)
			(end 0.12065 -0.3048)
			(stroke
				(width 0.1)
				(type default)
			)
			(layer "F.Fab")
		)
		(fp_line
			(start 0.67945 -0.3048)
			(end 0.67945 0.3048)
			(stroke
				(width 0.1)
				(type default)
			)
			(layer "F.Fab")
		)
		(fp_line
			(start 0.67945 0.3048)
			(end 0.120396 0.3048)
			(stroke
				(width 0.1)
				(type default)
			)
			(layer "F.Fab")
		)
		(pad "1" smd circle
			(at -0.40005 0)
			(size 0 0)
			(layers "F.Cu" "F.Mask" "F.Paste")
			(net "P3V3_AUX")
		)
		(pad "2" smd circle
			(at 0.40005 0)
			(size 0 0)
			(layers "F.Cu" "F.Mask" "F.Paste")
			(net "GPU_3V3IO_RSVD1_ISO")
		)
	)
	(footprint ""
		(layer "F.Cu")
		(at 119.508016 -238.162592 90)
		(property "Reference" "C440"
			(at 0 0 90)
			(layer "F.SilkS")
			(hide yes)
			(effects
				(font
					(size 1.27 1.27)
				)
			)
		)
		(property "Value" ""
			(at 0 0 90)
			(layer "F.Fab")
			(effects
				(font
					(size 1.27 1.27)
				)
			)
		)
		(duplicate_pad_numbers_are_jumpers no)
		(fp_line
			(start 0.7874 -0.4064)
			(end 0.7874 0.4064)
			(stroke
				(width 0.1524)
				(type default)
			)
			(layer "F.SilkS")
		)
		(fp_line
			(start -0.7874 -0.4064)
			(end 0.7874 -0.4064)
			(stroke
				(width 0.1524)
				(type default)
			)
			(layer "F.SilkS")
		)
		(fp_line
			(start 0.7874 0.4064)
			(end -0.7874 0.4064)
			(stroke
				(width 0.1524)
				(type default)
			)
			(layer "F.SilkS")
		)
		(fp_line
			(start -0.7874 0.4064)
			(end -0.7874 -0.4064)
			(stroke
				(width 0.1524)
				(type default)
			)
			(layer "F.SilkS")
		)
		(fp_line
			(start -0.12065 -0.305054)
			(end -0.12065 -0.2794)
			(stroke
				(width 0.1)
				(type default)
			)
			(layer "F.Fab")
		)
		(fp_line
			(start -0.67945 -0.305054)
			(end -0.12065 -0.305054)
			(stroke
				(width 0.1)
				(type default)
			)
			(layer "F.Fab")
		)
		(fp_line
			(start 0.67945 -0.3048)
			(end 0.67945 0.3048)
			(stroke
				(width 0.1)
				(type default)
			)
			(layer "F.Fab")
		)
		(fp_line
			(start 0.12065 -0.3048)
			(end 0.67945 -0.3048)
			(stroke
				(width 0.1)
				(type default)
			)
			(layer "F.Fab")
		)
		(fp_line
			(start 0.12065 -0.2794)
			(end 0.12065 -0.3048)
			(stroke
				(width 0.1)
				(type default)
			)
			(layer "F.Fab")
		)
		(fp_line
			(start -0.12065 -0.2794)
			(end 0.12065 -0.2794)
			(stroke
				(width 0.1)
				(type default)
			)
			(layer "F.Fab")
		)
		(fp_line
			(start 0.120396 0.2794)
			(end -0.12065 0.2794)
			(stroke
				(width 0.1)
				(type default)
			)
			(layer "F.Fab")
		)
		(fp_line
			(start -0.12065 0.2794)
			(end -0.12065 0.3048)
			(stroke
				(width 0.1)
				(type default)
			)
			(layer "F.Fab")
		)
		(fp_line
			(start 0.67945 0.3048)
			(end 0.120396 0.3048)
			(stroke
				(width 0.1)
				(type default)
			)
			(layer "F.Fab")
		)
		(fp_line
			(start 0.120396 0.3048)
			(end 0.120396 0.2794)
			(stroke
				(width 0.1)
				(type default)
			)
			(layer "F.Fab")
		)
		(fp_line
			(start -0.12065 0.3048)
			(end -0.67945 0.3048)
			(stroke
				(width 0.1)
				(type default)
			)
			(layer "F.Fab")
		)
		(fp_line
			(start -0.67945 0.3048)
			(end -0.67945 -0.305054)
			(stroke
				(width 0.1)
				(type default)
			)
			(layer "F.Fab")
		)
		(pad "1" smd circle
			(at -0.40005 0 90)
			(size 0 0)
			(layers "F.Cu" "F.Mask" "F.Paste")
			(net "PVCCINFAON_CPU1")
		)
		(pad "2" smd circle
			(at 0.40005 0 90)
			(size 0 0)
			(layers "F.Cu" "F.Mask" "F.Paste")
			(net "GND")
		)
	)
	(footprint ""
		(layer "F.Cu")
		(at 149.987 -131.282948 180)
		(property "Reference" "Q144"
			(at 1.15824 -2.07391 0)
			(unlocked yes)
			(layer "F.SilkS")
			(effects
				(font
					(size 0.7874 0.5842)
					(thickness 0.1524)
				)
				(justify left)
			)
		)
		(property "Value" ""
			(at 0 0 180)
			(layer "F.Fab")
			(effects
				(font
					(size 1.27 1.27)
				)
			)
		)
		(duplicate_pad_numbers_are_jumpers no)
		(fp_line
			(start 1.332738 1.100074)
			(end -1.332738 1.100074)
			(stroke
				(width 0.1524)
				(type default)
			)
			(layer "F.SilkS")
		)
		(fp_line
			(start 1.332738 -1.100074)
			(end 1.332738 1.100074)
			(stroke
				(width 0.1524)
				(type default)
			)
			(layer "F.SilkS")
		)
		(fp_line
			(start 0.4826 -1.100074)
			(end 1.332738 -1.100074)
			(stroke
				(width 0.1524)
				(type default)
			)
			(layer "F.SilkS")
		)
		(fp_line
			(start 0 -0.541274)
			(end 0.4826 -1.100074)
			(stroke
				(width 0.1524)
				(type default)
			)
			(layer "F.SilkS")
		)
		(fp_line
			(start -0.4826 -1.100074)
			(end 0 -0.541274)
			(stroke
				(width 0.1524)
				(type default)
			)
			(layer "F.SilkS")
		)
		(fp_line
			(start -1.332738 1.100074)
			(end -1.332738 -1.100074)
			(stroke
				(width 0.1524)
				(type default)
			)
			(layer "F.SilkS")
		)
		(fp_line
			(start -1.332738 -1.100074)
			(end -0.4826 -1.100074)
			(stroke
				(width 0.1524)
				(type default)
			)
			(layer "F.SilkS")
		)
		(fp_poly
			(pts
				(xy -2.05486 -0.910844) (xy -1.533144 -0.649986) (xy -2.05486 -0.389128)
			)
			(stroke
				(width 0)
				(type default)
			)
			(fill yes)
			(layer "F.SilkS")
		)
		(fp_line
			(start 0.674878 1.100074)
			(end -0.674878 1.100074)
			(stroke
				(width 0.1)
				(type default)
			)
			(layer "F.Fab")
		)
		(fp_line
			(start 0.674878 -1.100074)
			(end 0.674878 1.100074)
			(stroke
				(width 0.1)
				(type default)
			)
			(layer "F.Fab")
		)
		(fp_line
			(start -0.674878 1.100074)
			(end -0.674878 -1.100074)
			(stroke
				(width 0.1)
				(type default)
			)
			(layer "F.Fab")
		)
		(fp_line
			(start -0.674878 -1.100074)
			(end 0.674878 -1.100074)
			(stroke
				(width 0.1)
				(type default)
			)
			(layer "F.Fab")
		)
		(fp_poly
			(pts
				(xy -2.2352 -0.298958) (xy -2.2352 -1.001014) (xy -1.533144 -0.649986)
			)
			(stroke
				(width 0)
				(type default)
			)
			(fill yes)
			(layer "F.Fab")
		)
		(pad "1" smd rect
			(at -0.94996 -0.649986 270)
			(size 0.4318 0.508)
			(layers "F.Cu" "F.Mask" "F.Paste")
			(net "GND")
		)
		(pad "2" smd rect
			(at -0.94996 0 270)
			(size 0.4318 0.508)
			(layers "F.Cu" "F.Mask" "F.Paste")
			(net "PWRGD_PS_PWROK_PLD")
		)
		(pad "3" smd rect
			(at -0.94996 0.649986 270)
			(size 0.4318 0.508)
			(layers "F.Cu" "F.Mask" "F.Paste")
			(net "PWRGD_PS_PWROK_PLD_ISO")
		)
		(pad "4" smd rect
			(at 0.94996 0.649986 270)
			(size 0.4318 0.508)
			(layers "F.Cu" "F.Mask" "F.Paste")
			(net "GND")
		)
		(pad "5" smd rect
			(at 0.94996 0 270)
			(size 0.4318 0.508)
			(layers "F.Cu" "F.Mask" "F.Paste")
			(net "PWRGD_PS_PWROK_PLD_N")
		)
		(pad "6" smd rect
			(at 0.94996 -0.649986 270)
			(size 0.4318 0.508)
			(layers "F.Cu" "F.Mask" "F.Paste")
			(net "PWRGD_PS_PWROK_PLD_N")
		)
	)
	(footprint ""
		(layer "F.Cu")
		(at 46.582584 -108.047282 180)
		(property "Reference" "R2908"
			(at 0 0 180)
			(layer "F.SilkS")
			(hide yes)
			(effects
				(font
					(size 1.27 1.27)
				)
			)
		)
		(property "Value" ""
			(at 0 0 180)
			(layer "F.Fab")
			(effects
				(font
					(size 1.27 1.27)
				)
			)
		)
		(duplicate_pad_numbers_are_jumpers no)
		(fp_line
			(start 0.7874 0.4064)
			(end -0.7874 0.4064)
			(stroke
				(width 0.1524)
				(type default)
			)
			(layer "F.SilkS")
		)
		(fp_line
			(start 0.7874 -0.4064)
			(end 0.7874 0.4064)
			(stroke
				(width 0.1524)
				(type default)
			)
			(layer "F.SilkS")
		)
		(fp_line
			(start -0.7874 0.4064)
			(end -0.7874 -0.4064)
			(stroke
				(width 0.1524)
				(type default)
			)
			(layer "F.SilkS")
		)
		(fp_line
			(start -0.7874 -0.4064)
			(end 0.7874 -0.4064)
			(stroke
				(width 0.1524)
				(type default)
			)
			(layer "F.SilkS")
		)
		(fp_line
			(start 0.67945 0.3048)
			(end 0.120396 0.3048)
			(stroke
				(width 0.1)
				(type default)
			)
			(layer "F.Fab")
		)
		(fp_line
			(start 0.67945 -0.3048)
			(end 0.67945 0.3048)
			(stroke
				(width 0.1)
				(type default)
			)
			(layer "F.Fab")
		)
		(fp_line
			(start 0.12065 -0.2794)
			(end 0.12065 -0.3048)
			(stroke
				(width 0.1)
				(type default)
			)
			(layer "F.Fab")
		)
		(fp_line
			(start 0.12065 -0.3048)
			(end 0.67945 -0.3048)
			(stroke
				(width 0.1)
				(type default)
			)
			(layer "F.Fab")
		)
		(fp_line
			(start 0.120396 0.3048)
			(end 0.120396 0.2794)
			(stroke
				(width 0.1)
				(type default)
			)
			(layer "F.Fab")
		)
		(fp_line
			(start 0.120396 0.2794)
			(end -0.12065 0.2794)
			(stroke
				(width 0.1)
				(type default)
			)
			(layer "F.Fab")
		)
		(fp_line
			(start -0.12065 0.3048)
			(end -0.67945 0.3048)
			(stroke
				(width 0.1)
				(type default)
			)
			(layer "F.Fab")
		)
		(fp_line
			(start -0.12065 0.2794)
			(end -0.12065 0.3048)
			(stroke
				(width 0.1)
				(type default)
			)
			(layer "F.Fab")
		)
		(fp_line
			(start -0.12065 -0.2794)
			(end 0.12065 -0.2794)
			(stroke
				(width 0.1)
				(type default)
			)
			(layer "F.Fab")
		)
		(fp_line
			(start -0.12065 -0.305054)
			(end -0.12065 -0.2794)
			(stroke
				(width 0.1)
				(type default)
			)
			(layer "F.Fab")
		)
		(fp_line
			(start -0.67945 0.3048)
			(end -0.67945 -0.305054)
			(stroke
				(width 0.1)
				(type default)
			)
			(layer "F.Fab")
		)
		(fp_line
			(start -0.67945 -0.305054)
			(end -0.12065 -0.305054)
			(stroke
				(width 0.1)
				(type default)
			)
			(layer "F.Fab")
		)
		(pad "1" smd circle
			(at -0.40005 0 180)
			(size 0 0)
			(layers "F.Cu" "F.Mask" "F.Paste")
			(net "P3V3")
		)
		(pad "2" smd circle
			(at 0.40005 0 180)
			(size 0 0)
			(layers "F.Cu" "F.Mask" "F.Paste")
			(net "P3V3_ADC")
		)
	)
	(footprint ""
		(layer "F.Cu")
		(at 174.82566 -97.516188 90)
		(property "Reference" "R1330"
			(at 0 0 90)
			(layer "F.SilkS")
			(hide yes)
			(effects
				(font
					(size 1.27 1.27)
				)
			)
		)
		(property "Value" ""
			(at 0 0 90)
			(layer "F.Fab")
			(effects
				(font
					(size 1.27 1.27)
				)
			)
		)
		(duplicate_pad_numbers_are_jumpers no)
		(fp_line
			(start 0.7874 -0.4064)
			(end 0.7874 0.4064)
			(stroke
				(width 0.1524)
				(type default)
			)
			(layer "F.SilkS")
		)
		(fp_line
			(start -0.7874 -0.4064)
			(end 0.7874 -0.4064)
			(stroke
				(width 0.1524)
				(type default)
			)
			(layer "F.SilkS")
		)
		(fp_line
			(start 0.7874 0.4064)
			(end -0.7874 0.4064)
			(stroke
				(width 0.1524)
				(type default)
			)
			(layer "F.SilkS")
		)
		(fp_line
			(start -0.7874 0.4064)
			(end -0.7874 -0.4064)
			(stroke
				(width 0.1524)
				(type default)
			)
			(layer "F.SilkS")
		)
		(fp_line
			(start -0.12065 -0.305054)
			(end -0.12065 -0.2794)
			(stroke
				(width 0.1)
				(type default)
			)
			(layer "F.Fab")
		)
		(fp_line
			(start -0.67945 -0.305054)
			(end -0.12065 -0.305054)
			(stroke
				(width 0.1)
				(type default)
			)
			(layer "F.Fab")
		)
		(fp_line
			(start 0.67945 -0.3048)
			(end 0.67945 0.3048)
			(stroke
				(width 0.1)
				(type default)
			)
			(layer "F.Fab")
		)
		(fp_line
			(start 0.12065 -0.3048)
			(end 0.67945 -0.3048)
			(stroke
				(width 0.1)
				(type default)
			)
			(layer "F.Fab")
		)
		(fp_line
			(start 0.12065 -0.2794)
			(end 0.12065 -0.3048)
			(stroke
				(width 0.1)
				(type default)
			)
			(layer "F.Fab")
		)
		(fp_line
			(start -0.12065 -0.2794)
			(end 0.12065 -0.2794)
			(stroke
				(width 0.1)
				(type default)
			)
			(layer "F.Fab")
		)
		(fp_line
			(start 0.120396 0.2794)
			(end -0.12065 0.2794)
			(stroke
				(width 0.1)
				(type default)
			)
			(layer "F.Fab")
		)
		(fp_line
			(start -0.12065 0.2794)
			(end -0.12065 0.3048)
			(stroke
				(width 0.1)
				(type default)
			)
			(layer "F.Fab")
		)
		(fp_line
			(start 0.67945 0.3048)
			(end 0.120396 0.3048)
			(stroke
				(width 0.1)
				(type default)
			)
			(layer "F.Fab")
		)
		(fp_line
			(start 0.120396 0.3048)
			(end 0.120396 0.2794)
			(stroke
				(width 0.1)
				(type default)
			)
			(layer "F.Fab")
		)
		(fp_line
			(start -0.12065 0.3048)
			(end -0.67945 0.3048)
			(stroke
				(width 0.1)
				(type default)
			)
			(layer "F.Fab")
		)
		(fp_line
			(start -0.67945 0.3048)
			(end -0.67945 -0.305054)
			(stroke
				(width 0.1)
				(type default)
			)
			(layer "F.Fab")
		)
		(pad "1" smd circle
			(at -0.40005 0 90)
			(size 0 0)
			(layers "F.Cu" "F.Mask" "F.Paste")
			(net "PWRGD_DRAMPWRGD_CPU1_CD_R_LVC1")
		)
		(pad "2" smd circle
			(at 0.40005 0 90)
			(size 0 0)
			(layers "F.Cu" "F.Mask" "F.Paste")
			(net "GND")
		)
	)
	(footprint ""
		(layer "F.Cu")
		(at 374.00484 -336.935572 -90)
		(property "Reference" "PC251_P0_5"
			(at 0 0 270)
			(layer "F.SilkS")
			(hide yes)
			(effects
				(font
					(size 1.27 1.27)
				)
			)
		)
		(property "Value" ""
			(at 0 0 270)
			(layer "F.Fab")
			(effects
				(font
					(size 1.27 1.27)
				)
			)
		)
		(duplicate_pad_numbers_are_jumpers no)
		(fp_line
			(start -0.7874 0.4064)
			(end -0.7874 -0.4064)
			(stroke
				(width 0.1524)
				(type default)
			)
			(layer "F.SilkS")
		)
		(fp_line
			(start 0.7874 0.4064)
			(end -0.7874 0.4064)
			(stroke
				(width 0.1524)
				(type default)
			)
			(layer "F.SilkS")
		)
		(fp_line
			(start -0.7874 -0.4064)
			(end 0.7874 -0.4064)
			(stroke
				(width 0.1524)
				(type default)
			)
			(layer "F.SilkS")
		)
		(fp_line
			(start 0.7874 -0.4064)
			(end 0.7874 0.4064)
			(stroke
				(width 0.1524)
				(type default)
			)
			(layer "F.SilkS")
		)
		(fp_line
			(start -0.67945 0.3048)
			(end -0.67945 -0.305054)
			(stroke
				(width 0.1)
				(type default)
			)
			(layer "F.Fab")
		)
		(fp_line
			(start -0.12065 0.3048)
			(end -0.67945 0.3048)
			(stroke
				(width 0.1)
				(type default)
			)
			(layer "F.Fab")
		)
		(fp_line
			(start 0.120396 0.3048)
			(end 0.120396 0.2794)
			(stroke
				(width 0.1)
				(type default)
			)
			(layer "F.Fab")
		)
		(fp_line
			(start 0.67945 0.3048)
			(end 0.120396 0.3048)
			(stroke
				(width 0.1)
				(type default)
			)
			(layer "F.Fab")
		)
		(fp_line
			(start -0.12065 0.2794)
			(end -0.12065 0.3048)
			(stroke
				(width 0.1)
				(type default)
			)
			(layer "F.Fab")
		)
		(fp_line
			(start 0.120396 0.2794)
			(end -0.12065 0.2794)
			(stroke
				(width 0.1)
				(type default)
			)
			(layer "F.Fab")
		)
		(fp_line
			(start -0.12065 -0.2794)
			(end 0.12065 -0.2794)
			(stroke
				(width 0.1)
				(type default)
			)
			(layer "F.Fab")
		)
		(fp_line
			(start 0.12065 -0.2794)
			(end 0.12065 -0.3048)
			(stroke
				(width 0.1)
				(type default)
			)
			(layer "F.Fab")
		)
		(fp_line
			(start 0.12065 -0.3048)
			(end 0.67945 -0.3048)
			(stroke
				(width 0.1)
				(type default)
			)
			(layer "F.Fab")
		)
		(fp_line
			(start 0.67945 -0.3048)
			(end 0.67945 0.3048)
			(stroke
				(width 0.1)
				(type default)
			)
			(layer "F.Fab")
		)
		(fp_line
			(start -0.67945 -0.305054)
			(end -0.12065 -0.305054)
			(stroke
				(width 0.1)
				(type default)
			)
			(layer "F.Fab")
		)
		(fp_line
			(start -0.12065 -0.305054)
			(end -0.12065 -0.2794)
			(stroke
				(width 0.1)
				(type default)
			)
			(layer "F.Fab")
		)
		(pad "1" smd circle
			(at -0.40005 0 270)
			(size 0 0)
			(layers "F.Cu" "F.Mask" "F.Paste")
			(net "PVCCIN_CPU0_PVCC")
		)
		(pad "2" smd circle
			(at 0.40005 0 270)
			(size 0 0)
			(layers "F.Cu" "F.Mask" "F.Paste")
			(net "GND")
		)
	)
	(footprint ""
		(layer "F.Cu")
		(at 148.197824 -51.404012)
		(property "Reference" "R3611"
			(at 0 0 0)
			(layer "F.SilkS")
			(hide yes)
			(effects
				(font
					(size 1.27 1.27)
				)
			)
		)
		(property "Value" ""
			(at 0 0 0)
			(layer "F.Fab")
			(effects
				(font
					(size 1.27 1.27)
				)
			)
		)
		(duplicate_pad_numbers_are_jumpers no)
		(fp_line
			(start -0.7874 -0.4064)
			(end 0.7874 -0.4064)
			(stroke
				(width 0.1524)
				(type default)
			)
			(layer "F.SilkS")
		)
		(fp_line
			(start -0.7874 0.4064)
			(end -0.7874 -0.4064)
			(stroke
				(width 0.1524)
				(type default)
			)
			(layer "F.SilkS")
		)
		(fp_line
			(start 0.7874 -0.4064)
			(end 0.7874 0.4064)
			(stroke
				(width 0.1524)
				(type default)
			)
			(layer "F.SilkS")
		)
		(fp_line
			(start 0.7874 0.4064)
			(end -0.7874 0.4064)
			(stroke
				(width 0.1524)
				(type default)
			)
			(layer "F.SilkS")
		)
		(fp_line
			(start -0.67945 -0.305054)
			(end -0.12065 -0.305054)
			(stroke
				(width 0.1)
				(type default)
			)
			(layer "F.Fab")
		)
		(fp_line
			(start -0.67945 0.3048)
			(end -0.67945 -0.305054)
			(stroke
				(width 0.1)
				(type default)
			)
			(layer "F.Fab")
		)
		(fp_line
			(start -0.12065 -0.305054)
			(end -0.12065 -0.2794)
			(stroke
				(width 0.1)
				(type default)
			)
			(layer "F.Fab")
		)
		(fp_line
			(start -0.12065 -0.2794)
			(end 0.12065 -0.2794)
			(stroke
				(width 0.1)
				(type default)
			)
			(layer "F.Fab")
		)
		(fp_line
			(start -0.12065 0.2794)
			(end -0.12065 0.3048)
			(stroke
				(width 0.1)
				(type default)
			)
			(layer "F.Fab")
		)
		(fp_line
			(start -0.12065 0.3048)
			(end -0.67945 0.3048)
			(stroke
				(width 0.1)
				(type default)
			)
			(layer "F.Fab")
		)
		(fp_line
			(start 0.120396 0.2794)
			(end -0.12065 0.2794)
			(stroke
				(width 0.1)
				(type default)
			)
			(layer "F.Fab")
		)
		(fp_line
			(start 0.120396 0.3048)
			(end 0.120396 0.2794)
			(stroke
				(width 0.1)
				(type default)
			)
			(layer "F.Fab")
		)
		(fp_line
			(start 0.12065 -0.3048)
			(end 0.67945 -0.3048)
			(stroke
				(width 0.1)
				(type default)
			)
			(layer "F.Fab")
		)
		(fp_line
			(start 0.12065 -0.2794)
			(end 0.12065 -0.3048)
			(stroke
				(width 0.1)
				(type default)
			)
			(layer "F.Fab")
		)
		(fp_line
			(start 0.67945 -0.3048)
			(end 0.67945 0.3048)
			(stroke
				(width 0.1)
				(type default)
			)
			(layer "F.Fab")
		)
		(fp_line
			(start 0.67945 0.3048)
			(end 0.120396 0.3048)
			(stroke
				(width 0.1)
				(type default)
			)
			(layer "F.Fab")
		)
		(pad "1" smd circle
			(at -0.40005 0)
			(size 0 0)
			(layers "F.Cu" "F.Mask" "F.Paste")
			(net "GND")
		)
		(pad "2" smd circle
			(at 0.40005 0)
			(size 0 0)
			(layers "F.Cu" "F.Mask" "F.Paste")
			(net "INA230_4_A0")
		)
	)
	(footprint ""
		(layer "F.Cu")
		(at 176.17948 -422.366948 180)
		(property "Reference" "R2911"
			(at 0 0 180)
			(layer "F.SilkS")
			(hide yes)
			(effects
				(font
					(size 1.27 1.27)
				)
			)
		)
		(property "Value" ""
			(at 0 0 180)
			(layer "F.Fab")
			(effects
				(font
					(size 1.27 1.27)
				)
			)
		)
		(duplicate_pad_numbers_are_jumpers no)
		(fp_line
			(start 0.7874 0.4064)
			(end -0.7874 0.4064)
			(stroke
				(width 0.1524)
				(type default)
			)
			(layer "F.SilkS")
		)
		(fp_line
			(start 0.7874 -0.4064)
			(end 0.7874 0.4064)
			(stroke
				(width 0.1524)
				(type default)
			)
			(layer "F.SilkS")
		)
		(fp_line
			(start -0.7874 0.4064)
			(end -0.7874 -0.4064)
			(stroke
				(width 0.1524)
				(type default)
			)
			(layer "F.SilkS")
		)
		(fp_line
			(start -0.7874 -0.4064)
			(end 0.7874 -0.4064)
			(stroke
				(width 0.1524)
				(type default)
			)
			(layer "F.SilkS")
		)
		(fp_line
			(start 0.67945 0.3048)
			(end 0.120396 0.3048)
			(stroke
				(width 0.1)
				(type default)
			)
			(layer "F.Fab")
		)
		(fp_line
			(start 0.67945 -0.3048)
			(end 0.67945 0.3048)
			(stroke
				(width 0.1)
				(type default)
			)
			(layer "F.Fab")
		)
		(fp_line
			(start 0.12065 -0.2794)
			(end 0.12065 -0.3048)
			(stroke
				(width 0.1)
				(type default)
			)
			(layer "F.Fab")
		)
		(fp_line
			(start 0.12065 -0.3048)
			(end 0.67945 -0.3048)
			(stroke
				(width 0.1)
				(type default)
			)
			(layer "F.Fab")
		)
		(fp_line
			(start 0.120396 0.3048)
			(end 0.120396 0.2794)
			(stroke
				(width 0.1)
				(type default)
			)
			(layer "F.Fab")
		)
		(fp_line
			(start 0.120396 0.2794)
			(end -0.12065 0.2794)
			(stroke
				(width 0.1)
				(type default)
			)
			(layer "F.Fab")
		)
		(fp_line
			(start -0.12065 0.3048)
			(end -0.67945 0.3048)
			(stroke
				(width 0.1)
				(type default)
			)
			(layer "F.Fab")
		)
		(fp_line
			(start -0.12065 0.2794)
			(end -0.12065 0.3048)
			(stroke
				(width 0.1)
				(type default)
			)
			(layer "F.Fab")
		)
		(fp_line
			(start -0.12065 -0.2794)
			(end 0.12065 -0.2794)
			(stroke
				(width 0.1)
				(type default)
			)
			(layer "F.Fab")
		)
		(fp_line
			(start -0.12065 -0.305054)
			(end -0.12065 -0.2794)
			(stroke
				(width 0.1)
				(type default)
			)
			(layer "F.Fab")
		)
		(fp_line
			(start -0.67945 0.3048)
			(end -0.67945 -0.305054)
			(stroke
				(width 0.1)
				(type default)
			)
			(layer "F.Fab")
		)
		(fp_line
			(start -0.67945 -0.305054)
			(end -0.12065 -0.305054)
			(stroke
				(width 0.1)
				(type default)
			)
			(layer "F.Fab")
		)
		(pad "1" smd circle
			(at -0.40005 0 180)
			(size 0 0)
			(layers "F.Cu" "F.Mask" "F.Paste")
			(net "P3V3_AUX")
		)
		(pad "2" smd circle
			(at 0.40005 0 180)
			(size 0 0)
			(layers "F.Cu" "F.Mask" "F.Paste")
			(net "RST_SWB_BIC_BUF_R_N")
		)
	)
	(footprint ""
		(layer "F.Cu")
		(at 253.08941 -44.849542 90)
		(property "Reference" "PR3968"
			(at 0 0 90)
			(layer "F.SilkS")
			(hide yes)
			(effects
				(font
					(size 1.27 1.27)
				)
			)
		)
		(property "Value" ""
			(at 0 0 90)
			(layer "F.Fab")
			(effects
				(font
					(size 1.27 1.27)
				)
			)
		)
		(duplicate_pad_numbers_are_jumpers no)
		(fp_line
			(start 0.7874 -0.4064)
			(end 0.7874 0.4064)
			(stroke
				(width 0.1524)
				(type default)
			)
			(layer "F.SilkS")
		)
		(fp_line
			(start -0.7874 -0.4064)
			(end 0.7874 -0.4064)
			(stroke
				(width 0.1524)
				(type default)
			)
			(layer "F.SilkS")
		)
		(fp_line
			(start 0.7874 0.4064)
			(end -0.7874 0.4064)
			(stroke
				(width 0.1524)
				(type default)
			)
			(layer "F.SilkS")
		)
		(fp_line
			(start -0.7874 0.4064)
			(end -0.7874 -0.4064)
			(stroke
				(width 0.1524)
				(type default)
			)
			(layer "F.SilkS")
		)
		(fp_line
			(start -0.12065 -0.305054)
			(end -0.12065 -0.2794)
			(stroke
				(width 0.1)
				(type default)
			)
			(layer "F.Fab")
		)
		(fp_line
			(start -0.67945 -0.305054)
			(end -0.12065 -0.305054)
			(stroke
				(width 0.1)
				(type default)
			)
			(layer "F.Fab")
		)
		(fp_line
			(start 0.67945 -0.3048)
			(end 0.67945 0.3048)
			(stroke
				(width 0.1)
				(type default)
			)
			(layer "F.Fab")
		)
		(fp_line
			(start 0.12065 -0.3048)
			(end 0.67945 -0.3048)
			(stroke
				(width 0.1)
				(type default)
			)
			(layer "F.Fab")
		)
		(fp_line
			(start 0.12065 -0.2794)
			(end 0.12065 -0.3048)
			(stroke
				(width 0.1)
				(type default)
			)
			(layer "F.Fab")
		)
		(fp_line
			(start -0.12065 -0.2794)
			(end 0.12065 -0.2794)
			(stroke
				(width 0.1)
				(type default)
			)
			(layer "F.Fab")
		)
		(fp_line
			(start 0.120396 0.2794)
			(end -0.12065 0.2794)
			(stroke
				(width 0.1)
				(type default)
			)
			(layer "F.Fab")
		)
		(fp_line
			(start -0.12065 0.2794)
			(end -0.12065 0.3048)
			(stroke
				(width 0.1)
				(type default)
			)
			(layer "F.Fab")
		)
		(fp_line
			(start 0.67945 0.3048)
			(end 0.120396 0.3048)
			(stroke
				(width 0.1)
				(type default)
			)
			(layer "F.Fab")
		)
		(fp_line
			(start 0.120396 0.3048)
			(end 0.120396 0.2794)
			(stroke
				(width 0.1)
				(type default)
			)
			(layer "F.Fab")
		)
		(fp_line
			(start -0.12065 0.3048)
			(end -0.67945 0.3048)
			(stroke
				(width 0.1)
				(type default)
			)
			(layer "F.Fab")
		)
		(fp_line
			(start -0.67945 0.3048)
			(end -0.67945 -0.305054)
			(stroke
				(width 0.1)
				(type default)
			)
			(layer "F.Fab")
		)
		(pad "1" smd circle
			(at -0.40005 0 90)
			(size 0 0)
			(layers "F.Cu" "F.Mask" "F.Paste")
			(net "P12V_E1S_CB_0")
		)
		(pad "2" smd circle
			(at 0.40005 0 90)
			(size 0 0)
			(layers "F.Cu" "F.Mask" "F.Paste")
			(net "GND")
		)
	)
	(footprint ""
		(layer "F.Cu")
		(at 287.979866 -419.999922)
		(property "Reference" "H129"
			(at -3.46456 -4.95681 0)
			(unlocked yes)
			(layer "F.SilkS")
			(effects
				(font
					(size 0.7874 0.5842)
					(thickness 0.1524)
				)
				(justify left)
			)
		)
		(property "Value" ""
			(at 0 0 0)
			(layer "F.Fab")
			(effects
				(font
					(size 1.27 1.27)
				)
			)
		)
		(duplicate_pad_numbers_are_jumpers no)
		(pad "1" thru_hole circle
			(at 0 0)
			(size 8.001 8.001)
			(drill 4.2164)
			(layers "*.Cu" "*.Mask")
			(remove_unused_layers no)
			(net "GND")
			(clearance -1.6383)
		)
	)
	(footprint ""
		(layer "F.Cu")
		(at 463.562954 -92.387674)
		(property "Reference" "R3233"
			(at 0 0 0)
			(layer "F.SilkS")
			(hide yes)
			(effects
				(font
					(size 1.27 1.27)
				)
			)
		)
		(property "Value" ""
			(at 0 0 0)
			(layer "F.Fab")
			(effects
				(font
					(size 1.27 1.27)
				)
			)
		)
		(duplicate_pad_numbers_are_jumpers no)
		(fp_line
			(start -0.7874 -0.4064)
			(end 0.7874 -0.4064)
			(stroke
				(width 0.1524)
				(type default)
			)
			(layer "F.SilkS")
		)
		(fp_line
			(start -0.7874 0.4064)
			(end -0.7874 -0.4064)
			(stroke
				(width 0.1524)
				(type default)
			)
			(layer "F.SilkS")
		)
		(fp_line
			(start 0.7874 -0.4064)
			(end 0.7874 0.4064)
			(stroke
				(width 0.1524)
				(type default)
			)
			(layer "F.SilkS")
		)
		(fp_line
			(start 0.7874 0.4064)
			(end -0.7874 0.4064)
			(stroke
				(width 0.1524)
				(type default)
			)
			(layer "F.SilkS")
		)
		(fp_line
			(start -0.67945 -0.305054)
			(end -0.12065 -0.305054)
			(stroke
				(width 0.1)
				(type default)
			)
			(layer "F.Fab")
		)
		(fp_line
			(start -0.67945 0.3048)
			(end -0.67945 -0.305054)
			(stroke
				(width 0.1)
				(type default)
			)
			(layer "F.Fab")
		)
		(fp_line
			(start -0.12065 -0.305054)
			(end -0.12065 -0.2794)
			(stroke
				(width 0.1)
				(type default)
			)
			(layer "F.Fab")
		)
		(fp_line
			(start -0.12065 -0.2794)
			(end 0.12065 -0.2794)
			(stroke
				(width 0.1)
				(type default)
			)
			(layer "F.Fab")
		)
		(fp_line
			(start -0.12065 0.2794)
			(end -0.12065 0.3048)
			(stroke
				(width 0.1)
				(type default)
			)
			(layer "F.Fab")
		)
		(fp_line
			(start -0.12065 0.3048)
			(end -0.67945 0.3048)
			(stroke
				(width 0.1)
				(type default)
			)
			(layer "F.Fab")
		)
		(fp_line
			(start 0.120396 0.2794)
			(end -0.12065 0.2794)
			(stroke
				(width 0.1)
				(type default)
			)
			(layer "F.Fab")
		)
		(fp_line
			(start 0.120396 0.3048)
			(end 0.120396 0.2794)
			(stroke
				(width 0.1)
				(type default)
			)
			(layer "F.Fab")
		)
		(fp_line
			(start 0.12065 -0.3048)
			(end 0.67945 -0.3048)
			(stroke
				(width 0.1)
				(type default)
			)
			(layer "F.Fab")
		)
		(fp_line
			(start 0.12065 -0.2794)
			(end 0.12065 -0.3048)
			(stroke
				(width 0.1)
				(type default)
			)
			(layer "F.Fab")
		)
		(fp_line
			(start 0.67945 -0.3048)
			(end 0.67945 0.3048)
			(stroke
				(width 0.1)
				(type default)
			)
			(layer "F.Fab")
		)
		(fp_line
			(start 0.67945 0.3048)
			(end 0.120396 0.3048)
			(stroke
				(width 0.1)
				(type default)
			)
			(layer "F.Fab")
		)
		(pad "1" smd circle
			(at -0.40005 0)
			(size 0 0)
			(layers "F.Cu" "F.Mask" "F.Paste")
			(net "RST_HP_OCP_SFF_R_N")
		)
		(pad "2" smd circle
			(at 0.40005 0)
			(size 0 0)
			(layers "F.Cu" "F.Mask" "F.Paste")
			(net "RST_SMB_OCP_SFF_N")
		)
	)
	(footprint ""
		(layer "F.Cu")
		(at 107.975146 -99.609402)
		(property "Reference" "Q86"
			(at 2.133854 -1.933956 0)
			(unlocked yes)
			(layer "F.SilkS")
			(effects
				(font
					(size 0.7874 0.5842)
					(thickness 0.1524)
				)
				(justify left)
			)
		)
		(property "Value" ""
			(at 0 0 0)
			(layer "F.Fab")
			(effects
				(font
					(size 1.27 1.27)
				)
			)
		)
		(duplicate_pad_numbers_are_jumpers no)
		(fp_line
			(start -1.332738 -1.100074)
			(end -0.4826 -1.100074)
			(stroke
				(width 0.1524)
				(type default)
			)
			(layer "F.SilkS")
		)
		(fp_line
			(start -1.332738 1.100074)
			(end -1.332738 -1.100074)
			(stroke
				(width 0.1524)
				(type default)
			)
			(layer "F.SilkS")
		)
		(fp_line
			(start -0.4826 -1.100074)
			(end 0 -0.541274)
			(stroke
				(width 0.1524)
				(type default)
			)
			(layer "F.SilkS")
		)
		(fp_line
			(start 0 -0.541274)
			(end 0.4826 -1.100074)
			(stroke
				(width 0.1524)
				(type default)
			)
			(layer "F.SilkS")
		)
		(fp_line
			(start 0.4826 -1.100074)
			(end 1.332738 -1.100074)
			(stroke
				(width 0.1524)
				(type default)
			)
			(layer "F.SilkS")
		)
		(fp_line
			(start 1.332738 -1.100074)
			(end 1.332738 1.100074)
			(stroke
				(width 0.1524)
				(type default)
			)
			(layer "F.SilkS")
		)
		(fp_line
			(start 1.332738 1.100074)
			(end -1.332738 1.100074)
			(stroke
				(width 0.1524)
				(type default)
			)
			(layer "F.SilkS")
		)
		(fp_poly
			(pts
				(xy -0.634238 -1.97358) (xy -0.985266 -1.271524) (xy -1.336294 -1.97358)
			)
			(stroke
				(width 0)
				(type default)
			)
			(fill yes)
			(layer "F.SilkS")
		)
		(fp_line
			(start -0.674878 -1.100074)
			(end 0.674878 -1.100074)
			(stroke
				(width 0.1)
				(type default)
			)
			(layer "F.Fab")
		)
		(fp_line
			(start -0.674878 1.100074)
			(end -0.674878 -1.100074)
			(stroke
				(width 0.1)
				(type default)
			)
			(layer "F.Fab")
		)
		(fp_line
			(start 0.674878 -1.100074)
			(end 0.674878 1.100074)
			(stroke
				(width 0.1)
				(type default)
			)
			(layer "F.Fab")
		)
		(fp_line
			(start 0.674878 1.100074)
			(end -0.674878 1.100074)
			(stroke
				(width 0.1)
				(type default)
			)
			(layer "F.Fab")
		)
		(fp_poly
			(pts
				(xy -2.2352 -0.298958) (xy -2.2352 -1.001014) (xy -1.533144 -0.649986)
			)
			(stroke
				(width 0)
				(type default)
			)
			(fill yes)
			(layer "F.Fab")
		)
		(pad "1" smd rect
			(at -0.94996 -0.649986 90)
			(size 0.4318 0.508)
			(layers "F.Cu" "F.Mask" "F.Paste")
			(net "GND")
		)
		(pad "2" smd rect
			(at -0.94996 0 90)
			(size 0.4318 0.508)
			(layers "F.Cu" "F.Mask" "F.Paste")
			(net "PWRGD_PVCCINFAON_CPU1")
		)
		(pad "3" smd rect
			(at -0.94996 0.649986 90)
			(size 0.4318 0.508)
			(layers "F.Cu" "F.Mask" "F.Paste")
			(net "LED_PWRGD_PVNN_MAIN_CPU1_D")
		)
		(pad "4" smd rect
			(at 0.94996 0.649986 90)
			(size 0.4318 0.508)
			(layers "F.Cu" "F.Mask" "F.Paste")
			(net "GND")
		)
		(pad "5" smd rect
			(at 0.94996 0 90)
			(size 0.4318 0.508)
			(layers "F.Cu" "F.Mask" "F.Paste")
			(net "PWRGD_PVNN_MAIN_CPU1")
		)
		(pad "6" smd rect
			(at 0.94996 -0.649986 90)
			(size 0.4318 0.508)
			(layers "F.Cu" "F.Mask" "F.Paste")
			(net "LED_PWRGD_PVCCINFAON_CPU1_D")
		)
	)
	(footprint ""
		(layer "F.Cu")
		(at 101.219 -40.231568)
		(property "Reference" "U207"
			(at -1.778 -1.819148 0)
			(unlocked yes)
			(layer "F.SilkS")
			(effects
				(font
					(size 0.7874 0.5842)
					(thickness 0.1524)
				)
				(justify left)
			)
		)
		(property "Value" ""
			(at 0 0 0)
			(layer "F.Fab")
			(effects
				(font
					(size 1.27 1.27)
				)
			)
		)
		(duplicate_pad_numbers_are_jumpers no)
		(fp_line
			(start -1.695958 -1.124966)
			(end 1.695958 -1.124966)
			(stroke
				(width 0.1524)
				(type default)
			)
			(layer "F.SilkS")
		)
		(fp_line
			(start -1.695958 1.124966)
			(end -1.695958 -1.124966)
			(stroke
				(width 0.1524)
				(type default)
			)
			(layer "F.SilkS")
		)
		(fp_line
			(start 1.695958 -1.124966)
			(end 1.695958 1.124966)
			(stroke
				(width 0.1524)
				(type default)
			)
			(layer "F.SilkS")
		)
		(fp_line
			(start 1.695958 1.124966)
			(end -1.695958 1.124966)
			(stroke
				(width 0.1524)
				(type default)
			)
			(layer "F.SilkS")
		)
		(fp_poly
			(pts
				(xy -1.96342 -0.680466) (xy -2.58318 -0.370586) (xy -2.58318 -0.990346)
			)
			(stroke
				(width 0)
				(type default)
			)
			(fill yes)
			(layer "F.SilkS")
		)
		(fp_line
			(start -0.674878 -1.124966)
			(end 0.674878 -1.124966)
			(stroke
				(width 0.1)
				(type default)
			)
			(layer "F.Fab")
		)
		(fp_line
			(start -0.674878 1.124966)
			(end -0.674878 -1.124966)
			(stroke
				(width 0.1)
				(type default)
			)
			(layer "F.Fab")
		)
		(fp_line
			(start 0.674878 -1.124966)
			(end 0.674878 1.124966)
			(stroke
				(width 0.1)
				(type default)
			)
			(layer "F.Fab")
		)
		(fp_line
			(start 0.674878 1.124966)
			(end -0.674878 1.124966)
			(stroke
				(width 0.1)
				(type default)
			)
			(layer "F.Fab")
		)
		(fp_poly
			(pts
				(xy -2.4892 -0.959866) (xy -1.86944 -0.649986) (xy -2.4892 -0.340106)
			)
			(stroke
				(width 0)
				(type default)
			)
			(fill yes)
			(layer "F.Fab")
		)
		(pad "1" smd rect
			(at -0.94488 -0.649986 90)
			(size 0.3556 1.2446)
			(layers "F.Cu" "F.Mask" "F.Paste")
			(net "Net_1690")
		)
		(pad "2" smd rect
			(at -0.94488 0 90)
			(size 0.3556 1.2446)
			(layers "F.Cu" "F.Mask" "F.Paste")
			(net "RST_HP_OCP_V3_2_N")
		)
		(pad "3" smd rect
			(at -0.94488 0.649986 90)
			(size 0.3556 1.2446)
			(layers "F.Cu" "F.Mask" "F.Paste")
			(net "GND")
		)
		(pad "4" smd rect
			(at 0.94488 0.649986 90)
			(size 0.3556 1.2446)
			(layers "F.Cu" "F.Mask" "F.Paste")
			(net "RST_OCP_V3_2_BUF_N")
		)
		(pad "5" smd rect
			(at 0.94488 -0.649986 90)
			(size 0.3556 1.2446)
			(layers "F.Cu" "F.Mask" "F.Paste")
			(net "P3V3_AUX")
		)
	)
	(footprint ""
		(layer "F.Cu")
		(at 22.64156 -169.604436 180)
		(property "Reference" "C2454"
			(at 0 0 180)
			(layer "F.SilkS")
			(hide yes)
			(effects
				(font
					(size 1.27 1.27)
				)
			)
		)
		(property "Value" ""
			(at 0 0 180)
			(layer "F.Fab")
			(effects
				(font
					(size 1.27 1.27)
				)
			)
		)
		(duplicate_pad_numbers_are_jumpers no)
		(fp_line
			(start 0.7874 0.4064)
			(end -0.7874 0.4064)
			(stroke
				(width 0.1524)
				(type default)
			)
			(layer "F.SilkS")
		)
		(fp_line
			(start 0.7874 -0.4064)
			(end 0.7874 0.4064)
			(stroke
				(width 0.1524)
				(type default)
			)
			(layer "F.SilkS")
		)
		(fp_line
			(start -0.7874 0.4064)
			(end -0.7874 -0.4064)
			(stroke
				(width 0.1524)
				(type default)
			)
			(layer "F.SilkS")
		)
		(fp_line
			(start -0.7874 -0.4064)
			(end 0.7874 -0.4064)
			(stroke
				(width 0.1524)
				(type default)
			)
			(layer "F.SilkS")
		)
		(fp_line
			(start 0.67945 0.3048)
			(end 0.120396 0.3048)
			(stroke
				(width 0.1)
				(type default)
			)
			(layer "F.Fab")
		)
		(fp_line
			(start 0.67945 -0.3048)
			(end 0.67945 0.3048)
			(stroke
				(width 0.1)
				(type default)
			)
			(layer "F.Fab")
		)
		(fp_line
			(start 0.12065 -0.2794)
			(end 0.12065 -0.3048)
			(stroke
				(width 0.1)
				(type default)
			)
			(layer "F.Fab")
		)
		(fp_line
			(start 0.12065 -0.3048)
			(end 0.67945 -0.3048)
			(stroke
				(width 0.1)
				(type default)
			)
			(layer "F.Fab")
		)
		(fp_line
			(start 0.120396 0.3048)
			(end 0.120396 0.2794)
			(stroke
				(width 0.1)
				(type default)
			)
			(layer "F.Fab")
		)
		(fp_line
			(start 0.120396 0.2794)
			(end -0.12065 0.2794)
			(stroke
				(width 0.1)
				(type default)
			)
			(layer "F.Fab")
		)
		(fp_line
			(start -0.12065 0.3048)
			(end -0.67945 0.3048)
			(stroke
				(width 0.1)
				(type default)
			)
			(layer "F.Fab")
		)
		(fp_line
			(start -0.12065 0.2794)
			(end -0.12065 0.3048)
			(stroke
				(width 0.1)
				(type default)
			)
			(layer "F.Fab")
		)
		(fp_line
			(start -0.12065 -0.2794)
			(end 0.12065 -0.2794)
			(stroke
				(width 0.1)
				(type default)
			)
			(layer "F.Fab")
		)
		(fp_line
			(start -0.12065 -0.305054)
			(end -0.12065 -0.2794)
			(stroke
				(width 0.1)
				(type default)
			)
			(layer "F.Fab")
		)
		(fp_line
			(start -0.67945 0.3048)
			(end -0.67945 -0.305054)
			(stroke
				(width 0.1)
				(type default)
			)
			(layer "F.Fab")
		)
		(fp_line
			(start -0.67945 -0.305054)
			(end -0.12065 -0.305054)
			(stroke
				(width 0.1)
				(type default)
			)
			(layer "F.Fab")
		)
		(pad "1" smd circle
			(at -0.40005 0 180)
			(size 0 0)
			(layers "F.Cu" "F.Mask" "F.Paste")
			(net "PWRGD_PVCCD_HV_CPU1_R")
		)
		(pad "2" smd circle
			(at 0.40005 0 180)
			(size 0 0)
			(layers "F.Cu" "F.Mask" "F.Paste")
			(net "GND")
		)
	)
	(footprint ""
		(layer "F.Cu")
		(at 218.08948 -127.803148)
		(property "Reference" "C1318"
			(at 0 0 0)
			(layer "F.SilkS")
			(hide yes)
			(effects
				(font
					(size 1.27 1.27)
				)
			)
		)
		(property "Value" ""
			(at 0 0 0)
			(layer "F.Fab")
			(effects
				(font
					(size 1.27 1.27)
				)
			)
		)
		(duplicate_pad_numbers_are_jumpers no)
		(fp_line
			(start -0.7874 -0.4064)
			(end 0.7874 -0.4064)
			(stroke
				(width 0.1524)
				(type default)
			)
			(layer "F.SilkS")
		)
		(fp_line
			(start -0.7874 0.4064)
			(end -0.7874 -0.4064)
			(stroke
				(width 0.1524)
				(type default)
			)
			(layer "F.SilkS")
		)
		(fp_line
			(start 0.7874 -0.4064)
			(end 0.7874 0.4064)
			(stroke
				(width 0.1524)
				(type default)
			)
			(layer "F.SilkS")
		)
		(fp_line
			(start 0.7874 0.4064)
			(end -0.7874 0.4064)
			(stroke
				(width 0.1524)
				(type default)
			)
			(layer "F.SilkS")
		)
		(fp_line
			(start -0.67945 -0.305054)
			(end -0.12065 -0.305054)
			(stroke
				(width 0.1)
				(type default)
			)
			(layer "F.Fab")
		)
		(fp_line
			(start -0.67945 0.3048)
			(end -0.67945 -0.305054)
			(stroke
				(width 0.1)
				(type default)
			)
			(layer "F.Fab")
		)
		(fp_line
			(start -0.12065 -0.305054)
			(end -0.12065 -0.2794)
			(stroke
				(width 0.1)
				(type default)
			)
			(layer "F.Fab")
		)
		(fp_line
			(start -0.12065 -0.2794)
			(end 0.12065 -0.2794)
			(stroke
				(width 0.1)
				(type default)
			)
			(layer "F.Fab")
		)
		(fp_line
			(start -0.12065 0.2794)
			(end -0.12065 0.3048)
			(stroke
				(width 0.1)
				(type default)
			)
			(layer "F.Fab")
		)
		(fp_line
			(start -0.12065 0.3048)
			(end -0.67945 0.3048)
			(stroke
				(width 0.1)
				(type default)
			)
			(layer "F.Fab")
		)
		(fp_line
			(start 0.120396 0.2794)
			(end -0.12065 0.2794)
			(stroke
				(width 0.1)
				(type default)
			)
			(layer "F.Fab")
		)
		(fp_line
			(start 0.120396 0.3048)
			(end 0.120396 0.2794)
			(stroke
				(width 0.1)
				(type default)
			)
			(layer "F.Fab")
		)
		(fp_line
			(start 0.12065 -0.3048)
			(end 0.67945 -0.3048)
			(stroke
				(width 0.1)
				(type default)
			)
			(layer "F.Fab")
		)
		(fp_line
			(start 0.12065 -0.2794)
			(end 0.12065 -0.3048)
			(stroke
				(width 0.1)
				(type default)
			)
			(layer "F.Fab")
		)
		(fp_line
			(start 0.67945 -0.3048)
			(end 0.67945 0.3048)
			(stroke
				(width 0.1)
				(type default)
			)
			(layer "F.Fab")
		)
		(fp_line
			(start 0.67945 0.3048)
			(end 0.120396 0.3048)
			(stroke
				(width 0.1)
				(type default)
			)
			(layer "F.Fab")
		)
		(pad "1" smd circle
			(at -0.40005 0)
			(size 0 0)
			(layers "F.Cu" "F.Mask" "F.Paste")
			(net "PWRGD_DSW_PWROK_R1")
		)
		(pad "2" smd circle
			(at 0.40005 0)
			(size 0 0)
			(layers "F.Cu" "F.Mask" "F.Paste")
			(net "GND")
		)
	)
	(footprint ""
		(layer "F.Cu")
		(at 353.245928 -260.364986 -90)
		(property "Reference" "C409"
			(at 0 0 270)
			(layer "F.SilkS")
			(hide yes)
			(effects
				(font
					(size 1.27 1.27)
				)
			)
		)
		(property "Value" ""
			(at 0 0 270)
			(layer "F.Fab")
			(effects
				(font
					(size 1.27 1.27)
				)
			)
		)
		(duplicate_pad_numbers_are_jumpers no)
		(fp_line
			(start -0.7874 0.4064)
			(end -0.7874 -0.4064)
			(stroke
				(width 0.1524)
				(type default)
			)
			(layer "F.SilkS")
		)
		(fp_line
			(start 0.7874 0.4064)
			(end -0.7874 0.4064)
			(stroke
				(width 0.1524)
				(type default)
			)
			(layer "F.SilkS")
		)
		(fp_line
			(start -0.7874 -0.4064)
			(end 0.7874 -0.4064)
			(stroke
				(width 0.1524)
				(type default)
			)
			(layer "F.SilkS")
		)
		(fp_line
			(start 0.7874 -0.4064)
			(end 0.7874 0.4064)
			(stroke
				(width 0.1524)
				(type default)
			)
			(layer "F.SilkS")
		)
		(fp_line
			(start -0.67945 0.3048)
			(end -0.67945 -0.305054)
			(stroke
				(width 0.1)
				(type default)
			)
			(layer "F.Fab")
		)
		(fp_line
			(start -0.12065 0.3048)
			(end -0.67945 0.3048)
			(stroke
				(width 0.1)
				(type default)
			)
			(layer "F.Fab")
		)
		(fp_line
			(start 0.120396 0.3048)
			(end 0.120396 0.2794)
			(stroke
				(width 0.1)
				(type default)
			)
			(layer "F.Fab")
		)
		(fp_line
			(start 0.67945 0.3048)
			(end 0.120396 0.3048)
			(stroke
				(width 0.1)
				(type default)
			)
			(layer "F.Fab")
		)
		(fp_line
			(start -0.12065 0.2794)
			(end -0.12065 0.3048)
			(stroke
				(width 0.1)
				(type default)
			)
			(layer "F.Fab")
		)
		(fp_line
			(start 0.120396 0.2794)
			(end -0.12065 0.2794)
			(stroke
				(width 0.1)
				(type default)
			)
			(layer "F.Fab")
		)
		(fp_line
			(start -0.12065 -0.2794)
			(end 0.12065 -0.2794)
			(stroke
				(width 0.1)
				(type default)
			)
			(layer "F.Fab")
		)
		(fp_line
			(start 0.12065 -0.2794)
			(end 0.12065 -0.3048)
			(stroke
				(width 0.1)
				(type default)
			)
			(layer "F.Fab")
		)
		(fp_line
			(start 0.12065 -0.3048)
			(end 0.67945 -0.3048)
			(stroke
				(width 0.1)
				(type default)
			)
			(layer "F.Fab")
		)
		(fp_line
			(start 0.67945 -0.3048)
			(end 0.67945 0.3048)
			(stroke
				(width 0.1)
				(type default)
			)
			(layer "F.Fab")
		)
		(fp_line
			(start -0.67945 -0.305054)
			(end -0.12065 -0.305054)
			(stroke
				(width 0.1)
				(type default)
			)
			(layer "F.Fab")
		)
		(fp_line
			(start -0.12065 -0.305054)
			(end -0.12065 -0.2794)
			(stroke
				(width 0.1)
				(type default)
			)
			(layer "F.Fab")
		)
		(pad "1" smd circle
			(at -0.40005 0 270)
			(size 0 0)
			(layers "F.Cu" "F.Mask" "F.Paste")
			(net "PVCCFA_EHV_FIVRA_CPU0")
		)
		(pad "2" smd circle
			(at 0.40005 0 270)
			(size 0 0)
			(layers "F.Cu" "F.Mask" "F.Paste")
			(net "GND")
		)
	)
	(footprint ""
		(layer "F.Cu")
		(at 369.358418 -417.17341 90)
		(property "Reference" "R4190"
			(at 0 0 90)
			(layer "F.SilkS")
			(hide yes)
			(effects
				(font
					(size 1.27 1.27)
				)
			)
		)
		(property "Value" ""
			(at 0 0 90)
			(layer "F.Fab")
			(effects
				(font
					(size 1.27 1.27)
				)
			)
		)
		(duplicate_pad_numbers_are_jumpers no)
		(fp_line
			(start 0.7874 -0.4064)
			(end 0.7874 0.4064)
			(stroke
				(width 0.1524)
				(type default)
			)
			(layer "F.SilkS")
		)
		(fp_line
			(start -0.7874 -0.4064)
			(end 0.7874 -0.4064)
			(stroke
				(width 0.1524)
				(type default)
			)
			(layer "F.SilkS")
		)
		(fp_line
			(start 0.7874 0.4064)
			(end -0.7874 0.4064)
			(stroke
				(width 0.1524)
				(type default)
			)
			(layer "F.SilkS")
		)
		(fp_line
			(start -0.7874 0.4064)
			(end -0.7874 -0.4064)
			(stroke
				(width 0.1524)
				(type default)
			)
			(layer "F.SilkS")
		)
		(fp_line
			(start -0.12065 -0.305054)
			(end -0.12065 -0.2794)
			(stroke
				(width 0.1)
				(type default)
			)
			(layer "F.Fab")
		)
		(fp_line
			(start -0.67945 -0.305054)
			(end -0.12065 -0.305054)
			(stroke
				(width 0.1)
				(type default)
			)
			(layer "F.Fab")
		)
		(fp_line
			(start 0.67945 -0.3048)
			(end 0.67945 0.3048)
			(stroke
				(width 0.1)
				(type default)
			)
			(layer "F.Fab")
		)
		(fp_line
			(start 0.12065 -0.3048)
			(end 0.67945 -0.3048)
			(stroke
				(width 0.1)
				(type default)
			)
			(layer "F.Fab")
		)
		(fp_line
			(start 0.12065 -0.2794)
			(end 0.12065 -0.3048)
			(stroke
				(width 0.1)
				(type default)
			)
			(layer "F.Fab")
		)
		(fp_line
			(start -0.12065 -0.2794)
			(end 0.12065 -0.2794)
			(stroke
				(width 0.1)
				(type default)
			)
			(layer "F.Fab")
		)
		(fp_line
			(start 0.120396 0.2794)
			(end -0.12065 0.2794)
			(stroke
				(width 0.1)
				(type default)
			)
			(layer "F.Fab")
		)
		(fp_line
			(start -0.12065 0.2794)
			(end -0.12065 0.3048)
			(stroke
				(width 0.1)
				(type default)
			)
			(layer "F.Fab")
		)
		(fp_line
			(start 0.67945 0.3048)
			(end 0.120396 0.3048)
			(stroke
				(width 0.1)
				(type default)
			)
			(layer "F.Fab")
		)
		(fp_line
			(start 0.120396 0.3048)
			(end 0.120396 0.2794)
			(stroke
				(width 0.1)
				(type default)
			)
			(layer "F.Fab")
		)
		(fp_line
			(start -0.12065 0.3048)
			(end -0.67945 0.3048)
			(stroke
				(width 0.1)
				(type default)
			)
			(layer "F.Fab")
		)
		(fp_line
			(start -0.67945 0.3048)
			(end -0.67945 -0.305054)
			(stroke
				(width 0.1)
				(type default)
			)
			(layer "F.Fab")
		)
		(pad "1" smd circle
			(at -0.40005 0 90)
			(size 0 0)
			(layers "F.Cu" "F.Mask" "F.Paste")
			(net "P3V3_AUX")
		)
		(pad "2" smd circle
			(at 0.40005 0 90)
			(size 0 0)
			(layers "F.Cu" "F.Mask" "F.Paste")
			(net "U270_0_ADD2")
		)
	)
	(footprint ""
		(layer "F.Cu")
		(at 306.263294 -14.51102)
		(property "Reference" "R2487"
			(at 0 0 0)
			(layer "F.SilkS")
			(hide yes)
			(effects
				(font
					(size 1.27 1.27)
				)
			)
		)
		(property "Value" ""
			(at 0 0 0)
			(layer "F.Fab")
			(effects
				(font
					(size 1.27 1.27)
				)
			)
		)
		(duplicate_pad_numbers_are_jumpers no)
		(fp_line
			(start -0.7874 -0.4064)
			(end 0.7874 -0.4064)
			(stroke
				(width 0.1524)
				(type default)
			)
			(layer "F.SilkS")
		)
		(fp_line
			(start -0.7874 0.4064)
			(end -0.7874 -0.4064)
			(stroke
				(width 0.1524)
				(type default)
			)
			(layer "F.SilkS")
		)
		(fp_line
			(start 0.7874 -0.4064)
			(end 0.7874 0.4064)
			(stroke
				(width 0.1524)
				(type default)
			)
			(layer "F.SilkS")
		)
		(fp_line
			(start 0.7874 0.4064)
			(end -0.7874 0.4064)
			(stroke
				(width 0.1524)
				(type default)
			)
			(layer "F.SilkS")
		)
		(fp_line
			(start -0.67945 -0.305054)
			(end -0.12065 -0.305054)
			(stroke
				(width 0.1)
				(type default)
			)
			(layer "F.Fab")
		)
		(fp_line
			(start -0.67945 0.3048)
			(end -0.67945 -0.305054)
			(stroke
				(width 0.1)
				(type default)
			)
			(layer "F.Fab")
		)
		(fp_line
			(start -0.12065 -0.305054)
			(end -0.12065 -0.2794)
			(stroke
				(width 0.1)
				(type default)
			)
			(layer "F.Fab")
		)
		(fp_line
			(start -0.12065 -0.2794)
			(end 0.12065 -0.2794)
			(stroke
				(width 0.1)
				(type default)
			)
			(layer "F.Fab")
		)
		(fp_line
			(start -0.12065 0.2794)
			(end -0.12065 0.3048)
			(stroke
				(width 0.1)
				(type default)
			)
			(layer "F.Fab")
		)
		(fp_line
			(start -0.12065 0.3048)
			(end -0.67945 0.3048)
			(stroke
				(width 0.1)
				(type default)
			)
			(layer "F.Fab")
		)
		(fp_line
			(start 0.120396 0.2794)
			(end -0.12065 0.2794)
			(stroke
				(width 0.1)
				(type default)
			)
			(layer "F.Fab")
		)
		(fp_line
			(start 0.120396 0.3048)
			(end 0.120396 0.2794)
			(stroke
				(width 0.1)
				(type default)
			)
			(layer "F.Fab")
		)
		(fp_line
			(start 0.12065 -0.3048)
			(end 0.67945 -0.3048)
			(stroke
				(width 0.1)
				(type default)
			)
			(layer "F.Fab")
		)
		(fp_line
			(start 0.12065 -0.2794)
			(end 0.12065 -0.3048)
			(stroke
				(width 0.1)
				(type default)
			)
			(layer "F.Fab")
		)
		(fp_line
			(start 0.67945 -0.3048)
			(end 0.67945 0.3048)
			(stroke
				(width 0.1)
				(type default)
			)
			(layer "F.Fab")
		)
		(fp_line
			(start 0.67945 0.3048)
			(end 0.120396 0.3048)
			(stroke
				(width 0.1)
				(type default)
			)
			(layer "F.Fab")
		)
		(pad "1" smd circle
			(at -0.40005 0)
			(size 0 0)
			(layers "F.Cu" "F.Mask" "F.Paste")
			(net "P3V3_AUX")
		)
		(pad "2" smd circle
			(at 0.40005 0)
			(size 0 0)
			(layers "F.Cu" "F.Mask" "F.Paste")
			(net "IRQ_LVC3_WAKE_BUF_N")
		)
	)
	(footprint ""
		(layer "F.Cu")
		(at 155.194 -126.365 -90)
		(property "Reference" "R4638"
			(at 0 0 270)
			(layer "F.SilkS")
			(hide yes)
			(effects
				(font
					(size 1.27 1.27)
				)
			)
		)
		(property "Value" ""
			(at 0 0 270)
			(layer "F.Fab")
			(effects
				(font
					(size 1.27 1.27)
				)
			)
		)
		(duplicate_pad_numbers_are_jumpers no)
		(fp_line
			(start -2.234946 0.9271)
			(end -2.234946 -0.9271)
			(stroke
				(width 0.1524)
				(type default)
			)
			(layer "F.SilkS")
		)
		(fp_line
			(start 2.234946 0.9271)
			(end -2.234946 0.9271)
			(stroke
				(width 0.1524)
				(type default)
			)
			(layer "F.SilkS")
		)
		(fp_line
			(start -2.234946 -0.9271)
			(end 2.234946 -0.9271)
			(stroke
				(width 0.1524)
				(type default)
			)
			(layer "F.SilkS")
		)
		(fp_line
			(start 2.234946 -0.9271)
			(end 2.234946 0.9271)
			(stroke
				(width 0.1524)
				(type default)
			)
			(layer "F.SilkS")
		)
		(fp_line
			(start -1.575054 0.824992)
			(end 1.575054 0.824992)
			(stroke
				(width 0.1)
				(type default)
			)
			(layer "F.Fab")
		)
		(fp_line
			(start 1.575054 0.824992)
			(end 1.575054 -0.824992)
			(stroke
				(width 0.1)
				(type default)
			)
			(layer "F.Fab")
		)
		(fp_line
			(start -1.575054 -0.824992)
			(end -1.575054 0.824992)
			(stroke
				(width 0.1)
				(type default)
			)
			(layer "F.Fab")
		)
		(fp_line
			(start 1.575054 -0.824992)
			(end -1.575054 -0.824992)
			(stroke
				(width 0.1)
				(type default)
			)
			(layer "F.Fab")
		)
		(pad "1" smd rect
			(at -1.599946 0 270)
			(size 1.016 1.6002)
			(layers "F.Cu" "F.Mask" "F.Paste")
			(net "P5V")
		)
		(pad "2" smd rect
			(at 1.599946 0 270)
			(size 1.016 1.6002)
			(layers "F.Cu" "F.Mask" "F.Paste")
			(net "VR_P5V_EN_D")
		)
	)
	(footprint ""
		(layer "F.Cu")
		(at 129.69748 -327.79335)
		(property "Reference" "PL27"
			(at 4.329684 4.104894 0)
			(unlocked yes)
			(layer "F.SilkS")
			(effects
				(font
					(size 0.7874 0.5842)
					(thickness 0.1524)
				)
				(justify left)
			)
		)
		(property "Value" ""
			(at 0 0 0)
			(layer "F.Fab")
			(effects
				(font
					(size 1.27 1.27)
				)
			)
		)
		(duplicate_pad_numbers_are_jumpers no)
		(fp_line
			(start -3.750056 -5.500116)
			(end -2.393442 -5.500116)
			(stroke
				(width 0.1524)
				(type default)
			)
			(layer "F.SilkS")
		)
		(fp_line
			(start -3.750056 5.500116)
			(end -3.750056 -5.500116)
			(stroke
				(width 0.1524)
				(type default)
			)
			(layer "F.SilkS")
		)
		(fp_line
			(start -2.393442 5.500116)
			(end -3.750056 5.500116)
			(stroke
				(width 0.1524)
				(type default)
			)
			(layer "F.SilkS")
		)
		(fp_line
			(start 2.393442 5.500116)
			(end 3.750056 5.500116)
			(stroke
				(width 0.1524)
				(type default)
			)
			(layer "F.SilkS")
		)
		(fp_line
			(start 3.750056 -5.500116)
			(end 2.393442 -5.500116)
			(stroke
				(width 0.1524)
				(type default)
			)
			(layer "F.SilkS")
		)
		(fp_line
			(start 3.750056 5.500116)
			(end 3.750056 -5.500116)
			(stroke
				(width 0.1524)
				(type default)
			)
			(layer "F.SilkS")
		)
		(fp_poly
			(pts
				(xy -5.12318 -4.930648) (xy -4.10718 -4.422648) (xy -5.12318 -3.914648)
			)
			(stroke
				(width 0)
				(type default)
			)
			(fill yes)
			(layer "F.SilkS")
		)
		(fp_line
			(start -3.750056 -5.500116)
			(end -3.750056 5.500116)
			(stroke
				(width 0.1)
				(type default)
			)
			(layer "F.Fab")
		)
		(fp_line
			(start -3.750056 5.500116)
			(end 3.750056 5.500116)
			(stroke
				(width 0.1)
				(type default)
			)
			(layer "F.Fab")
		)
		(fp_line
			(start 3.750056 -5.500116)
			(end -3.750056 -5.500116)
			(stroke
				(width 0.1)
				(type default)
			)
			(layer "F.Fab")
		)
		(fp_line
			(start 3.750056 5.500116)
			(end 3.750056 -5.500116)
			(stroke
				(width 0.1)
				(type default)
			)
			(layer "F.Fab")
		)
		(fp_poly
			(pts
				(xy -4.9276 -4.757928) (xy -4.9276 -3.741928) (xy -3.9116 -4.249928)
			)
			(stroke
				(width 0)
				(type default)
			)
			(fill yes)
			(layer "F.Fab")
		)
		(pad "1" smd rect
			(at 0 -4.249928 270)
			(size 2.413 4.5212)
			(layers "F.Cu" "F.Mask" "F.Paste")
			(net "SW_PVCCIN_CPU1_SW5")
		)
		(pad "2" smd rect
			(at 0 -1.175004 270)
			(size 1.3716 4.5212)
			(layers "F.Cu" "F.Mask" "F.Paste")
			(net "IND_P1_CPL5")
		)
		(pad "3" smd rect
			(at 0 1.175004 270)
			(size 1.3716 4.5212)
			(layers "F.Cu" "F.Mask" "F.Paste")
			(net "IND_P1_CPL4")
		)
		(pad "4" smd rect
			(at 0 4.249928 270)
			(size 2.413 4.5212)
			(layers "F.Cu" "F.Mask" "F.Paste")
			(net "PVCCIN_CPU1")
		)
	)
	(footprint ""
		(layer "F.Cu")
		(at 140.00988 -43.652948 180)
		(property "Reference" "R3296"
			(at 0 0 180)
			(layer "F.SilkS")
			(hide yes)
			(effects
				(font
					(size 1.27 1.27)
				)
			)
		)
		(property "Value" ""
			(at 0 0 180)
			(layer "F.Fab")
			(effects
				(font
					(size 1.27 1.27)
				)
			)
		)
		(duplicate_pad_numbers_are_jumpers no)
		(fp_line
			(start 0.7874 0.4064)
			(end -0.7874 0.4064)
			(stroke
				(width 0.1524)
				(type default)
			)
			(layer "F.SilkS")
		)
		(fp_line
			(start 0.7874 -0.4064)
			(end 0.7874 0.4064)
			(stroke
				(width 0.1524)
				(type default)
			)
			(layer "F.SilkS")
		)
		(fp_line
			(start -0.7874 0.4064)
			(end -0.7874 -0.4064)
			(stroke
				(width 0.1524)
				(type default)
			)
			(layer "F.SilkS")
		)
		(fp_line
			(start -0.7874 -0.4064)
			(end 0.7874 -0.4064)
			(stroke
				(width 0.1524)
				(type default)
			)
			(layer "F.SilkS")
		)
		(fp_line
			(start 0.67945 0.3048)
			(end 0.120396 0.3048)
			(stroke
				(width 0.1)
				(type default)
			)
			(layer "F.Fab")
		)
		(fp_line
			(start 0.67945 -0.3048)
			(end 0.67945 0.3048)
			(stroke
				(width 0.1)
				(type default)
			)
			(layer "F.Fab")
		)
		(fp_line
			(start 0.12065 -0.2794)
			(end 0.12065 -0.3048)
			(stroke
				(width 0.1)
				(type default)
			)
			(layer "F.Fab")
		)
		(fp_line
			(start 0.12065 -0.3048)
			(end 0.67945 -0.3048)
			(stroke
				(width 0.1)
				(type default)
			)
			(layer "F.Fab")
		)
		(fp_line
			(start 0.120396 0.3048)
			(end 0.120396 0.2794)
			(stroke
				(width 0.1)
				(type default)
			)
			(layer "F.Fab")
		)
		(fp_line
			(start 0.120396 0.2794)
			(end -0.12065 0.2794)
			(stroke
				(width 0.1)
				(type default)
			)
			(layer "F.Fab")
		)
		(fp_line
			(start -0.12065 0.3048)
			(end -0.67945 0.3048)
			(stroke
				(width 0.1)
				(type default)
			)
			(layer "F.Fab")
		)
		(fp_line
			(start -0.12065 0.2794)
			(end -0.12065 0.3048)
			(stroke
				(width 0.1)
				(type default)
			)
			(layer "F.Fab")
		)
		(fp_line
			(start -0.12065 -0.2794)
			(end 0.12065 -0.2794)
			(stroke
				(width 0.1)
				(type default)
			)
			(layer "F.Fab")
		)
		(fp_line
			(start -0.12065 -0.305054)
			(end -0.12065 -0.2794)
			(stroke
				(width 0.1)
				(type default)
			)
			(layer "F.Fab")
		)
		(fp_line
			(start -0.67945 0.3048)
			(end -0.67945 -0.305054)
			(stroke
				(width 0.1)
				(type default)
			)
			(layer "F.Fab")
		)
		(fp_line
			(start -0.67945 -0.305054)
			(end -0.12065 -0.305054)
			(stroke
				(width 0.1)
				(type default)
			)
			(layer "F.Fab")
		)
		(pad "1" smd circle
			(at -0.40005 0 180)
			(size 0 0)
			(layers "F.Cu" "F.Mask" "F.Paste")
			(net "P3V3_AUX")
		)
		(pad "2" smd circle
			(at 0.40005 0 180)
			(size 0 0)
			(layers "F.Cu" "F.Mask" "F.Paste")
			(net "HDD_ACTIVITY_BUF")
		)
	)
	(footprint ""
		(layer "F.Cu")
		(at 220.087444 -101.24948 180)
		(property "Reference" "R4806"
			(at 0 0 180)
			(layer "F.SilkS")
			(hide yes)
			(effects
				(font
					(size 1.27 1.27)
				)
			)
		)
		(property "Value" ""
			(at 0 0 180)
			(layer "F.Fab")
			(effects
				(font
					(size 1.27 1.27)
				)
			)
		)
		(duplicate_pad_numbers_are_jumpers no)
		(fp_line
			(start 0.7874 0.4064)
			(end -0.7874 0.4064)
			(stroke
				(width 0.1524)
				(type default)
			)
			(layer "F.SilkS")
		)
		(fp_line
			(start 0.7874 -0.4064)
			(end 0.7874 0.4064)
			(stroke
				(width 0.1524)
				(type default)
			)
			(layer "F.SilkS")
		)
		(fp_line
			(start -0.7874 0.4064)
			(end -0.7874 -0.4064)
			(stroke
				(width 0.1524)
				(type default)
			)
			(layer "F.SilkS")
		)
		(fp_line
			(start -0.7874 -0.4064)
			(end 0.7874 -0.4064)
			(stroke
				(width 0.1524)
				(type default)
			)
			(layer "F.SilkS")
		)
		(fp_line
			(start 0.67945 0.3048)
			(end 0.120396 0.3048)
			(stroke
				(width 0.1)
				(type default)
			)
			(layer "F.Fab")
		)
		(fp_line
			(start 0.67945 -0.3048)
			(end 0.67945 0.3048)
			(stroke
				(width 0.1)
				(type default)
			)
			(layer "F.Fab")
		)
		(fp_line
			(start 0.12065 -0.2794)
			(end 0.12065 -0.3048)
			(stroke
				(width 0.1)
				(type default)
			)
			(layer "F.Fab")
		)
		(fp_line
			(start 0.12065 -0.3048)
			(end 0.67945 -0.3048)
			(stroke
				(width 0.1)
				(type default)
			)
			(layer "F.Fab")
		)
		(fp_line
			(start 0.120396 0.3048)
			(end 0.120396 0.2794)
			(stroke
				(width 0.1)
				(type default)
			)
			(layer "F.Fab")
		)
		(fp_line
			(start 0.120396 0.2794)
			(end -0.12065 0.2794)
			(stroke
				(width 0.1)
				(type default)
			)
			(layer "F.Fab")
		)
		(fp_line
			(start -0.12065 0.3048)
			(end -0.67945 0.3048)
			(stroke
				(width 0.1)
				(type default)
			)
			(layer "F.Fab")
		)
		(fp_line
			(start -0.12065 0.2794)
			(end -0.12065 0.3048)
			(stroke
				(width 0.1)
				(type default)
			)
			(layer "F.Fab")
		)
		(fp_line
			(start -0.12065 -0.2794)
			(end 0.12065 -0.2794)
			(stroke
				(width 0.1)
				(type default)
			)
			(layer "F.Fab")
		)
		(fp_line
			(start -0.12065 -0.305054)
			(end -0.12065 -0.2794)
			(stroke
				(width 0.1)
				(type default)
			)
			(layer "F.Fab")
		)
		(fp_line
			(start -0.67945 0.3048)
			(end -0.67945 -0.305054)
			(stroke
				(width 0.1)
				(type default)
			)
			(layer "F.Fab")
		)
		(fp_line
			(start -0.67945 -0.305054)
			(end -0.12065 -0.305054)
			(stroke
				(width 0.1)
				(type default)
			)
			(layer "F.Fab")
		)
		(pad "1" smd circle
			(at -0.40005 0 180)
			(size 0 0)
			(layers "F.Cu" "F.Mask" "F.Paste")
			(net "P12V_AUX")
		)
		(pad "2" smd circle
			(at 0.40005 0 180)
			(size 0 0)
			(layers "F.Cu" "F.Mask" "F.Paste")
			(net "U206_VDD")
		)
	)
	(footprint ""
		(layer "F.Cu")
		(at 307.3908 -23.7744 180)
		(property "Reference" "C2385"
			(at 0 0 180)
			(layer "F.SilkS")
			(hide yes)
			(effects
				(font
					(size 1.27 1.27)
				)
			)
		)
		(property "Value" ""
			(at 0 0 180)
			(layer "F.Fab")
			(effects
				(font
					(size 1.27 1.27)
				)
			)
		)
		(duplicate_pad_numbers_are_jumpers no)
		(fp_line
			(start 0.7874 0.4064)
			(end -0.7874 0.4064)
			(stroke
				(width 0.1524)
				(type default)
			)
			(layer "F.SilkS")
		)
		(fp_line
			(start 0.7874 -0.4064)
			(end 0.7874 0.4064)
			(stroke
				(width 0.1524)
				(type default)
			)
			(layer "F.SilkS")
		)
		(fp_line
			(start -0.7874 0.4064)
			(end -0.7874 -0.4064)
			(stroke
				(width 0.1524)
				(type default)
			)
			(layer "F.SilkS")
		)
		(fp_line
			(start -0.7874 -0.4064)
			(end 0.7874 -0.4064)
			(stroke
				(width 0.1524)
				(type default)
			)
			(layer "F.SilkS")
		)
		(fp_line
			(start 0.67945 0.3048)
			(end 0.120396 0.3048)
			(stroke
				(width 0.1)
				(type default)
			)
			(layer "F.Fab")
		)
		(fp_line
			(start 0.67945 -0.3048)
			(end 0.67945 0.3048)
			(stroke
				(width 0.1)
				(type default)
			)
			(layer "F.Fab")
		)
		(fp_line
			(start 0.12065 -0.2794)
			(end 0.12065 -0.3048)
			(stroke
				(width 0.1)
				(type default)
			)
			(layer "F.Fab")
		)
		(fp_line
			(start 0.12065 -0.3048)
			(end 0.67945 -0.3048)
			(stroke
				(width 0.1)
				(type default)
			)
			(layer "F.Fab")
		)
		(fp_line
			(start 0.120396 0.3048)
			(end 0.120396 0.2794)
			(stroke
				(width 0.1)
				(type default)
			)
			(layer "F.Fab")
		)
		(fp_line
			(start 0.120396 0.2794)
			(end -0.12065 0.2794)
			(stroke
				(width 0.1)
				(type default)
			)
			(layer "F.Fab")
		)
		(fp_line
			(start -0.12065 0.3048)
			(end -0.67945 0.3048)
			(stroke
				(width 0.1)
				(type default)
			)
			(layer "F.Fab")
		)
		(fp_line
			(start -0.12065 0.2794)
			(end -0.12065 0.3048)
			(stroke
				(width 0.1)
				(type default)
			)
			(layer "F.Fab")
		)
		(fp_line
			(start -0.12065 -0.2794)
			(end 0.12065 -0.2794)
			(stroke
				(width 0.1)
				(type default)
			)
			(layer "F.Fab")
		)
		(fp_line
			(start -0.12065 -0.305054)
			(end -0.12065 -0.2794)
			(stroke
				(width 0.1)
				(type default)
			)
			(layer "F.Fab")
		)
		(fp_line
			(start -0.67945 0.3048)
			(end -0.67945 -0.305054)
			(stroke
				(width 0.1)
				(type default)
			)
			(layer "F.Fab")
		)
		(fp_line
			(start -0.67945 -0.305054)
			(end -0.12065 -0.305054)
			(stroke
				(width 0.1)
				(type default)
			)
			(layer "F.Fab")
		)
		(pad "1" smd circle
			(at -0.40005 0 180)
			(size 0 0)
			(layers "F.Cu" "F.Mask" "F.Paste")
			(net "DSW_PWROK_P2V5_COMP")
		)
		(pad "2" smd circle
			(at 0.40005 0 180)
			(size 0 0)
			(layers "F.Cu" "F.Mask" "F.Paste")
			(net "GND")
		)
	)
	(footprint ""
		(layer "F.Cu")
		(at 303.65573 -345.347544 180)
		(property "Reference" "PR586"
			(at 0 0 180)
			(layer "F.SilkS")
			(hide yes)
			(effects
				(font
					(size 1.27 1.27)
				)
			)
		)
		(property "Value" ""
			(at 0 0 180)
			(layer "F.Fab")
			(effects
				(font
					(size 1.27 1.27)
				)
			)
		)
		(duplicate_pad_numbers_are_jumpers no)
		(fp_line
			(start 0.7874 0.4064)
			(end -0.7874 0.4064)
			(stroke
				(width 0.1524)
				(type default)
			)
			(layer "F.SilkS")
		)
		(fp_line
			(start 0.7874 -0.4064)
			(end 0.7874 0.4064)
			(stroke
				(width 0.1524)
				(type default)
			)
			(layer "F.SilkS")
		)
		(fp_line
			(start -0.7874 0.4064)
			(end -0.7874 -0.4064)
			(stroke
				(width 0.1524)
				(type default)
			)
			(layer "F.SilkS")
		)
		(fp_line
			(start -0.7874 -0.4064)
			(end 0.7874 -0.4064)
			(stroke
				(width 0.1524)
				(type default)
			)
			(layer "F.SilkS")
		)
		(fp_line
			(start 0.67945 0.3048)
			(end 0.120396 0.3048)
			(stroke
				(width 0.1)
				(type default)
			)
			(layer "F.Fab")
		)
		(fp_line
			(start 0.67945 -0.3048)
			(end 0.67945 0.3048)
			(stroke
				(width 0.1)
				(type default)
			)
			(layer "F.Fab")
		)
		(fp_line
			(start 0.12065 -0.2794)
			(end 0.12065 -0.3048)
			(stroke
				(width 0.1)
				(type default)
			)
			(layer "F.Fab")
		)
		(fp_line
			(start 0.12065 -0.3048)
			(end 0.67945 -0.3048)
			(stroke
				(width 0.1)
				(type default)
			)
			(layer "F.Fab")
		)
		(fp_line
			(start 0.120396 0.3048)
			(end 0.120396 0.2794)
			(stroke
				(width 0.1)
				(type default)
			)
			(layer "F.Fab")
		)
		(fp_line
			(start 0.120396 0.2794)
			(end -0.12065 0.2794)
			(stroke
				(width 0.1)
				(type default)
			)
			(layer "F.Fab")
		)
		(fp_line
			(start -0.12065 0.3048)
			(end -0.67945 0.3048)
			(stroke
				(width 0.1)
				(type default)
			)
			(layer "F.Fab")
		)
		(fp_line
			(start -0.12065 0.2794)
			(end -0.12065 0.3048)
			(stroke
				(width 0.1)
				(type default)
			)
			(layer "F.Fab")
		)
		(fp_line
			(start -0.12065 -0.2794)
			(end 0.12065 -0.2794)
			(stroke
				(width 0.1)
				(type default)
			)
			(layer "F.Fab")
		)
		(fp_line
			(start -0.12065 -0.305054)
			(end -0.12065 -0.2794)
			(stroke
				(width 0.1)
				(type default)
			)
			(layer "F.Fab")
		)
		(fp_line
			(start -0.67945 0.3048)
			(end -0.67945 -0.305054)
			(stroke
				(width 0.1)
				(type default)
			)
			(layer "F.Fab")
		)
		(fp_line
			(start -0.67945 -0.305054)
			(end -0.12065 -0.305054)
			(stroke
				(width 0.1)
				(type default)
			)
			(layer "F.Fab")
		)
		(pad "1" smd circle
			(at -0.40005 0 180)
			(size 0 0)
			(layers "F.Cu" "F.Mask" "F.Paste")
			(net "VSENSE_PVCCFA_EHV_FIVRA_CPU0_DN")
		)
		(pad "2" smd circle
			(at 0.40005 0 180)
			(size 0 0)
			(layers "F.Cu" "F.Mask" "F.Paste")
			(net "GND")
		)
	)
	(footprint ""
		(layer "F.Cu")
		(at 108.85043 -401.184364)
		(property "Reference" "R3490"
			(at 0 0 0)
			(layer "F.SilkS")
			(hide yes)
			(effects
				(font
					(size 1.27 1.27)
				)
			)
		)
		(property "Value" ""
			(at 0 0 0)
			(layer "F.Fab")
			(effects
				(font
					(size 1.27 1.27)
				)
			)
		)
		(duplicate_pad_numbers_are_jumpers no)
		(fp_line
			(start -0.7874 -0.4064)
			(end 0.7874 -0.4064)
			(stroke
				(width 0.1524)
				(type default)
			)
			(layer "F.SilkS")
		)
		(fp_line
			(start -0.7874 0.4064)
			(end -0.7874 -0.4064)
			(stroke
				(width 0.1524)
				(type default)
			)
			(layer "F.SilkS")
		)
		(fp_line
			(start 0.7874 -0.4064)
			(end 0.7874 0.4064)
			(stroke
				(width 0.1524)
				(type default)
			)
			(layer "F.SilkS")
		)
		(fp_line
			(start 0.7874 0.4064)
			(end -0.7874 0.4064)
			(stroke
				(width 0.1524)
				(type default)
			)
			(layer "F.SilkS")
		)
		(fp_line
			(start -0.67945 -0.305054)
			(end -0.12065 -0.305054)
			(stroke
				(width 0.1)
				(type default)
			)
			(layer "F.Fab")
		)
		(fp_line
			(start -0.67945 0.3048)
			(end -0.67945 -0.305054)
			(stroke
				(width 0.1)
				(type default)
			)
			(layer "F.Fab")
		)
		(fp_line
			(start -0.12065 -0.305054)
			(end -0.12065 -0.2794)
			(stroke
				(width 0.1)
				(type default)
			)
			(layer "F.Fab")
		)
		(fp_line
			(start -0.12065 -0.2794)
			(end 0.12065 -0.2794)
			(stroke
				(width 0.1)
				(type default)
			)
			(layer "F.Fab")
		)
		(fp_line
			(start -0.12065 0.2794)
			(end -0.12065 0.3048)
			(stroke
				(width 0.1)
				(type default)
			)
			(layer "F.Fab")
		)
		(fp_line
			(start -0.12065 0.3048)
			(end -0.67945 0.3048)
			(stroke
				(width 0.1)
				(type default)
			)
			(layer "F.Fab")
		)
		(fp_line
			(start 0.120396 0.2794)
			(end -0.12065 0.2794)
			(stroke
				(width 0.1)
				(type default)
			)
			(layer "F.Fab")
		)
		(fp_line
			(start 0.120396 0.3048)
			(end 0.120396 0.2794)
			(stroke
				(width 0.1)
				(type default)
			)
			(layer "F.Fab")
		)
		(fp_line
			(start 0.12065 -0.3048)
			(end 0.67945 -0.3048)
			(stroke
				(width 0.1)
				(type default)
			)
			(layer "F.Fab")
		)
		(fp_line
			(start 0.12065 -0.2794)
			(end 0.12065 -0.3048)
			(stroke
				(width 0.1)
				(type default)
			)
			(layer "F.Fab")
		)
		(fp_line
			(start 0.67945 -0.3048)
			(end 0.67945 0.3048)
			(stroke
				(width 0.1)
				(type default)
			)
			(layer "F.Fab")
		)
		(fp_line
			(start 0.67945 0.3048)
			(end 0.120396 0.3048)
			(stroke
				(width 0.1)
				(type default)
			)
			(layer "F.Fab")
		)
		(pad "1" smd circle
			(at -0.40005 0)
			(size 0 0)
			(layers "F.Cu" "F.Mask" "F.Paste")
			(net "P3V3_AUX")
		)
		(pad "2" smd circle
			(at 0.40005 0)
			(size 0 0)
			(layers "F.Cu" "F.Mask" "F.Paste")
			(net "GPU_FPGA_EROT_RECOV_N")
		)
	)
	(footprint ""
		(layer "F.Cu")
		(at 104.503728 -426.787818)
		(property "Reference" "R4210"
			(at 0 0 0)
			(layer "F.SilkS")
			(hide yes)
			(effects
				(font
					(size 1.27 1.27)
				)
			)
		)
		(property "Value" ""
			(at 0 0 0)
			(layer "F.Fab")
			(effects
				(font
					(size 1.27 1.27)
				)
			)
		)
		(duplicate_pad_numbers_are_jumpers no)
		(fp_line
			(start -0.7874 -0.4064)
			(end 0.7874 -0.4064)
			(stroke
				(width 0.1524)
				(type default)
			)
			(layer "F.SilkS")
		)
		(fp_line
			(start -0.7874 0.4064)
			(end -0.7874 -0.4064)
			(stroke
				(width 0.1524)
				(type default)
			)
			(layer "F.SilkS")
		)
		(fp_line
			(start 0.7874 -0.4064)
			(end 0.7874 0.4064)
			(stroke
				(width 0.1524)
				(type default)
			)
			(layer "F.SilkS")
		)
		(fp_line
			(start 0.7874 0.4064)
			(end -0.7874 0.4064)
			(stroke
				(width 0.1524)
				(type default)
			)
			(layer "F.SilkS")
		)
		(fp_line
			(start -0.67945 -0.305054)
			(end -0.12065 -0.305054)
			(stroke
				(width 0.1)
				(type default)
			)
			(layer "F.Fab")
		)
		(fp_line
			(start -0.67945 0.3048)
			(end -0.67945 -0.305054)
			(stroke
				(width 0.1)
				(type default)
			)
			(layer "F.Fab")
		)
		(fp_line
			(start -0.12065 -0.305054)
			(end -0.12065 -0.2794)
			(stroke
				(width 0.1)
				(type default)
			)
			(layer "F.Fab")
		)
		(fp_line
			(start -0.12065 -0.2794)
			(end 0.12065 -0.2794)
			(stroke
				(width 0.1)
				(type default)
			)
			(layer "F.Fab")
		)
		(fp_line
			(start -0.12065 0.2794)
			(end -0.12065 0.3048)
			(stroke
				(width 0.1)
				(type default)
			)
			(layer "F.Fab")
		)
		(fp_line
			(start -0.12065 0.3048)
			(end -0.67945 0.3048)
			(stroke
				(width 0.1)
				(type default)
			)
			(layer "F.Fab")
		)
		(fp_line
			(start 0.120396 0.2794)
			(end -0.12065 0.2794)
			(stroke
				(width 0.1)
				(type default)
			)
			(layer "F.Fab")
		)
		(fp_line
			(start 0.120396 0.3048)
			(end 0.120396 0.2794)
			(stroke
				(width 0.1)
				(type default)
			)
			(layer "F.Fab")
		)
		(fp_line
			(start 0.12065 -0.3048)
			(end 0.67945 -0.3048)
			(stroke
				(width 0.1)
				(type default)
			)
			(layer "F.Fab")
		)
		(fp_line
			(start 0.12065 -0.2794)
			(end 0.12065 -0.3048)
			(stroke
				(width 0.1)
				(type default)
			)
			(layer "F.Fab")
		)
		(fp_line
			(start 0.67945 -0.3048)
			(end 0.67945 0.3048)
			(stroke
				(width 0.1)
				(type default)
			)
			(layer "F.Fab")
		)
		(fp_line
			(start 0.67945 0.3048)
			(end 0.120396 0.3048)
			(stroke
				(width 0.1)
				(type default)
			)
			(layer "F.Fab")
		)
		(pad "1" smd circle
			(at -0.40005 0)
			(size 0 0)
			(layers "F.Cu" "F.Mask" "F.Paste")
			(net "P3V3_AUX")
		)
		(pad "2" smd circle
			(at 0.40005 0)
			(size 0 0)
			(layers "F.Cu" "F.Mask" "F.Paste")
			(net "FM_THERMAL_ALERT_N")
		)
	)
	(footprint ""
		(layer "F.Cu")
		(at 388.05993 -408.517344 -90)
		(property "Reference" "C880"
			(at 0 0 270)
			(layer "F.SilkS")
			(hide yes)
			(effects
				(font
					(size 1.27 1.27)
				)
			)
		)
		(property "Value" ""
			(at 0 0 270)
			(layer "F.Fab")
			(effects
				(font
					(size 1.27 1.27)
				)
			)
		)
		(duplicate_pad_numbers_are_jumpers no)
		(fp_line
			(start -0.299974 0.150114)
			(end -0.299974 -0.150114)
			(stroke
				(width 0.1)
				(type default)
			)
			(layer "F.Fab")
		)
		(fp_line
			(start 0.299974 0.150114)
			(end -0.299974 0.150114)
			(stroke
				(width 0.1)
				(type default)
			)
			(layer "F.Fab")
		)
		(fp_line
			(start -0.299974 -0.150114)
			(end 0.299974 -0.150114)
			(stroke
				(width 0.1)
				(type default)
			)
			(layer "F.Fab")
		)
		(fp_line
			(start 0.299974 -0.150114)
			(end 0.299974 0.150114)
			(stroke
				(width 0.1)
				(type default)
			)
			(layer "F.Fab")
		)
		(pad "1" smd rect
			(at -0.2667 0 270)
			(size 0.3048 0.381)
			(layers "F.Cu" "F.Mask" "F.Paste")
			(net "P5E_CPU0_PE3_TX_C_DN<10>")
		)
		(pad "2" smd rect
			(at 0.2667 0 270)
			(size 0.3048 0.381)
			(layers "F.Cu" "F.Mask" "F.Paste")
			(net "P5E_CPU0_PE3_TX_DN<10>")
		)
	)
	(footprint ""
		(layer "F.Cu")
		(at 108.85043 -402.200364 180)
		(property "Reference" "R3491"
			(at 0 0 180)
			(layer "F.SilkS")
			(hide yes)
			(effects
				(font
					(size 1.27 1.27)
				)
			)
		)
		(property "Value" ""
			(at 0 0 180)
			(layer "F.Fab")
			(effects
				(font
					(size 1.27 1.27)
				)
			)
		)
		(duplicate_pad_numbers_are_jumpers no)
		(fp_line
			(start 0.7874 0.4064)
			(end -0.7874 0.4064)
			(stroke
				(width 0.1524)
				(type default)
			)
			(layer "F.SilkS")
		)
		(fp_line
			(start 0.7874 -0.4064)
			(end 0.7874 0.4064)
			(stroke
				(width 0.1524)
				(type default)
			)
			(layer "F.SilkS")
		)
		(fp_line
			(start -0.7874 0.4064)
			(end -0.7874 -0.4064)
			(stroke
				(width 0.1524)
				(type default)
			)
			(layer "F.SilkS")
		)
		(fp_line
			(start -0.7874 -0.4064)
			(end 0.7874 -0.4064)
			(stroke
				(width 0.1524)
				(type default)
			)
			(layer "F.SilkS")
		)
		(fp_line
			(start 0.67945 0.3048)
			(end 0.120396 0.3048)
			(stroke
				(width 0.1)
				(type default)
			)
			(layer "F.Fab")
		)
		(fp_line
			(start 0.67945 -0.3048)
			(end 0.67945 0.3048)
			(stroke
				(width 0.1)
				(type default)
			)
			(layer "F.Fab")
		)
		(fp_line
			(start 0.12065 -0.2794)
			(end 0.12065 -0.3048)
			(stroke
				(width 0.1)
				(type default)
			)
			(layer "F.Fab")
		)
		(fp_line
			(start 0.12065 -0.3048)
			(end 0.67945 -0.3048)
			(stroke
				(width 0.1)
				(type default)
			)
			(layer "F.Fab")
		)
		(fp_line
			(start 0.120396 0.3048)
			(end 0.120396 0.2794)
			(stroke
				(width 0.1)
				(type default)
			)
			(layer "F.Fab")
		)
		(fp_line
			(start 0.120396 0.2794)
			(end -0.12065 0.2794)
			(stroke
				(width 0.1)
				(type default)
			)
			(layer "F.Fab")
		)
		(fp_line
			(start -0.12065 0.3048)
			(end -0.67945 0.3048)
			(stroke
				(width 0.1)
				(type default)
			)
			(layer "F.Fab")
		)
		(fp_line
			(start -0.12065 0.2794)
			(end -0.12065 0.3048)
			(stroke
				(width 0.1)
				(type default)
			)
			(layer "F.Fab")
		)
		(fp_line
			(start -0.12065 -0.2794)
			(end 0.12065 -0.2794)
			(stroke
				(width 0.1)
				(type default)
			)
			(layer "F.Fab")
		)
		(fp_line
			(start -0.12065 -0.305054)
			(end -0.12065 -0.2794)
			(stroke
				(width 0.1)
				(type default)
			)
			(layer "F.Fab")
		)
		(fp_line
			(start -0.67945 0.3048)
			(end -0.67945 -0.305054)
			(stroke
				(width 0.1)
				(type default)
			)
			(layer "F.Fab")
		)
		(fp_line
			(start -0.67945 -0.305054)
			(end -0.12065 -0.305054)
			(stroke
				(width 0.1)
				(type default)
			)
			(layer "F.Fab")
		)
		(pad "1" smd circle
			(at -0.40005 0 180)
			(size 0 0)
			(layers "F.Cu" "F.Mask" "F.Paste")
			(net "GPU_FPGA_EROT_RECOV_N")
		)
		(pad "2" smd circle
			(at 0.40005 0 180)
			(size 0 0)
			(layers "F.Cu" "F.Mask" "F.Paste")
			(net "GND")
		)
	)
	(footprint ""
		(layer "F.Cu")
		(at 120.37822 -422.463468 180)
		(property "Reference" "R2912"
			(at 0 0 180)
			(layer "F.SilkS")
			(hide yes)
			(effects
				(font
					(size 1.27 1.27)
				)
			)
		)
		(property "Value" ""
			(at 0 0 180)
			(layer "F.Fab")
			(effects
				(font
					(size 1.27 1.27)
				)
			)
		)
		(duplicate_pad_numbers_are_jumpers no)
		(fp_line
			(start 0.7874 0.4064)
			(end -0.7874 0.4064)
			(stroke
				(width 0.1524)
				(type default)
			)
			(layer "F.SilkS")
		)
		(fp_line
			(start 0.7874 -0.4064)
			(end 0.7874 0.4064)
			(stroke
				(width 0.1524)
				(type default)
			)
			(layer "F.SilkS")
		)
		(fp_line
			(start -0.7874 0.4064)
			(end -0.7874 -0.4064)
			(stroke
				(width 0.1524)
				(type default)
			)
			(layer "F.SilkS")
		)
		(fp_line
			(start -0.7874 -0.4064)
			(end 0.7874 -0.4064)
			(stroke
				(width 0.1524)
				(type default)
			)
			(layer "F.SilkS")
		)
		(fp_line
			(start 0.67945 0.3048)
			(end 0.120396 0.3048)
			(stroke
				(width 0.1)
				(type default)
			)
			(layer "F.Fab")
		)
		(fp_line
			(start 0.67945 -0.3048)
			(end 0.67945 0.3048)
			(stroke
				(width 0.1)
				(type default)
			)
			(layer "F.Fab")
		)
		(fp_line
			(start 0.12065 -0.2794)
			(end 0.12065 -0.3048)
			(stroke
				(width 0.1)
				(type default)
			)
			(layer "F.Fab")
		)
		(fp_line
			(start 0.12065 -0.3048)
			(end 0.67945 -0.3048)
			(stroke
				(width 0.1)
				(type default)
			)
			(layer "F.Fab")
		)
		(fp_line
			(start 0.120396 0.3048)
			(end 0.120396 0.2794)
			(stroke
				(width 0.1)
				(type default)
			)
			(layer "F.Fab")
		)
		(fp_line
			(start 0.120396 0.2794)
			(end -0.12065 0.2794)
			(stroke
				(width 0.1)
				(type default)
			)
			(layer "F.Fab")
		)
		(fp_line
			(start -0.12065 0.3048)
			(end -0.67945 0.3048)
			(stroke
				(width 0.1)
				(type default)
			)
			(layer "F.Fab")
		)
		(fp_line
			(start -0.12065 0.2794)
			(end -0.12065 0.3048)
			(stroke
				(width 0.1)
				(type default)
			)
			(layer "F.Fab")
		)
		(fp_line
			(start -0.12065 -0.2794)
			(end 0.12065 -0.2794)
			(stroke
				(width 0.1)
				(type default)
			)
			(layer "F.Fab")
		)
		(fp_line
			(start -0.12065 -0.305054)
			(end -0.12065 -0.2794)
			(stroke
				(width 0.1)
				(type default)
			)
			(layer "F.Fab")
		)
		(fp_line
			(start -0.67945 0.3048)
			(end -0.67945 -0.305054)
			(stroke
				(width 0.1)
				(type default)
			)
			(layer "F.Fab")
		)
		(fp_line
			(start -0.67945 -0.305054)
			(end -0.12065 -0.305054)
			(stroke
				(width 0.1)
				(type default)
			)
			(layer "F.Fab")
		)
		(pad "1" smd circle
			(at -0.40005 0 180)
			(size 0 0)
			(layers "F.Cu" "F.Mask" "F.Paste")
			(net "P3V3_AUX")
		)
		(pad "2" smd circle
			(at 0.40005 0 180)
			(size 0 0)
			(layers "F.Cu" "F.Mask" "F.Paste")
			(net "FM_GPU_PWR_EN_R1")
		)
	)
	(footprint ""
		(layer "F.Cu")
		(at 365.46663 -252.956314 -90)
		(property "Reference" "C1020"
			(at 0 0 270)
			(layer "F.SilkS")
			(hide yes)
			(effects
				(font
					(size 1.27 1.27)
				)
			)
		)
		(property "Value" ""
			(at 0 0 270)
			(layer "F.Fab")
			(effects
				(font
					(size 1.27 1.27)
				)
			)
		)
		(duplicate_pad_numbers_are_jumpers no)
		(fp_line
			(start -0.7874 0.4064)
			(end -0.7874 -0.4064)
			(stroke
				(width 0.1524)
				(type default)
			)
			(layer "F.SilkS")
		)
		(fp_line
			(start 0.7874 0.4064)
			(end -0.7874 0.4064)
			(stroke
				(width 0.1524)
				(type default)
			)
			(layer "F.SilkS")
		)
		(fp_line
			(start -0.7874 -0.4064)
			(end 0.7874 -0.4064)
			(stroke
				(width 0.1524)
				(type default)
			)
			(layer "F.SilkS")
		)
		(fp_line
			(start 0.7874 -0.4064)
			(end 0.7874 0.4064)
			(stroke
				(width 0.1524)
				(type default)
			)
			(layer "F.SilkS")
		)
		(fp_line
			(start -0.67945 0.3048)
			(end -0.67945 -0.305054)
			(stroke
				(width 0.1)
				(type default)
			)
			(layer "F.Fab")
		)
		(fp_line
			(start -0.12065 0.3048)
			(end -0.67945 0.3048)
			(stroke
				(width 0.1)
				(type default)
			)
			(layer "F.Fab")
		)
		(fp_line
			(start 0.120396 0.3048)
			(end 0.120396 0.2794)
			(stroke
				(width 0.1)
				(type default)
			)
			(layer "F.Fab")
		)
		(fp_line
			(start 0.67945 0.3048)
			(end 0.120396 0.3048)
			(stroke
				(width 0.1)
				(type default)
			)
			(layer "F.Fab")
		)
		(fp_line
			(start -0.12065 0.2794)
			(end -0.12065 0.3048)
			(stroke
				(width 0.1)
				(type default)
			)
			(layer "F.Fab")
		)
		(fp_line
			(start 0.120396 0.2794)
			(end -0.12065 0.2794)
			(stroke
				(width 0.1)
				(type default)
			)
			(layer "F.Fab")
		)
		(fp_line
			(start -0.12065 -0.2794)
			(end 0.12065 -0.2794)
			(stroke
				(width 0.1)
				(type default)
			)
			(layer "F.Fab")
		)
		(fp_line
			(start 0.12065 -0.2794)
			(end 0.12065 -0.3048)
			(stroke
				(width 0.1)
				(type default)
			)
			(layer "F.Fab")
		)
		(fp_line
			(start 0.12065 -0.3048)
			(end 0.67945 -0.3048)
			(stroke
				(width 0.1)
				(type default)
			)
			(layer "F.Fab")
		)
		(fp_line
			(start 0.67945 -0.3048)
			(end 0.67945 0.3048)
			(stroke
				(width 0.1)
				(type default)
			)
			(layer "F.Fab")
		)
		(fp_line
			(start -0.67945 -0.305054)
			(end -0.12065 -0.305054)
			(stroke
				(width 0.1)
				(type default)
			)
			(layer "F.Fab")
		)
		(fp_line
			(start -0.12065 -0.305054)
			(end -0.12065 -0.2794)
			(stroke
				(width 0.1)
				(type default)
			)
			(layer "F.Fab")
		)
		(pad "1" smd circle
			(at -0.40005 0 270)
			(size 0 0)
			(layers "F.Cu" "F.Mask" "F.Paste")
			(net "PVCCIN_CPU0")
		)
		(pad "2" smd circle
			(at 0.40005 0 270)
			(size 0 0)
			(layers "F.Cu" "F.Mask" "F.Paste")
			(net "GND")
		)
	)
	(footprint ""
		(layer "F.Cu")
		(at 152.755346 -115.4684 180)
		(property "Reference" "R4697"
			(at 0 0 180)
			(layer "F.SilkS")
			(hide yes)
			(effects
				(font
					(size 1.27 1.27)
				)
			)
		)
		(property "Value" ""
			(at 0 0 180)
			(layer "F.Fab")
			(effects
				(font
					(size 1.27 1.27)
				)
			)
		)
		(duplicate_pad_numbers_are_jumpers no)
		(fp_line
			(start 0.7874 0.4064)
			(end -0.7874 0.4064)
			(stroke
				(width 0.1524)
				(type default)
			)
			(layer "F.SilkS")
		)
		(fp_line
			(start 0.7874 -0.4064)
			(end 0.7874 0.4064)
			(stroke
				(width 0.1524)
				(type default)
			)
			(layer "F.SilkS")
		)
		(fp_line
			(start -0.7874 0.4064)
			(end -0.7874 -0.4064)
			(stroke
				(width 0.1524)
				(type default)
			)
			(layer "F.SilkS")
		)
		(fp_line
			(start -0.7874 -0.4064)
			(end 0.7874 -0.4064)
			(stroke
				(width 0.1524)
				(type default)
			)
			(layer "F.SilkS")
		)
		(fp_line
			(start 0.67945 0.3048)
			(end 0.120396 0.3048)
			(stroke
				(width 0.1)
				(type default)
			)
			(layer "F.Fab")
		)
		(fp_line
			(start 0.67945 -0.3048)
			(end 0.67945 0.3048)
			(stroke
				(width 0.1)
				(type default)
			)
			(layer "F.Fab")
		)
		(fp_line
			(start 0.12065 -0.2794)
			(end 0.12065 -0.3048)
			(stroke
				(width 0.1)
				(type default)
			)
			(layer "F.Fab")
		)
		(fp_line
			(start 0.12065 -0.3048)
			(end 0.67945 -0.3048)
			(stroke
				(width 0.1)
				(type default)
			)
			(layer "F.Fab")
		)
		(fp_line
			(start 0.120396 0.3048)
			(end 0.120396 0.2794)
			(stroke
				(width 0.1)
				(type default)
			)
			(layer "F.Fab")
		)
		(fp_line
			(start 0.120396 0.2794)
			(end -0.12065 0.2794)
			(stroke
				(width 0.1)
				(type default)
			)
			(layer "F.Fab")
		)
		(fp_line
			(start -0.12065 0.3048)
			(end -0.67945 0.3048)
			(stroke
				(width 0.1)
				(type default)
			)
			(layer "F.Fab")
		)
		(fp_line
			(start -0.12065 0.2794)
			(end -0.12065 0.3048)
			(stroke
				(width 0.1)
				(type default)
			)
			(layer "F.Fab")
		)
		(fp_line
			(start -0.12065 -0.2794)
			(end 0.12065 -0.2794)
			(stroke
				(width 0.1)
				(type default)
			)
			(layer "F.Fab")
		)
		(fp_line
			(start -0.12065 -0.305054)
			(end -0.12065 -0.2794)
			(stroke
				(width 0.1)
				(type default)
			)
			(layer "F.Fab")
		)
		(fp_line
			(start -0.67945 0.3048)
			(end -0.67945 -0.305054)
			(stroke
				(width 0.1)
				(type default)
			)
			(layer "F.Fab")
		)
		(fp_line
			(start -0.67945 -0.305054)
			(end -0.12065 -0.305054)
			(stroke
				(width 0.1)
				(type default)
			)
			(layer "F.Fab")
		)
		(pad "1" smd circle
			(at -0.40005 0 180)
			(size 0 0)
			(layers "F.Cu" "F.Mask" "F.Paste")
			(net "RST_SRST_PLD_BMC_R_N")
		)
		(pad "2" smd circle
			(at 0.40005 0 180)
			(size 0 0)
			(layers "F.Cu" "F.Mask" "F.Paste")
			(net "RST_SRST_PLD_BMC_N")
		)
	)
	(footprint ""
		(layer "F.Cu")
		(at 408.554682 -179.457858 180)
		(property "Reference" "PL5"
			(at 5.785104 -0.050292 0)
			(unlocked yes)
			(layer "F.SilkS")
			(effects
				(font
					(size 0.7874 0.5842)
					(thickness 0.1524)
				)
				(justify left)
			)
		)
		(property "Value" ""
			(at 0 0 180)
			(layer "F.Fab")
			(effects
				(font
					(size 1.27 1.27)
				)
			)
		)
		(duplicate_pad_numbers_are_jumpers no)
		(fp_line
			(start 3.24993 3.24993)
			(end -3.24993 3.24993)
			(stroke
				(width 0.1524)
				(type default)
			)
			(layer "F.SilkS")
		)
		(fp_line
			(start 3.24993 2.2352)
			(end 3.24993 3.24993)
			(stroke
				(width 0.1524)
				(type default)
			)
			(layer "F.SilkS")
		)
		(fp_line
			(start 3.24993 -3.24993)
			(end 3.24993 -2.2352)
			(stroke
				(width 0.1524)
				(type default)
			)
			(layer "F.SilkS")
		)
		(fp_line
			(start -3.24993 3.24993)
			(end -3.24993 2.2352)
			(stroke
				(width 0.1524)
				(type default)
			)
			(layer "F.SilkS")
		)
		(fp_line
			(start -3.24993 -2.2352)
			(end -3.24993 -3.24993)
			(stroke
				(width 0.1524)
				(type default)
			)
			(layer "F.SilkS")
		)
		(fp_line
			(start -3.24993 -3.24993)
			(end 3.24993 -3.24993)
			(stroke
				(width 0.1524)
				(type default)
			)
			(layer "F.SilkS")
		)
		(fp_line
			(start 3.24993 3.24993)
			(end -3.24993 3.24993)
			(stroke
				(width 0.1)
				(type default)
			)
			(layer "F.Fab")
		)
		(fp_line
			(start 3.24993 -3.24993)
			(end 3.24993 3.24993)
			(stroke
				(width 0.1)
				(type default)
			)
			(layer "F.Fab")
		)
		(fp_line
			(start -3.24993 3.24993)
			(end -3.24993 -3.24993)
			(stroke
				(width 0.1)
				(type default)
			)
			(layer "F.Fab")
		)
		(fp_line
			(start -3.24993 -3.24993)
			(end 3.24993 -3.24993)
			(stroke
				(width 0.1)
				(type default)
			)
			(layer "F.Fab")
		)
		(pad "1" smd rect
			(at -2.29997 0 180)
			(size 2.0066 4.2164)
			(layers "F.Cu" "F.Mask" "F.Paste")
			(net "SW_PVCCINFAON_CPU0_SW2")
		)
		(pad "2" smd rect
			(at 2.29997 0 180)
			(size 2.0066 4.2164)
			(layers "F.Cu" "F.Mask" "F.Paste")
			(net "PVCCINFAON_CPU0")
		)
	)
	(footprint ""
		(layer "F.Cu")
		(at 48.868838 -402.371052 -90)
		(property "Reference" "C711"
			(at 0 0 270)
			(layer "F.SilkS")
			(hide yes)
			(effects
				(font
					(size 1.27 1.27)
				)
			)
		)
		(property "Value" ""
			(at 0 0 270)
			(layer "F.Fab")
			(effects
				(font
					(size 1.27 1.27)
				)
			)
		)
		(duplicate_pad_numbers_are_jumpers no)
		(fp_line
			(start -0.299974 0.150114)
			(end -0.299974 -0.150114)
			(stroke
				(width 0.1)
				(type default)
			)
			(layer "F.Fab")
		)
		(fp_line
			(start 0.299974 0.150114)
			(end -0.299974 0.150114)
			(stroke
				(width 0.1)
				(type default)
			)
			(layer "F.Fab")
		)
		(fp_line
			(start -0.299974 -0.150114)
			(end 0.299974 -0.150114)
			(stroke
				(width 0.1)
				(type default)
			)
			(layer "F.Fab")
		)
		(fp_line
			(start 0.299974 -0.150114)
			(end 0.299974 0.150114)
			(stroke
				(width 0.1)
				(type default)
			)
			(layer "F.Fab")
		)
		(pad "1" smd rect
			(at -0.2667 0 270)
			(size 0.3048 0.381)
			(layers "F.Cu" "F.Mask" "F.Paste")
			(net "P5E_CPU1_PE0_TX_C_DP<15>")
		)
		(pad "2" smd rect
			(at 0.2667 0 270)
			(size 0.3048 0.381)
			(layers "F.Cu" "F.Mask" "F.Paste")
			(net "P5E_CPU1_PE0_TX_DP<15>")
		)
	)
	(footprint ""
		(layer "F.Cu")
		(at 213.54288 -34.508948 180)
		(property "Reference" "R3576"
			(at 0 0 180)
			(layer "F.SilkS")
			(hide yes)
			(effects
				(font
					(size 1.27 1.27)
				)
			)
		)
		(property "Value" ""
			(at 0 0 180)
			(layer "F.Fab")
			(effects
				(font
					(size 1.27 1.27)
				)
			)
		)
		(duplicate_pad_numbers_are_jumpers no)
		(fp_line
			(start 0.7874 0.4064)
			(end -0.7874 0.4064)
			(stroke
				(width 0.1524)
				(type default)
			)
			(layer "F.SilkS")
		)
		(fp_line
			(start 0.7874 -0.4064)
			(end 0.7874 0.4064)
			(stroke
				(width 0.1524)
				(type default)
			)
			(layer "F.SilkS")
		)
		(fp_line
			(start -0.7874 0.4064)
			(end -0.7874 -0.4064)
			(stroke
				(width 0.1524)
				(type default)
			)
			(layer "F.SilkS")
		)
		(fp_line
			(start -0.7874 -0.4064)
			(end 0.7874 -0.4064)
			(stroke
				(width 0.1524)
				(type default)
			)
			(layer "F.SilkS")
		)
		(fp_line
			(start 0.67945 0.3048)
			(end 0.120396 0.3048)
			(stroke
				(width 0.1)
				(type default)
			)
			(layer "F.Fab")
		)
		(fp_line
			(start 0.67945 -0.3048)
			(end 0.67945 0.3048)
			(stroke
				(width 0.1)
				(type default)
			)
			(layer "F.Fab")
		)
		(fp_line
			(start 0.12065 -0.2794)
			(end 0.12065 -0.3048)
			(stroke
				(width 0.1)
				(type default)
			)
			(layer "F.Fab")
		)
		(fp_line
			(start 0.12065 -0.3048)
			(end 0.67945 -0.3048)
			(stroke
				(width 0.1)
				(type default)
			)
			(layer "F.Fab")
		)
		(fp_line
			(start 0.120396 0.3048)
			(end 0.120396 0.2794)
			(stroke
				(width 0.1)
				(type default)
			)
			(layer "F.Fab")
		)
		(fp_line
			(start 0.120396 0.2794)
			(end -0.12065 0.2794)
			(stroke
				(width 0.1)
				(type default)
			)
			(layer "F.Fab")
		)
		(fp_line
			(start -0.12065 0.3048)
			(end -0.67945 0.3048)
			(stroke
				(width 0.1)
				(type default)
			)
			(layer "F.Fab")
		)
		(fp_line
			(start -0.12065 0.2794)
			(end -0.12065 0.3048)
			(stroke
				(width 0.1)
				(type default)
			)
			(layer "F.Fab")
		)
		(fp_line
			(start -0.12065 -0.2794)
			(end 0.12065 -0.2794)
			(stroke
				(width 0.1)
				(type default)
			)
			(layer "F.Fab")
		)
		(fp_line
			(start -0.12065 -0.305054)
			(end -0.12065 -0.2794)
			(stroke
				(width 0.1)
				(type default)
			)
			(layer "F.Fab")
		)
		(fp_line
			(start -0.67945 0.3048)
			(end -0.67945 -0.305054)
			(stroke
				(width 0.1)
				(type default)
			)
			(layer "F.Fab")
		)
		(fp_line
			(start -0.67945 -0.305054)
			(end -0.12065 -0.305054)
			(stroke
				(width 0.1)
				(type default)
			)
			(layer "F.Fab")
		)
		(pad "1" smd circle
			(at -0.40005 0 180)
			(size 0 0)
			(layers "F.Cu" "F.Mask" "F.Paste")
			(net "SMB_INA230_5_3V3AUX_SCL_R")
		)
		(pad "2" smd circle
			(at 0.40005 0 180)
			(size 0 0)
			(layers "F.Cu" "F.Mask" "F.Paste")
			(net "SMB_INA230_5_3V3AUX_SCL_R1")
		)
	)
	(footprint ""
		(layer "F.Cu")
		(at 365.46663 -247.715024 90)
		(property "Reference" "C989"
			(at 0 0 90)
			(layer "F.SilkS")
			(hide yes)
			(effects
				(font
					(size 1.27 1.27)
				)
			)
		)
		(property "Value" ""
			(at 0 0 90)
			(layer "F.Fab")
			(effects
				(font
					(size 1.27 1.27)
				)
			)
		)
		(duplicate_pad_numbers_are_jumpers no)
		(fp_line
			(start 0.7874 -0.4064)
			(end 0.7874 0.4064)
			(stroke
				(width 0.1524)
				(type default)
			)
			(layer "F.SilkS")
		)
		(fp_line
			(start -0.7874 -0.4064)
			(end 0.7874 -0.4064)
			(stroke
				(width 0.1524)
				(type default)
			)
			(layer "F.SilkS")
		)
		(fp_line
			(start 0.7874 0.4064)
			(end -0.7874 0.4064)
			(stroke
				(width 0.1524)
				(type default)
			)
			(layer "F.SilkS")
		)
		(fp_line
			(start -0.7874 0.4064)
			(end -0.7874 -0.4064)
			(stroke
				(width 0.1524)
				(type default)
			)
			(layer "F.SilkS")
		)
		(fp_line
			(start -0.12065 -0.305054)
			(end -0.12065 -0.2794)
			(stroke
				(width 0.1)
				(type default)
			)
			(layer "F.Fab")
		)
		(fp_line
			(start -0.67945 -0.305054)
			(end -0.12065 -0.305054)
			(stroke
				(width 0.1)
				(type default)
			)
			(layer "F.Fab")
		)
		(fp_line
			(start 0.67945 -0.3048)
			(end 0.67945 0.3048)
			(stroke
				(width 0.1)
				(type default)
			)
			(layer "F.Fab")
		)
		(fp_line
			(start 0.12065 -0.3048)
			(end 0.67945 -0.3048)
			(stroke
				(width 0.1)
				(type default)
			)
			(layer "F.Fab")
		)
		(fp_line
			(start 0.12065 -0.2794)
			(end 0.12065 -0.3048)
			(stroke
				(width 0.1)
				(type default)
			)
			(layer "F.Fab")
		)
		(fp_line
			(start -0.12065 -0.2794)
			(end 0.12065 -0.2794)
			(stroke
				(width 0.1)
				(type default)
			)
			(layer "F.Fab")
		)
		(fp_line
			(start 0.120396 0.2794)
			(end -0.12065 0.2794)
			(stroke
				(width 0.1)
				(type default)
			)
			(layer "F.Fab")
		)
		(fp_line
			(start -0.12065 0.2794)
			(end -0.12065 0.3048)
			(stroke
				(width 0.1)
				(type default)
			)
			(layer "F.Fab")
		)
		(fp_line
			(start 0.67945 0.3048)
			(end 0.120396 0.3048)
			(stroke
				(width 0.1)
				(type default)
			)
			(layer "F.Fab")
		)
		(fp_line
			(start 0.120396 0.3048)
			(end 0.120396 0.2794)
			(stroke
				(width 0.1)
				(type default)
			)
			(layer "F.Fab")
		)
		(fp_line
			(start -0.12065 0.3048)
			(end -0.67945 0.3048)
			(stroke
				(width 0.1)
				(type default)
			)
			(layer "F.Fab")
		)
		(fp_line
			(start -0.67945 0.3048)
			(end -0.67945 -0.305054)
			(stroke
				(width 0.1)
				(type default)
			)
			(layer "F.Fab")
		)
		(pad "1" smd circle
			(at -0.40005 0 90)
			(size 0 0)
			(layers "F.Cu" "F.Mask" "F.Paste")
			(net "PVCCIN_CPU0")
		)
		(pad "2" smd circle
			(at 0.40005 0 90)
			(size 0 0)
			(layers "F.Cu" "F.Mask" "F.Paste")
			(net "GND")
		)
	)
	(footprint ""
		(layer "F.Cu")
		(at 248.20753 -52.177442 90)
		(property "Reference" "PR3950"
			(at 0 0 90)
			(layer "F.SilkS")
			(hide yes)
			(effects
				(font
					(size 1.27 1.27)
				)
			)
		)
		(property "Value" ""
			(at 0 0 90)
			(layer "F.Fab")
			(effects
				(font
					(size 1.27 1.27)
				)
			)
		)
		(duplicate_pad_numbers_are_jumpers no)
		(fp_line
			(start 0.7874 -0.4064)
			(end 0.7874 0.4064)
			(stroke
				(width 0.1524)
				(type default)
			)
			(layer "F.SilkS")
		)
		(fp_line
			(start -0.7874 -0.4064)
			(end 0.7874 -0.4064)
			(stroke
				(width 0.1524)
				(type default)
			)
			(layer "F.SilkS")
		)
		(fp_line
			(start 0.7874 0.4064)
			(end -0.7874 0.4064)
			(stroke
				(width 0.1524)
				(type default)
			)
			(layer "F.SilkS")
		)
		(fp_line
			(start -0.7874 0.4064)
			(end -0.7874 -0.4064)
			(stroke
				(width 0.1524)
				(type default)
			)
			(layer "F.SilkS")
		)
		(fp_line
			(start -0.12065 -0.305054)
			(end -0.12065 -0.2794)
			(stroke
				(width 0.1)
				(type default)
			)
			(layer "F.Fab")
		)
		(fp_line
			(start -0.67945 -0.305054)
			(end -0.12065 -0.305054)
			(stroke
				(width 0.1)
				(type default)
			)
			(layer "F.Fab")
		)
		(fp_line
			(start 0.67945 -0.3048)
			(end 0.67945 0.3048)
			(stroke
				(width 0.1)
				(type default)
			)
			(layer "F.Fab")
		)
		(fp_line
			(start 0.12065 -0.3048)
			(end 0.67945 -0.3048)
			(stroke
				(width 0.1)
				(type default)
			)
			(layer "F.Fab")
		)
		(fp_line
			(start 0.12065 -0.2794)
			(end 0.12065 -0.3048)
			(stroke
				(width 0.1)
				(type default)
			)
			(layer "F.Fab")
		)
		(fp_line
			(start -0.12065 -0.2794)
			(end 0.12065 -0.2794)
			(stroke
				(width 0.1)
				(type default)
			)
			(layer "F.Fab")
		)
		(fp_line
			(start 0.120396 0.2794)
			(end -0.12065 0.2794)
			(stroke
				(width 0.1)
				(type default)
			)
			(layer "F.Fab")
		)
		(fp_line
			(start -0.12065 0.2794)
			(end -0.12065 0.3048)
			(stroke
				(width 0.1)
				(type default)
			)
			(layer "F.Fab")
		)
		(fp_line
			(start 0.67945 0.3048)
			(end 0.120396 0.3048)
			(stroke
				(width 0.1)
				(type default)
			)
			(layer "F.Fab")
		)
		(fp_line
			(start 0.120396 0.3048)
			(end 0.120396 0.2794)
			(stroke
				(width 0.1)
				(type default)
			)
			(layer "F.Fab")
		)
		(fp_line
			(start -0.12065 0.3048)
			(end -0.67945 0.3048)
			(stroke
				(width 0.1)
				(type default)
			)
			(layer "F.Fab")
		)
		(fp_line
			(start -0.67945 0.3048)
			(end -0.67945 -0.305054)
			(stroke
				(width 0.1)
				(type default)
			)
			(layer "F.Fab")
		)
		(pad "1" smd circle
			(at -0.40005 0 90)
			(size 0 0)
			(layers "F.Cu" "F.Mask" "F.Paste")
			(net "P12V_E1S_0")
		)
		(pad "2" smd circle
			(at 0.40005 0 90)
			(size 0 0)
			(layers "F.Cu" "F.Mask" "F.Paste")
			(net "P12V_E1S_AVIN_PD_0")
		)
	)
	(footprint ""
		(layer "F.Cu")
		(at 173.597062 -32.935672 90)
		(property "Reference" "PR4005"
			(at 0 0 90)
			(layer "F.SilkS")
			(hide yes)
			(effects
				(font
					(size 1.27 1.27)
				)
			)
		)
		(property "Value" ""
			(at 0 0 90)
			(layer "F.Fab")
			(effects
				(font
					(size 1.27 1.27)
				)
			)
		)
		(duplicate_pad_numbers_are_jumpers no)
		(fp_line
			(start 0.7874 -0.4064)
			(end 0.7874 0.4064)
			(stroke
				(width 0.1524)
				(type default)
			)
			(layer "F.SilkS")
		)
		(fp_line
			(start -0.7874 -0.4064)
			(end 0.7874 -0.4064)
			(stroke
				(width 0.1524)
				(type default)
			)
			(layer "F.SilkS")
		)
		(fp_line
			(start 0.7874 0.4064)
			(end -0.7874 0.4064)
			(stroke
				(width 0.1524)
				(type default)
			)
			(layer "F.SilkS")
		)
		(fp_line
			(start -0.7874 0.4064)
			(end -0.7874 -0.4064)
			(stroke
				(width 0.1524)
				(type default)
			)
			(layer "F.SilkS")
		)
		(fp_line
			(start -0.12065 -0.305054)
			(end -0.12065 -0.2794)
			(stroke
				(width 0.1)
				(type default)
			)
			(layer "F.Fab")
		)
		(fp_line
			(start -0.67945 -0.305054)
			(end -0.12065 -0.305054)
			(stroke
				(width 0.1)
				(type default)
			)
			(layer "F.Fab")
		)
		(fp_line
			(start 0.67945 -0.3048)
			(end 0.67945 0.3048)
			(stroke
				(width 0.1)
				(type default)
			)
			(layer "F.Fab")
		)
		(fp_line
			(start 0.12065 -0.3048)
			(end 0.67945 -0.3048)
			(stroke
				(width 0.1)
				(type default)
			)
			(layer "F.Fab")
		)
		(fp_line
			(start 0.12065 -0.2794)
			(end 0.12065 -0.3048)
			(stroke
				(width 0.1)
				(type default)
			)
			(layer "F.Fab")
		)
		(fp_line
			(start -0.12065 -0.2794)
			(end 0.12065 -0.2794)
			(stroke
				(width 0.1)
				(type default)
			)
			(layer "F.Fab")
		)
		(fp_line
			(start 0.120396 0.2794)
			(end -0.12065 0.2794)
			(stroke
				(width 0.1)
				(type default)
			)
			(layer "F.Fab")
		)
		(fp_line
			(start -0.12065 0.2794)
			(end -0.12065 0.3048)
			(stroke
				(width 0.1)
				(type default)
			)
			(layer "F.Fab")
		)
		(fp_line
			(start 0.67945 0.3048)
			(end 0.120396 0.3048)
			(stroke
				(width 0.1)
				(type default)
			)
			(layer "F.Fab")
		)
		(fp_line
			(start 0.120396 0.3048)
			(end 0.120396 0.2794)
			(stroke
				(width 0.1)
				(type default)
			)
			(layer "F.Fab")
		)
		(fp_line
			(start -0.12065 0.3048)
			(end -0.67945 0.3048)
			(stroke
				(width 0.1)
				(type default)
			)
			(layer "F.Fab")
		)
		(fp_line
			(start -0.67945 0.3048)
			(end -0.67945 -0.305054)
			(stroke
				(width 0.1)
				(type default)
			)
			(layer "F.Fab")
		)
		(pad "1" smd circle
			(at -0.40005 0 90)
			(size 0 0)
			(layers "F.Cu" "F.Mask" "F.Paste")
			(net "P12V_SCM_IMON")
		)
		(pad "2" smd circle
			(at 0.40005 0 90)
			(size 0 0)
			(layers "F.Cu" "F.Mask" "F.Paste")
			(net "GND")
		)
	)
	(footprint ""
		(layer "F.Cu")
		(at 415.4678 -17.612614 90)
		(property "Reference" "C856"
			(at 0 0 90)
			(layer "F.SilkS")
			(hide yes)
			(effects
				(font
					(size 1.27 1.27)
				)
			)
		)
		(property "Value" ""
			(at 0 0 90)
			(layer "F.Fab")
			(effects
				(font
					(size 1.27 1.27)
				)
			)
		)
		(duplicate_pad_numbers_are_jumpers no)
		(fp_line
			(start 0.299974 -0.150114)
			(end 0.299974 0.150114)
			(stroke
				(width 0.1)
				(type default)
			)
			(layer "F.Fab")
		)
		(fp_line
			(start -0.299974 -0.150114)
			(end 0.299974 -0.150114)
			(stroke
				(width 0.1)
				(type default)
			)
			(layer "F.Fab")
		)
		(fp_line
			(start 0.299974 0.150114)
			(end -0.299974 0.150114)
			(stroke
				(width 0.1)
				(type default)
			)
			(layer "F.Fab")
		)
		(fp_line
			(start -0.299974 0.150114)
			(end -0.299974 -0.150114)
			(stroke
				(width 0.1)
				(type default)
			)
			(layer "F.Fab")
		)
		(pad "1" smd rect
			(at -0.2667 0 90)
			(size 0.3048 0.381)
			(layers "F.Cu" "F.Mask" "F.Paste")
			(net "P5E_CPU0_PE1_TX_C_DN<6>")
		)
		(pad "2" smd rect
			(at 0.2667 0 90)
			(size 0.3048 0.381)
			(layers "F.Cu" "F.Mask" "F.Paste")
			(net "P5E_CPU0_PE1_TX_DN<6>")
		)
	)
	(footprint ""
		(layer "F.Cu")
		(at 116.367306 -30.720792 180)
		(property "Reference" "R3190"
			(at 0 0 180)
			(layer "F.SilkS")
			(hide yes)
			(effects
				(font
					(size 1.27 1.27)
				)
			)
		)
		(property "Value" ""
			(at 0 0 180)
			(layer "F.Fab")
			(effects
				(font
					(size 1.27 1.27)
				)
			)
		)
		(duplicate_pad_numbers_are_jumpers no)
		(fp_line
			(start 0.7874 0.4064)
			(end -0.7874 0.4064)
			(stroke
				(width 0.1524)
				(type default)
			)
			(layer "F.SilkS")
		)
		(fp_line
			(start 0.7874 -0.4064)
			(end 0.7874 0.4064)
			(stroke
				(width 0.1524)
				(type default)
			)
			(layer "F.SilkS")
		)
		(fp_line
			(start -0.7874 0.4064)
			(end -0.7874 -0.4064)
			(stroke
				(width 0.1524)
				(type default)
			)
			(layer "F.SilkS")
		)
		(fp_line
			(start -0.7874 -0.4064)
			(end 0.7874 -0.4064)
			(stroke
				(width 0.1524)
				(type default)
			)
			(layer "F.SilkS")
		)
		(fp_line
			(start 0.67945 0.3048)
			(end 0.120396 0.3048)
			(stroke
				(width 0.1)
				(type default)
			)
			(layer "F.Fab")
		)
		(fp_line
			(start 0.67945 -0.3048)
			(end 0.67945 0.3048)
			(stroke
				(width 0.1)
				(type default)
			)
			(layer "F.Fab")
		)
		(fp_line
			(start 0.12065 -0.2794)
			(end 0.12065 -0.3048)
			(stroke
				(width 0.1)
				(type default)
			)
			(layer "F.Fab")
		)
		(fp_line
			(start 0.12065 -0.3048)
			(end 0.67945 -0.3048)
			(stroke
				(width 0.1)
				(type default)
			)
			(layer "F.Fab")
		)
		(fp_line
			(start 0.120396 0.3048)
			(end 0.120396 0.2794)
			(stroke
				(width 0.1)
				(type default)
			)
			(layer "F.Fab")
		)
		(fp_line
			(start 0.120396 0.2794)
			(end -0.12065 0.2794)
			(stroke
				(width 0.1)
				(type default)
			)
			(layer "F.Fab")
		)
		(fp_line
			(start -0.12065 0.3048)
			(end -0.67945 0.3048)
			(stroke
				(width 0.1)
				(type default)
			)
			(layer "F.Fab")
		)
		(fp_line
			(start -0.12065 0.2794)
			(end -0.12065 0.3048)
			(stroke
				(width 0.1)
				(type default)
			)
			(layer "F.Fab")
		)
		(fp_line
			(start -0.12065 -0.2794)
			(end 0.12065 -0.2794)
			(stroke
				(width 0.1)
				(type default)
			)
			(layer "F.Fab")
		)
		(fp_line
			(start -0.12065 -0.305054)
			(end -0.12065 -0.2794)
			(stroke
				(width 0.1)
				(type default)
			)
			(layer "F.Fab")
		)
		(fp_line
			(start -0.67945 0.3048)
			(end -0.67945 -0.305054)
			(stroke
				(width 0.1)
				(type default)
			)
			(layer "F.Fab")
		)
		(fp_line
			(start -0.67945 -0.305054)
			(end -0.12065 -0.305054)
			(stroke
				(width 0.1)
				(type default)
			)
			(layer "F.Fab")
		)
		(pad "1" smd circle
			(at -0.40005 0 180)
			(size 0 0)
			(layers "F.Cu" "F.Mask" "F.Paste")
			(net "P3V3_AUX")
		)
		(pad "2" smd circle
			(at 0.40005 0 180)
			(size 0 0)
			(layers "F.Cu" "F.Mask" "F.Paste")
			(net "OCP_V3_2_PWRBRK_BUFF_N")
		)
	)
	(footprint ""
		(layer "F.Cu")
		(at 127.170434 -402.371052 -90)
		(property "Reference" "C746"
			(at 0 0 270)
			(layer "F.SilkS")
			(hide yes)
			(effects
				(font
					(size 1.27 1.27)
				)
			)
		)
		(property "Value" ""
			(at 0 0 270)
			(layer "F.Fab")
			(effects
				(font
					(size 1.27 1.27)
				)
			)
		)
		(duplicate_pad_numbers_are_jumpers no)
		(fp_line
			(start -0.299974 0.150114)
			(end -0.299974 -0.150114)
			(stroke
				(width 0.1)
				(type default)
			)
			(layer "F.Fab")
		)
		(fp_line
			(start 0.299974 0.150114)
			(end -0.299974 0.150114)
			(stroke
				(width 0.1)
				(type default)
			)
			(layer "F.Fab")
		)
		(fp_line
			(start -0.299974 -0.150114)
			(end 0.299974 -0.150114)
			(stroke
				(width 0.1)
				(type default)
			)
			(layer "F.Fab")
		)
		(fp_line
			(start 0.299974 -0.150114)
			(end 0.299974 0.150114)
			(stroke
				(width 0.1)
				(type default)
			)
			(layer "F.Fab")
		)
		(pad "1" smd rect
			(at -0.2667 0 270)
			(size 0.3048 0.381)
			(layers "F.Cu" "F.Mask" "F.Paste")
			(net "P5E_CPU1_PE2_TX_C_DN<13>")
		)
		(pad "2" smd rect
			(at 0.2667 0 270)
			(size 0.3048 0.381)
			(layers "F.Cu" "F.Mask" "F.Paste")
			(net "P5E_CPU1_PE2_TX_DN<13>")
		)
	)
	(footprint ""
		(layer "F.Cu")
		(at 488.03433 -148.048472 90)
		(property "Reference" "X22"
			(at -3.517392 3.52298 90)
			(unlocked yes)
			(layer "F.SilkS")
			(effects
				(font
					(size 0.7874 0.5842)
					(thickness 0.1524)
				)
				(justify left)
			)
		)
		(property "Value" ""
			(at 0 0 90)
			(layer "F.Fab")
			(effects
				(font
					(size 1.27 1.27)
				)
			)
		)
		(property "Device Type" "TP_TDR_4P_FTS_TH-TP_TDR_4P_DIPA"
			(at 1.30175 1.27 180)
			(unlocked yes)
			(layer "F.Fab")
			(hide yes)
			(effects
				(font
					(size 0.635 0.4064)
					(thickness 0.1524)
				)
			)
		)
		(property "User Part Number" "N_A"
			(at 1.30175 1.27 180)
			(unlocked yes)
			(layer "Cmts.User")
			(hide yes)
			(effects
				(font
					(size 0.635 0.4064)
					(thickness 0.1524)
				)
			)
		)
		(duplicate_pad_numbers_are_jumpers no)
		(fp_line
			(start 2.54 -1.27)
			(end 0 -1.27)
			(stroke
				(width 0.1524)
				(type default)
			)
			(layer "F.SilkS")
		)
		(fp_line
			(start 0 -1.27)
			(end 0 -0.635)
			(stroke
				(width 0.1524)
				(type default)
			)
			(layer "F.SilkS")
		)
		(fp_line
			(start 2.54 -1.1303)
			(end 2.54 -1.27)
			(stroke
				(width 0.1524)
				(type default)
			)
			(layer "F.SilkS")
		)
		(fp_line
			(start 0 0.635)
			(end 0 1.905)
			(stroke
				(width 0.1524)
				(type default)
			)
			(layer "F.SilkS")
		)
		(fp_line
			(start 2.54 1.4097)
			(end 2.54 1.1303)
			(stroke
				(width 0.1524)
				(type default)
			)
			(layer "F.SilkS")
		)
		(fp_line
			(start 0 3.175)
			(end 0 3.81)
			(stroke
				(width 0.1524)
				(type default)
			)
			(layer "F.SilkS")
		)
		(fp_line
			(start 2.54 3.81)
			(end 2.54 3.6703)
			(stroke
				(width 0.1524)
				(type default)
			)
			(layer "F.SilkS")
		)
		(fp_line
			(start 0 3.81)
			(end 2.54 3.81)
			(stroke
				(width 0.1524)
				(type default)
			)
			(layer "F.SilkS")
		)
		(fp_poly
			(pts
				(xy -0.761746 0) (xy -2.285746 0.762) (xy -2.285746 -0.762)
			)
			(stroke
				(width 0)
				(type default)
			)
			(fill yes)
			(layer "F.SilkS")
		)
		(fp_line
			(start 2.54 -1.27)
			(end 0 -1.27)
			(stroke
				(width 0.1)
				(type default)
			)
			(layer "F.Fab")
		)
		(fp_line
			(start 0 -1.27)
			(end 0 3.81)
			(stroke
				(width 0.1)
				(type default)
			)
			(layer "F.Fab")
		)
		(fp_line
			(start 2.54 3.81)
			(end 2.54 -1.27)
			(stroke
				(width 0.1)
				(type default)
			)
			(layer "F.Fab")
		)
		(fp_line
			(start 0 3.81)
			(end 2.54 3.81)
			(stroke
				(width 0.1)
				(type default)
			)
			(layer "F.Fab")
		)
		(fp_poly
			(pts
				(xy -0.761746 0) (xy -2.285746 -0.762) (xy -2.285746 0.762)
			)
			(stroke
				(width 0)
				(type default)
			)
			(fill yes)
			(layer "F.Fab")
		)
		(pad "1" thru_hole circle
			(at 0 0 90)
			(size 1.0033 1.0033)
			(drill 0.249936)
			(layers "*.Cu" "*.Mask")
			(remove_unused_layers no)
			(net "TDR_DIFF_100_IN3_DN")
			(clearance 0.10795)
			(thermal_gap 0.10795)
			(padstack
				(mode front_inner_back)
				(layer "Inner"
					(shape circle)
					(size 0.8001 0.8001)
					(clearance 0.1524)
				)
				(layer "B.Cu"
					(shape circle)
					(size 1.0033 1.0033)
					(clearance 0.10795)
				)
			)
		)
		(pad "2" thru_hole circle
			(at 2.54 0 90)
			(size 1.9939 1.9939)
			(drill 0.249936)
			(layers "*.Cu" "*.Mask")
			(remove_unused_layers no)
			(net "T1_GND")
			(clearance 0.10795)
			(thermal_gap 0.10795)
			(padstack
				(mode front_inner_back)
				(layer "Inner"
					(shape circle)
					(size 0.8001 0.8001)
					(clearance 0.1524)
				)
				(layer "B.Cu"
					(shape circle)
					(size 1.9939 1.9939)
					(clearance 0.10795)
				)
			)
		)
		(pad "3" thru_hole circle
			(at 2.54 2.54 90)
			(size 1.9939 1.9939)
			(drill 0.249936)
			(layers "*.Cu" "*.Mask")
			(remove_unused_layers no)
			(net "T1_GND")
			(clearance 0.10795)
			(thermal_gap 0.10795)
			(padstack
				(mode front_inner_back)
				(layer "Inner"
					(shape circle)
					(size 0.8001 0.8001)
					(clearance 0.1524)
				)
				(layer "B.Cu"
					(shape circle)
					(size 1.9939 1.9939)
					(clearance 0.10795)
				)
			)
		)
		(pad "4" thru_hole circle
			(at 0 2.54 90)
			(size 1.0033 1.0033)
			(drill 0.249936)
			(layers "*.Cu" "*.Mask")
			(remove_unused_layers no)
			(net "TDR_DIFF_100_IN3_DP")
			(clearance 0.10795)
			(thermal_gap 0.10795)
			(padstack
				(mode front_inner_back)
				(layer "Inner"
					(shape circle)
					(size 0.8001 0.8001)
					(clearance 0.1524)
				)
				(layer "B.Cu"
					(shape circle)
					(size 1.0033 1.0033)
					(clearance 0.10795)
				)
			)
		)
	)
	(footprint ""
		(layer "F.Cu")
		(at 424.204892 -390.616948 180)
		(property "Reference" "C1754"
			(at 0 0 180)
			(layer "F.SilkS")
			(hide yes)
			(effects
				(font
					(size 1.27 1.27)
				)
			)
		)
		(property "Value" ""
			(at 0 0 180)
			(layer "F.Fab")
			(effects
				(font
					(size 1.27 1.27)
				)
			)
		)
		(duplicate_pad_numbers_are_jumpers no)
		(fp_line
			(start 0.7874 0.4064)
			(end -0.7874 0.4064)
			(stroke
				(width 0.1524)
				(type default)
			)
			(layer "F.SilkS")
		)
		(fp_line
			(start 0.7874 -0.4064)
			(end 0.7874 0.4064)
			(stroke
				(width 0.1524)
				(type default)
			)
			(layer "F.SilkS")
		)
		(fp_line
			(start -0.7874 0.4064)
			(end -0.7874 -0.4064)
			(stroke
				(width 0.1524)
				(type default)
			)
			(layer "F.SilkS")
		)
		(fp_line
			(start -0.7874 -0.4064)
			(end 0.7874 -0.4064)
			(stroke
				(width 0.1524)
				(type default)
			)
			(layer "F.SilkS")
		)
		(fp_line
			(start 0.67945 0.3048)
			(end 0.120396 0.3048)
			(stroke
				(width 0.1)
				(type default)
			)
			(layer "F.Fab")
		)
		(fp_line
			(start 0.67945 -0.3048)
			(end 0.67945 0.3048)
			(stroke
				(width 0.1)
				(type default)
			)
			(layer "F.Fab")
		)
		(fp_line
			(start 0.12065 -0.2794)
			(end 0.12065 -0.3048)
			(stroke
				(width 0.1)
				(type default)
			)
			(layer "F.Fab")
		)
		(fp_line
			(start 0.12065 -0.3048)
			(end 0.67945 -0.3048)
			(stroke
				(width 0.1)
				(type default)
			)
			(layer "F.Fab")
		)
		(fp_line
			(start 0.120396 0.3048)
			(end 0.120396 0.2794)
			(stroke
				(width 0.1)
				(type default)
			)
			(layer "F.Fab")
		)
		(fp_line
			(start 0.120396 0.2794)
			(end -0.12065 0.2794)
			(stroke
				(width 0.1)
				(type default)
			)
			(layer "F.Fab")
		)
		(fp_line
			(start -0.12065 0.3048)
			(end -0.67945 0.3048)
			(stroke
				(width 0.1)
				(type default)
			)
			(layer "F.Fab")
		)
		(fp_line
			(start -0.12065 0.2794)
			(end -0.12065 0.3048)
			(stroke
				(width 0.1)
				(type default)
			)
			(layer "F.Fab")
		)
		(fp_line
			(start -0.12065 -0.2794)
			(end 0.12065 -0.2794)
			(stroke
				(width 0.1)
				(type default)
			)
			(layer "F.Fab")
		)
		(fp_line
			(start -0.12065 -0.305054)
			(end -0.12065 -0.2794)
			(stroke
				(width 0.1)
				(type default)
			)
			(layer "F.Fab")
		)
		(fp_line
			(start -0.67945 0.3048)
			(end -0.67945 -0.305054)
			(stroke
				(width 0.1)
				(type default)
			)
			(layer "F.Fab")
		)
		(fp_line
			(start -0.67945 -0.305054)
			(end -0.12065 -0.305054)
			(stroke
				(width 0.1)
				(type default)
			)
			(layer "F.Fab")
		)
		(pad "1" smd circle
			(at -0.40005 0 180)
			(size 0 0)
			(layers "F.Cu" "F.Mask" "F.Paste")
			(net "FM_SWB_BIC_READY_ISO_N")
		)
		(pad "2" smd circle
			(at 0.40005 0 180)
			(size 0 0)
			(layers "F.Cu" "F.Mask" "F.Paste")
			(net "GND")
		)
	)
	(footprint ""
		(layer "F.Cu")
		(at 336.018124 -26.856182 -90)
		(property "Reference" "R1961"
			(at 0 0 270)
			(layer "F.SilkS")
			(hide yes)
			(effects
				(font
					(size 1.27 1.27)
				)
			)
		)
		(property "Value" ""
			(at 0 0 270)
			(layer "F.Fab")
			(effects
				(font
					(size 1.27 1.27)
				)
			)
		)
		(duplicate_pad_numbers_are_jumpers no)
		(fp_line
			(start -0.7874 0.4064)
			(end -0.7874 -0.4064)
			(stroke
				(width 0.1524)
				(type default)
			)
			(layer "F.SilkS")
		)
		(fp_line
			(start 0.7874 0.4064)
			(end -0.7874 0.4064)
			(stroke
				(width 0.1524)
				(type default)
			)
			(layer "F.SilkS")
		)
		(fp_line
			(start -0.7874 -0.4064)
			(end 0.7874 -0.4064)
			(stroke
				(width 0.1524)
				(type default)
			)
			(layer "F.SilkS")
		)
		(fp_line
			(start 0.7874 -0.4064)
			(end 0.7874 0.4064)
			(stroke
				(width 0.1524)
				(type default)
			)
			(layer "F.SilkS")
		)
		(fp_line
			(start -0.67945 0.3048)
			(end -0.67945 -0.305054)
			(stroke
				(width 0.1)
				(type default)
			)
			(layer "F.Fab")
		)
		(fp_line
			(start -0.12065 0.3048)
			(end -0.67945 0.3048)
			(stroke
				(width 0.1)
				(type default)
			)
			(layer "F.Fab")
		)
		(fp_line
			(start 0.120396 0.3048)
			(end 0.120396 0.2794)
			(stroke
				(width 0.1)
				(type default)
			)
			(layer "F.Fab")
		)
		(fp_line
			(start 0.67945 0.3048)
			(end 0.120396 0.3048)
			(stroke
				(width 0.1)
				(type default)
			)
			(layer "F.Fab")
		)
		(fp_line
			(start -0.12065 0.2794)
			(end -0.12065 0.3048)
			(stroke
				(width 0.1)
				(type default)
			)
			(layer "F.Fab")
		)
		(fp_line
			(start 0.120396 0.2794)
			(end -0.12065 0.2794)
			(stroke
				(width 0.1)
				(type default)
			)
			(layer "F.Fab")
		)
		(fp_line
			(start -0.12065 -0.2794)
			(end 0.12065 -0.2794)
			(stroke
				(width 0.1)
				(type default)
			)
			(layer "F.Fab")
		)
		(fp_line
			(start 0.12065 -0.2794)
			(end 0.12065 -0.3048)
			(stroke
				(width 0.1)
				(type default)
			)
			(layer "F.Fab")
		)
		(fp_line
			(start 0.12065 -0.3048)
			(end 0.67945 -0.3048)
			(stroke
				(width 0.1)
				(type default)
			)
			(layer "F.Fab")
		)
		(fp_line
			(start 0.67945 -0.3048)
			(end 0.67945 0.3048)
			(stroke
				(width 0.1)
				(type default)
			)
			(layer "F.Fab")
		)
		(fp_line
			(start -0.67945 -0.305054)
			(end -0.12065 -0.305054)
			(stroke
				(width 0.1)
				(type default)
			)
			(layer "F.Fab")
		)
		(fp_line
			(start -0.12065 -0.305054)
			(end -0.12065 -0.2794)
			(stroke
				(width 0.1)
				(type default)
			)
			(layer "F.Fab")
		)
		(pad "1" smd circle
			(at -0.40005 0 270)
			(size 0 0)
			(layers "F.Cu" "F.Mask" "F.Paste")
			(net "PGPPA_AUX")
		)
		(pad "2" smd circle
			(at 0.40005 0 270)
			(size 0 0)
			(layers "F.Cu" "F.Mask" "F.Paste")
			(net "ESPI_LFRAME_N_BMC_CS0_N")
		)
	)
	(footprint ""
		(layer "F.Cu")
		(at 65.52946 -379.03912)
		(property "Reference" "ME12"
			(at -9.652 -9.540748 0)
			(unlocked yes)
			(layer "F.SilkS")
			(effects
				(font
					(size 0.7874 0.5842)
					(thickness 0.1524)
				)
				(justify left)
			)
		)
		(property "Value" ""
			(at 0 0 0)
			(layer "F.Fab")
			(effects
				(font
					(size 1.27 1.27)
				)
			)
		)
		(duplicate_pad_numbers_are_jumpers no)
		(zone
			(layer "F.Cu")
			(hatch none 0.5)
			(connect_pads
				(clearance 0)
			)
			(min_thickness 0.25)
			(keepout
				(tracks allowed)
				(vias allowed)
				(pads allowed)
				(copperpour allowed)
				(footprints not_allowed)
			)
			(placement
				(enabled no)
				(sheetname "")
			)
			(fill
				(thermal_gap 0.5)
				(thermal_bridge_width 0.5)
				(island_removal_mode 0)
			)
			(polygon
				(pts
					(arc
						(start 75.52944 -379.03912)
						(mid 55.52948 -379.03912)
						(end 75.52944 -379.03912)
					)
				)
			)
		)
	)
	(footprint ""
		(layer "F.Cu")
		(at 308.33314 -433.12461 90)
		(property "Reference" "R4123"
			(at 0 0 90)
			(layer "F.SilkS")
			(hide yes)
			(effects
				(font
					(size 1.27 1.27)
				)
			)
		)
		(property "Value" ""
			(at 0 0 90)
			(layer "F.Fab")
			(effects
				(font
					(size 1.27 1.27)
				)
			)
		)
		(duplicate_pad_numbers_are_jumpers no)
		(fp_line
			(start 0.7874 -0.4064)
			(end 0.7874 0.4064)
			(stroke
				(width 0.1524)
				(type default)
			)
			(layer "F.SilkS")
		)
		(fp_line
			(start -0.7874 -0.4064)
			(end 0.7874 -0.4064)
			(stroke
				(width 0.1524)
				(type default)
			)
			(layer "F.SilkS")
		)
		(fp_line
			(start 0.7874 0.4064)
			(end -0.7874 0.4064)
			(stroke
				(width 0.1524)
				(type default)
			)
			(layer "F.SilkS")
		)
		(fp_line
			(start -0.7874 0.4064)
			(end -0.7874 -0.4064)
			(stroke
				(width 0.1524)
				(type default)
			)
			(layer "F.SilkS")
		)
		(fp_line
			(start -0.12065 -0.305054)
			(end -0.12065 -0.2794)
			(stroke
				(width 0.1)
				(type default)
			)
			(layer "F.Fab")
		)
		(fp_line
			(start -0.67945 -0.305054)
			(end -0.12065 -0.305054)
			(stroke
				(width 0.1)
				(type default)
			)
			(layer "F.Fab")
		)
		(fp_line
			(start 0.67945 -0.3048)
			(end 0.67945 0.3048)
			(stroke
				(width 0.1)
				(type default)
			)
			(layer "F.Fab")
		)
		(fp_line
			(start 0.12065 -0.3048)
			(end 0.67945 -0.3048)
			(stroke
				(width 0.1)
				(type default)
			)
			(layer "F.Fab")
		)
		(fp_line
			(start 0.12065 -0.2794)
			(end 0.12065 -0.3048)
			(stroke
				(width 0.1)
				(type default)
			)
			(layer "F.Fab")
		)
		(fp_line
			(start -0.12065 -0.2794)
			(end 0.12065 -0.2794)
			(stroke
				(width 0.1)
				(type default)
			)
			(layer "F.Fab")
		)
		(fp_line
			(start 0.120396 0.2794)
			(end -0.12065 0.2794)
			(stroke
				(width 0.1)
				(type default)
			)
			(layer "F.Fab")
		)
		(fp_line
			(start -0.12065 0.2794)
			(end -0.12065 0.3048)
			(stroke
				(width 0.1)
				(type default)
			)
			(layer "F.Fab")
		)
		(fp_line
			(start 0.67945 0.3048)
			(end 0.120396 0.3048)
			(stroke
				(width 0.1)
				(type default)
			)
			(layer "F.Fab")
		)
		(fp_line
			(start 0.120396 0.3048)
			(end 0.120396 0.2794)
			(stroke
				(width 0.1)
				(type default)
			)
			(layer "F.Fab")
		)
		(fp_line
			(start -0.12065 0.3048)
			(end -0.67945 0.3048)
			(stroke
				(width 0.1)
				(type default)
			)
			(layer "F.Fab")
		)
		(fp_line
			(start -0.67945 0.3048)
			(end -0.67945 -0.305054)
			(stroke
				(width 0.1)
				(type default)
			)
			(layer "F.Fab")
		)
		(pad "1" smd circle
			(at -0.40005 0 90)
			(size 0 0)
			(layers "F.Cu" "F.Mask" "F.Paste")
			(net "P3V3_AUX")
		)
		(pad "2" smd circle
			(at 0.40005 0 90)
			(size 0 0)
			(layers "F.Cu" "F.Mask" "F.Paste")
			(net "GPU_3V3IO_RSVD1_FFU")
		)
	)
	(footprint ""
		(layer "F.Cu")
		(at 19.707352 -167.170608 90)
		(property "Reference" "C1337"
			(at 0 0 90)
			(layer "F.SilkS")
			(hide yes)
			(effects
				(font
					(size 1.27 1.27)
				)
			)
		)
		(property "Value" ""
			(at 0 0 90)
			(layer "F.Fab")
			(effects
				(font
					(size 1.27 1.27)
				)
			)
		)
		(duplicate_pad_numbers_are_jumpers no)
		(fp_line
			(start 0.7874 -0.4064)
			(end 0.7874 0.4064)
			(stroke
				(width 0.1524)
				(type default)
			)
			(layer "F.SilkS")
		)
		(fp_line
			(start -0.7874 -0.4064)
			(end 0.7874 -0.4064)
			(stroke
				(width 0.1524)
				(type default)
			)
			(layer "F.SilkS")
		)
		(fp_line
			(start 0.7874 0.4064)
			(end -0.7874 0.4064)
			(stroke
				(width 0.1524)
				(type default)
			)
			(layer "F.SilkS")
		)
		(fp_line
			(start -0.7874 0.4064)
			(end -0.7874 -0.4064)
			(stroke
				(width 0.1524)
				(type default)
			)
			(layer "F.SilkS")
		)
		(fp_line
			(start -0.12065 -0.305054)
			(end -0.12065 -0.2794)
			(stroke
				(width 0.1)
				(type default)
			)
			(layer "F.Fab")
		)
		(fp_line
			(start -0.67945 -0.305054)
			(end -0.12065 -0.305054)
			(stroke
				(width 0.1)
				(type default)
			)
			(layer "F.Fab")
		)
		(fp_line
			(start 0.67945 -0.3048)
			(end 0.67945 0.3048)
			(stroke
				(width 0.1)
				(type default)
			)
			(layer "F.Fab")
		)
		(fp_line
			(start 0.12065 -0.3048)
			(end 0.67945 -0.3048)
			(stroke
				(width 0.1)
				(type default)
			)
			(layer "F.Fab")
		)
		(fp_line
			(start 0.12065 -0.2794)
			(end 0.12065 -0.3048)
			(stroke
				(width 0.1)
				(type default)
			)
			(layer "F.Fab")
		)
		(fp_line
			(start -0.12065 -0.2794)
			(end 0.12065 -0.2794)
			(stroke
				(width 0.1)
				(type default)
			)
			(layer "F.Fab")
		)
		(fp_line
			(start 0.120396 0.2794)
			(end -0.12065 0.2794)
			(stroke
				(width 0.1)
				(type default)
			)
			(layer "F.Fab")
		)
		(fp_line
			(start -0.12065 0.2794)
			(end -0.12065 0.3048)
			(stroke
				(width 0.1)
				(type default)
			)
			(layer "F.Fab")
		)
		(fp_line
			(start 0.67945 0.3048)
			(end 0.120396 0.3048)
			(stroke
				(width 0.1)
				(type default)
			)
			(layer "F.Fab")
		)
		(fp_line
			(start 0.120396 0.3048)
			(end 0.120396 0.2794)
			(stroke
				(width 0.1)
				(type default)
			)
			(layer "F.Fab")
		)
		(fp_line
			(start -0.12065 0.3048)
			(end -0.67945 0.3048)
			(stroke
				(width 0.1)
				(type default)
			)
			(layer "F.Fab")
		)
		(fp_line
			(start -0.67945 0.3048)
			(end -0.67945 -0.305054)
			(stroke
				(width 0.1)
				(type default)
			)
			(layer "F.Fab")
		)
		(pad "1" smd circle
			(at -0.40005 0 90)
			(size 0 0)
			(layers "F.Cu" "F.Mask" "F.Paste")
			(net "PVNN_TERM_CPU1")
		)
		(pad "2" smd circle
			(at 0.40005 0 90)
			(size 0 0)
			(layers "F.Cu" "F.Mask" "F.Paste")
			(net "GND")
		)
	)
	(footprint ""
		(layer "F.Cu")
		(at 360.544618 -343.902284 90)
		(property "Reference" "PC315"
			(at 0 0 90)
			(layer "F.SilkS")
			(hide yes)
			(effects
				(font
					(size 1.27 1.27)
				)
			)
		)
		(property "Value" ""
			(at 0 0 90)
			(layer "F.Fab")
			(effects
				(font
					(size 1.27 1.27)
				)
			)
		)
		(duplicate_pad_numbers_are_jumpers no)
		(fp_line
			(start -3.400044 1.249934)
			(end 3.400044 1.249934)
			(stroke
				(width 0.1524)
				(type default)
			)
			(layer "F.SilkS")
		)
		(fp_circle
			(center 0 1.249934)
			(end 0 4.649978)
			(stroke
				(width 0.1524)
				(type default)
			)
			(fill no)
			(layer "F.SilkS")
		)
		(fp_poly
			(pts
				(arc
					(start -3.400044 1.249934)
					(mid 0 4.649978)
					(end 3.400044 1.249934)
				)
			)
			(stroke
				(width 0)
				(type default)
			)
			(fill yes)
			(layer "F.SilkS")
		)
		(fp_circle
			(center 0 1.249934)
			(end 0 4.649978)
			(stroke
				(width 0.1)
				(type default)
			)
			(fill no)
			(layer "F.Fab")
		)
		(pad "1" thru_hole rect
			(at 0 0 90)
			(size 1.524 1.524)
			(drill 1.016)
			(layers "*.Cu" "*.Mask")
			(remove_unused_layers no)
			(net "SW_P12V_PVCCIN_CPU0_FLT")
			(clearance 0)
			(padstack
				(mode front_inner_back)
				(layer "Inner"
					(shape circle)
					(size 1.524 1.524)
					(clearance 0)
				)
				(layer "B.Cu"
					(shape rect)
					(size 1.524 1.524)
					(clearance 0)
				)
			)
		)
		(pad "2" thru_hole circle
			(at 0 2.500122 90)
			(size 1.524 1.524)
			(drill 1.016)
			(layers "*.Cu" "*.Mask")
			(remove_unused_layers no)
			(net "GND")
			(clearance 0)
		)
	)
	(footprint ""
		(layer "F.Cu")
		(at 200.172066 -402.722842 180)
		(property "Reference" "PU287"
			(at 0.468376 7.808468 0)
			(unlocked yes)
			(layer "F.SilkS")
			(effects
				(font
					(size 0.7874 0.5842)
					(thickness 0.1524)
				)
			)
		)
		(property "Value" ""
			(at 0 0 180)
			(layer "F.Fab")
			(effects
				(font
					(size 1.27 1.27)
				)
			)
		)
		(duplicate_pad_numbers_are_jumpers no)
		(fp_line
			(start 2.567686 2.567686)
			(end 2.567686 -2.567686)
			(stroke
				(width 0.1524)
				(type default)
			)
			(layer "F.SilkS")
		)
		(fp_line
			(start 2.567686 -2.567686)
			(end -2.567686 -2.567686)
			(stroke
				(width 0.1524)
				(type default)
			)
			(layer "F.SilkS")
		)
		(fp_line
			(start -2.567686 2.567686)
			(end 2.567686 2.567686)
			(stroke
				(width 0.1524)
				(type default)
			)
			(layer "F.SilkS")
		)
		(fp_line
			(start -2.567686 -2.567686)
			(end -2.567686 2.567686)
			(stroke
				(width 0.1524)
				(type default)
			)
			(layer "F.SilkS")
		)
		(fp_poly
			(pts
				(xy -3.055366 -3.35534) (xy -2.69621 -2.277618) (xy -3.773678 -2.636774)
			)
			(stroke
				(width 0)
				(type default)
			)
			(fill yes)
			(layer "F.SilkS")
		)
		(fp_line
			(start 2.549906 2.549906)
			(end 2.549906 -2.549906)
			(stroke
				(width 0.1)
				(type default)
			)
			(layer "F.Fab")
		)
		(fp_line
			(start 2.549906 -2.549906)
			(end -2.549906 -2.549906)
			(stroke
				(width 0.1)
				(type default)
			)
			(layer "F.Fab")
		)
		(fp_line
			(start -2.549906 2.549906)
			(end 2.549906 2.549906)
			(stroke
				(width 0.1)
				(type default)
			)
			(layer "F.Fab")
		)
		(fp_line
			(start -2.549906 -2.549906)
			(end -2.549906 2.549906)
			(stroke
				(width 0.1)
				(type default)
			)
			(layer "F.Fab")
		)
		(fp_poly
			(pts
				(xy -3.806698 -2.25806) (xy -3.806698 -1.24206) (xy -2.790698 -1.75006)
			)
			(stroke
				(width 0)
				(type default)
			)
			(fill yes)
			(layer "F.Fab")
		)
		(pad "1" smd rect
			(at -2.250186 -1.75006 270)
			(size 0.254 0.3556)
			(layers "F.Cu" "F.Mask" "F.Paste")
			(net "P12V_AUX")
		)
		(pad "2" smd rect
			(at -2.237486 -1.249934 270)
			(size 0.254 0.381)
			(layers "F.Cu" "F.Mask" "F.Paste")
			(net "P12V_AUX")
		)
		(pad "3" smd rect
			(at -2.237486 -0.750062 270)
			(size 0.254 0.381)
			(layers "F.Cu" "F.Mask" "F.Paste")
			(net "HSC_D_OC_1")
		)
		(pad "4" smd rect
			(at -2.237486 -0.249936 270)
			(size 0.254 0.381)
			(layers "F.Cu" "F.Mask" "F.Paste")
			(net "HSC_ON")
		)
		(pad "5" smd rect
			(at -2.237486 0.249936 270)
			(size 0.254 0.381)
			(layers "F.Cu" "F.Mask" "F.Paste")
			(net "HSC_FAULT")
		)
		(pad "6" smd rect
			(at -2.237486 0.750062 270)
			(size 0.254 0.381)
			(layers "F.Cu" "F.Mask" "F.Paste")
			(net "HSC_FLT_TYPE_1")
		)
		(pad "7" smd rect
			(at -2.237486 1.249934 270)
			(size 0.254 0.381)
			(layers "F.Cu" "F.Mask" "F.Paste")
			(net "HSC_NC1_1")
		)
		(pad "8" smd rect
			(at -2.250186 1.75006 270)
			(size 0.254 0.3556)
			(layers "F.Cu" "F.Mask" "F.Paste")
			(net "HSC_MODE_1")
		)
		(pad "9" smd rect
			(at -1.75006 2.250186 180)
			(size 0.254 0.3556)
			(layers "F.Cu" "F.Mask" "F.Paste")
			(net "P12V_PSU")
		)
		(pad "10" smd rect
			(at -1.249934 2.237486 180)
			(size 0.254 0.381)
			(layers "F.Cu" "F.Mask" "F.Paste")
			(net "P12V_PSU")
		)
		(pad "11" smd rect
			(at -0.750062 2.237486 180)
			(size 0.254 0.381)
			(layers "F.Cu" "F.Mask" "F.Paste")
			(net "P12V_PSU")
		)
		(pad "12" smd rect
			(at -0.249936 2.237486 180)
			(size 0.254 0.381)
			(layers "F.Cu" "F.Mask" "F.Paste")
			(net "P12V_PSU")
		)
		(pad "13" smd rect
			(at 0.249936 2.237486 180)
			(size 0.254 0.381)
			(layers "F.Cu" "F.Mask" "F.Paste")
			(net "P12V_PSU")
		)
		(pad "14" smd rect
			(at 0.750062 2.237486 180)
			(size 0.254 0.381)
			(layers "F.Cu" "F.Mask" "F.Paste")
			(net "P12V_PSU")
		)
		(pad "15" smd rect
			(at 1.249934 2.237486 180)
			(size 0.254 0.381)
			(layers "F.Cu" "F.Mask" "F.Paste")
			(net "P12V_PSU")
		)
		(pad "16" smd rect
			(at 1.75006 2.250186 180)
			(size 0.254 0.3556)
			(layers "F.Cu" "F.Mask" "F.Paste")
			(net "P12V_PSU")
		)
		(pad "17" smd rect
			(at 2.250186 1.75006 270)
			(size 0.254 0.3556)
			(layers "F.Cu" "F.Mask" "F.Paste")
			(net "HSC_SCREF_1")
		)
		(pad "18" smd rect
			(at 2.237486 1.249934 270)
			(size 0.254 0.381)
			(layers "F.Cu" "F.Mask" "F.Paste")
			(net "HSC_VTEMP")
		)
		(pad "19" smd rect
			(at 2.237486 0.750062 270)
			(size 0.254 0.381)
			(layers "F.Cu" "F.Mask" "F.Paste")
			(net "HSC_SS")
		)
		(pad "20" smd rect
			(at 2.237486 0.249936 270)
			(size 0.254 0.381)
			(layers "F.Cu" "F.Mask" "F.Paste")
			(net "AGND_HSC")
		)
		(pad "21" smd rect
			(at 2.237486 -0.249936 270)
			(size 0.254 0.381)
			(layers "F.Cu" "F.Mask" "F.Paste")
			(net "HSC_VDD_R_1")
		)
		(pad "22" smd rect
			(at 2.237486 -0.750062 270)
			(size 0.254 0.381)
			(layers "F.Cu" "F.Mask" "F.Paste")
			(net "HSC_IMON")
		)
		(pad "23" smd rect
			(at 2.237486 -1.249934 270)
			(size 0.254 0.381)
			(layers "F.Cu" "F.Mask" "F.Paste")
			(net "HSC_CS_1")
		)
		(pad "24" smd rect
			(at 2.250186 -1.75006 270)
			(size 0.254 0.3556)
			(layers "F.Cu" "F.Mask" "F.Paste")
			(net "HSC_OCREF")
		)
		(pad "25" smd rect
			(at 1.75006 -2.250186 180)
			(size 0.254 0.3556)
			(layers "F.Cu" "F.Mask" "F.Paste")
			(net "P12V_AUX")
		)
		(pad "26" smd rect
			(at 1.249934 -2.237486 180)
			(size 0.254 0.381)
			(layers "F.Cu" "F.Mask" "F.Paste")
			(net "P12V_AUX")
		)
		(pad "27" smd rect
			(at 0.750062 -2.237486 180)
			(size 0.254 0.381)
			(layers "F.Cu" "F.Mask" "F.Paste")
			(net "P12V_AUX")
		)
		(pad "28" smd rect
			(at 0.249936 -2.237486 180)
			(size 0.254 0.381)
			(layers "F.Cu" "F.Mask" "F.Paste")
			(net "P12V_AUX")
		)
		(pad "29" smd rect
			(at -0.249936 -2.237486 180)
			(size 0.254 0.381)
			(layers "F.Cu" "F.Mask" "F.Paste")
			(net "P12V_AUX")
		)
		(pad "30" smd rect
			(at -0.750062 -2.237486 180)
			(size 0.254 0.381)
			(layers "F.Cu" "F.Mask" "F.Paste")
			(net "P12V_AUX")
		)
		(pad "31" smd rect
			(at -1.249934 -2.237486 180)
			(size 0.254 0.381)
			(layers "F.Cu" "F.Mask" "F.Paste")
			(net "P12V_AUX")
		)
		(pad "32" smd rect
			(at -1.75006 -2.250186 180)
			(size 0.254 0.3556)
			(layers "F.Cu" "F.Mask" "F.Paste")
			(net "P12V_AUX")
		)
		(pad "33" smd rect
			(at 0 0 180)
			(size 3.4036 3.4036)
			(layers "F.Cu" "F.Mask" "F.Paste")
			(net "P12V_PSU")
		)
		(zone
			(layer "F.Cu")
			(hatch none 0.5)
			(connect_pads
				(clearance 0)
			)
			(min_thickness 0.25)
			(keepout
				(tracks not_allowed)
				(vias allowed)
				(pads allowed)
				(copperpour not_allowed)
				(footprints allowed)
			)
			(placement
				(enabled no)
				(sheetname "")
			)
			(fill
				(thermal_gap 0.5)
				(thermal_bridge_width 0.5)
				(island_removal_mode 0)
			)
			(polygon
				(pts
					(xy 202.193652 -401.275042) (xy 202.193652 -400.845528) (xy 202.04938 -400.701256) (xy 201.619866 -400.701256)
					(xy 201.619866 -400.726656) (xy 198.724266 -400.726656) (xy 198.724266 -400.701256) (xy 198.15048 -400.701256)
					(xy 198.15048 -401.275042) (xy 198.17588 -401.275042) (xy 198.17588 -404.170642) (xy 198.15048 -404.170642)
					(xy 198.15048 -404.475442) (xy 198.419466 -404.475442) (xy 198.419466 -400.970242) (xy 201.924666 -400.970242)
					(xy 201.924666 -403.230842) (xy 202.168252 -403.230842) (xy 202.168252 -401.275042)
				)
			)
		)
	)
	(footprint ""
		(layer "F.Cu")
		(at 46.350428 -97.808034)
		(property "Reference" "C2043"
			(at 0 0 0)
			(layer "F.SilkS")
			(hide yes)
			(effects
				(font
					(size 1.27 1.27)
				)
			)
		)
		(property "Value" ""
			(at 0 0 0)
			(layer "F.Fab")
			(effects
				(font
					(size 1.27 1.27)
				)
			)
		)
		(duplicate_pad_numbers_are_jumpers no)
		(fp_line
			(start -0.7874 -0.4064)
			(end 0.7874 -0.4064)
			(stroke
				(width 0.1524)
				(type default)
			)
			(layer "F.SilkS")
		)
		(fp_line
			(start -0.7874 0.4064)
			(end -0.7874 -0.4064)
			(stroke
				(width 0.1524)
				(type default)
			)
			(layer "F.SilkS")
		)
		(fp_line
			(start 0.7874 -0.4064)
			(end 0.7874 0.4064)
			(stroke
				(width 0.1524)
				(type default)
			)
			(layer "F.SilkS")
		)
		(fp_line
			(start 0.7874 0.4064)
			(end -0.7874 0.4064)
			(stroke
				(width 0.1524)
				(type default)
			)
			(layer "F.SilkS")
		)
		(fp_line
			(start -0.67945 -0.305054)
			(end -0.12065 -0.305054)
			(stroke
				(width 0.1)
				(type default)
			)
			(layer "F.Fab")
		)
		(fp_line
			(start -0.67945 0.3048)
			(end -0.67945 -0.305054)
			(stroke
				(width 0.1)
				(type default)
			)
			(layer "F.Fab")
		)
		(fp_line
			(start -0.12065 -0.305054)
			(end -0.12065 -0.2794)
			(stroke
				(width 0.1)
				(type default)
			)
			(layer "F.Fab")
		)
		(fp_line
			(start -0.12065 -0.2794)
			(end 0.12065 -0.2794)
			(stroke
				(width 0.1)
				(type default)
			)
			(layer "F.Fab")
		)
		(fp_line
			(start -0.12065 0.2794)
			(end -0.12065 0.3048)
			(stroke
				(width 0.1)
				(type default)
			)
			(layer "F.Fab")
		)
		(fp_line
			(start -0.12065 0.3048)
			(end -0.67945 0.3048)
			(stroke
				(width 0.1)
				(type default)
			)
			(layer "F.Fab")
		)
		(fp_line
			(start 0.120396 0.2794)
			(end -0.12065 0.2794)
			(stroke
				(width 0.1)
				(type default)
			)
			(layer "F.Fab")
		)
		(fp_line
			(start 0.120396 0.3048)
			(end 0.120396 0.2794)
			(stroke
				(width 0.1)
				(type default)
			)
			(layer "F.Fab")
		)
		(fp_line
			(start 0.12065 -0.3048)
			(end 0.67945 -0.3048)
			(stroke
				(width 0.1)
				(type default)
			)
			(layer "F.Fab")
		)
		(fp_line
			(start 0.12065 -0.2794)
			(end 0.12065 -0.3048)
			(stroke
				(width 0.1)
				(type default)
			)
			(layer "F.Fab")
		)
		(fp_line
			(start 0.67945 -0.3048)
			(end 0.67945 0.3048)
			(stroke
				(width 0.1)
				(type default)
			)
			(layer "F.Fab")
		)
		(fp_line
			(start 0.67945 0.3048)
			(end 0.120396 0.3048)
			(stroke
				(width 0.1)
				(type default)
			)
			(layer "F.Fab")
		)
		(pad "1" smd circle
			(at -0.40005 0)
			(size 0 0)
			(layers "F.Cu" "F.Mask" "F.Paste")
			(net "P3V3_ADC_MAM")
		)
		(pad "2" smd circle
			(at 0.40005 0)
			(size 0 0)
			(layers "F.Cu" "F.Mask" "F.Paste")
			(net "GND")
		)
	)
	(footprint ""
		(layer "F.Cu")
		(at 430.600104 -137.542778 180)
		(property "Reference" "R2388"
			(at 0 0 180)
			(layer "F.SilkS")
			(hide yes)
			(effects
				(font
					(size 1.27 1.27)
				)
			)
		)
		(property "Value" ""
			(at 0 0 180)
			(layer "F.Fab")
			(effects
				(font
					(size 1.27 1.27)
				)
			)
		)
		(duplicate_pad_numbers_are_jumpers no)
		(fp_line
			(start 0.7874 0.4064)
			(end -0.7874 0.4064)
			(stroke
				(width 0.1524)
				(type default)
			)
			(layer "F.SilkS")
		)
		(fp_line
			(start 0.7874 -0.4064)
			(end 0.7874 0.4064)
			(stroke
				(width 0.1524)
				(type default)
			)
			(layer "F.SilkS")
		)
		(fp_line
			(start -0.7874 0.4064)
			(end -0.7874 -0.4064)
			(stroke
				(width 0.1524)
				(type default)
			)
			(layer "F.SilkS")
		)
		(fp_line
			(start -0.7874 -0.4064)
			(end 0.7874 -0.4064)
			(stroke
				(width 0.1524)
				(type default)
			)
			(layer "F.SilkS")
		)
		(fp_line
			(start 0.67945 0.3048)
			(end 0.120396 0.3048)
			(stroke
				(width 0.1)
				(type default)
			)
			(layer "F.Fab")
		)
		(fp_line
			(start 0.67945 -0.3048)
			(end 0.67945 0.3048)
			(stroke
				(width 0.1)
				(type default)
			)
			(layer "F.Fab")
		)
		(fp_line
			(start 0.12065 -0.2794)
			(end 0.12065 -0.3048)
			(stroke
				(width 0.1)
				(type default)
			)
			(layer "F.Fab")
		)
		(fp_line
			(start 0.12065 -0.3048)
			(end 0.67945 -0.3048)
			(stroke
				(width 0.1)
				(type default)
			)
			(layer "F.Fab")
		)
		(fp_line
			(start 0.120396 0.3048)
			(end 0.120396 0.2794)
			(stroke
				(width 0.1)
				(type default)
			)
			(layer "F.Fab")
		)
		(fp_line
			(start 0.120396 0.2794)
			(end -0.12065 0.2794)
			(stroke
				(width 0.1)
				(type default)
			)
			(layer "F.Fab")
		)
		(fp_line
			(start -0.12065 0.3048)
			(end -0.67945 0.3048)
			(stroke
				(width 0.1)
				(type default)
			)
			(layer "F.Fab")
		)
		(fp_line
			(start -0.12065 0.2794)
			(end -0.12065 0.3048)
			(stroke
				(width 0.1)
				(type default)
			)
			(layer "F.Fab")
		)
		(fp_line
			(start -0.12065 -0.2794)
			(end 0.12065 -0.2794)
			(stroke
				(width 0.1)
				(type default)
			)
			(layer "F.Fab")
		)
		(fp_line
			(start -0.12065 -0.305054)
			(end -0.12065 -0.2794)
			(stroke
				(width 0.1)
				(type default)
			)
			(layer "F.Fab")
		)
		(fp_line
			(start -0.67945 0.3048)
			(end -0.67945 -0.305054)
			(stroke
				(width 0.1)
				(type default)
			)
			(layer "F.Fab")
		)
		(fp_line
			(start -0.67945 -0.305054)
			(end -0.12065 -0.305054)
			(stroke
				(width 0.1)
				(type default)
			)
			(layer "F.Fab")
		)
		(pad "1" smd circle
			(at -0.40005 0 180)
			(size 0 0)
			(layers "F.Cu" "F.Mask" "F.Paste")
			(net "SVID_DIO0_CPU0_R")
		)
		(pad "2" smd circle
			(at 0.40005 0 180)
			(size 0 0)
			(layers "F.Cu" "F.Mask" "F.Paste")
			(net "SVID_DIO_PVCCINFAON_CPU0_R")
		)
	)
	(footprint ""
		(layer "F.Cu")
		(at 307.93309 -427.170342)
		(property "Reference" "R4266"
			(at 0 0 0)
			(layer "F.SilkS")
			(hide yes)
			(effects
				(font
					(size 1.27 1.27)
				)
			)
		)
		(property "Value" ""
			(at 0 0 0)
			(layer "F.Fab")
			(effects
				(font
					(size 1.27 1.27)
				)
			)
		)
		(duplicate_pad_numbers_are_jumpers no)
		(fp_line
			(start -0.7874 -0.4064)
			(end 0.7874 -0.4064)
			(stroke
				(width 0.1524)
				(type default)
			)
			(layer "F.SilkS")
		)
		(fp_line
			(start -0.7874 0.4064)
			(end -0.7874 -0.4064)
			(stroke
				(width 0.1524)
				(type default)
			)
			(layer "F.SilkS")
		)
		(fp_line
			(start 0.7874 -0.4064)
			(end 0.7874 0.4064)
			(stroke
				(width 0.1524)
				(type default)
			)
			(layer "F.SilkS")
		)
		(fp_line
			(start 0.7874 0.4064)
			(end -0.7874 0.4064)
			(stroke
				(width 0.1524)
				(type default)
			)
			(layer "F.SilkS")
		)
		(fp_line
			(start -0.67945 -0.305054)
			(end -0.12065 -0.305054)
			(stroke
				(width 0.1)
				(type default)
			)
			(layer "F.Fab")
		)
		(fp_line
			(start -0.67945 0.3048)
			(end -0.67945 -0.305054)
			(stroke
				(width 0.1)
				(type default)
			)
			(layer "F.Fab")
		)
		(fp_line
			(start -0.12065 -0.305054)
			(end -0.12065 -0.2794)
			(stroke
				(width 0.1)
				(type default)
			)
			(layer "F.Fab")
		)
		(fp_line
			(start -0.12065 -0.2794)
			(end 0.12065 -0.2794)
			(stroke
				(width 0.1)
				(type default)
			)
			(layer "F.Fab")
		)
		(fp_line
			(start -0.12065 0.2794)
			(end -0.12065 0.3048)
			(stroke
				(width 0.1)
				(type default)
			)
			(layer "F.Fab")
		)
		(fp_line
			(start -0.12065 0.3048)
			(end -0.67945 0.3048)
			(stroke
				(width 0.1)
				(type default)
			)
			(layer "F.Fab")
		)
		(fp_line
			(start 0.120396 0.2794)
			(end -0.12065 0.2794)
			(stroke
				(width 0.1)
				(type default)
			)
			(layer "F.Fab")
		)
		(fp_line
			(start 0.120396 0.3048)
			(end 0.120396 0.2794)
			(stroke
				(width 0.1)
				(type default)
			)
			(layer "F.Fab")
		)
		(fp_line
			(start 0.12065 -0.3048)
			(end 0.67945 -0.3048)
			(stroke
				(width 0.1)
				(type default)
			)
			(layer "F.Fab")
		)
		(fp_line
			(start 0.12065 -0.2794)
			(end 0.12065 -0.3048)
			(stroke
				(width 0.1)
				(type default)
			)
			(layer "F.Fab")
		)
		(fp_line
			(start 0.67945 -0.3048)
			(end 0.67945 0.3048)
			(stroke
				(width 0.1)
				(type default)
			)
			(layer "F.Fab")
		)
		(fp_line
			(start 0.67945 0.3048)
			(end 0.120396 0.3048)
			(stroke
				(width 0.1)
				(type default)
			)
			(layer "F.Fab")
		)
		(pad "1" smd circle
			(at -0.40005 0)
			(size 0 0)
			(layers "F.Cu" "F.Mask" "F.Paste")
			(net "PWRGD_P3V3_AUX_PDB_BUF_R")
		)
		(pad "2" smd circle
			(at 0.40005 0)
			(size 0 0)
			(layers "F.Cu" "F.Mask" "F.Paste")
			(net "PWRGD_P3V3_AUX_PDB_BUF")
		)
	)
	(footprint ""
		(layer "F.Cu")
		(at 114.826034 -66.672206 90)
		(property "Reference" "R806"
			(at 0 0 90)
			(layer "F.SilkS")
			(hide yes)
			(effects
				(font
					(size 1.27 1.27)
				)
			)
		)
		(property "Value" ""
			(at 0 0 90)
			(layer "F.Fab")
			(effects
				(font
					(size 1.27 1.27)
				)
			)
		)
		(duplicate_pad_numbers_are_jumpers no)
		(fp_line
			(start 0.7874 -0.4064)
			(end 0.7874 0.4064)
			(stroke
				(width 0.1524)
				(type default)
			)
			(layer "F.SilkS")
		)
		(fp_line
			(start -0.7874 -0.4064)
			(end 0.7874 -0.4064)
			(stroke
				(width 0.1524)
				(type default)
			)
			(layer "F.SilkS")
		)
		(fp_line
			(start 0.7874 0.4064)
			(end -0.7874 0.4064)
			(stroke
				(width 0.1524)
				(type default)
			)
			(layer "F.SilkS")
		)
		(fp_line
			(start -0.7874 0.4064)
			(end -0.7874 -0.4064)
			(stroke
				(width 0.1524)
				(type default)
			)
			(layer "F.SilkS")
		)
		(fp_line
			(start -0.12065 -0.305054)
			(end -0.12065 -0.2794)
			(stroke
				(width 0.1)
				(type default)
			)
			(layer "F.Fab")
		)
		(fp_line
			(start -0.67945 -0.305054)
			(end -0.12065 -0.305054)
			(stroke
				(width 0.1)
				(type default)
			)
			(layer "F.Fab")
		)
		(fp_line
			(start 0.67945 -0.3048)
			(end 0.67945 0.3048)
			(stroke
				(width 0.1)
				(type default)
			)
			(layer "F.Fab")
		)
		(fp_line
			(start 0.12065 -0.3048)
			(end 0.67945 -0.3048)
			(stroke
				(width 0.1)
				(type default)
			)
			(layer "F.Fab")
		)
		(fp_line
			(start 0.12065 -0.2794)
			(end 0.12065 -0.3048)
			(stroke
				(width 0.1)
				(type default)
			)
			(layer "F.Fab")
		)
		(fp_line
			(start -0.12065 -0.2794)
			(end 0.12065 -0.2794)
			(stroke
				(width 0.1)
				(type default)
			)
			(layer "F.Fab")
		)
		(fp_line
			(start 0.120396 0.2794)
			(end -0.12065 0.2794)
			(stroke
				(width 0.1)
				(type default)
			)
			(layer "F.Fab")
		)
		(fp_line
			(start -0.12065 0.2794)
			(end -0.12065 0.3048)
			(stroke
				(width 0.1)
				(type default)
			)
			(layer "F.Fab")
		)
		(fp_line
			(start 0.67945 0.3048)
			(end 0.120396 0.3048)
			(stroke
				(width 0.1)
				(type default)
			)
			(layer "F.Fab")
		)
		(fp_line
			(start 0.120396 0.3048)
			(end 0.120396 0.2794)
			(stroke
				(width 0.1)
				(type default)
			)
			(layer "F.Fab")
		)
		(fp_line
			(start -0.12065 0.3048)
			(end -0.67945 0.3048)
			(stroke
				(width 0.1)
				(type default)
			)
			(layer "F.Fab")
		)
		(fp_line
			(start -0.67945 0.3048)
			(end -0.67945 -0.305054)
			(stroke
				(width 0.1)
				(type default)
			)
			(layer "F.Fab")
		)
		(pad "1" smd circle
			(at -0.40005 0 90)
			(size 0 0)
			(layers "F.Cu" "F.Mask" "F.Paste")
			(net "JTAG_PLD_TCK_R")
		)
		(pad "2" smd circle
			(at 0.40005 0 90)
			(size 0 0)
			(layers "F.Cu" "F.Mask" "F.Paste")
			(net "JTAG_BMC_PLD_TCK")
		)
	)
	(footprint ""
		(layer "F.Cu")
		(at 185.799222 -22.097492 180)
		(property "Reference" "PR4002"
			(at 0 0 180)
			(layer "F.SilkS")
			(hide yes)
			(effects
				(font
					(size 1.27 1.27)
				)
			)
		)
		(property "Value" ""
			(at 0 0 180)
			(layer "F.Fab")
			(effects
				(font
					(size 1.27 1.27)
				)
			)
		)
		(duplicate_pad_numbers_are_jumpers no)
		(fp_line
			(start 0.7874 0.4064)
			(end -0.7874 0.4064)
			(stroke
				(width 0.1524)
				(type default)
			)
			(layer "F.SilkS")
		)
		(fp_line
			(start 0.7874 -0.4064)
			(end 0.7874 0.4064)
			(stroke
				(width 0.1524)
				(type default)
			)
			(layer "F.SilkS")
		)
		(fp_line
			(start -0.7874 0.4064)
			(end -0.7874 -0.4064)
			(stroke
				(width 0.1524)
				(type default)
			)
			(layer "F.SilkS")
		)
		(fp_line
			(start -0.7874 -0.4064)
			(end 0.7874 -0.4064)
			(stroke
				(width 0.1524)
				(type default)
			)
			(layer "F.SilkS")
		)
		(fp_line
			(start 0.67945 0.3048)
			(end 0.120396 0.3048)
			(stroke
				(width 0.1)
				(type default)
			)
			(layer "F.Fab")
		)
		(fp_line
			(start 0.67945 -0.3048)
			(end 0.67945 0.3048)
			(stroke
				(width 0.1)
				(type default)
			)
			(layer "F.Fab")
		)
		(fp_line
			(start 0.12065 -0.2794)
			(end 0.12065 -0.3048)
			(stroke
				(width 0.1)
				(type default)
			)
			(layer "F.Fab")
		)
		(fp_line
			(start 0.12065 -0.3048)
			(end 0.67945 -0.3048)
			(stroke
				(width 0.1)
				(type default)
			)
			(layer "F.Fab")
		)
		(fp_line
			(start 0.120396 0.3048)
			(end 0.120396 0.2794)
			(stroke
				(width 0.1)
				(type default)
			)
			(layer "F.Fab")
		)
		(fp_line
			(start 0.120396 0.2794)
			(end -0.12065 0.2794)
			(stroke
				(width 0.1)
				(type default)
			)
			(layer "F.Fab")
		)
		(fp_line
			(start -0.12065 0.3048)
			(end -0.67945 0.3048)
			(stroke
				(width 0.1)
				(type default)
			)
			(layer "F.Fab")
		)
		(fp_line
			(start -0.12065 0.2794)
			(end -0.12065 0.3048)
			(stroke
				(width 0.1)
				(type default)
			)
			(layer "F.Fab")
		)
		(fp_line
			(start -0.12065 -0.2794)
			(end 0.12065 -0.2794)
			(stroke
				(width 0.1)
				(type default)
			)
			(layer "F.Fab")
		)
		(fp_line
			(start -0.12065 -0.305054)
			(end -0.12065 -0.2794)
			(stroke
				(width 0.1)
				(type default)
			)
			(layer "F.Fab")
		)
		(fp_line
			(start -0.67945 0.3048)
			(end -0.67945 -0.305054)
			(stroke
				(width 0.1)
				(type default)
			)
			(layer "F.Fab")
		)
		(fp_line
			(start -0.67945 -0.305054)
			(end -0.12065 -0.305054)
			(stroke
				(width 0.1)
				(type default)
			)
			(layer "F.Fab")
		)
		(pad "1" smd circle
			(at -0.40005 0 180)
			(size 0 0)
			(layers "F.Cu" "F.Mask" "F.Paste")
			(net "P12V_SCM_OV")
		)
		(pad "2" smd circle
			(at 0.40005 0 180)
			(size 0 0)
			(layers "F.Cu" "F.Mask" "F.Paste")
			(net "GND")
		)
	)
	(footprint ""
		(layer "F.Cu")
		(at 178.55565 -113.37544 90)
		(property "Reference" "U249"
			(at -11.966194 -11.833098 0)
			(unlocked yes)
			(layer "F.SilkS")
			(effects
				(font
					(size 0.7874 0.5842)
					(thickness 0.1524)
				)
				(justify left)
			)
		)
		(property "Value" ""
			(at 0 0 90)
			(layer "F.Fab")
			(effects
				(font
					(size 1.27 1.27)
				)
			)
		)
		(duplicate_pad_numbers_are_jumpers no)
		(fp_line
			(start 9.500108 -9.500108)
			(end -9.500108 -9.500108)
			(stroke
				(width 0.1524)
				(type default)
			)
			(layer "F.SilkS")
		)
		(fp_line
			(start -9.500108 -9.500108)
			(end -9.500108 9.500108)
			(stroke
				(width 0.1524)
				(type default)
			)
			(layer "F.SilkS")
		)
		(fp_line
			(start 9.500108 9.500108)
			(end 9.500108 -9.500108)
			(stroke
				(width 0.1524)
				(type default)
			)
			(layer "F.SilkS")
		)
		(fp_line
			(start -9.500108 9.500108)
			(end 9.500108 9.500108)
			(stroke
				(width 0.1524)
				(type default)
			)
			(layer "F.SilkS")
		)
		(fp_poly
			(pts
				(xy -9.500108 -9.500108) (xy -9.500108 -7.599934) (xy -10.262108 -7.599934) (xy -10.262108 -10.262108)
				(xy -7.599934 -10.262108) (xy -7.599934 -9.500108)
			)
			(stroke
				(width 0)
				(type default)
			)
			(fill yes)
			(layer "F.SilkS")
		)
		(fp_line
			(start 9.500108 -9.500108)
			(end -9.500108 -9.500108)
			(stroke
				(width 0.1)
				(type default)
			)
			(layer "F.Fab")
		)
		(fp_line
			(start -9.500108 -9.500108)
			(end -9.500108 9.500108)
			(stroke
				(width 0.1)
				(type default)
			)
			(layer "F.Fab")
		)
		(fp_line
			(start 9.500108 9.500108)
			(end 9.500108 -9.500108)
			(stroke
				(width 0.1)
				(type default)
			)
			(layer "F.Fab")
		)
		(fp_line
			(start -9.500108 9.500108)
			(end 9.500108 9.500108)
			(stroke
				(width 0.1)
				(type default)
			)
			(layer "F.Fab")
		)
		(fp_poly
			(pts
				(xy -9.500108 -9.500108) (xy -7.599934 -9.500108) (xy -7.599934 -10.262108) (xy -10.262108 -10.262108)
				(xy -10.262108 -7.599934) (xy -9.500108 -7.599934)
			)
			(stroke
				(width 0)
				(type default)
			)
			(fill yes)
			(layer "F.Fab")
		)
		(pad "A1" smd circle
			(at -8.400034 -8.400034 90)
			(size 0.4064 0.4064)
			(layers "F.Cu" "F.Mask" "F.Paste")
			(net "GND")
		)
		(pad "A2" smd circle
			(at -7.599934 -8.400034 90)
			(size 0.4064 0.4064)
			(layers "F.Cu" "F.Mask" "F.Paste")
			(net "FM_GPU_PWR_EN")
		)
		(pad "A3" smd circle
			(at -6.800088 -8.400034 90)
			(size 0.4064 0.4064)
			(layers "F.Cu" "F.Mask" "F.Paste")
			(net "FM_GPU_HSC_EN_R")
		)
		(pad "A4" smd circle
			(at -5.999988 -8.400034 90)
			(size 0.4064 0.4064)
			(layers "F.Cu" "F.Mask" "F.Paste")
			(net "SMB_BMC_SWB_EN")
		)
		(pad "A5" smd circle
			(at -5.199888 -8.400034 90)
			(size 0.4064 0.4064)
			(layers "F.Cu" "F.Mask" "F.Paste")
			(net "FM_TPM_PRSNT_R_N")
		)
		(pad "A6" smd circle
			(at -4.400042 -8.400034 90)
			(size 0.4064 0.4064)
			(layers "F.Cu" "F.Mask" "F.Paste")
			(net "FM_PECI_MUX_SEL_N")
		)
		(pad "A7" smd circle
			(at -3.599942 -8.400034 90)
			(size 0.4064 0.4064)
			(layers "F.Cu" "F.Mask" "F.Paste")
			(net "FM_OCP_SFF_PWR_GOOD_R")
		)
		(pad "A8" smd circle
			(at -2.800096 -8.400034 90)
			(size 0.4064 0.4064)
			(layers "F.Cu" "F.Mask" "F.Paste")
			(net "IRQ_SML1_PMBUS_PLD_ALERT_N")
		)
		(pad "A9" smd circle
			(at -1.999996 -8.400034 90)
			(size 0.4064 0.4064)
			(layers "F.Cu" "F.Mask" "F.Paste")
			(net "GPU_NVS_PWR_BRAKE_R_N")
		)
		(pad "A10" smd circle
			(at -1.199896 -8.400034 90)
			(size 0.4064 0.4064)
			(layers "F.Cu" "F.Mask" "F.Paste")
			(net "SMB_HOST_3V3AUX_PLD_SCL")
		)
		(pad "A11" smd circle
			(at -0.40005 -8.400034 90)
			(size 0.4064 0.4064)
			(layers "F.Cu" "F.Mask" "F.Paste")
			(net "GPU_WP_HW_CTRL_R_N")
		)
		(pad "A12" smd circle
			(at 0.40005 -8.400034 90)
			(size 0.4064 0.4064)
			(layers "F.Cu" "F.Mask" "F.Paste")
			(net "SMB_1_PLD_3V3AUX_SDA_R1")
		)
		(pad "A13" smd circle
			(at 1.199896 -8.400034 90)
			(size 0.4064 0.4064)
			(layers "F.Cu" "F.Mask" "F.Paste")
			(net "PWRGD_PVNN_MAIN_CPU0")
		)
		(pad "A14" smd circle
			(at 1.999996 -8.400034 90)
			(size 0.4064 0.4064)
			(layers "F.Cu" "F.Mask" "F.Paste")
			(net "PWRGD_PVPP_HBM_CPU1")
		)
		(pad "A15" smd circle
			(at 2.800096 -8.400034 90)
			(size 0.4064 0.4064)
			(layers "F.Cu" "F.Mask" "F.Paste")
			(net "SGPIO_DEBUG_PLD_DOUT")
		)
		(pad "A16" smd circle
			(at 3.599942 -8.400034 90)
			(size 0.4064 0.4064)
			(layers "F.Cu" "F.Mask" "F.Paste")
			(net "SGPIO_OCP_SFF_DATAOUT")
		)
		(pad "A17" smd circle
			(at 4.400042 -8.400034 90)
			(size 0.4064 0.4064)
			(layers "F.Cu" "F.Mask" "F.Paste")
			(net "SGPIO_OCP_V3_2_DATAOUT")
		)
		(pad "A18" smd circle
			(at 5.199888 -8.400034 90)
			(size 0.4064 0.4064)
			(layers "F.Cu" "F.Mask" "F.Paste")
			(net "GPU_FPGA_READY_ISO_R")
		)
		(pad "A19" smd circle
			(at 5.999988 -8.400034 90)
			(size 0.4064 0.4064)
			(layers "F.Cu" "F.Mask" "F.Paste")
			(net "P12V_HSC_TEMP_ALERT_R_N")
		)
		(pad "A20" smd circle
			(at 6.800088 -8.400034 90)
			(size 0.4064 0.4064)
			(layers "F.Cu" "F.Mask" "F.Paste")
			(net "NC_FPGA_PT43A")
		)
		(pad "A21" smd circle
			(at 7.599934 -8.400034 90)
			(size 0.4064 0.4064)
			(layers "F.Cu" "F.Mask" "F.Paste")
			(net "NC_FPGA_PT44A")
		)
		(pad "A22" smd circle
			(at 8.400034 -8.400034 90)
			(size 0.4064 0.4064)
			(layers "F.Cu" "F.Mask" "F.Paste")
			(net "GND")
		)
		(pad "AA1" smd circle
			(at -8.400034 7.599934 90)
			(size 0.4064 0.4064)
			(layers "F.Cu" "F.Mask" "F.Paste")
			(net "H_CPU_NMI_LVC1_R_N")
		)
		(pad "AA2" smd circle
			(at -7.599934 7.599934 90)
			(size 0.4064 0.4064)
			(layers "F.Cu" "F.Mask" "F.Paste")
			(net "FM_ADR_ACK_R")
		)
		(pad "AA3" smd circle
			(at -6.800088 7.599934 90)
			(size 0.4064 0.4064)
			(layers "F.Cu" "F.Mask" "F.Paste")
			(net "FM_ADR_MODE0_R")
		)
		(pad "AA4" smd circle
			(at -5.999988 7.599934 90)
			(size 0.4064 0.4064)
			(layers "F.Cu" "F.Mask" "F.Paste")
			(net "IRQ_PVCCD_CPU0_VRHOT_LVC3_N")
		)
		(pad "AA5" smd circle
			(at -5.199888 7.599934 90)
			(size 0.4064 0.4064)
			(layers "F.Cu" "F.Mask" "F.Paste")
			(net "PWRGD_PLT_AUX_CPU0_LVT3_R")
		)
		(pad "AA6" smd circle
			(at -4.400042 7.599934 90)
			(size 0.4064 0.4064)
			(layers "F.Cu" "F.Mask" "F.Paste")
			(net "RST_MB_STBY_R_N")
		)
		(pad "AA7" smd circle
			(at -3.599942 7.599934 90)
			(size 0.4064 0.4064)
			(layers "F.Cu" "F.Mask" "F.Paste")
			(net "FM_DIS_PS_PWROK_DLY")
		)
		(pad "AA8" smd circle
			(at -2.800096 7.599934 90)
			(size 0.4064 0.4064)
			(layers "F.Cu" "F.Mask" "F.Paste")
			(net "FM_CPU_RMCA_CATERR_LVT3_R_N")
		)
		(pad "AA9" smd circle
			(at -1.999996 7.599934 90)
			(size 0.4064 0.4064)
			(layers "F.Cu" "F.Mask" "F.Paste")
			(net "JTAG_DBP_BMC_PRDY_R_N")
		)
		(pad "AA10" smd circle
			(at -1.199896 7.599934 90)
			(size 0.4064 0.4064)
			(layers "F.Cu" "F.Mask" "F.Paste")
			(net "CLK_25M_OSC_MAIN_FPGA")
		)
		(pad "AA11" smd circle
			(at -0.40005 7.599934 90)
			(size 0.4064 0.4064)
			(layers "F.Cu" "F.Mask" "F.Paste")
			(net "PRSNT_CABLE_GPU_B3_ISO_R_N")
		)
		(pad "AA12" smd circle
			(at 0.40005 7.599934 90)
			(size 0.4064 0.4064)
			(layers "F.Cu" "F.Mask" "F.Paste")
			(net "IRQ_PSYS_CRIT_N")
		)
		(pad "AA13" smd circle
			(at 1.199896 7.599934 90)
			(size 0.4064 0.4064)
			(layers "F.Cu" "F.Mask" "F.Paste")
			(net "IRQ_PVCCD_CPU1_VRHOT_LVC3_N")
		)
		(pad "AA14" smd circle
			(at 1.999996 7.599934 90)
			(size 0.4064 0.4064)
			(layers "F.Cu" "F.Mask" "F.Paste")
			(net "FM_SYS_THROTTLE_R_N")
		)
		(pad "AA15" smd circle
			(at 2.800096 7.599934 90)
			(size 0.4064 0.4064)
			(layers "F.Cu" "F.Mask" "F.Paste")
			(net "NC_FPGA_PB35B")
		)
		(pad "AA16" smd circle
			(at 3.599942 7.599934 90)
			(size 0.4064 0.4064)
			(layers "F.Cu" "F.Mask" "F.Paste")
			(net "FM_PCH_PLD_GLB_RST_WARN_N")
		)
		(pad "AA17" smd circle
			(at 4.400042 7.599934 90)
			(size 0.4064 0.4064)
			(layers "F.Cu" "F.Mask" "F.Paste")
			(net "FM_BMC_READY_R_PLD_N")
		)
		(pad "AA18" smd circle
			(at 5.199888 7.599934 90)
			(size 0.4064 0.4064)
			(layers "F.Cu" "F.Mask" "F.Paste")
			(net "CLK_GPU_1_OE_N")
		)
		(pad "AA19" smd circle
			(at 5.999988 7.599934 90)
			(size 0.4064 0.4064)
			(layers "F.Cu" "F.Mask" "F.Paste")
			(net "FM_PLD_REV_N")
		)
		(pad "AA20" smd circle
			(at 6.800088 7.599934 90)
			(size 0.4064 0.4064)
			(layers "F.Cu" "F.Mask" "F.Paste")
			(net "HPDB_HSC_PWRGD_ISO_R")
		)
		(pad "AA21" smd circle
			(at 7.599934 7.599934 90)
			(size 0.4064 0.4064)
			(layers "F.Cu" "F.Mask" "F.Paste")
			(net "NC_FPGA_PB46B")
		)
		(pad "AA22" smd circle
			(at 8.400034 7.599934 90)
			(size 0.4064 0.4064)
			(layers "F.Cu" "F.Mask" "F.Paste")
			(net "LED_HDD_ACTIVITY_B_PLD_N")
		)
		(pad "AB1" smd circle
			(at -8.400034 8.400034 90)
			(size 0.4064 0.4064)
			(layers "F.Cu" "F.Mask" "F.Paste")
			(net "GND")
		)
		(pad "AB2" smd circle
			(at -7.599934 8.400034 90)
			(size 0.4064 0.4064)
			(layers "F.Cu" "F.Mask" "F.Paste")
			(net "FM_UV_ADR_TRIGGER_R_N")
		)
		(pad "AB3" smd circle
			(at -6.800088 8.400034 90)
			(size 0.4064 0.4064)
			(layers "F.Cu" "F.Mask" "F.Paste")
			(net "FM_ADR_MODE1_R")
		)
		(pad "AB4" smd circle
			(at -5.999988 8.400034 90)
			(size 0.4064 0.4064)
			(layers "F.Cu" "F.Mask" "F.Paste")
			(net "IRQ_BMC_PCH_NMI_R")
		)
		(pad "AB5" smd circle
			(at -5.199888 8.400034 90)
			(size 0.4064 0.4064)
			(layers "F.Cu" "F.Mask" "F.Paste")
			(net "PWRGD_PLT_AUX_CPU1_LVT3_R")
		)
		(pad "AB6" smd circle
			(at -4.400042 8.400034 90)
			(size 0.4064 0.4064)
			(layers "F.Cu" "F.Mask" "F.Paste")
			(net "RST_SMB_SWITCH_N")
		)
		(pad "AB7" smd circle
			(at -3.599942 8.400034 90)
			(size 0.4064 0.4064)
			(layers "F.Cu" "F.Mask" "F.Paste")
			(net "FM_PCH_CRASHLOG_TRIG_R_N")
		)
		(pad "AB8" smd circle
			(at -2.800096 8.400034 90)
			(size 0.4064 0.4064)
			(layers "F.Cu" "F.Mask" "F.Paste")
			(net "FM_PCH_BMC_THERMTRIP_N")
		)
		(pad "AB9" smd circle
			(at -1.999996 8.400034 90)
			(size 0.4064 0.4064)
			(layers "F.Cu" "F.Mask" "F.Paste")
			(net "FM_DEBUG_PORT_PRSNT_N")
		)
		(pad "AB10" smd circle
			(at -1.199896 8.400034 90)
			(size 0.4064 0.4064)
			(layers "F.Cu" "F.Mask" "F.Paste")
			(net "NC_FPGA_PB22B")
		)
		(pad "AB11" smd circle
			(at -0.40005 8.400034 90)
			(size 0.4064 0.4064)
			(layers "F.Cu" "F.Mask" "F.Paste")
			(net "GPU_3V3IO_RSVD3_FFU_ISO_R")
		)
		(pad "AB12" smd circle
			(at 0.40005 8.400034 90)
			(size 0.4064 0.4064)
			(layers "F.Cu" "F.Mask" "F.Paste")
			(net "IRQ_SGPIO_INTR_N_R")
		)
		(pad "AB13" smd circle
			(at 1.199896 8.400034 90)
			(size 0.4064 0.4064)
			(layers "F.Cu" "F.Mask" "F.Paste")
			(net "IRQ_TPM_SPI_N")
		)
		(pad "AB14" smd circle
			(at 1.999996 8.400034 90)
			(size 0.4064 0.4064)
			(layers "F.Cu" "F.Mask" "F.Paste")
			(net "RST_PLTRST_PLD_B_N")
		)
		(pad "AB15" smd circle
			(at 2.800096 8.400034 90)
			(size 0.4064 0.4064)
			(layers "F.Cu" "F.Mask" "F.Paste")
			(net "FM_SPD_REMOTE_EN_R")
		)
		(pad "AB16" smd circle
			(at 3.599942 8.400034 90)
			(size 0.4064 0.4064)
			(layers "F.Cu" "F.Mask" "F.Paste")
			(net "VIRTUAL_RESEAT")
		)
		(pad "AB17" smd circle
			(at 4.400042 8.400034 90)
			(size 0.4064 0.4064)
			(layers "F.Cu" "F.Mask" "F.Paste")
			(net "FM_PCHHOT_R_N")
		)
		(pad "AB18" smd circle
			(at 5.199888 8.400034 90)
			(size 0.4064 0.4064)
			(layers "F.Cu" "F.Mask" "F.Paste")
			(net "JTAG_DBP_BMC_PREQ_R_N")
		)
		(pad "AB19" smd circle
			(at 5.999988 8.400034 90)
			(size 0.4064 0.4064)
			(layers "F.Cu" "F.Mask" "F.Paste")
			(net "CLK_GEN2_BMC_RC_OE_N")
		)
		(pad "AB20" smd circle
			(at 6.800088 8.400034 90)
			(size 0.4064 0.4064)
			(layers "F.Cu" "F.Mask" "F.Paste")
			(net "HGX_DETECT_N_R")
		)
		(pad "AB21" smd circle
			(at 7.599934 8.400034 90)
			(size 0.4064 0.4064)
			(layers "F.Cu" "F.Mask" "F.Paste")
			(net "PULL_FPGA_PB46A")
		)
		(pad "AB22" smd circle
			(at 8.400034 8.400034 90)
			(size 0.4064 0.4064)
			(layers "F.Cu" "F.Mask" "F.Paste")
			(net "GND")
		)
		(pad "B1" smd circle
			(at -8.400034 -7.599934 90)
			(size 0.4064 0.4064)
			(layers "F.Cu" "F.Mask" "F.Paste")
			(net "FM_SWB_PWR_EN")
		)
		(pad "B2" smd circle
			(at -7.599934 -7.599934 90)
			(size 0.4064 0.4064)
			(layers "F.Cu" "F.Mask" "F.Paste")
			(net "FM_FAN_PWR_EN")
		)
		(pad "B3" smd circle
			(at -6.800088 -7.599934 90)
			(size 0.4064 0.4064)
			(layers "F.Cu" "F.Mask" "F.Paste")
			(net "FM_SWB_BIC_READY_ISO_R_N")
		)
		(pad "B4" smd circle
			(at -5.999988 -7.599934 90)
			(size 0.4064 0.4064)
			(layers "F.Cu" "F.Mask" "F.Paste")
			(net "FM_PCH_PRSNT_N")
		)
		(pad "B5" smd circle
			(at -5.199888 -7.599934 90)
			(size 0.4064 0.4064)
			(layers "F.Cu" "F.Mask" "F.Paste")
			(net "IRQ_HSC_FAULT_R1_N")
		)
		(pad "B6" smd circle
			(at -4.400042 -7.599934 90)
			(size 0.4064 0.4064)
			(layers "F.Cu" "F.Mask" "F.Paste")
			(net "FM_OCP_V3_2_PWR_GOOD_R")
		)
		(pad "B7" smd circle
			(at -3.599942 -7.599934 90)
			(size 0.4064 0.4064)
			(layers "F.Cu" "F.Mask" "F.Paste")
			(net "GND")
		)
		(pad "B8" smd circle
			(at -2.800096 -7.599934 90)
			(size 0.4064 0.4064)
			(layers "F.Cu" "F.Mask" "F.Paste")
			(net "IRQ_SML0_ALERT_R_N")
		)
		(pad "B9" smd circle
			(at -1.999996 -7.599934 90)
			(size 0.4064 0.4064)
			(layers "F.Cu" "F.Mask" "F.Paste")
			(net "GPU_FPGA_THERM_OVERT_ISO_R_N")
		)
		(pad "B10" smd circle
			(at -1.199896 -7.599934 90)
			(size 0.4064 0.4064)
			(layers "F.Cu" "F.Mask" "F.Paste")
			(net "SMB_HOST_3V3AUX_PLD_SDA")
		)
		(pad "B11" smd circle
			(at -0.40005 -7.599934 90)
			(size 0.4064 0.4064)
			(layers "F.Cu" "F.Mask" "F.Paste")
			(net "GPU_FPGA_OVERT_ISO_R_N")
		)
		(pad "B12" smd circle
			(at 0.40005 -7.599934 90)
			(size 0.4064 0.4064)
			(layers "F.Cu" "F.Mask" "F.Paste")
			(net "SMB_1_PLD_3V3AUX_SCL_R1")
		)
		(pad "B13" smd circle
			(at 1.199896 -7.599934 90)
			(size 0.4064 0.4064)
			(layers "F.Cu" "F.Mask" "F.Paste")
			(net "PWRGD_PVNN_PCH_AUX")
		)
		(pad "B14" smd circle
			(at 1.999996 -7.599934 90)
			(size 0.4064 0.4064)
			(layers "F.Cu" "F.Mask" "F.Paste")
			(net "FM_NCSI_OCP_V3_2_R_OE")
		)
		(pad "B15" smd circle
			(at 2.800096 -7.599934 90)
			(size 0.4064 0.4064)
			(layers "F.Cu" "F.Mask" "F.Paste")
			(net "SGPIO_DEBUG_PLD_CLK")
		)
		(pad "B16" smd circle
			(at 3.599942 -7.599934 90)
			(size 0.4064 0.4064)
			(layers "F.Cu" "F.Mask" "F.Paste")
			(net "GND")
		)
		(pad "B17" smd circle
			(at 4.400042 -7.599934 90)
			(size 0.4064 0.4064)
			(layers "F.Cu" "F.Mask" "F.Paste")
			(net "SGPIO_OCP_SFF_CLK")
		)
		(pad "B18" smd circle
			(at 5.199888 -7.599934 90)
			(size 0.4064 0.4064)
			(layers "F.Cu" "F.Mask" "F.Paste")
			(net "SGPIO_OCP_V3_2_CLK")
		)
		(pad "B19" smd circle
			(at 5.999988 -7.599934 90)
			(size 0.4064 0.4064)
			(layers "F.Cu" "F.Mask" "F.Paste")
			(net "PU_MAIN_FPGA_CONFIG_DONE")
		)
		(pad "B20" smd circle
			(at 6.800088 -7.599934 90)
			(size 0.4064 0.4064)
			(layers "F.Cu" "F.Mask" "F.Paste")
			(net "P12V_HSC_T_CRIT_R_N")
		)
		(pad "B21" smd circle
			(at 7.599934 -7.599934 90)
			(size 0.4064 0.4064)
			(layers "F.Cu" "F.Mask" "F.Paste")
			(net "NC_FPGA_PT43B")
		)
		(pad "B22" smd circle
			(at 8.400034 -7.599934 90)
			(size 0.4064 0.4064)
			(layers "F.Cu" "F.Mask" "F.Paste")
			(net "NC_FPGA_PT44B")
		)
		(pad "C1" smd circle
			(at -8.400034 -6.800088 90)
			(size 0.4064 0.4064)
			(layers "F.Cu" "F.Mask" "F.Paste")
			(net "RST_PLD_CPU0_DRAM_AB_N")
		)
		(pad "C2" smd circle
			(at -7.599934 -6.800088 90)
			(size 0.4064 0.4064)
			(layers "F.Cu" "F.Mask" "F.Paste")
			(net "GND")
		)
		(pad "C3" smd circle
			(at -6.800088 -6.800088 90)
			(size 0.4064 0.4064)
			(layers "F.Cu" "F.Mask" "F.Paste")
			(net "BIC_MONITER_ISO_R")
		)
		(pad "C4" smd circle
			(at -5.999988 -6.800088 90)
			(size 0.4064 0.4064)
			(layers "F.Cu" "F.Mask" "F.Paste")
			(net "BMC_MONITER")
		)
		(pad "C5" smd circle
			(at -5.199888 -6.800088 90)
			(size 0.4064 0.4064)
			(layers "F.Cu" "F.Mask" "F.Paste")
			(net "FM_BMC_SUSACK_R_N")
		)
		(pad "C6" smd circle
			(at -4.400042 -6.800088 90)
			(size 0.4064 0.4064)
			(layers "F.Cu" "F.Mask" "F.Paste")
			(net "FM_S3M_CPU0_CPLD_CRC_ERROR")
		)
		(pad "C7" smd circle
			(at -3.599942 -6.800088 90)
			(size 0.4064 0.4064)
			(layers "F.Cu" "F.Mask" "F.Paste")
			(net "P3V3_AUX_FPGA_VCCIO0")
		)
		(pad "C8" smd circle
			(at -2.800096 -6.800088 90)
			(size 0.4064 0.4064)
			(layers "F.Cu" "F.Mask" "F.Paste")
			(net "OCP_SFF_CLK_OE_R_N")
		)
		(pad "C9" smd circle
			(at -1.999996 -6.800088 90)
			(size 0.4064 0.4064)
			(layers "F.Cu" "F.Mask" "F.Paste")
			(net "FM_SLP_SUS_RSM_RST_N")
		)
		(pad "C10" smd circle
			(at -1.199896 -6.800088 90)
			(size 0.4064 0.4064)
			(layers "F.Cu" "F.Mask" "F.Paste")
			(net "JTAG_PLD_TMS_R")
		)
		(pad "C11" smd circle
			(at -0.40005 -6.800088 90)
			(size 0.4064 0.4064)
			(layers "F.Cu" "F.Mask" "F.Paste")
			(net "GND")
		)
		(pad "C12" smd circle
			(at 0.40005 -6.800088 90)
			(size 0.4064 0.4064)
			(layers "F.Cu" "F.Mask" "F.Paste")
			(net "P3V3_AUX_FPGA_VCCIO0")
		)
		(pad "C13" smd circle
			(at 1.199896 -6.800088 90)
			(size 0.4064 0.4064)
			(layers "F.Cu" "F.Mask" "F.Paste")
			(net "PWRGD_PVNN_MAIN_CPU1")
		)
		(pad "C14" smd circle
			(at 1.999996 -6.800088 90)
			(size 0.4064 0.4064)
			(layers "F.Cu" "F.Mask" "F.Paste")
			(net "SGPIO_BMC_DOUT")
		)
		(pad "C15" smd circle
			(at 2.800096 -6.800088 90)
			(size 0.4064 0.4064)
			(layers "F.Cu" "F.Mask" "F.Paste")
			(net "SGPIO_DEBUG_PLD_DIN")
		)
		(pad "C16" smd circle
			(at 3.599942 -6.800088 90)
			(size 0.4064 0.4064)
			(layers "F.Cu" "F.Mask" "F.Paste")
			(net "P3V3_AUX_FPGA_VCCIO0")
		)
		(pad "C17" smd circle
			(at 4.400042 -6.800088 90)
			(size 0.4064 0.4064)
			(layers "F.Cu" "F.Mask" "F.Paste")
			(net "SGPIO_OCP_SFF_DATAIN")
		)
		(pad "C18" smd circle
			(at 5.199888 -6.800088 90)
			(size 0.4064 0.4064)
			(layers "F.Cu" "F.Mask" "F.Paste")
			(net "JTAG_BMC_SW_PLD_OE")
		)
		(pad "C19" smd circle
			(at 5.999988 -6.800088 90)
			(size 0.4064 0.4064)
			(layers "F.Cu" "F.Mask" "F.Paste")
			(net "NC_FPGA_PT43C")
		)
		(pad "C20" smd circle
			(at 6.800088 -6.800088 90)
			(size 0.4064 0.4064)
			(layers "F.Cu" "F.Mask" "F.Paste")
			(net "NC_FPGA_PT43D")
		)
		(pad "C21" smd circle
			(at 7.599934 -6.800088 90)
			(size 0.4064 0.4064)
			(layers "F.Cu" "F.Mask" "F.Paste")
			(net "FM_PVCCD_HV_CPU0_EN")
		)
		(pad "C22" smd circle
			(at 8.400034 -6.800088 90)
			(size 0.4064 0.4064)
			(layers "F.Cu" "F.Mask" "F.Paste")
			(net "FM_PVCCD_HV_CPU1_EN")
		)
		(pad "D1" smd circle
			(at -8.400034 -5.999988 90)
			(size 0.4064 0.4064)
			(layers "F.Cu" "F.Mask" "F.Paste")
			(net "RST_PLD_CPU1_DRAM_AB_N")
		)
		(pad "D2" smd circle
			(at -7.599934 -5.999988 90)
			(size 0.4064 0.4064)
			(layers "F.Cu" "F.Mask" "F.Paste")
			(net "RST_PLD_CPU0_DRAM_CD_N")
		)
		(pad "D3" smd circle
			(at -6.800088 -5.999988 90)
			(size 0.4064 0.4064)
			(layers "F.Cu" "F.Mask" "F.Paste")
			(net "RST_CPU0_DRAM_AB_PLD_LVT3_N")
		)
		(pad "D4" smd circle
			(at -5.999988 -5.999988 90)
			(size 0.4064 0.4064)
			(layers "F.Cu" "F.Mask" "F.Paste")
			(net "RST_CPU0_DRAM_CD_PLD_LVT3_N")
		)
		(pad "D5" smd circle
			(at -5.199888 -5.999988 90)
			(size 0.4064 0.4064)
			(layers "F.Cu" "F.Mask" "F.Paste")
			(net "VIRTUAL_RESEAT_FPGA_R_N")
		)
		(pad "D6" smd circle
			(at -4.400042 -5.999988 90)
			(size 0.4064 0.4064)
			(layers "F.Cu" "F.Mask" "F.Paste")
			(net "OCP_V3_2_AUX_PWR_PLD_EN")
		)
		(pad "D7" smd circle
			(at -3.599942 -5.999988 90)
			(size 0.4064 0.4064)
			(layers "F.Cu" "F.Mask" "F.Paste")
			(net "FM_S3M_CPU1_CPLD_CRC_ERROR")
		)
		(pad "D8" smd circle
			(at -2.800096 -5.999988 90)
			(size 0.4064 0.4064)
			(layers "F.Cu" "F.Mask" "F.Paste")
			(net "IRQ_SML1_PMBUS_BMC_ALERT_N")
		)
		(pad "D9" smd circle
			(at -1.999996 -5.999988 90)
			(size 0.4064 0.4064)
			(layers "F.Cu" "F.Mask" "F.Paste")
			(net "PU_RST_DEDI_BUSY_PLD_N")
		)
		(pad "D10" smd circle
			(at -1.199896 -5.999988 90)
			(size 0.4064 0.4064)
			(layers "F.Cu" "F.Mask" "F.Paste")
			(net "JTAG_PLD_TCK_R")
		)
		(pad "D11" smd circle
			(at -0.40005 -5.999988 90)
			(size 0.4064 0.4064)
			(layers "F.Cu" "F.Mask" "F.Paste")
			(net "GPU_FPGA_EROT_FATALERR_ISO_R_N")
		)
		(pad "D12" smd circle
			(at 0.40005 -5.999988 90)
			(size 0.4064 0.4064)
			(layers "F.Cu" "F.Mask" "F.Paste")
			(net "PWRGD_P5V_AUX_R2")
		)
		(pad "D13" smd circle
			(at 1.199896 -5.999988 90)
			(size 0.4064 0.4064)
			(layers "F.Cu" "F.Mask" "F.Paste")
			(net "PWRGD_PVPP_HBM_CPU0")
		)
		(pad "D14" smd circle
			(at 1.999996 -5.999988 90)
			(size 0.4064 0.4064)
			(layers "F.Cu" "F.Mask" "F.Paste")
			(net "SGPIO_BMC_CLK")
		)
		(pad "D15" smd circle
			(at 2.800096 -5.999988 90)
			(size 0.4064 0.4064)
			(layers "F.Cu" "F.Mask" "F.Paste")
			(net "SGPIO_DEBUG_PLD_LD_N")
		)
		(pad "D16" smd circle
			(at 3.599942 -5.999988 90)
			(size 0.4064 0.4064)
			(layers "F.Cu" "F.Mask" "F.Paste")
			(net "SGPIO_OCP_SFF_LD_N")
		)
		(pad "D17" smd circle
			(at 4.400042 -5.999988 90)
			(size 0.4064 0.4064)
			(layers "F.Cu" "F.Mask" "F.Paste")
			(net "SGPIO_OCP_V3_2_LD_N")
		)
		(pad "D18" smd circle
			(at 5.199888 -5.999988 90)
			(size 0.4064 0.4064)
			(layers "F.Cu" "F.Mask" "F.Paste")
			(net "NC_FPGA_PT41D")
		)
		(pad "D19" smd circle
			(at 5.999988 -5.999988 90)
			(size 0.4064 0.4064)
			(layers "F.Cu" "F.Mask" "F.Paste")
			(net "FM_PVCCINFAON_CPU0_R_EN")
		)
		(pad "D20" smd circle
			(at 6.800088 -5.999988 90)
			(size 0.4064 0.4064)
			(layers "F.Cu" "F.Mask" "F.Paste")
			(net "FM_PVCCINFAON_CPU1_R_EN")
		)
		(pad "D21" smd circle
			(at 7.599934 -5.999988 90)
			(size 0.4064 0.4064)
			(layers "F.Cu" "F.Mask" "F.Paste")
			(net "FM_PVCCFA_EHV_FIVRA_CPU1_R_EN")
		)
		(pad "D22" smd circle
			(at 8.400034 -5.999988 90)
			(size 0.4064 0.4064)
			(layers "F.Cu" "F.Mask" "F.Paste")
			(net "FM_PVCCFA_EHV_FIVRA_CPU0_R_EN")
		)
		(pad "E1" smd circle
			(at -8.400034 -5.199888 90)
			(size 0.4064 0.4064)
			(layers "F.Cu" "F.Mask" "F.Paste")
			(net "Net_1460")
		)
		(pad "E2" smd circle
			(at -7.599934 -5.199888 90)
			(size 0.4064 0.4064)
			(layers "F.Cu" "F.Mask" "F.Paste")
			(net "RST_PLD_CPU1_DRAM_CD_N")
		)
		(pad "E3" smd circle
			(at -6.800088 -5.199888 90)
			(size 0.4064 0.4064)
			(layers "F.Cu" "F.Mask" "F.Paste")
			(net "RST_PLD_CPU1_DRAM_EF_N")
		)
		(pad "E4" smd circle
			(at -5.999988 -5.199888 90)
			(size 0.4064 0.4064)
			(layers "F.Cu" "F.Mask" "F.Paste")
			(net "RST_CPU1_DRAM_AB_PLD_LVT3_N")
		)
		(pad "E5" smd circle
			(at -5.199888 -5.199888 90)
			(size 0.4064 0.4064)
			(layers "F.Cu" "F.Mask" "F.Paste")
			(net "GND")
		)
		(pad "E6" smd circle
			(at -4.400042 -5.199888 90)
			(size 0.4064 0.4064)
			(layers "F.Cu" "F.Mask" "F.Paste")
			(net "FM_SWB_PWRGD_ISO_R")
		)
		(pad "E7" smd circle
			(at -3.599942 -5.199888 90)
			(size 0.4064 0.4064)
			(layers "F.Cu" "F.Mask" "F.Paste")
			(net "OCP_SFF_AUX_PWR_PLD_EN")
		)
		(pad "E8" smd circle
			(at -2.800096 -5.199888 90)
			(size 0.4064 0.4064)
			(layers "F.Cu" "F.Mask" "F.Paste")
			(net "JTAG_PLD_TDO_R")
		)
		(pad "E9" smd circle
			(at -1.999996 -5.199888 90)
			(size 0.4064 0.4064)
			(layers "F.Cu" "F.Mask" "F.Paste")
			(net "JTAG_PLD_TDI_R")
		)
		(pad "E10" smd circle
			(at -1.199896 -5.199888 90)
			(size 0.4064 0.4064)
			(layers "F.Cu" "F.Mask" "F.Paste")
			(net "GPU_HMC_PRSNT_ISO_R_N")
		)
		(pad "E11" smd circle
			(at -0.40005 -5.199888 90)
			(size 0.4064 0.4064)
			(layers "F.Cu" "F.Mask" "F.Paste")
			(net "GPU_PRSNT_N_ISO_R")
		)
		(pad "E12" smd circle
			(at 0.40005 -5.199888 90)
			(size 0.4064 0.4064)
			(layers "F.Cu" "F.Mask" "F.Paste")
			(net "PWRGD_P3V3")
		)
		(pad "E13" smd circle
			(at 1.199896 -5.199888 90)
			(size 0.4064 0.4064)
			(layers "F.Cu" "F.Mask" "F.Paste")
			(net "PWRGD_PVCCFA_EHV_FIVRA_CPU0")
		)
		(pad "E14" smd circle
			(at 1.999996 -5.199888 90)
			(size 0.4064 0.4064)
			(layers "F.Cu" "F.Mask" "F.Paste")
			(net "JTAG_PLD_JTAGEN")
		)
		(pad "E15" smd circle
			(at 2.800096 -5.199888 90)
			(size 0.4064 0.4064)
			(layers "F.Cu" "F.Mask" "F.Paste")
			(net "PU_FPGA_D12_PROGRAMN")
		)
		(pad "E16" smd circle
			(at 3.599942 -5.199888 90)
			(size 0.4064 0.4064)
			(layers "F.Cu" "F.Mask" "F.Paste")
			(net "SGPIO_OCP_V3_2_DATAIN")
		)
		(pad "E17" smd circle
			(at 4.400042 -5.199888 90)
			(size 0.4064 0.4064)
			(layers "F.Cu" "F.Mask" "F.Paste")
			(net "NC_FPGA_PT44D")
		)
		(pad "E18" smd circle
			(at 5.199888 -5.199888 90)
			(size 0.4064 0.4064)
			(layers "F.Cu" "F.Mask" "F.Paste")
			(net "GND")
		)
		(pad "E19" smd circle
			(at 5.999988 -5.199888 90)
			(size 0.4064 0.4064)
			(layers "F.Cu" "F.Mask" "F.Paste")
			(net "FM_PVCCIN_CPU0_R_EN")
		)
		(pad "E20" smd circle
			(at 6.800088 -5.199888 90)
			(size 0.4064 0.4064)
			(layers "F.Cu" "F.Mask" "F.Paste")
			(net "FM_PVCCIN_CPU1_R_EN")
		)
		(pad "E21" smd circle
			(at 7.599934 -5.199888 90)
			(size 0.4064 0.4064)
			(layers "F.Cu" "F.Mask" "F.Paste")
			(net "FM_PVNN_MAIN_CPU1_EN")
		)
		(pad "E22" smd circle
			(at 8.400034 -5.199888 90)
			(size 0.4064 0.4064)
			(layers "F.Cu" "F.Mask" "F.Paste")
			(net "FM_PVNN_MAIN_CPU0_EN")
		)
		(pad "F1" smd circle
			(at -8.400034 -4.400042 90)
			(size 0.4064 0.4064)
			(layers "F.Cu" "F.Mask" "F.Paste")
			(net "Net_1461")
		)
		(pad "F2" smd circle
			(at -7.599934 -4.400042 90)
			(size 0.4064 0.4064)
			(layers "F.Cu" "F.Mask" "F.Paste")
			(net "GND")
		)
		(pad "F3" smd circle
			(at -6.800088 -4.400042 90)
			(size 0.4064 0.4064)
			(layers "F.Cu" "F.Mask" "F.Paste")
			(net "P3V3_AUX_FPGA_VCCIO5")
		)
		(pad "F4" smd circle
			(at -5.999988 -4.400042 90)
			(size 0.4064 0.4064)
			(layers "F.Cu" "F.Mask" "F.Paste")
			(net "RST_PLD_CPU1_DRAM_GH_N")
		)
		(pad "F5" smd circle
			(at -5.199888 -4.400042 90)
			(size 0.4064 0.4064)
			(layers "F.Cu" "F.Mask" "F.Paste")
			(net "RST_CPU1_DRAM_CD_PLD_LVT3_N")
		)
		(pad "F6" smd circle
			(at -4.400042 -4.400042 90)
			(size 0.4064 0.4064)
			(layers "F.Cu" "F.Mask" "F.Paste")
			(net "RST_CPU0_DRAM_EF_PLD_LVT3_N")
		)
		(pad "F7" smd circle
			(at -3.599942 -4.400042 90)
			(size 0.4064 0.4064)
			(layers "F.Cu" "F.Mask" "F.Paste")
			(net "FM_GPU_PWRGD_ISO_R")
		)
		(pad "F8" smd circle
			(at -2.800096 -4.400042 90)
			(size 0.4064 0.4064)
			(layers "F.Cu" "F.Mask" "F.Paste")
			(net "RST_BMC_FROM_SWB_ISO_R_N")
		)
		(pad "F9" smd circle
			(at -1.999996 -4.400042 90)
			(size 0.4064 0.4064)
			(layers "F.Cu" "F.Mask" "F.Paste")
			(net "GPU_FPGA_EROT_RST_R_N")
		)
		(pad "F10" smd circle
			(at -1.199896 -4.400042 90)
			(size 0.4064 0.4064)
			(layers "F.Cu" "F.Mask" "F.Paste")
			(net "GPU_BASE_HMC_READY_ISO_R")
		)
		(pad "F11" smd circle
			(at -0.40005 -4.400042 90)
			(size 0.4064 0.4064)
			(layers "F.Cu" "F.Mask" "F.Paste")
			(net "GPU_FPGA_EROT_RECOV_R_N")
		)
		(pad "F12" smd circle
			(at 0.40005 -4.400042 90)
			(size 0.4064 0.4064)
			(layers "F.Cu" "F.Mask" "F.Paste")
			(net "PWRGD_PVCCD_HV_CPU0")
		)
		(pad "F13" smd circle
			(at 1.199896 -4.400042 90)
			(size 0.4064 0.4064)
			(layers "F.Cu" "F.Mask" "F.Paste")
			(net "PWRGD_PVCCIN_CPU0")
		)
		(pad "F14" smd circle
			(at 1.999996 -4.400042 90)
			(size 0.4064 0.4064)
			(layers "F.Cu" "F.Mask" "F.Paste")
			(net "SGPIO_BMC_LD_N")
		)
		(pad "F15" smd circle
			(at 2.800096 -4.400042 90)
			(size 0.4064 0.4064)
			(layers "F.Cu" "F.Mask" "F.Paste")
			(net "RST_SRST_PLD_BMC_R_N")
		)
		(pad "F16" smd circle
			(at 3.599942 -4.400042 90)
			(size 0.4064 0.4064)
			(layers "F.Cu" "F.Mask" "F.Paste")
			(net "NC_FPGA_PT44C")
		)
		(pad "F17" smd circle
			(at 4.400042 -4.400042 90)
			(size 0.4064 0.4064)
			(layers "F.Cu" "F.Mask" "F.Paste")
			(net "FM_PVCCFA_EHV_CPU0_R_EN")
		)
		(pad "F18" smd circle
			(at 5.199888 -4.400042 90)
			(size 0.4064 0.4064)
			(layers "F.Cu" "F.Mask" "F.Paste")
			(net "FM_AUX_SW_EN")
		)
		(pad "F19" smd circle
			(at 5.999988 -4.400042 90)
			(size 0.4064 0.4064)
			(layers "F.Cu" "F.Mask" "F.Paste")
			(net "FM_PCH_P1V8_AUX_EN")
		)
		(pad "F20" smd circle
			(at 6.800088 -4.400042 90)
			(size 0.4064 0.4064)
			(layers "F.Cu" "F.Mask" "F.Paste")
			(net "P3V3_AUX_FPGA_VCCIO1")
		)
		(pad "F21" smd circle
			(at 7.599934 -4.400042 90)
			(size 0.4064 0.4064)
			(layers "F.Cu" "F.Mask" "F.Paste")
			(net "GND")
		)
		(pad "F22" smd circle
			(at 8.400034 -4.400042 90)
			(size 0.4064 0.4064)
			(layers "F.Cu" "F.Mask" "F.Paste")
			(net "FM_PVPP_HBM_CPU1_EN")
		)
		(pad "G1" smd circle
			(at -8.400034 -3.599942 90)
			(size 0.4064 0.4064)
			(layers "F.Cu" "F.Mask" "F.Paste")
			(net "PWRGD_DRAMPWRGD_CPU0_CD_R_LVC1")
		)
		(pad "G2" smd circle
			(at -7.599934 -3.599942 90)
			(size 0.4064 0.4064)
			(layers "F.Cu" "F.Mask" "F.Paste")
			(net "PWRGD_DRAMPWRGD_CPU0_AB_R_LVC1")
		)
		(pad "G3" smd circle
			(at -6.800088 -3.599942 90)
			(size 0.4064 0.4064)
			(layers "F.Cu" "F.Mask" "F.Paste")
			(net "Net_1462")
		)
		(pad "G4" smd circle
			(at -5.999988 -3.599942 90)
			(size 0.4064 0.4064)
			(layers "F.Cu" "F.Mask" "F.Paste")
			(net "Net_1463")
		)
		(pad "G5" smd circle
			(at -5.199888 -3.599942 90)
			(size 0.4064 0.4064)
			(layers "F.Cu" "F.Mask" "F.Paste")
			(net "RST_PLD_CPU0_DRAM_EF_N")
		)
		(pad "G6" smd circle
			(at -4.400042 -3.599942 90)
			(size 0.4064 0.4064)
			(layers "F.Cu" "F.Mask" "F.Paste")
			(net "RST_CPU1_DRAM_EF_PLD_LVT3_N")
		)
		(pad "G7" smd circle
			(at -3.599942 -3.599942 90)
			(size 0.4064 0.4064)
			(layers "F.Cu" "F.Mask" "F.Paste")
			(net "RST_CPU0_DRAM_GH_PLD_LVT3_N")
		)
		(pad "G8" smd circle
			(at -2.800096 -3.599942 90)
			(size 0.4064 0.4064)
			(layers "F.Cu" "F.Mask" "F.Paste")
			(net "SMB_BMC_GPU_EN")
		)
		(pad "G9" smd circle
			(at -1.999996 -3.599942 90)
			(size 0.4064 0.4064)
			(layers "F.Cu" "F.Mask" "F.Paste")
			(net "GPU_BASE_STBY_EN_R")
		)
		(pad "G10" smd circle
			(at -1.199896 -3.599942 90)
			(size 0.4064 0.4064)
			(layers "F.Cu" "F.Mask" "F.Paste")
			(net "P3V3_AUX_FPGA_VCCIO0")
		)
		(pad "G11" smd circle
			(at -0.40005 -3.599942 90)
			(size 0.4064 0.4064)
			(layers "F.Cu" "F.Mask" "F.Paste")
			(net "GPU_FPGA_BOOT_EN_R")
		)
		(pad "G12" smd circle
			(at 0.40005 -3.599942 90)
			(size 0.4064 0.4064)
			(layers "F.Cu" "F.Mask" "F.Paste")
			(net "PWRGD_P3V3_AUX_PLD")
		)
		(pad "G13" smd circle
			(at 1.199896 -3.599942 90)
			(size 0.4064 0.4064)
			(layers "F.Cu" "F.Mask" "F.Paste")
			(net "P3V3_AUX_FPGA_VCCIO0")
		)
		(pad "G14" smd circle
			(at 1.999996 -3.599942 90)
			(size 0.4064 0.4064)
			(layers "F.Cu" "F.Mask" "F.Paste")
			(net "SGPIO_BMC_DIN_R")
		)
		(pad "G15" smd circle
			(at 2.800096 -3.599942 90)
			(size 0.4064 0.4064)
			(layers "F.Cu" "F.Mask" "F.Paste")
			(net "NC_FPGA_PT42D")
		)
		(pad "G16" smd circle
			(at 3.599942 -3.599942 90)
			(size 0.4064 0.4064)
			(layers "F.Cu" "F.Mask" "F.Paste")
			(net "FM_PVCCFA_EHV_CPU1_R_EN")
		)
		(pad "G17" smd circle
			(at 4.400042 -3.599942 90)
			(size 0.4064 0.4064)
			(layers "F.Cu" "F.Mask" "F.Paste")
			(net "PWRGD_PVCCINFAON_CPU0")
		)
		(pad "G18" smd circle
			(at 5.199888 -3.599942 90)
			(size 0.4064 0.4064)
			(layers "F.Cu" "F.Mask" "F.Paste")
			(net "PWRGD_PVCCIN_CPU1")
		)
		(pad "G19" smd circle
			(at 5.999988 -3.599942 90)
			(size 0.4064 0.4064)
			(layers "F.Cu" "F.Mask" "F.Paste")
			(net "FM_ESPI_PLD_R_EN")
		)
		(pad "G20" smd circle
			(at 6.800088 -3.599942 90)
			(size 0.4064 0.4064)
			(layers "F.Cu" "F.Mask" "F.Paste")
			(net "FM_P1V05_PCH_AUX_EN")
		)
		(pad "G21" smd circle
			(at 7.599934 -3.599942 90)
			(size 0.4064 0.4064)
			(layers "F.Cu" "F.Mask" "F.Paste")
			(net "FM_P5V_EN")
		)
		(pad "G22" smd circle
			(at 8.400034 -3.599942 90)
			(size 0.4064 0.4064)
			(layers "F.Cu" "F.Mask" "F.Paste")
			(net "FM_PVPP_HBM_CPU0_EN")
		)
		(pad "H1" smd circle
			(at -8.400034 -2.800096 90)
			(size 0.4064 0.4064)
			(layers "F.Cu" "F.Mask" "F.Paste")
			(net "PWRGD_DRAMPWRGD_CPU1_CD_R_LVC1")
		)
		(pad "H2" smd circle
			(at -7.599934 -2.800096 90)
			(size 0.4064 0.4064)
			(layers "F.Cu" "F.Mask" "F.Paste")
			(net "PWRGD_DRAMPWRGD_CPU1_AB_R_LVC1")
		)
		(pad "H3" smd circle
			(at -6.800088 -2.800096 90)
			(size 0.4064 0.4064)
			(layers "F.Cu" "F.Mask" "F.Paste")
			(net "PWRGD_DRAMPWRGD_CPU0_GH_R_LVC1")
		)
		(pad "H4" smd circle
			(at -5.999988 -2.800096 90)
			(size 0.4064 0.4064)
			(layers "F.Cu" "F.Mask" "F.Paste")
			(net "PWRGD_DRAMPWRGD_CPU0_EF_R_LVC1")
		)
		(pad "H5" smd circle
			(at -5.199888 -2.800096 90)
			(size 0.4064 0.4064)
			(layers "F.Cu" "F.Mask" "F.Paste")
			(net "FM_BOARD_BMC_SKU_ID4")
		)
		(pad "H6" smd circle
			(at -4.400042 -2.800096 90)
			(size 0.4064 0.4064)
			(layers "F.Cu" "F.Mask" "F.Paste")
			(net "RST_PLD_CPU0_DRAM_GH_N")
		)
		(pad "H7" smd circle
			(at -3.599942 -2.800096 90)
			(size 0.4064 0.4064)
			(layers "F.Cu" "F.Mask" "F.Paste")
			(net "RST_CPU1_DRAM_GH_PLD_LVT3_N")
		)
		(pad "H8" smd circle
			(at -2.800096 -2.800096 90)
			(size 0.4064 0.4064)
			(layers "F.Cu" "F.Mask" "F.Paste")
			(net "GND")
		)
		(pad "H9" smd circle
			(at -1.999996 -2.800096 90)
			(size 0.4064 0.4064)
			(layers "F.Cu" "F.Mask" "F.Paste")
			(net "P3V3_AUX_FPGA_VCCIO0")
		)
		(pad "H10" smd circle
			(at -1.199896 -2.800096 90)
			(size 0.4064 0.4064)
			(layers "F.Cu" "F.Mask" "F.Paste")
			(net "GND")
		)
		(pad "H11" smd circle
			(at -0.40005 -2.800096 90)
			(size 0.4064 0.4064)
			(layers "F.Cu" "F.Mask" "F.Paste")
			(net "P3V3_AUX_FPGA_VCCIO0")
		)
		(pad "H12" smd circle
			(at 0.40005 -2.800096 90)
			(size 0.4064 0.4064)
			(layers "F.Cu" "F.Mask" "F.Paste")
			(net "P3V3_AUX_FPGA_VCCIO0")
		)
		(pad "H13" smd circle
			(at 1.199896 -2.800096 90)
			(size 0.4064 0.4064)
			(layers "F.Cu" "F.Mask" "F.Paste")
			(net "GND")
		)
		(pad "H14" smd circle
			(at 1.999996 -2.800096 90)
			(size 0.4064 0.4064)
			(layers "F.Cu" "F.Mask" "F.Paste")
			(net "P3V3_AUX_FPGA_VCCIO0")
		)
		(pad "H15" smd circle
			(at 2.800096 -2.800096 90)
			(size 0.4064 0.4064)
			(layers "F.Cu" "F.Mask" "F.Paste")
			(net "GND")
		)
		(pad "H16" smd circle
			(at 3.599942 -2.800096 90)
			(size 0.4064 0.4064)
			(layers "F.Cu" "F.Mask" "F.Paste")
			(net "PWRGD_PS_PWROK_PLD_ISO_R")
		)
		(pad "H17" smd circle
			(at 4.400042 -2.800096 90)
			(size 0.4064 0.4064)
			(layers "F.Cu" "F.Mask" "F.Paste")
			(net "FM_PFR_DSW_PWROK_N")
		)
		(pad "H18" smd circle
			(at 5.199888 -2.800096 90)
			(size 0.4064 0.4064)
			(layers "F.Cu" "F.Mask" "F.Paste")
			(net "PWRGD_PVCCD_HV_CPU1")
		)
		(pad "H19" smd circle
			(at 5.999988 -2.800096 90)
			(size 0.4064 0.4064)
			(layers "F.Cu" "F.Mask" "F.Paste")
			(net "PWRGD_PVCCFA_EHV_FIVRA_CPU1")
		)
		(pad "H20" smd circle
			(at 6.800088 -2.800096 90)
			(size 0.4064 0.4064)
			(layers "F.Cu" "F.Mask" "F.Paste")
			(net "PWRGD_PVCCINFAON_CPU1")
		)
		(pad "H21" smd circle
			(at 7.599934 -2.800096 90)
			(size 0.4064 0.4064)
			(layers "F.Cu" "F.Mask" "F.Paste")
			(net "PWRGD_PVCCFA_EHV_CPU1")
		)
		(pad "H22" smd circle
			(at 8.400034 -2.800096 90)
			(size 0.4064 0.4064)
			(layers "F.Cu" "F.Mask" "F.Paste")
			(net "PWRGD_PVCCFA_EHV_CPU0")
		)
		(pad "J1" smd circle
			(at -8.400034 -1.999996 90)
			(size 0.4064 0.4064)
			(layers "F.Cu" "F.Mask" "F.Paste")
			(net "FAB_BMC_REV_ID2")
		)
		(pad "J2" smd circle
			(at -7.599934 -1.999996 90)
			(size 0.4064 0.4064)
			(layers "F.Cu" "F.Mask" "F.Paste")
			(net "FM_BOARD_BMC_SKU_ID0")
		)
		(pad "J3" smd circle
			(at -6.800088 -1.999996 90)
			(size 0.4064 0.4064)
			(layers "F.Cu" "F.Mask" "F.Paste")
			(net "FM_BOARD_BMC_SKU_ID1")
		)
		(pad "J4" smd circle
			(at -5.999988 -1.999996 90)
			(size 0.4064 0.4064)
			(layers "F.Cu" "F.Mask" "F.Paste")
			(net "FM_BOARD_BMC_SKU_ID2")
		)
		(pad "J5" smd circle
			(at -5.199888 -1.999996 90)
			(size 0.4064 0.4064)
			(layers "F.Cu" "F.Mask" "F.Paste")
			(net "FM_BOARD_BMC_SKU_ID3")
		)
		(pad "J6" smd circle
			(at -4.400042 -1.999996 90)
			(size 0.4064 0.4064)
			(layers "F.Cu" "F.Mask" "F.Paste")
			(net "PWRGD_DRAMPWRGD_CPU1_GH_R_LVC1")
		)
		(pad "J7" smd circle
			(at -3.599942 -1.999996 90)
			(size 0.4064 0.4064)
			(layers "F.Cu" "F.Mask" "F.Paste")
			(net "PWRGD_DRAMPWRGD_CPU1_EF_R_LVC1")
		)
		(pad "J8" smd circle
			(at -2.800096 -1.999996 90)
			(size 0.4064 0.4064)
			(layers "F.Cu" "F.Mask" "F.Paste")
			(net "P3V3_AUX_FPGA_VCCIO5")
		)
		(pad "J9" smd circle
			(at -1.999996 -1.999996 90)
			(size 0.4064 0.4064)
			(layers "F.Cu" "F.Mask" "F.Paste")
			(net "GND")
		)
		(pad "J10" smd circle
			(at -1.199896 -1.999996 90)
			(size 0.4064 0.4064)
			(layers "F.Cu" "F.Mask" "F.Paste")
			(net "GND")
		)
		(pad "J11" smd circle
			(at -0.40005 -1.999996 90)
			(size 0.4064 0.4064)
			(layers "F.Cu" "F.Mask" "F.Paste")
			(net "GND")
		)
		(pad "J12" smd circle
			(at 0.40005 -1.999996 90)
			(size 0.4064 0.4064)
			(layers "F.Cu" "F.Mask" "F.Paste")
			(net "GND")
		)
		(pad "J13" smd circle
			(at 1.199896 -1.999996 90)
			(size 0.4064 0.4064)
			(layers "F.Cu" "F.Mask" "F.Paste")
			(net "GND")
		)
		(pad "J14" smd circle
			(at 1.999996 -1.999996 90)
			(size 0.4064 0.4064)
			(layers "F.Cu" "F.Mask" "F.Paste")
			(net "GND")
		)
		(pad "J15" smd circle
			(at 2.800096 -1.999996 90)
			(size 0.4064 0.4064)
			(layers "F.Cu" "F.Mask" "F.Paste")
			(net "P3V3_AUX_FPGA_VCCIO1")
		)
		(pad "J16" smd circle
			(at 3.599942 -1.999996 90)
			(size 0.4064 0.4064)
			(layers "F.Cu" "F.Mask" "F.Paste")
			(net "PWRGD_P1V05_PCH_AUX")
		)
		(pad "J17" smd circle
			(at 4.400042 -1.999996 90)
			(size 0.4064 0.4064)
			(layers "F.Cu" "F.Mask" "F.Paste")
			(net "PWRGD_P1V8_PCH_AUX_PLD")
		)
		(pad "J18" smd circle
			(at 5.199888 -1.999996 90)
			(size 0.4064 0.4064)
			(layers "F.Cu" "F.Mask" "F.Paste")
			(net "PWRGD_SYS_PWROK_R")
		)
		(pad "J19" smd circle
			(at 5.999988 -1.999996 90)
			(size 0.4064 0.4064)
			(layers "F.Cu" "F.Mask" "F.Paste")
			(net "PWRGD_PCH_PWROK_R")
		)
		(pad "J20" smd circle
			(at 6.800088 -1.999996 90)
			(size 0.4064 0.4064)
			(layers "F.Cu" "F.Mask" "F.Paste")
			(net "E1S_0_P3V3_ADC_ALERT")
		)
		(pad "J21" smd circle
			(at 7.599934 -1.999996 90)
			(size 0.4064 0.4064)
			(layers "F.Cu" "F.Mask" "F.Paste")
			(net "IRQ_PVCCFA_CPU0_VRHOT_R_N")
		)
		(pad "J22" smd circle
			(at 8.400034 -1.999996 90)
			(size 0.4064 0.4064)
			(layers "F.Cu" "F.Mask" "F.Paste")
			(net "IRQ_PVCCFA_CPU1_VRHOT_R_N")
		)
		(pad "K1" smd circle
			(at -8.400034 -1.199896 90)
			(size 0.4064 0.4064)
			(layers "F.Cu" "F.Mask" "F.Paste")
			(net "HP_E1S_0_P3V3_PWRGD_PLD")
		)
		(pad "K2" smd circle
			(at -7.599934 -1.199896 90)
			(size 0.4064 0.4064)
			(layers "F.Cu" "F.Mask" "F.Paste")
			(net "HP_LVC3_E1S_0_HSC_PWRGD_PLD")
		)
		(pad "K3" smd circle
			(at -6.800088 -1.199896 90)
			(size 0.4064 0.4064)
			(layers "F.Cu" "F.Mask" "F.Paste")
			(net "HP_LVC3_OCP_V3_2_PRSNT2_PLD_N")
		)
		(pad "K4" smd circle
			(at -5.999988 -1.199896 90)
			(size 0.4064 0.4064)
			(layers "F.Cu" "F.Mask" "F.Paste")
			(net "HP_LVC3_OCP_V3_1_PRSNT2_PLD_N")
		)
		(pad "K5" smd circle
			(at -5.199888 -1.199896 90)
			(size 0.4064 0.4064)
			(layers "F.Cu" "F.Mask" "F.Paste")
			(net "HP_LVC3_OCP_V3_2_FUSE_PWRGD")
		)
		(pad "K6" smd circle
			(at -4.400042 -1.199896 90)
			(size 0.4064 0.4064)
			(layers "F.Cu" "F.Mask" "F.Paste")
			(net "FAB_BMC_REV_ID0")
		)
		(pad "K7" smd circle
			(at -3.599942 -1.199896 90)
			(size 0.4064 0.4064)
			(layers "F.Cu" "F.Mask" "F.Paste")
			(net "FAB_BMC_REV_ID1")
		)
		(pad "K8" smd circle
			(at -2.800096 -1.199896 90)
			(size 0.4064 0.4064)
			(layers "F.Cu" "F.Mask" "F.Paste")
			(net "P3V3_AUX_FPGA_VCCIO5")
		)
		(pad "K9" smd circle
			(at -1.999996 -1.199896 90)
			(size 0.4064 0.4064)
			(layers "F.Cu" "F.Mask" "F.Paste")
			(net "GND")
		)
		(pad "K10" smd circle
			(at -1.199896 -1.199896 90)
			(size 0.4064 0.4064)
			(layers "F.Cu" "F.Mask" "F.Paste")
			(net "VCC_PLD_CORE")
		)
		(pad "K11" smd circle
			(at -0.40005 -1.199896 90)
			(size 0.4064 0.4064)
			(layers "F.Cu" "F.Mask" "F.Paste")
			(net "VCC_PLD_CORE")
		)
		(pad "K12" smd circle
			(at 0.40005 -1.199896 90)
			(size 0.4064 0.4064)
			(layers "F.Cu" "F.Mask" "F.Paste")
			(net "VCC_PLD_CORE")
		)
		(pad "K13" smd circle
			(at 1.199896 -1.199896 90)
			(size 0.4064 0.4064)
			(layers "F.Cu" "F.Mask" "F.Paste")
			(net "VCC_PLD_CORE")
		)
		(pad "K14" smd circle
			(at 1.999996 -1.199896 90)
			(size 0.4064 0.4064)
			(layers "F.Cu" "F.Mask" "F.Paste")
			(net "GND")
		)
		(pad "K15" smd circle
			(at 2.800096 -1.199896 90)
			(size 0.4064 0.4064)
			(layers "F.Cu" "F.Mask" "F.Paste")
			(net "P3V3_AUX_FPGA_VCCIO1")
		)
		(pad "K16" smd circle
			(at 3.599942 -1.199896 90)
			(size 0.4064 0.4064)
			(layers "F.Cu" "F.Mask" "F.Paste")
			(net "P12V_SCM_ADC_ALERT")
		)
		(pad "K17" smd circle
			(at 4.400042 -1.199896 90)
			(size 0.4064 0.4064)
			(layers "F.Cu" "F.Mask" "F.Paste")
			(net "M2_0_P3V3_ADC_ALERT")
		)
		(pad "K18" smd circle
			(at 5.199888 -1.199896 90)
			(size 0.4064 0.4064)
			(layers "F.Cu" "F.Mask" "F.Paste")
			(net "OCP_V3_2_P3V3_ADC_ALERT")
		)
		(pad "K19" smd circle
			(at 5.999988 -1.199896 90)
			(size 0.4064 0.4064)
			(layers "F.Cu" "F.Mask" "F.Paste")
			(net "NC_FPGA_PR13A")
		)
		(pad "K20" smd circle
			(at 6.800088 -1.199896 90)
			(size 0.4064 0.4064)
			(layers "F.Cu" "F.Mask" "F.Paste")
			(net "OCP_SFF_P3V3_ADC_ALERT")
		)
		(pad "K21" smd circle
			(at 7.599934 -1.199896 90)
			(size 0.4064 0.4064)
			(layers "F.Cu" "F.Mask" "F.Paste")
			(net "GND")
		)
		(pad "K22" smd circle
			(at 8.400034 -1.199896 90)
			(size 0.4064 0.4064)
			(layers "F.Cu" "F.Mask" "F.Paste")
			(net "FM_SOL_UART_CH_SEL")
		)
		(pad "L1" smd circle
			(at -8.400034 -0.40005 90)
			(size 0.4064 0.4064)
			(layers "F.Cu" "F.Mask" "F.Paste")
			(net "Net_1435")
		)
		(pad "L2" smd circle
			(at -7.599934 -0.40005 90)
			(size 0.4064 0.4064)
			(layers "F.Cu" "F.Mask" "F.Paste")
			(net "GND")
		)
		(pad "L3" smd circle
			(at -6.800088 -0.40005 90)
			(size 0.4064 0.4064)
			(layers "F.Cu" "F.Mask" "F.Paste")
			(net "Net_1437")
		)
		(pad "L4" smd circle
			(at -5.999988 -0.40005 90)
			(size 0.4064 0.4064)
			(layers "F.Cu" "F.Mask" "F.Paste")
			(net "Net_1438")
		)
		(pad "L5" smd circle
			(at -5.199888 -0.40005 90)
			(size 0.4064 0.4064)
			(layers "F.Cu" "F.Mask" "F.Paste")
			(net "HP_LVC3_SCM_HSC_PWRGD_PLD")
		)
		(pad "L6" smd circle
			(at -4.400042 -0.40005 90)
			(size 0.4064 0.4064)
			(layers "F.Cu" "F.Mask" "F.Paste")
			(net "E1S_0_CLK_OE_N")
		)
		(pad "L7" smd circle
			(at -3.599942 -0.40005 90)
			(size 0.4064 0.4064)
			(layers "F.Cu" "F.Mask" "F.Paste")
			(net "HP_LVC3_OCP_V3_1_FUSE_PWRGD")
		)
		(pad "L8" smd circle
			(at -2.800096 -0.40005 90)
			(size 0.4064 0.4064)
			(layers "F.Cu" "F.Mask" "F.Paste")
			(net "P3V3_AUX_FPGA_VCCIO4")
		)
		(pad "L9" smd circle
			(at -1.999996 -0.40005 90)
			(size 0.4064 0.4064)
			(layers "F.Cu" "F.Mask" "F.Paste")
			(net "GND")
		)
		(pad "L10" smd circle
			(at -1.199896 -0.40005 90)
			(size 0.4064 0.4064)
			(layers "F.Cu" "F.Mask" "F.Paste")
			(net "GND")
		)
		(pad "L11" smd circle
			(at -0.40005 -0.40005 90)
			(size 0.4064 0.4064)
			(layers "F.Cu" "F.Mask" "F.Paste")
			(net "VCC_PLD_CORE")
		)
		(pad "L12" smd circle
			(at 0.40005 -0.40005 90)
			(size 0.4064 0.4064)
			(layers "F.Cu" "F.Mask" "F.Paste")
			(net "VCC_PLD_CORE")
		)
		(pad "L13" smd circle
			(at 1.199896 -0.40005 90)
			(size 0.4064 0.4064)
			(layers "F.Cu" "F.Mask" "F.Paste")
			(net "GND")
		)
		(pad "L14" smd circle
			(at 1.999996 -0.40005 90)
			(size 0.4064 0.4064)
			(layers "F.Cu" "F.Mask" "F.Paste")
			(net "GND")
		)
		(pad "L15" smd circle
			(at 2.800096 -0.40005 90)
			(size 0.4064 0.4064)
			(layers "F.Cu" "F.Mask" "F.Paste")
			(net "P3V3_AUX_FPGA_VCCIO1")
		)
		(pad "L16" smd circle
			(at 3.599942 -0.40005 90)
			(size 0.4064 0.4064)
			(layers "F.Cu" "F.Mask" "F.Paste")
			(net "NC_FPGA_PR14B")
		)
		(pad "L17" smd circle
			(at 4.400042 -0.40005 90)
			(size 0.4064 0.4064)
			(layers "F.Cu" "F.Mask" "F.Paste")
			(net "NC_FPGA_PR14A")
		)
		(pad "L18" smd circle
			(at 5.199888 -0.40005 90)
			(size 0.4064 0.4064)
			(layers "F.Cu" "F.Mask" "F.Paste")
			(net "GND")
		)
		(pad "L19" smd circle
			(at 5.999988 -0.40005 90)
			(size 0.4064 0.4064)
			(layers "F.Cu" "F.Mask" "F.Paste")
			(net "FM_UARTSW_LSB_N")
		)
		(pad "L20" smd circle
			(at 6.800088 -0.40005 90)
			(size 0.4064 0.4064)
			(layers "F.Cu" "F.Mask" "F.Paste")
			(net "FM_UARTSW_MSB_N")
		)
		(pad "L21" smd circle
			(at 7.599934 -0.40005 90)
			(size 0.4064 0.4064)
			(layers "F.Cu" "F.Mask" "F.Paste")
			(net "FM_THERMAL_ALERT_R_N")
		)
		(pad "L22" smd circle
			(at 8.400034 -0.40005 90)
			(size 0.4064 0.4064)
			(layers "F.Cu" "F.Mask" "F.Paste")
			(net "NC_FPGA_PR16C")
		)
		(pad "M1" smd circle
			(at -8.400034 0.40005 90)
			(size 0.4064 0.4064)
			(layers "F.Cu" "F.Mask" "F.Paste")
			(net "Net_1439")
		)
		(pad "M2" smd circle
			(at -7.599934 0.40005 90)
			(size 0.4064 0.4064)
			(layers "F.Cu" "F.Mask" "F.Paste")
			(net "Net_1436")
		)
		(pad "M3" smd circle
			(at -6.800088 0.40005 90)
			(size 0.4064 0.4064)
			(layers "F.Cu" "F.Mask" "F.Paste")
			(net "P3V3_AUX_FPGA_VCCIO4")
		)
		(pad "M4" smd circle
			(at -5.999988 0.40005 90)
			(size 0.4064 0.4064)
			(layers "F.Cu" "F.Mask" "F.Paste")
			(net "GND")
		)
		(pad "M5" smd circle
			(at -5.199888 0.40005 90)
			(size 0.4064 0.4064)
			(layers "F.Cu" "F.Mask" "F.Paste")
			(net "Net_1442")
		)
		(pad "M6" smd circle
			(at -4.400042 0.40005 90)
			(size 0.4064 0.4064)
			(layers "F.Cu" "F.Mask" "F.Paste")
			(net "Net_1441")
		)
		(pad "M7" smd circle
			(at -3.599942 0.40005 90)
			(size 0.4064 0.4064)
			(layers "F.Cu" "F.Mask" "F.Paste")
			(net "Net_1450")
		)
		(pad "M8" smd circle
			(at -2.800096 0.40005 90)
			(size 0.4064 0.4064)
			(layers "F.Cu" "F.Mask" "F.Paste")
			(net "P3V3_AUX_FPGA_VCCIO4")
		)
		(pad "M9" smd circle
			(at -1.999996 0.40005 90)
			(size 0.4064 0.4064)
			(layers "F.Cu" "F.Mask" "F.Paste")
			(net "GND")
		)
		(pad "M10" smd circle
			(at -1.199896 0.40005 90)
			(size 0.4064 0.4064)
			(layers "F.Cu" "F.Mask" "F.Paste")
			(net "GND")
		)
		(pad "M11" smd circle
			(at -0.40005 0.40005 90)
			(size 0.4064 0.4064)
			(layers "F.Cu" "F.Mask" "F.Paste")
			(net "VCC_PLD_CORE")
		)
		(pad "M12" smd circle
			(at 0.40005 0.40005 90)
			(size 0.4064 0.4064)
			(layers "F.Cu" "F.Mask" "F.Paste")
			(net "VCC_PLD_CORE")
		)
		(pad "M13" smd circle
			(at 1.199896 0.40005 90)
			(size 0.4064 0.4064)
			(layers "F.Cu" "F.Mask" "F.Paste")
			(net "GND")
		)
		(pad "M14" smd circle
			(at 1.999996 0.40005 90)
			(size 0.4064 0.4064)
			(layers "F.Cu" "F.Mask" "F.Paste")
			(net "GND")
		)
		(pad "M15" smd circle
			(at 2.800096 0.40005 90)
			(size 0.4064 0.4064)
			(layers "F.Cu" "F.Mask" "F.Paste")
			(net "P3V3_AUX_FPGA_VCCIO1")
		)
		(pad "M16" smd circle
			(at 3.599942 0.40005 90)
			(size 0.4064 0.4064)
			(layers "F.Cu" "F.Mask" "F.Paste")
			(net "FM_CPU0_SKTOCC_LVT3_PLD_N")
		)
		(pad "M17" smd circle
			(at 4.400042 0.40005 90)
			(size 0.4064 0.4064)
			(layers "F.Cu" "F.Mask" "F.Paste")
			(net "NC_FPGA_PR16D")
		)
		(pad "M18" smd circle
			(at 5.199888 0.40005 90)
			(size 0.4064 0.4064)
			(layers "F.Cu" "F.Mask" "F.Paste")
			(net "P3V3_AUX_FPGA_VCCIO1")
		)
		(pad "M19" smd circle
			(at 5.999988 0.40005 90)
			(size 0.4064 0.4064)
			(layers "F.Cu" "F.Mask" "F.Paste")
			(net "RST_PCIE_CPU1_DEV_PERST_N")
		)
		(pad "M20" smd circle
			(at 6.800088 0.40005 90)
			(size 0.4064 0.4064)
			(layers "F.Cu" "F.Mask" "F.Paste")
			(net "RST_PCIE_CPU0_DEV_PERST_N")
		)
		(pad "M21" smd circle
			(at 7.599934 0.40005 90)
			(size 0.4064 0.4064)
			(layers "F.Cu" "F.Mask" "F.Paste")
			(net "SMB_2_PLD_3V3AUX_SDA_R1")
		)
		(pad "M22" smd circle
			(at 8.400034 0.40005 90)
			(size 0.4064 0.4064)
			(layers "F.Cu" "F.Mask" "F.Paste")
			(net "SMB_2_PLD_3V3AUX_SCL_R1")
		)
		(pad "N1" smd circle
			(at -8.400034 1.199896 90)
			(size 0.4064 0.4064)
			(layers "F.Cu" "F.Mask" "F.Paste")
			(net "Net_1440")
		)
		(pad "N2" smd circle
			(at -7.599934 1.199896 90)
			(size 0.4064 0.4064)
			(layers "F.Cu" "F.Mask" "F.Paste")
			(net "Net_1443")
		)
		(pad "N3" smd circle
			(at -6.800088 1.199896 90)
			(size 0.4064 0.4064)
			(layers "F.Cu" "F.Mask" "F.Paste")
			(net "Net_1445")
		)
		(pad "N4" smd circle
			(at -5.999988 1.199896 90)
			(size 0.4064 0.4064)
			(layers "F.Cu" "F.Mask" "F.Paste")
			(net "Net_1446")
		)
		(pad "N5" smd circle
			(at -5.199888 1.199896 90)
			(size 0.4064 0.4064)
			(layers "F.Cu" "F.Mask" "F.Paste")
			(net "Net_1451")
		)
		(pad "N6" smd circle
			(at -4.400042 1.199896 90)
			(size 0.4064 0.4064)
			(layers "F.Cu" "F.Mask" "F.Paste")
			(net "Net_1452")
		)
		(pad "N7" smd circle
			(at -3.599942 1.199896 90)
			(size 0.4064 0.4064)
			(layers "F.Cu" "F.Mask" "F.Paste")
			(net "Net_1453")
		)
		(pad "N8" smd circle
			(at -2.800096 1.199896 90)
			(size 0.4064 0.4064)
			(layers "F.Cu" "F.Mask" "F.Paste")
			(net "P3V3_AUX_FPGA_VCCIO3")
		)
		(pad "N9" smd circle
			(at -1.999996 1.199896 90)
			(size 0.4064 0.4064)
			(layers "F.Cu" "F.Mask" "F.Paste")
			(net "GND")
		)
		(pad "N10" smd circle
			(at -1.199896 1.199896 90)
			(size 0.4064 0.4064)
			(layers "F.Cu" "F.Mask" "F.Paste")
			(net "VCC_PLD_CORE")
		)
		(pad "N11" smd circle
			(at -0.40005 1.199896 90)
			(size 0.4064 0.4064)
			(layers "F.Cu" "F.Mask" "F.Paste")
			(net "VCC_PLD_CORE")
		)
		(pad "N12" smd circle
			(at 0.40005 1.199896 90)
			(size 0.4064 0.4064)
			(layers "F.Cu" "F.Mask" "F.Paste")
			(net "VCC_PLD_CORE")
		)
		(pad "N13" smd circle
			(at 1.199896 1.199896 90)
			(size 0.4064 0.4064)
			(layers "F.Cu" "F.Mask" "F.Paste")
			(net "VCC_PLD_CORE")
		)
		(pad "N14" smd circle
			(at 1.999996 1.199896 90)
			(size 0.4064 0.4064)
			(layers "F.Cu" "F.Mask" "F.Paste")
			(net "GND")
		)
		(pad "N15" smd circle
			(at 2.800096 1.199896 90)
			(size 0.4064 0.4064)
			(layers "F.Cu" "F.Mask" "F.Paste")
			(net "P3V3_AUX_FPGA_VCCIO1")
		)
		(pad "N16" smd circle
			(at 3.599942 1.199896 90)
			(size 0.4064 0.4064)
			(layers "F.Cu" "F.Mask" "F.Paste")
			(net "FM_CPU1_SKTOCC_LVT3_PLD_N")
		)
		(pad "N17" smd circle
			(at 4.400042 1.199896 90)
			(size 0.4064 0.4064)
			(layers "F.Cu" "F.Mask" "F.Paste")
			(net "FM_CPU0_PROC_ID0")
		)
		(pad "N18" smd circle
			(at 5.199888 1.199896 90)
			(size 0.4064 0.4064)
			(layers "F.Cu" "F.Mask" "F.Paste")
			(net "FM_CPU0_PROC_ID1")
		)
		(pad "N19" smd circle
			(at 5.999988 1.199896 90)
			(size 0.4064 0.4064)
			(layers "F.Cu" "F.Mask" "F.Paste")
			(net "FM_CPU0_PKGID1")
		)
		(pad "N20" smd circle
			(at 6.800088 1.199896 90)
			(size 0.4064 0.4064)
			(layers "F.Cu" "F.Mask" "F.Paste")
			(net "FM_CPU0_PKGID0")
		)
		(pad "N21" smd circle
			(at 7.599934 1.199896 90)
			(size 0.4064 0.4064)
			(layers "F.Cu" "F.Mask" "F.Paste")
			(net "GND")
		)
		(pad "N22" smd circle
			(at 8.400034 1.199896 90)
			(size 0.4064 0.4064)
			(layers "F.Cu" "F.Mask" "F.Paste")
			(net "FM_CPU1_PROC_ID0")
		)
		(pad "P1" smd circle
			(at -8.400034 1.999996 90)
			(size 0.4064 0.4064)
			(layers "F.Cu" "F.Mask" "F.Paste")
			(net "Net_1444")
		)
		(pad "P2" smd circle
			(at -7.599934 1.999996 90)
			(size 0.4064 0.4064)
			(layers "F.Cu" "F.Mask" "F.Paste")
			(net "Net_1447")
		)
		(pad "P3" smd circle
			(at -6.800088 1.999996 90)
			(size 0.4064 0.4064)
			(layers "F.Cu" "F.Mask" "F.Paste")
			(net "Net_1449")
		)
		(pad "P4" smd circle
			(at -5.999988 1.999996 90)
			(size 0.4064 0.4064)
			(layers "F.Cu" "F.Mask" "F.Paste")
			(net "Net_750")
		)
		(pad "P5" smd circle
			(at -5.199888 1.999996 90)
			(size 0.4064 0.4064)
			(layers "F.Cu" "F.Mask" "F.Paste")
			(net "PWRGD_CPUPWRGD_LVC2_R1")
		)
		(pad "P6" smd circle
			(at -4.400042 1.999996 90)
			(size 0.4064 0.4064)
			(layers "F.Cu" "F.Mask" "F.Paste")
			(net "Net_442")
		)
		(pad "P7" smd circle
			(at -3.599942 1.999996 90)
			(size 0.4064 0.4064)
			(layers "F.Cu" "F.Mask" "F.Paste")
			(net "H_CPU1_THERMTRIP_LVC1_N")
		)
		(pad "P8" smd circle
			(at -2.800096 1.999996 90)
			(size 0.4064 0.4064)
			(layers "F.Cu" "F.Mask" "F.Paste")
			(net "P3V3_AUX_FPGA_VCCIO3")
		)
		(pad "P9" smd circle
			(at -1.999996 1.999996 90)
			(size 0.4064 0.4064)
			(layers "F.Cu" "F.Mask" "F.Paste")
			(net "GND")
		)
		(pad "P10" smd circle
			(at -1.199896 1.999996 90)
			(size 0.4064 0.4064)
			(layers "F.Cu" "F.Mask" "F.Paste")
			(net "GND")
		)
		(pad "P11" smd circle
			(at -0.40005 1.999996 90)
			(size 0.4064 0.4064)
			(layers "F.Cu" "F.Mask" "F.Paste")
			(net "GND")
		)
		(pad "P12" smd circle
			(at 0.40005 1.999996 90)
			(size 0.4064 0.4064)
			(layers "F.Cu" "F.Mask" "F.Paste")
			(net "GND")
		)
		(pad "P13" smd circle
			(at 1.199896 1.999996 90)
			(size 0.4064 0.4064)
			(layers "F.Cu" "F.Mask" "F.Paste")
			(net "GND")
		)
		(pad "P14" smd circle
			(at 1.999996 1.999996 90)
			(size 0.4064 0.4064)
			(layers "F.Cu" "F.Mask" "F.Paste")
			(net "GND")
		)
		(pad "P15" smd circle
			(at 2.800096 1.999996 90)
			(size 0.4064 0.4064)
			(layers "F.Cu" "F.Mask" "F.Paste")
			(net "P3V3_AUX_FPGA_VCCIO1")
		)
		(pad "P16" smd circle
			(at 3.599942 1.999996 90)
			(size 0.4064 0.4064)
			(layers "F.Cu" "F.Mask" "F.Paste")
			(net "FM_CPU_RMCA_CATERR_DLY_LVT3_R_N")
		)
		(pad "P17" smd circle
			(at 4.400042 1.999996 90)
			(size 0.4064 0.4064)
			(layers "F.Cu" "F.Mask" "F.Paste")
			(net "FM_RST_PERST_BIT1")
		)
		(pad "P18" smd circle
			(at 5.199888 1.999996 90)
			(size 0.4064 0.4064)
			(layers "F.Cu" "F.Mask" "F.Paste")
			(net "FM_RST_PERST_BIT0")
		)
		(pad "P19" smd circle
			(at 5.999988 1.999996 90)
			(size 0.4064 0.4064)
			(layers "F.Cu" "F.Mask" "F.Paste")
			(net "IRQ_PVCCIN_CPU1_VRHOT_R_N")
		)
		(pad "P20" smd circle
			(at 6.800088 1.999996 90)
			(size 0.4064 0.4064)
			(layers "F.Cu" "F.Mask" "F.Paste")
			(net "FM_CPU1_PKGID2")
		)
		(pad "P21" smd circle
			(at 7.599934 1.999996 90)
			(size 0.4064 0.4064)
			(layers "F.Cu" "F.Mask" "F.Paste")
			(net "FM_CPU1_PROC_ID1")
		)
		(pad "P22" smd circle
			(at 8.400034 1.999996 90)
			(size 0.4064 0.4064)
			(layers "F.Cu" "F.Mask" "F.Paste")
			(net "FM_CPU1_PKGID1")
		)
		(pad "R1" smd circle
			(at -8.400034 2.800096 90)
			(size 0.4064 0.4064)
			(layers "F.Cu" "F.Mask" "F.Paste")
			(net "Net_1448")
		)
		(pad "R2" smd circle
			(at -7.599934 2.800096 90)
			(size 0.4064 0.4064)
			(layers "F.Cu" "F.Mask" "F.Paste")
			(net "Net_1454")
		)
		(pad "R3" smd circle
			(at -6.800088 2.800096 90)
			(size 0.4064 0.4064)
			(layers "F.Cu" "F.Mask" "F.Paste")
			(net "Net_441")
		)
		(pad "R4" smd circle
			(at -5.999988 2.800096 90)
			(size 0.4064 0.4064)
			(layers "F.Cu" "F.Mask" "F.Paste")
			(net "Net_443")
		)
		(pad "R5" smd circle
			(at -5.199888 2.800096 90)
			(size 0.4064 0.4064)
			(layers "F.Cu" "F.Mask" "F.Paste")
			(net "Net_444")
		)
		(pad "R6" smd circle
			(at -4.400042 2.800096 90)
			(size 0.4064 0.4064)
			(layers "F.Cu" "F.Mask" "F.Paste")
			(net "H_CPU0_MEMTRIP_LVC1_N")
		)
		(pad "R7" smd circle
			(at -3.599942 2.800096 90)
			(size 0.4064 0.4064)
			(layers "F.Cu" "F.Mask" "F.Paste")
			(net "H_CPU1_MEMHOT_OUT_LVC1_N")
		)
		(pad "R8" smd circle
			(at -2.800096 2.800096 90)
			(size 0.4064 0.4064)
			(layers "F.Cu" "F.Mask" "F.Paste")
			(net "GND")
		)
		(pad "R9" smd circle
			(at -1.999996 2.800096 90)
			(size 0.4064 0.4064)
			(layers "F.Cu" "F.Mask" "F.Paste")
			(net "P3V3_AUX_FPGA_VCCIO2")
		)
		(pad "R10" smd circle
			(at -1.199896 2.800096 90)
			(size 0.4064 0.4064)
			(layers "F.Cu" "F.Mask" "F.Paste")
			(net "P3V3_AUX_FPGA_VCCIO2")
		)
		(pad "R11" smd circle
			(at -0.40005 2.800096 90)
			(size 0.4064 0.4064)
			(layers "F.Cu" "F.Mask" "F.Paste")
			(net "P3V3_AUX_FPGA_VCCIO2")
		)
		(pad "R12" smd circle
			(at 0.40005 2.800096 90)
			(size 0.4064 0.4064)
			(layers "F.Cu" "F.Mask" "F.Paste")
			(net "P3V3_AUX_FPGA_VCCIO2")
		)
		(pad "R13" smd circle
			(at 1.199896 2.800096 90)
			(size 0.4064 0.4064)
			(layers "F.Cu" "F.Mask" "F.Paste")
			(net "P3V3_AUX_FPGA_VCCIO2")
		)
		(pad "R14" smd circle
			(at 1.999996 2.800096 90)
			(size 0.4064 0.4064)
			(layers "F.Cu" "F.Mask" "F.Paste")
			(net "P3V3_AUX_FPGA_VCCIO2")
		)
		(pad "R15" smd circle
			(at 2.800096 2.800096 90)
			(size 0.4064 0.4064)
			(layers "F.Cu" "F.Mask" "F.Paste")
			(net "GND")
		)
		(pad "R16" smd circle
			(at 3.599942 2.800096 90)
			(size 0.4064 0.4064)
			(layers "F.Cu" "F.Mask" "F.Paste")
			(net "PWRGD_FAIL_CPU1_CD_R")
		)
		(pad "R17" smd circle
			(at 4.400042 2.800096 90)
			(size 0.4064 0.4064)
			(layers "F.Cu" "F.Mask" "F.Paste")
			(net "PWRGD_FAIL_CPU1_AB_R")
		)
		(pad "R18" smd circle
			(at 5.199888 2.800096 90)
			(size 0.4064 0.4064)
			(layers "F.Cu" "F.Mask" "F.Paste")
			(net "PWRGD_FAIL_CPU0_GH_R")
		)
		(pad "R19" smd circle
			(at 5.999988 2.800096 90)
			(size 0.4064 0.4064)
			(layers "F.Cu" "F.Mask" "F.Paste")
			(net "PWRGD_FAIL_CPU0_EF_R")
		)
		(pad "R20" smd circle
			(at 6.800088 2.800096 90)
			(size 0.4064 0.4064)
			(layers "F.Cu" "F.Mask" "F.Paste")
			(net "PWRGD_FAIL_CPU0_CD_R")
		)
		(pad "R21" smd circle
			(at 7.599934 2.800096 90)
			(size 0.4064 0.4064)
			(layers "F.Cu" "F.Mask" "F.Paste")
			(net "FM_CPU1_PKGID0")
		)
		(pad "R22" smd circle
			(at 8.400034 2.800096 90)
			(size 0.4064 0.4064)
			(layers "F.Cu" "F.Mask" "F.Paste")
			(net "FM_CPU0_PKGID2")
		)
		(pad "T1" smd circle
			(at -8.400034 3.599942 90)
			(size 0.4064 0.4064)
			(layers "F.Cu" "F.Mask" "F.Paste")
			(net "Net_1455")
		)
		(pad "T2" smd circle
			(at -7.599934 3.599942 90)
			(size 0.4064 0.4064)
			(layers "F.Cu" "F.Mask" "F.Paste")
			(net "H_CPU0_THERMTRIP_LVC1_N")
		)
		(pad "T3" smd circle
			(at -6.800088 3.599942 90)
			(size 0.4064 0.4064)
			(layers "F.Cu" "F.Mask" "F.Paste")
			(net "H_CPU0_MEMHOT_OUT_LVC1_N")
		)
		(pad "T4" smd circle
			(at -5.999988 3.599942 90)
			(size 0.4064 0.4064)
			(layers "F.Cu" "F.Mask" "F.Paste")
			(net "H_CPU_ERR2_LVC2_N")
		)
		(pad "T5" smd circle
			(at -5.199888 3.599942 90)
			(size 0.4064 0.4064)
			(layers "F.Cu" "F.Mask" "F.Paste")
			(net "H_CPU_ERR1_LVC2_N")
		)
		(pad "T6" smd circle
			(at -4.400042 3.599942 90)
			(size 0.4064 0.4064)
			(layers "F.Cu" "F.Mask" "F.Paste")
			(net "H_CPU_ERR0_LVC2_N")
		)
		(pad "T7" smd circle
			(at -3.599942 3.599942 90)
			(size 0.4064 0.4064)
			(layers "F.Cu" "F.Mask" "F.Paste")
			(net "H_CPU0_MEMHOT_IN_LVC1_R_N")
		)
		(pad "T8" smd circle
			(at -2.800096 3.599942 90)
			(size 0.4064 0.4064)
			(layers "F.Cu" "F.Mask" "F.Paste")
			(net "FM_PLD_CLK_25M_R_EN")
		)
		(pad "T9" smd circle
			(at -1.999996 3.599942 90)
			(size 0.4064 0.4064)
			(layers "F.Cu" "F.Mask" "F.Paste")
			(net "FM_BIOS_POST_CMPLT_BMC_N")
		)
		(pad "T10" smd circle
			(at -1.199896 3.599942 90)
			(size 0.4064 0.4064)
			(layers "F.Cu" "F.Mask" "F.Paste")
			(net "FM_PLD_HEARTBEAT_LVC3")
		)
		(pad "T11" smd circle
			(at -0.40005 3.599942 90)
			(size 0.4064 0.4064)
			(layers "F.Cu" "F.Mask" "F.Paste")
			(net "GPU_3V3IO_RSVD0_FFU_ISO_R")
		)
		(pad "T12" smd circle
			(at 0.40005 3.599942 90)
			(size 0.4064 0.4064)
			(layers "F.Cu" "F.Mask" "F.Paste")
			(net "GPU_3V3IO_RSVD1_ISO_R")
		)
		(pad "T13" smd circle
			(at 1.199896 3.599942 90)
			(size 0.4064 0.4064)
			(layers "F.Cu" "F.Mask" "F.Paste")
			(net "RST_SGPIO_RESET_N_R")
		)
		(pad "T14" smd circle
			(at 1.999996 3.599942 90)
			(size 0.4064 0.4064)
			(layers "F.Cu" "F.Mask" "F.Paste")
			(net "FM_ME_BT_DONE")
		)
		(pad "T15" smd circle
			(at 2.800096 3.599942 90)
			(size 0.4064 0.4064)
			(layers "F.Cu" "F.Mask" "F.Paste")
			(net "CLK_SWB_BUF2_OE_N")
		)
		(pad "T16" smd circle
			(at 3.599942 3.599942 90)
			(size 0.4064 0.4064)
			(layers "F.Cu" "F.Mask" "F.Paste")
			(net "FM_AC_PWR_BTN_PLD_ISO_N")
		)
		(pad "T17" smd circle
			(at 4.400042 3.599942 90)
			(size 0.4064 0.4064)
			(layers "F.Cu" "F.Mask" "F.Paste")
			(net "OCP_V3_2_MAIN_PWR_EN")
		)
		(pad "T18" smd circle
			(at 5.199888 3.599942 90)
			(size 0.4064 0.4064)
			(layers "F.Cu" "F.Mask" "F.Paste")
			(net "OCP_SFF_MAIN_PWR_EN")
		)
		(pad "T19" smd circle
			(at 5.999988 3.599942 90)
			(size 0.4064 0.4064)
			(layers "F.Cu" "F.Mask" "F.Paste")
			(net "PWRGD_FAIL_CPU1_GH_R")
		)
		(pad "T20" smd circle
			(at 6.800088 3.599942 90)
			(size 0.4064 0.4064)
			(layers "F.Cu" "F.Mask" "F.Paste")
			(net "PWRGD_FAIL_CPU1_EF_R")
		)
		(pad "T21" smd circle
			(at 7.599934 3.599942 90)
			(size 0.4064 0.4064)
			(layers "F.Cu" "F.Mask" "F.Paste")
			(net "IRQ_PVCCIN_CPU0_VRHOT_R_N")
		)
		(pad "T22" smd circle
			(at 8.400034 3.599942 90)
			(size 0.4064 0.4064)
			(layers "F.Cu" "F.Mask" "F.Paste")
			(net "PWRGD_DSW_PWROK_R3")
		)
		(pad "U1" smd circle
			(at -8.400034 4.400042 90)
			(size 0.4064 0.4064)
			(layers "F.Cu" "F.Mask" "F.Paste")
			(net "H_CPU1_MEMTRIP_LVC1_N")
		)
		(pad "U2" smd circle
			(at -7.599934 4.400042 90)
			(size 0.4064 0.4064)
			(layers "F.Cu" "F.Mask" "F.Paste")
			(net "Net_1456")
		)
		(pad "U3" smd circle
			(at -6.800088 4.400042 90)
			(size 0.4064 0.4064)
			(layers "F.Cu" "F.Mask" "F.Paste")
			(net "Net_1458")
		)
		(pad "U4" smd circle
			(at -5.999988 4.400042 90)
			(size 0.4064 0.4064)
			(layers "F.Cu" "F.Mask" "F.Paste")
			(net "Net_1459")
		)
		(pad "U5" smd circle
			(at -5.199888 4.400042 90)
			(size 0.4064 0.4064)
			(layers "F.Cu" "F.Mask" "F.Paste")
			(net "RST_CPU0_LVC1_R_N")
		)
		(pad "U6" smd circle
			(at -4.400042 4.400042 90)
			(size 0.4064 0.4064)
			(layers "F.Cu" "F.Mask" "F.Paste")
			(net "FM_ADR_COMPLETE")
		)
		(pad "U7" smd circle
			(at -3.599942 4.400042 90)
			(size 0.4064 0.4064)
			(layers "F.Cu" "F.Mask" "F.Paste")
			(net "FM_PLD_CLKS_DEV_R_EN")
		)
		(pad "U8" smd circle
			(at -2.800096 4.400042 90)
			(size 0.4064 0.4064)
			(layers "F.Cu" "F.Mask" "F.Paste")
			(net "FM_BMC_DBP_PRESENT_R_N")
		)
		(pad "U9" smd circle
			(at -1.999996 4.400042 90)
			(size 0.4064 0.4064)
			(layers "F.Cu" "F.Mask" "F.Paste")
			(net "FM_BMC_RSTBTN_OUT_N")
		)
		(pad "U10" smd circle
			(at -1.199896 4.400042 90)
			(size 0.4064 0.4064)
			(layers "F.Cu" "F.Mask" "F.Paste")
			(net "FM_FORCE_PWRON_LVC3")
		)
		(pad "U11" smd circle
			(at -0.40005 4.400042 90)
			(size 0.4064 0.4064)
			(layers "F.Cu" "F.Mask" "F.Paste")
			(net "GPU_3V3IO_RSVD1_FFU_ISO_R")
		)
		(pad "U12" smd circle
			(at 0.40005 4.400042 90)
			(size 0.4064 0.4064)
			(layers "F.Cu" "F.Mask" "F.Paste")
			(net "GPU_3V3IO_RSVD3_ISO_R")
		)
		(pad "U13" smd circle
			(at 1.199896 4.400042 90)
			(size 0.4064 0.4064)
			(layers "F.Cu" "F.Mask" "F.Paste")
			(net "IRQ_BMC_CPU_NMI_R1")
		)
		(pad "U14" smd circle
			(at 1.999996 4.400042 90)
			(size 0.4064 0.4064)
			(layers "F.Cu" "F.Mask" "F.Paste")
			(net "RST_PCIE_PCH_DEV_PERST_N")
		)
		(pad "U15" smd circle
			(at 2.800096 4.400042 90)
			(size 0.4064 0.4064)
			(layers "F.Cu" "F.Mask" "F.Paste")
			(net "FM_SLPS3_PLD_N")
		)
		(pad "U16" smd circle
			(at 3.599942 4.400042 90)
			(size 0.4064 0.4064)
			(layers "F.Cu" "F.Mask" "F.Paste")
			(net "NC_FPGA_PB43D")
		)
		(pad "U17" smd circle
			(at 4.400042 4.400042 90)
			(size 0.4064 0.4064)
			(layers "F.Cu" "F.Mask" "F.Paste")
			(net "FM_JTAG_TCK_MUX_SEL_R")
		)
		(pad "U18" smd circle
			(at 5.199888 4.400042 90)
			(size 0.4064 0.4064)
			(layers "F.Cu" "F.Mask" "F.Paste")
			(net "E1S_0_LED_ACT_R_N")
		)
		(pad "U19" smd circle
			(at 5.999988 4.400042 90)
			(size 0.4064 0.4064)
			(layers "F.Cu" "F.Mask" "F.Paste")
			(net "FM_SMB_2_ALERT_GPU_ISO_R_N")
		)
		(pad "U20" smd circle
			(at 6.800088 4.400042 90)
			(size 0.4064 0.4064)
			(layers "F.Cu" "F.Mask" "F.Paste")
			(net "HP_LVC3_OCP_V3_2_HSC_PWRGD_PLD_")
		)
		(pad "U21" smd circle
			(at 7.599934 4.400042 90)
			(size 0.4064 0.4064)
			(layers "F.Cu" "F.Mask" "F.Paste")
			(net "FM_SLPS4_PLD_N")
		)
		(pad "U22" smd circle
			(at 8.400034 4.400042 90)
			(size 0.4064 0.4064)
			(layers "F.Cu" "F.Mask" "F.Paste")
			(net "FM_JTAG_BMC_MUX_SEL_R")
		)
		(pad "V1" smd circle
			(at -8.400034 5.199888 90)
			(size 0.4064 0.4064)
			(layers "F.Cu" "F.Mask" "F.Paste")
			(net "Net_1457")
		)
		(pad "V2" smd circle
			(at -7.599934 5.199888 90)
			(size 0.4064 0.4064)
			(layers "F.Cu" "F.Mask" "F.Paste")
			(net "GND")
		)
		(pad "V3" smd circle
			(at -6.800088 5.199888 90)
			(size 0.4064 0.4064)
			(layers "F.Cu" "F.Mask" "F.Paste")
			(net "P3V3_AUX_FPGA_VCCIO3")
		)
		(pad "V4" smd circle
			(at -5.999988 5.199888 90)
			(size 0.4064 0.4064)
			(layers "F.Cu" "F.Mask" "F.Paste")
			(net "RST_CPU1_LVC1_R_N")
		)
		(pad "V5" smd circle
			(at -5.199888 5.199888 90)
			(size 0.4064 0.4064)
			(layers "F.Cu" "F.Mask" "F.Paste")
			(net "H_CPU1_MEMHOT_IN_LVC1_R_N")
		)
		(pad "V6" smd circle
			(at -4.400042 5.199888 90)
			(size 0.4064 0.4064)
			(layers "F.Cu" "F.Mask" "F.Paste")
			(net "FM_ADR_TRIGGER_N")
		)
		(pad "V7" smd circle
			(at -3.599942 5.199888 90)
			(size 0.4064 0.4064)
			(layers "F.Cu" "F.Mask" "F.Paste")
			(net "RST_PFR_OVR_SRTC_R")
		)
		(pad "V8" smd circle
			(at -2.800096 5.199888 90)
			(size 0.4064 0.4064)
			(layers "F.Cu" "F.Mask" "F.Paste")
			(net "FM_REMOTE_DEBUG_DET")
		)
		(pad "V9" smd circle
			(at -1.999996 5.199888 90)
			(size 0.4064 0.4064)
			(layers "F.Cu" "F.Mask" "F.Paste")
			(net "FM_PS_PWROK_DLY_SEL")
		)
		(pad "V10" smd circle
			(at -1.199896 5.199888 90)
			(size 0.4064 0.4064)
			(layers "F.Cu" "F.Mask" "F.Paste")
			(net "E1S_0_PRSNT_N")
		)
		(pad "V11" smd circle
			(at -0.40005 5.199888 90)
			(size 0.4064 0.4064)
			(layers "F.Cu" "F.Mask" "F.Paste")
			(net "PRSNT_CABLE_GPU_A2_ISO_R_N")
		)
		(pad "V12" smd circle
			(at 0.40005 5.199888 90)
			(size 0.4064 0.4064)
			(layers "F.Cu" "F.Mask" "F.Paste")
			(net "GPU_3V3IO_RSVD4_ISO_R")
		)
		(pad "V13" smd circle
			(at 1.199896 5.199888 90)
			(size 0.4064 0.4064)
			(layers "F.Cu" "F.Mask" "F.Paste")
			(net "IRQ_PCH_CPU_NMI_EVENT_N")
		)
		(pad "V14" smd circle
			(at 1.999996 5.199888 90)
			(size 0.4064 0.4064)
			(layers "F.Cu" "F.Mask" "F.Paste")
			(net "NC_FPGA_PB32D")
		)
		(pad "V15" smd circle
			(at 2.800096 5.199888 90)
			(size 0.4064 0.4064)
			(layers "F.Cu" "F.Mask" "F.Paste")
			(net "ROT_P1_RST_IND_N_R")
		)
		(pad "V16" smd circle
			(at 3.599942 5.199888 90)
			(size 0.4064 0.4064)
			(layers "F.Cu" "F.Mask" "F.Paste")
			(net "RST_RSMRST_PLD_R_N")
		)
		(pad "V17" smd circle
			(at 4.400042 5.199888 90)
			(size 0.4064 0.4064)
			(layers "F.Cu" "F.Mask" "F.Paste")
			(net "FM_PDB_BUF_EN")
		)
		(pad "V18" smd circle
			(at 5.199888 5.199888 90)
			(size 0.4064 0.4064)
			(layers "F.Cu" "F.Mask" "F.Paste")
			(net "FM_BMC_CPU_FBRK_OUT_R_N")
		)
		(pad "V19" smd circle
			(at 5.999988 5.199888 90)
			(size 0.4064 0.4064)
			(layers "F.Cu" "F.Mask" "F.Paste")
			(net "CLK_GEN2_GPU_FPGA_OE_R_N")
		)
		(pad "V20" smd circle
			(at 6.800088 5.199888 90)
			(size 0.4064 0.4064)
			(layers "F.Cu" "F.Mask" "F.Paste")
			(net "P3V3_AUX_FPGA_VCCIO1")
		)
		(pad "V21" smd circle
			(at 7.599934 5.199888 90)
			(size 0.4064 0.4064)
			(layers "F.Cu" "F.Mask" "F.Paste")
			(net "GND")
		)
		(pad "V22" smd circle
			(at 8.400034 5.199888 90)
			(size 0.4064 0.4064)
			(layers "F.Cu" "F.Mask" "F.Paste")
			(net "FM_PS_EN_PLD_R")
		)
		(pad "W1" smd circle
			(at -8.400034 5.999988 90)
			(size 0.4064 0.4064)
			(layers "F.Cu" "F.Mask" "F.Paste")
			(net "PWRGD_CPU1_LVC1_R")
		)
		(pad "W2" smd circle
			(at -7.599934 5.999988 90)
			(size 0.4064 0.4064)
			(layers "F.Cu" "F.Mask" "F.Paste")
			(net "PWRGD_CPU0_LVC1_R")
		)
		(pad "W3" smd circle
			(at -6.800088 5.999988 90)
			(size 0.4064 0.4064)
			(layers "F.Cu" "F.Mask" "F.Paste")
			(net "FM_THERMTRIP_DLY_LVC1_R_N")
		)
		(pad "W4" smd circle
			(at -5.999988 5.999988 90)
			(size 0.4064 0.4064)
			(layers "F.Cu" "F.Mask" "F.Paste")
			(net "H_CPU0_PROCHOT_LVC1_R_N")
		)
		(pad "W5" smd circle
			(at -5.199888 5.999988 90)
			(size 0.4064 0.4064)
			(layers "F.Cu" "F.Mask" "F.Paste")
			(net "NC_FPGA_PB7D")
		)
		(pad "W6" smd circle
			(at -4.400042 5.999988 90)
			(size 0.4064 0.4064)
			(layers "F.Cu" "F.Mask" "F.Paste")
			(net "RST_PFR_OVR_RTC_R")
		)
		(pad "W7" smd circle
			(at -3.599942 5.999988 90)
			(size 0.4064 0.4064)
			(layers "F.Cu" "F.Mask" "F.Paste")
			(net "P3V3_AUX_FPGA_VCCIO2")
		)
		(pad "W8" smd circle
			(at -2.800096 5.999988 90)
			(size 0.4064 0.4064)
			(layers "F.Cu" "F.Mask" "F.Paste")
			(net "FM_RST_PERST_BIT2")
		)
		(pad "W9" smd circle
			(at -1.999996 5.999988 90)
			(size 0.4064 0.4064)
			(layers "F.Cu" "F.Mask" "F.Paste")
			(net "USB_OC1_REAR_N")
		)
		(pad "W10" smd circle
			(at -1.199896 5.999988 90)
			(size 0.4064 0.4064)
			(layers "F.Cu" "F.Mask" "F.Paste")
			(net "HSC_D_OC_R1")
		)
		(pad "W11" smd circle
			(at -0.40005 5.999988 90)
			(size 0.4064 0.4064)
			(layers "F.Cu" "F.Mask" "F.Paste")
			(net "P3V3_AUX_FPGA_VCCIO2")
		)
		(pad "W12" smd circle
			(at 0.40005 5.999988 90)
			(size 0.4064 0.4064)
			(layers "F.Cu" "F.Mask" "F.Paste")
			(net "GND")
		)
		(pad "W13" smd circle
			(at 1.199896 5.999988 90)
			(size 0.4064 0.4064)
			(layers "F.Cu" "F.Mask" "F.Paste")
			(net "IRQ_PCH_SCI_WHEA_R_N")
		)
		(pad "W14" smd circle
			(at 1.999996 5.999988 90)
			(size 0.4064 0.4064)
			(layers "F.Cu" "F.Mask" "F.Paste")
			(net "FM_BIOS_DEBUG_EN_N")
		)
		(pad "W15" smd circle
			(at 2.800096 5.999988 90)
			(size 0.4064 0.4064)
			(layers "F.Cu" "F.Mask" "F.Paste")
			(net "FM_DIMM_12V_CPS_SX_N")
		)
		(pad "W16" smd circle
			(at 3.599942 5.999988 90)
			(size 0.4064 0.4064)
			(layers "F.Cu" "F.Mask" "F.Paste")
			(net "P3V3_AUX_FPGA_VCCIO2")
		)
		(pad "W17" smd circle
			(at 4.400042 5.999988 90)
			(size 0.4064 0.4064)
			(layers "F.Cu" "F.Mask" "F.Paste")
			(net "CLK_SWB_OE_N")
		)
		(pad "W18" smd circle
			(at 5.199888 5.999988 90)
			(size 0.4064 0.4064)
			(layers "F.Cu" "F.Mask" "F.Paste")
			(net "SWB_HSC_PWRGD_ISO_R")
		)
		(pad "W19" smd circle
			(at 5.999988 5.999988 90)
			(size 0.4064 0.4064)
			(layers "F.Cu" "F.Mask" "F.Paste")
			(net "RST_PERST_SWB_N")
		)
		(pad "W20" smd circle
			(at 6.800088 5.999988 90)
			(size 0.4064 0.4064)
			(layers "F.Cu" "F.Mask" "F.Paste")
			(net "FM_PCH_SPKR_R")
		)
		(pad "W21" smd circle
			(at 7.599934 5.999988 90)
			(size 0.4064 0.4064)
			(layers "F.Cu" "F.Mask" "F.Paste")
			(net "FM_SMB_1_ALERT_GPU_ISO_R_N")
		)
		(pad "W22" smd circle
			(at 8.400034 5.999988 90)
			(size 0.4064 0.4064)
			(layers "F.Cu" "F.Mask" "F.Paste")
			(net "PWRGD_FAIL_CPU0_AB_R")
		)
		(pad "Y1" smd circle
			(at -8.400034 6.800088 90)
			(size 0.4064 0.4064)
			(layers "F.Cu" "F.Mask" "F.Paste")
			(net "H_CPU_RMCA_LVC2_R2_N")
		)
		(pad "Y2" smd circle
			(at -7.599934 6.800088 90)
			(size 0.4064 0.4064)
			(layers "F.Cu" "F.Mask" "F.Paste")
			(net "H_CPU_CATERR_LVC2_R2_N")
		)
		(pad "Y3" smd circle
			(at -6.800088 6.800088 90)
			(size 0.4064 0.4064)
			(layers "F.Cu" "F.Mask" "F.Paste")
			(net "H_CPU1_PROCHOT_LVC1_R_N")
		)
		(pad "Y4" smd circle
			(at -5.999988 6.800088 90)
			(size 0.4064 0.4064)
			(layers "F.Cu" "F.Mask" "F.Paste")
			(net "IRQ_UV_DETECT_R_N")
		)
		(pad "Y5" smd circle
			(at -5.199888 6.800088 90)
			(size 0.4064 0.4064)
			(layers "F.Cu" "F.Mask" "F.Paste")
			(net "PCIE_M2_SSD0_PRSNT_N")
		)
		(pad "Y6" smd circle
			(at -4.400042 6.800088 90)
			(size 0.4064 0.4064)
			(layers "F.Cu" "F.Mask" "F.Paste")
			(net "FM_HBM2_HBM3_VPP_SEL")
		)
		(pad "Y7" smd circle
			(at -3.599942 6.800088 90)
			(size 0.4064 0.4064)
			(layers "F.Cu" "F.Mask" "F.Paste")
			(net "GND")
		)
		(pad "Y8" smd circle
			(at -2.800096 6.800088 90)
			(size 0.4064 0.4064)
			(layers "F.Cu" "F.Mask" "F.Paste")
			(net "FM_ME_AUTHN_FAIL")
		)
		(pad "Y9" smd circle
			(at -1.999996 6.800088 90)
			(size 0.4064 0.4064)
			(layers "F.Cu" "F.Mask" "F.Paste")
			(net "PRSNT_SWB_ISO_R_N")
		)
		(pad "Y10" smd circle
			(at -1.199896 6.800088 90)
			(size 0.4064 0.4064)
			(layers "F.Cu" "F.Mask" "F.Paste")
			(net "FM_PCH_BMC_RST_N")
		)
		(pad "Y11" smd circle
			(at -0.40005 6.800088 90)
			(size 0.4064 0.4064)
			(layers "F.Cu" "F.Mask" "F.Paste")
			(net "GPU_3V3IO_RSVD5_FFU_ISO_R")
		)
		(pad "Y12" smd circle
			(at 0.40005 6.800088 90)
			(size 0.4064 0.4064)
			(layers "F.Cu" "F.Mask" "F.Paste")
			(net "PRSNT_CABLE_GPU_A1_ISO_R_N")
		)
		(pad "Y13" smd circle
			(at 1.199896 6.800088 90)
			(size 0.4064 0.4064)
			(layers "F.Cu" "F.Mask" "F.Paste")
			(net "IRQ_PSU_ALERT_R_N")
		)
		(pad "Y14" smd circle
			(at 1.999996 6.800088 90)
			(size 0.4064 0.4064)
			(layers "F.Cu" "F.Mask" "F.Paste")
			(net "FM_NCSI_OCP_V3_1_R_OE")
		)
		(pad "Y15" smd circle
			(at 2.800096 6.800088 90)
			(size 0.4064 0.4064)
			(layers "F.Cu" "F.Mask" "F.Paste")
			(net "FM_THROTTLE_R_N")
		)
		(pad "Y16" smd circle
			(at 3.599942 6.800088 90)
			(size 0.4064 0.4064)
			(layers "F.Cu" "F.Mask" "F.Paste")
			(net "GND")
		)
		(pad "Y17" smd circle
			(at 4.400042 6.800088 90)
			(size 0.4064 0.4064)
			(layers "F.Cu" "F.Mask" "F.Paste")
			(net "RST_PLTRST_PLD_N")
		)
		(pad "Y18" smd circle
			(at 5.199888 6.800088 90)
			(size 0.4064 0.4064)
			(layers "F.Cu" "F.Mask" "F.Paste")
			(net "CLK_GPU_2_OE_N")
		)
		(pad "Y19" smd circle
			(at 5.999988 6.800088 90)
			(size 0.4064 0.4064)
			(layers "F.Cu" "F.Mask" "F.Paste")
			(net "SWB_HSC_EN_R")
		)
		(pad "Y20" smd circle
			(at 6.800088 6.800088 90)
			(size 0.4064 0.4064)
			(layers "F.Cu" "F.Mask" "F.Paste")
			(net "NC_FPGA_PR30D")
		)
		(pad "Y21" smd circle
			(at 7.599934 6.800088 90)
			(size 0.4064 0.4064)
			(layers "F.Cu" "F.Mask" "F.Paste")
			(net "GPU_FPGA_RST_N")
		)
		(pad "Y22" smd circle
			(at 8.400034 6.800088 90)
			(size 0.4064 0.4064)
			(layers "F.Cu" "F.Mask" "F.Paste")
			(net "HP_LVC3_OCP_V3_1_HSC_PWRGD_PLD_")
		)
		(zone
			(layer "F.Cu")
			(hatch none 0.5)
			(connect_pads
				(clearance 0)
			)
			(min_thickness 0.25)
			(keepout
				(tracks allowed)
				(vias not_allowed)
				(pads allowed)
				(copperpour not_allowed)
				(footprints allowed)
			)
			(placement
				(enabled no)
				(sheetname "")
			)
			(fill
				(thermal_gap 0.5)
				(thermal_bridge_width 0.5)
				(island_removal_mode 0)
			)
			(polygon
				(pts
					(xy 187.971684 -113.22939) (xy 178.7017 -113.22939) (xy 178.7017 -105.6894) (xy 178.4096 -105.6894)
					(xy 178.4096 -113.22939) (xy 170.9928 -113.22939) (xy 170.9928 -113.52149) (xy 178.4096 -113.52149)
					(xy 178.4096 -122.791474) (xy 178.7017 -122.791474) (xy 178.7017 -113.52149) (xy 187.971684 -113.52149)
				)
			)
		)
	)
	(footprint ""
		(layer "F.Cu")
		(at 169.441622 -420.511478)
		(property "Reference" "R3429"
			(at 0 0 0)
			(layer "F.SilkS")
			(hide yes)
			(effects
				(font
					(size 1.27 1.27)
				)
			)
		)
		(property "Value" ""
			(at 0 0 0)
			(layer "F.Fab")
			(effects
				(font
					(size 1.27 1.27)
				)
			)
		)
		(duplicate_pad_numbers_are_jumpers no)
		(fp_line
			(start -0.7874 -0.4064)
			(end 0.7874 -0.4064)
			(stroke
				(width 0.1524)
				(type default)
			)
			(layer "F.SilkS")
		)
		(fp_line
			(start -0.7874 0.4064)
			(end -0.7874 -0.4064)
			(stroke
				(width 0.1524)
				(type default)
			)
			(layer "F.SilkS")
		)
		(fp_line
			(start 0.7874 -0.4064)
			(end 0.7874 0.4064)
			(stroke
				(width 0.1524)
				(type default)
			)
			(layer "F.SilkS")
		)
		(fp_line
			(start 0.7874 0.4064)
			(end -0.7874 0.4064)
			(stroke
				(width 0.1524)
				(type default)
			)
			(layer "F.SilkS")
		)
		(fp_line
			(start -0.67945 -0.305054)
			(end -0.12065 -0.305054)
			(stroke
				(width 0.1)
				(type default)
			)
			(layer "F.Fab")
		)
		(fp_line
			(start -0.67945 0.3048)
			(end -0.67945 -0.305054)
			(stroke
				(width 0.1)
				(type default)
			)
			(layer "F.Fab")
		)
		(fp_line
			(start -0.12065 -0.305054)
			(end -0.12065 -0.2794)
			(stroke
				(width 0.1)
				(type default)
			)
			(layer "F.Fab")
		)
		(fp_line
			(start -0.12065 -0.2794)
			(end 0.12065 -0.2794)
			(stroke
				(width 0.1)
				(type default)
			)
			(layer "F.Fab")
		)
		(fp_line
			(start -0.12065 0.2794)
			(end -0.12065 0.3048)
			(stroke
				(width 0.1)
				(type default)
			)
			(layer "F.Fab")
		)
		(fp_line
			(start -0.12065 0.3048)
			(end -0.67945 0.3048)
			(stroke
				(width 0.1)
				(type default)
			)
			(layer "F.Fab")
		)
		(fp_line
			(start 0.120396 0.2794)
			(end -0.12065 0.2794)
			(stroke
				(width 0.1)
				(type default)
			)
			(layer "F.Fab")
		)
		(fp_line
			(start 0.120396 0.3048)
			(end 0.120396 0.2794)
			(stroke
				(width 0.1)
				(type default)
			)
			(layer "F.Fab")
		)
		(fp_line
			(start 0.12065 -0.3048)
			(end 0.67945 -0.3048)
			(stroke
				(width 0.1)
				(type default)
			)
			(layer "F.Fab")
		)
		(fp_line
			(start 0.12065 -0.2794)
			(end 0.12065 -0.3048)
			(stroke
				(width 0.1)
				(type default)
			)
			(layer "F.Fab")
		)
		(fp_line
			(start 0.67945 -0.3048)
			(end 0.67945 0.3048)
			(stroke
				(width 0.1)
				(type default)
			)
			(layer "F.Fab")
		)
		(fp_line
			(start 0.67945 0.3048)
			(end 0.120396 0.3048)
			(stroke
				(width 0.1)
				(type default)
			)
			(layer "F.Fab")
		)
		(pad "1" smd circle
			(at -0.40005 0)
			(size 0 0)
			(layers "F.Cu" "F.Mask" "F.Paste")
			(net "P3V3_AUX")
		)
		(pad "2" smd circle
			(at 0.40005 0)
			(size 0 0)
			(layers "F.Cu" "F.Mask" "F.Paste")
			(net "GPU_BASE_HMC_READY")
		)
	)
	(footprint ""
		(layer "F.Cu")
		(at 111.332772 -133.663182)
		(property "Reference" "R3583"
			(at 0 0 0)
			(layer "F.SilkS")
			(hide yes)
			(effects
				(font
					(size 1.27 1.27)
				)
			)
		)
		(property "Value" ""
			(at 0 0 0)
			(layer "F.Fab")
			(effects
				(font
					(size 1.27 1.27)
				)
			)
		)
		(duplicate_pad_numbers_are_jumpers no)
		(fp_line
			(start -0.7874 -0.4064)
			(end 0.7874 -0.4064)
			(stroke
				(width 0.1524)
				(type default)
			)
			(layer "F.SilkS")
		)
		(fp_line
			(start -0.7874 0.4064)
			(end -0.7874 -0.4064)
			(stroke
				(width 0.1524)
				(type default)
			)
			(layer "F.SilkS")
		)
		(fp_line
			(start 0.7874 -0.4064)
			(end 0.7874 0.4064)
			(stroke
				(width 0.1524)
				(type default)
			)
			(layer "F.SilkS")
		)
		(fp_line
			(start 0.7874 0.4064)
			(end -0.7874 0.4064)
			(stroke
				(width 0.1524)
				(type default)
			)
			(layer "F.SilkS")
		)
		(fp_line
			(start -0.67945 -0.305054)
			(end -0.12065 -0.305054)
			(stroke
				(width 0.1)
				(type default)
			)
			(layer "F.Fab")
		)
		(fp_line
			(start -0.67945 0.3048)
			(end -0.67945 -0.305054)
			(stroke
				(width 0.1)
				(type default)
			)
			(layer "F.Fab")
		)
		(fp_line
			(start -0.12065 -0.305054)
			(end -0.12065 -0.2794)
			(stroke
				(width 0.1)
				(type default)
			)
			(layer "F.Fab")
		)
		(fp_line
			(start -0.12065 -0.2794)
			(end 0.12065 -0.2794)
			(stroke
				(width 0.1)
				(type default)
			)
			(layer "F.Fab")
		)
		(fp_line
			(start -0.12065 0.2794)
			(end -0.12065 0.3048)
			(stroke
				(width 0.1)
				(type default)
			)
			(layer "F.Fab")
		)
		(fp_line
			(start -0.12065 0.3048)
			(end -0.67945 0.3048)
			(stroke
				(width 0.1)
				(type default)
			)
			(layer "F.Fab")
		)
		(fp_line
			(start 0.120396 0.2794)
			(end -0.12065 0.2794)
			(stroke
				(width 0.1)
				(type default)
			)
			(layer "F.Fab")
		)
		(fp_line
			(start 0.120396 0.3048)
			(end 0.120396 0.2794)
			(stroke
				(width 0.1)
				(type default)
			)
			(layer "F.Fab")
		)
		(fp_line
			(start 0.12065 -0.3048)
			(end 0.67945 -0.3048)
			(stroke
				(width 0.1)
				(type default)
			)
			(layer "F.Fab")
		)
		(fp_line
			(start 0.12065 -0.2794)
			(end 0.12065 -0.3048)
			(stroke
				(width 0.1)
				(type default)
			)
			(layer "F.Fab")
		)
		(fp_line
			(start 0.67945 -0.3048)
			(end 0.67945 0.3048)
			(stroke
				(width 0.1)
				(type default)
			)
			(layer "F.Fab")
		)
		(fp_line
			(start 0.67945 0.3048)
			(end 0.120396 0.3048)
			(stroke
				(width 0.1)
				(type default)
			)
			(layer "F.Fab")
		)
		(pad "1" smd circle
			(at -0.40005 0)
			(size 0 0)
			(layers "F.Cu" "F.Mask" "F.Paste")
			(net "P3V3_AUX")
		)
		(pad "2" smd circle
			(at 0.40005 0)
			(size 0 0)
			(layers "F.Cu" "F.Mask" "F.Paste")
			(net "SMB_IOEXP_3V3AUX_SDA")
		)
	)
	(footprint ""
		(layer "F.Cu")
		(at 148.197824 -49.372012 180)
		(property "Reference" "R3560"
			(at 0 0 180)
			(layer "F.SilkS")
			(hide yes)
			(effects
				(font
					(size 1.27 1.27)
				)
			)
		)
		(property "Value" ""
			(at 0 0 180)
			(layer "F.Fab")
			(effects
				(font
					(size 1.27 1.27)
				)
			)
		)
		(duplicate_pad_numbers_are_jumpers no)
		(fp_line
			(start 0.7874 0.4064)
			(end -0.7874 0.4064)
			(stroke
				(width 0.1524)
				(type default)
			)
			(layer "F.SilkS")
		)
		(fp_line
			(start 0.7874 -0.4064)
			(end 0.7874 0.4064)
			(stroke
				(width 0.1524)
				(type default)
			)
			(layer "F.SilkS")
		)
		(fp_line
			(start -0.7874 0.4064)
			(end -0.7874 -0.4064)
			(stroke
				(width 0.1524)
				(type default)
			)
			(layer "F.SilkS")
		)
		(fp_line
			(start -0.7874 -0.4064)
			(end 0.7874 -0.4064)
			(stroke
				(width 0.1524)
				(type default)
			)
			(layer "F.SilkS")
		)
		(fp_line
			(start 0.67945 0.3048)
			(end 0.120396 0.3048)
			(stroke
				(width 0.1)
				(type default)
			)
			(layer "F.Fab")
		)
		(fp_line
			(start 0.67945 -0.3048)
			(end 0.67945 0.3048)
			(stroke
				(width 0.1)
				(type default)
			)
			(layer "F.Fab")
		)
		(fp_line
			(start 0.12065 -0.2794)
			(end 0.12065 -0.3048)
			(stroke
				(width 0.1)
				(type default)
			)
			(layer "F.Fab")
		)
		(fp_line
			(start 0.12065 -0.3048)
			(end 0.67945 -0.3048)
			(stroke
				(width 0.1)
				(type default)
			)
			(layer "F.Fab")
		)
		(fp_line
			(start 0.120396 0.3048)
			(end 0.120396 0.2794)
			(stroke
				(width 0.1)
				(type default)
			)
			(layer "F.Fab")
		)
		(fp_line
			(start 0.120396 0.2794)
			(end -0.12065 0.2794)
			(stroke
				(width 0.1)
				(type default)
			)
			(layer "F.Fab")
		)
		(fp_line
			(start -0.12065 0.3048)
			(end -0.67945 0.3048)
			(stroke
				(width 0.1)
				(type default)
			)
			(layer "F.Fab")
		)
		(fp_line
			(start -0.12065 0.2794)
			(end -0.12065 0.3048)
			(stroke
				(width 0.1)
				(type default)
			)
			(layer "F.Fab")
		)
		(fp_line
			(start -0.12065 -0.2794)
			(end 0.12065 -0.2794)
			(stroke
				(width 0.1)
				(type default)
			)
			(layer "F.Fab")
		)
		(fp_line
			(start -0.12065 -0.305054)
			(end -0.12065 -0.2794)
			(stroke
				(width 0.1)
				(type default)
			)
			(layer "F.Fab")
		)
		(fp_line
			(start -0.67945 0.3048)
			(end -0.67945 -0.305054)
			(stroke
				(width 0.1)
				(type default)
			)
			(layer "F.Fab")
		)
		(fp_line
			(start -0.67945 -0.305054)
			(end -0.12065 -0.305054)
			(stroke
				(width 0.1)
				(type default)
			)
			(layer "F.Fab")
		)
		(pad "1" smd circle
			(at -0.40005 0 180)
			(size 0 0)
			(layers "F.Cu" "F.Mask" "F.Paste")
			(net "M2_0_P3V3_ADC_ALERT_R")
		)
		(pad "2" smd circle
			(at 0.40005 0 180)
			(size 0 0)
			(layers "F.Cu" "F.Mask" "F.Paste")
			(net "M2_0_P3V3_ADC_ALERT")
		)
	)
	(footprint ""
		(layer "F.Cu")
		(at 140.769594 -408.517344 -90)
		(property "Reference" "C1529"
			(at 0 0 270)
			(layer "F.SilkS")
			(hide yes)
			(effects
				(font
					(size 1.27 1.27)
				)
			)
		)
		(property "Value" ""
			(at 0 0 270)
			(layer "F.Fab")
			(effects
				(font
					(size 1.27 1.27)
				)
			)
		)
		(duplicate_pad_numbers_are_jumpers no)
		(fp_line
			(start -0.299974 0.150114)
			(end -0.299974 -0.150114)
			(stroke
				(width 0.1)
				(type default)
			)
			(layer "F.Fab")
		)
		(fp_line
			(start 0.299974 0.150114)
			(end -0.299974 0.150114)
			(stroke
				(width 0.1)
				(type default)
			)
			(layer "F.Fab")
		)
		(fp_line
			(start -0.299974 -0.150114)
			(end 0.299974 -0.150114)
			(stroke
				(width 0.1)
				(type default)
			)
			(layer "F.Fab")
		)
		(fp_line
			(start 0.299974 -0.150114)
			(end 0.299974 0.150114)
			(stroke
				(width 0.1)
				(type default)
			)
			(layer "F.Fab")
		)
		(pad "1" smd rect
			(at -0.2667 0 270)
			(size 0.3048 0.381)
			(layers "F.Cu" "F.Mask" "F.Paste")
			(net "P5E_CPU1_PE3_TX_C_DP<9>")
		)
		(pad "2" smd rect
			(at 0.2667 0 270)
			(size 0.3048 0.381)
			(layers "F.Cu" "F.Mask" "F.Paste")
			(net "P5E_CPU1_PE3_TX_DP<9>")
		)
	)
	(footprint ""
		(layer "F.Cu")
		(at 317.396622 -56.759348 180)
		(property "Reference" "R612"
			(at 0 0 180)
			(layer "F.SilkS")
			(hide yes)
			(effects
				(font
					(size 1.27 1.27)
				)
			)
		)
		(property "Value" ""
			(at 0 0 180)
			(layer "F.Fab")
			(effects
				(font
					(size 1.27 1.27)
				)
			)
		)
		(duplicate_pad_numbers_are_jumpers no)
		(fp_line
			(start 0.7874 0.4064)
			(end -0.7874 0.4064)
			(stroke
				(width 0.1524)
				(type default)
			)
			(layer "F.SilkS")
		)
		(fp_line
			(start 0.7874 -0.4064)
			(end 0.7874 0.4064)
			(stroke
				(width 0.1524)
				(type default)
			)
			(layer "F.SilkS")
		)
		(fp_line
			(start -0.7874 0.4064)
			(end -0.7874 -0.4064)
			(stroke
				(width 0.1524)
				(type default)
			)
			(layer "F.SilkS")
		)
		(fp_line
			(start -0.7874 -0.4064)
			(end 0.7874 -0.4064)
			(stroke
				(width 0.1524)
				(type default)
			)
			(layer "F.SilkS")
		)
		(fp_line
			(start 0.67945 0.3048)
			(end 0.120396 0.3048)
			(stroke
				(width 0.1)
				(type default)
			)
			(layer "F.Fab")
		)
		(fp_line
			(start 0.67945 -0.3048)
			(end 0.67945 0.3048)
			(stroke
				(width 0.1)
				(type default)
			)
			(layer "F.Fab")
		)
		(fp_line
			(start 0.12065 -0.2794)
			(end 0.12065 -0.3048)
			(stroke
				(width 0.1)
				(type default)
			)
			(layer "F.Fab")
		)
		(fp_line
			(start 0.12065 -0.3048)
			(end 0.67945 -0.3048)
			(stroke
				(width 0.1)
				(type default)
			)
			(layer "F.Fab")
		)
		(fp_line
			(start 0.120396 0.3048)
			(end 0.120396 0.2794)
			(stroke
				(width 0.1)
				(type default)
			)
			(layer "F.Fab")
		)
		(fp_line
			(start 0.120396 0.2794)
			(end -0.12065 0.2794)
			(stroke
				(width 0.1)
				(type default)
			)
			(layer "F.Fab")
		)
		(fp_line
			(start -0.12065 0.3048)
			(end -0.67945 0.3048)
			(stroke
				(width 0.1)
				(type default)
			)
			(layer "F.Fab")
		)
		(fp_line
			(start -0.12065 0.2794)
			(end -0.12065 0.3048)
			(stroke
				(width 0.1)
				(type default)
			)
			(layer "F.Fab")
		)
		(fp_line
			(start -0.12065 -0.2794)
			(end 0.12065 -0.2794)
			(stroke
				(width 0.1)
				(type default)
			)
			(layer "F.Fab")
		)
		(fp_line
			(start -0.12065 -0.305054)
			(end -0.12065 -0.2794)
			(stroke
				(width 0.1)
				(type default)
			)
			(layer "F.Fab")
		)
		(fp_line
			(start -0.67945 0.3048)
			(end -0.67945 -0.305054)
			(stroke
				(width 0.1)
				(type default)
			)
			(layer "F.Fab")
		)
		(fp_line
			(start -0.67945 -0.305054)
			(end -0.12065 -0.305054)
			(stroke
				(width 0.1)
				(type default)
			)
			(layer "F.Fab")
		)
		(pad "1" smd circle
			(at -0.40005 0 180)
			(size 0 0)
			(layers "F.Cu" "F.Mask" "F.Paste")
			(net "FM_PCH_EXTERNALCLKMODE")
		)
		(pad "2" smd circle
			(at 0.40005 0 180)
			(size 0 0)
			(layers "F.Cu" "F.Mask" "F.Paste")
			(net "GND")
		)
	)
	(footprint ""
		(layer "F.Cu")
		(at 52.894738 -337.477608)
		(property "Reference" "PC416"
			(at 0 0 0)
			(layer "F.SilkS")
			(hide yes)
			(effects
				(font
					(size 1.27 1.27)
				)
			)
		)
		(property "Value" ""
			(at 0 0 0)
			(layer "F.Fab")
			(effects
				(font
					(size 1.27 1.27)
				)
			)
		)
		(duplicate_pad_numbers_are_jumpers no)
		(fp_line
			(start 2.750058 0.999998)
			(end -2.750058 0.999998)
			(stroke
				(width 0.1524)
				(type default)
			)
			(layer "F.SilkS")
		)
		(fp_circle
			(center 0 0.999998)
			(end 2.750058 0.999998)
			(stroke
				(width 0.1524)
				(type default)
			)
			(fill no)
			(layer "F.SilkS")
		)
		(fp_poly
			(pts
				(arc
					(start 2.750058 0.999998)
					(mid 0 3.750056)
					(end -2.750058 0.999998)
				)
			)
			(stroke
				(width 0)
				(type default)
			)
			(fill yes)
			(layer "F.SilkS")
		)
		(fp_circle
			(center 0 0.999998)
			(end 2.750058 0.999998)
			(stroke
				(width 0.1)
				(type default)
			)
			(fill no)
			(layer "F.Fab")
		)
		(pad "1" thru_hole rect
			(at 0 0)
			(size 1.5748 1.5748)
			(drill 1.0668)
			(layers "*.Cu" "*.Mask")
			(remove_unused_layers no)
			(net "PVCCFA_EHV_FIVRA_CPU1")
			(clearance 0)
			(padstack
				(mode front_inner_back)
				(layer "Inner"
					(shape circle)
					(size 1.5748 1.5748)
					(clearance 0)
				)
				(layer "B.Cu"
					(shape rect)
					(size 1.5748 1.5748)
					(clearance 0)
				)
			)
		)
		(pad "2" thru_hole circle
			(at 0 1.999996)
			(size 1.5748 1.5748)
			(drill 1.0668)
			(layers "*.Cu" "*.Mask")
			(remove_unused_layers no)
			(net "GND")
			(clearance 0)
		)
	)
	(footprint ""
		(layer "F.Cu")
		(at 378.099574 0.383794 180)
		(property "Reference" "J65"
			(at -4.451096 -1.394206 90)
			(unlocked yes)
			(layer "F.SilkS")
			(effects
				(font
					(size 0.7874 0.5842)
					(thickness 0.1524)
				)
				(justify left)
			)
		)
		(property "Value" ""
			(at 0 0 180)
			(layer "F.Fab")
			(effects
				(font
					(size 1.27 1.27)
				)
			)
		)
		(duplicate_pad_numbers_are_jumpers no)
		(fp_line
			(start 1.2192 2.1082)
			(end -1.2192 2.1082)
			(stroke
				(width 0.1524)
				(type default)
			)
			(layer "F.SilkS")
		)
		(fp_line
			(start 1.2192 -2.1082)
			(end 1.2192 2.1082)
			(stroke
				(width 0.1524)
				(type default)
			)
			(layer "F.SilkS")
		)
		(fp_line
			(start -1.2192 2.1082)
			(end -1.2192 -2.1082)
			(stroke
				(width 0.1524)
				(type default)
			)
			(layer "F.SilkS")
		)
		(fp_line
			(start -1.2192 -2.1082)
			(end 1.2192 -2.1082)
			(stroke
				(width 0.1524)
				(type default)
			)
			(layer "F.SilkS")
		)
		(pad "" np_thru_hole circle
			(at -2.8829 -1.27 90)
			(size 1.0414 1.0414)
			(drill 1.0414)
			(layers "*.Cu" "*.Mask")
			(clearance 0.381)
			(thermal_gap 0.381)
		)
		(pad "" np_thru_hole circle
			(at -2.8829 1.27 90)
			(size 1.0414 1.0414)
			(drill 1.0414)
			(layers "*.Cu" "*.Mask")
			(clearance 0.381)
			(thermal_gap 0.381)
		)
		(pad "" np_thru_hole circle
			(at 3.4671 -1.27 90)
			(size 1.0414 1.0414)
			(drill 1.0414)
			(layers "*.Cu" "*.Mask")
			(clearance 0.381)
			(thermal_gap 0.381)
		)
		(pad "" np_thru_hole circle
			(at 3.4671 1.27 90)
			(size 1.0414 1.0414)
			(drill 1.0414)
			(layers "*.Cu" "*.Mask")
			(clearance 0.381)
			(thermal_gap 0.381)
		)
		(pad "1" smd rect
			(at 0.8255 -0.249936 90)
			(size 0.3048 0.508)
			(layers "F.Cu" "F.Mask" "F.Paste")
			(net "DELTA_L_85_5INCH_IN1_DP")
		)
		(pad "2" smd rect
			(at 0.8255 0.249936 90)
			(size 0.3048 0.508)
			(layers "F.Cu" "F.Mask" "F.Paste")
			(net "DELTA_L_85_5INCH_IN1_DN")
		)
		(pad "3" smd circle
			(at 0 0 180)
			(size 0 0)
			(layers "F.Cu" "F.Mask" "F.Paste")
			(net "DELTA_L_GND_1")
		)
		(zone
			(layer "F.Cu")
			(hatch none 0.5)
			(connect_pads
				(clearance 0)
			)
			(min_thickness 0.25)
			(keepout
				(tracks not_allowed)
				(vias allowed)
				(pads allowed)
				(copperpour not_allowed)
				(footprints allowed)
			)
			(placement
				(enabled no)
				(sheetname "")
			)
			(fill
				(thermal_gap 0.5)
				(thermal_bridge_width 0.5)
				(island_removal_mode 0)
			)
			(polygon
				(pts
					(xy 376.981974 0.932434) (xy 376.981974 0.83693) (xy 377.578874 0.83693) (xy 377.578874 0.43053)
					(xy 376.981974 0.43053) (xy 376.981974 0.337058) (xy 377.578874 0.337058) (xy 377.578874 -0.069342)
					(xy 376.981974 -0.069342) (xy 376.981974 -0.164846) (xy 377.680474 -0.164846) (xy 377.680474 0.932434)
				)
			)
		)
		(zone
			(layers "F.Cu" "B.Cu" "In1.Cu" "In2.Cu" "In3.Cu" "In4.Cu" "In5.Cu" "In6.Cu"
				"In7.Cu" "In8.Cu" "In9.Cu" "In10.Cu" "In11.Cu" "In12.Cu" "In13.Cu" "In14.Cu"
				"In15.Cu" "In16.Cu"
			)
			(hatch none 0.5)
			(connect_pads
				(clearance 0)
			)
			(min_thickness 0.25)
			(keepout
				(tracks not_allowed)
				(vias allowed)
				(pads allowed)
				(copperpour not_allowed)
				(footprints allowed)
			)
			(placement
				(enabled no)
				(sheetname "")
			)
			(fill
				(thermal_gap 0.5)
				(thermal_bridge_width 0.5)
				(island_removal_mode 0)
			)
			(polygon
				(pts
					(arc
						(start 375.559574 -0.886206)
						(mid 373.705374 -0.886206)
						(end 375.559574 -0.886206)
					)
				)
			)
		)
		(zone
			(layers "F.Cu" "B.Cu" "In1.Cu" "In2.Cu" "In3.Cu" "In4.Cu" "In5.Cu" "In6.Cu"
				"In7.Cu" "In8.Cu" "In9.Cu" "In10.Cu" "In11.Cu" "In12.Cu" "In13.Cu" "In14.Cu"
				"In15.Cu" "In16.Cu"
			)
			(hatch none 0.5)
			(connect_pads
				(clearance 0)
			)
			(min_thickness 0.25)
			(keepout
				(tracks not_allowed)
				(vias allowed)
				(pads allowed)
				(copperpour not_allowed)
				(footprints allowed)
			)
			(placement
				(enabled no)
				(sheetname "")
			)
			(fill
				(thermal_gap 0.5)
				(thermal_bridge_width 0.5)
				(island_removal_mode 0)
			)
			(polygon
				(pts
					(arc
						(start 375.559574 1.653794)
						(mid 373.705374 1.653794)
						(end 375.559574 1.653794)
					)
				)
			)
		)
		(zone
			(layers "F.Cu" "B.Cu" "In1.Cu" "In2.Cu" "In3.Cu" "In4.Cu" "In5.Cu" "In6.Cu"
				"In7.Cu" "In8.Cu" "In9.Cu" "In10.Cu" "In11.Cu" "In12.Cu" "In13.Cu" "In14.Cu"
				"In15.Cu" "In16.Cu"
			)
			(hatch none 0.5)
			(connect_pads
				(clearance 0)
			)
			(min_thickness 0.25)
			(keepout
				(tracks not_allowed)
				(vias allowed)
				(pads allowed)
				(copperpour not_allowed)
				(footprints allowed)
			)
			(placement
				(enabled no)
				(sheetname "")
			)
			(fill
				(thermal_gap 0.5)
				(thermal_bridge_width 0.5)
				(island_removal_mode 0)
			)
			(polygon
				(pts
					(arc
						(start 381.909574 -0.886206)
						(mid 380.055374 -0.886206)
						(end 381.909574 -0.886206)
					)
				)
			)
		)
		(zone
			(layers "F.Cu" "B.Cu" "In1.Cu" "In2.Cu" "In3.Cu" "In4.Cu" "In5.Cu" "In6.Cu"
				"In7.Cu" "In8.Cu" "In9.Cu" "In10.Cu" "In11.Cu" "In12.Cu" "In13.Cu" "In14.Cu"
				"In15.Cu" "In16.Cu"
			)
			(hatch none 0.5)
			(connect_pads
				(clearance 0)
			)
			(min_thickness 0.25)
			(keepout
				(tracks not_allowed)
				(vias allowed)
				(pads allowed)
				(copperpour not_allowed)
				(footprints allowed)
			)
			(placement
				(enabled no)
				(sheetname "")
			)
			(fill
				(thermal_gap 0.5)
				(thermal_bridge_width 0.5)
				(island_removal_mode 0)
			)
			(polygon
				(pts
					(arc
						(start 381.909574 1.653794)
						(mid 380.055374 1.653794)
						(end 381.909574 1.653794)
					)
				)
			)
		)
	)
	(footprint ""
		(layer "F.Cu")
		(at 47.678594 -353.35718 -90)
		(property "Reference" "PC1243_P1_2"
			(at 0 0 270)
			(layer "F.SilkS")
			(hide yes)
			(effects
				(font
					(size 1.27 1.27)
				)
			)
		)
		(property "Value" ""
			(at 0 0 270)
			(layer "F.Fab")
			(effects
				(font
					(size 1.27 1.27)
				)
			)
		)
		(duplicate_pad_numbers_are_jumpers no)
		(fp_line
			(start -0.7874 0.4064)
			(end -0.7874 -0.4064)
			(stroke
				(width 0.1524)
				(type default)
			)
			(layer "F.SilkS")
		)
		(fp_line
			(start 0.7874 0.4064)
			(end -0.7874 0.4064)
			(stroke
				(width 0.1524)
				(type default)
			)
			(layer "F.SilkS")
		)
		(fp_line
			(start -0.7874 -0.4064)
			(end 0.7874 -0.4064)
			(stroke
				(width 0.1524)
				(type default)
			)
			(layer "F.SilkS")
		)
		(fp_line
			(start 0.7874 -0.4064)
			(end 0.7874 0.4064)
			(stroke
				(width 0.1524)
				(type default)
			)
			(layer "F.SilkS")
		)
		(fp_line
			(start -0.67945 0.3048)
			(end -0.67945 -0.305054)
			(stroke
				(width 0.1)
				(type default)
			)
			(layer "F.Fab")
		)
		(fp_line
			(start -0.12065 0.3048)
			(end -0.67945 0.3048)
			(stroke
				(width 0.1)
				(type default)
			)
			(layer "F.Fab")
		)
		(fp_line
			(start 0.120396 0.3048)
			(end 0.120396 0.2794)
			(stroke
				(width 0.1)
				(type default)
			)
			(layer "F.Fab")
		)
		(fp_line
			(start 0.67945 0.3048)
			(end 0.120396 0.3048)
			(stroke
				(width 0.1)
				(type default)
			)
			(layer "F.Fab")
		)
		(fp_line
			(start -0.12065 0.2794)
			(end -0.12065 0.3048)
			(stroke
				(width 0.1)
				(type default)
			)
			(layer "F.Fab")
		)
		(fp_line
			(start 0.120396 0.2794)
			(end -0.12065 0.2794)
			(stroke
				(width 0.1)
				(type default)
			)
			(layer "F.Fab")
		)
		(fp_line
			(start -0.12065 -0.2794)
			(end 0.12065 -0.2794)
			(stroke
				(width 0.1)
				(type default)
			)
			(layer "F.Fab")
		)
		(fp_line
			(start 0.12065 -0.2794)
			(end 0.12065 -0.3048)
			(stroke
				(width 0.1)
				(type default)
			)
			(layer "F.Fab")
		)
		(fp_line
			(start 0.12065 -0.3048)
			(end 0.67945 -0.3048)
			(stroke
				(width 0.1)
				(type default)
			)
			(layer "F.Fab")
		)
		(fp_line
			(start 0.67945 -0.3048)
			(end 0.67945 0.3048)
			(stroke
				(width 0.1)
				(type default)
			)
			(layer "F.Fab")
		)
		(fp_line
			(start -0.67945 -0.305054)
			(end -0.12065 -0.305054)
			(stroke
				(width 0.1)
				(type default)
			)
			(layer "F.Fab")
		)
		(fp_line
			(start -0.12065 -0.305054)
			(end -0.12065 -0.2794)
			(stroke
				(width 0.1)
				(type default)
			)
			(layer "F.Fab")
		)
		(pad "1" smd circle
			(at -0.40005 0 270)
			(size 0 0)
			(layers "F.Cu" "F.Mask" "F.Paste")
			(net "PVCCFA_EHV_FIVRA_CPU1_PVCC2")
		)
		(pad "2" smd circle
			(at 0.40005 0 270)
			(size 0 0)
			(layers "F.Cu" "F.Mask" "F.Paste")
			(net "GND")
		)
	)
	(footprint ""
		(layer "F.Cu")
		(at 115.06708 -106.238548 -90)
		(property "Reference" "R4044"
			(at 0 0 270)
			(layer "F.SilkS")
			(hide yes)
			(effects
				(font
					(size 1.27 1.27)
				)
			)
		)
		(property "Value" ""
			(at 0 0 270)
			(layer "F.Fab")
			(effects
				(font
					(size 1.27 1.27)
				)
			)
		)
		(duplicate_pad_numbers_are_jumpers no)
		(fp_line
			(start -0.7874 0.4064)
			(end -0.7874 -0.4064)
			(stroke
				(width 0.1524)
				(type default)
			)
			(layer "F.SilkS")
		)
		(fp_line
			(start 0.7874 0.4064)
			(end -0.7874 0.4064)
			(stroke
				(width 0.1524)
				(type default)
			)
			(layer "F.SilkS")
		)
		(fp_line
			(start -0.7874 -0.4064)
			(end 0.7874 -0.4064)
			(stroke
				(width 0.1524)
				(type default)
			)
			(layer "F.SilkS")
		)
		(fp_line
			(start 0.7874 -0.4064)
			(end 0.7874 0.4064)
			(stroke
				(width 0.1524)
				(type default)
			)
			(layer "F.SilkS")
		)
		(fp_line
			(start -0.67945 0.3048)
			(end -0.67945 -0.305054)
			(stroke
				(width 0.1)
				(type default)
			)
			(layer "F.Fab")
		)
		(fp_line
			(start -0.12065 0.3048)
			(end -0.67945 0.3048)
			(stroke
				(width 0.1)
				(type default)
			)
			(layer "F.Fab")
		)
		(fp_line
			(start 0.120396 0.3048)
			(end 0.120396 0.2794)
			(stroke
				(width 0.1)
				(type default)
			)
			(layer "F.Fab")
		)
		(fp_line
			(start 0.67945 0.3048)
			(end 0.120396 0.3048)
			(stroke
				(width 0.1)
				(type default)
			)
			(layer "F.Fab")
		)
		(fp_line
			(start -0.12065 0.2794)
			(end -0.12065 0.3048)
			(stroke
				(width 0.1)
				(type default)
			)
			(layer "F.Fab")
		)
		(fp_line
			(start 0.120396 0.2794)
			(end -0.12065 0.2794)
			(stroke
				(width 0.1)
				(type default)
			)
			(layer "F.Fab")
		)
		(fp_line
			(start -0.12065 -0.2794)
			(end 0.12065 -0.2794)
			(stroke
				(width 0.1)
				(type default)
			)
			(layer "F.Fab")
		)
		(fp_line
			(start 0.12065 -0.2794)
			(end 0.12065 -0.3048)
			(stroke
				(width 0.1)
				(type default)
			)
			(layer "F.Fab")
		)
		(fp_line
			(start 0.12065 -0.3048)
			(end 0.67945 -0.3048)
			(stroke
				(width 0.1)
				(type default)
			)
			(layer "F.Fab")
		)
		(fp_line
			(start 0.67945 -0.3048)
			(end 0.67945 0.3048)
			(stroke
				(width 0.1)
				(type default)
			)
			(layer "F.Fab")
		)
		(fp_line
			(start -0.67945 -0.305054)
			(end -0.12065 -0.305054)
			(stroke
				(width 0.1)
				(type default)
			)
			(layer "F.Fab")
		)
		(fp_line
			(start -0.12065 -0.305054)
			(end -0.12065 -0.2794)
			(stroke
				(width 0.1)
				(type default)
			)
			(layer "F.Fab")
		)
		(pad "1" smd circle
			(at -0.40005 0 270)
			(size 0 0)
			(layers "F.Cu" "F.Mask" "F.Paste")
			(net "RST_CPU0_DRAM_EF_PLD_LVT3_R_N")
		)
		(pad "2" smd circle
			(at 0.40005 0 270)
			(size 0 0)
			(layers "F.Cu" "F.Mask" "F.Paste")
			(net "RST_CPU0_DRAM_EF_PLD_LVT3_N")
		)
	)
	(footprint ""
		(layer "F.Cu")
		(at 446.03035 -374.891554)
		(property "Reference" "C1042"
			(at 0 0 0)
			(layer "F.SilkS")
			(hide yes)
			(effects
				(font
					(size 1.27 1.27)
				)
			)
		)
		(property "Value" ""
			(at 0 0 0)
			(layer "F.Fab")
			(effects
				(font
					(size 1.27 1.27)
				)
			)
		)
		(duplicate_pad_numbers_are_jumpers no)
		(fp_line
			(start -0.7874 -0.4064)
			(end 0.7874 -0.4064)
			(stroke
				(width 0.1524)
				(type default)
			)
			(layer "F.SilkS")
		)
		(fp_line
			(start -0.7874 0.4064)
			(end -0.7874 -0.4064)
			(stroke
				(width 0.1524)
				(type default)
			)
			(layer "F.SilkS")
		)
		(fp_line
			(start 0.7874 -0.4064)
			(end 0.7874 0.4064)
			(stroke
				(width 0.1524)
				(type default)
			)
			(layer "F.SilkS")
		)
		(fp_line
			(start 0.7874 0.4064)
			(end -0.7874 0.4064)
			(stroke
				(width 0.1524)
				(type default)
			)
			(layer "F.SilkS")
		)
		(fp_line
			(start -0.67945 -0.305054)
			(end -0.12065 -0.305054)
			(stroke
				(width 0.1)
				(type default)
			)
			(layer "F.Fab")
		)
		(fp_line
			(start -0.67945 0.3048)
			(end -0.67945 -0.305054)
			(stroke
				(width 0.1)
				(type default)
			)
			(layer "F.Fab")
		)
		(fp_line
			(start -0.12065 -0.305054)
			(end -0.12065 -0.2794)
			(stroke
				(width 0.1)
				(type default)
			)
			(layer "F.Fab")
		)
		(fp_line
			(start -0.12065 -0.2794)
			(end 0.12065 -0.2794)
			(stroke
				(width 0.1)
				(type default)
			)
			(layer "F.Fab")
		)
		(fp_line
			(start -0.12065 0.2794)
			(end -0.12065 0.3048)
			(stroke
				(width 0.1)
				(type default)
			)
			(layer "F.Fab")
		)
		(fp_line
			(start -0.12065 0.3048)
			(end -0.67945 0.3048)
			(stroke
				(width 0.1)
				(type default)
			)
			(layer "F.Fab")
		)
		(fp_line
			(start 0.120396 0.2794)
			(end -0.12065 0.2794)
			(stroke
				(width 0.1)
				(type default)
			)
			(layer "F.Fab")
		)
		(fp_line
			(start 0.120396 0.3048)
			(end 0.120396 0.2794)
			(stroke
				(width 0.1)
				(type default)
			)
			(layer "F.Fab")
		)
		(fp_line
			(start 0.12065 -0.3048)
			(end 0.67945 -0.3048)
			(stroke
				(width 0.1)
				(type default)
			)
			(layer "F.Fab")
		)
		(fp_line
			(start 0.12065 -0.2794)
			(end 0.12065 -0.3048)
			(stroke
				(width 0.1)
				(type default)
			)
			(layer "F.Fab")
		)
		(fp_line
			(start 0.67945 -0.3048)
			(end 0.67945 0.3048)
			(stroke
				(width 0.1)
				(type default)
			)
			(layer "F.Fab")
		)
		(fp_line
			(start 0.67945 0.3048)
			(end 0.120396 0.3048)
			(stroke
				(width 0.1)
				(type default)
			)
			(layer "F.Fab")
		)
		(pad "1" smd circle
			(at -0.40005 0)
			(size 0 0)
			(layers "F.Cu" "F.Mask" "F.Paste")
			(net "P5V_AUX")
		)
		(pad "2" smd circle
			(at 0.40005 0)
			(size 0 0)
			(layers "F.Cu" "F.Mask" "F.Paste")
			(net "GND")
		)
	)
	(footprint ""
		(layer "F.Cu")
		(at 329.240388 5.463794 180)
		(property "Reference" "J84"
			(at -4.415282 -1.140206 90)
			(unlocked yes)
			(layer "F.SilkS")
			(effects
				(font
					(size 0.7874 0.5842)
					(thickness 0.1524)
				)
				(justify left)
			)
		)
		(property "Value" ""
			(at 0 0 180)
			(layer "F.Fab")
			(effects
				(font
					(size 1.27 1.27)
				)
			)
		)
		(duplicate_pad_numbers_are_jumpers no)
		(fp_line
			(start 1.2192 2.1082)
			(end -1.2192 2.1082)
			(stroke
				(width 0.1524)
				(type default)
			)
			(layer "F.SilkS")
		)
		(fp_line
			(start 1.2192 -2.1082)
			(end 1.2192 2.1082)
			(stroke
				(width 0.1524)
				(type default)
			)
			(layer "F.SilkS")
		)
		(fp_line
			(start -1.2192 2.1082)
			(end -1.2192 -2.1082)
			(stroke
				(width 0.1524)
				(type default)
			)
			(layer "F.SilkS")
		)
		(fp_line
			(start -1.2192 -2.1082)
			(end 1.2192 -2.1082)
			(stroke
				(width 0.1524)
				(type default)
			)
			(layer "F.SilkS")
		)
		(pad "" np_thru_hole circle
			(at -2.8829 -1.27 90)
			(size 1.0414 1.0414)
			(drill 1.0414)
			(layers "*.Cu" "*.Mask")
			(clearance 0.381)
			(thermal_gap 0.381)
		)
		(pad "" np_thru_hole circle
			(at -2.8829 1.27 90)
			(size 1.0414 1.0414)
			(drill 1.0414)
			(layers "*.Cu" "*.Mask")
			(clearance 0.381)
			(thermal_gap 0.381)
		)
		(pad "" np_thru_hole circle
			(at 3.4671 -1.27 90)
			(size 1.0414 1.0414)
			(drill 1.0414)
			(layers "*.Cu" "*.Mask")
			(clearance 0.381)
			(thermal_gap 0.381)
		)
		(pad "" np_thru_hole circle
			(at 3.4671 1.27 90)
			(size 1.0414 1.0414)
			(drill 1.0414)
			(layers "*.Cu" "*.Mask")
			(clearance 0.381)
			(thermal_gap 0.381)
		)
		(pad "1" smd rect
			(at 0.8255 -0.249936 90)
			(size 0.3048 0.508)
			(layers "F.Cu" "F.Mask" "F.Paste")
			(net "DELTA_L_85_10INCH_IN2_DN")
		)
		(pad "2" smd rect
			(at 0.8255 0.249936 90)
			(size 0.3048 0.508)
			(layers "F.Cu" "F.Mask" "F.Paste")
			(net "DELTA_L_85_10INCH_IN2_DP")
		)
		(pad "3" smd circle
			(at 0 0 180)
			(size 0 0)
			(layers "F.Cu" "F.Mask" "F.Paste")
			(net "DELTA_L_GND_1")
		)
		(zone
			(layer "F.Cu")
			(hatch none 0.5)
			(connect_pads
				(clearance 0)
			)
			(min_thickness 0.25)
			(keepout
				(tracks not_allowed)
				(vias allowed)
				(pads allowed)
				(copperpour not_allowed)
				(footprints allowed)
			)
			(placement
				(enabled no)
				(sheetname "")
			)
			(fill
				(thermal_gap 0.5)
				(thermal_bridge_width 0.5)
				(island_removal_mode 0)
			)
			(polygon
				(pts
					(xy 328.122788 6.012434) (xy 328.122788 5.91693) (xy 328.719688 5.91693) (xy 328.719688 5.51053)
					(xy 328.122788 5.51053) (xy 328.122788 5.417058) (xy 328.719688 5.417058) (xy 328.719688 5.010658)
					(xy 328.122788 5.010658) (xy 328.122788 4.915154) (xy 328.821288 4.915154) (xy 328.821288 6.012434)
				)
			)
		)
		(zone
			(layers "F.Cu" "B.Cu" "In1.Cu" "In2.Cu" "In3.Cu" "In4.Cu" "In5.Cu" "In6.Cu"
				"In7.Cu" "In8.Cu" "In9.Cu" "In10.Cu" "In11.Cu" "In12.Cu" "In13.Cu" "In14.Cu"
				"In15.Cu" "In16.Cu"
			)
			(hatch none 0.5)
			(connect_pads
				(clearance 0)
			)
			(min_thickness 0.25)
			(keepout
				(tracks not_allowed)
				(vias allowed)
				(pads allowed)
				(copperpour not_allowed)
				(footprints allowed)
			)
			(placement
				(enabled no)
				(sheetname "")
			)
			(fill
				(thermal_gap 0.5)
				(thermal_bridge_width 0.5)
				(island_removal_mode 0)
			)
			(polygon
				(pts
					(arc
						(start 326.700388 4.193794)
						(mid 324.846188 4.193794)
						(end 326.700388 4.193794)
					)
				)
			)
		)
		(zone
			(layers "F.Cu" "B.Cu" "In1.Cu" "In2.Cu" "In3.Cu" "In4.Cu" "In5.Cu" "In6.Cu"
				"In7.Cu" "In8.Cu" "In9.Cu" "In10.Cu" "In11.Cu" "In12.Cu" "In13.Cu" "In14.Cu"
				"In15.Cu" "In16.Cu"
			)
			(hatch none 0.5)
			(connect_pads
				(clearance 0)
			)
			(min_thickness 0.25)
			(keepout
				(tracks not_allowed)
				(vias allowed)
				(pads allowed)
				(copperpour not_allowed)
				(footprints allowed)
			)
			(placement
				(enabled no)
				(sheetname "")
			)
			(fill
				(thermal_gap 0.5)
				(thermal_bridge_width 0.5)
				(island_removal_mode 0)
			)
			(polygon
				(pts
					(arc
						(start 326.700388 6.733794)
						(mid 324.846188 6.733794)
						(end 326.700388 6.733794)
					)
				)
			)
		)
		(zone
			(layers "F.Cu" "B.Cu" "In1.Cu" "In2.Cu" "In3.Cu" "In4.Cu" "In5.Cu" "In6.Cu"
				"In7.Cu" "In8.Cu" "In9.Cu" "In10.Cu" "In11.Cu" "In12.Cu" "In13.Cu" "In14.Cu"
				"In15.Cu" "In16.Cu"
			)
			(hatch none 0.5)
			(connect_pads
				(clearance 0)
			)
			(min_thickness 0.25)
			(keepout
				(tracks not_allowed)
				(vias allowed)
				(pads allowed)
				(copperpour not_allowed)
				(footprints allowed)
			)
			(placement
				(enabled no)
				(sheetname "")
			)
			(fill
				(thermal_gap 0.5)
				(thermal_bridge_width 0.5)
				(island_removal_mode 0)
			)
			(polygon
				(pts
					(arc
						(start 333.050388 4.193794)
						(mid 331.196188 4.193794)
						(end 333.050388 4.193794)
					)
				)
			)
		)
		(zone
			(layers "F.Cu" "B.Cu" "In1.Cu" "In2.Cu" "In3.Cu" "In4.Cu" "In5.Cu" "In6.Cu"
				"In7.Cu" "In8.Cu" "In9.Cu" "In10.Cu" "In11.Cu" "In12.Cu" "In13.Cu" "In14.Cu"
				"In15.Cu" "In16.Cu"
			)
			(hatch none 0.5)
			(connect_pads
				(clearance 0)
			)
			(min_thickness 0.25)
			(keepout
				(tracks not_allowed)
				(vias allowed)
				(pads allowed)
				(copperpour not_allowed)
				(footprints allowed)
			)
			(placement
				(enabled no)
				(sheetname "")
			)
			(fill
				(thermal_gap 0.5)
				(thermal_bridge_width 0.5)
				(island_removal_mode 0)
			)
			(polygon
				(pts
					(arc
						(start 333.050388 6.733794)
						(mid 331.196188 6.733794)
						(end 333.050388 6.733794)
					)
				)
			)
		)
	)
	(footprint ""
		(layer "F.Cu")
		(at 329.124818 -23.803864 -90)
		(property "Reference" "R1871"
			(at 0 0 270)
			(layer "F.SilkS")
			(hide yes)
			(effects
				(font
					(size 1.27 1.27)
				)
			)
		)
		(property "Value" ""
			(at 0 0 270)
			(layer "F.Fab")
			(effects
				(font
					(size 1.27 1.27)
				)
			)
		)
		(duplicate_pad_numbers_are_jumpers no)
		(fp_line
			(start -0.7874 0.4064)
			(end -0.7874 -0.4064)
			(stroke
				(width 0.1524)
				(type default)
			)
			(layer "F.SilkS")
		)
		(fp_line
			(start 0.7874 0.4064)
			(end -0.7874 0.4064)
			(stroke
				(width 0.1524)
				(type default)
			)
			(layer "F.SilkS")
		)
		(fp_line
			(start -0.7874 -0.4064)
			(end 0.7874 -0.4064)
			(stroke
				(width 0.1524)
				(type default)
			)
			(layer "F.SilkS")
		)
		(fp_line
			(start 0.7874 -0.4064)
			(end 0.7874 0.4064)
			(stroke
				(width 0.1524)
				(type default)
			)
			(layer "F.SilkS")
		)
		(fp_line
			(start -0.67945 0.3048)
			(end -0.67945 -0.305054)
			(stroke
				(width 0.1)
				(type default)
			)
			(layer "F.Fab")
		)
		(fp_line
			(start -0.12065 0.3048)
			(end -0.67945 0.3048)
			(stroke
				(width 0.1)
				(type default)
			)
			(layer "F.Fab")
		)
		(fp_line
			(start 0.120396 0.3048)
			(end 0.120396 0.2794)
			(stroke
				(width 0.1)
				(type default)
			)
			(layer "F.Fab")
		)
		(fp_line
			(start 0.67945 0.3048)
			(end 0.120396 0.3048)
			(stroke
				(width 0.1)
				(type default)
			)
			(layer "F.Fab")
		)
		(fp_line
			(start -0.12065 0.2794)
			(end -0.12065 0.3048)
			(stroke
				(width 0.1)
				(type default)
			)
			(layer "F.Fab")
		)
		(fp_line
			(start 0.120396 0.2794)
			(end -0.12065 0.2794)
			(stroke
				(width 0.1)
				(type default)
			)
			(layer "F.Fab")
		)
		(fp_line
			(start -0.12065 -0.2794)
			(end 0.12065 -0.2794)
			(stroke
				(width 0.1)
				(type default)
			)
			(layer "F.Fab")
		)
		(fp_line
			(start 0.12065 -0.2794)
			(end 0.12065 -0.3048)
			(stroke
				(width 0.1)
				(type default)
			)
			(layer "F.Fab")
		)
		(fp_line
			(start 0.12065 -0.3048)
			(end 0.67945 -0.3048)
			(stroke
				(width 0.1)
				(type default)
			)
			(layer "F.Fab")
		)
		(fp_line
			(start 0.67945 -0.3048)
			(end 0.67945 0.3048)
			(stroke
				(width 0.1)
				(type default)
			)
			(layer "F.Fab")
		)
		(fp_line
			(start -0.67945 -0.305054)
			(end -0.12065 -0.305054)
			(stroke
				(width 0.1)
				(type default)
			)
			(layer "F.Fab")
		)
		(fp_line
			(start -0.12065 -0.305054)
			(end -0.12065 -0.2794)
			(stroke
				(width 0.1)
				(type default)
			)
			(layer "F.Fab")
		)
		(pad "1" smd circle
			(at -0.40005 0 270)
			(size 0 0)
			(layers "F.Cu" "F.Mask" "F.Paste")
			(net "ESPI_LAD0_DATA_IO0")
		)
		(pad "2" smd circle
			(at 0.40005 0 270)
			(size 0 0)
			(layers "F.Cu" "F.Mask" "F.Paste")
			(net "ESPI_LPC_LAD0_IO0")
		)
	)
	(footprint ""
		(layer "F.Cu")
		(at 68.644008 -171.77004 90)
		(property "Reference" "PC384"
			(at 0 0 90)
			(layer "F.SilkS")
			(hide yes)
			(effects
				(font
					(size 1.27 1.27)
				)
			)
		)
		(property "Value" ""
			(at 0 0 90)
			(layer "F.Fab")
			(effects
				(font
					(size 1.27 1.27)
				)
			)
		)
		(duplicate_pad_numbers_are_jumpers no)
		(fp_line
			(start 2.750058 0.999998)
			(end -2.750058 0.999998)
			(stroke
				(width 0.1524)
				(type default)
			)
			(layer "F.SilkS")
		)
		(fp_circle
			(center 0 0.999998)
			(end 0 3.750056)
			(stroke
				(width 0.1524)
				(type default)
			)
			(fill no)
			(layer "F.SilkS")
		)
		(fp_poly
			(pts
				(arc
					(start 2.750058 0.999998)
					(mid 0 3.750056)
					(end -2.750058 0.999998)
				)
			)
			(stroke
				(width 0)
				(type default)
			)
			(fill yes)
			(layer "F.SilkS")
		)
		(fp_circle
			(center 0 0.999998)
			(end 0 3.750056)
			(stroke
				(width 0.1)
				(type default)
			)
			(fill no)
			(layer "F.Fab")
		)
		(pad "1" thru_hole rect
			(at 0 0 90)
			(size 1.5748 1.5748)
			(drill 1.0668)
			(layers "*.Cu" "*.Mask")
			(remove_unused_layers no)
			(net "PVCCD_HV_CPU1")
			(clearance 0)
			(padstack
				(mode front_inner_back)
				(layer "Inner"
					(shape circle)
					(size 1.5748 1.5748)
					(clearance 0)
				)
				(layer "B.Cu"
					(shape rect)
					(size 1.5748 1.5748)
					(clearance 0)
				)
			)
		)
		(pad "2" thru_hole circle
			(at 0 1.999996 90)
			(size 1.5748 1.5748)
			(drill 1.0668)
			(layers "*.Cu" "*.Mask")
			(remove_unused_layers no)
			(net "GND")
			(clearance 0)
		)
	)
	(footprint ""
		(layer "F.Cu")
		(at 145.59534 -36.761928)
		(property "Reference" "U243"
			(at -1.016 -1.80213 0)
			(unlocked yes)
			(layer "F.SilkS")
			(effects
				(font
					(size 0.7874 0.5842)
					(thickness 0.1524)
				)
			)
		)
		(property "Value" ""
			(at 0 0 0)
			(layer "F.Fab")
			(effects
				(font
					(size 1.27 1.27)
				)
			)
		)
		(duplicate_pad_numbers_are_jumpers no)
		(fp_line
			(start -1.7272 1.1176)
			(end -1.7272 -1.1176)
			(stroke
				(width 0.1524)
				(type default)
			)
			(layer "F.SilkS")
		)
		(fp_line
			(start -0.254 -1.1176)
			(end -1.7272 -1.1176)
			(stroke
				(width 0.1524)
				(type default)
			)
			(layer "F.SilkS")
		)
		(fp_line
			(start 0 -0.7366)
			(end -0.254 -1.1176)
			(stroke
				(width 0.1524)
				(type default)
			)
			(layer "F.SilkS")
		)
		(fp_line
			(start 0.254 -1.1176)
			(end 0 -0.7366)
			(stroke
				(width 0.1524)
				(type default)
			)
			(layer "F.SilkS")
		)
		(fp_line
			(start 1.7272 -1.1176)
			(end 0.254 -1.1176)
			(stroke
				(width 0.1524)
				(type default)
			)
			(layer "F.SilkS")
		)
		(fp_line
			(start 1.7272 -1.1176)
			(end 1.7272 1.1176)
			(stroke
				(width 0.1524)
				(type default)
			)
			(layer "F.SilkS")
		)
		(fp_line
			(start 1.7272 1.1176)
			(end -1.7272 1.1176)
			(stroke
				(width 0.1524)
				(type default)
			)
			(layer "F.SilkS")
		)
		(fp_poly
			(pts
				(xy -2.7178 -0.268986) (xy -2.7178 -1.030986) (xy -1.9558 -0.649986)
			)
			(stroke
				(width 0)
				(type default)
			)
			(fill yes)
			(layer "F.SilkS")
		)
		(fp_line
			(start -1.5748 -1.1176)
			(end -1.5748 1.1176)
			(stroke
				(width 0.1)
				(type default)
			)
			(layer "F.Fab")
		)
		(fp_line
			(start -1.5748 1.1176)
			(end 1.5748 1.1176)
			(stroke
				(width 0.1)
				(type default)
			)
			(layer "F.Fab")
		)
		(fp_line
			(start 1.5748 -1.1176)
			(end -1.5748 -1.1176)
			(stroke
				(width 0.1)
				(type default)
			)
			(layer "F.Fab")
		)
		(fp_line
			(start 1.5748 1.1176)
			(end 1.5748 -1.1176)
			(stroke
				(width 0.1)
				(type default)
			)
			(layer "F.Fab")
		)
		(fp_poly
			(pts
				(xy -1.9558 -0.649986) (xy -2.7178 -0.268986) (xy -2.7178 -1.030986)
			)
			(stroke
				(width 0)
				(type default)
			)
			(fill yes)
			(layer "F.Fab")
		)
		(pad "1" smd rect
			(at -0.999998 -0.649986 270)
			(size 0.3556 1.1176)
			(layers "F.Cu" "F.Mask" "F.Paste")
			(net "OCP_SFF_NOT_PRSNT_RBT_ARB_IN")
		)
		(pad "2" smd rect
			(at -0.999998 0 270)
			(size 0.3556 1.1176)
			(layers "F.Cu" "F.Mask" "F.Paste")
			(net "GND")
		)
		(pad "3" smd rect
			(at -0.999998 0.649986 270)
			(size 0.3556 1.1176)
			(layers "F.Cu" "F.Mask" "F.Paste")
			(net "OCP_SFF_RBT_ARB_OUT")
		)
		(pad "4" smd rect
			(at 0.999998 0.649986 270)
			(size 0.3556 1.1176)
			(layers "F.Cu" "F.Mask" "F.Paste")
			(net "OCP_SFF_RBT_ARB_IN_MUX2")
		)
		(pad "5" smd rect
			(at 0.999998 0 270)
			(size 0.3556 1.1176)
			(layers "F.Cu" "F.Mask" "F.Paste")
			(net "P3V3_AUX")
		)
		(pad "6" smd rect
			(at 0.999998 -0.649986 270)
			(size 0.3556 1.1176)
			(layers "F.Cu" "F.Mask" "F.Paste")
			(net "OCP_SFF_PRSNT_ALL_R1_N")
		)
	)
	(footprint ""
		(layer "F.Cu")
		(at 29.332428 -99.586034 180)
		(property "Reference" "R3864"
			(at 0 0 180)
			(layer "F.SilkS")
			(hide yes)
			(effects
				(font
					(size 1.27 1.27)
				)
			)
		)
		(property "Value" ""
			(at 0 0 180)
			(layer "F.Fab")
			(effects
				(font
					(size 1.27 1.27)
				)
			)
		)
		(duplicate_pad_numbers_are_jumpers no)
		(fp_line
			(start 0.7874 0.4064)
			(end -0.7874 0.4064)
			(stroke
				(width 0.1524)
				(type default)
			)
			(layer "F.SilkS")
		)
		(fp_line
			(start 0.7874 -0.4064)
			(end 0.7874 0.4064)
			(stroke
				(width 0.1524)
				(type default)
			)
			(layer "F.SilkS")
		)
		(fp_line
			(start -0.7874 0.4064)
			(end -0.7874 -0.4064)
			(stroke
				(width 0.1524)
				(type default)
			)
			(layer "F.SilkS")
		)
		(fp_line
			(start -0.7874 -0.4064)
			(end 0.7874 -0.4064)
			(stroke
				(width 0.1524)
				(type default)
			)
			(layer "F.SilkS")
		)
		(fp_line
			(start 0.67945 0.3048)
			(end 0.120396 0.3048)
			(stroke
				(width 0.1)
				(type default)
			)
			(layer "F.Fab")
		)
		(fp_line
			(start 0.67945 -0.3048)
			(end 0.67945 0.3048)
			(stroke
				(width 0.1)
				(type default)
			)
			(layer "F.Fab")
		)
		(fp_line
			(start 0.12065 -0.2794)
			(end 0.12065 -0.3048)
			(stroke
				(width 0.1)
				(type default)
			)
			(layer "F.Fab")
		)
		(fp_line
			(start 0.12065 -0.3048)
			(end 0.67945 -0.3048)
			(stroke
				(width 0.1)
				(type default)
			)
			(layer "F.Fab")
		)
		(fp_line
			(start 0.120396 0.3048)
			(end 0.120396 0.2794)
			(stroke
				(width 0.1)
				(type default)
			)
			(layer "F.Fab")
		)
		(fp_line
			(start 0.120396 0.2794)
			(end -0.12065 0.2794)
			(stroke
				(width 0.1)
				(type default)
			)
			(layer "F.Fab")
		)
		(fp_line
			(start -0.12065 0.3048)
			(end -0.67945 0.3048)
			(stroke
				(width 0.1)
				(type default)
			)
			(layer "F.Fab")
		)
		(fp_line
			(start -0.12065 0.2794)
			(end -0.12065 0.3048)
			(stroke
				(width 0.1)
				(type default)
			)
			(layer "F.Fab")
		)
		(fp_line
			(start -0.12065 -0.2794)
			(end 0.12065 -0.2794)
			(stroke
				(width 0.1)
				(type default)
			)
			(layer "F.Fab")
		)
		(fp_line
			(start -0.12065 -0.305054)
			(end -0.12065 -0.2794)
			(stroke
				(width 0.1)
				(type default)
			)
			(layer "F.Fab")
		)
		(fp_line
			(start -0.67945 0.3048)
			(end -0.67945 -0.305054)
			(stroke
				(width 0.1)
				(type default)
			)
			(layer "F.Fab")
		)
		(fp_line
			(start -0.67945 -0.305054)
			(end -0.12065 -0.305054)
			(stroke
				(width 0.1)
				(type default)
			)
			(layer "F.Fab")
		)
		(pad "1" smd rect
			(at -0.40005 0)
			(size 0.4572 0.508)
			(layers "F.Cu" "F.Mask" "F.Paste")
			(net "P12V_OCP_SFF_ISENSE_MPS_MAM")
		)
		(pad "2" smd rect
			(at 0.40005 0)
			(size 0.4572 0.508)
			(layers "F.Cu" "F.Mask" "F.Paste")
			(net "P12V_OCP_SFF_ISENSE_MAM")
		)
	)
	(footprint ""
		(layer "F.Cu")
		(at 73.806558 -408.517344 -90)
		(property "Reference" "C692"
			(at 0 0 270)
			(layer "F.SilkS")
			(hide yes)
			(effects
				(font
					(size 1.27 1.27)
				)
			)
		)
		(property "Value" ""
			(at 0 0 270)
			(layer "F.Fab")
			(effects
				(font
					(size 1.27 1.27)
				)
			)
		)
		(duplicate_pad_numbers_are_jumpers no)
		(fp_line
			(start -0.299974 0.150114)
			(end -0.299974 -0.150114)
			(stroke
				(width 0.1)
				(type default)
			)
			(layer "F.Fab")
		)
		(fp_line
			(start 0.299974 0.150114)
			(end -0.299974 0.150114)
			(stroke
				(width 0.1)
				(type default)
			)
			(layer "F.Fab")
		)
		(fp_line
			(start -0.299974 -0.150114)
			(end 0.299974 -0.150114)
			(stroke
				(width 0.1)
				(type default)
			)
			(layer "F.Fab")
		)
		(fp_line
			(start 0.299974 -0.150114)
			(end 0.299974 0.150114)
			(stroke
				(width 0.1)
				(type default)
			)
			(layer "F.Fab")
		)
		(pad "1" smd rect
			(at -0.2667 0 270)
			(size 0.3048 0.381)
			(layers "F.Cu" "F.Mask" "F.Paste")
			(net "P5E_CPU1_PE4_TX_C_DN<8>")
		)
		(pad "2" smd rect
			(at 0.2667 0 270)
			(size 0.3048 0.381)
			(layers "F.Cu" "F.Mask" "F.Paste")
			(net "P5E_CPU1_PE4_TX_DN<8>")
		)
	)
	(footprint ""
		(layer "F.Cu")
		(at 264.52449 -41.492678)
		(property "Reference" "JP4"
			(at -1.4097 -2.009648 0)
			(unlocked yes)
			(layer "F.SilkS")
			(effects
				(font
					(size 0.7874 0.5842)
					(thickness 0.1524)
				)
				(justify left)
			)
		)
		(property "Value" ""
			(at 0 0 0)
			(layer "F.Fab")
			(effects
				(font
					(size 1.27 1.27)
				)
			)
		)
		(duplicate_pad_numbers_are_jumpers no)
		(fp_line
			(start -1.249934 -1.320038)
			(end 1.249934 -1.320038)
			(stroke
				(width 0.1524)
				(type default)
			)
			(layer "F.SilkS")
		)
		(fp_line
			(start -1.249934 6.400038)
			(end -1.249934 -1.320038)
			(stroke
				(width 0.1524)
				(type default)
			)
			(layer "F.SilkS")
		)
		(fp_line
			(start 1.249934 -1.320038)
			(end 1.249934 6.400038)
			(stroke
				(width 0.1524)
				(type default)
			)
			(layer "F.SilkS")
		)
		(fp_line
			(start 1.249934 6.400038)
			(end -1.249934 6.400038)
			(stroke
				(width 0.1524)
				(type default)
			)
			(layer "F.SilkS")
		)
		(fp_poly
			(pts
				(xy -1.452372 0) (xy -2.5654 0.556514) (xy -2.5654 -0.556514)
			)
			(stroke
				(width 0)
				(type default)
			)
			(fill yes)
			(layer "F.SilkS")
		)
		(fp_line
			(start -1.249934 -1.320038)
			(end 1.249934 -1.320038)
			(stroke
				(width 0.1)
				(type default)
			)
			(layer "F.Fab")
		)
		(fp_line
			(start -1.249934 6.400038)
			(end -1.249934 -1.320038)
			(stroke
				(width 0.1)
				(type default)
			)
			(layer "F.Fab")
		)
		(fp_line
			(start 1.249934 -1.320038)
			(end 1.249934 6.400038)
			(stroke
				(width 0.1)
				(type default)
			)
			(layer "F.Fab")
		)
		(fp_line
			(start 1.249934 6.400038)
			(end -1.249934 6.400038)
			(stroke
				(width 0.1)
				(type default)
			)
			(layer "F.Fab")
		)
		(fp_poly
			(pts
				(xy -2.5654 -0.556514) (xy -1.452372 0) (xy -2.5654 0.556514)
			)
			(stroke
				(width 0)
				(type default)
			)
			(fill yes)
			(layer "F.Fab")
		)
		(fp_text user "3"
			(at -1.778 5.13207 0)
			(unlocked yes)
			(layer "F.SilkS")
			(effects
				(font
					(size 0.7874 0.5842)
					(thickness 0.1524)
				)
			)
		)
		(fp_text user "3"
			(at -1.1557 5.18287 0)
			(unlocked yes)
			(layer "B.SilkS")
			(effects
				(font
					(size 0.7874 0.5842)
					(thickness 0.1524)
				)
				(justify mirror)
			)
		)
		(fp_text user "1"
			(at -1.143 0.02667 0)
			(unlocked yes)
			(layer "B.SilkS")
			(effects
				(font
					(size 0.7874 0.5842)
					(thickness 0.1524)
				)
				(justify mirror)
			)
		)
		(fp_text user "3"
			(at -1.1557 5.18287 0)
			(unlocked yes)
			(layer "B.Fab")
			(effects
				(font
					(size 0.7874 0.5842)
					(thickness 0.1524)
				)
				(justify mirror)
			)
		)
		(fp_text user "1"
			(at -1.143 0.02667 0)
			(unlocked yes)
			(layer "B.Fab")
			(effects
				(font
					(size 0.7874 0.5842)
					(thickness 0.1524)
				)
				(justify mirror)
			)
		)
		(fp_text user "3"
			(at -1.778 5.13207 0)
			(unlocked yes)
			(layer "F.Fab")
			(effects
				(font
					(size 0.7874 0.5842)
					(thickness 0.1524)
				)
			)
		)
		(pad "1" thru_hole rect
			(at 0 0)
			(size 1.5494 1.5494)
			(drill 1.0414)
			(layers "*.Cu" "*.Mask")
			(remove_unused_layers no)
			(net "SMB_SML0_3V3AUX_PCH_SCL")
			(clearance 0)
			(padstack
				(mode front_inner_back)
				(layer "Inner"
					(shape circle)
					(size 1.5494 1.5494)
					(clearance 0)
				)
				(layer "B.Cu"
					(shape rect)
					(size 1.5494 1.5494)
					(clearance 0)
				)
			)
		)
		(pad "2" thru_hole circle
			(at 0 2.54)
			(size 1.5494 1.5494)
			(drill 1.0414)
			(layers "*.Cu" "*.Mask")
			(remove_unused_layers no)
			(net "GND")
			(clearance 0)
		)
		(pad "3" thru_hole circle
			(at 0 5.08)
			(size 1.5494 1.5494)
			(drill 1.0414)
			(layers "*.Cu" "*.Mask")
			(remove_unused_layers no)
			(net "SMB_SML0_3V3AUX_PCH_SDA")
			(clearance 0)
		)
	)
	(footprint ""
		(layer "F.Cu")
		(at 218.011502 -71.126858 180)
		(property "Reference" "PR3969"
			(at 0 0 180)
			(layer "F.SilkS")
			(hide yes)
			(effects
				(font
					(size 1.27 1.27)
				)
			)
		)
		(property "Value" ""
			(at 0 0 180)
			(layer "F.Fab")
			(effects
				(font
					(size 1.27 1.27)
				)
			)
		)
		(duplicate_pad_numbers_are_jumpers no)
		(fp_line
			(start 0.7874 0.4064)
			(end -0.7874 0.4064)
			(stroke
				(width 0.1524)
				(type default)
			)
			(layer "F.SilkS")
		)
		(fp_line
			(start 0.7874 -0.4064)
			(end 0.7874 0.4064)
			(stroke
				(width 0.1524)
				(type default)
			)
			(layer "F.SilkS")
		)
		(fp_line
			(start -0.7874 0.4064)
			(end -0.7874 -0.4064)
			(stroke
				(width 0.1524)
				(type default)
			)
			(layer "F.SilkS")
		)
		(fp_line
			(start -0.7874 -0.4064)
			(end 0.7874 -0.4064)
			(stroke
				(width 0.1524)
				(type default)
			)
			(layer "F.SilkS")
		)
		(fp_line
			(start 0.67945 0.3048)
			(end 0.120396 0.3048)
			(stroke
				(width 0.1)
				(type default)
			)
			(layer "F.Fab")
		)
		(fp_line
			(start 0.67945 -0.3048)
			(end 0.67945 0.3048)
			(stroke
				(width 0.1)
				(type default)
			)
			(layer "F.Fab")
		)
		(fp_line
			(start 0.12065 -0.2794)
			(end 0.12065 -0.3048)
			(stroke
				(width 0.1)
				(type default)
			)
			(layer "F.Fab")
		)
		(fp_line
			(start 0.12065 -0.3048)
			(end 0.67945 -0.3048)
			(stroke
				(width 0.1)
				(type default)
			)
			(layer "F.Fab")
		)
		(fp_line
			(start 0.120396 0.3048)
			(end 0.120396 0.2794)
			(stroke
				(width 0.1)
				(type default)
			)
			(layer "F.Fab")
		)
		(fp_line
			(start 0.120396 0.2794)
			(end -0.12065 0.2794)
			(stroke
				(width 0.1)
				(type default)
			)
			(layer "F.Fab")
		)
		(fp_line
			(start -0.12065 0.3048)
			(end -0.67945 0.3048)
			(stroke
				(width 0.1)
				(type default)
			)
			(layer "F.Fab")
		)
		(fp_line
			(start -0.12065 0.2794)
			(end -0.12065 0.3048)
			(stroke
				(width 0.1)
				(type default)
			)
			(layer "F.Fab")
		)
		(fp_line
			(start -0.12065 -0.2794)
			(end 0.12065 -0.2794)
			(stroke
				(width 0.1)
				(type default)
			)
			(layer "F.Fab")
		)
		(fp_line
			(start -0.12065 -0.305054)
			(end -0.12065 -0.2794)
			(stroke
				(width 0.1)
				(type default)
			)
			(layer "F.Fab")
		)
		(fp_line
			(start -0.67945 0.3048)
			(end -0.67945 -0.305054)
			(stroke
				(width 0.1)
				(type default)
			)
			(layer "F.Fab")
		)
		(fp_line
			(start -0.67945 -0.305054)
			(end -0.12065 -0.305054)
			(stroke
				(width 0.1)
				(type default)
			)
			(layer "F.Fab")
		)
		(pad "1" smd circle
			(at -0.40005 0 180)
			(size 0 0)
			(layers "F.Cu" "F.Mask" "F.Paste")
			(net "P3V3_E1S_CB_0")
		)
		(pad "2" smd circle
			(at 0.40005 0 180)
			(size 0 0)
			(layers "F.Cu" "F.Mask" "F.Paste")
			(net "GND")
		)
	)
	(footprint ""
		(layer "F.Cu")
		(at 174.635922 -25.846532 180)
		(property "Reference" "PC2239"
			(at 0 0 180)
			(layer "F.SilkS")
			(hide yes)
			(effects
				(font
					(size 1.27 1.27)
				)
			)
		)
		(property "Value" ""
			(at 0 0 180)
			(layer "F.Fab")
			(effects
				(font
					(size 1.27 1.27)
				)
			)
		)
		(duplicate_pad_numbers_are_jumpers no)
		(fp_line
			(start 1.2954 0.5842)
			(end -1.2954 0.5842)
			(stroke
				(width 0.1524)
				(type default)
			)
			(layer "F.SilkS")
		)
		(fp_line
			(start 1.2954 -0.5842)
			(end 1.2954 0.5842)
			(stroke
				(width 0.1524)
				(type default)
			)
			(layer "F.SilkS")
		)
		(fp_line
			(start 0 -0.5842)
			(end 0 0.5842)
			(stroke
				(width 0.1524)
				(type default)
			)
			(layer "F.SilkS")
		)
		(fp_line
			(start -1.2954 0.5842)
			(end -1.2954 -0.5842)
			(stroke
				(width 0.1524)
				(type default)
			)
			(layer "F.SilkS")
		)
		(fp_line
			(start -1.2954 -0.5842)
			(end 1.2954 -0.5842)
			(stroke
				(width 0.1524)
				(type default)
			)
			(layer "F.SilkS")
		)
		(fp_line
			(start 1.1938 0.4064)
			(end 0.8636 0.4064)
			(stroke
				(width 0.1)
				(type default)
			)
			(layer "F.Fab")
		)
		(fp_line
			(start 1.1938 -0.4064)
			(end 1.1938 0.4064)
			(stroke
				(width 0.1)
				(type default)
			)
			(layer "F.Fab")
		)
		(fp_line
			(start 0.8636 0.4572)
			(end -0.8636 0.4572)
			(stroke
				(width 0.1)
				(type default)
			)
			(layer "F.Fab")
		)
		(fp_line
			(start 0.8636 0.4064)
			(end 0.8636 0.4572)
			(stroke
				(width 0.1)
				(type default)
			)
			(layer "F.Fab")
		)
		(fp_line
			(start 0.8636 -0.4064)
			(end 1.1938 -0.4064)
			(stroke
				(width 0.1)
				(type default)
			)
			(layer "F.Fab")
		)
		(fp_line
			(start 0.8636 -0.4572)
			(end 0.8636 -0.4064)
			(stroke
				(width 0.1)
				(type default)
			)
			(layer "F.Fab")
		)
		(fp_line
			(start -0.8636 0.4572)
			(end -0.8636 0.4064)
			(stroke
				(width 0.1)
				(type default)
			)
			(layer "F.Fab")
		)
		(fp_line
			(start -0.8636 0.4064)
			(end -1.1938 0.4064)
			(stroke
				(width 0.1)
				(type default)
			)
			(layer "F.Fab")
		)
		(fp_line
			(start -0.8636 -0.4064)
			(end -0.8636 -0.4572)
			(stroke
				(width 0.1)
				(type default)
			)
			(layer "F.Fab")
		)
		(fp_line
			(start -0.8636 -0.4572)
			(end 0.8636 -0.4572)
			(stroke
				(width 0.1)
				(type default)
			)
			(layer "F.Fab")
		)
		(fp_line
			(start -1.1938 0.4064)
			(end -1.1938 -0.4064)
			(stroke
				(width 0.1)
				(type default)
			)
			(layer "F.Fab")
		)
		(fp_line
			(start -1.1938 -0.4064)
			(end -0.8636 -0.4064)
			(stroke
				(width 0.1)
				(type default)
			)
			(layer "F.Fab")
		)
		(pad "1" smd rect
			(at -0.7366 0 90)
			(size 0.7112 0.8128)
			(layers "F.Cu" "F.Mask" "F.Paste")
			(net "P12V_SCM_AVIN_PD")
		)
		(pad "2" smd rect
			(at 0.7366 0 90)
			(size 0.7112 0.8128)
			(layers "F.Cu" "F.Mask" "F.Paste")
			(net "GND")
		)
	)
	(footprint ""
		(layer "F.Cu")
		(at 241.28857 -111.212376 180)
		(property "Reference" "R1018"
			(at 0 0 180)
			(layer "F.SilkS")
			(hide yes)
			(effects
				(font
					(size 1.27 1.27)
				)
			)
		)
		(property "Value" ""
			(at 0 0 180)
			(layer "F.Fab")
			(effects
				(font
					(size 1.27 1.27)
				)
			)
		)
		(duplicate_pad_numbers_are_jumpers no)
		(fp_line
			(start 0.7874 0.4064)
			(end -0.7874 0.4064)
			(stroke
				(width 0.1524)
				(type default)
			)
			(layer "F.SilkS")
		)
		(fp_line
			(start 0.7874 -0.4064)
			(end 0.7874 0.4064)
			(stroke
				(width 0.1524)
				(type default)
			)
			(layer "F.SilkS")
		)
		(fp_line
			(start -0.7874 0.4064)
			(end -0.7874 -0.4064)
			(stroke
				(width 0.1524)
				(type default)
			)
			(layer "F.SilkS")
		)
		(fp_line
			(start -0.7874 -0.4064)
			(end 0.7874 -0.4064)
			(stroke
				(width 0.1524)
				(type default)
			)
			(layer "F.SilkS")
		)
		(fp_line
			(start 0.67945 0.3048)
			(end 0.120396 0.3048)
			(stroke
				(width 0.1)
				(type default)
			)
			(layer "F.Fab")
		)
		(fp_line
			(start 0.67945 -0.3048)
			(end 0.67945 0.3048)
			(stroke
				(width 0.1)
				(type default)
			)
			(layer "F.Fab")
		)
		(fp_line
			(start 0.12065 -0.2794)
			(end 0.12065 -0.3048)
			(stroke
				(width 0.1)
				(type default)
			)
			(layer "F.Fab")
		)
		(fp_line
			(start 0.12065 -0.3048)
			(end 0.67945 -0.3048)
			(stroke
				(width 0.1)
				(type default)
			)
			(layer "F.Fab")
		)
		(fp_line
			(start 0.120396 0.3048)
			(end 0.120396 0.2794)
			(stroke
				(width 0.1)
				(type default)
			)
			(layer "F.Fab")
		)
		(fp_line
			(start 0.120396 0.2794)
			(end -0.12065 0.2794)
			(stroke
				(width 0.1)
				(type default)
			)
			(layer "F.Fab")
		)
		(fp_line
			(start -0.12065 0.3048)
			(end -0.67945 0.3048)
			(stroke
				(width 0.1)
				(type default)
			)
			(layer "F.Fab")
		)
		(fp_line
			(start -0.12065 0.2794)
			(end -0.12065 0.3048)
			(stroke
				(width 0.1)
				(type default)
			)
			(layer "F.Fab")
		)
		(fp_line
			(start -0.12065 -0.2794)
			(end 0.12065 -0.2794)
			(stroke
				(width 0.1)
				(type default)
			)
			(layer "F.Fab")
		)
		(fp_line
			(start -0.12065 -0.305054)
			(end -0.12065 -0.2794)
			(stroke
				(width 0.1)
				(type default)
			)
			(layer "F.Fab")
		)
		(fp_line
			(start -0.67945 0.3048)
			(end -0.67945 -0.305054)
			(stroke
				(width 0.1)
				(type default)
			)
			(layer "F.Fab")
		)
		(fp_line
			(start -0.67945 -0.305054)
			(end -0.12065 -0.305054)
			(stroke
				(width 0.1)
				(type default)
			)
			(layer "F.Fab")
		)
		(pad "1" smd circle
			(at -0.40005 0 180)
			(size 0 0)
			(layers "F.Cu" "F.Mask" "F.Paste")
			(net "CLK_25M_CK440_CPU1_DN")
		)
		(pad "2" smd circle
			(at 0.40005 0 180)
			(size 0 0)
			(layers "F.Cu" "F.Mask" "F.Paste")
			(net "CLK_25M_CK440_CPU1_R_DN")
		)
	)
	(footprint ""
		(layer "F.Cu")
		(at 333.702152 -16.2052 90)
		(property "Reference" "R1749"
			(at 0 0 90)
			(layer "F.SilkS")
			(hide yes)
			(effects
				(font
					(size 1.27 1.27)
				)
			)
		)
		(property "Value" ""
			(at 0 0 90)
			(layer "F.Fab")
			(effects
				(font
					(size 1.27 1.27)
				)
			)
		)
		(duplicate_pad_numbers_are_jumpers no)
		(fp_line
			(start 0.7874 -0.4064)
			(end 0.7874 0.4064)
			(stroke
				(width 0.1524)
				(type default)
			)
			(layer "F.SilkS")
		)
		(fp_line
			(start -0.7874 -0.4064)
			(end 0.7874 -0.4064)
			(stroke
				(width 0.1524)
				(type default)
			)
			(layer "F.SilkS")
		)
		(fp_line
			(start 0.7874 0.4064)
			(end -0.7874 0.4064)
			(stroke
				(width 0.1524)
				(type default)
			)
			(layer "F.SilkS")
		)
		(fp_line
			(start -0.7874 0.4064)
			(end -0.7874 -0.4064)
			(stroke
				(width 0.1524)
				(type default)
			)
			(layer "F.SilkS")
		)
		(fp_line
			(start -0.12065 -0.305054)
			(end -0.12065 -0.2794)
			(stroke
				(width 0.1)
				(type default)
			)
			(layer "F.Fab")
		)
		(fp_line
			(start -0.67945 -0.305054)
			(end -0.12065 -0.305054)
			(stroke
				(width 0.1)
				(type default)
			)
			(layer "F.Fab")
		)
		(fp_line
			(start 0.67945 -0.3048)
			(end 0.67945 0.3048)
			(stroke
				(width 0.1)
				(type default)
			)
			(layer "F.Fab")
		)
		(fp_line
			(start 0.12065 -0.3048)
			(end 0.67945 -0.3048)
			(stroke
				(width 0.1)
				(type default)
			)
			(layer "F.Fab")
		)
		(fp_line
			(start 0.12065 -0.2794)
			(end 0.12065 -0.3048)
			(stroke
				(width 0.1)
				(type default)
			)
			(layer "F.Fab")
		)
		(fp_line
			(start -0.12065 -0.2794)
			(end 0.12065 -0.2794)
			(stroke
				(width 0.1)
				(type default)
			)
			(layer "F.Fab")
		)
		(fp_line
			(start 0.120396 0.2794)
			(end -0.12065 0.2794)
			(stroke
				(width 0.1)
				(type default)
			)
			(layer "F.Fab")
		)
		(fp_line
			(start -0.12065 0.2794)
			(end -0.12065 0.3048)
			(stroke
				(width 0.1)
				(type default)
			)
			(layer "F.Fab")
		)
		(fp_line
			(start 0.67945 0.3048)
			(end 0.120396 0.3048)
			(stroke
				(width 0.1)
				(type default)
			)
			(layer "F.Fab")
		)
		(fp_line
			(start 0.120396 0.3048)
			(end 0.120396 0.2794)
			(stroke
				(width 0.1)
				(type default)
			)
			(layer "F.Fab")
		)
		(fp_line
			(start -0.12065 0.3048)
			(end -0.67945 0.3048)
			(stroke
				(width 0.1)
				(type default)
			)
			(layer "F.Fab")
		)
		(fp_line
			(start -0.67945 0.3048)
			(end -0.67945 -0.305054)
			(stroke
				(width 0.1)
				(type default)
			)
			(layer "F.Fab")
		)
		(pad "1" smd circle
			(at -0.40005 0 90)
			(size 0 0)
			(layers "F.Cu" "F.Mask" "F.Paste")
			(net "FM_ESPI_PLD_R1_EN")
		)
		(pad "2" smd circle
			(at 0.40005 0 90)
			(size 0 0)
			(layers "F.Cu" "F.Mask" "F.Paste")
			(net "GND")
		)
	)
	(footprint ""
		(layer "F.Cu")
		(at 44.169584 -109.444282)
		(property "Reference" "R1791"
			(at 0 0 0)
			(layer "F.SilkS")
			(hide yes)
			(effects
				(font
					(size 1.27 1.27)
				)
			)
		)
		(property "Value" ""
			(at 0 0 0)
			(layer "F.Fab")
			(effects
				(font
					(size 1.27 1.27)
				)
			)
		)
		(duplicate_pad_numbers_are_jumpers no)
		(fp_line
			(start -0.7874 -0.4064)
			(end 0.7874 -0.4064)
			(stroke
				(width 0.1524)
				(type default)
			)
			(layer "F.SilkS")
		)
		(fp_line
			(start -0.7874 0.4064)
			(end -0.7874 -0.4064)
			(stroke
				(width 0.1524)
				(type default)
			)
			(layer "F.SilkS")
		)
		(fp_line
			(start 0.7874 -0.4064)
			(end 0.7874 0.4064)
			(stroke
				(width 0.1524)
				(type default)
			)
			(layer "F.SilkS")
		)
		(fp_line
			(start 0.7874 0.4064)
			(end -0.7874 0.4064)
			(stroke
				(width 0.1524)
				(type default)
			)
			(layer "F.SilkS")
		)
		(fp_line
			(start -0.67945 -0.305054)
			(end -0.12065 -0.305054)
			(stroke
				(width 0.1)
				(type default)
			)
			(layer "F.Fab")
		)
		(fp_line
			(start -0.67945 0.3048)
			(end -0.67945 -0.305054)
			(stroke
				(width 0.1)
				(type default)
			)
			(layer "F.Fab")
		)
		(fp_line
			(start -0.12065 -0.305054)
			(end -0.12065 -0.2794)
			(stroke
				(width 0.1)
				(type default)
			)
			(layer "F.Fab")
		)
		(fp_line
			(start -0.12065 -0.2794)
			(end 0.12065 -0.2794)
			(stroke
				(width 0.1)
				(type default)
			)
			(layer "F.Fab")
		)
		(fp_line
			(start -0.12065 0.2794)
			(end -0.12065 0.3048)
			(stroke
				(width 0.1)
				(type default)
			)
			(layer "F.Fab")
		)
		(fp_line
			(start -0.12065 0.3048)
			(end -0.67945 0.3048)
			(stroke
				(width 0.1)
				(type default)
			)
			(layer "F.Fab")
		)
		(fp_line
			(start 0.120396 0.2794)
			(end -0.12065 0.2794)
			(stroke
				(width 0.1)
				(type default)
			)
			(layer "F.Fab")
		)
		(fp_line
			(start 0.120396 0.3048)
			(end 0.120396 0.2794)
			(stroke
				(width 0.1)
				(type default)
			)
			(layer "F.Fab")
		)
		(fp_line
			(start 0.12065 -0.3048)
			(end 0.67945 -0.3048)
			(stroke
				(width 0.1)
				(type default)
			)
			(layer "F.Fab")
		)
		(fp_line
			(start 0.12065 -0.2794)
			(end 0.12065 -0.3048)
			(stroke
				(width 0.1)
				(type default)
			)
			(layer "F.Fab")
		)
		(fp_line
			(start 0.67945 -0.3048)
			(end 0.67945 0.3048)
			(stroke
				(width 0.1)
				(type default)
			)
			(layer "F.Fab")
		)
		(fp_line
			(start 0.67945 0.3048)
			(end 0.120396 0.3048)
			(stroke
				(width 0.1)
				(type default)
			)
			(layer "F.Fab")
		)
		(pad "1" smd circle
			(at -0.40005 0)
			(size 0 0)
			(layers "F.Cu" "F.Mask" "F.Paste")
			(net "P5V_ADC")
		)
		(pad "2" smd circle
			(at 0.40005 0)
			(size 0 0)
			(layers "F.Cu" "F.Mask" "F.Paste")
			(net "GND")
		)
	)
	(footprint ""
		(layer "F.Cu")
		(at 119.508016 -256.6543 -90)
		(property "Reference" "C253"
			(at 0 0 270)
			(layer "F.SilkS")
			(hide yes)
			(effects
				(font
					(size 1.27 1.27)
				)
			)
		)
		(property "Value" ""
			(at 0 0 270)
			(layer "F.Fab")
			(effects
				(font
					(size 1.27 1.27)
				)
			)
		)
		(duplicate_pad_numbers_are_jumpers no)
		(fp_line
			(start -0.7874 0.4064)
			(end -0.7874 -0.4064)
			(stroke
				(width 0.1524)
				(type default)
			)
			(layer "F.SilkS")
		)
		(fp_line
			(start 0.7874 0.4064)
			(end -0.7874 0.4064)
			(stroke
				(width 0.1524)
				(type default)
			)
			(layer "F.SilkS")
		)
		(fp_line
			(start -0.7874 -0.4064)
			(end 0.7874 -0.4064)
			(stroke
				(width 0.1524)
				(type default)
			)
			(layer "F.SilkS")
		)
		(fp_line
			(start 0.7874 -0.4064)
			(end 0.7874 0.4064)
			(stroke
				(width 0.1524)
				(type default)
			)
			(layer "F.SilkS")
		)
		(fp_line
			(start -0.67945 0.3048)
			(end -0.67945 -0.305054)
			(stroke
				(width 0.1)
				(type default)
			)
			(layer "F.Fab")
		)
		(fp_line
			(start -0.12065 0.3048)
			(end -0.67945 0.3048)
			(stroke
				(width 0.1)
				(type default)
			)
			(layer "F.Fab")
		)
		(fp_line
			(start 0.120396 0.3048)
			(end 0.120396 0.2794)
			(stroke
				(width 0.1)
				(type default)
			)
			(layer "F.Fab")
		)
		(fp_line
			(start 0.67945 0.3048)
			(end 0.120396 0.3048)
			(stroke
				(width 0.1)
				(type default)
			)
			(layer "F.Fab")
		)
		(fp_line
			(start -0.12065 0.2794)
			(end -0.12065 0.3048)
			(stroke
				(width 0.1)
				(type default)
			)
			(layer "F.Fab")
		)
		(fp_line
			(start 0.120396 0.2794)
			(end -0.12065 0.2794)
			(stroke
				(width 0.1)
				(type default)
			)
			(layer "F.Fab")
		)
		(fp_line
			(start -0.12065 -0.2794)
			(end 0.12065 -0.2794)
			(stroke
				(width 0.1)
				(type default)
			)
			(layer "F.Fab")
		)
		(fp_line
			(start 0.12065 -0.2794)
			(end 0.12065 -0.3048)
			(stroke
				(width 0.1)
				(type default)
			)
			(layer "F.Fab")
		)
		(fp_line
			(start 0.12065 -0.3048)
			(end 0.67945 -0.3048)
			(stroke
				(width 0.1)
				(type default)
			)
			(layer "F.Fab")
		)
		(fp_line
			(start 0.67945 -0.3048)
			(end 0.67945 0.3048)
			(stroke
				(width 0.1)
				(type default)
			)
			(layer "F.Fab")
		)
		(fp_line
			(start -0.67945 -0.305054)
			(end -0.12065 -0.305054)
			(stroke
				(width 0.1)
				(type default)
			)
			(layer "F.Fab")
		)
		(fp_line
			(start -0.12065 -0.305054)
			(end -0.12065 -0.2794)
			(stroke
				(width 0.1)
				(type default)
			)
			(layer "F.Fab")
		)
		(pad "1" smd circle
			(at -0.40005 0 270)
			(size 0 0)
			(layers "F.Cu" "F.Mask" "F.Paste")
			(net "PVCCIN_CPU1")
		)
		(pad "2" smd circle
			(at 0.40005 0 270)
			(size 0 0)
			(layers "F.Cu" "F.Mask" "F.Paste")
			(net "GND")
		)
	)
	(footprint ""
		(layer "F.Cu")
		(at 162.34283 -80.159098)
		(property "Reference" "R2211"
			(at 0 0 0)
			(layer "F.SilkS")
			(hide yes)
			(effects
				(font
					(size 1.27 1.27)
				)
			)
		)
		(property "Value" ""
			(at 0 0 0)
			(layer "F.Fab")
			(effects
				(font
					(size 1.27 1.27)
				)
			)
		)
		(duplicate_pad_numbers_are_jumpers no)
		(fp_line
			(start -0.7874 -0.4064)
			(end 0.7874 -0.4064)
			(stroke
				(width 0.1524)
				(type default)
			)
			(layer "F.SilkS")
		)
		(fp_line
			(start -0.7874 0.4064)
			(end -0.7874 -0.4064)
			(stroke
				(width 0.1524)
				(type default)
			)
			(layer "F.SilkS")
		)
		(fp_line
			(start 0.7874 -0.4064)
			(end 0.7874 0.4064)
			(stroke
				(width 0.1524)
				(type default)
			)
			(layer "F.SilkS")
		)
		(fp_line
			(start 0.7874 0.4064)
			(end -0.7874 0.4064)
			(stroke
				(width 0.1524)
				(type default)
			)
			(layer "F.SilkS")
		)
		(fp_line
			(start -0.67945 -0.305054)
			(end -0.12065 -0.305054)
			(stroke
				(width 0.1)
				(type default)
			)
			(layer "F.Fab")
		)
		(fp_line
			(start -0.67945 0.3048)
			(end -0.67945 -0.305054)
			(stroke
				(width 0.1)
				(type default)
			)
			(layer "F.Fab")
		)
		(fp_line
			(start -0.12065 -0.305054)
			(end -0.12065 -0.2794)
			(stroke
				(width 0.1)
				(type default)
			)
			(layer "F.Fab")
		)
		(fp_line
			(start -0.12065 -0.2794)
			(end 0.12065 -0.2794)
			(stroke
				(width 0.1)
				(type default)
			)
			(layer "F.Fab")
		)
		(fp_line
			(start -0.12065 0.2794)
			(end -0.12065 0.3048)
			(stroke
				(width 0.1)
				(type default)
			)
			(layer "F.Fab")
		)
		(fp_line
			(start -0.12065 0.3048)
			(end -0.67945 0.3048)
			(stroke
				(width 0.1)
				(type default)
			)
			(layer "F.Fab")
		)
		(fp_line
			(start 0.120396 0.2794)
			(end -0.12065 0.2794)
			(stroke
				(width 0.1)
				(type default)
			)
			(layer "F.Fab")
		)
		(fp_line
			(start 0.120396 0.3048)
			(end 0.120396 0.2794)
			(stroke
				(width 0.1)
				(type default)
			)
			(layer "F.Fab")
		)
		(fp_line
			(start 0.12065 -0.3048)
			(end 0.67945 -0.3048)
			(stroke
				(width 0.1)
				(type default)
			)
			(layer "F.Fab")
		)
		(fp_line
			(start 0.12065 -0.2794)
			(end 0.12065 -0.3048)
			(stroke
				(width 0.1)
				(type default)
			)
			(layer "F.Fab")
		)
		(fp_line
			(start 0.67945 -0.3048)
			(end 0.67945 0.3048)
			(stroke
				(width 0.1)
				(type default)
			)
			(layer "F.Fab")
		)
		(fp_line
			(start 0.67945 0.3048)
			(end 0.120396 0.3048)
			(stroke
				(width 0.1)
				(type default)
			)
			(layer "F.Fab")
		)
		(pad "1" smd circle
			(at -0.40005 0)
			(size 0 0)
			(layers "F.Cu" "F.Mask" "F.Paste")
			(net "SMB_S3M_CPU1_3V3AUX_SCL_R")
		)
		(pad "2" smd circle
			(at 0.40005 0)
			(size 0 0)
			(layers "F.Cu" "F.Mask" "F.Paste")
			(net "SMB_S3M_CPU1_3V3AUX_SCL")
		)
	)
	(footprint ""
		(layer "F.Cu")
		(at 257.85953 -55.479442)
		(property "Reference" "R3956"
			(at 0 0 0)
			(layer "F.SilkS")
			(hide yes)
			(effects
				(font
					(size 1.27 1.27)
				)
			)
		)
		(property "Value" ""
			(at 0 0 0)
			(layer "F.Fab")
			(effects
				(font
					(size 1.27 1.27)
				)
			)
		)
		(duplicate_pad_numbers_are_jumpers no)
		(fp_line
			(start -0.7874 -0.4064)
			(end 0.7874 -0.4064)
			(stroke
				(width 0.1524)
				(type default)
			)
			(layer "F.SilkS")
		)
		(fp_line
			(start -0.7874 0.4064)
			(end -0.7874 -0.4064)
			(stroke
				(width 0.1524)
				(type default)
			)
			(layer "F.SilkS")
		)
		(fp_line
			(start 0.7874 -0.4064)
			(end 0.7874 0.4064)
			(stroke
				(width 0.1524)
				(type default)
			)
			(layer "F.SilkS")
		)
		(fp_line
			(start 0.7874 0.4064)
			(end -0.7874 0.4064)
			(stroke
				(width 0.1524)
				(type default)
			)
			(layer "F.SilkS")
		)
		(fp_line
			(start -0.67945 -0.305054)
			(end -0.12065 -0.305054)
			(stroke
				(width 0.1)
				(type default)
			)
			(layer "F.Fab")
		)
		(fp_line
			(start -0.67945 0.3048)
			(end -0.67945 -0.305054)
			(stroke
				(width 0.1)
				(type default)
			)
			(layer "F.Fab")
		)
		(fp_line
			(start -0.12065 -0.305054)
			(end -0.12065 -0.2794)
			(stroke
				(width 0.1)
				(type default)
			)
			(layer "F.Fab")
		)
		(fp_line
			(start -0.12065 -0.2794)
			(end 0.12065 -0.2794)
			(stroke
				(width 0.1)
				(type default)
			)
			(layer "F.Fab")
		)
		(fp_line
			(start -0.12065 0.2794)
			(end -0.12065 0.3048)
			(stroke
				(width 0.1)
				(type default)
			)
			(layer "F.Fab")
		)
		(fp_line
			(start -0.12065 0.3048)
			(end -0.67945 0.3048)
			(stroke
				(width 0.1)
				(type default)
			)
			(layer "F.Fab")
		)
		(fp_line
			(start 0.120396 0.2794)
			(end -0.12065 0.2794)
			(stroke
				(width 0.1)
				(type default)
			)
			(layer "F.Fab")
		)
		(fp_line
			(start 0.120396 0.3048)
			(end 0.120396 0.2794)
			(stroke
				(width 0.1)
				(type default)
			)
			(layer "F.Fab")
		)
		(fp_line
			(start 0.12065 -0.3048)
			(end 0.67945 -0.3048)
			(stroke
				(width 0.1)
				(type default)
			)
			(layer "F.Fab")
		)
		(fp_line
			(start 0.12065 -0.2794)
			(end 0.12065 -0.3048)
			(stroke
				(width 0.1)
				(type default)
			)
			(layer "F.Fab")
		)
		(fp_line
			(start 0.67945 -0.3048)
			(end 0.67945 0.3048)
			(stroke
				(width 0.1)
				(type default)
			)
			(layer "F.Fab")
		)
		(fp_line
			(start 0.67945 0.3048)
			(end 0.120396 0.3048)
			(stroke
				(width 0.1)
				(type default)
			)
			(layer "F.Fab")
		)
		(pad "1" smd circle
			(at -0.40005 0)
			(size 0 0)
			(layers "F.Cu" "F.Mask" "F.Paste")
			(net "P12V_E1S_IMON_0")
		)
		(pad "2" smd circle
			(at 0.40005 0)
			(size 0 0)
			(layers "F.Cu" "F.Mask" "F.Paste")
			(net "P12V_E1S_0_ISENSE_MPS_TIC")
		)
	)
	(footprint ""
		(layer "F.Cu")
		(at 162.34283 -73.727818 180)
		(property "Reference" "R2313"
			(at 0 0 180)
			(layer "F.SilkS")
			(hide yes)
			(effects
				(font
					(size 1.27 1.27)
				)
			)
		)
		(property "Value" ""
			(at 0 0 180)
			(layer "F.Fab")
			(effects
				(font
					(size 1.27 1.27)
				)
			)
		)
		(duplicate_pad_numbers_are_jumpers no)
		(fp_line
			(start 0.7874 0.4064)
			(end -0.7874 0.4064)
			(stroke
				(width 0.1524)
				(type default)
			)
			(layer "F.SilkS")
		)
		(fp_line
			(start 0.7874 -0.4064)
			(end 0.7874 0.4064)
			(stroke
				(width 0.1524)
				(type default)
			)
			(layer "F.SilkS")
		)
		(fp_line
			(start -0.7874 0.4064)
			(end -0.7874 -0.4064)
			(stroke
				(width 0.1524)
				(type default)
			)
			(layer "F.SilkS")
		)
		(fp_line
			(start -0.7874 -0.4064)
			(end 0.7874 -0.4064)
			(stroke
				(width 0.1524)
				(type default)
			)
			(layer "F.SilkS")
		)
		(fp_line
			(start 0.67945 0.3048)
			(end 0.120396 0.3048)
			(stroke
				(width 0.1)
				(type default)
			)
			(layer "F.Fab")
		)
		(fp_line
			(start 0.67945 -0.3048)
			(end 0.67945 0.3048)
			(stroke
				(width 0.1)
				(type default)
			)
			(layer "F.Fab")
		)
		(fp_line
			(start 0.12065 -0.2794)
			(end 0.12065 -0.3048)
			(stroke
				(width 0.1)
				(type default)
			)
			(layer "F.Fab")
		)
		(fp_line
			(start 0.12065 -0.3048)
			(end 0.67945 -0.3048)
			(stroke
				(width 0.1)
				(type default)
			)
			(layer "F.Fab")
		)
		(fp_line
			(start 0.120396 0.3048)
			(end 0.120396 0.2794)
			(stroke
				(width 0.1)
				(type default)
			)
			(layer "F.Fab")
		)
		(fp_line
			(start 0.120396 0.2794)
			(end -0.12065 0.2794)
			(stroke
				(width 0.1)
				(type default)
			)
			(layer "F.Fab")
		)
		(fp_line
			(start -0.12065 0.3048)
			(end -0.67945 0.3048)
			(stroke
				(width 0.1)
				(type default)
			)
			(layer "F.Fab")
		)
		(fp_line
			(start -0.12065 0.2794)
			(end -0.12065 0.3048)
			(stroke
				(width 0.1)
				(type default)
			)
			(layer "F.Fab")
		)
		(fp_line
			(start -0.12065 -0.2794)
			(end 0.12065 -0.2794)
			(stroke
				(width 0.1)
				(type default)
			)
			(layer "F.Fab")
		)
		(fp_line
			(start -0.12065 -0.305054)
			(end -0.12065 -0.2794)
			(stroke
				(width 0.1)
				(type default)
			)
			(layer "F.Fab")
		)
		(fp_line
			(start -0.67945 0.3048)
			(end -0.67945 -0.305054)
			(stroke
				(width 0.1)
				(type default)
			)
			(layer "F.Fab")
		)
		(fp_line
			(start -0.67945 -0.305054)
			(end -0.12065 -0.305054)
			(stroke
				(width 0.1)
				(type default)
			)
			(layer "F.Fab")
		)
		(pad "1" smd circle
			(at -0.40005 0 180)
			(size 0 0)
			(layers "F.Cu" "F.Mask" "F.Paste")
			(net "RST_SMB_SWITCH_N")
		)
		(pad "2" smd circle
			(at 0.40005 0 180)
			(size 0 0)
			(layers "F.Cu" "F.Mask" "F.Paste")
			(net "RST_SMB_S3M_N")
		)
	)
	(footprint ""
		(layer "F.Cu")
		(at 128.401572 -133.050026)
		(property "Reference" "R3581"
			(at 0 0 0)
			(layer "F.SilkS")
			(hide yes)
			(effects
				(font
					(size 1.27 1.27)
				)
			)
		)
		(property "Value" ""
			(at 0 0 0)
			(layer "F.Fab")
			(effects
				(font
					(size 1.27 1.27)
				)
			)
		)
		(duplicate_pad_numbers_are_jumpers no)
		(fp_line
			(start -0.7874 -0.4064)
			(end 0.7874 -0.4064)
			(stroke
				(width 0.1524)
				(type default)
			)
			(layer "F.SilkS")
		)
		(fp_line
			(start -0.7874 0.4064)
			(end -0.7874 -0.4064)
			(stroke
				(width 0.1524)
				(type default)
			)
			(layer "F.SilkS")
		)
		(fp_line
			(start 0.7874 -0.4064)
			(end 0.7874 0.4064)
			(stroke
				(width 0.1524)
				(type default)
			)
			(layer "F.SilkS")
		)
		(fp_line
			(start 0.7874 0.4064)
			(end -0.7874 0.4064)
			(stroke
				(width 0.1524)
				(type default)
			)
			(layer "F.SilkS")
		)
		(fp_line
			(start -0.67945 -0.305054)
			(end -0.12065 -0.305054)
			(stroke
				(width 0.1)
				(type default)
			)
			(layer "F.Fab")
		)
		(fp_line
			(start -0.67945 0.3048)
			(end -0.67945 -0.305054)
			(stroke
				(width 0.1)
				(type default)
			)
			(layer "F.Fab")
		)
		(fp_line
			(start -0.12065 -0.305054)
			(end -0.12065 -0.2794)
			(stroke
				(width 0.1)
				(type default)
			)
			(layer "F.Fab")
		)
		(fp_line
			(start -0.12065 -0.2794)
			(end 0.12065 -0.2794)
			(stroke
				(width 0.1)
				(type default)
			)
			(layer "F.Fab")
		)
		(fp_line
			(start -0.12065 0.2794)
			(end -0.12065 0.3048)
			(stroke
				(width 0.1)
				(type default)
			)
			(layer "F.Fab")
		)
		(fp_line
			(start -0.12065 0.3048)
			(end -0.67945 0.3048)
			(stroke
				(width 0.1)
				(type default)
			)
			(layer "F.Fab")
		)
		(fp_line
			(start 0.120396 0.2794)
			(end -0.12065 0.2794)
			(stroke
				(width 0.1)
				(type default)
			)
			(layer "F.Fab")
		)
		(fp_line
			(start 0.120396 0.3048)
			(end 0.120396 0.2794)
			(stroke
				(width 0.1)
				(type default)
			)
			(layer "F.Fab")
		)
		(fp_line
			(start 0.12065 -0.3048)
			(end 0.67945 -0.3048)
			(stroke
				(width 0.1)
				(type default)
			)
			(layer "F.Fab")
		)
		(fp_line
			(start 0.12065 -0.2794)
			(end 0.12065 -0.3048)
			(stroke
				(width 0.1)
				(type default)
			)
			(layer "F.Fab")
		)
		(fp_line
			(start 0.67945 -0.3048)
			(end 0.67945 0.3048)
			(stroke
				(width 0.1)
				(type default)
			)
			(layer "F.Fab")
		)
		(fp_line
			(start 0.67945 0.3048)
			(end 0.120396 0.3048)
			(stroke
				(width 0.1)
				(type default)
			)
			(layer "F.Fab")
		)
		(pad "1" smd circle
			(at -0.40005 0)
			(size 0 0)
			(layers "F.Cu" "F.Mask" "F.Paste")
			(net "SMB_INA230_3V3AUX_SDA_R")
		)
		(pad "2" smd circle
			(at 0.40005 0)
			(size 0 0)
			(layers "F.Cu" "F.Mask" "F.Paste")
			(net "SMB_INA230_3V3AUX_SDA")
		)
	)
	(footprint ""
		(layer "F.Cu")
		(at 140.843 -78.500478)
		(property "Reference" "U150"
			(at -1.16078 -1.98628 0)
			(unlocked yes)
			(layer "F.SilkS")
			(effects
				(font
					(size 0.7874 0.5842)
					(thickness 0.1524)
				)
				(justify left)
			)
		)
		(property "Value" ""
			(at 0 0 0)
			(layer "F.Fab")
			(effects
				(font
					(size 1.27 1.27)
				)
			)
		)
		(duplicate_pad_numbers_are_jumpers no)
		(fp_line
			(start -1.3462 -1.100074)
			(end -0.670052 -1.100074)
			(stroke
				(width 0.1524)
				(type default)
			)
			(layer "F.SilkS")
		)
		(fp_line
			(start -1.3462 1.100074)
			(end -1.3462 -1.100074)
			(stroke
				(width 0.1524)
				(type default)
			)
			(layer "F.SilkS")
		)
		(fp_line
			(start -0.670052 -1.100074)
			(end 0 -0.381)
			(stroke
				(width 0.1524)
				(type default)
			)
			(layer "F.SilkS")
		)
		(fp_line
			(start 0 -0.381)
			(end 0.670052 -1.100074)
			(stroke
				(width 0.1524)
				(type default)
			)
			(layer "F.SilkS")
		)
		(fp_line
			(start 0.670052 -1.100074)
			(end 1.3462 -1.100074)
			(stroke
				(width 0.1524)
				(type default)
			)
			(layer "F.SilkS")
		)
		(fp_line
			(start 1.3462 -1.100074)
			(end 1.3462 1.100074)
			(stroke
				(width 0.1524)
				(type default)
			)
			(layer "F.SilkS")
		)
		(fp_line
			(start 1.3462 1.100074)
			(end -1.3462 1.100074)
			(stroke
				(width 0.1524)
				(type default)
			)
			(layer "F.SilkS")
		)
		(fp_poly
			(pts
				(xy -1.524 -0.649986) (xy -2.286 -0.268986) (xy -2.286 -1.030986)
			)
			(stroke
				(width 0)
				(type default)
			)
			(fill yes)
			(layer "F.SilkS")
		)
		(fp_line
			(start -1.100074 -0.8001)
			(end -0.670052 -0.8001)
			(stroke
				(width 0.1)
				(type default)
			)
			(layer "F.Fab")
		)
		(fp_line
			(start -1.100074 0.8001)
			(end -1.100074 -0.8001)
			(stroke
				(width 0.1)
				(type default)
			)
			(layer "F.Fab")
		)
		(fp_line
			(start -0.670052 -1.100074)
			(end 0.670052 -1.100074)
			(stroke
				(width 0.1)
				(type default)
			)
			(layer "F.Fab")
		)
		(fp_line
			(start -0.670052 -0.8001)
			(end -0.670052 -1.100074)
			(stroke
				(width 0.1)
				(type default)
			)
			(layer "F.Fab")
		)
		(fp_line
			(start -0.670052 0.8001)
			(end -1.100074 0.8001)
			(stroke
				(width 0.1)
				(type default)
			)
			(layer "F.Fab")
		)
		(fp_line
			(start -0.670052 0.8001)
			(end -0.670052 -0.8001)
			(stroke
				(width 0.1)
				(type default)
			)
			(layer "F.Fab")
		)
		(fp_line
			(start -0.670052 1.100074)
			(end -0.670052 0.8001)
			(stroke
				(width 0.1)
				(type default)
			)
			(layer "F.Fab")
		)
		(fp_line
			(start 0.670052 -1.100074)
			(end 0.670052 -0.8001)
			(stroke
				(width 0.1)
				(type default)
			)
			(layer "F.Fab")
		)
		(fp_line
			(start 0.670052 -0.8001)
			(end 0.670052 0.8001)
			(stroke
				(width 0.1)
				(type default)
			)
			(layer "F.Fab")
		)
		(fp_line
			(start 0.670052 -0.8001)
			(end 1.100074 -0.8001)
			(stroke
				(width 0.1)
				(type default)
			)
			(layer "F.Fab")
		)
		(fp_line
			(start 0.670052 0.8001)
			(end 0.670052 1.100074)
			(stroke
				(width 0.1)
				(type default)
			)
			(layer "F.Fab")
		)
		(fp_line
			(start 0.670052 1.100074)
			(end -0.670052 1.100074)
			(stroke
				(width 0.1)
				(type default)
			)
			(layer "F.Fab")
		)
		(fp_line
			(start 1.100074 -0.8001)
			(end 1.100074 0.8001)
			(stroke
				(width 0.1)
				(type default)
			)
			(layer "F.Fab")
		)
		(fp_line
			(start 1.100074 0.8001)
			(end 0.670052 0.8001)
			(stroke
				(width 0.1)
				(type default)
			)
			(layer "F.Fab")
		)
		(fp_poly
			(pts
				(xy -1.524 -0.649986) (xy -2.286 -1.030986) (xy -2.286 -0.268986)
			)
			(stroke
				(width 0)
				(type default)
			)
			(fill yes)
			(layer "F.Fab")
		)
		(pad "1" smd rect
			(at -0.94996 -0.649986 270)
			(size 0.4064 0.508)
			(layers "F.Cu" "F.Mask" "F.Paste")
			(net "FM_PS_EN_PLD_R")
		)
		(pad "2" smd rect
			(at -0.94996 0 270)
			(size 0.4064 0.508)
			(layers "F.Cu" "F.Mask" "F.Paste")
			(net "GND")
		)
		(pad "3" smd rect
			(at -0.94996 0.649986 270)
			(size 0.4064 0.508)
			(layers "F.Cu" "F.Mask" "F.Paste")
			(net "NC_U150_A1")
		)
		(pad "4" smd rect
			(at 0.94996 0.649986 270)
			(size 0.4064 0.508)
			(layers "F.Cu" "F.Mask" "F.Paste")
			(net "NC_U150_B1")
		)
		(pad "5" smd rect
			(at 0.94996 0 270)
			(size 0.4064 0.508)
			(layers "F.Cu" "F.Mask" "F.Paste")
			(net "P3V3_AUX")
		)
		(pad "6" smd rect
			(at 0.94996 -0.649986 270)
			(size 0.4064 0.508)
			(layers "F.Cu" "F.Mask" "F.Paste")
			(net "FM_PS_EN_PLD_BUF1")
		)
	)
	(footprint ""
		(layer "F.Cu")
		(at 213.41588 -47.335948 90)
		(property "Reference" "R3589"
			(at 0 0 90)
			(layer "F.SilkS")
			(hide yes)
			(effects
				(font
					(size 1.27 1.27)
				)
			)
		)
		(property "Value" ""
			(at 0 0 90)
			(layer "F.Fab")
			(effects
				(font
					(size 1.27 1.27)
				)
			)
		)
		(duplicate_pad_numbers_are_jumpers no)
		(fp_line
			(start 0.7874 -0.4064)
			(end 0.7874 0.4064)
			(stroke
				(width 0.1524)
				(type default)
			)
			(layer "F.SilkS")
		)
		(fp_line
			(start -0.7874 -0.4064)
			(end 0.7874 -0.4064)
			(stroke
				(width 0.1524)
				(type default)
			)
			(layer "F.SilkS")
		)
		(fp_line
			(start 0.7874 0.4064)
			(end -0.7874 0.4064)
			(stroke
				(width 0.1524)
				(type default)
			)
			(layer "F.SilkS")
		)
		(fp_line
			(start -0.7874 0.4064)
			(end -0.7874 -0.4064)
			(stroke
				(width 0.1524)
				(type default)
			)
			(layer "F.SilkS")
		)
		(fp_line
			(start -0.12065 -0.305054)
			(end -0.12065 -0.2794)
			(stroke
				(width 0.1)
				(type default)
			)
			(layer "F.Fab")
		)
		(fp_line
			(start -0.67945 -0.305054)
			(end -0.12065 -0.305054)
			(stroke
				(width 0.1)
				(type default)
			)
			(layer "F.Fab")
		)
		(fp_line
			(start 0.67945 -0.3048)
			(end 0.67945 0.3048)
			(stroke
				(width 0.1)
				(type default)
			)
			(layer "F.Fab")
		)
		(fp_line
			(start 0.12065 -0.3048)
			(end 0.67945 -0.3048)
			(stroke
				(width 0.1)
				(type default)
			)
			(layer "F.Fab")
		)
		(fp_line
			(start 0.12065 -0.2794)
			(end 0.12065 -0.3048)
			(stroke
				(width 0.1)
				(type default)
			)
			(layer "F.Fab")
		)
		(fp_line
			(start -0.12065 -0.2794)
			(end 0.12065 -0.2794)
			(stroke
				(width 0.1)
				(type default)
			)
			(layer "F.Fab")
		)
		(fp_line
			(start 0.120396 0.2794)
			(end -0.12065 0.2794)
			(stroke
				(width 0.1)
				(type default)
			)
			(layer "F.Fab")
		)
		(fp_line
			(start -0.12065 0.2794)
			(end -0.12065 0.3048)
			(stroke
				(width 0.1)
				(type default)
			)
			(layer "F.Fab")
		)
		(fp_line
			(start 0.67945 0.3048)
			(end 0.120396 0.3048)
			(stroke
				(width 0.1)
				(type default)
			)
			(layer "F.Fab")
		)
		(fp_line
			(start 0.120396 0.3048)
			(end 0.120396 0.2794)
			(stroke
				(width 0.1)
				(type default)
			)
			(layer "F.Fab")
		)
		(fp_line
			(start -0.12065 0.3048)
			(end -0.67945 0.3048)
			(stroke
				(width 0.1)
				(type default)
			)
			(layer "F.Fab")
		)
		(fp_line
			(start -0.67945 0.3048)
			(end -0.67945 -0.305054)
			(stroke
				(width 0.1)
				(type default)
			)
			(layer "F.Fab")
		)
		(pad "1" smd circle
			(at -0.40005 0 90)
			(size 0 0)
			(layers "F.Cu" "F.Mask" "F.Paste")
			(net "SMB_INA230_3V3AUX_SDA")
		)
		(pad "2" smd circle
			(at 0.40005 0 90)
			(size 0 0)
			(layers "F.Cu" "F.Mask" "F.Paste")
			(net "SMB_INA230_2_3V3AUX_SDA_R")
		)
	)
	(footprint ""
		(layer "F.Cu")
		(at 106.86034 -417.362386 180)
		(property "Reference" "R4478"
			(at 0 0 180)
			(layer "F.SilkS")
			(hide yes)
			(effects
				(font
					(size 1.27 1.27)
				)
			)
		)
		(property "Value" ""
			(at 0 0 180)
			(layer "F.Fab")
			(effects
				(font
					(size 1.27 1.27)
				)
			)
		)
		(duplicate_pad_numbers_are_jumpers no)
		(fp_line
			(start 0.7874 0.4064)
			(end -0.7874 0.4064)
			(stroke
				(width 0.1524)
				(type default)
			)
			(layer "F.SilkS")
		)
		(fp_line
			(start 0.7874 -0.4064)
			(end 0.7874 0.4064)
			(stroke
				(width 0.1524)
				(type default)
			)
			(layer "F.SilkS")
		)
		(fp_line
			(start -0.7874 0.4064)
			(end -0.7874 -0.4064)
			(stroke
				(width 0.1524)
				(type default)
			)
			(layer "F.SilkS")
		)
		(fp_line
			(start -0.7874 -0.4064)
			(end 0.7874 -0.4064)
			(stroke
				(width 0.1524)
				(type default)
			)
			(layer "F.SilkS")
		)
		(fp_line
			(start 0.67945 0.3048)
			(end 0.120396 0.3048)
			(stroke
				(width 0.1)
				(type default)
			)
			(layer "F.Fab")
		)
		(fp_line
			(start 0.67945 -0.3048)
			(end 0.67945 0.3048)
			(stroke
				(width 0.1)
				(type default)
			)
			(layer "F.Fab")
		)
		(fp_line
			(start 0.12065 -0.2794)
			(end 0.12065 -0.3048)
			(stroke
				(width 0.1)
				(type default)
			)
			(layer "F.Fab")
		)
		(fp_line
			(start 0.12065 -0.3048)
			(end 0.67945 -0.3048)
			(stroke
				(width 0.1)
				(type default)
			)
			(layer "F.Fab")
		)
		(fp_line
			(start 0.120396 0.3048)
			(end 0.120396 0.2794)
			(stroke
				(width 0.1)
				(type default)
			)
			(layer "F.Fab")
		)
		(fp_line
			(start 0.120396 0.2794)
			(end -0.12065 0.2794)
			(stroke
				(width 0.1)
				(type default)
			)
			(layer "F.Fab")
		)
		(fp_line
			(start -0.12065 0.3048)
			(end -0.67945 0.3048)
			(stroke
				(width 0.1)
				(type default)
			)
			(layer "F.Fab")
		)
		(fp_line
			(start -0.12065 0.2794)
			(end -0.12065 0.3048)
			(stroke
				(width 0.1)
				(type default)
			)
			(layer "F.Fab")
		)
		(fp_line
			(start -0.12065 -0.2794)
			(end 0.12065 -0.2794)
			(stroke
				(width 0.1)
				(type default)
			)
			(layer "F.Fab")
		)
		(fp_line
			(start -0.12065 -0.305054)
			(end -0.12065 -0.2794)
			(stroke
				(width 0.1)
				(type default)
			)
			(layer "F.Fab")
		)
		(fp_line
			(start -0.67945 0.3048)
			(end -0.67945 -0.305054)
			(stroke
				(width 0.1)
				(type default)
			)
			(layer "F.Fab")
		)
		(fp_line
			(start -0.67945 -0.305054)
			(end -0.12065 -0.305054)
			(stroke
				(width 0.1)
				(type default)
			)
			(layer "F.Fab")
		)
		(pad "1" smd circle
			(at -0.40005 0 180)
			(size 0 0)
			(layers "F.Cu" "F.Mask" "F.Paste")
			(net "FM_9ZXL045_1_OE_N")
		)
		(pad "2" smd circle
			(at 0.40005 0 180)
			(size 0 0)
			(layers "F.Cu" "F.Mask" "F.Paste")
			(net "CLK_GPU_1_OE_N")
		)
	)
	(footprint ""
		(layer "F.Cu")
		(at 352.289618 -245.634002 -90)
		(property "Reference" "C401"
			(at 0 0 270)
			(layer "F.SilkS")
			(hide yes)
			(effects
				(font
					(size 1.27 1.27)
				)
			)
		)
		(property "Value" ""
			(at 0 0 270)
			(layer "F.Fab")
			(effects
				(font
					(size 1.27 1.27)
				)
			)
		)
		(duplicate_pad_numbers_are_jumpers no)
		(fp_line
			(start -0.7874 0.4064)
			(end -0.7874 -0.4064)
			(stroke
				(width 0.1524)
				(type default)
			)
			(layer "F.SilkS")
		)
		(fp_line
			(start 0.7874 0.4064)
			(end -0.7874 0.4064)
			(stroke
				(width 0.1524)
				(type default)
			)
			(layer "F.SilkS")
		)
		(fp_line
			(start -0.7874 -0.4064)
			(end 0.7874 -0.4064)
			(stroke
				(width 0.1524)
				(type default)
			)
			(layer "F.SilkS")
		)
		(fp_line
			(start 0.7874 -0.4064)
			(end 0.7874 0.4064)
			(stroke
				(width 0.1524)
				(type default)
			)
			(layer "F.SilkS")
		)
		(fp_line
			(start -0.67945 0.3048)
			(end -0.67945 -0.305054)
			(stroke
				(width 0.1)
				(type default)
			)
			(layer "F.Fab")
		)
		(fp_line
			(start -0.12065 0.3048)
			(end -0.67945 0.3048)
			(stroke
				(width 0.1)
				(type default)
			)
			(layer "F.Fab")
		)
		(fp_line
			(start 0.120396 0.3048)
			(end 0.120396 0.2794)
			(stroke
				(width 0.1)
				(type default)
			)
			(layer "F.Fab")
		)
		(fp_line
			(start 0.67945 0.3048)
			(end 0.120396 0.3048)
			(stroke
				(width 0.1)
				(type default)
			)
			(layer "F.Fab")
		)
		(fp_line
			(start -0.12065 0.2794)
			(end -0.12065 0.3048)
			(stroke
				(width 0.1)
				(type default)
			)
			(layer "F.Fab")
		)
		(fp_line
			(start 0.120396 0.2794)
			(end -0.12065 0.2794)
			(stroke
				(width 0.1)
				(type default)
			)
			(layer "F.Fab")
		)
		(fp_line
			(start -0.12065 -0.2794)
			(end 0.12065 -0.2794)
			(stroke
				(width 0.1)
				(type default)
			)
			(layer "F.Fab")
		)
		(fp_line
			(start 0.12065 -0.2794)
			(end 0.12065 -0.3048)
			(stroke
				(width 0.1)
				(type default)
			)
			(layer "F.Fab")
		)
		(fp_line
			(start 0.12065 -0.3048)
			(end 0.67945 -0.3048)
			(stroke
				(width 0.1)
				(type default)
			)
			(layer "F.Fab")
		)
		(fp_line
			(start 0.67945 -0.3048)
			(end 0.67945 0.3048)
			(stroke
				(width 0.1)
				(type default)
			)
			(layer "F.Fab")
		)
		(fp_line
			(start -0.67945 -0.305054)
			(end -0.12065 -0.305054)
			(stroke
				(width 0.1)
				(type default)
			)
			(layer "F.Fab")
		)
		(fp_line
			(start -0.12065 -0.305054)
			(end -0.12065 -0.2794)
			(stroke
				(width 0.1)
				(type default)
			)
			(layer "F.Fab")
		)
		(pad "1" smd circle
			(at -0.40005 0 270)
			(size 0 0)
			(layers "F.Cu" "F.Mask" "F.Paste")
			(net "PVCCD_HV_CPU0")
		)
		(pad "2" smd circle
			(at 0.40005 0 270)
			(size 0 0)
			(layers "F.Cu" "F.Mask" "F.Paste")
			(net "GND")
		)
	)
	(footprint ""
		(layer "F.Cu")
		(at 333.20228 -339.602572 90)
		(property "Reference" "PC248"
			(at 0 0 90)
			(layer "F.SilkS")
			(hide yes)
			(effects
				(font
					(size 1.27 1.27)
				)
			)
		)
		(property "Value" ""
			(at 0 0 90)
			(layer "F.Fab")
			(effects
				(font
					(size 1.27 1.27)
				)
			)
		)
		(duplicate_pad_numbers_are_jumpers no)
		(fp_line
			(start 0.7874 -0.4064)
			(end 0.7874 0.4064)
			(stroke
				(width 0.1524)
				(type default)
			)
			(layer "F.SilkS")
		)
		(fp_line
			(start -0.7874 -0.4064)
			(end 0.7874 -0.4064)
			(stroke
				(width 0.1524)
				(type default)
			)
			(layer "F.SilkS")
		)
		(fp_line
			(start 0.7874 0.4064)
			(end -0.7874 0.4064)
			(stroke
				(width 0.1524)
				(type default)
			)
			(layer "F.SilkS")
		)
		(fp_line
			(start -0.7874 0.4064)
			(end -0.7874 -0.4064)
			(stroke
				(width 0.1524)
				(type default)
			)
			(layer "F.SilkS")
		)
		(fp_line
			(start -0.12065 -0.305054)
			(end -0.12065 -0.2794)
			(stroke
				(width 0.1)
				(type default)
			)
			(layer "F.Fab")
		)
		(fp_line
			(start -0.67945 -0.305054)
			(end -0.12065 -0.305054)
			(stroke
				(width 0.1)
				(type default)
			)
			(layer "F.Fab")
		)
		(fp_line
			(start 0.67945 -0.3048)
			(end 0.67945 0.3048)
			(stroke
				(width 0.1)
				(type default)
			)
			(layer "F.Fab")
		)
		(fp_line
			(start 0.12065 -0.3048)
			(end 0.67945 -0.3048)
			(stroke
				(width 0.1)
				(type default)
			)
			(layer "F.Fab")
		)
		(fp_line
			(start 0.12065 -0.2794)
			(end 0.12065 -0.3048)
			(stroke
				(width 0.1)
				(type default)
			)
			(layer "F.Fab")
		)
		(fp_line
			(start -0.12065 -0.2794)
			(end 0.12065 -0.2794)
			(stroke
				(width 0.1)
				(type default)
			)
			(layer "F.Fab")
		)
		(fp_line
			(start 0.120396 0.2794)
			(end -0.12065 0.2794)
			(stroke
				(width 0.1)
				(type default)
			)
			(layer "F.Fab")
		)
		(fp_line
			(start -0.12065 0.2794)
			(end -0.12065 0.3048)
			(stroke
				(width 0.1)
				(type default)
			)
			(layer "F.Fab")
		)
		(fp_line
			(start 0.67945 0.3048)
			(end 0.120396 0.3048)
			(stroke
				(width 0.1)
				(type default)
			)
			(layer "F.Fab")
		)
		(fp_line
			(start 0.120396 0.3048)
			(end 0.120396 0.2794)
			(stroke
				(width 0.1)
				(type default)
			)
			(layer "F.Fab")
		)
		(fp_line
			(start -0.12065 0.3048)
			(end -0.67945 0.3048)
			(stroke
				(width 0.1)
				(type default)
			)
			(layer "F.Fab")
		)
		(fp_line
			(start -0.67945 0.3048)
			(end -0.67945 -0.305054)
			(stroke
				(width 0.1)
				(type default)
			)
			(layer "F.Fab")
		)
		(pad "1" smd circle
			(at -0.40005 0 90)
			(size 0 0)
			(layers "F.Cu" "F.Mask" "F.Paste")
			(net "PVCCIN_CPU0_VDD6")
		)
		(pad "2" smd circle
			(at 0.40005 0 90)
			(size 0 0)
			(layers "F.Cu" "F.Mask" "F.Paste")
			(net "GND")
		)
	)
	(footprint ""
		(layer "F.Cu")
		(at 355.2698 -406.852628 -90)
		(property "Reference" "R4548"
			(at 0 0 270)
			(layer "F.SilkS")
			(hide yes)
			(effects
				(font
					(size 1.27 1.27)
				)
			)
		)
		(property "Value" ""
			(at 0 0 270)
			(layer "F.Fab")
			(effects
				(font
					(size 1.27 1.27)
				)
			)
		)
		(duplicate_pad_numbers_are_jumpers no)
		(fp_line
			(start -0.7874 0.4064)
			(end -0.7874 -0.4064)
			(stroke
				(width 0.1524)
				(type default)
			)
			(layer "F.SilkS")
		)
		(fp_line
			(start 0.7874 0.4064)
			(end -0.7874 0.4064)
			(stroke
				(width 0.1524)
				(type default)
			)
			(layer "F.SilkS")
		)
		(fp_line
			(start -0.7874 -0.4064)
			(end 0.7874 -0.4064)
			(stroke
				(width 0.1524)
				(type default)
			)
			(layer "F.SilkS")
		)
		(fp_line
			(start 0.7874 -0.4064)
			(end 0.7874 0.4064)
			(stroke
				(width 0.1524)
				(type default)
			)
			(layer "F.SilkS")
		)
		(fp_line
			(start -0.67945 0.3048)
			(end -0.67945 -0.305054)
			(stroke
				(width 0.1)
				(type default)
			)
			(layer "F.Fab")
		)
		(fp_line
			(start -0.12065 0.3048)
			(end -0.67945 0.3048)
			(stroke
				(width 0.1)
				(type default)
			)
			(layer "F.Fab")
		)
		(fp_line
			(start 0.120396 0.3048)
			(end 0.120396 0.2794)
			(stroke
				(width 0.1)
				(type default)
			)
			(layer "F.Fab")
		)
		(fp_line
			(start 0.67945 0.3048)
			(end 0.120396 0.3048)
			(stroke
				(width 0.1)
				(type default)
			)
			(layer "F.Fab")
		)
		(fp_line
			(start -0.12065 0.2794)
			(end -0.12065 0.3048)
			(stroke
				(width 0.1)
				(type default)
			)
			(layer "F.Fab")
		)
		(fp_line
			(start 0.120396 0.2794)
			(end -0.12065 0.2794)
			(stroke
				(width 0.1)
				(type default)
			)
			(layer "F.Fab")
		)
		(fp_line
			(start -0.12065 -0.2794)
			(end 0.12065 -0.2794)
			(stroke
				(width 0.1)
				(type default)
			)
			(layer "F.Fab")
		)
		(fp_line
			(start 0.12065 -0.2794)
			(end 0.12065 -0.3048)
			(stroke
				(width 0.1)
				(type default)
			)
			(layer "F.Fab")
		)
		(fp_line
			(start 0.12065 -0.3048)
			(end 0.67945 -0.3048)
			(stroke
				(width 0.1)
				(type default)
			)
			(layer "F.Fab")
		)
		(fp_line
			(start 0.67945 -0.3048)
			(end 0.67945 0.3048)
			(stroke
				(width 0.1)
				(type default)
			)
			(layer "F.Fab")
		)
		(fp_line
			(start -0.67945 -0.305054)
			(end -0.12065 -0.305054)
			(stroke
				(width 0.1)
				(type default)
			)
			(layer "F.Fab")
		)
		(fp_line
			(start -0.12065 -0.305054)
			(end -0.12065 -0.2794)
			(stroke
				(width 0.1)
				(type default)
			)
			(layer "F.Fab")
		)
		(pad "1" smd circle
			(at -0.40005 0 270)
			(size 0 0)
			(layers "F.Cu" "F.Mask" "F.Paste")
			(net "SWB_HSC_EN")
		)
		(pad "2" smd circle
			(at 0.40005 0 270)
			(size 0 0)
			(layers "F.Cu" "F.Mask" "F.Paste")
			(net "GND")
		)
	)
	(footprint ""
		(layer "F.Cu")
		(at 357.735632 -398.789398)
		(property "Reference" "R2670"
			(at 0 0 0)
			(layer "F.SilkS")
			(hide yes)
			(effects
				(font
					(size 1.27 1.27)
				)
			)
		)
		(property "Value" ""
			(at 0 0 0)
			(layer "F.Fab")
			(effects
				(font
					(size 1.27 1.27)
				)
			)
		)
		(duplicate_pad_numbers_are_jumpers no)
		(fp_line
			(start -0.7874 -0.4064)
			(end 0.7874 -0.4064)
			(stroke
				(width 0.1524)
				(type default)
			)
			(layer "F.SilkS")
		)
		(fp_line
			(start -0.7874 0.4064)
			(end -0.7874 -0.4064)
			(stroke
				(width 0.1524)
				(type default)
			)
			(layer "F.SilkS")
		)
		(fp_line
			(start 0.7874 -0.4064)
			(end 0.7874 0.4064)
			(stroke
				(width 0.1524)
				(type default)
			)
			(layer "F.SilkS")
		)
		(fp_line
			(start 0.7874 0.4064)
			(end -0.7874 0.4064)
			(stroke
				(width 0.1524)
				(type default)
			)
			(layer "F.SilkS")
		)
		(fp_line
			(start -0.67945 -0.305054)
			(end -0.12065 -0.305054)
			(stroke
				(width 0.1)
				(type default)
			)
			(layer "F.Fab")
		)
		(fp_line
			(start -0.67945 0.3048)
			(end -0.67945 -0.305054)
			(stroke
				(width 0.1)
				(type default)
			)
			(layer "F.Fab")
		)
		(fp_line
			(start -0.12065 -0.305054)
			(end -0.12065 -0.2794)
			(stroke
				(width 0.1)
				(type default)
			)
			(layer "F.Fab")
		)
		(fp_line
			(start -0.12065 -0.2794)
			(end 0.12065 -0.2794)
			(stroke
				(width 0.1)
				(type default)
			)
			(layer "F.Fab")
		)
		(fp_line
			(start -0.12065 0.2794)
			(end -0.12065 0.3048)
			(stroke
				(width 0.1)
				(type default)
			)
			(layer "F.Fab")
		)
		(fp_line
			(start -0.12065 0.3048)
			(end -0.67945 0.3048)
			(stroke
				(width 0.1)
				(type default)
			)
			(layer "F.Fab")
		)
		(fp_line
			(start 0.120396 0.2794)
			(end -0.12065 0.2794)
			(stroke
				(width 0.1)
				(type default)
			)
			(layer "F.Fab")
		)
		(fp_line
			(start 0.120396 0.3048)
			(end 0.120396 0.2794)
			(stroke
				(width 0.1)
				(type default)
			)
			(layer "F.Fab")
		)
		(fp_line
			(start 0.12065 -0.3048)
			(end 0.67945 -0.3048)
			(stroke
				(width 0.1)
				(type default)
			)
			(layer "F.Fab")
		)
		(fp_line
			(start 0.12065 -0.2794)
			(end 0.12065 -0.3048)
			(stroke
				(width 0.1)
				(type default)
			)
			(layer "F.Fab")
		)
		(fp_line
			(start 0.67945 -0.3048)
			(end 0.67945 0.3048)
			(stroke
				(width 0.1)
				(type default)
			)
			(layer "F.Fab")
		)
		(fp_line
			(start 0.67945 0.3048)
			(end 0.120396 0.3048)
			(stroke
				(width 0.1)
				(type default)
			)
			(layer "F.Fab")
		)
		(pad "1" smd circle
			(at -0.40005 0)
			(size 0 0)
			(layers "F.Cu" "F.Mask" "F.Paste")
			(net "P3V3_AUX")
		)
		(pad "2" smd circle
			(at 0.40005 0)
			(size 0 0)
			(layers "F.Cu" "F.Mask" "F.Paste")
			(net "I3C_BMC_SWB_BUF_R_SCL")
		)
	)
	(footprint ""
		(layer "F.Cu")
		(at 307.363622 -44.948348 180)
		(property "Reference" "R608"
			(at 0 0 180)
			(layer "F.SilkS")
			(hide yes)
			(effects
				(font
					(size 1.27 1.27)
				)
			)
		)
		(property "Value" ""
			(at 0 0 180)
			(layer "F.Fab")
			(effects
				(font
					(size 1.27 1.27)
				)
			)
		)
		(duplicate_pad_numbers_are_jumpers no)
		(fp_line
			(start 0.7874 0.4064)
			(end -0.7874 0.4064)
			(stroke
				(width 0.1524)
				(type default)
			)
			(layer "F.SilkS")
		)
		(fp_line
			(start 0.7874 -0.4064)
			(end 0.7874 0.4064)
			(stroke
				(width 0.1524)
				(type default)
			)
			(layer "F.SilkS")
		)
		(fp_line
			(start -0.7874 0.4064)
			(end -0.7874 -0.4064)
			(stroke
				(width 0.1524)
				(type default)
			)
			(layer "F.SilkS")
		)
		(fp_line
			(start -0.7874 -0.4064)
			(end 0.7874 -0.4064)
			(stroke
				(width 0.1524)
				(type default)
			)
			(layer "F.SilkS")
		)
		(fp_line
			(start 0.67945 0.3048)
			(end 0.120396 0.3048)
			(stroke
				(width 0.1)
				(type default)
			)
			(layer "F.Fab")
		)
		(fp_line
			(start 0.67945 -0.3048)
			(end 0.67945 0.3048)
			(stroke
				(width 0.1)
				(type default)
			)
			(layer "F.Fab")
		)
		(fp_line
			(start 0.12065 -0.2794)
			(end 0.12065 -0.3048)
			(stroke
				(width 0.1)
				(type default)
			)
			(layer "F.Fab")
		)
		(fp_line
			(start 0.12065 -0.3048)
			(end 0.67945 -0.3048)
			(stroke
				(width 0.1)
				(type default)
			)
			(layer "F.Fab")
		)
		(fp_line
			(start 0.120396 0.3048)
			(end 0.120396 0.2794)
			(stroke
				(width 0.1)
				(type default)
			)
			(layer "F.Fab")
		)
		(fp_line
			(start 0.120396 0.2794)
			(end -0.12065 0.2794)
			(stroke
				(width 0.1)
				(type default)
			)
			(layer "F.Fab")
		)
		(fp_line
			(start -0.12065 0.3048)
			(end -0.67945 0.3048)
			(stroke
				(width 0.1)
				(type default)
			)
			(layer "F.Fab")
		)
		(fp_line
			(start -0.12065 0.2794)
			(end -0.12065 0.3048)
			(stroke
				(width 0.1)
				(type default)
			)
			(layer "F.Fab")
		)
		(fp_line
			(start -0.12065 -0.2794)
			(end 0.12065 -0.2794)
			(stroke
				(width 0.1)
				(type default)
			)
			(layer "F.Fab")
		)
		(fp_line
			(start -0.12065 -0.305054)
			(end -0.12065 -0.2794)
			(stroke
				(width 0.1)
				(type default)
			)
			(layer "F.Fab")
		)
		(fp_line
			(start -0.67945 0.3048)
			(end -0.67945 -0.305054)
			(stroke
				(width 0.1)
				(type default)
			)
			(layer "F.Fab")
		)
		(fp_line
			(start -0.67945 -0.305054)
			(end -0.12065 -0.305054)
			(stroke
				(width 0.1)
				(type default)
			)
			(layer "F.Fab")
		)
		(pad "1" smd circle
			(at -0.40005 0 180)
			(size 0 0)
			(layers "F.Cu" "F.Mask" "F.Paste")
			(net "FM_ESPI_FLASH_MODE")
		)
		(pad "2" smd circle
			(at 0.40005 0 180)
			(size 0 0)
			(layers "F.Cu" "F.Mask" "F.Paste")
			(net "GND")
		)
	)
	(footprint ""
		(layer "F.Cu")
		(at 404.900384 -17.612614 90)
		(property "Reference" "C849"
			(at 0 0 90)
			(layer "F.SilkS")
			(hide yes)
			(effects
				(font
					(size 1.27 1.27)
				)
			)
		)
		(property "Value" ""
			(at 0 0 90)
			(layer "F.Fab")
			(effects
				(font
					(size 1.27 1.27)
				)
			)
		)
		(duplicate_pad_numbers_are_jumpers no)
		(fp_line
			(start 0.299974 -0.150114)
			(end 0.299974 0.150114)
			(stroke
				(width 0.1)
				(type default)
			)
			(layer "F.Fab")
		)
		(fp_line
			(start -0.299974 -0.150114)
			(end 0.299974 -0.150114)
			(stroke
				(width 0.1)
				(type default)
			)
			(layer "F.Fab")
		)
		(fp_line
			(start 0.299974 0.150114)
			(end -0.299974 0.150114)
			(stroke
				(width 0.1)
				(type default)
			)
			(layer "F.Fab")
		)
		(fp_line
			(start -0.299974 0.150114)
			(end -0.299974 -0.150114)
			(stroke
				(width 0.1)
				(type default)
			)
			(layer "F.Fab")
		)
		(pad "1" smd rect
			(at -0.2667 0 90)
			(size 0.3048 0.381)
			(layers "F.Cu" "F.Mask" "F.Paste")
			(net "P5E_CPU0_PE1_TX_C_DP<10>")
		)
		(pad "2" smd rect
			(at 0.2667 0 90)
			(size 0.3048 0.381)
			(layers "F.Cu" "F.Mask" "F.Paste")
			(net "P5E_CPU0_PE1_TX_DP<10>")
		)
	)
	(footprint ""
		(layer "F.Cu")
		(at 213.4108 -107.4166 -90)
		(property "Reference" "R4777"
			(at 0 0 270)
			(layer "F.SilkS")
			(hide yes)
			(effects
				(font
					(size 1.27 1.27)
				)
			)
		)
		(property "Value" ""
			(at 0 0 270)
			(layer "F.Fab")
			(effects
				(font
					(size 1.27 1.27)
				)
			)
		)
		(duplicate_pad_numbers_are_jumpers no)
		(fp_line
			(start -0.7874 0.4064)
			(end -0.7874 -0.4064)
			(stroke
				(width 0.1524)
				(type default)
			)
			(layer "F.SilkS")
		)
		(fp_line
			(start 0.7874 0.4064)
			(end -0.7874 0.4064)
			(stroke
				(width 0.1524)
				(type default)
			)
			(layer "F.SilkS")
		)
		(fp_line
			(start -0.7874 -0.4064)
			(end 0.7874 -0.4064)
			(stroke
				(width 0.1524)
				(type default)
			)
			(layer "F.SilkS")
		)
		(fp_line
			(start 0.7874 -0.4064)
			(end 0.7874 0.4064)
			(stroke
				(width 0.1524)
				(type default)
			)
			(layer "F.SilkS")
		)
		(fp_line
			(start -0.67945 0.3048)
			(end -0.67945 -0.305054)
			(stroke
				(width 0.1)
				(type default)
			)
			(layer "F.Fab")
		)
		(fp_line
			(start -0.12065 0.3048)
			(end -0.67945 0.3048)
			(stroke
				(width 0.1)
				(type default)
			)
			(layer "F.Fab")
		)
		(fp_line
			(start 0.120396 0.3048)
			(end 0.120396 0.2794)
			(stroke
				(width 0.1)
				(type default)
			)
			(layer "F.Fab")
		)
		(fp_line
			(start 0.67945 0.3048)
			(end 0.120396 0.3048)
			(stroke
				(width 0.1)
				(type default)
			)
			(layer "F.Fab")
		)
		(fp_line
			(start -0.12065 0.2794)
			(end -0.12065 0.3048)
			(stroke
				(width 0.1)
				(type default)
			)
			(layer "F.Fab")
		)
		(fp_line
			(start 0.120396 0.2794)
			(end -0.12065 0.2794)
			(stroke
				(width 0.1)
				(type default)
			)
			(layer "F.Fab")
		)
		(fp_line
			(start -0.12065 -0.2794)
			(end 0.12065 -0.2794)
			(stroke
				(width 0.1)
				(type default)
			)
			(layer "F.Fab")
		)
		(fp_line
			(start 0.12065 -0.2794)
			(end 0.12065 -0.3048)
			(stroke
				(width 0.1)
				(type default)
			)
			(layer "F.Fab")
		)
		(fp_line
			(start 0.12065 -0.3048)
			(end 0.67945 -0.3048)
			(stroke
				(width 0.1)
				(type default)
			)
			(layer "F.Fab")
		)
		(fp_line
			(start 0.67945 -0.3048)
			(end 0.67945 0.3048)
			(stroke
				(width 0.1)
				(type default)
			)
			(layer "F.Fab")
		)
		(fp_line
			(start -0.67945 -0.305054)
			(end -0.12065 -0.305054)
			(stroke
				(width 0.1)
				(type default)
			)
			(layer "F.Fab")
		)
		(fp_line
			(start -0.12065 -0.305054)
			(end -0.12065 -0.2794)
			(stroke
				(width 0.1)
				(type default)
			)
			(layer "F.Fab")
		)
		(pad "1" smd circle
			(at -0.40005 0 270)
			(size 0 0)
			(layers "F.Cu" "F.Mask" "F.Paste")
			(net "P12V_AUX_UV_TRIGGER")
		)
		(pad "2" smd circle
			(at 0.40005 0 270)
			(size 0 0)
			(layers "F.Cu" "F.Mask" "F.Paste")
			(net "GND")
		)
	)
	(footprint ""
		(layer "F.Cu")
		(at 241.314986 -107.771692 180)
		(property "Reference" "R1012"
			(at 0 0 180)
			(layer "F.SilkS")
			(hide yes)
			(effects
				(font
					(size 1.27 1.27)
				)
			)
		)
		(property "Value" ""
			(at 0 0 180)
			(layer "F.Fab")
			(effects
				(font
					(size 1.27 1.27)
				)
			)
		)
		(duplicate_pad_numbers_are_jumpers no)
		(fp_line
			(start 0.7874 0.4064)
			(end -0.7874 0.4064)
			(stroke
				(width 0.1524)
				(type default)
			)
			(layer "F.SilkS")
		)
		(fp_line
			(start 0.7874 -0.4064)
			(end 0.7874 0.4064)
			(stroke
				(width 0.1524)
				(type default)
			)
			(layer "F.SilkS")
		)
		(fp_line
			(start -0.7874 0.4064)
			(end -0.7874 -0.4064)
			(stroke
				(width 0.1524)
				(type default)
			)
			(layer "F.SilkS")
		)
		(fp_line
			(start -0.7874 -0.4064)
			(end 0.7874 -0.4064)
			(stroke
				(width 0.1524)
				(type default)
			)
			(layer "F.SilkS")
		)
		(fp_line
			(start 0.67945 0.3048)
			(end 0.120396 0.3048)
			(stroke
				(width 0.1)
				(type default)
			)
			(layer "F.Fab")
		)
		(fp_line
			(start 0.67945 -0.3048)
			(end 0.67945 0.3048)
			(stroke
				(width 0.1)
				(type default)
			)
			(layer "F.Fab")
		)
		(fp_line
			(start 0.12065 -0.2794)
			(end 0.12065 -0.3048)
			(stroke
				(width 0.1)
				(type default)
			)
			(layer "F.Fab")
		)
		(fp_line
			(start 0.12065 -0.3048)
			(end 0.67945 -0.3048)
			(stroke
				(width 0.1)
				(type default)
			)
			(layer "F.Fab")
		)
		(fp_line
			(start 0.120396 0.3048)
			(end 0.120396 0.2794)
			(stroke
				(width 0.1)
				(type default)
			)
			(layer "F.Fab")
		)
		(fp_line
			(start 0.120396 0.2794)
			(end -0.12065 0.2794)
			(stroke
				(width 0.1)
				(type default)
			)
			(layer "F.Fab")
		)
		(fp_line
			(start -0.12065 0.3048)
			(end -0.67945 0.3048)
			(stroke
				(width 0.1)
				(type default)
			)
			(layer "F.Fab")
		)
		(fp_line
			(start -0.12065 0.2794)
			(end -0.12065 0.3048)
			(stroke
				(width 0.1)
				(type default)
			)
			(layer "F.Fab")
		)
		(fp_line
			(start -0.12065 -0.2794)
			(end 0.12065 -0.2794)
			(stroke
				(width 0.1)
				(type default)
			)
			(layer "F.Fab")
		)
		(fp_line
			(start -0.12065 -0.305054)
			(end -0.12065 -0.2794)
			(stroke
				(width 0.1)
				(type default)
			)
			(layer "F.Fab")
		)
		(fp_line
			(start -0.67945 0.3048)
			(end -0.67945 -0.305054)
			(stroke
				(width 0.1)
				(type default)
			)
			(layer "F.Fab")
		)
		(fp_line
			(start -0.67945 -0.305054)
			(end -0.12065 -0.305054)
			(stroke
				(width 0.1)
				(type default)
			)
			(layer "F.Fab")
		)
		(pad "1" smd circle
			(at -0.40005 0 180)
			(size 0 0)
			(layers "F.Cu" "F.Mask" "F.Paste")
			(net "CLK_25M_CK440_CPU0_DP")
		)
		(pad "2" smd circle
			(at 0.40005 0 180)
			(size 0 0)
			(layers "F.Cu" "F.Mask" "F.Paste")
			(net "CLK_25M_CK440_CPU0_R_DP")
		)
	)
	(footprint ""
		(layer "F.Cu")
		(at 349.014034 -69.13118)
		(property "Reference" "C148"
			(at 0 0 0)
			(layer "F.SilkS")
			(hide yes)
			(effects
				(font
					(size 1.27 1.27)
				)
			)
		)
		(property "Value" ""
			(at 0 0 0)
			(layer "F.Fab")
			(effects
				(font
					(size 1.27 1.27)
				)
			)
		)
		(duplicate_pad_numbers_are_jumpers no)
		(fp_line
			(start -0.299974 -0.150114)
			(end 0.299974 -0.150114)
			(stroke
				(width 0.1)
				(type default)
			)
			(layer "F.Fab")
		)
		(fp_line
			(start -0.299974 0.150114)
			(end -0.299974 -0.150114)
			(stroke
				(width 0.1)
				(type default)
			)
			(layer "F.Fab")
		)
		(fp_line
			(start 0.299974 -0.150114)
			(end 0.299974 0.150114)
			(stroke
				(width 0.1)
				(type default)
			)
			(layer "F.Fab")
		)
		(fp_line
			(start 0.299974 0.150114)
			(end -0.299974 0.150114)
			(stroke
				(width 0.1)
				(type default)
			)
			(layer "F.Fab")
		)
		(pad "1" smd rect
			(at -0.2667 0)
			(size 0.3048 0.381)
			(layers "F.Cu" "F.Mask" "F.Paste")
			(net "DMI_CPU0_PCH_TX_C_DP<3>")
		)
		(pad "2" smd rect
			(at 0.2667 0)
			(size 0.3048 0.381)
			(layers "F.Cu" "F.Mask" "F.Paste")
			(net "DMI_CPU0_PCH_TX_DP<3>")
		)
		(zone
			(layer "In1.Cu")
			(hatch none 0.5)
			(connect_pads
				(clearance 0)
			)
			(min_thickness 0.25)
			(keepout
				(tracks not_allowed)
				(vias allowed)
				(pads allowed)
				(copperpour not_allowed)
				(footprints allowed)
			)
			(placement
				(enabled no)
				(sheetname "")
			)
			(fill
				(thermal_gap 0.5)
				(thermal_bridge_width 0.5)
				(island_removal_mode 0)
			)
			(polygon
				(pts
					(arc
						(start 348.620334 -68.88988)
						(mid 348.566452 -68.912198)
						(end 348.544134 -68.96608)
					)
					(arc
						(start 348.544134 -69.29628)
						(mid 348.566452 -69.350162)
						(end 348.620334 -69.37248)
					)
					(arc
						(start 348.874334 -69.37248)
						(mid 348.928216 -69.350162)
						(end 348.950534 -69.29628)
					)
					(arc
						(start 348.950534 -68.96608)
						(mid 348.928216 -68.912198)
						(end 348.874334 -68.88988)
					)
				)
			)
		)
		(zone
			(layer "In1.Cu")
			(hatch none 0.5)
			(connect_pads
				(clearance 0)
			)
			(min_thickness 0.25)
			(keepout
				(tracks not_allowed)
				(vias allowed)
				(pads allowed)
				(copperpour not_allowed)
				(footprints allowed)
			)
			(placement
				(enabled no)
				(sheetname "")
			)
			(fill
				(thermal_gap 0.5)
				(thermal_bridge_width 0.5)
				(island_removal_mode 0)
			)
			(polygon
				(pts
					(arc
						(start 349.153734 -68.88988)
						(mid 349.099852 -68.912198)
						(end 349.077534 -68.96608)
					)
					(arc
						(start 349.077534 -69.29628)
						(mid 349.099852 -69.350162)
						(end 349.153734 -69.37248)
					)
					(arc
						(start 349.407734 -69.37248)
						(mid 349.461616 -69.350162)
						(end 349.483934 -69.29628)
					)
					(arc
						(start 349.483934 -68.96608)
						(mid 349.461616 -68.912198)
						(end 349.407734 -68.88988)
					)
				)
			)
		)
	)
	(footprint ""
		(layer "F.Cu")
		(at 435.621176 -103.77043 90)
		(property "Reference" "PC2144"
			(at 0 0 90)
			(layer "F.SilkS")
			(hide yes)
			(effects
				(font
					(size 1.27 1.27)
				)
			)
		)
		(property "Value" ""
			(at 0 0 90)
			(layer "F.Fab")
			(effects
				(font
					(size 1.27 1.27)
				)
			)
		)
		(duplicate_pad_numbers_are_jumpers no)
		(fp_line
			(start 0.7874 -0.4064)
			(end 0.7874 0.4064)
			(stroke
				(width 0.1524)
				(type default)
			)
			(layer "F.SilkS")
		)
		(fp_line
			(start -0.7874 -0.4064)
			(end 0.7874 -0.4064)
			(stroke
				(width 0.1524)
				(type default)
			)
			(layer "F.SilkS")
		)
		(fp_line
			(start 0.7874 0.4064)
			(end -0.7874 0.4064)
			(stroke
				(width 0.1524)
				(type default)
			)
			(layer "F.SilkS")
		)
		(fp_line
			(start -0.7874 0.4064)
			(end -0.7874 -0.4064)
			(stroke
				(width 0.1524)
				(type default)
			)
			(layer "F.SilkS")
		)
		(fp_line
			(start -0.12065 -0.305054)
			(end -0.12065 -0.2794)
			(stroke
				(width 0.1)
				(type default)
			)
			(layer "F.Fab")
		)
		(fp_line
			(start -0.67945 -0.305054)
			(end -0.12065 -0.305054)
			(stroke
				(width 0.1)
				(type default)
			)
			(layer "F.Fab")
		)
		(fp_line
			(start 0.67945 -0.3048)
			(end 0.67945 0.3048)
			(stroke
				(width 0.1)
				(type default)
			)
			(layer "F.Fab")
		)
		(fp_line
			(start 0.12065 -0.3048)
			(end 0.67945 -0.3048)
			(stroke
				(width 0.1)
				(type default)
			)
			(layer "F.Fab")
		)
		(fp_line
			(start 0.12065 -0.2794)
			(end 0.12065 -0.3048)
			(stroke
				(width 0.1)
				(type default)
			)
			(layer "F.Fab")
		)
		(fp_line
			(start -0.12065 -0.2794)
			(end 0.12065 -0.2794)
			(stroke
				(width 0.1)
				(type default)
			)
			(layer "F.Fab")
		)
		(fp_line
			(start 0.120396 0.2794)
			(end -0.12065 0.2794)
			(stroke
				(width 0.1)
				(type default)
			)
			(layer "F.Fab")
		)
		(fp_line
			(start -0.12065 0.2794)
			(end -0.12065 0.3048)
			(stroke
				(width 0.1)
				(type default)
			)
			(layer "F.Fab")
		)
		(fp_line
			(start 0.67945 0.3048)
			(end 0.120396 0.3048)
			(stroke
				(width 0.1)
				(type default)
			)
			(layer "F.Fab")
		)
		(fp_line
			(start 0.120396 0.3048)
			(end 0.120396 0.2794)
			(stroke
				(width 0.1)
				(type default)
			)
			(layer "F.Fab")
		)
		(fp_line
			(start -0.12065 0.3048)
			(end -0.67945 0.3048)
			(stroke
				(width 0.1)
				(type default)
			)
			(layer "F.Fab")
		)
		(fp_line
			(start -0.67945 0.3048)
			(end -0.67945 -0.305054)
			(stroke
				(width 0.1)
				(type default)
			)
			(layer "F.Fab")
		)
		(pad "1" smd circle
			(at -0.40005 0 90)
			(size 0 0)
			(layers "F.Cu" "F.Mask" "F.Paste")
			(net "P3V3_OCP_SFF_R")
		)
		(pad "2" smd circle
			(at 0.40005 0 90)
			(size 0 0)
			(layers "F.Cu" "F.Mask" "F.Paste")
			(net "P3V3_OCP_GATE_PU202_1")
		)
	)
	(footprint ""
		(layer "F.Cu")
		(at 440.384438 -14.593316 180)
		(property "Reference" "PC2092"
			(at 0 0 180)
			(layer "F.SilkS")
			(hide yes)
			(effects
				(font
					(size 1.27 1.27)
				)
			)
		)
		(property "Value" ""
			(at 0 0 180)
			(layer "F.Fab")
			(effects
				(font
					(size 1.27 1.27)
				)
			)
		)
		(duplicate_pad_numbers_are_jumpers no)
		(fp_line
			(start 0.7874 0.4064)
			(end -0.7874 0.4064)
			(stroke
				(width 0.1524)
				(type default)
			)
			(layer "F.SilkS")
		)
		(fp_line
			(start 0.7874 -0.4064)
			(end 0.7874 0.4064)
			(stroke
				(width 0.1524)
				(type default)
			)
			(layer "F.SilkS")
		)
		(fp_line
			(start -0.7874 0.4064)
			(end -0.7874 -0.4064)
			(stroke
				(width 0.1524)
				(type default)
			)
			(layer "F.SilkS")
		)
		(fp_line
			(start -0.7874 -0.4064)
			(end 0.7874 -0.4064)
			(stroke
				(width 0.1524)
				(type default)
			)
			(layer "F.SilkS")
		)
		(fp_line
			(start 0.67945 0.3048)
			(end 0.120396 0.3048)
			(stroke
				(width 0.1)
				(type default)
			)
			(layer "F.Fab")
		)
		(fp_line
			(start 0.67945 -0.3048)
			(end 0.67945 0.3048)
			(stroke
				(width 0.1)
				(type default)
			)
			(layer "F.Fab")
		)
		(fp_line
			(start 0.12065 -0.2794)
			(end 0.12065 -0.3048)
			(stroke
				(width 0.1)
				(type default)
			)
			(layer "F.Fab")
		)
		(fp_line
			(start 0.12065 -0.3048)
			(end 0.67945 -0.3048)
			(stroke
				(width 0.1)
				(type default)
			)
			(layer "F.Fab")
		)
		(fp_line
			(start 0.120396 0.3048)
			(end 0.120396 0.2794)
			(stroke
				(width 0.1)
				(type default)
			)
			(layer "F.Fab")
		)
		(fp_line
			(start 0.120396 0.2794)
			(end -0.12065 0.2794)
			(stroke
				(width 0.1)
				(type default)
			)
			(layer "F.Fab")
		)
		(fp_line
			(start -0.12065 0.3048)
			(end -0.67945 0.3048)
			(stroke
				(width 0.1)
				(type default)
			)
			(layer "F.Fab")
		)
		(fp_line
			(start -0.12065 0.2794)
			(end -0.12065 0.3048)
			(stroke
				(width 0.1)
				(type default)
			)
			(layer "F.Fab")
		)
		(fp_line
			(start -0.12065 -0.2794)
			(end 0.12065 -0.2794)
			(stroke
				(width 0.1)
				(type default)
			)
			(layer "F.Fab")
		)
		(fp_line
			(start -0.12065 -0.305054)
			(end -0.12065 -0.2794)
			(stroke
				(width 0.1)
				(type default)
			)
			(layer "F.Fab")
		)
		(fp_line
			(start -0.67945 0.3048)
			(end -0.67945 -0.305054)
			(stroke
				(width 0.1)
				(type default)
			)
			(layer "F.Fab")
		)
		(fp_line
			(start -0.67945 -0.305054)
			(end -0.12065 -0.305054)
			(stroke
				(width 0.1)
				(type default)
			)
			(layer "F.Fab")
		)
		(pad "1" smd circle
			(at -0.40005 0 180)
			(size 0 0)
			(layers "F.Cu" "F.Mask" "F.Paste")
			(net "P12V_OCP_SFF")
		)
		(pad "2" smd circle
			(at 0.40005 0 180)
			(size 0 0)
			(layers "F.Cu" "F.Mask" "F.Paste")
			(net "GND")
		)
	)
	(footprint ""
		(layer "F.Cu")
		(at 295.849548 -258.091686)
		(property "Reference" "J4"
			(at -3.683 -81.702148 0)
			(unlocked yes)
			(layer "F.SilkS")
			(effects
				(font
					(size 0.7874 0.5842)
					(thickness 0.1524)
				)
				(justify left)
			)
		)
		(property "Value" ""
			(at 0 0 0)
			(layer "F.Fab")
			(effects
				(font
					(size 1.27 1.27)
				)
			)
		)
		(duplicate_pad_numbers_are_jumpers no)
		(fp_line
			(start -3.24993 -81.000092)
			(end -3.24993 81.000092)
			(stroke
				(width 0.1524)
				(type default)
			)
			(layer "F.SilkS")
		)
		(fp_line
			(start -3.24993 81.000092)
			(end 3.24993 81.000092)
			(stroke
				(width 0.1524)
				(type default)
			)
			(layer "F.SilkS")
		)
		(fp_line
			(start 3.24993 -81.000092)
			(end -3.24993 -81.000092)
			(stroke
				(width 0.1524)
				(type default)
			)
			(layer "F.SilkS")
		)
		(fp_line
			(start 3.24993 -72.00011)
			(end -3.24993 -72.00011)
			(stroke
				(width 0.1524)
				(type default)
			)
			(layer "F.SilkS")
		)
		(fp_line
			(start 3.24993 72.00011)
			(end -3.24993 72.00011)
			(stroke
				(width 0.1524)
				(type default)
			)
			(layer "F.SilkS")
		)
		(fp_line
			(start 3.24993 81.000092)
			(end 3.24993 -81.000092)
			(stroke
				(width 0.1524)
				(type default)
			)
			(layer "F.SilkS")
		)
		(fp_poly
			(pts
				(xy -4.209796 -63.941198) (xy -3.300476 -63.486538) (xy -4.209796 -63.031878)
			)
			(stroke
				(width 0)
				(type default)
			)
			(fill yes)
			(layer "F.SilkS")
		)
		(fp_line
			(start -3.24993 -81.000092)
			(end -3.24993 81.000092)
			(stroke
				(width 0.1)
				(type default)
			)
			(layer "F.Fab")
		)
		(fp_line
			(start -3.24993 81.000092)
			(end 3.24993 81.000092)
			(stroke
				(width 0.1)
				(type default)
			)
			(layer "F.Fab")
		)
		(fp_line
			(start 3.24993 -81.000092)
			(end -3.24993 -81.000092)
			(stroke
				(width 0.1)
				(type default)
			)
			(layer "F.Fab")
		)
		(fp_line
			(start 3.24993 -72.00011)
			(end -3.24993 -72.00011)
			(stroke
				(width 0.1)
				(type default)
			)
			(layer "F.Fab")
		)
		(fp_line
			(start 3.24993 -71.000112)
			(end -3.24993 -71.000112)
			(stroke
				(width 0.1)
				(type default)
			)
			(layer "F.Fab")
		)
		(fp_line
			(start 3.24993 71.000112)
			(end -3.24993 71.000112)
			(stroke
				(width 0.1)
				(type default)
			)
			(layer "F.Fab")
		)
		(fp_line
			(start 3.24993 72.00011)
			(end -3.24993 72.00011)
			(stroke
				(width 0.1)
				(type default)
			)
			(layer "F.Fab")
		)
		(fp_line
			(start 3.24993 81.000092)
			(end 3.24993 -81.000092)
			(stroke
				(width 0.1)
				(type default)
			)
			(layer "F.Fab")
		)
		(fp_poly
			(pts
				(xy -4.445 -63.832994) (xy -4.445 -62.816994) (xy -3.429 -63.324994)
			)
			(stroke
				(width 0)
				(type default)
			)
			(fill yes)
			(layer "F.Fab")
		)
		(pad "1" smd rect
			(at -2.050034 -63.324994 270)
			(size 0.519938 1.4986)
			(layers "F.Cu" "F.Mask" "F.Paste")
			(net "P12V_S3_AUX_CPU0_NVDIMM")
		)
		(pad "2" smd rect
			(at -2.050034 -62.47511 270)
			(size 0.519938 1.4986)
			(layers "F.Cu" "F.Mask" "F.Paste")
			(net "TP_CHB_CPU0_DIMM2_FRU_0")
		)
		(pad "3" smd rect
			(at -2.050034 -61.624972 270)
			(size 0.519938 1.4986)
			(layers "F.Cu" "F.Mask" "F.Paste")
			(net "P3V3_AUX")
		)
		(pad "4" smd rect
			(at -2.050034 -60.775088 270)
			(size 0.519938 1.4986)
			(layers "F.Cu" "F.Mask" "F.Paste")
			(net "I3C_SPD_DDRABCD_CPU0_LVC1_SCL_3")
		)
		(pad "5" smd rect
			(at -2.050034 -59.92495 270)
			(size 0.519938 1.4986)
			(layers "F.Cu" "F.Mask" "F.Paste")
			(net "I3C_SPD_DDRABCD_CPU0_LVC1_SDA")
		)
		(pad "6" smd rect
			(at -2.050034 -59.075066 270)
			(size 0.519938 1.4986)
			(layers "F.Cu" "F.Mask" "F.Paste")
			(net "GND")
		)
		(pad "7" smd rect
			(at -2.050034 -58.224928 270)
			(size 0.519938 1.4986)
			(layers "F.Cu" "F.Mask" "F.Paste")
			(net "M_B_CPU0_SA_DQ<0>")
		)
		(pad "8" smd rect
			(at -2.050034 -57.375044 270)
			(size 0.519938 1.4986)
			(layers "F.Cu" "F.Mask" "F.Paste")
			(net "GND")
		)
		(pad "9" smd rect
			(at -2.050034 -56.524906 270)
			(size 0.519938 1.4986)
			(layers "F.Cu" "F.Mask" "F.Paste")
			(net "M_B_CPU0_SA_DQ<1>")
		)
		(pad "10" smd rect
			(at -2.050034 -55.675022 270)
			(size 0.519938 1.4986)
			(layers "F.Cu" "F.Mask" "F.Paste")
			(net "GND")
		)
		(pad "11" smd rect
			(at -2.050034 -54.824884 270)
			(size 0.519938 1.4986)
			(layers "F.Cu" "F.Mask" "F.Paste")
			(net "M_B_CPU0_SA_DQS_DP<0>")
		)
		(pad "12" smd rect
			(at -2.050034 -53.975 270)
			(size 0.519938 1.4986)
			(layers "F.Cu" "F.Mask" "F.Paste")
			(net "M_B_CPU0_SA_DQS_DN<0>")
		)
		(pad "13" smd rect
			(at -2.050034 -53.125116 270)
			(size 0.519938 1.4986)
			(layers "F.Cu" "F.Mask" "F.Paste")
			(net "GND")
		)
		(pad "14" smd rect
			(at -2.050034 -52.274978 270)
			(size 0.519938 1.4986)
			(layers "F.Cu" "F.Mask" "F.Paste")
			(net "M_B_CPU0_SA_DQ<4>")
		)
		(pad "15" smd rect
			(at -2.050034 -51.425094 270)
			(size 0.519938 1.4986)
			(layers "F.Cu" "F.Mask" "F.Paste")
			(net "GND")
		)
		(pad "16" smd rect
			(at -2.050034 -50.574956 270)
			(size 0.519938 1.4986)
			(layers "F.Cu" "F.Mask" "F.Paste")
			(net "M_B_CPU0_SA_DQ<5>")
		)
		(pad "17" smd rect
			(at -2.050034 -49.725072 270)
			(size 0.519938 1.4986)
			(layers "F.Cu" "F.Mask" "F.Paste")
			(net "GND")
		)
		(pad "18" smd rect
			(at -2.050034 -48.874934 270)
			(size 0.519938 1.4986)
			(layers "F.Cu" "F.Mask" "F.Paste")
			(net "M_B_CPU0_SA_DQ<8>")
		)
		(pad "19" smd rect
			(at -2.050034 -48.02505 270)
			(size 0.519938 1.4986)
			(layers "F.Cu" "F.Mask" "F.Paste")
			(net "GND")
		)
		(pad "20" smd rect
			(at -2.050034 -47.174912 270)
			(size 0.519938 1.4986)
			(layers "F.Cu" "F.Mask" "F.Paste")
			(net "M_B_CPU0_SA_DQ<9>")
		)
		(pad "21" smd rect
			(at -2.050034 -46.325028 270)
			(size 0.519938 1.4986)
			(layers "F.Cu" "F.Mask" "F.Paste")
			(net "GND")
		)
		(pad "22" smd rect
			(at -2.050034 -45.47489 270)
			(size 0.519938 1.4986)
			(layers "F.Cu" "F.Mask" "F.Paste")
			(net "M_B_CPU0_SA_DQS_DP<1>")
		)
		(pad "23" smd rect
			(at -2.050034 -44.625006 270)
			(size 0.519938 1.4986)
			(layers "F.Cu" "F.Mask" "F.Paste")
			(net "M_B_CPU0_SA_DQS_DN<1>")
		)
		(pad "24" smd rect
			(at -2.050034 -43.775122 270)
			(size 0.519938 1.4986)
			(layers "F.Cu" "F.Mask" "F.Paste")
			(net "GND")
		)
		(pad "25" smd rect
			(at -2.050034 -42.924984 270)
			(size 0.519938 1.4986)
			(layers "F.Cu" "F.Mask" "F.Paste")
			(net "M_B_CPU0_SA_DQ<12>")
		)
		(pad "26" smd rect
			(at -2.050034 -42.0751 270)
			(size 0.519938 1.4986)
			(layers "F.Cu" "F.Mask" "F.Paste")
			(net "GND")
		)
		(pad "27" smd rect
			(at -2.050034 -41.224962 270)
			(size 0.519938 1.4986)
			(layers "F.Cu" "F.Mask" "F.Paste")
			(net "M_B_CPU0_SA_DQ<13>")
		)
		(pad "28" smd rect
			(at -2.050034 -40.375078 270)
			(size 0.519938 1.4986)
			(layers "F.Cu" "F.Mask" "F.Paste")
			(net "GND")
		)
		(pad "29" smd rect
			(at -2.050034 -39.52494 270)
			(size 0.519938 1.4986)
			(layers "F.Cu" "F.Mask" "F.Paste")
			(net "M_B_CPU0_SA_DQ<16>")
		)
		(pad "30" smd rect
			(at -2.050034 -38.675056 270)
			(size 0.519938 1.4986)
			(layers "F.Cu" "F.Mask" "F.Paste")
			(net "GND")
		)
		(pad "31" smd rect
			(at -2.050034 -37.824918 270)
			(size 0.519938 1.4986)
			(layers "F.Cu" "F.Mask" "F.Paste")
			(net "M_B_CPU0_SA_DQ<17>")
		)
		(pad "32" smd rect
			(at -2.050034 -36.975034 270)
			(size 0.519938 1.4986)
			(layers "F.Cu" "F.Mask" "F.Paste")
			(net "GND")
		)
		(pad "33" smd rect
			(at -2.050034 -36.124896 270)
			(size 0.519938 1.4986)
			(layers "F.Cu" "F.Mask" "F.Paste")
			(net "M_B_CPU0_SA_DQS_DP<2>")
		)
		(pad "34" smd rect
			(at -2.050034 -35.275012 270)
			(size 0.519938 1.4986)
			(layers "F.Cu" "F.Mask" "F.Paste")
			(net "M_B_CPU0_SA_DQS_DN<2>")
		)
		(pad "35" smd rect
			(at -2.050034 -34.425128 270)
			(size 0.519938 1.4986)
			(layers "F.Cu" "F.Mask" "F.Paste")
			(net "GND")
		)
		(pad "36" smd rect
			(at -2.050034 -33.57499 270)
			(size 0.519938 1.4986)
			(layers "F.Cu" "F.Mask" "F.Paste")
			(net "M_B_CPU0_SA_DQ<20>")
		)
		(pad "37" smd rect
			(at -2.050034 -32.725106 270)
			(size 0.519938 1.4986)
			(layers "F.Cu" "F.Mask" "F.Paste")
			(net "GND")
		)
		(pad "38" smd rect
			(at -2.050034 -31.874968 270)
			(size 0.519938 1.4986)
			(layers "F.Cu" "F.Mask" "F.Paste")
			(net "M_B_CPU0_SA_DQ<21>")
		)
		(pad "39" smd rect
			(at -2.050034 -31.025084 270)
			(size 0.519938 1.4986)
			(layers "F.Cu" "F.Mask" "F.Paste")
			(net "GND")
		)
		(pad "40" smd rect
			(at -2.050034 -30.174946 270)
			(size 0.519938 1.4986)
			(layers "F.Cu" "F.Mask" "F.Paste")
			(net "M_B_CPU0_SA_DQ<24>")
		)
		(pad "41" smd rect
			(at -2.050034 -29.325062 270)
			(size 0.519938 1.4986)
			(layers "F.Cu" "F.Mask" "F.Paste")
			(net "GND")
		)
		(pad "42" smd rect
			(at -2.050034 -28.474924 270)
			(size 0.519938 1.4986)
			(layers "F.Cu" "F.Mask" "F.Paste")
			(net "M_B_CPU0_SA_DQ<25>")
		)
		(pad "43" smd rect
			(at -2.050034 -27.62504 270)
			(size 0.519938 1.4986)
			(layers "F.Cu" "F.Mask" "F.Paste")
			(net "GND")
		)
		(pad "44" smd rect
			(at -2.050034 -26.774902 270)
			(size 0.519938 1.4986)
			(layers "F.Cu" "F.Mask" "F.Paste")
			(net "M_B_CPU0_SA_DQS_DP<3>")
		)
		(pad "45" smd rect
			(at -2.050034 -25.925018 270)
			(size 0.519938 1.4986)
			(layers "F.Cu" "F.Mask" "F.Paste")
			(net "M_B_CPU0_SA_DQS_DN<3>")
		)
		(pad "46" smd rect
			(at -2.050034 -25.07488 270)
			(size 0.519938 1.4986)
			(layers "F.Cu" "F.Mask" "F.Paste")
			(net "GND")
		)
		(pad "47" smd rect
			(at -2.050034 -24.224996 270)
			(size 0.519938 1.4986)
			(layers "F.Cu" "F.Mask" "F.Paste")
			(net "M_B_CPU0_SA_DQ<28>")
		)
		(pad "48" smd rect
			(at -2.050034 -23.375112 270)
			(size 0.519938 1.4986)
			(layers "F.Cu" "F.Mask" "F.Paste")
			(net "GND")
		)
		(pad "49" smd rect
			(at -2.050034 -22.524974 270)
			(size 0.519938 1.4986)
			(layers "F.Cu" "F.Mask" "F.Paste")
			(net "M_B_CPU0_SA_DQ<29>")
		)
		(pad "50" smd rect
			(at -2.050034 -21.67509 270)
			(size 0.519938 1.4986)
			(layers "F.Cu" "F.Mask" "F.Paste")
			(net "GND")
		)
		(pad "51" smd rect
			(at -2.050034 -20.824952 270)
			(size 0.519938 1.4986)
			(layers "F.Cu" "F.Mask" "F.Paste")
			(net "M_B_CPU0_SA_CB<0>")
		)
		(pad "52" smd rect
			(at -2.050034 -19.975068 270)
			(size 0.519938 1.4986)
			(layers "F.Cu" "F.Mask" "F.Paste")
			(net "GND")
		)
		(pad "53" smd rect
			(at -2.050034 -19.12493 270)
			(size 0.519938 1.4986)
			(layers "F.Cu" "F.Mask" "F.Paste")
			(net "M_B_CPU0_SA_CB<1>")
		)
		(pad "54" smd rect
			(at -2.050034 -18.275046 270)
			(size 0.519938 1.4986)
			(layers "F.Cu" "F.Mask" "F.Paste")
			(net "GND")
		)
		(pad "55" smd rect
			(at -2.050034 -17.424908 270)
			(size 0.519938 1.4986)
			(layers "F.Cu" "F.Mask" "F.Paste")
			(net "M_B_CPU0_SA_DQS_DP<4>")
		)
		(pad "56" smd rect
			(at -2.050034 -16.575024 270)
			(size 0.519938 1.4986)
			(layers "F.Cu" "F.Mask" "F.Paste")
			(net "M_B_CPU0_SA_DQS_DN<4>")
		)
		(pad "57" smd rect
			(at -2.050034 -15.724886 270)
			(size 0.519938 1.4986)
			(layers "F.Cu" "F.Mask" "F.Paste")
			(net "GND")
		)
		(pad "58" smd rect
			(at -2.050034 -14.875002 270)
			(size 0.519938 1.4986)
			(layers "F.Cu" "F.Mask" "F.Paste")
			(net "M_B_CPU0_SA_CB<4>")
		)
		(pad "59" smd rect
			(at -2.050034 -14.025118 270)
			(size 0.519938 1.4986)
			(layers "F.Cu" "F.Mask" "F.Paste")
			(net "GND")
		)
		(pad "60" smd rect
			(at -2.050034 -13.17498 270)
			(size 0.519938 1.4986)
			(layers "F.Cu" "F.Mask" "F.Paste")
			(net "M_B_CPU0_SA_CB<5>")
		)
		(pad "61" smd rect
			(at -2.050034 -12.325096 270)
			(size 0.519938 1.4986)
			(layers "F.Cu" "F.Mask" "F.Paste")
			(net "GND")
		)
		(pad "62" smd rect
			(at -2.050034 -11.474958 270)
			(size 0.519938 1.4986)
			(layers "F.Cu" "F.Mask" "F.Paste")
			(net "M_B_CPU0_ALERT_N")
		)
		(pad "63" smd rect
			(at -2.050034 -10.625074 270)
			(size 0.519938 1.4986)
			(layers "F.Cu" "F.Mask" "F.Paste")
			(net "GND")
		)
		(pad "64" smd rect
			(at -2.050034 -9.774936 270)
			(size 0.519938 1.4986)
			(layers "F.Cu" "F.Mask" "F.Paste")
			(net "M_B_CPU0_SA_CS_N<2>")
		)
		(pad "65" smd rect
			(at -2.050034 -8.925052 270)
			(size 0.519938 1.4986)
			(layers "F.Cu" "F.Mask" "F.Paste")
			(net "GND")
		)
		(pad "66" smd rect
			(at -2.050034 -8.074914 270)
			(size 0.519938 1.4986)
			(layers "F.Cu" "F.Mask" "F.Paste")
			(net "M_B_CPU0_SA_CA<0>")
		)
		(pad "67" smd rect
			(at -2.050034 -7.22503 270)
			(size 0.519938 1.4986)
			(layers "F.Cu" "F.Mask" "F.Paste")
			(net "GND")
		)
		(pad "68" smd rect
			(at -2.050034 -6.374892 270)
			(size 0.519938 1.4986)
			(layers "F.Cu" "F.Mask" "F.Paste")
			(net "M_B_CPU0_SA_CA<2>")
		)
		(pad "69" smd rect
			(at -2.050034 -5.525008 270)
			(size 0.519938 1.4986)
			(layers "F.Cu" "F.Mask" "F.Paste")
			(net "GND")
		)
		(pad "70" smd rect
			(at -2.050034 -4.675124 270)
			(size 0.519938 1.4986)
			(layers "F.Cu" "F.Mask" "F.Paste")
			(net "M_B_CPU0_SA_CA<4>")
		)
		(pad "71" smd rect
			(at -2.050034 -3.824986 270)
			(size 0.519938 1.4986)
			(layers "F.Cu" "F.Mask" "F.Paste")
			(net "GND")
		)
		(pad "72" smd rect
			(at -2.050034 -2.975102 270)
			(size 0.519938 1.4986)
			(layers "F.Cu" "F.Mask" "F.Paste")
			(net "M_B_CPU0_SA_CA<6>")
		)
		(pad "73" smd rect
			(at -2.050034 -2.124964 270)
			(size 0.519938 1.4986)
			(layers "F.Cu" "F.Mask" "F.Paste")
			(net "GND")
		)
		(pad "74" smd rect
			(at -2.050034 -1.27508 270)
			(size 0.519938 1.4986)
			(layers "F.Cu" "F.Mask" "F.Paste")
			(net "M_B_CPU0_SA_PAR")
		)
		(pad "75" smd rect
			(at -2.050034 -0.424942 270)
			(size 0.519938 1.4986)
			(layers "F.Cu" "F.Mask" "F.Paste")
			(net "GND")
		)
		(pad "76" smd rect
			(at -2.050034 5.525008 270)
			(size 0.519938 1.4986)
			(layers "F.Cu" "F.Mask" "F.Paste")
			(net "M_B_CPU0_SB_CA<0>")
		)
		(pad "77" smd rect
			(at -2.050034 6.374892 270)
			(size 0.519938 1.4986)
			(layers "F.Cu" "F.Mask" "F.Paste")
			(net "GND")
		)
		(pad "78" smd rect
			(at -2.050034 7.22503 270)
			(size 0.519938 1.4986)
			(layers "F.Cu" "F.Mask" "F.Paste")
			(net "M_B_CPU0_SB_CA<2>")
		)
		(pad "79" smd rect
			(at -2.050034 8.074914 270)
			(size 0.519938 1.4986)
			(layers "F.Cu" "F.Mask" "F.Paste")
			(net "GND")
		)
		(pad "80" smd rect
			(at -2.050034 8.925052 270)
			(size 0.519938 1.4986)
			(layers "F.Cu" "F.Mask" "F.Paste")
			(net "M_B_CPU0_SB_CA<4>")
		)
		(pad "81" smd rect
			(at -2.050034 9.774936 270)
			(size 0.519938 1.4986)
			(layers "F.Cu" "F.Mask" "F.Paste")
			(net "GND")
		)
		(pad "82" smd rect
			(at -2.050034 10.625074 270)
			(size 0.519938 1.4986)
			(layers "F.Cu" "F.Mask" "F.Paste")
			(net "M_B_CPU0_SB_CA<6>")
		)
		(pad "83" smd rect
			(at -2.050034 11.474958 270)
			(size 0.519938 1.4986)
			(layers "F.Cu" "F.Mask" "F.Paste")
			(net "GND")
		)
		(pad "84" smd rect
			(at -2.050034 12.325096 270)
			(size 0.519938 1.4986)
			(layers "F.Cu" "F.Mask" "F.Paste")
			(net "M_B_CPU0_SB_CS_N<2>")
		)
		(pad "85" smd rect
			(at -2.050034 13.17498 270)
			(size 0.519938 1.4986)
			(layers "F.Cu" "F.Mask" "F.Paste")
			(net "GND")
		)
		(pad "86" smd rect
			(at -2.050034 14.025118 270)
			(size 0.519938 1.4986)
			(layers "F.Cu" "F.Mask" "F.Paste")
			(net "M_B_CPU0_SA_RSP<1>")
		)
		(pad "87" smd rect
			(at -2.050034 14.875002 270)
			(size 0.519938 1.4986)
			(layers "F.Cu" "F.Mask" "F.Paste")
			(net "M_B_CPU0_SB_RSP<1>")
		)
		(pad "88" smd rect
			(at -2.050034 15.724886 270)
			(size 0.519938 1.4986)
			(layers "F.Cu" "F.Mask" "F.Paste")
			(net "GND")
		)
		(pad "89" smd rect
			(at -2.050034 16.575024 270)
			(size 0.519938 1.4986)
			(layers "F.Cu" "F.Mask" "F.Paste")
			(net "M_B_CPU0_SB_CB<4>")
		)
		(pad "90" smd rect
			(at -2.050034 17.424908 270)
			(size 0.519938 1.4986)
			(layers "F.Cu" "F.Mask" "F.Paste")
			(net "GND")
		)
		(pad "91" smd rect
			(at -2.050034 18.275046 270)
			(size 0.519938 1.4986)
			(layers "F.Cu" "F.Mask" "F.Paste")
			(net "M_B_CPU0_SB_CB<5>")
		)
		(pad "92" smd rect
			(at -2.050034 19.12493 270)
			(size 0.519938 1.4986)
			(layers "F.Cu" "F.Mask" "F.Paste")
			(net "GND")
		)
		(pad "93" smd rect
			(at -2.050034 19.975068 270)
			(size 0.519938 1.4986)
			(layers "F.Cu" "F.Mask" "F.Paste")
			(net "M_B_CPU0_SB_DQS_DP<9>")
		)
		(pad "94" smd rect
			(at -2.050034 20.824952 270)
			(size 0.519938 1.4986)
			(layers "F.Cu" "F.Mask" "F.Paste")
			(net "M_B_CPU0_SB_DQS_DN<9>")
		)
		(pad "95" smd rect
			(at -2.050034 21.67509 270)
			(size 0.519938 1.4986)
			(layers "F.Cu" "F.Mask" "F.Paste")
			(net "GND")
		)
		(pad "96" smd rect
			(at -2.050034 22.524974 270)
			(size 0.519938 1.4986)
			(layers "F.Cu" "F.Mask" "F.Paste")
			(net "M_B_CPU0_SB_CB<0>")
		)
		(pad "97" smd rect
			(at -2.050034 23.375112 270)
			(size 0.519938 1.4986)
			(layers "F.Cu" "F.Mask" "F.Paste")
			(net "GND")
		)
		(pad "98" smd rect
			(at -2.050034 24.224996 270)
			(size 0.519938 1.4986)
			(layers "F.Cu" "F.Mask" "F.Paste")
			(net "M_B_CPU0_SB_CB<1>")
		)
		(pad "99" smd rect
			(at -2.050034 25.07488 270)
			(size 0.519938 1.4986)
			(layers "F.Cu" "F.Mask" "F.Paste")
			(net "GND")
		)
		(pad "100" smd rect
			(at -2.050034 25.925018 270)
			(size 0.519938 1.4986)
			(layers "F.Cu" "F.Mask" "F.Paste")
			(net "M_B_CPU0_SB_DQ<0>")
		)
		(pad "101" smd rect
			(at -2.050034 26.774902 270)
			(size 0.519938 1.4986)
			(layers "F.Cu" "F.Mask" "F.Paste")
			(net "GND")
		)
		(pad "102" smd rect
			(at -2.050034 27.62504 270)
			(size 0.519938 1.4986)
			(layers "F.Cu" "F.Mask" "F.Paste")
			(net "M_B_CPU0_SB_DQ<1>")
		)
		(pad "103" smd rect
			(at -2.050034 28.474924 270)
			(size 0.519938 1.4986)
			(layers "F.Cu" "F.Mask" "F.Paste")
			(net "GND")
		)
		(pad "104" smd rect
			(at -2.050034 29.325062 270)
			(size 0.519938 1.4986)
			(layers "F.Cu" "F.Mask" "F.Paste")
			(net "M_B_CPU0_SB_DQS_DP<0>")
		)
		(pad "105" smd rect
			(at -2.050034 30.174946 270)
			(size 0.519938 1.4986)
			(layers "F.Cu" "F.Mask" "F.Paste")
			(net "M_B_CPU0_SB_DQS_DN<0>")
		)
		(pad "106" smd rect
			(at -2.050034 31.025084 270)
			(size 0.519938 1.4986)
			(layers "F.Cu" "F.Mask" "F.Paste")
			(net "GND")
		)
		(pad "107" smd rect
			(at -2.050034 31.874968 270)
			(size 0.519938 1.4986)
			(layers "F.Cu" "F.Mask" "F.Paste")
			(net "M_B_CPU0_SB_DQ<4>")
		)
		(pad "108" smd rect
			(at -2.050034 32.725106 270)
			(size 0.519938 1.4986)
			(layers "F.Cu" "F.Mask" "F.Paste")
			(net "GND")
		)
		(pad "109" smd rect
			(at -2.050034 33.57499 270)
			(size 0.519938 1.4986)
			(layers "F.Cu" "F.Mask" "F.Paste")
			(net "M_B_CPU0_SB_DQ<5>")
		)
		(pad "110" smd rect
			(at -2.050034 34.425128 270)
			(size 0.519938 1.4986)
			(layers "F.Cu" "F.Mask" "F.Paste")
			(net "GND")
		)
		(pad "111" smd rect
			(at -2.050034 35.275012 270)
			(size 0.519938 1.4986)
			(layers "F.Cu" "F.Mask" "F.Paste")
			(net "M_B_CPU0_SB_DQ<8>")
		)
		(pad "112" smd rect
			(at -2.050034 36.124896 270)
			(size 0.519938 1.4986)
			(layers "F.Cu" "F.Mask" "F.Paste")
			(net "GND")
		)
		(pad "113" smd rect
			(at -2.050034 36.975034 270)
			(size 0.519938 1.4986)
			(layers "F.Cu" "F.Mask" "F.Paste")
			(net "M_B_CPU0_SB_DQ<9>")
		)
		(pad "114" smd rect
			(at -2.050034 37.824918 270)
			(size 0.519938 1.4986)
			(layers "F.Cu" "F.Mask" "F.Paste")
			(net "GND")
		)
		(pad "115" smd rect
			(at -2.050034 38.675056 270)
			(size 0.519938 1.4986)
			(layers "F.Cu" "F.Mask" "F.Paste")
			(net "M_B_CPU0_SB_DQS_DP<1>")
		)
		(pad "116" smd rect
			(at -2.050034 39.52494 270)
			(size 0.519938 1.4986)
			(layers "F.Cu" "F.Mask" "F.Paste")
			(net "M_B_CPU0_SB_DQS_DN<1>")
		)
		(pad "117" smd rect
			(at -2.050034 40.375078 270)
			(size 0.519938 1.4986)
			(layers "F.Cu" "F.Mask" "F.Paste")
			(net "GND")
		)
		(pad "118" smd rect
			(at -2.050034 41.224962 270)
			(size 0.519938 1.4986)
			(layers "F.Cu" "F.Mask" "F.Paste")
			(net "M_B_CPU0_SB_DQ<12>")
		)
		(pad "119" smd rect
			(at -2.050034 42.0751 270)
			(size 0.519938 1.4986)
			(layers "F.Cu" "F.Mask" "F.Paste")
			(net "GND")
		)
		(pad "120" smd rect
			(at -2.050034 42.924984 270)
			(size 0.519938 1.4986)
			(layers "F.Cu" "F.Mask" "F.Paste")
			(net "M_B_CPU0_SB_DQ<13>")
		)
		(pad "121" smd rect
			(at -2.050034 43.775122 270)
			(size 0.519938 1.4986)
			(layers "F.Cu" "F.Mask" "F.Paste")
			(net "GND")
		)
		(pad "122" smd rect
			(at -2.050034 44.625006 270)
			(size 0.519938 1.4986)
			(layers "F.Cu" "F.Mask" "F.Paste")
			(net "M_B_CPU0_SB_DQ<16>")
		)
		(pad "123" smd rect
			(at -2.050034 45.47489 270)
			(size 0.519938 1.4986)
			(layers "F.Cu" "F.Mask" "F.Paste")
			(net "GND")
		)
		(pad "124" smd rect
			(at -2.050034 46.325028 270)
			(size 0.519938 1.4986)
			(layers "F.Cu" "F.Mask" "F.Paste")
			(net "M_B_CPU0_SB_DQ<17>")
		)
		(pad "125" smd rect
			(at -2.050034 47.174912 270)
			(size 0.519938 1.4986)
			(layers "F.Cu" "F.Mask" "F.Paste")
			(net "GND")
		)
		(pad "126" smd rect
			(at -2.050034 48.02505 270)
			(size 0.519938 1.4986)
			(layers "F.Cu" "F.Mask" "F.Paste")
			(net "M_B_CPU0_SB_DQS_DP<2>")
		)
		(pad "127" smd rect
			(at -2.050034 48.874934 270)
			(size 0.519938 1.4986)
			(layers "F.Cu" "F.Mask" "F.Paste")
			(net "M_B_CPU0_SB_DQS_DN<2>")
		)
		(pad "128" smd rect
			(at -2.050034 49.725072 270)
			(size 0.519938 1.4986)
			(layers "F.Cu" "F.Mask" "F.Paste")
			(net "GND")
		)
		(pad "129" smd rect
			(at -2.050034 50.574956 270)
			(size 0.519938 1.4986)
			(layers "F.Cu" "F.Mask" "F.Paste")
			(net "M_B_CPU0_SB_DQ<20>")
		)
		(pad "130" smd rect
			(at -2.050034 51.425094 270)
			(size 0.519938 1.4986)
			(layers "F.Cu" "F.Mask" "F.Paste")
			(net "GND")
		)
		(pad "131" smd rect
			(at -2.050034 52.274978 270)
			(size 0.519938 1.4986)
			(layers "F.Cu" "F.Mask" "F.Paste")
			(net "M_B_CPU0_SB_DQ<21>")
		)
		(pad "132" smd rect
			(at -2.050034 53.125116 270)
			(size 0.519938 1.4986)
			(layers "F.Cu" "F.Mask" "F.Paste")
			(net "GND")
		)
		(pad "133" smd rect
			(at -2.050034 53.975 270)
			(size 0.519938 1.4986)
			(layers "F.Cu" "F.Mask" "F.Paste")
			(net "M_B_CPU0_SB_DQ<24>")
		)
		(pad "134" smd rect
			(at -2.050034 54.824884 270)
			(size 0.519938 1.4986)
			(layers "F.Cu" "F.Mask" "F.Paste")
			(net "GND")
		)
		(pad "135" smd rect
			(at -2.050034 55.675022 270)
			(size 0.519938 1.4986)
			(layers "F.Cu" "F.Mask" "F.Paste")
			(net "M_B_CPU0_SB_DQ<25>")
		)
		(pad "136" smd rect
			(at -2.050034 56.524906 270)
			(size 0.519938 1.4986)
			(layers "F.Cu" "F.Mask" "F.Paste")
			(net "GND")
		)
		(pad "137" smd rect
			(at -2.050034 57.375044 270)
			(size 0.519938 1.4986)
			(layers "F.Cu" "F.Mask" "F.Paste")
			(net "M_B_CPU0_SB_DQS_DP<3>")
		)
		(pad "138" smd rect
			(at -2.050034 58.224928 270)
			(size 0.519938 1.4986)
			(layers "F.Cu" "F.Mask" "F.Paste")
			(net "M_B_CPU0_SB_DQS_DN<3>")
		)
		(pad "139" smd rect
			(at -2.050034 59.075066 270)
			(size 0.519938 1.4986)
			(layers "F.Cu" "F.Mask" "F.Paste")
			(net "GND")
		)
		(pad "140" smd rect
			(at -2.050034 59.92495 270)
			(size 0.519938 1.4986)
			(layers "F.Cu" "F.Mask" "F.Paste")
			(net "M_B_CPU0_SB_DQ<28>")
		)
		(pad "141" smd rect
			(at -2.050034 60.775088 270)
			(size 0.519938 1.4986)
			(layers "F.Cu" "F.Mask" "F.Paste")
			(net "GND")
		)
		(pad "142" smd rect
			(at -2.050034 61.624972 270)
			(size 0.519938 1.4986)
			(layers "F.Cu" "F.Mask" "F.Paste")
			(net "M_B_CPU0_SB_DQ<29>")
		)
		(pad "143" smd rect
			(at -2.050034 62.47511 270)
			(size 0.519938 1.4986)
			(layers "F.Cu" "F.Mask" "F.Paste")
			(net "GND")
		)
		(pad "144" smd rect
			(at -2.050034 63.324994 270)
			(size 0.519938 1.4986)
			(layers "F.Cu" "F.Mask" "F.Paste")
			(net "TP_CHB_CPU0_DIMM2_FRU_1")
		)
		(pad "145" smd rect
			(at 2.050034 -63.324994 270)
			(size 0.519938 1.4986)
			(layers "F.Cu" "F.Mask" "F.Paste")
			(net "P12V_S3_AUX_CPU0_NVDIMM")
		)
		(pad "146" smd rect
			(at 2.050034 -62.47511 270)
			(size 0.519938 1.4986)
			(layers "F.Cu" "F.Mask" "F.Paste")
			(net "P12V_S3_AUX_CPU0_NVDIMM")
		)
		(pad "147" smd rect
			(at 2.050034 -61.624972 270)
			(size 0.519938 1.4986)
			(layers "F.Cu" "F.Mask" "F.Paste")
			(net "PWRGD_CHB_CPU0_DIMM2")
		)
		(pad "148" smd rect
			(at 2.050034 -60.775088 270)
			(size 0.519938 1.4986)
			(layers "F.Cu" "F.Mask" "F.Paste")
			(net "PD_CHB_CPU0_DIMM2_SAA")
		)
		(pad "149" smd rect
			(at 2.050034 -59.92495 270)
			(size 0.519938 1.4986)
			(layers "F.Cu" "F.Mask" "F.Paste")
			(net "TP_CHB_CPU0_DIMM2_FRU_2")
		)
		(pad "150" smd rect
			(at 2.050034 -59.075066 270)
			(size 0.519938 1.4986)
			(layers "F.Cu" "F.Mask" "F.Paste")
			(net "TP_CHB_CPU0_DIMM2_FRU_3")
		)
		(pad "151" smd rect
			(at 2.050034 -58.224928 270)
			(size 0.519938 1.4986)
			(layers "F.Cu" "F.Mask" "F.Paste")
			(net "GND")
		)
		(pad "152" smd rect
			(at 2.050034 -57.375044 270)
			(size 0.519938 1.4986)
			(layers "F.Cu" "F.Mask" "F.Paste")
			(net "M_B_CPU0_SA_DQ<2>")
		)
		(pad "153" smd rect
			(at 2.050034 -56.524906 270)
			(size 0.519938 1.4986)
			(layers "F.Cu" "F.Mask" "F.Paste")
			(net "GND")
		)
		(pad "154" smd rect
			(at 2.050034 -55.675022 270)
			(size 0.519938 1.4986)
			(layers "F.Cu" "F.Mask" "F.Paste")
			(net "M_B_CPU0_SA_DQ<3>")
		)
		(pad "155" smd rect
			(at 2.050034 -54.824884 270)
			(size 0.519938 1.4986)
			(layers "F.Cu" "F.Mask" "F.Paste")
			(net "GND")
		)
		(pad "156" smd rect
			(at 2.050034 -53.975 270)
			(size 0.519938 1.4986)
			(layers "F.Cu" "F.Mask" "F.Paste")
			(net "M_B_CPU0_SA_DQS_DN<5>")
		)
		(pad "157" smd rect
			(at 2.050034 -53.125116 270)
			(size 0.519938 1.4986)
			(layers "F.Cu" "F.Mask" "F.Paste")
			(net "M_B_CPU0_SA_DQS_DP<5>")
		)
		(pad "158" smd rect
			(at 2.050034 -52.274978 270)
			(size 0.519938 1.4986)
			(layers "F.Cu" "F.Mask" "F.Paste")
			(net "GND")
		)
		(pad "159" smd rect
			(at 2.050034 -51.425094 270)
			(size 0.519938 1.4986)
			(layers "F.Cu" "F.Mask" "F.Paste")
			(net "M_B_CPU0_SA_DQ<6>")
		)
		(pad "160" smd rect
			(at 2.050034 -50.574956 270)
			(size 0.519938 1.4986)
			(layers "F.Cu" "F.Mask" "F.Paste")
			(net "GND")
		)
		(pad "161" smd rect
			(at 2.050034 -49.725072 270)
			(size 0.519938 1.4986)
			(layers "F.Cu" "F.Mask" "F.Paste")
			(net "M_B_CPU0_SA_DQ<7>")
		)
		(pad "162" smd rect
			(at 2.050034 -48.874934 270)
			(size 0.519938 1.4986)
			(layers "F.Cu" "F.Mask" "F.Paste")
			(net "GND")
		)
		(pad "163" smd rect
			(at 2.050034 -48.02505 270)
			(size 0.519938 1.4986)
			(layers "F.Cu" "F.Mask" "F.Paste")
			(net "M_B_CPU0_SA_DQ<10>")
		)
		(pad "164" smd rect
			(at 2.050034 -47.174912 270)
			(size 0.519938 1.4986)
			(layers "F.Cu" "F.Mask" "F.Paste")
			(net "GND")
		)
		(pad "165" smd rect
			(at 2.050034 -46.325028 270)
			(size 0.519938 1.4986)
			(layers "F.Cu" "F.Mask" "F.Paste")
			(net "M_B_CPU0_SA_DQ<11>")
		)
		(pad "166" smd rect
			(at 2.050034 -45.47489 270)
			(size 0.519938 1.4986)
			(layers "F.Cu" "F.Mask" "F.Paste")
			(net "GND")
		)
		(pad "167" smd rect
			(at 2.050034 -44.625006 270)
			(size 0.519938 1.4986)
			(layers "F.Cu" "F.Mask" "F.Paste")
			(net "M_B_CPU0_SA_DQS_DN<6>")
		)
		(pad "168" smd rect
			(at 2.050034 -43.775122 270)
			(size 0.519938 1.4986)
			(layers "F.Cu" "F.Mask" "F.Paste")
			(net "M_B_CPU0_SA_DQS_DP<6>")
		)
		(pad "169" smd rect
			(at 2.050034 -42.924984 270)
			(size 0.519938 1.4986)
			(layers "F.Cu" "F.Mask" "F.Paste")
			(net "GND")
		)
		(pad "170" smd rect
			(at 2.050034 -42.0751 270)
			(size 0.519938 1.4986)
			(layers "F.Cu" "F.Mask" "F.Paste")
			(net "M_B_CPU0_SA_DQ<14>")
		)
		(pad "171" smd rect
			(at 2.050034 -41.224962 270)
			(size 0.519938 1.4986)
			(layers "F.Cu" "F.Mask" "F.Paste")
			(net "GND")
		)
		(pad "172" smd rect
			(at 2.050034 -40.375078 270)
			(size 0.519938 1.4986)
			(layers "F.Cu" "F.Mask" "F.Paste")
			(net "M_B_CPU0_SA_DQ<15>")
		)
		(pad "173" smd rect
			(at 2.050034 -39.52494 270)
			(size 0.519938 1.4986)
			(layers "F.Cu" "F.Mask" "F.Paste")
			(net "GND")
		)
		(pad "174" smd rect
			(at 2.050034 -38.675056 270)
			(size 0.519938 1.4986)
			(layers "F.Cu" "F.Mask" "F.Paste")
			(net "M_B_CPU0_SA_DQ<18>")
		)
		(pad "175" smd rect
			(at 2.050034 -37.824918 270)
			(size 0.519938 1.4986)
			(layers "F.Cu" "F.Mask" "F.Paste")
			(net "GND")
		)
		(pad "176" smd rect
			(at 2.050034 -36.975034 270)
			(size 0.519938 1.4986)
			(layers "F.Cu" "F.Mask" "F.Paste")
			(net "M_B_CPU0_SA_DQ<19>")
		)
		(pad "177" smd rect
			(at 2.050034 -36.124896 270)
			(size 0.519938 1.4986)
			(layers "F.Cu" "F.Mask" "F.Paste")
			(net "GND")
		)
		(pad "178" smd rect
			(at 2.050034 -35.275012 270)
			(size 0.519938 1.4986)
			(layers "F.Cu" "F.Mask" "F.Paste")
			(net "M_B_CPU0_SA_DQS_DN<7>")
		)
		(pad "179" smd rect
			(at 2.050034 -34.425128 270)
			(size 0.519938 1.4986)
			(layers "F.Cu" "F.Mask" "F.Paste")
			(net "M_B_CPU0_SA_DQS_DP<7>")
		)
		(pad "180" smd rect
			(at 2.050034 -33.57499 270)
			(size 0.519938 1.4986)
			(layers "F.Cu" "F.Mask" "F.Paste")
			(net "GND")
		)
		(pad "181" smd rect
			(at 2.050034 -32.725106 270)
			(size 0.519938 1.4986)
			(layers "F.Cu" "F.Mask" "F.Paste")
			(net "M_B_CPU0_SA_DQ<22>")
		)
		(pad "182" smd rect
			(at 2.050034 -31.874968 270)
			(size 0.519938 1.4986)
			(layers "F.Cu" "F.Mask" "F.Paste")
			(net "GND")
		)
		(pad "183" smd rect
			(at 2.050034 -31.025084 270)
			(size 0.519938 1.4986)
			(layers "F.Cu" "F.Mask" "F.Paste")
			(net "M_B_CPU0_SA_DQ<23>")
		)
		(pad "184" smd rect
			(at 2.050034 -30.174946 270)
			(size 0.519938 1.4986)
			(layers "F.Cu" "F.Mask" "F.Paste")
			(net "GND")
		)
		(pad "185" smd rect
			(at 2.050034 -29.325062 270)
			(size 0.519938 1.4986)
			(layers "F.Cu" "F.Mask" "F.Paste")
			(net "M_B_CPU0_SA_DQ<26>")
		)
		(pad "186" smd rect
			(at 2.050034 -28.474924 270)
			(size 0.519938 1.4986)
			(layers "F.Cu" "F.Mask" "F.Paste")
			(net "GND")
		)
		(pad "187" smd rect
			(at 2.050034 -27.62504 270)
			(size 0.519938 1.4986)
			(layers "F.Cu" "F.Mask" "F.Paste")
			(net "M_B_CPU0_SA_DQ<27>")
		)
		(pad "188" smd rect
			(at 2.050034 -26.774902 270)
			(size 0.519938 1.4986)
			(layers "F.Cu" "F.Mask" "F.Paste")
			(net "GND")
		)
		(pad "189" smd rect
			(at 2.050034 -25.925018 270)
			(size 0.519938 1.4986)
			(layers "F.Cu" "F.Mask" "F.Paste")
			(net "M_B_CPU0_SA_DQS_DN<8>")
		)
		(pad "190" smd rect
			(at 2.050034 -25.07488 270)
			(size 0.519938 1.4986)
			(layers "F.Cu" "F.Mask" "F.Paste")
			(net "M_B_CPU0_SA_DQS_DP<8>")
		)
		(pad "191" smd rect
			(at 2.050034 -24.224996 270)
			(size 0.519938 1.4986)
			(layers "F.Cu" "F.Mask" "F.Paste")
			(net "GND")
		)
		(pad "192" smd rect
			(at 2.050034 -23.375112 270)
			(size 0.519938 1.4986)
			(layers "F.Cu" "F.Mask" "F.Paste")
			(net "M_B_CPU0_SA_DQ<30>")
		)
		(pad "193" smd rect
			(at 2.050034 -22.524974 270)
			(size 0.519938 1.4986)
			(layers "F.Cu" "F.Mask" "F.Paste")
			(net "GND")
		)
		(pad "194" smd rect
			(at 2.050034 -21.67509 270)
			(size 0.519938 1.4986)
			(layers "F.Cu" "F.Mask" "F.Paste")
			(net "M_B_CPU0_SA_DQ<31>")
		)
		(pad "195" smd rect
			(at 2.050034 -20.824952 270)
			(size 0.519938 1.4986)
			(layers "F.Cu" "F.Mask" "F.Paste")
			(net "GND")
		)
		(pad "196" smd rect
			(at 2.050034 -19.975068 270)
			(size 0.519938 1.4986)
			(layers "F.Cu" "F.Mask" "F.Paste")
			(net "M_B_CPU0_SA_CB<2>")
		)
		(pad "197" smd rect
			(at 2.050034 -19.12493 270)
			(size 0.519938 1.4986)
			(layers "F.Cu" "F.Mask" "F.Paste")
			(net "GND")
		)
		(pad "198" smd rect
			(at 2.050034 -18.275046 270)
			(size 0.519938 1.4986)
			(layers "F.Cu" "F.Mask" "F.Paste")
			(net "M_B_CPU0_SA_CB<3>")
		)
		(pad "199" smd rect
			(at 2.050034 -17.424908 270)
			(size 0.519938 1.4986)
			(layers "F.Cu" "F.Mask" "F.Paste")
			(net "GND")
		)
		(pad "200" smd rect
			(at 2.050034 -16.575024 270)
			(size 0.519938 1.4986)
			(layers "F.Cu" "F.Mask" "F.Paste")
			(net "M_B_CPU0_SA_DQS_DN<9>")
		)
		(pad "201" smd rect
			(at 2.050034 -15.724886 270)
			(size 0.519938 1.4986)
			(layers "F.Cu" "F.Mask" "F.Paste")
			(net "M_B_CPU0_SA_DQS_DP<9>")
		)
		(pad "202" smd rect
			(at 2.050034 -14.875002 270)
			(size 0.519938 1.4986)
			(layers "F.Cu" "F.Mask" "F.Paste")
			(net "GND")
		)
		(pad "203" smd rect
			(at 2.050034 -14.025118 270)
			(size 0.519938 1.4986)
			(layers "F.Cu" "F.Mask" "F.Paste")
			(net "M_B_CPU0_SA_CB<6>")
		)
		(pad "204" smd rect
			(at 2.050034 -13.17498 270)
			(size 0.519938 1.4986)
			(layers "F.Cu" "F.Mask" "F.Paste")
			(net "GND")
		)
		(pad "205" smd rect
			(at 2.050034 -12.325096 270)
			(size 0.519938 1.4986)
			(layers "F.Cu" "F.Mask" "F.Paste")
			(net "M_B_CPU0_SA_CB<7>")
		)
		(pad "206" smd rect
			(at 2.050034 -11.474958 270)
			(size 0.519938 1.4986)
			(layers "F.Cu" "F.Mask" "F.Paste")
			(net "GND")
		)
		(pad "207" smd rect
			(at 2.050034 -10.625074 270)
			(size 0.519938 1.4986)
			(layers "F.Cu" "F.Mask" "F.Paste")
			(net "RST_M_AB_CPU0_FPGA_N")
		)
		(pad "208" smd rect
			(at 2.050034 -9.774936 270)
			(size 0.519938 1.4986)
			(layers "F.Cu" "F.Mask" "F.Paste")
			(net "GND")
		)
		(pad "209" smd rect
			(at 2.050034 -8.925052 270)
			(size 0.519938 1.4986)
			(layers "F.Cu" "F.Mask" "F.Paste")
			(net "M_B_CPU0_SA_CS_N<3>")
		)
		(pad "210" smd rect
			(at 2.050034 -8.074914 270)
			(size 0.519938 1.4986)
			(layers "F.Cu" "F.Mask" "F.Paste")
			(net "GND")
		)
		(pad "211" smd rect
			(at 2.050034 -7.22503 270)
			(size 0.519938 1.4986)
			(layers "F.Cu" "F.Mask" "F.Paste")
			(net "M_B_CPU0_SA_CA<1>")
		)
		(pad "212" smd rect
			(at 2.050034 -6.374892 270)
			(size 0.519938 1.4986)
			(layers "F.Cu" "F.Mask" "F.Paste")
			(net "GND")
		)
		(pad "213" smd rect
			(at 2.050034 -5.525008 270)
			(size 0.519938 1.4986)
			(layers "F.Cu" "F.Mask" "F.Paste")
			(net "M_B_CPU0_SA_CA<3>")
		)
		(pad "214" smd rect
			(at 2.050034 -4.675124 270)
			(size 0.519938 1.4986)
			(layers "F.Cu" "F.Mask" "F.Paste")
			(net "GND")
		)
		(pad "215" smd rect
			(at 2.050034 -3.824986 270)
			(size 0.519938 1.4986)
			(layers "F.Cu" "F.Mask" "F.Paste")
			(net "M_B_CPU0_SA_CA<5>")
		)
		(pad "216" smd rect
			(at 2.050034 -2.975102 270)
			(size 0.519938 1.4986)
			(layers "F.Cu" "F.Mask" "F.Paste")
			(net "GND")
		)
		(pad "217" smd rect
			(at 2.050034 -2.124964 270)
			(size 0.519938 1.4986)
			(layers "F.Cu" "F.Mask" "F.Paste")
			(net "M_B_CPU0_CLK_DP<1>")
		)
		(pad "218" smd rect
			(at 2.050034 -1.27508 270)
			(size 0.519938 1.4986)
			(layers "F.Cu" "F.Mask" "F.Paste")
			(net "M_B_CPU0_CLK_DN<1>")
		)
		(pad "219" smd rect
			(at 2.050034 -0.424942 270)
			(size 0.519938 1.4986)
			(layers "F.Cu" "F.Mask" "F.Paste")
			(net "GND")
		)
		(pad "220" smd rect
			(at 2.050034 5.525008 270)
			(size 0.519938 1.4986)
			(layers "F.Cu" "F.Mask" "F.Paste")
			(net "TP_CHB_CPU0_DIMM2_FRU_4")
		)
		(pad "221" smd rect
			(at 2.050034 6.374892 270)
			(size 0.519938 1.4986)
			(layers "F.Cu" "F.Mask" "F.Paste")
			(net "M_B_CPU0_SB_CA<1>")
		)
		(pad "222" smd rect
			(at 2.050034 7.22503 270)
			(size 0.519938 1.4986)
			(layers "F.Cu" "F.Mask" "F.Paste")
			(net "GND")
		)
		(pad "223" smd rect
			(at 2.050034 8.074914 270)
			(size 0.519938 1.4986)
			(layers "F.Cu" "F.Mask" "F.Paste")
			(net "M_B_CPU0_SB_CA<3>")
		)
		(pad "224" smd rect
			(at 2.050034 8.925052 270)
			(size 0.519938 1.4986)
			(layers "F.Cu" "F.Mask" "F.Paste")
			(net "GND")
		)
		(pad "225" smd rect
			(at 2.050034 9.774936 270)
			(size 0.519938 1.4986)
			(layers "F.Cu" "F.Mask" "F.Paste")
			(net "M_B_CPU0_SB_CA<5>")
		)
		(pad "226" smd rect
			(at 2.050034 10.625074 270)
			(size 0.519938 1.4986)
			(layers "F.Cu" "F.Mask" "F.Paste")
			(net "GND")
		)
		(pad "227" smd rect
			(at 2.050034 11.474958 270)
			(size 0.519938 1.4986)
			(layers "F.Cu" "F.Mask" "F.Paste")
			(net "M_B_CPU0_SB_PAR")
		)
		(pad "228" smd rect
			(at 2.050034 12.325096 270)
			(size 0.519938 1.4986)
			(layers "F.Cu" "F.Mask" "F.Paste")
			(net "GND")
		)
		(pad "229" smd rect
			(at 2.050034 13.17498 270)
			(size 0.519938 1.4986)
			(layers "F.Cu" "F.Mask" "F.Paste")
			(net "M_B_CPU0_SB_CS_N<3>")
		)
		(pad "230" smd rect
			(at 2.050034 14.025118 270)
			(size 0.519938 1.4986)
			(layers "F.Cu" "F.Mask" "F.Paste")
			(net "GND")
		)
		(pad "231" smd rect
			(at 2.050034 14.875002 270)
			(size 0.519938 1.4986)
			(layers "F.Cu" "F.Mask" "F.Paste")
			(net "TP_CHB_CPU0_DIMM2_FRU_5")
		)
		(pad "232" smd rect
			(at 2.050034 15.724886 270)
			(size 0.519938 1.4986)
			(layers "F.Cu" "F.Mask" "F.Paste")
			(net "TP_CHB_CPU0_DIMM2_FRU_6")
		)
		(pad "233" smd rect
			(at 2.050034 16.575024 270)
			(size 0.519938 1.4986)
			(layers "F.Cu" "F.Mask" "F.Paste")
			(net "GND")
		)
		(pad "234" smd rect
			(at 2.050034 17.424908 270)
			(size 0.519938 1.4986)
			(layers "F.Cu" "F.Mask" "F.Paste")
			(net "M_B_CPU0_SB_CB<6>")
		)
		(pad "235" smd rect
			(at 2.050034 18.275046 270)
			(size 0.519938 1.4986)
			(layers "F.Cu" "F.Mask" "F.Paste")
			(net "GND")
		)
		(pad "236" smd rect
			(at 2.050034 19.12493 270)
			(size 0.519938 1.4986)
			(layers "F.Cu" "F.Mask" "F.Paste")
			(net "M_B_CPU0_SB_CB<7>")
		)
		(pad "237" smd rect
			(at 2.050034 19.975068 270)
			(size 0.519938 1.4986)
			(layers "F.Cu" "F.Mask" "F.Paste")
			(net "GND")
		)
		(pad "238" smd rect
			(at 2.050034 20.824952 270)
			(size 0.519938 1.4986)
			(layers "F.Cu" "F.Mask" "F.Paste")
			(net "M_B_CPU0_SB_DQS_DN<4>")
		)
		(pad "239" smd rect
			(at 2.050034 21.67509 270)
			(size 0.519938 1.4986)
			(layers "F.Cu" "F.Mask" "F.Paste")
			(net "M_B_CPU0_SB_DQS_DP<4>")
		)
		(pad "240" smd rect
			(at 2.050034 22.524974 270)
			(size 0.519938 1.4986)
			(layers "F.Cu" "F.Mask" "F.Paste")
			(net "GND")
		)
		(pad "241" smd rect
			(at 2.050034 23.375112 270)
			(size 0.519938 1.4986)
			(layers "F.Cu" "F.Mask" "F.Paste")
			(net "M_B_CPU0_SB_CB<2>")
		)
		(pad "242" smd rect
			(at 2.050034 24.224996 270)
			(size 0.519938 1.4986)
			(layers "F.Cu" "F.Mask" "F.Paste")
			(net "GND")
		)
		(pad "243" smd rect
			(at 2.050034 25.07488 270)
			(size 0.519938 1.4986)
			(layers "F.Cu" "F.Mask" "F.Paste")
			(net "M_B_CPU0_SB_CB<3>")
		)
		(pad "244" smd rect
			(at 2.050034 25.925018 270)
			(size 0.519938 1.4986)
			(layers "F.Cu" "F.Mask" "F.Paste")
			(net "GND")
		)
		(pad "245" smd rect
			(at 2.050034 26.774902 270)
			(size 0.519938 1.4986)
			(layers "F.Cu" "F.Mask" "F.Paste")
			(net "M_B_CPU0_SB_DQ<2>")
		)
		(pad "246" smd rect
			(at 2.050034 27.62504 270)
			(size 0.519938 1.4986)
			(layers "F.Cu" "F.Mask" "F.Paste")
			(net "GND")
		)
		(pad "247" smd rect
			(at 2.050034 28.474924 270)
			(size 0.519938 1.4986)
			(layers "F.Cu" "F.Mask" "F.Paste")
			(net "M_B_CPU0_SB_DQ<3>")
		)
		(pad "248" smd rect
			(at 2.050034 29.325062 270)
			(size 0.519938 1.4986)
			(layers "F.Cu" "F.Mask" "F.Paste")
			(net "GND")
		)
		(pad "249" smd rect
			(at 2.050034 30.174946 270)
			(size 0.519938 1.4986)
			(layers "F.Cu" "F.Mask" "F.Paste")
			(net "M_B_CPU0_SB_DQS_DN<5>")
		)
		(pad "250" smd rect
			(at 2.050034 31.025084 270)
			(size 0.519938 1.4986)
			(layers "F.Cu" "F.Mask" "F.Paste")
			(net "M_B_CPU0_SB_DQS_DP<5>")
		)
		(pad "251" smd rect
			(at 2.050034 31.874968 270)
			(size 0.519938 1.4986)
			(layers "F.Cu" "F.Mask" "F.Paste")
			(net "GND")
		)
		(pad "252" smd rect
			(at 2.050034 32.725106 270)
			(size 0.519938 1.4986)
			(layers "F.Cu" "F.Mask" "F.Paste")
			(net "M_B_CPU0_SB_DQ<6>")
		)
		(pad "253" smd rect
			(at 2.050034 33.57499 270)
			(size 0.519938 1.4986)
			(layers "F.Cu" "F.Mask" "F.Paste")
			(net "GND")
		)
		(pad "254" smd rect
			(at 2.050034 34.425128 270)
			(size 0.519938 1.4986)
			(layers "F.Cu" "F.Mask" "F.Paste")
			(net "M_B_CPU0_SB_DQ<7>")
		)
		(pad "255" smd rect
			(at 2.050034 35.275012 270)
			(size 0.519938 1.4986)
			(layers "F.Cu" "F.Mask" "F.Paste")
			(net "GND")
		)
		(pad "256" smd rect
			(at 2.050034 36.124896 270)
			(size 0.519938 1.4986)
			(layers "F.Cu" "F.Mask" "F.Paste")
			(net "M_B_CPU0_SB_DQ<10>")
		)
		(pad "257" smd rect
			(at 2.050034 36.975034 270)
			(size 0.519938 1.4986)
			(layers "F.Cu" "F.Mask" "F.Paste")
			(net "GND")
		)
		(pad "258" smd rect
			(at 2.050034 37.824918 270)
			(size 0.519938 1.4986)
			(layers "F.Cu" "F.Mask" "F.Paste")
			(net "M_B_CPU0_SB_DQ<11>")
		)
		(pad "259" smd rect
			(at 2.050034 38.675056 270)
			(size 0.519938 1.4986)
			(layers "F.Cu" "F.Mask" "F.Paste")
			(net "GND")
		)
		(pad "260" smd rect
			(at 2.050034 39.52494 270)
			(size 0.519938 1.4986)
			(layers "F.Cu" "F.Mask" "F.Paste")
			(net "M_B_CPU0_SB_DQS_DN<6>")
		)
		(pad "261" smd rect
			(at 2.050034 40.375078 270)
			(size 0.519938 1.4986)
			(layers "F.Cu" "F.Mask" "F.Paste")
			(net "M_B_CPU0_SB_DQS_DP<6>")
		)
		(pad "262" smd rect
			(at 2.050034 41.224962 270)
			(size 0.519938 1.4986)
			(layers "F.Cu" "F.Mask" "F.Paste")
			(net "GND")
		)
		(pad "263" smd rect
			(at 2.050034 42.0751 270)
			(size 0.519938 1.4986)
			(layers "F.Cu" "F.Mask" "F.Paste")
			(net "M_B_CPU0_SB_DQ<14>")
		)
		(pad "264" smd rect
			(at 2.050034 42.924984 270)
			(size 0.519938 1.4986)
			(layers "F.Cu" "F.Mask" "F.Paste")
			(net "GND")
		)
		(pad "265" smd rect
			(at 2.050034 43.775122 270)
			(size 0.519938 1.4986)
			(layers "F.Cu" "F.Mask" "F.Paste")
			(net "M_B_CPU0_SB_DQ<15>")
		)
		(pad "266" smd rect
			(at 2.050034 44.625006 270)
			(size 0.519938 1.4986)
			(layers "F.Cu" "F.Mask" "F.Paste")
			(net "GND")
		)
		(pad "267" smd rect
			(at 2.050034 45.47489 270)
			(size 0.519938 1.4986)
			(layers "F.Cu" "F.Mask" "F.Paste")
			(net "M_B_CPU0_SB_DQ<18>")
		)
		(pad "268" smd rect
			(at 2.050034 46.325028 270)
			(size 0.519938 1.4986)
			(layers "F.Cu" "F.Mask" "F.Paste")
			(net "GND")
		)
		(pad "269" smd rect
			(at 2.050034 47.174912 270)
			(size 0.519938 1.4986)
			(layers "F.Cu" "F.Mask" "F.Paste")
			(net "M_B_CPU0_SB_DQ<19>")
		)
		(pad "270" smd rect
			(at 2.050034 48.02505 270)
			(size 0.519938 1.4986)
			(layers "F.Cu" "F.Mask" "F.Paste")
			(net "GND")
		)
		(pad "271" smd rect
			(at 2.050034 48.874934 270)
			(size 0.519938 1.4986)
			(layers "F.Cu" "F.Mask" "F.Paste")
			(net "M_B_CPU0_SB_DQS_DN<7>")
		)
		(pad "272" smd rect
			(at 2.050034 49.725072 270)
			(size 0.519938 1.4986)
			(layers "F.Cu" "F.Mask" "F.Paste")
			(net "M_B_CPU0_SB_DQS_DP<7>")
		)
		(pad "273" smd rect
			(at 2.050034 50.574956 270)
			(size 0.519938 1.4986)
			(layers "F.Cu" "F.Mask" "F.Paste")
			(net "GND")
		)
		(pad "274" smd rect
			(at 2.050034 51.425094 270)
			(size 0.519938 1.4986)
			(layers "F.Cu" "F.Mask" "F.Paste")
			(net "M_B_CPU0_SB_DQ<22>")
		)
		(pad "275" smd rect
			(at 2.050034 52.274978 270)
			(size 0.519938 1.4986)
			(layers "F.Cu" "F.Mask" "F.Paste")
			(net "GND")
		)
		(pad "276" smd rect
			(at 2.050034 53.125116 270)
			(size 0.519938 1.4986)
			(layers "F.Cu" "F.Mask" "F.Paste")
			(net "M_B_CPU0_SB_DQ<23>")
		)
		(pad "277" smd rect
			(at 2.050034 53.975 270)
			(size 0.519938 1.4986)
			(layers "F.Cu" "F.Mask" "F.Paste")
			(net "GND")
		)
		(pad "278" smd rect
			(at 2.050034 54.824884 270)
			(size 0.519938 1.4986)
			(layers "F.Cu" "F.Mask" "F.Paste")
			(net "M_B_CPU0_SB_DQ<26>")
		)
		(pad "279" smd rect
			(at 2.050034 55.675022 270)
			(size 0.519938 1.4986)
			(layers "F.Cu" "F.Mask" "F.Paste")
			(net "GND")
		)
		(pad "280" smd rect
			(at 2.050034 56.524906 270)
			(size 0.519938 1.4986)
			(layers "F.Cu" "F.Mask" "F.Paste")
			(net "M_B_CPU0_SB_DQ<27>")
		)
		(pad "281" smd rect
			(at 2.050034 57.375044 270)
			(size 0.519938 1.4986)
			(layers "F.Cu" "F.Mask" "F.Paste")
			(net "GND")
		)
		(pad "282" smd rect
			(at 2.050034 58.224928 270)
			(size 0.519938 1.4986)
			(layers "F.Cu" "F.Mask" "F.Paste")
			(net "M_B_CPU0_SB_DQS_DN<8>")
		)
		(pad "283" smd rect
			(at 2.050034 59.075066 270)
			(size 0.519938 1.4986)
			(layers "F.Cu" "F.Mask" "F.Paste")
			(net "M_B_CPU0_SB_DQS_DP<8>")
		)
		(pad "284" smd rect
			(at 2.050034 59.92495 270)
			(size 0.519938 1.4986)
			(layers "F.Cu" "F.Mask" "F.Paste")
			(net "GND")
		)
		(pad "285" smd rect
			(at 2.050034 60.775088 270)
			(size 0.519938 1.4986)
			(layers "F.Cu" "F.Mask" "F.Paste")
			(net "M_B_CPU0_SB_DQ<30>")
		)
		(pad "286" smd rect
			(at 2.050034 61.624972 270)
			(size 0.519938 1.4986)
			(layers "F.Cu" "F.Mask" "F.Paste")
			(net "GND")
		)
		(pad "287" smd rect
			(at 2.050034 62.47511 270)
			(size 0.519938 1.4986)
			(layers "F.Cu" "F.Mask" "F.Paste")
			(net "M_B_CPU0_SB_DQ<31>")
		)
		(pad "288" smd rect
			(at 2.050034 63.324994 270)
			(size 0.519938 1.4986)
			(layers "F.Cu" "F.Mask" "F.Paste")
			(net "GND")
		)
		(pad "G1" thru_hole oval
			(at 0 -68.97497)
			(size 2.8194 1.5748)
			(drill oval 2.4384 1.1938)
			(layers "*.Cu" "*.Mask")
			(remove_unused_layers no)
			(net "GND")
			(clearance 0.127)
			(thermal_gap 0.127)
		)
		(pad "G2" thru_hole oval
			(at 0 3.875024)
			(size 2.8194 1.5748)
			(drill oval 2.4384 1.1938)
			(layers "*.Cu" "*.Mask")
			(remove_unused_layers no)
			(net "GND")
			(clearance 0.127)
			(thermal_gap 0.127)
		)
		(pad "G3" thru_hole oval
			(at 0 68.97497)
			(size 2.8194 1.5748)
			(drill oval 2.4384 1.1938)
			(layers "*.Cu" "*.Mask")
			(remove_unused_layers no)
			(net "GND")
			(clearance 0.127)
			(thermal_gap 0.127)
		)
	)
	(footprint ""
		(layer "F.Cu")
		(at 89.122758 -408.517344 -90)
		(property "Reference" "C682"
			(at 0 0 270)
			(layer "F.SilkS")
			(hide yes)
			(effects
				(font
					(size 1.27 1.27)
				)
			)
		)
		(property "Value" ""
			(at 0 0 270)
			(layer "F.Fab")
			(effects
				(font
					(size 1.27 1.27)
				)
			)
		)
		(duplicate_pad_numbers_are_jumpers no)
		(fp_line
			(start -0.299974 0.150114)
			(end -0.299974 -0.150114)
			(stroke
				(width 0.1)
				(type default)
			)
			(layer "F.Fab")
		)
		(fp_line
			(start 0.299974 0.150114)
			(end -0.299974 0.150114)
			(stroke
				(width 0.1)
				(type default)
			)
			(layer "F.Fab")
		)
		(fp_line
			(start -0.299974 -0.150114)
			(end 0.299974 -0.150114)
			(stroke
				(width 0.1)
				(type default)
			)
			(layer "F.Fab")
		)
		(fp_line
			(start 0.299974 -0.150114)
			(end 0.299974 0.150114)
			(stroke
				(width 0.1)
				(type default)
			)
			(layer "F.Fab")
		)
		(pad "1" smd rect
			(at -0.2667 0 270)
			(size 0.3048 0.381)
			(layers "F.Cu" "F.Mask" "F.Paste")
			(net "P5E_CPU1_PE4_TX_C_DN<13>")
		)
		(pad "2" smd rect
			(at 0.2667 0 270)
			(size 0.3048 0.381)
			(layers "F.Cu" "F.Mask" "F.Paste")
			(net "P5E_CPU1_PE4_TX_DN<13>")
		)
	)
	(footprint ""
		(layer "F.Cu")
		(at 327.657968 -408.517344 -90)
		(property "Reference" "C917"
			(at 0 0 270)
			(layer "F.SilkS")
			(hide yes)
			(effects
				(font
					(size 1.27 1.27)
				)
			)
		)
		(property "Value" ""
			(at 0 0 270)
			(layer "F.Fab")
			(effects
				(font
					(size 1.27 1.27)
				)
			)
		)
		(duplicate_pad_numbers_are_jumpers no)
		(fp_line
			(start -0.299974 0.150114)
			(end -0.299974 -0.150114)
			(stroke
				(width 0.1)
				(type default)
			)
			(layer "F.Fab")
		)
		(fp_line
			(start 0.299974 0.150114)
			(end -0.299974 0.150114)
			(stroke
				(width 0.1)
				(type default)
			)
			(layer "F.Fab")
		)
		(fp_line
			(start -0.299974 -0.150114)
			(end 0.299974 -0.150114)
			(stroke
				(width 0.1)
				(type default)
			)
			(layer "F.Fab")
		)
		(fp_line
			(start 0.299974 -0.150114)
			(end 0.299974 0.150114)
			(stroke
				(width 0.1)
				(type default)
			)
			(layer "F.Fab")
		)
		(pad "1" smd rect
			(at -0.2667 0 270)
			(size 0.3048 0.381)
			(layers "F.Cu" "F.Mask" "F.Paste")
			(net "P5E_CPU0_PE0_TX_C_DP<8>")
		)
		(pad "2" smd rect
			(at 0.2667 0 270)
			(size 0.3048 0.381)
			(layers "F.Cu" "F.Mask" "F.Paste")
			(net "P5E_CPU0_PE0_TX_DP<8>")
		)
	)
	(footprint ""
		(layer "F.Cu")
		(at 385.637532 -71.362824 180)
		(property "Reference" "C2287"
			(at 0 0 180)
			(layer "F.SilkS")
			(hide yes)
			(effects
				(font
					(size 1.27 1.27)
				)
			)
		)
		(property "Value" ""
			(at 0 0 180)
			(layer "F.Fab")
			(effects
				(font
					(size 1.27 1.27)
				)
			)
		)
		(duplicate_pad_numbers_are_jumpers no)
		(fp_line
			(start 0.7874 0.4064)
			(end -0.7874 0.4064)
			(stroke
				(width 0.1524)
				(type default)
			)
			(layer "F.SilkS")
		)
		(fp_line
			(start 0.7874 -0.4064)
			(end 0.7874 0.4064)
			(stroke
				(width 0.1524)
				(type default)
			)
			(layer "F.SilkS")
		)
		(fp_line
			(start -0.7874 0.4064)
			(end -0.7874 -0.4064)
			(stroke
				(width 0.1524)
				(type default)
			)
			(layer "F.SilkS")
		)
		(fp_line
			(start -0.7874 -0.4064)
			(end 0.7874 -0.4064)
			(stroke
				(width 0.1524)
				(type default)
			)
			(layer "F.SilkS")
		)
		(fp_line
			(start 0.67945 0.3048)
			(end 0.120396 0.3048)
			(stroke
				(width 0.1)
				(type default)
			)
			(layer "F.Fab")
		)
		(fp_line
			(start 0.67945 -0.3048)
			(end 0.67945 0.3048)
			(stroke
				(width 0.1)
				(type default)
			)
			(layer "F.Fab")
		)
		(fp_line
			(start 0.12065 -0.2794)
			(end 0.12065 -0.3048)
			(stroke
				(width 0.1)
				(type default)
			)
			(layer "F.Fab")
		)
		(fp_line
			(start 0.12065 -0.3048)
			(end 0.67945 -0.3048)
			(stroke
				(width 0.1)
				(type default)
			)
			(layer "F.Fab")
		)
		(fp_line
			(start 0.120396 0.3048)
			(end 0.120396 0.2794)
			(stroke
				(width 0.1)
				(type default)
			)
			(layer "F.Fab")
		)
		(fp_line
			(start 0.120396 0.2794)
			(end -0.12065 0.2794)
			(stroke
				(width 0.1)
				(type default)
			)
			(layer "F.Fab")
		)
		(fp_line
			(start -0.12065 0.3048)
			(end -0.67945 0.3048)
			(stroke
				(width 0.1)
				(type default)
			)
			(layer "F.Fab")
		)
		(fp_line
			(start -0.12065 0.2794)
			(end -0.12065 0.3048)
			(stroke
				(width 0.1)
				(type default)
			)
			(layer "F.Fab")
		)
		(fp_line
			(start -0.12065 -0.2794)
			(end 0.12065 -0.2794)
			(stroke
				(width 0.1)
				(type default)
			)
			(layer "F.Fab")
		)
		(fp_line
			(start -0.12065 -0.305054)
			(end -0.12065 -0.2794)
			(stroke
				(width 0.1)
				(type default)
			)
			(layer "F.Fab")
		)
		(fp_line
			(start -0.67945 0.3048)
			(end -0.67945 -0.305054)
			(stroke
				(width 0.1)
				(type default)
			)
			(layer "F.Fab")
		)
		(fp_line
			(start -0.67945 -0.305054)
			(end -0.12065 -0.305054)
			(stroke
				(width 0.1)
				(type default)
			)
			(layer "F.Fab")
		)
		(pad "1" smd circle
			(at -0.40005 0 180)
			(size 0 0)
			(layers "F.Cu" "F.Mask" "F.Paste")
			(net "PWRGD_P1V8_PCH_AUX")
		)
		(pad "2" smd circle
			(at 0.40005 0 180)
			(size 0 0)
			(layers "F.Cu" "F.Mask" "F.Paste")
			(net "GND")
		)
	)
	(footprint ""
		(layer "F.Cu")
		(at 185.22188 -130.266948 -90)
		(property "Reference" "R272"
			(at 0 0 270)
			(layer "F.SilkS")
			(hide yes)
			(effects
				(font
					(size 1.27 1.27)
				)
			)
		)
		(property "Value" ""
			(at 0 0 270)
			(layer "F.Fab")
			(effects
				(font
					(size 1.27 1.27)
				)
			)
		)
		(duplicate_pad_numbers_are_jumpers no)
		(fp_line
			(start -0.7874 0.4064)
			(end -0.7874 -0.4064)
			(stroke
				(width 0.1524)
				(type default)
			)
			(layer "F.SilkS")
		)
		(fp_line
			(start 0.7874 0.4064)
			(end -0.7874 0.4064)
			(stroke
				(width 0.1524)
				(type default)
			)
			(layer "F.SilkS")
		)
		(fp_line
			(start -0.7874 -0.4064)
			(end 0.7874 -0.4064)
			(stroke
				(width 0.1524)
				(type default)
			)
			(layer "F.SilkS")
		)
		(fp_line
			(start 0.7874 -0.4064)
			(end 0.7874 0.4064)
			(stroke
				(width 0.1524)
				(type default)
			)
			(layer "F.SilkS")
		)
		(fp_line
			(start -0.67945 0.3048)
			(end -0.67945 -0.305054)
			(stroke
				(width 0.1)
				(type default)
			)
			(layer "F.Fab")
		)
		(fp_line
			(start -0.12065 0.3048)
			(end -0.67945 0.3048)
			(stroke
				(width 0.1)
				(type default)
			)
			(layer "F.Fab")
		)
		(fp_line
			(start 0.120396 0.3048)
			(end 0.120396 0.2794)
			(stroke
				(width 0.1)
				(type default)
			)
			(layer "F.Fab")
		)
		(fp_line
			(start 0.67945 0.3048)
			(end 0.120396 0.3048)
			(stroke
				(width 0.1)
				(type default)
			)
			(layer "F.Fab")
		)
		(fp_line
			(start -0.12065 0.2794)
			(end -0.12065 0.3048)
			(stroke
				(width 0.1)
				(type default)
			)
			(layer "F.Fab")
		)
		(fp_line
			(start 0.120396 0.2794)
			(end -0.12065 0.2794)
			(stroke
				(width 0.1)
				(type default)
			)
			(layer "F.Fab")
		)
		(fp_line
			(start -0.12065 -0.2794)
			(end 0.12065 -0.2794)
			(stroke
				(width 0.1)
				(type default)
			)
			(layer "F.Fab")
		)
		(fp_line
			(start 0.12065 -0.2794)
			(end 0.12065 -0.3048)
			(stroke
				(width 0.1)
				(type default)
			)
			(layer "F.Fab")
		)
		(fp_line
			(start 0.12065 -0.3048)
			(end 0.67945 -0.3048)
			(stroke
				(width 0.1)
				(type default)
			)
			(layer "F.Fab")
		)
		(fp_line
			(start 0.67945 -0.3048)
			(end 0.67945 0.3048)
			(stroke
				(width 0.1)
				(type default)
			)
			(layer "F.Fab")
		)
		(fp_line
			(start -0.67945 -0.305054)
			(end -0.12065 -0.305054)
			(stroke
				(width 0.1)
				(type default)
			)
			(layer "F.Fab")
		)
		(fp_line
			(start -0.12065 -0.305054)
			(end -0.12065 -0.2794)
			(stroke
				(width 0.1)
				(type default)
			)
			(layer "F.Fab")
		)
		(pad "1" smd circle
			(at -0.40005 0 270)
			(size 0 0)
			(layers "F.Cu" "F.Mask" "F.Paste")
			(net "P3V3_AUX")
		)
		(pad "2" smd circle
			(at 0.40005 0 270)
			(size 0 0)
			(layers "F.Cu" "F.Mask" "F.Paste")
			(net "FM_CPU1_PKGID2")
		)
	)
	(footprint ""
		(layer "F.Cu")
		(at 146.12874 -33.157668)
		(property "Reference" "U244"
			(at 0.11684 1.95961 0)
			(unlocked yes)
			(layer "F.SilkS")
			(effects
				(font
					(size 0.7874 0.5842)
					(thickness 0.1524)
				)
			)
		)
		(property "Value" ""
			(at 0 0 0)
			(layer "F.Fab")
			(effects
				(font
					(size 1.27 1.27)
				)
			)
		)
		(duplicate_pad_numbers_are_jumpers no)
		(fp_line
			(start -1.7272 1.1176)
			(end -1.7272 -1.1176)
			(stroke
				(width 0.1524)
				(type default)
			)
			(layer "F.SilkS")
		)
		(fp_line
			(start -0.254 -1.1176)
			(end -1.7272 -1.1176)
			(stroke
				(width 0.1524)
				(type default)
			)
			(layer "F.SilkS")
		)
		(fp_line
			(start 0 -0.7366)
			(end -0.254 -1.1176)
			(stroke
				(width 0.1524)
				(type default)
			)
			(layer "F.SilkS")
		)
		(fp_line
			(start 0.254 -1.1176)
			(end 0 -0.7366)
			(stroke
				(width 0.1524)
				(type default)
			)
			(layer "F.SilkS")
		)
		(fp_line
			(start 1.7272 -1.1176)
			(end 0.254 -1.1176)
			(stroke
				(width 0.1524)
				(type default)
			)
			(layer "F.SilkS")
		)
		(fp_line
			(start 1.7272 -1.1176)
			(end 1.7272 1.1176)
			(stroke
				(width 0.1524)
				(type default)
			)
			(layer "F.SilkS")
		)
		(fp_line
			(start 1.7272 1.1176)
			(end -1.7272 1.1176)
			(stroke
				(width 0.1524)
				(type default)
			)
			(layer "F.SilkS")
		)
		(fp_poly
			(pts
				(xy -1.633474 -2.05994) (xy -0.871474 -2.05994) (xy -1.252474 -1.29794)
			)
			(stroke
				(width 0)
				(type default)
			)
			(fill yes)
			(layer "F.SilkS")
		)
		(fp_line
			(start -1.5748 -1.1176)
			(end -1.5748 1.1176)
			(stroke
				(width 0.1)
				(type default)
			)
			(layer "F.Fab")
		)
		(fp_line
			(start -1.5748 1.1176)
			(end 1.5748 1.1176)
			(stroke
				(width 0.1)
				(type default)
			)
			(layer "F.Fab")
		)
		(fp_line
			(start 1.5748 -1.1176)
			(end -1.5748 -1.1176)
			(stroke
				(width 0.1)
				(type default)
			)
			(layer "F.Fab")
		)
		(fp_line
			(start 1.5748 1.1176)
			(end 1.5748 -1.1176)
			(stroke
				(width 0.1)
				(type default)
			)
			(layer "F.Fab")
		)
		(fp_poly
			(pts
				(xy -1.9558 -0.649986) (xy -2.7178 -0.268986) (xy -2.7178 -1.030986)
			)
			(stroke
				(width 0)
				(type default)
			)
			(fill yes)
			(layer "F.Fab")
		)
		(pad "1" smd rect
			(at -0.999998 -0.649986 270)
			(size 0.3556 1.1176)
			(layers "F.Cu" "F.Mask" "F.Paste")
			(net "OCP_SFF_NOT_PRSNT_RBT_ARB_IN")
		)
		(pad "2" smd rect
			(at -0.999998 0 270)
			(size 0.3556 1.1176)
			(layers "F.Cu" "F.Mask" "F.Paste")
			(net "GND")
		)
		(pad "3" smd rect
			(at -0.999998 0.649986 270)
			(size 0.3556 1.1176)
			(layers "F.Cu" "F.Mask" "F.Paste")
			(net "OCP_SFF_RBT_ARB_IN")
		)
		(pad "4" smd rect
			(at 0.999998 0.649986 270)
			(size 0.3556 1.1176)
			(layers "F.Cu" "F.Mask" "F.Paste")
			(net "OCP_SFF_RBT_ARB_IN_MUX1_R")
		)
		(pad "5" smd rect
			(at 0.999998 0 270)
			(size 0.3556 1.1176)
			(layers "F.Cu" "F.Mask" "F.Paste")
			(net "P3V3_AUX")
		)
		(pad "6" smd rect
			(at 0.999998 -0.649986 270)
			(size 0.3556 1.1176)
			(layers "F.Cu" "F.Mask" "F.Paste")
			(net "OCP_SFF_PRSNT_ALL_R3_N")
		)
	)
	(footprint ""
		(layer "F.Cu")
		(at 305.58994 -430.6697 -90)
		(property "Reference" "R4136"
			(at 0 0 270)
			(layer "F.SilkS")
			(hide yes)
			(effects
				(font
					(size 1.27 1.27)
				)
			)
		)
		(property "Value" ""
			(at 0 0 270)
			(layer "F.Fab")
			(effects
				(font
					(size 1.27 1.27)
				)
			)
		)
		(duplicate_pad_numbers_are_jumpers no)
		(fp_line
			(start -0.7874 0.4064)
			(end -0.7874 -0.4064)
			(stroke
				(width 0.1524)
				(type default)
			)
			(layer "F.SilkS")
		)
		(fp_line
			(start 0.7874 0.4064)
			(end -0.7874 0.4064)
			(stroke
				(width 0.1524)
				(type default)
			)
			(layer "F.SilkS")
		)
		(fp_line
			(start -0.7874 -0.4064)
			(end 0.7874 -0.4064)
			(stroke
				(width 0.1524)
				(type default)
			)
			(layer "F.SilkS")
		)
		(fp_line
			(start 0.7874 -0.4064)
			(end 0.7874 0.4064)
			(stroke
				(width 0.1524)
				(type default)
			)
			(layer "F.SilkS")
		)
		(fp_line
			(start -0.67945 0.3048)
			(end -0.67945 -0.305054)
			(stroke
				(width 0.1)
				(type default)
			)
			(layer "F.Fab")
		)
		(fp_line
			(start -0.12065 0.3048)
			(end -0.67945 0.3048)
			(stroke
				(width 0.1)
				(type default)
			)
			(layer "F.Fab")
		)
		(fp_line
			(start 0.120396 0.3048)
			(end 0.120396 0.2794)
			(stroke
				(width 0.1)
				(type default)
			)
			(layer "F.Fab")
		)
		(fp_line
			(start 0.67945 0.3048)
			(end 0.120396 0.3048)
			(stroke
				(width 0.1)
				(type default)
			)
			(layer "F.Fab")
		)
		(fp_line
			(start -0.12065 0.2794)
			(end -0.12065 0.3048)
			(stroke
				(width 0.1)
				(type default)
			)
			(layer "F.Fab")
		)
		(fp_line
			(start 0.120396 0.2794)
			(end -0.12065 0.2794)
			(stroke
				(width 0.1)
				(type default)
			)
			(layer "F.Fab")
		)
		(fp_line
			(start -0.12065 -0.2794)
			(end 0.12065 -0.2794)
			(stroke
				(width 0.1)
				(type default)
			)
			(layer "F.Fab")
		)
		(fp_line
			(start 0.12065 -0.2794)
			(end 0.12065 -0.3048)
			(stroke
				(width 0.1)
				(type default)
			)
			(layer "F.Fab")
		)
		(fp_line
			(start 0.12065 -0.3048)
			(end 0.67945 -0.3048)
			(stroke
				(width 0.1)
				(type default)
			)
			(layer "F.Fab")
		)
		(fp_line
			(start 0.67945 -0.3048)
			(end 0.67945 0.3048)
			(stroke
				(width 0.1)
				(type default)
			)
			(layer "F.Fab")
		)
		(fp_line
			(start -0.67945 -0.305054)
			(end -0.12065 -0.305054)
			(stroke
				(width 0.1)
				(type default)
			)
			(layer "F.Fab")
		)
		(fp_line
			(start -0.12065 -0.305054)
			(end -0.12065 -0.2794)
			(stroke
				(width 0.1)
				(type default)
			)
			(layer "F.Fab")
		)
		(pad "1" smd circle
			(at -0.40005 0 270)
			(size 0 0)
			(layers "F.Cu" "F.Mask" "F.Paste")
			(net "PRSNT_CABLE_GPU_A2_N")
		)
		(pad "2" smd circle
			(at 0.40005 0 270)
			(size 0 0)
			(layers "F.Cu" "F.Mask" "F.Paste")
			(net "GND")
		)
	)
	(footprint ""
		(layer "F.Cu")
		(at 303.393348 -258.091686)
		(property "Reference" "J1"
			(at -3.683 -81.702148 0)
			(unlocked yes)
			(layer "F.SilkS")
			(effects
				(font
					(size 0.7874 0.5842)
					(thickness 0.1524)
				)
				(justify left)
			)
		)
		(property "Value" ""
			(at 0 0 0)
			(layer "F.Fab")
			(effects
				(font
					(size 1.27 1.27)
				)
			)
		)
		(duplicate_pad_numbers_are_jumpers no)
		(fp_line
			(start -3.24993 -81.000092)
			(end -3.24993 81.000092)
			(stroke
				(width 0.1524)
				(type default)
			)
			(layer "F.SilkS")
		)
		(fp_line
			(start -3.24993 81.000092)
			(end 3.24993 81.000092)
			(stroke
				(width 0.1524)
				(type default)
			)
			(layer "F.SilkS")
		)
		(fp_line
			(start 3.24993 -81.000092)
			(end -3.24993 -81.000092)
			(stroke
				(width 0.1524)
				(type default)
			)
			(layer "F.SilkS")
		)
		(fp_line
			(start 3.24993 -72.00011)
			(end -3.24993 -72.00011)
			(stroke
				(width 0.1524)
				(type default)
			)
			(layer "F.SilkS")
		)
		(fp_line
			(start 3.24993 72.00011)
			(end -3.24993 72.00011)
			(stroke
				(width 0.1524)
				(type default)
			)
			(layer "F.SilkS")
		)
		(fp_line
			(start 3.24993 81.000092)
			(end 3.24993 -81.000092)
			(stroke
				(width 0.1524)
				(type default)
			)
			(layer "F.SilkS")
		)
		(fp_poly
			(pts
				(xy -4.193032 -63.857886) (xy -3.282696 -63.402718) (xy -4.193032 -62.94755)
			)
			(stroke
				(width 0)
				(type default)
			)
			(fill yes)
			(layer "F.SilkS")
		)
		(fp_line
			(start -3.24993 -81.000092)
			(end -3.24993 81.000092)
			(stroke
				(width 0.1)
				(type default)
			)
			(layer "F.Fab")
		)
		(fp_line
			(start -3.24993 81.000092)
			(end 3.24993 81.000092)
			(stroke
				(width 0.1)
				(type default)
			)
			(layer "F.Fab")
		)
		(fp_line
			(start 3.24993 -81.000092)
			(end -3.24993 -81.000092)
			(stroke
				(width 0.1)
				(type default)
			)
			(layer "F.Fab")
		)
		(fp_line
			(start 3.24993 -72.00011)
			(end -3.24993 -72.00011)
			(stroke
				(width 0.1)
				(type default)
			)
			(layer "F.Fab")
		)
		(fp_line
			(start 3.24993 -71.000112)
			(end -3.24993 -71.000112)
			(stroke
				(width 0.1)
				(type default)
			)
			(layer "F.Fab")
		)
		(fp_line
			(start 3.24993 71.000112)
			(end -3.24993 71.000112)
			(stroke
				(width 0.1)
				(type default)
			)
			(layer "F.Fab")
		)
		(fp_line
			(start 3.24993 72.00011)
			(end -3.24993 72.00011)
			(stroke
				(width 0.1)
				(type default)
			)
			(layer "F.Fab")
		)
		(fp_line
			(start 3.24993 81.000092)
			(end 3.24993 -81.000092)
			(stroke
				(width 0.1)
				(type default)
			)
			(layer "F.Fab")
		)
		(fp_poly
			(pts
				(xy -4.445 -63.832994) (xy -4.445 -62.816994) (xy -3.429 -63.324994)
			)
			(stroke
				(width 0)
				(type default)
			)
			(fill yes)
			(layer "F.Fab")
		)
		(pad "1" smd rect
			(at -2.050034 -63.324994 270)
			(size 0.519938 1.4986)
			(layers "F.Cu" "F.Mask" "F.Paste")
			(net "P12V_S3_AUX_CPU0_NVDIMM")
		)
		(pad "2" smd rect
			(at -2.050034 -62.47511 270)
			(size 0.519938 1.4986)
			(layers "F.Cu" "F.Mask" "F.Paste")
			(net "TP_CHA_CPU0_DIMM1_FRU_0")
		)
		(pad "3" smd rect
			(at -2.050034 -61.624972 270)
			(size 0.519938 1.4986)
			(layers "F.Cu" "F.Mask" "F.Paste")
			(net "P3V3_AUX")
		)
		(pad "4" smd rect
			(at -2.050034 -60.775088 270)
			(size 0.519938 1.4986)
			(layers "F.Cu" "F.Mask" "F.Paste")
			(net "I3C_SPD_DDRABCD_CPU0_LVC1_SCL_R")
		)
		(pad "5" smd rect
			(at -2.050034 -59.92495 270)
			(size 0.519938 1.4986)
			(layers "F.Cu" "F.Mask" "F.Paste")
			(net "I3C_SPD_DDRABCD_CPU0_LVC1_SDA")
		)
		(pad "6" smd rect
			(at -2.050034 -59.075066 270)
			(size 0.519938 1.4986)
			(layers "F.Cu" "F.Mask" "F.Paste")
			(net "GND")
		)
		(pad "7" smd rect
			(at -2.050034 -58.224928 270)
			(size 0.519938 1.4986)
			(layers "F.Cu" "F.Mask" "F.Paste")
			(net "M_A_CPU0_SA_DQ<0>")
		)
		(pad "8" smd rect
			(at -2.050034 -57.375044 270)
			(size 0.519938 1.4986)
			(layers "F.Cu" "F.Mask" "F.Paste")
			(net "GND")
		)
		(pad "9" smd rect
			(at -2.050034 -56.524906 270)
			(size 0.519938 1.4986)
			(layers "F.Cu" "F.Mask" "F.Paste")
			(net "M_A_CPU0_SA_DQ<1>")
		)
		(pad "10" smd rect
			(at -2.050034 -55.675022 270)
			(size 0.519938 1.4986)
			(layers "F.Cu" "F.Mask" "F.Paste")
			(net "GND")
		)
		(pad "11" smd rect
			(at -2.050034 -54.824884 270)
			(size 0.519938 1.4986)
			(layers "F.Cu" "F.Mask" "F.Paste")
			(net "M_A_CPU0_SA_DQS_DP<0>")
		)
		(pad "12" smd rect
			(at -2.050034 -53.975 270)
			(size 0.519938 1.4986)
			(layers "F.Cu" "F.Mask" "F.Paste")
			(net "M_A_CPU0_SA_DQS_DN<0>")
		)
		(pad "13" smd rect
			(at -2.050034 -53.125116 270)
			(size 0.519938 1.4986)
			(layers "F.Cu" "F.Mask" "F.Paste")
			(net "GND")
		)
		(pad "14" smd rect
			(at -2.050034 -52.274978 270)
			(size 0.519938 1.4986)
			(layers "F.Cu" "F.Mask" "F.Paste")
			(net "M_A_CPU0_SA_DQ<4>")
		)
		(pad "15" smd rect
			(at -2.050034 -51.425094 270)
			(size 0.519938 1.4986)
			(layers "F.Cu" "F.Mask" "F.Paste")
			(net "GND")
		)
		(pad "16" smd rect
			(at -2.050034 -50.574956 270)
			(size 0.519938 1.4986)
			(layers "F.Cu" "F.Mask" "F.Paste")
			(net "M_A_CPU0_SA_DQ<5>")
		)
		(pad "17" smd rect
			(at -2.050034 -49.725072 270)
			(size 0.519938 1.4986)
			(layers "F.Cu" "F.Mask" "F.Paste")
			(net "GND")
		)
		(pad "18" smd rect
			(at -2.050034 -48.874934 270)
			(size 0.519938 1.4986)
			(layers "F.Cu" "F.Mask" "F.Paste")
			(net "M_A_CPU0_SA_DQ<8>")
		)
		(pad "19" smd rect
			(at -2.050034 -48.02505 270)
			(size 0.519938 1.4986)
			(layers "F.Cu" "F.Mask" "F.Paste")
			(net "GND")
		)
		(pad "20" smd rect
			(at -2.050034 -47.174912 270)
			(size 0.519938 1.4986)
			(layers "F.Cu" "F.Mask" "F.Paste")
			(net "M_A_CPU0_SA_DQ<9>")
		)
		(pad "21" smd rect
			(at -2.050034 -46.325028 270)
			(size 0.519938 1.4986)
			(layers "F.Cu" "F.Mask" "F.Paste")
			(net "GND")
		)
		(pad "22" smd rect
			(at -2.050034 -45.47489 270)
			(size 0.519938 1.4986)
			(layers "F.Cu" "F.Mask" "F.Paste")
			(net "M_A_CPU0_SA_DQS_DP<1>")
		)
		(pad "23" smd rect
			(at -2.050034 -44.625006 270)
			(size 0.519938 1.4986)
			(layers "F.Cu" "F.Mask" "F.Paste")
			(net "M_A_CPU0_SA_DQS_DN<1>")
		)
		(pad "24" smd rect
			(at -2.050034 -43.775122 270)
			(size 0.519938 1.4986)
			(layers "F.Cu" "F.Mask" "F.Paste")
			(net "GND")
		)
		(pad "25" smd rect
			(at -2.050034 -42.924984 270)
			(size 0.519938 1.4986)
			(layers "F.Cu" "F.Mask" "F.Paste")
			(net "M_A_CPU0_SA_DQ<12>")
		)
		(pad "26" smd rect
			(at -2.050034 -42.0751 270)
			(size 0.519938 1.4986)
			(layers "F.Cu" "F.Mask" "F.Paste")
			(net "GND")
		)
		(pad "27" smd rect
			(at -2.050034 -41.224962 270)
			(size 0.519938 1.4986)
			(layers "F.Cu" "F.Mask" "F.Paste")
			(net "M_A_CPU0_SA_DQ<13>")
		)
		(pad "28" smd rect
			(at -2.050034 -40.375078 270)
			(size 0.519938 1.4986)
			(layers "F.Cu" "F.Mask" "F.Paste")
			(net "GND")
		)
		(pad "29" smd rect
			(at -2.050034 -39.52494 270)
			(size 0.519938 1.4986)
			(layers "F.Cu" "F.Mask" "F.Paste")
			(net "M_A_CPU0_SA_DQ<16>")
		)
		(pad "30" smd rect
			(at -2.050034 -38.675056 270)
			(size 0.519938 1.4986)
			(layers "F.Cu" "F.Mask" "F.Paste")
			(net "GND")
		)
		(pad "31" smd rect
			(at -2.050034 -37.824918 270)
			(size 0.519938 1.4986)
			(layers "F.Cu" "F.Mask" "F.Paste")
			(net "M_A_CPU0_SA_DQ<17>")
		)
		(pad "32" smd rect
			(at -2.050034 -36.975034 270)
			(size 0.519938 1.4986)
			(layers "F.Cu" "F.Mask" "F.Paste")
			(net "GND")
		)
		(pad "33" smd rect
			(at -2.050034 -36.124896 270)
			(size 0.519938 1.4986)
			(layers "F.Cu" "F.Mask" "F.Paste")
			(net "M_A_CPU0_SA_DQS_DP<2>")
		)
		(pad "34" smd rect
			(at -2.050034 -35.275012 270)
			(size 0.519938 1.4986)
			(layers "F.Cu" "F.Mask" "F.Paste")
			(net "M_A_CPU0_SA_DQS_DN<2>")
		)
		(pad "35" smd rect
			(at -2.050034 -34.425128 270)
			(size 0.519938 1.4986)
			(layers "F.Cu" "F.Mask" "F.Paste")
			(net "GND")
		)
		(pad "36" smd rect
			(at -2.050034 -33.57499 270)
			(size 0.519938 1.4986)
			(layers "F.Cu" "F.Mask" "F.Paste")
			(net "M_A_CPU0_SA_DQ<20>")
		)
		(pad "37" smd rect
			(at -2.050034 -32.725106 270)
			(size 0.519938 1.4986)
			(layers "F.Cu" "F.Mask" "F.Paste")
			(net "GND")
		)
		(pad "38" smd rect
			(at -2.050034 -31.874968 270)
			(size 0.519938 1.4986)
			(layers "F.Cu" "F.Mask" "F.Paste")
			(net "M_A_CPU0_SA_DQ<21>")
		)
		(pad "39" smd rect
			(at -2.050034 -31.025084 270)
			(size 0.519938 1.4986)
			(layers "F.Cu" "F.Mask" "F.Paste")
			(net "GND")
		)
		(pad "40" smd rect
			(at -2.050034 -30.174946 270)
			(size 0.519938 1.4986)
			(layers "F.Cu" "F.Mask" "F.Paste")
			(net "M_A_CPU0_SA_DQ<24>")
		)
		(pad "41" smd rect
			(at -2.050034 -29.325062 270)
			(size 0.519938 1.4986)
			(layers "F.Cu" "F.Mask" "F.Paste")
			(net "GND")
		)
		(pad "42" smd rect
			(at -2.050034 -28.474924 270)
			(size 0.519938 1.4986)
			(layers "F.Cu" "F.Mask" "F.Paste")
			(net "M_A_CPU0_SA_DQ<25>")
		)
		(pad "43" smd rect
			(at -2.050034 -27.62504 270)
			(size 0.519938 1.4986)
			(layers "F.Cu" "F.Mask" "F.Paste")
			(net "GND")
		)
		(pad "44" smd rect
			(at -2.050034 -26.774902 270)
			(size 0.519938 1.4986)
			(layers "F.Cu" "F.Mask" "F.Paste")
			(net "M_A_CPU0_SA_DQS_DP<3>")
		)
		(pad "45" smd rect
			(at -2.050034 -25.925018 270)
			(size 0.519938 1.4986)
			(layers "F.Cu" "F.Mask" "F.Paste")
			(net "M_A_CPU0_SA_DQS_DN<3>")
		)
		(pad "46" smd rect
			(at -2.050034 -25.07488 270)
			(size 0.519938 1.4986)
			(layers "F.Cu" "F.Mask" "F.Paste")
			(net "GND")
		)
		(pad "47" smd rect
			(at -2.050034 -24.224996 270)
			(size 0.519938 1.4986)
			(layers "F.Cu" "F.Mask" "F.Paste")
			(net "M_A_CPU0_SA_DQ<28>")
		)
		(pad "48" smd rect
			(at -2.050034 -23.375112 270)
			(size 0.519938 1.4986)
			(layers "F.Cu" "F.Mask" "F.Paste")
			(net "GND")
		)
		(pad "49" smd rect
			(at -2.050034 -22.524974 270)
			(size 0.519938 1.4986)
			(layers "F.Cu" "F.Mask" "F.Paste")
			(net "M_A_CPU0_SA_DQ<29>")
		)
		(pad "50" smd rect
			(at -2.050034 -21.67509 270)
			(size 0.519938 1.4986)
			(layers "F.Cu" "F.Mask" "F.Paste")
			(net "GND")
		)
		(pad "51" smd rect
			(at -2.050034 -20.824952 270)
			(size 0.519938 1.4986)
			(layers "F.Cu" "F.Mask" "F.Paste")
			(net "M_A_CPU0_SA_CB<0>")
		)
		(pad "52" smd rect
			(at -2.050034 -19.975068 270)
			(size 0.519938 1.4986)
			(layers "F.Cu" "F.Mask" "F.Paste")
			(net "GND")
		)
		(pad "53" smd rect
			(at -2.050034 -19.12493 270)
			(size 0.519938 1.4986)
			(layers "F.Cu" "F.Mask" "F.Paste")
			(net "M_A_CPU0_SA_CB<1>")
		)
		(pad "54" smd rect
			(at -2.050034 -18.275046 270)
			(size 0.519938 1.4986)
			(layers "F.Cu" "F.Mask" "F.Paste")
			(net "GND")
		)
		(pad "55" smd rect
			(at -2.050034 -17.424908 270)
			(size 0.519938 1.4986)
			(layers "F.Cu" "F.Mask" "F.Paste")
			(net "M_A_CPU0_SA_DQS_DP<4>")
		)
		(pad "56" smd rect
			(at -2.050034 -16.575024 270)
			(size 0.519938 1.4986)
			(layers "F.Cu" "F.Mask" "F.Paste")
			(net "M_A_CPU0_SA_DQS_DN<4>")
		)
		(pad "57" smd rect
			(at -2.050034 -15.724886 270)
			(size 0.519938 1.4986)
			(layers "F.Cu" "F.Mask" "F.Paste")
			(net "GND")
		)
		(pad "58" smd rect
			(at -2.050034 -14.875002 270)
			(size 0.519938 1.4986)
			(layers "F.Cu" "F.Mask" "F.Paste")
			(net "M_A_CPU0_SA_CB<4>")
		)
		(pad "59" smd rect
			(at -2.050034 -14.025118 270)
			(size 0.519938 1.4986)
			(layers "F.Cu" "F.Mask" "F.Paste")
			(net "GND")
		)
		(pad "60" smd rect
			(at -2.050034 -13.17498 270)
			(size 0.519938 1.4986)
			(layers "F.Cu" "F.Mask" "F.Paste")
			(net "M_A_CPU0_SA_CB<5>")
		)
		(pad "61" smd rect
			(at -2.050034 -12.325096 270)
			(size 0.519938 1.4986)
			(layers "F.Cu" "F.Mask" "F.Paste")
			(net "GND")
		)
		(pad "62" smd rect
			(at -2.050034 -11.474958 270)
			(size 0.519938 1.4986)
			(layers "F.Cu" "F.Mask" "F.Paste")
			(net "M_A_CPU0_ALERT_N")
		)
		(pad "63" smd rect
			(at -2.050034 -10.625074 270)
			(size 0.519938 1.4986)
			(layers "F.Cu" "F.Mask" "F.Paste")
			(net "GND")
		)
		(pad "64" smd rect
			(at -2.050034 -9.774936 270)
			(size 0.519938 1.4986)
			(layers "F.Cu" "F.Mask" "F.Paste")
			(net "M_A_CPU0_SA_CS_N<0>")
		)
		(pad "65" smd rect
			(at -2.050034 -8.925052 270)
			(size 0.519938 1.4986)
			(layers "F.Cu" "F.Mask" "F.Paste")
			(net "GND")
		)
		(pad "66" smd rect
			(at -2.050034 -8.074914 270)
			(size 0.519938 1.4986)
			(layers "F.Cu" "F.Mask" "F.Paste")
			(net "M_A_CPU0_SA_CA<0>")
		)
		(pad "67" smd rect
			(at -2.050034 -7.22503 270)
			(size 0.519938 1.4986)
			(layers "F.Cu" "F.Mask" "F.Paste")
			(net "GND")
		)
		(pad "68" smd rect
			(at -2.050034 -6.374892 270)
			(size 0.519938 1.4986)
			(layers "F.Cu" "F.Mask" "F.Paste")
			(net "M_A_CPU0_SA_CA<2>")
		)
		(pad "69" smd rect
			(at -2.050034 -5.525008 270)
			(size 0.519938 1.4986)
			(layers "F.Cu" "F.Mask" "F.Paste")
			(net "GND")
		)
		(pad "70" smd rect
			(at -2.050034 -4.675124 270)
			(size 0.519938 1.4986)
			(layers "F.Cu" "F.Mask" "F.Paste")
			(net "M_A_CPU0_SA_CA<4>")
		)
		(pad "71" smd rect
			(at -2.050034 -3.824986 270)
			(size 0.519938 1.4986)
			(layers "F.Cu" "F.Mask" "F.Paste")
			(net "GND")
		)
		(pad "72" smd rect
			(at -2.050034 -2.975102 270)
			(size 0.519938 1.4986)
			(layers "F.Cu" "F.Mask" "F.Paste")
			(net "M_A_CPU0_SA_CA<6>")
		)
		(pad "73" smd rect
			(at -2.050034 -2.124964 270)
			(size 0.519938 1.4986)
			(layers "F.Cu" "F.Mask" "F.Paste")
			(net "GND")
		)
		(pad "74" smd rect
			(at -2.050034 -1.27508 270)
			(size 0.519938 1.4986)
			(layers "F.Cu" "F.Mask" "F.Paste")
			(net "M_A_CPU0_SA_PAR")
		)
		(pad "75" smd rect
			(at -2.050034 -0.424942 270)
			(size 0.519938 1.4986)
			(layers "F.Cu" "F.Mask" "F.Paste")
			(net "GND")
		)
		(pad "76" smd rect
			(at -2.050034 5.525008 270)
			(size 0.519938 1.4986)
			(layers "F.Cu" "F.Mask" "F.Paste")
			(net "M_A_CPU0_SB_CA<0>")
		)
		(pad "77" smd rect
			(at -2.050034 6.374892 270)
			(size 0.519938 1.4986)
			(layers "F.Cu" "F.Mask" "F.Paste")
			(net "GND")
		)
		(pad "78" smd rect
			(at -2.050034 7.22503 270)
			(size 0.519938 1.4986)
			(layers "F.Cu" "F.Mask" "F.Paste")
			(net "M_A_CPU0_SB_CA<2>")
		)
		(pad "79" smd rect
			(at -2.050034 8.074914 270)
			(size 0.519938 1.4986)
			(layers "F.Cu" "F.Mask" "F.Paste")
			(net "GND")
		)
		(pad "80" smd rect
			(at -2.050034 8.925052 270)
			(size 0.519938 1.4986)
			(layers "F.Cu" "F.Mask" "F.Paste")
			(net "M_A_CPU0_SB_CA<4>")
		)
		(pad "81" smd rect
			(at -2.050034 9.774936 270)
			(size 0.519938 1.4986)
			(layers "F.Cu" "F.Mask" "F.Paste")
			(net "GND")
		)
		(pad "82" smd rect
			(at -2.050034 10.625074 270)
			(size 0.519938 1.4986)
			(layers "F.Cu" "F.Mask" "F.Paste")
			(net "M_A_CPU0_SB_CA<6>")
		)
		(pad "83" smd rect
			(at -2.050034 11.474958 270)
			(size 0.519938 1.4986)
			(layers "F.Cu" "F.Mask" "F.Paste")
			(net "GND")
		)
		(pad "84" smd rect
			(at -2.050034 12.325096 270)
			(size 0.519938 1.4986)
			(layers "F.Cu" "F.Mask" "F.Paste")
			(net "M_A_CPU0_SB_CS_N<0>")
		)
		(pad "85" smd rect
			(at -2.050034 13.17498 270)
			(size 0.519938 1.4986)
			(layers "F.Cu" "F.Mask" "F.Paste")
			(net "GND")
		)
		(pad "86" smd rect
			(at -2.050034 14.025118 270)
			(size 0.519938 1.4986)
			(layers "F.Cu" "F.Mask" "F.Paste")
			(net "M_A_CPU0_SA_RSP<0>")
		)
		(pad "87" smd rect
			(at -2.050034 14.875002 270)
			(size 0.519938 1.4986)
			(layers "F.Cu" "F.Mask" "F.Paste")
			(net "M_A_CPU0_SB_RSP<0>")
		)
		(pad "88" smd rect
			(at -2.050034 15.724886 270)
			(size 0.519938 1.4986)
			(layers "F.Cu" "F.Mask" "F.Paste")
			(net "GND")
		)
		(pad "89" smd rect
			(at -2.050034 16.575024 270)
			(size 0.519938 1.4986)
			(layers "F.Cu" "F.Mask" "F.Paste")
			(net "M_A_CPU0_SB_CB<4>")
		)
		(pad "90" smd rect
			(at -2.050034 17.424908 270)
			(size 0.519938 1.4986)
			(layers "F.Cu" "F.Mask" "F.Paste")
			(net "GND")
		)
		(pad "91" smd rect
			(at -2.050034 18.275046 270)
			(size 0.519938 1.4986)
			(layers "F.Cu" "F.Mask" "F.Paste")
			(net "M_A_CPU0_SB_CB<5>")
		)
		(pad "92" smd rect
			(at -2.050034 19.12493 270)
			(size 0.519938 1.4986)
			(layers "F.Cu" "F.Mask" "F.Paste")
			(net "GND")
		)
		(pad "93" smd rect
			(at -2.050034 19.975068 270)
			(size 0.519938 1.4986)
			(layers "F.Cu" "F.Mask" "F.Paste")
			(net "M_A_CPU0_SB_DQS_DP<9>")
		)
		(pad "94" smd rect
			(at -2.050034 20.824952 270)
			(size 0.519938 1.4986)
			(layers "F.Cu" "F.Mask" "F.Paste")
			(net "M_A_CPU0_SB_DQS_DN<9>")
		)
		(pad "95" smd rect
			(at -2.050034 21.67509 270)
			(size 0.519938 1.4986)
			(layers "F.Cu" "F.Mask" "F.Paste")
			(net "GND")
		)
		(pad "96" smd rect
			(at -2.050034 22.524974 270)
			(size 0.519938 1.4986)
			(layers "F.Cu" "F.Mask" "F.Paste")
			(net "M_A_CPU0_SB_CB<0>")
		)
		(pad "97" smd rect
			(at -2.050034 23.375112 270)
			(size 0.519938 1.4986)
			(layers "F.Cu" "F.Mask" "F.Paste")
			(net "GND")
		)
		(pad "98" smd rect
			(at -2.050034 24.224996 270)
			(size 0.519938 1.4986)
			(layers "F.Cu" "F.Mask" "F.Paste")
			(net "M_A_CPU0_SB_CB<1>")
		)
		(pad "99" smd rect
			(at -2.050034 25.07488 270)
			(size 0.519938 1.4986)
			(layers "F.Cu" "F.Mask" "F.Paste")
			(net "GND")
		)
		(pad "100" smd rect
			(at -2.050034 25.925018 270)
			(size 0.519938 1.4986)
			(layers "F.Cu" "F.Mask" "F.Paste")
			(net "M_A_CPU0_SB_DQ<0>")
		)
		(pad "101" smd rect
			(at -2.050034 26.774902 270)
			(size 0.519938 1.4986)
			(layers "F.Cu" "F.Mask" "F.Paste")
			(net "GND")
		)
		(pad "102" smd rect
			(at -2.050034 27.62504 270)
			(size 0.519938 1.4986)
			(layers "F.Cu" "F.Mask" "F.Paste")
			(net "M_A_CPU0_SB_DQ<1>")
		)
		(pad "103" smd rect
			(at -2.050034 28.474924 270)
			(size 0.519938 1.4986)
			(layers "F.Cu" "F.Mask" "F.Paste")
			(net "GND")
		)
		(pad "104" smd rect
			(at -2.050034 29.325062 270)
			(size 0.519938 1.4986)
			(layers "F.Cu" "F.Mask" "F.Paste")
			(net "M_A_CPU0_SB_DQS_DP<0>")
		)
		(pad "105" smd rect
			(at -2.050034 30.174946 270)
			(size 0.519938 1.4986)
			(layers "F.Cu" "F.Mask" "F.Paste")
			(net "M_A_CPU0_SB_DQS_DN<0>")
		)
		(pad "106" smd rect
			(at -2.050034 31.025084 270)
			(size 0.519938 1.4986)
			(layers "F.Cu" "F.Mask" "F.Paste")
			(net "GND")
		)
		(pad "107" smd rect
			(at -2.050034 31.874968 270)
			(size 0.519938 1.4986)
			(layers "F.Cu" "F.Mask" "F.Paste")
			(net "M_A_CPU0_SB_DQ<4>")
		)
		(pad "108" smd rect
			(at -2.050034 32.725106 270)
			(size 0.519938 1.4986)
			(layers "F.Cu" "F.Mask" "F.Paste")
			(net "GND")
		)
		(pad "109" smd rect
			(at -2.050034 33.57499 270)
			(size 0.519938 1.4986)
			(layers "F.Cu" "F.Mask" "F.Paste")
			(net "M_A_CPU0_SB_DQ<5>")
		)
		(pad "110" smd rect
			(at -2.050034 34.425128 270)
			(size 0.519938 1.4986)
			(layers "F.Cu" "F.Mask" "F.Paste")
			(net "GND")
		)
		(pad "111" smd rect
			(at -2.050034 35.275012 270)
			(size 0.519938 1.4986)
			(layers "F.Cu" "F.Mask" "F.Paste")
			(net "M_A_CPU0_SB_DQ<8>")
		)
		(pad "112" smd rect
			(at -2.050034 36.124896 270)
			(size 0.519938 1.4986)
			(layers "F.Cu" "F.Mask" "F.Paste")
			(net "GND")
		)
		(pad "113" smd rect
			(at -2.050034 36.975034 270)
			(size 0.519938 1.4986)
			(layers "F.Cu" "F.Mask" "F.Paste")
			(net "M_A_CPU0_SB_DQ<9>")
		)
		(pad "114" smd rect
			(at -2.050034 37.824918 270)
			(size 0.519938 1.4986)
			(layers "F.Cu" "F.Mask" "F.Paste")
			(net "GND")
		)
		(pad "115" smd rect
			(at -2.050034 38.675056 270)
			(size 0.519938 1.4986)
			(layers "F.Cu" "F.Mask" "F.Paste")
			(net "M_A_CPU0_SB_DQS_DP<1>")
		)
		(pad "116" smd rect
			(at -2.050034 39.52494 270)
			(size 0.519938 1.4986)
			(layers "F.Cu" "F.Mask" "F.Paste")
			(net "M_A_CPU0_SB_DQS_DN<1>")
		)
		(pad "117" smd rect
			(at -2.050034 40.375078 270)
			(size 0.519938 1.4986)
			(layers "F.Cu" "F.Mask" "F.Paste")
			(net "GND")
		)
		(pad "118" smd rect
			(at -2.050034 41.224962 270)
			(size 0.519938 1.4986)
			(layers "F.Cu" "F.Mask" "F.Paste")
			(net "M_A_CPU0_SB_DQ<12>")
		)
		(pad "119" smd rect
			(at -2.050034 42.0751 270)
			(size 0.519938 1.4986)
			(layers "F.Cu" "F.Mask" "F.Paste")
			(net "GND")
		)
		(pad "120" smd rect
			(at -2.050034 42.924984 270)
			(size 0.519938 1.4986)
			(layers "F.Cu" "F.Mask" "F.Paste")
			(net "M_A_CPU0_SB_DQ<13>")
		)
		(pad "121" smd rect
			(at -2.050034 43.775122 270)
			(size 0.519938 1.4986)
			(layers "F.Cu" "F.Mask" "F.Paste")
			(net "GND")
		)
		(pad "122" smd rect
			(at -2.050034 44.625006 270)
			(size 0.519938 1.4986)
			(layers "F.Cu" "F.Mask" "F.Paste")
			(net "M_A_CPU0_SB_DQ<16>")
		)
		(pad "123" smd rect
			(at -2.050034 45.47489 270)
			(size 0.519938 1.4986)
			(layers "F.Cu" "F.Mask" "F.Paste")
			(net "GND")
		)
		(pad "124" smd rect
			(at -2.050034 46.325028 270)
			(size 0.519938 1.4986)
			(layers "F.Cu" "F.Mask" "F.Paste")
			(net "M_A_CPU0_SB_DQ<17>")
		)
		(pad "125" smd rect
			(at -2.050034 47.174912 270)
			(size 0.519938 1.4986)
			(layers "F.Cu" "F.Mask" "F.Paste")
			(net "GND")
		)
		(pad "126" smd rect
			(at -2.050034 48.02505 270)
			(size 0.519938 1.4986)
			(layers "F.Cu" "F.Mask" "F.Paste")
			(net "M_A_CPU0_SB_DQS_DP<2>")
		)
		(pad "127" smd rect
			(at -2.050034 48.874934 270)
			(size 0.519938 1.4986)
			(layers "F.Cu" "F.Mask" "F.Paste")
			(net "M_A_CPU0_SB_DQS_DN<2>")
		)
		(pad "128" smd rect
			(at -2.050034 49.725072 270)
			(size 0.519938 1.4986)
			(layers "F.Cu" "F.Mask" "F.Paste")
			(net "GND")
		)
		(pad "129" smd rect
			(at -2.050034 50.574956 270)
			(size 0.519938 1.4986)
			(layers "F.Cu" "F.Mask" "F.Paste")
			(net "M_A_CPU0_SB_DQ<20>")
		)
		(pad "130" smd rect
			(at -2.050034 51.425094 270)
			(size 0.519938 1.4986)
			(layers "F.Cu" "F.Mask" "F.Paste")
			(net "GND")
		)
		(pad "131" smd rect
			(at -2.050034 52.274978 270)
			(size 0.519938 1.4986)
			(layers "F.Cu" "F.Mask" "F.Paste")
			(net "M_A_CPU0_SB_DQ<21>")
		)
		(pad "132" smd rect
			(at -2.050034 53.125116 270)
			(size 0.519938 1.4986)
			(layers "F.Cu" "F.Mask" "F.Paste")
			(net "GND")
		)
		(pad "133" smd rect
			(at -2.050034 53.975 270)
			(size 0.519938 1.4986)
			(layers "F.Cu" "F.Mask" "F.Paste")
			(net "M_A_CPU0_SB_DQ<24>")
		)
		(pad "134" smd rect
			(at -2.050034 54.824884 270)
			(size 0.519938 1.4986)
			(layers "F.Cu" "F.Mask" "F.Paste")
			(net "GND")
		)
		(pad "135" smd rect
			(at -2.050034 55.675022 270)
			(size 0.519938 1.4986)
			(layers "F.Cu" "F.Mask" "F.Paste")
			(net "M_A_CPU0_SB_DQ<25>")
		)
		(pad "136" smd rect
			(at -2.050034 56.524906 270)
			(size 0.519938 1.4986)
			(layers "F.Cu" "F.Mask" "F.Paste")
			(net "GND")
		)
		(pad "137" smd rect
			(at -2.050034 57.375044 270)
			(size 0.519938 1.4986)
			(layers "F.Cu" "F.Mask" "F.Paste")
			(net "M_A_CPU0_SB_DQS_DP<3>")
		)
		(pad "138" smd rect
			(at -2.050034 58.224928 270)
			(size 0.519938 1.4986)
			(layers "F.Cu" "F.Mask" "F.Paste")
			(net "M_A_CPU0_SB_DQS_DN<3>")
		)
		(pad "139" smd rect
			(at -2.050034 59.075066 270)
			(size 0.519938 1.4986)
			(layers "F.Cu" "F.Mask" "F.Paste")
			(net "GND")
		)
		(pad "140" smd rect
			(at -2.050034 59.92495 270)
			(size 0.519938 1.4986)
			(layers "F.Cu" "F.Mask" "F.Paste")
			(net "M_A_CPU0_SB_DQ<28>")
		)
		(pad "141" smd rect
			(at -2.050034 60.775088 270)
			(size 0.519938 1.4986)
			(layers "F.Cu" "F.Mask" "F.Paste")
			(net "GND")
		)
		(pad "142" smd rect
			(at -2.050034 61.624972 270)
			(size 0.519938 1.4986)
			(layers "F.Cu" "F.Mask" "F.Paste")
			(net "M_A_CPU0_SB_DQ<29>")
		)
		(pad "143" smd rect
			(at -2.050034 62.47511 270)
			(size 0.519938 1.4986)
			(layers "F.Cu" "F.Mask" "F.Paste")
			(net "GND")
		)
		(pad "144" smd rect
			(at -2.050034 63.324994 270)
			(size 0.519938 1.4986)
			(layers "F.Cu" "F.Mask" "F.Paste")
			(net "TP_CHA_CPU0_DIMM1_FRU_1")
		)
		(pad "145" smd rect
			(at 2.050034 -63.324994 270)
			(size 0.519938 1.4986)
			(layers "F.Cu" "F.Mask" "F.Paste")
			(net "P12V_S3_AUX_CPU0_NVDIMM")
		)
		(pad "146" smd rect
			(at 2.050034 -62.47511 270)
			(size 0.519938 1.4986)
			(layers "F.Cu" "F.Mask" "F.Paste")
			(net "P12V_S3_AUX_CPU0_NVDIMM")
		)
		(pad "147" smd rect
			(at 2.050034 -61.624972 270)
			(size 0.519938 1.4986)
			(layers "F.Cu" "F.Mask" "F.Paste")
			(net "PWRGD_CHA_CPU0_DIMM1")
		)
		(pad "148" smd rect
			(at 2.050034 -60.775088 270)
			(size 0.519938 1.4986)
			(layers "F.Cu" "F.Mask" "F.Paste")
			(net "PD_CHA_CPU0_DIMM1_SAA")
		)
		(pad "149" smd rect
			(at 2.050034 -59.92495 270)
			(size 0.519938 1.4986)
			(layers "F.Cu" "F.Mask" "F.Paste")
			(net "TP_CHA_CPU0_DIMM1_FRU_2")
		)
		(pad "150" smd rect
			(at 2.050034 -59.075066 270)
			(size 0.519938 1.4986)
			(layers "F.Cu" "F.Mask" "F.Paste")
			(net "TP_CHA_CPU0_DIMM1_FRU_3")
		)
		(pad "151" smd rect
			(at 2.050034 -58.224928 270)
			(size 0.519938 1.4986)
			(layers "F.Cu" "F.Mask" "F.Paste")
			(net "GND")
		)
		(pad "152" smd rect
			(at 2.050034 -57.375044 270)
			(size 0.519938 1.4986)
			(layers "F.Cu" "F.Mask" "F.Paste")
			(net "M_A_CPU0_SA_DQ<2>")
		)
		(pad "153" smd rect
			(at 2.050034 -56.524906 270)
			(size 0.519938 1.4986)
			(layers "F.Cu" "F.Mask" "F.Paste")
			(net "GND")
		)
		(pad "154" smd rect
			(at 2.050034 -55.675022 270)
			(size 0.519938 1.4986)
			(layers "F.Cu" "F.Mask" "F.Paste")
			(net "M_A_CPU0_SA_DQ<3>")
		)
		(pad "155" smd rect
			(at 2.050034 -54.824884 270)
			(size 0.519938 1.4986)
			(layers "F.Cu" "F.Mask" "F.Paste")
			(net "GND")
		)
		(pad "156" smd rect
			(at 2.050034 -53.975 270)
			(size 0.519938 1.4986)
			(layers "F.Cu" "F.Mask" "F.Paste")
			(net "M_A_CPU0_SA_DQS_DN<5>")
		)
		(pad "157" smd rect
			(at 2.050034 -53.125116 270)
			(size 0.519938 1.4986)
			(layers "F.Cu" "F.Mask" "F.Paste")
			(net "M_A_CPU0_SA_DQS_DP<5>")
		)
		(pad "158" smd rect
			(at 2.050034 -52.274978 270)
			(size 0.519938 1.4986)
			(layers "F.Cu" "F.Mask" "F.Paste")
			(net "GND")
		)
		(pad "159" smd rect
			(at 2.050034 -51.425094 270)
			(size 0.519938 1.4986)
			(layers "F.Cu" "F.Mask" "F.Paste")
			(net "M_A_CPU0_SA_DQ<6>")
		)
		(pad "160" smd rect
			(at 2.050034 -50.574956 270)
			(size 0.519938 1.4986)
			(layers "F.Cu" "F.Mask" "F.Paste")
			(net "GND")
		)
		(pad "161" smd rect
			(at 2.050034 -49.725072 270)
			(size 0.519938 1.4986)
			(layers "F.Cu" "F.Mask" "F.Paste")
			(net "M_A_CPU0_SA_DQ<7>")
		)
		(pad "162" smd rect
			(at 2.050034 -48.874934 270)
			(size 0.519938 1.4986)
			(layers "F.Cu" "F.Mask" "F.Paste")
			(net "GND")
		)
		(pad "163" smd rect
			(at 2.050034 -48.02505 270)
			(size 0.519938 1.4986)
			(layers "F.Cu" "F.Mask" "F.Paste")
			(net "M_A_CPU0_SA_DQ<10>")
		)
		(pad "164" smd rect
			(at 2.050034 -47.174912 270)
			(size 0.519938 1.4986)
			(layers "F.Cu" "F.Mask" "F.Paste")
			(net "GND")
		)
		(pad "165" smd rect
			(at 2.050034 -46.325028 270)
			(size 0.519938 1.4986)
			(layers "F.Cu" "F.Mask" "F.Paste")
			(net "M_A_CPU0_SA_DQ<11>")
		)
		(pad "166" smd rect
			(at 2.050034 -45.47489 270)
			(size 0.519938 1.4986)
			(layers "F.Cu" "F.Mask" "F.Paste")
			(net "GND")
		)
		(pad "167" smd rect
			(at 2.050034 -44.625006 270)
			(size 0.519938 1.4986)
			(layers "F.Cu" "F.Mask" "F.Paste")
			(net "M_A_CPU0_SA_DQS_DN<6>")
		)
		(pad "168" smd rect
			(at 2.050034 -43.775122 270)
			(size 0.519938 1.4986)
			(layers "F.Cu" "F.Mask" "F.Paste")
			(net "M_A_CPU0_SA_DQS_DP<6>")
		)
		(pad "169" smd rect
			(at 2.050034 -42.924984 270)
			(size 0.519938 1.4986)
			(layers "F.Cu" "F.Mask" "F.Paste")
			(net "GND")
		)
		(pad "170" smd rect
			(at 2.050034 -42.0751 270)
			(size 0.519938 1.4986)
			(layers "F.Cu" "F.Mask" "F.Paste")
			(net "M_A_CPU0_SA_DQ<14>")
		)
		(pad "171" smd rect
			(at 2.050034 -41.224962 270)
			(size 0.519938 1.4986)
			(layers "F.Cu" "F.Mask" "F.Paste")
			(net "GND")
		)
		(pad "172" smd rect
			(at 2.050034 -40.375078 270)
			(size 0.519938 1.4986)
			(layers "F.Cu" "F.Mask" "F.Paste")
			(net "M_A_CPU0_SA_DQ<15>")
		)
		(pad "173" smd rect
			(at 2.050034 -39.52494 270)
			(size 0.519938 1.4986)
			(layers "F.Cu" "F.Mask" "F.Paste")
			(net "GND")
		)
		(pad "174" smd rect
			(at 2.050034 -38.675056 270)
			(size 0.519938 1.4986)
			(layers "F.Cu" "F.Mask" "F.Paste")
			(net "M_A_CPU0_SA_DQ<18>")
		)
		(pad "175" smd rect
			(at 2.050034 -37.824918 270)
			(size 0.519938 1.4986)
			(layers "F.Cu" "F.Mask" "F.Paste")
			(net "GND")
		)
		(pad "176" smd rect
			(at 2.050034 -36.975034 270)
			(size 0.519938 1.4986)
			(layers "F.Cu" "F.Mask" "F.Paste")
			(net "M_A_CPU0_SA_DQ<19>")
		)
		(pad "177" smd rect
			(at 2.050034 -36.124896 270)
			(size 0.519938 1.4986)
			(layers "F.Cu" "F.Mask" "F.Paste")
			(net "GND")
		)
		(pad "178" smd rect
			(at 2.050034 -35.275012 270)
			(size 0.519938 1.4986)
			(layers "F.Cu" "F.Mask" "F.Paste")
			(net "M_A_CPU0_SA_DQS_DN<7>")
		)
		(pad "179" smd rect
			(at 2.050034 -34.425128 270)
			(size 0.519938 1.4986)
			(layers "F.Cu" "F.Mask" "F.Paste")
			(net "M_A_CPU0_SA_DQS_DP<7>")
		)
		(pad "180" smd rect
			(at 2.050034 -33.57499 270)
			(size 0.519938 1.4986)
			(layers "F.Cu" "F.Mask" "F.Paste")
			(net "GND")
		)
		(pad "181" smd rect
			(at 2.050034 -32.725106 270)
			(size 0.519938 1.4986)
			(layers "F.Cu" "F.Mask" "F.Paste")
			(net "M_A_CPU0_SA_DQ<22>")
		)
		(pad "182" smd rect
			(at 2.050034 -31.874968 270)
			(size 0.519938 1.4986)
			(layers "F.Cu" "F.Mask" "F.Paste")
			(net "GND")
		)
		(pad "183" smd rect
			(at 2.050034 -31.025084 270)
			(size 0.519938 1.4986)
			(layers "F.Cu" "F.Mask" "F.Paste")
			(net "M_A_CPU0_SA_DQ<23>")
		)
		(pad "184" smd rect
			(at 2.050034 -30.174946 270)
			(size 0.519938 1.4986)
			(layers "F.Cu" "F.Mask" "F.Paste")
			(net "GND")
		)
		(pad "185" smd rect
			(at 2.050034 -29.325062 270)
			(size 0.519938 1.4986)
			(layers "F.Cu" "F.Mask" "F.Paste")
			(net "M_A_CPU0_SA_DQ<26>")
		)
		(pad "186" smd rect
			(at 2.050034 -28.474924 270)
			(size 0.519938 1.4986)
			(layers "F.Cu" "F.Mask" "F.Paste")
			(net "GND")
		)
		(pad "187" smd rect
			(at 2.050034 -27.62504 270)
			(size 0.519938 1.4986)
			(layers "F.Cu" "F.Mask" "F.Paste")
			(net "M_A_CPU0_SA_DQ<27>")
		)
		(pad "188" smd rect
			(at 2.050034 -26.774902 270)
			(size 0.519938 1.4986)
			(layers "F.Cu" "F.Mask" "F.Paste")
			(net "GND")
		)
		(pad "189" smd rect
			(at 2.050034 -25.925018 270)
			(size 0.519938 1.4986)
			(layers "F.Cu" "F.Mask" "F.Paste")
			(net "M_A_CPU0_SA_DQS_DN<8>")
		)
		(pad "190" smd rect
			(at 2.050034 -25.07488 270)
			(size 0.519938 1.4986)
			(layers "F.Cu" "F.Mask" "F.Paste")
			(net "M_A_CPU0_SA_DQS_DP<8>")
		)
		(pad "191" smd rect
			(at 2.050034 -24.224996 270)
			(size 0.519938 1.4986)
			(layers "F.Cu" "F.Mask" "F.Paste")
			(net "GND")
		)
		(pad "192" smd rect
			(at 2.050034 -23.375112 270)
			(size 0.519938 1.4986)
			(layers "F.Cu" "F.Mask" "F.Paste")
			(net "M_A_CPU0_SA_DQ<30>")
		)
		(pad "193" smd rect
			(at 2.050034 -22.524974 270)
			(size 0.519938 1.4986)
			(layers "F.Cu" "F.Mask" "F.Paste")
			(net "GND")
		)
		(pad "194" smd rect
			(at 2.050034 -21.67509 270)
			(size 0.519938 1.4986)
			(layers "F.Cu" "F.Mask" "F.Paste")
			(net "M_A_CPU0_SA_DQ<31>")
		)
		(pad "195" smd rect
			(at 2.050034 -20.824952 270)
			(size 0.519938 1.4986)
			(layers "F.Cu" "F.Mask" "F.Paste")
			(net "GND")
		)
		(pad "196" smd rect
			(at 2.050034 -19.975068 270)
			(size 0.519938 1.4986)
			(layers "F.Cu" "F.Mask" "F.Paste")
			(net "M_A_CPU0_SA_CB<2>")
		)
		(pad "197" smd rect
			(at 2.050034 -19.12493 270)
			(size 0.519938 1.4986)
			(layers "F.Cu" "F.Mask" "F.Paste")
			(net "GND")
		)
		(pad "198" smd rect
			(at 2.050034 -18.275046 270)
			(size 0.519938 1.4986)
			(layers "F.Cu" "F.Mask" "F.Paste")
			(net "M_A_CPU0_SA_CB<3>")
		)
		(pad "199" smd rect
			(at 2.050034 -17.424908 270)
			(size 0.519938 1.4986)
			(layers "F.Cu" "F.Mask" "F.Paste")
			(net "GND")
		)
		(pad "200" smd rect
			(at 2.050034 -16.575024 270)
			(size 0.519938 1.4986)
			(layers "F.Cu" "F.Mask" "F.Paste")
			(net "M_A_CPU0_SA_DQS_DN<9>")
		)
		(pad "201" smd rect
			(at 2.050034 -15.724886 270)
			(size 0.519938 1.4986)
			(layers "F.Cu" "F.Mask" "F.Paste")
			(net "M_A_CPU0_SA_DQS_DP<9>")
		)
		(pad "202" smd rect
			(at 2.050034 -14.875002 270)
			(size 0.519938 1.4986)
			(layers "F.Cu" "F.Mask" "F.Paste")
			(net "GND")
		)
		(pad "203" smd rect
			(at 2.050034 -14.025118 270)
			(size 0.519938 1.4986)
			(layers "F.Cu" "F.Mask" "F.Paste")
			(net "M_A_CPU0_SA_CB<6>")
		)
		(pad "204" smd rect
			(at 2.050034 -13.17498 270)
			(size 0.519938 1.4986)
			(layers "F.Cu" "F.Mask" "F.Paste")
			(net "GND")
		)
		(pad "205" smd rect
			(at 2.050034 -12.325096 270)
			(size 0.519938 1.4986)
			(layers "F.Cu" "F.Mask" "F.Paste")
			(net "M_A_CPU0_SA_CB<7>")
		)
		(pad "206" smd rect
			(at 2.050034 -11.474958 270)
			(size 0.519938 1.4986)
			(layers "F.Cu" "F.Mask" "F.Paste")
			(net "GND")
		)
		(pad "207" smd rect
			(at 2.050034 -10.625074 270)
			(size 0.519938 1.4986)
			(layers "F.Cu" "F.Mask" "F.Paste")
			(net "RST_M_AB_CPU0_FPGA_N")
		)
		(pad "208" smd rect
			(at 2.050034 -9.774936 270)
			(size 0.519938 1.4986)
			(layers "F.Cu" "F.Mask" "F.Paste")
			(net "GND")
		)
		(pad "209" smd rect
			(at 2.050034 -8.925052 270)
			(size 0.519938 1.4986)
			(layers "F.Cu" "F.Mask" "F.Paste")
			(net "M_A_CPU0_SA_CS_N<1>")
		)
		(pad "210" smd rect
			(at 2.050034 -8.074914 270)
			(size 0.519938 1.4986)
			(layers "F.Cu" "F.Mask" "F.Paste")
			(net "GND")
		)
		(pad "211" smd rect
			(at 2.050034 -7.22503 270)
			(size 0.519938 1.4986)
			(layers "F.Cu" "F.Mask" "F.Paste")
			(net "M_A_CPU0_SA_CA<1>")
		)
		(pad "212" smd rect
			(at 2.050034 -6.374892 270)
			(size 0.519938 1.4986)
			(layers "F.Cu" "F.Mask" "F.Paste")
			(net "GND")
		)
		(pad "213" smd rect
			(at 2.050034 -5.525008 270)
			(size 0.519938 1.4986)
			(layers "F.Cu" "F.Mask" "F.Paste")
			(net "M_A_CPU0_SA_CA<3>")
		)
		(pad "214" smd rect
			(at 2.050034 -4.675124 270)
			(size 0.519938 1.4986)
			(layers "F.Cu" "F.Mask" "F.Paste")
			(net "GND")
		)
		(pad "215" smd rect
			(at 2.050034 -3.824986 270)
			(size 0.519938 1.4986)
			(layers "F.Cu" "F.Mask" "F.Paste")
			(net "M_A_CPU0_SA_CA<5>")
		)
		(pad "216" smd rect
			(at 2.050034 -2.975102 270)
			(size 0.519938 1.4986)
			(layers "F.Cu" "F.Mask" "F.Paste")
			(net "GND")
		)
		(pad "217" smd rect
			(at 2.050034 -2.124964 270)
			(size 0.519938 1.4986)
			(layers "F.Cu" "F.Mask" "F.Paste")
			(net "M_A_CPU0_CLK_DP<0>")
		)
		(pad "218" smd rect
			(at 2.050034 -1.27508 270)
			(size 0.519938 1.4986)
			(layers "F.Cu" "F.Mask" "F.Paste")
			(net "M_A_CPU0_CLK_DN<0>")
		)
		(pad "219" smd rect
			(at 2.050034 -0.424942 270)
			(size 0.519938 1.4986)
			(layers "F.Cu" "F.Mask" "F.Paste")
			(net "GND")
		)
		(pad "220" smd rect
			(at 2.050034 5.525008 270)
			(size 0.519938 1.4986)
			(layers "F.Cu" "F.Mask" "F.Paste")
			(net "TP_CHA_CPU0_DIMM1_FRU_4")
		)
		(pad "221" smd rect
			(at 2.050034 6.374892 270)
			(size 0.519938 1.4986)
			(layers "F.Cu" "F.Mask" "F.Paste")
			(net "M_A_CPU0_SB_CA<1>")
		)
		(pad "222" smd rect
			(at 2.050034 7.22503 270)
			(size 0.519938 1.4986)
			(layers "F.Cu" "F.Mask" "F.Paste")
			(net "GND")
		)
		(pad "223" smd rect
			(at 2.050034 8.074914 270)
			(size 0.519938 1.4986)
			(layers "F.Cu" "F.Mask" "F.Paste")
			(net "M_A_CPU0_SB_CA<3>")
		)
		(pad "224" smd rect
			(at 2.050034 8.925052 270)
			(size 0.519938 1.4986)
			(layers "F.Cu" "F.Mask" "F.Paste")
			(net "GND")
		)
		(pad "225" smd rect
			(at 2.050034 9.774936 270)
			(size 0.519938 1.4986)
			(layers "F.Cu" "F.Mask" "F.Paste")
			(net "M_A_CPU0_SB_CA<5>")
		)
		(pad "226" smd rect
			(at 2.050034 10.625074 270)
			(size 0.519938 1.4986)
			(layers "F.Cu" "F.Mask" "F.Paste")
			(net "GND")
		)
		(pad "227" smd rect
			(at 2.050034 11.474958 270)
			(size 0.519938 1.4986)
			(layers "F.Cu" "F.Mask" "F.Paste")
			(net "M_A_CPU0_SB_PAR")
		)
		(pad "228" smd rect
			(at 2.050034 12.325096 270)
			(size 0.519938 1.4986)
			(layers "F.Cu" "F.Mask" "F.Paste")
			(net "GND")
		)
		(pad "229" smd rect
			(at 2.050034 13.17498 270)
			(size 0.519938 1.4986)
			(layers "F.Cu" "F.Mask" "F.Paste")
			(net "M_A_CPU0_SB_CS_N<1>")
		)
		(pad "230" smd rect
			(at 2.050034 14.025118 270)
			(size 0.519938 1.4986)
			(layers "F.Cu" "F.Mask" "F.Paste")
			(net "GND")
		)
		(pad "231" smd rect
			(at 2.050034 14.875002 270)
			(size 0.519938 1.4986)
			(layers "F.Cu" "F.Mask" "F.Paste")
			(net "TP_CHA_CPU0_DIMM1_FRU_5")
		)
		(pad "232" smd rect
			(at 2.050034 15.724886 270)
			(size 0.519938 1.4986)
			(layers "F.Cu" "F.Mask" "F.Paste")
			(net "TP_CHA_CPU0_DIMM1_FRU_6")
		)
		(pad "233" smd rect
			(at 2.050034 16.575024 270)
			(size 0.519938 1.4986)
			(layers "F.Cu" "F.Mask" "F.Paste")
			(net "GND")
		)
		(pad "234" smd rect
			(at 2.050034 17.424908 270)
			(size 0.519938 1.4986)
			(layers "F.Cu" "F.Mask" "F.Paste")
			(net "M_A_CPU0_SB_CB<6>")
		)
		(pad "235" smd rect
			(at 2.050034 18.275046 270)
			(size 0.519938 1.4986)
			(layers "F.Cu" "F.Mask" "F.Paste")
			(net "GND")
		)
		(pad "236" smd rect
			(at 2.050034 19.12493 270)
			(size 0.519938 1.4986)
			(layers "F.Cu" "F.Mask" "F.Paste")
			(net "M_A_CPU0_SB_CB<7>")
		)
		(pad "237" smd rect
			(at 2.050034 19.975068 270)
			(size 0.519938 1.4986)
			(layers "F.Cu" "F.Mask" "F.Paste")
			(net "GND")
		)
		(pad "238" smd rect
			(at 2.050034 20.824952 270)
			(size 0.519938 1.4986)
			(layers "F.Cu" "F.Mask" "F.Paste")
			(net "M_A_CPU0_SB_DQS_DN<4>")
		)
		(pad "239" smd rect
			(at 2.050034 21.67509 270)
			(size 0.519938 1.4986)
			(layers "F.Cu" "F.Mask" "F.Paste")
			(net "M_A_CPU0_SB_DQS_DP<4>")
		)
		(pad "240" smd rect
			(at 2.050034 22.524974 270)
			(size 0.519938 1.4986)
			(layers "F.Cu" "F.Mask" "F.Paste")
			(net "GND")
		)
		(pad "241" smd rect
			(at 2.050034 23.375112 270)
			(size 0.519938 1.4986)
			(layers "F.Cu" "F.Mask" "F.Paste")
			(net "M_A_CPU0_SB_CB<2>")
		)
		(pad "242" smd rect
			(at 2.050034 24.224996 270)
			(size 0.519938 1.4986)
			(layers "F.Cu" "F.Mask" "F.Paste")
			(net "GND")
		)
		(pad "243" smd rect
			(at 2.050034 25.07488 270)
			(size 0.519938 1.4986)
			(layers "F.Cu" "F.Mask" "F.Paste")
			(net "M_A_CPU0_SB_CB<3>")
		)
		(pad "244" smd rect
			(at 2.050034 25.925018 270)
			(size 0.519938 1.4986)
			(layers "F.Cu" "F.Mask" "F.Paste")
			(net "GND")
		)
		(pad "245" smd rect
			(at 2.050034 26.774902 270)
			(size 0.519938 1.4986)
			(layers "F.Cu" "F.Mask" "F.Paste")
			(net "M_A_CPU0_SB_DQ<2>")
		)
		(pad "246" smd rect
			(at 2.050034 27.62504 270)
			(size 0.519938 1.4986)
			(layers "F.Cu" "F.Mask" "F.Paste")
			(net "GND")
		)
		(pad "247" smd rect
			(at 2.050034 28.474924 270)
			(size 0.519938 1.4986)
			(layers "F.Cu" "F.Mask" "F.Paste")
			(net "M_A_CPU0_SB_DQ<3>")
		)
		(pad "248" smd rect
			(at 2.050034 29.325062 270)
			(size 0.519938 1.4986)
			(layers "F.Cu" "F.Mask" "F.Paste")
			(net "GND")
		)
		(pad "249" smd rect
			(at 2.050034 30.174946 270)
			(size 0.519938 1.4986)
			(layers "F.Cu" "F.Mask" "F.Paste")
			(net "M_A_CPU0_SB_DQS_DN<5>")
		)
		(pad "250" smd rect
			(at 2.050034 31.025084 270)
			(size 0.519938 1.4986)
			(layers "F.Cu" "F.Mask" "F.Paste")
			(net "M_A_CPU0_SB_DQS_DP<5>")
		)
		(pad "251" smd rect
			(at 2.050034 31.874968 270)
			(size 0.519938 1.4986)
			(layers "F.Cu" "F.Mask" "F.Paste")
			(net "GND")
		)
		(pad "252" smd rect
			(at 2.050034 32.725106 270)
			(size 0.519938 1.4986)
			(layers "F.Cu" "F.Mask" "F.Paste")
			(net "M_A_CPU0_SB_DQ<6>")
		)
		(pad "253" smd rect
			(at 2.050034 33.57499 270)
			(size 0.519938 1.4986)
			(layers "F.Cu" "F.Mask" "F.Paste")
			(net "GND")
		)
		(pad "254" smd rect
			(at 2.050034 34.425128 270)
			(size 0.519938 1.4986)
			(layers "F.Cu" "F.Mask" "F.Paste")
			(net "M_A_CPU0_SB_DQ<7>")
		)
		(pad "255" smd rect
			(at 2.050034 35.275012 270)
			(size 0.519938 1.4986)
			(layers "F.Cu" "F.Mask" "F.Paste")
			(net "GND")
		)
		(pad "256" smd rect
			(at 2.050034 36.124896 270)
			(size 0.519938 1.4986)
			(layers "F.Cu" "F.Mask" "F.Paste")
			(net "M_A_CPU0_SB_DQ<10>")
		)
		(pad "257" smd rect
			(at 2.050034 36.975034 270)
			(size 0.519938 1.4986)
			(layers "F.Cu" "F.Mask" "F.Paste")
			(net "GND")
		)
		(pad "258" smd rect
			(at 2.050034 37.824918 270)
			(size 0.519938 1.4986)
			(layers "F.Cu" "F.Mask" "F.Paste")
			(net "M_A_CPU0_SB_DQ<11>")
		)
		(pad "259" smd rect
			(at 2.050034 38.675056 270)
			(size 0.519938 1.4986)
			(layers "F.Cu" "F.Mask" "F.Paste")
			(net "GND")
		)
		(pad "260" smd rect
			(at 2.050034 39.52494 270)
			(size 0.519938 1.4986)
			(layers "F.Cu" "F.Mask" "F.Paste")
			(net "M_A_CPU0_SB_DQS_DN<6>")
		)
		(pad "261" smd rect
			(at 2.050034 40.375078 270)
			(size 0.519938 1.4986)
			(layers "F.Cu" "F.Mask" "F.Paste")
			(net "M_A_CPU0_SB_DQS_DP<6>")
		)
		(pad "262" smd rect
			(at 2.050034 41.224962 270)
			(size 0.519938 1.4986)
			(layers "F.Cu" "F.Mask" "F.Paste")
			(net "GND")
		)
		(pad "263" smd rect
			(at 2.050034 42.0751 270)
			(size 0.519938 1.4986)
			(layers "F.Cu" "F.Mask" "F.Paste")
			(net "M_A_CPU0_SB_DQ<14>")
		)
		(pad "264" smd rect
			(at 2.050034 42.924984 270)
			(size 0.519938 1.4986)
			(layers "F.Cu" "F.Mask" "F.Paste")
			(net "GND")
		)
		(pad "265" smd rect
			(at 2.050034 43.775122 270)
			(size 0.519938 1.4986)
			(layers "F.Cu" "F.Mask" "F.Paste")
			(net "M_A_CPU0_SB_DQ<15>")
		)
		(pad "266" smd rect
			(at 2.050034 44.625006 270)
			(size 0.519938 1.4986)
			(layers "F.Cu" "F.Mask" "F.Paste")
			(net "GND")
		)
		(pad "267" smd rect
			(at 2.050034 45.47489 270)
			(size 0.519938 1.4986)
			(layers "F.Cu" "F.Mask" "F.Paste")
			(net "M_A_CPU0_SB_DQ<18>")
		)
		(pad "268" smd rect
			(at 2.050034 46.325028 270)
			(size 0.519938 1.4986)
			(layers "F.Cu" "F.Mask" "F.Paste")
			(net "GND")
		)
		(pad "269" smd rect
			(at 2.050034 47.174912 270)
			(size 0.519938 1.4986)
			(layers "F.Cu" "F.Mask" "F.Paste")
			(net "M_A_CPU0_SB_DQ<19>")
		)
		(pad "270" smd rect
			(at 2.050034 48.02505 270)
			(size 0.519938 1.4986)
			(layers "F.Cu" "F.Mask" "F.Paste")
			(net "GND")
		)
		(pad "271" smd rect
			(at 2.050034 48.874934 270)
			(size 0.519938 1.4986)
			(layers "F.Cu" "F.Mask" "F.Paste")
			(net "M_A_CPU0_SB_DQS_DN<7>")
		)
		(pad "272" smd rect
			(at 2.050034 49.725072 270)
			(size 0.519938 1.4986)
			(layers "F.Cu" "F.Mask" "F.Paste")
			(net "M_A_CPU0_SB_DQS_DP<7>")
		)
		(pad "273" smd rect
			(at 2.050034 50.574956 270)
			(size 0.519938 1.4986)
			(layers "F.Cu" "F.Mask" "F.Paste")
			(net "GND")
		)
		(pad "274" smd rect
			(at 2.050034 51.425094 270)
			(size 0.519938 1.4986)
			(layers "F.Cu" "F.Mask" "F.Paste")
			(net "M_A_CPU0_SB_DQ<22>")
		)
		(pad "275" smd rect
			(at 2.050034 52.274978 270)
			(size 0.519938 1.4986)
			(layers "F.Cu" "F.Mask" "F.Paste")
			(net "GND")
		)
		(pad "276" smd rect
			(at 2.050034 53.125116 270)
			(size 0.519938 1.4986)
			(layers "F.Cu" "F.Mask" "F.Paste")
			(net "M_A_CPU0_SB_DQ<23>")
		)
		(pad "277" smd rect
			(at 2.050034 53.975 270)
			(size 0.519938 1.4986)
			(layers "F.Cu" "F.Mask" "F.Paste")
			(net "GND")
		)
		(pad "278" smd rect
			(at 2.050034 54.824884 270)
			(size 0.519938 1.4986)
			(layers "F.Cu" "F.Mask" "F.Paste")
			(net "M_A_CPU0_SB_DQ<26>")
		)
		(pad "279" smd rect
			(at 2.050034 55.675022 270)
			(size 0.519938 1.4986)
			(layers "F.Cu" "F.Mask" "F.Paste")
			(net "GND")
		)
		(pad "280" smd rect
			(at 2.050034 56.524906 270)
			(size 0.519938 1.4986)
			(layers "F.Cu" "F.Mask" "F.Paste")
			(net "M_A_CPU0_SB_DQ<27>")
		)
		(pad "281" smd rect
			(at 2.050034 57.375044 270)
			(size 0.519938 1.4986)
			(layers "F.Cu" "F.Mask" "F.Paste")
			(net "GND")
		)
		(pad "282" smd rect
			(at 2.050034 58.224928 270)
			(size 0.519938 1.4986)
			(layers "F.Cu" "F.Mask" "F.Paste")
			(net "M_A_CPU0_SB_DQS_DN<8>")
		)
		(pad "283" smd rect
			(at 2.050034 59.075066 270)
			(size 0.519938 1.4986)
			(layers "F.Cu" "F.Mask" "F.Paste")
			(net "M_A_CPU0_SB_DQS_DP<8>")
		)
		(pad "284" smd rect
			(at 2.050034 59.92495 270)
			(size 0.519938 1.4986)
			(layers "F.Cu" "F.Mask" "F.Paste")
			(net "GND")
		)
		(pad "285" smd rect
			(at 2.050034 60.775088 270)
			(size 0.519938 1.4986)
			(layers "F.Cu" "F.Mask" "F.Paste")
			(net "M_A_CPU0_SB_DQ<30>")
		)
		(pad "286" smd rect
			(at 2.050034 61.624972 270)
			(size 0.519938 1.4986)
			(layers "F.Cu" "F.Mask" "F.Paste")
			(net "GND")
		)
		(pad "287" smd rect
			(at 2.050034 62.47511 270)
			(size 0.519938 1.4986)
			(layers "F.Cu" "F.Mask" "F.Paste")
			(net "M_A_CPU0_SB_DQ<31>")
		)
		(pad "288" smd rect
			(at 2.050034 63.324994 270)
			(size 0.519938 1.4986)
			(layers "F.Cu" "F.Mask" "F.Paste")
			(net "GND")
		)
		(pad "G1" thru_hole oval
			(at 0 -68.97497)
			(size 2.8194 1.5748)
			(drill oval 2.4384 1.1938)
			(layers "*.Cu" "*.Mask")
			(remove_unused_layers no)
			(net "GND")
			(clearance 0.127)
			(thermal_gap 0.127)
		)
		(pad "G2" thru_hole oval
			(at 0 3.875024)
			(size 2.8194 1.5748)
			(drill oval 2.4384 1.1938)
			(layers "*.Cu" "*.Mask")
			(remove_unused_layers no)
			(net "GND")
			(clearance 0.127)
			(thermal_gap 0.127)
		)
		(pad "G3" thru_hole oval
			(at 0 68.97497)
			(size 2.8194 1.5748)
			(drill oval 2.4384 1.1938)
			(layers "*.Cu" "*.Mask")
			(remove_unused_layers no)
			(net "GND")
			(clearance 0.127)
			(thermal_gap 0.127)
		)
	)
	(footprint ""
		(layer "F.Cu")
		(at 164.29101 -130.526536 -90)
		(property "Reference" "R1643"
			(at 0 0 270)
			(layer "F.SilkS")
			(hide yes)
			(effects
				(font
					(size 1.27 1.27)
				)
			)
		)
		(property "Value" ""
			(at 0 0 270)
			(layer "F.Fab")
			(effects
				(font
					(size 1.27 1.27)
				)
			)
		)
		(duplicate_pad_numbers_are_jumpers no)
		(fp_line
			(start -0.7874 0.4064)
			(end -0.7874 -0.4064)
			(stroke
				(width 0.1524)
				(type default)
			)
			(layer "F.SilkS")
		)
		(fp_line
			(start 0.7874 0.4064)
			(end -0.7874 0.4064)
			(stroke
				(width 0.1524)
				(type default)
			)
			(layer "F.SilkS")
		)
		(fp_line
			(start -0.7874 -0.4064)
			(end 0.7874 -0.4064)
			(stroke
				(width 0.1524)
				(type default)
			)
			(layer "F.SilkS")
		)
		(fp_line
			(start 0.7874 -0.4064)
			(end 0.7874 0.4064)
			(stroke
				(width 0.1524)
				(type default)
			)
			(layer "F.SilkS")
		)
		(fp_line
			(start -0.67945 0.3048)
			(end -0.67945 -0.305054)
			(stroke
				(width 0.1)
				(type default)
			)
			(layer "F.Fab")
		)
		(fp_line
			(start -0.12065 0.3048)
			(end -0.67945 0.3048)
			(stroke
				(width 0.1)
				(type default)
			)
			(layer "F.Fab")
		)
		(fp_line
			(start 0.120396 0.3048)
			(end 0.120396 0.2794)
			(stroke
				(width 0.1)
				(type default)
			)
			(layer "F.Fab")
		)
		(fp_line
			(start 0.67945 0.3048)
			(end 0.120396 0.3048)
			(stroke
				(width 0.1)
				(type default)
			)
			(layer "F.Fab")
		)
		(fp_line
			(start -0.12065 0.2794)
			(end -0.12065 0.3048)
			(stroke
				(width 0.1)
				(type default)
			)
			(layer "F.Fab")
		)
		(fp_line
			(start 0.120396 0.2794)
			(end -0.12065 0.2794)
			(stroke
				(width 0.1)
				(type default)
			)
			(layer "F.Fab")
		)
		(fp_line
			(start -0.12065 -0.2794)
			(end 0.12065 -0.2794)
			(stroke
				(width 0.1)
				(type default)
			)
			(layer "F.Fab")
		)
		(fp_line
			(start 0.12065 -0.2794)
			(end 0.12065 -0.3048)
			(stroke
				(width 0.1)
				(type default)
			)
			(layer "F.Fab")
		)
		(fp_line
			(start 0.12065 -0.3048)
			(end 0.67945 -0.3048)
			(stroke
				(width 0.1)
				(type default)
			)
			(layer "F.Fab")
		)
		(fp_line
			(start 0.67945 -0.3048)
			(end 0.67945 0.3048)
			(stroke
				(width 0.1)
				(type default)
			)
			(layer "F.Fab")
		)
		(fp_line
			(start -0.67945 -0.305054)
			(end -0.12065 -0.305054)
			(stroke
				(width 0.1)
				(type default)
			)
			(layer "F.Fab")
		)
		(fp_line
			(start -0.12065 -0.305054)
			(end -0.12065 -0.2794)
			(stroke
				(width 0.1)
				(type default)
			)
			(layer "F.Fab")
		)
		(pad "1" smd circle
			(at -0.40005 0 270)
			(size 0 0)
			(layers "F.Cu" "F.Mask" "F.Paste")
			(net "P12V_AUX")
		)
		(pad "2" smd circle
			(at 0.40005 0 270)
			(size 0 0)
			(layers "F.Cu" "F.Mask" "F.Paste")
			(net "VR_P5V_EN_N")
		)
	)
	(footprint ""
		(layer "F.Cu")
		(at 105.30713 -241.97691 -90)
		(property "Reference" "C242"
			(at 0 0 270)
			(layer "F.SilkS")
			(hide yes)
			(effects
				(font
					(size 1.27 1.27)
				)
			)
		)
		(property "Value" ""
			(at 0 0 270)
			(layer "F.Fab")
			(effects
				(font
					(size 1.27 1.27)
				)
			)
		)
		(duplicate_pad_numbers_are_jumpers no)
		(fp_line
			(start -0.7874 0.4064)
			(end -0.7874 -0.4064)
			(stroke
				(width 0.1524)
				(type default)
			)
			(layer "F.SilkS")
		)
		(fp_line
			(start 0.7874 0.4064)
			(end -0.7874 0.4064)
			(stroke
				(width 0.1524)
				(type default)
			)
			(layer "F.SilkS")
		)
		(fp_line
			(start -0.7874 -0.4064)
			(end 0.7874 -0.4064)
			(stroke
				(width 0.1524)
				(type default)
			)
			(layer "F.SilkS")
		)
		(fp_line
			(start 0.7874 -0.4064)
			(end 0.7874 0.4064)
			(stroke
				(width 0.1524)
				(type default)
			)
			(layer "F.SilkS")
		)
		(fp_line
			(start -0.67945 0.3048)
			(end -0.67945 -0.305054)
			(stroke
				(width 0.1)
				(type default)
			)
			(layer "F.Fab")
		)
		(fp_line
			(start -0.12065 0.3048)
			(end -0.67945 0.3048)
			(stroke
				(width 0.1)
				(type default)
			)
			(layer "F.Fab")
		)
		(fp_line
			(start 0.120396 0.3048)
			(end 0.120396 0.2794)
			(stroke
				(width 0.1)
				(type default)
			)
			(layer "F.Fab")
		)
		(fp_line
			(start 0.67945 0.3048)
			(end 0.120396 0.3048)
			(stroke
				(width 0.1)
				(type default)
			)
			(layer "F.Fab")
		)
		(fp_line
			(start -0.12065 0.2794)
			(end -0.12065 0.3048)
			(stroke
				(width 0.1)
				(type default)
			)
			(layer "F.Fab")
		)
		(fp_line
			(start 0.120396 0.2794)
			(end -0.12065 0.2794)
			(stroke
				(width 0.1)
				(type default)
			)
			(layer "F.Fab")
		)
		(fp_line
			(start -0.12065 -0.2794)
			(end 0.12065 -0.2794)
			(stroke
				(width 0.1)
				(type default)
			)
			(layer "F.Fab")
		)
		(fp_line
			(start 0.12065 -0.2794)
			(end 0.12065 -0.3048)
			(stroke
				(width 0.1)
				(type default)
			)
			(layer "F.Fab")
		)
		(fp_line
			(start 0.12065 -0.3048)
			(end 0.67945 -0.3048)
			(stroke
				(width 0.1)
				(type default)
			)
			(layer "F.Fab")
		)
		(fp_line
			(start 0.67945 -0.3048)
			(end 0.67945 0.3048)
			(stroke
				(width 0.1)
				(type default)
			)
			(layer "F.Fab")
		)
		(fp_line
			(start -0.67945 -0.305054)
			(end -0.12065 -0.305054)
			(stroke
				(width 0.1)
				(type default)
			)
			(layer "F.Fab")
		)
		(fp_line
			(start -0.12065 -0.305054)
			(end -0.12065 -0.2794)
			(stroke
				(width 0.1)
				(type default)
			)
			(layer "F.Fab")
		)
		(pad "1" smd circle
			(at -0.40005 0 270)
			(size 0 0)
			(layers "F.Cu" "F.Mask" "F.Paste")
			(net "PVCCIN_CPU1")
		)
		(pad "2" smd circle
			(at 0.40005 0 270)
			(size 0 0)
			(layers "F.Cu" "F.Mask" "F.Paste")
			(net "GND")
		)
	)
	(footprint ""
		(layer "F.Cu")
		(at 157.870144 -53.359304 -90)
		(property "Reference" "C2021"
			(at 0 0 270)
			(layer "F.SilkS")
			(hide yes)
			(effects
				(font
					(size 1.27 1.27)
				)
			)
		)
		(property "Value" ""
			(at 0 0 270)
			(layer "F.Fab")
			(effects
				(font
					(size 1.27 1.27)
				)
			)
		)
		(duplicate_pad_numbers_are_jumpers no)
		(fp_line
			(start -0.7874 0.4064)
			(end -0.7874 -0.4064)
			(stroke
				(width 0.1524)
				(type default)
			)
			(layer "F.SilkS")
		)
		(fp_line
			(start 0.7874 0.4064)
			(end -0.7874 0.4064)
			(stroke
				(width 0.1524)
				(type default)
			)
			(layer "F.SilkS")
		)
		(fp_line
			(start -0.7874 -0.4064)
			(end 0.7874 -0.4064)
			(stroke
				(width 0.1524)
				(type default)
			)
			(layer "F.SilkS")
		)
		(fp_line
			(start 0.7874 -0.4064)
			(end 0.7874 0.4064)
			(stroke
				(width 0.1524)
				(type default)
			)
			(layer "F.SilkS")
		)
		(fp_line
			(start -0.67945 0.3048)
			(end -0.67945 -0.305054)
			(stroke
				(width 0.1)
				(type default)
			)
			(layer "F.Fab")
		)
		(fp_line
			(start -0.12065 0.3048)
			(end -0.67945 0.3048)
			(stroke
				(width 0.1)
				(type default)
			)
			(layer "F.Fab")
		)
		(fp_line
			(start 0.120396 0.3048)
			(end 0.120396 0.2794)
			(stroke
				(width 0.1)
				(type default)
			)
			(layer "F.Fab")
		)
		(fp_line
			(start 0.67945 0.3048)
			(end 0.120396 0.3048)
			(stroke
				(width 0.1)
				(type default)
			)
			(layer "F.Fab")
		)
		(fp_line
			(start -0.12065 0.2794)
			(end -0.12065 0.3048)
			(stroke
				(width 0.1)
				(type default)
			)
			(layer "F.Fab")
		)
		(fp_line
			(start 0.120396 0.2794)
			(end -0.12065 0.2794)
			(stroke
				(width 0.1)
				(type default)
			)
			(layer "F.Fab")
		)
		(fp_line
			(start -0.12065 -0.2794)
			(end 0.12065 -0.2794)
			(stroke
				(width 0.1)
				(type default)
			)
			(layer "F.Fab")
		)
		(fp_line
			(start 0.12065 -0.2794)
			(end 0.12065 -0.3048)
			(stroke
				(width 0.1)
				(type default)
			)
			(layer "F.Fab")
		)
		(fp_line
			(start 0.12065 -0.3048)
			(end 0.67945 -0.3048)
			(stroke
				(width 0.1)
				(type default)
			)
			(layer "F.Fab")
		)
		(fp_line
			(start 0.67945 -0.3048)
			(end 0.67945 0.3048)
			(stroke
				(width 0.1)
				(type default)
			)
			(layer "F.Fab")
		)
		(fp_line
			(start -0.67945 -0.305054)
			(end -0.12065 -0.305054)
			(stroke
				(width 0.1)
				(type default)
			)
			(layer "F.Fab")
		)
		(fp_line
			(start -0.12065 -0.305054)
			(end -0.12065 -0.2794)
			(stroke
				(width 0.1)
				(type default)
			)
			(layer "F.Fab")
		)
		(pad "1" smd circle
			(at -0.40005 0 270)
			(size 0 0)
			(layers "F.Cu" "F.Mask" "F.Paste")
			(net "VSENSE_P12V_INA230_4_INP")
		)
		(pad "2" smd circle
			(at 0.40005 0 270)
			(size 0 0)
			(layers "F.Cu" "F.Mask" "F.Paste")
			(net "VSENSE_P12V_INA230_4_INN")
		)
	)
	(footprint ""
		(layer "F.Cu")
		(at 420.591488 -173.654974 180)
		(property "Reference" "PC1347"
			(at 0 0 180)
			(layer "F.SilkS")
			(hide yes)
			(effects
				(font
					(size 1.27 1.27)
				)
			)
		)
		(property "Value" ""
			(at 0 0 180)
			(layer "F.Fab")
			(effects
				(font
					(size 1.27 1.27)
				)
			)
		)
		(duplicate_pad_numbers_are_jumpers no)
		(fp_line
			(start 0.7874 0.4064)
			(end -0.7874 0.4064)
			(stroke
				(width 0.1524)
				(type default)
			)
			(layer "F.SilkS")
		)
		(fp_line
			(start 0.7874 -0.4064)
			(end 0.7874 0.4064)
			(stroke
				(width 0.1524)
				(type default)
			)
			(layer "F.SilkS")
		)
		(fp_line
			(start -0.7874 0.4064)
			(end -0.7874 -0.4064)
			(stroke
				(width 0.1524)
				(type default)
			)
			(layer "F.SilkS")
		)
		(fp_line
			(start -0.7874 -0.4064)
			(end 0.7874 -0.4064)
			(stroke
				(width 0.1524)
				(type default)
			)
			(layer "F.SilkS")
		)
		(fp_line
			(start 0.67945 0.3048)
			(end 0.120396 0.3048)
			(stroke
				(width 0.1)
				(type default)
			)
			(layer "F.Fab")
		)
		(fp_line
			(start 0.67945 -0.3048)
			(end 0.67945 0.3048)
			(stroke
				(width 0.1)
				(type default)
			)
			(layer "F.Fab")
		)
		(fp_line
			(start 0.12065 -0.2794)
			(end 0.12065 -0.3048)
			(stroke
				(width 0.1)
				(type default)
			)
			(layer "F.Fab")
		)
		(fp_line
			(start 0.12065 -0.3048)
			(end 0.67945 -0.3048)
			(stroke
				(width 0.1)
				(type default)
			)
			(layer "F.Fab")
		)
		(fp_line
			(start 0.120396 0.3048)
			(end 0.120396 0.2794)
			(stroke
				(width 0.1)
				(type default)
			)
			(layer "F.Fab")
		)
		(fp_line
			(start 0.120396 0.2794)
			(end -0.12065 0.2794)
			(stroke
				(width 0.1)
				(type default)
			)
			(layer "F.Fab")
		)
		(fp_line
			(start -0.12065 0.3048)
			(end -0.67945 0.3048)
			(stroke
				(width 0.1)
				(type default)
			)
			(layer "F.Fab")
		)
		(fp_line
			(start -0.12065 0.2794)
			(end -0.12065 0.3048)
			(stroke
				(width 0.1)
				(type default)
			)
			(layer "F.Fab")
		)
		(fp_line
			(start -0.12065 -0.2794)
			(end 0.12065 -0.2794)
			(stroke
				(width 0.1)
				(type default)
			)
			(layer "F.Fab")
		)
		(fp_line
			(start -0.12065 -0.305054)
			(end -0.12065 -0.2794)
			(stroke
				(width 0.1)
				(type default)
			)
			(layer "F.Fab")
		)
		(fp_line
			(start -0.67945 0.3048)
			(end -0.67945 -0.305054)
			(stroke
				(width 0.1)
				(type default)
			)
			(layer "F.Fab")
		)
		(fp_line
			(start -0.67945 -0.305054)
			(end -0.12065 -0.305054)
			(stroke
				(width 0.1)
				(type default)
			)
			(layer "F.Fab")
		)
		(pad "1" smd circle
			(at -0.40005 0 180)
			(size 0 0)
			(layers "F.Cu" "F.Mask" "F.Paste")
			(net "GND")
		)
		(pad "2" smd circle
			(at 0.40005 0 180)
			(size 0 0)
			(layers "F.Cu" "F.Mask" "F.Paste")
			(net "PVCCINFAON_CPU0_VREF")
		)
	)
	(footprint ""
		(layer "F.Cu")
		(at 129.75082 -27.348688 -90)
		(property "Reference" "C2285"
			(at 0 0 270)
			(layer "F.SilkS")
			(hide yes)
			(effects
				(font
					(size 1.27 1.27)
				)
			)
		)
		(property "Value" ""
			(at 0 0 270)
			(layer "F.Fab")
			(effects
				(font
					(size 1.27 1.27)
				)
			)
		)
		(duplicate_pad_numbers_are_jumpers no)
		(fp_line
			(start -0.7874 0.4064)
			(end -0.7874 -0.4064)
			(stroke
				(width 0.1524)
				(type default)
			)
			(layer "F.SilkS")
		)
		(fp_line
			(start 0.7874 0.4064)
			(end -0.7874 0.4064)
			(stroke
				(width 0.1524)
				(type default)
			)
			(layer "F.SilkS")
		)
		(fp_line
			(start -0.7874 -0.4064)
			(end 0.7874 -0.4064)
			(stroke
				(width 0.1524)
				(type default)
			)
			(layer "F.SilkS")
		)
		(fp_line
			(start 0.7874 -0.4064)
			(end 0.7874 0.4064)
			(stroke
				(width 0.1524)
				(type default)
			)
			(layer "F.SilkS")
		)
		(fp_line
			(start -0.67945 0.3048)
			(end -0.67945 -0.305054)
			(stroke
				(width 0.1)
				(type default)
			)
			(layer "F.Fab")
		)
		(fp_line
			(start -0.12065 0.3048)
			(end -0.67945 0.3048)
			(stroke
				(width 0.1)
				(type default)
			)
			(layer "F.Fab")
		)
		(fp_line
			(start 0.120396 0.3048)
			(end 0.120396 0.2794)
			(stroke
				(width 0.1)
				(type default)
			)
			(layer "F.Fab")
		)
		(fp_line
			(start 0.67945 0.3048)
			(end 0.120396 0.3048)
			(stroke
				(width 0.1)
				(type default)
			)
			(layer "F.Fab")
		)
		(fp_line
			(start -0.12065 0.2794)
			(end -0.12065 0.3048)
			(stroke
				(width 0.1)
				(type default)
			)
			(layer "F.Fab")
		)
		(fp_line
			(start 0.120396 0.2794)
			(end -0.12065 0.2794)
			(stroke
				(width 0.1)
				(type default)
			)
			(layer "F.Fab")
		)
		(fp_line
			(start -0.12065 -0.2794)
			(end 0.12065 -0.2794)
			(stroke
				(width 0.1)
				(type default)
			)
			(layer "F.Fab")
		)
		(fp_line
			(start 0.12065 -0.2794)
			(end 0.12065 -0.3048)
			(stroke
				(width 0.1)
				(type default)
			)
			(layer "F.Fab")
		)
		(fp_line
			(start 0.12065 -0.3048)
			(end 0.67945 -0.3048)
			(stroke
				(width 0.1)
				(type default)
			)
			(layer "F.Fab")
		)
		(fp_line
			(start 0.67945 -0.3048)
			(end 0.67945 0.3048)
			(stroke
				(width 0.1)
				(type default)
			)
			(layer "F.Fab")
		)
		(fp_line
			(start -0.67945 -0.305054)
			(end -0.12065 -0.305054)
			(stroke
				(width 0.1)
				(type default)
			)
			(layer "F.Fab")
		)
		(fp_line
			(start -0.12065 -0.305054)
			(end -0.12065 -0.2794)
			(stroke
				(width 0.1)
				(type default)
			)
			(layer "F.Fab")
		)
		(pad "1" smd circle
			(at -0.40005 0 270)
			(size 0 0)
			(layers "F.Cu" "F.Mask" "F.Paste")
			(net "P3V3_AUX_USB_BUF")
		)
		(pad "2" smd circle
			(at 0.40005 0 270)
			(size 0 0)
			(layers "F.Cu" "F.Mask" "F.Paste")
			(net "GND")
		)
	)
	(footprint ""
		(layer "F.Cu")
		(at 51.932078 -402.371052 -90)
		(property "Reference" "C713"
			(at 0 0 270)
			(layer "F.SilkS")
			(hide yes)
			(effects
				(font
					(size 1.27 1.27)
				)
			)
		)
		(property "Value" ""
			(at 0 0 270)
			(layer "F.Fab")
			(effects
				(font
					(size 1.27 1.27)
				)
			)
		)
		(duplicate_pad_numbers_are_jumpers no)
		(fp_line
			(start -0.299974 0.150114)
			(end -0.299974 -0.150114)
			(stroke
				(width 0.1)
				(type default)
			)
			(layer "F.Fab")
		)
		(fp_line
			(start 0.299974 0.150114)
			(end -0.299974 0.150114)
			(stroke
				(width 0.1)
				(type default)
			)
			(layer "F.Fab")
		)
		(fp_line
			(start -0.299974 -0.150114)
			(end 0.299974 -0.150114)
			(stroke
				(width 0.1)
				(type default)
			)
			(layer "F.Fab")
		)
		(fp_line
			(start 0.299974 -0.150114)
			(end 0.299974 0.150114)
			(stroke
				(width 0.1)
				(type default)
			)
			(layer "F.Fab")
		)
		(pad "1" smd rect
			(at -0.2667 0 270)
			(size 0.3048 0.381)
			(layers "F.Cu" "F.Mask" "F.Paste")
			(net "P5E_CPU1_PE0_TX_C_DP<14>")
		)
		(pad "2" smd rect
			(at 0.2667 0 270)
			(size 0.3048 0.381)
			(layers "F.Cu" "F.Mask" "F.Paste")
			(net "P5E_CPU1_PE0_TX_DP<14>")
		)
	)
	(footprint ""
		(layer "F.Cu")
		(at 128.401572 -130.002026)
		(property "Reference" "R2703"
			(at 0 0 0)
			(layer "F.SilkS")
			(hide yes)
			(effects
				(font
					(size 1.27 1.27)
				)
			)
		)
		(property "Value" ""
			(at 0 0 0)
			(layer "F.Fab")
			(effects
				(font
					(size 1.27 1.27)
				)
			)
		)
		(duplicate_pad_numbers_are_jumpers no)
		(fp_line
			(start -0.7874 -0.4064)
			(end 0.7874 -0.4064)
			(stroke
				(width 0.1524)
				(type default)
			)
			(layer "F.SilkS")
		)
		(fp_line
			(start -0.7874 0.4064)
			(end -0.7874 -0.4064)
			(stroke
				(width 0.1524)
				(type default)
			)
			(layer "F.SilkS")
		)
		(fp_line
			(start 0.7874 -0.4064)
			(end 0.7874 0.4064)
			(stroke
				(width 0.1524)
				(type default)
			)
			(layer "F.SilkS")
		)
		(fp_line
			(start 0.7874 0.4064)
			(end -0.7874 0.4064)
			(stroke
				(width 0.1524)
				(type default)
			)
			(layer "F.SilkS")
		)
		(fp_line
			(start -0.67945 -0.305054)
			(end -0.12065 -0.305054)
			(stroke
				(width 0.1)
				(type default)
			)
			(layer "F.Fab")
		)
		(fp_line
			(start -0.67945 0.3048)
			(end -0.67945 -0.305054)
			(stroke
				(width 0.1)
				(type default)
			)
			(layer "F.Fab")
		)
		(fp_line
			(start -0.12065 -0.305054)
			(end -0.12065 -0.2794)
			(stroke
				(width 0.1)
				(type default)
			)
			(layer "F.Fab")
		)
		(fp_line
			(start -0.12065 -0.2794)
			(end 0.12065 -0.2794)
			(stroke
				(width 0.1)
				(type default)
			)
			(layer "F.Fab")
		)
		(fp_line
			(start -0.12065 0.2794)
			(end -0.12065 0.3048)
			(stroke
				(width 0.1)
				(type default)
			)
			(layer "F.Fab")
		)
		(fp_line
			(start -0.12065 0.3048)
			(end -0.67945 0.3048)
			(stroke
				(width 0.1)
				(type default)
			)
			(layer "F.Fab")
		)
		(fp_line
			(start 0.120396 0.2794)
			(end -0.12065 0.2794)
			(stroke
				(width 0.1)
				(type default)
			)
			(layer "F.Fab")
		)
		(fp_line
			(start 0.120396 0.3048)
			(end 0.120396 0.2794)
			(stroke
				(width 0.1)
				(type default)
			)
			(layer "F.Fab")
		)
		(fp_line
			(start 0.12065 -0.3048)
			(end 0.67945 -0.3048)
			(stroke
				(width 0.1)
				(type default)
			)
			(layer "F.Fab")
		)
		(fp_line
			(start 0.12065 -0.2794)
			(end 0.12065 -0.3048)
			(stroke
				(width 0.1)
				(type default)
			)
			(layer "F.Fab")
		)
		(fp_line
			(start 0.67945 -0.3048)
			(end 0.67945 0.3048)
			(stroke
				(width 0.1)
				(type default)
			)
			(layer "F.Fab")
		)
		(fp_line
			(start 0.67945 0.3048)
			(end 0.120396 0.3048)
			(stroke
				(width 0.1)
				(type default)
			)
			(layer "F.Fab")
		)
		(pad "1" smd circle
			(at -0.40005 0)
			(size 0 0)
			(layers "F.Cu" "F.Mask" "F.Paste")
			(net "SMB_BMC_SWB_SCL_R4")
		)
		(pad "2" smd circle
			(at 0.40005 0)
			(size 0 0)
			(layers "F.Cu" "F.Mask" "F.Paste")
			(net "SMB_BMC_SWB_SCL")
		)
	)
	(footprint ""
		(layer "F.Cu")
		(at 361.44454 -412.9913 180)
		(property "Reference" "Q154"
			(at -1.8923 -2.470912 0)
			(unlocked yes)
			(layer "F.SilkS")
			(effects
				(font
					(size 0.7874 0.5842)
					(thickness 0.1524)
				)
				(justify left)
			)
		)
		(property "Value" ""
			(at 0 0 180)
			(layer "F.Fab")
			(effects
				(font
					(size 1.27 1.27)
				)
			)
		)
		(duplicate_pad_numbers_are_jumpers no)
		(fp_line
			(start 1.332738 1.100074)
			(end -1.332738 1.100074)
			(stroke
				(width 0.1524)
				(type default)
			)
			(layer "F.SilkS")
		)
		(fp_line
			(start 1.332738 -1.100074)
			(end 1.332738 1.100074)
			(stroke
				(width 0.1524)
				(type default)
			)
			(layer "F.SilkS")
		)
		(fp_line
			(start 0.4826 -1.100074)
			(end 1.332738 -1.100074)
			(stroke
				(width 0.1524)
				(type default)
			)
			(layer "F.SilkS")
		)
		(fp_line
			(start 0 -0.541274)
			(end 0.4826 -1.100074)
			(stroke
				(width 0.1524)
				(type default)
			)
			(layer "F.SilkS")
		)
		(fp_line
			(start -0.4826 -1.100074)
			(end 0 -0.541274)
			(stroke
				(width 0.1524)
				(type default)
			)
			(layer "F.SilkS")
		)
		(fp_line
			(start -1.332738 1.100074)
			(end -1.332738 -1.100074)
			(stroke
				(width 0.1524)
				(type default)
			)
			(layer "F.SilkS")
		)
		(fp_line
			(start -1.332738 -1.100074)
			(end -0.4826 -1.100074)
			(stroke
				(width 0.1524)
				(type default)
			)
			(layer "F.SilkS")
		)
		(fp_poly
			(pts
				(xy -2.422398 -1.07442) (xy -1.925828 -1.570736) (xy -1.67767 -0.826008)
			)
			(stroke
				(width 0)
				(type default)
			)
			(fill yes)
			(layer "F.SilkS")
		)
		(fp_line
			(start 0.674878 1.100074)
			(end -0.674878 1.100074)
			(stroke
				(width 0.1)
				(type default)
			)
			(layer "F.Fab")
		)
		(fp_line
			(start 0.674878 -1.100074)
			(end 0.674878 1.100074)
			(stroke
				(width 0.1)
				(type default)
			)
			(layer "F.Fab")
		)
		(fp_line
			(start -0.674878 1.100074)
			(end -0.674878 -1.100074)
			(stroke
				(width 0.1)
				(type default)
			)
			(layer "F.Fab")
		)
		(fp_line
			(start -0.674878 -1.100074)
			(end 0.674878 -1.100074)
			(stroke
				(width 0.1)
				(type default)
			)
			(layer "F.Fab")
		)
		(fp_poly
			(pts
				(xy -2.2352 -0.298958) (xy -2.2352 -1.001014) (xy -1.533144 -0.649986)
			)
			(stroke
				(width 0)
				(type default)
			)
			(fill yes)
			(layer "F.Fab")
		)
		(pad "1" smd rect
			(at -0.94996 -0.649986 270)
			(size 0.4318 0.508)
			(layers "F.Cu" "F.Mask" "F.Paste")
			(net "GND")
		)
		(pad "2" smd rect
			(at -0.94996 0 270)
			(size 0.4318 0.508)
			(layers "F.Cu" "F.Mask" "F.Paste")
			(net "PRSNT_CABLE_GPU_A3_N")
		)
		(pad "3" smd rect
			(at -0.94996 0.649986 270)
			(size 0.4318 0.508)
			(layers "F.Cu" "F.Mask" "F.Paste")
			(net "PRSNT_CABLE_GPU_A3_ISO_N")
		)
		(pad "4" smd rect
			(at 0.94996 0.649986 270)
			(size 0.4318 0.508)
			(layers "F.Cu" "F.Mask" "F.Paste")
			(net "GND")
		)
		(pad "5" smd rect
			(at 0.94996 0 270)
			(size 0.4318 0.508)
			(layers "F.Cu" "F.Mask" "F.Paste")
			(net "PRSNT_CABLE_GPU_A3")
		)
		(pad "6" smd rect
			(at 0.94996 -0.649986 270)
			(size 0.4318 0.508)
			(layers "F.Cu" "F.Mask" "F.Paste")
			(net "PRSNT_CABLE_GPU_A3")
		)
	)
	(footprint ""
		(layer "F.Cu")
		(at 457.684632 -107.018836)
		(property "Reference" "U211"
			(at -1.4732 -1.768348 0)
			(unlocked yes)
			(layer "F.SilkS")
			(effects
				(font
					(size 0.7874 0.5842)
					(thickness 0.1524)
				)
				(justify left)
			)
		)
		(property "Value" ""
			(at 0 0 0)
			(layer "F.Fab")
			(effects
				(font
					(size 1.27 1.27)
				)
			)
		)
		(duplicate_pad_numbers_are_jumpers no)
		(fp_line
			(start -1.38176 -1.100074)
			(end -1.38176 1.100074)
			(stroke
				(width 0.1524)
				(type default)
			)
			(layer "F.SilkS")
		)
		(fp_line
			(start -1.38176 1.100074)
			(end 1.38176 1.100074)
			(stroke
				(width 0.1524)
				(type default)
			)
			(layer "F.SilkS")
		)
		(fp_line
			(start -0.592074 -1.100074)
			(end -1.38176 -1.100074)
			(stroke
				(width 0.1524)
				(type default)
			)
			(layer "F.SilkS")
		)
		(fp_line
			(start 0 -0.508)
			(end -0.592074 -1.100074)
			(stroke
				(width 0.1524)
				(type default)
			)
			(layer "F.SilkS")
		)
		(fp_line
			(start 0.592074 -1.100074)
			(end 0 -0.508)
			(stroke
				(width 0.1524)
				(type default)
			)
			(layer "F.SilkS")
		)
		(fp_line
			(start 1.38176 -1.100074)
			(end 0.592074 -1.100074)
			(stroke
				(width 0.1524)
				(type default)
			)
			(layer "F.SilkS")
		)
		(fp_line
			(start 1.38176 1.100074)
			(end 1.38176 -1.100074)
			(stroke
				(width 0.1524)
				(type default)
			)
			(layer "F.SilkS")
		)
		(fp_poly
			(pts
				(xy -1.50241 -0.649986) (xy -1.9431 -0.429768) (xy -1.9431 -0.870204)
			)
			(stroke
				(width 0)
				(type default)
			)
			(fill yes)
			(layer "F.SilkS")
		)
		(fp_line
			(start -0.674878 -1.100074)
			(end -0.674878 1.100074)
			(stroke
				(width 0.1)
				(type default)
			)
			(layer "F.Fab")
		)
		(fp_line
			(start -0.674878 1.100074)
			(end 0.674878 1.100074)
			(stroke
				(width 0.1)
				(type default)
			)
			(layer "F.Fab")
		)
		(fp_line
			(start 0.674878 -1.100074)
			(end -0.674878 -1.100074)
			(stroke
				(width 0.1)
				(type default)
			)
			(layer "F.Fab")
		)
		(fp_line
			(start 0.674878 1.100074)
			(end 0.674878 -1.100074)
			(stroke
				(width 0.1)
				(type default)
			)
			(layer "F.Fab")
		)
		(fp_poly
			(pts
				(xy -1.9431 -0.870204) (xy -1.50241 -0.649986) (xy -1.9431 -0.429768)
			)
			(stroke
				(width 0)
				(type default)
			)
			(fill yes)
			(layer "F.Fab")
		)
		(pad "1" smd rect
			(at -0.94996 -0.649986 270)
			(size 0.4318 0.6096)
			(layers "F.Cu" "F.Mask" "F.Paste")
			(net "OCP_SFF_PRSNT0_R_N")
		)
		(pad "2" smd rect
			(at -0.94996 0 270)
			(size 0.4318 0.6096)
			(layers "F.Cu" "F.Mask" "F.Paste")
			(net "GND")
		)
		(pad "3" smd rect
			(at -0.94996 0.649986 270)
			(size 0.4318 0.6096)
			(layers "F.Cu" "F.Mask" "F.Paste")
			(net "OCP_SFF_PRSNT1_R_N")
		)
		(pad "4" smd rect
			(at 0.94996 0.649986 270)
			(size 0.4318 0.6096)
			(layers "F.Cu" "F.Mask" "F.Paste")
			(net "HP_LVC3_OCP_V3_1_PRSNT2_N_R")
		)
		(pad "5" smd rect
			(at 0.94996 0 270)
			(size 0.4318 0.6096)
			(layers "F.Cu" "F.Mask" "F.Paste")
			(net "P3V3_AUX")
		)
		(pad "6" smd rect
			(at 0.94996 -0.649986 270)
			(size 0.4318 0.6096)
			(layers "F.Cu" "F.Mask" "F.Paste")
			(net "HP_LVC3_OCP_V3_1_PRSNT2_N_R")
		)
	)
	(footprint ""
		(layer "F.Cu")
		(at 360.553 -415.889948)
		(property "Reference" "Q146"
			(at -1.4224 -1.768348 0)
			(unlocked yes)
			(layer "F.SilkS")
			(effects
				(font
					(size 0.7874 0.5842)
					(thickness 0.1524)
				)
				(justify left)
			)
		)
		(property "Value" ""
			(at 0 0 0)
			(layer "F.Fab")
			(effects
				(font
					(size 1.27 1.27)
				)
			)
		)
		(duplicate_pad_numbers_are_jumpers no)
		(fp_line
			(start -1.332738 -1.100074)
			(end -0.4826 -1.100074)
			(stroke
				(width 0.1524)
				(type default)
			)
			(layer "F.SilkS")
		)
		(fp_line
			(start -1.332738 1.100074)
			(end -1.332738 -1.100074)
			(stroke
				(width 0.1524)
				(type default)
			)
			(layer "F.SilkS")
		)
		(fp_line
			(start -0.4826 -1.100074)
			(end 0 -0.541274)
			(stroke
				(width 0.1524)
				(type default)
			)
			(layer "F.SilkS")
		)
		(fp_line
			(start 0 -0.541274)
			(end 0.4826 -1.100074)
			(stroke
				(width 0.1524)
				(type default)
			)
			(layer "F.SilkS")
		)
		(fp_line
			(start 0.4826 -1.100074)
			(end 1.332738 -1.100074)
			(stroke
				(width 0.1524)
				(type default)
			)
			(layer "F.SilkS")
		)
		(fp_line
			(start 1.332738 -1.100074)
			(end 1.332738 1.100074)
			(stroke
				(width 0.1524)
				(type default)
			)
			(layer "F.SilkS")
		)
		(fp_line
			(start 1.332738 1.100074)
			(end -1.332738 1.100074)
			(stroke
				(width 0.1524)
				(type default)
			)
			(layer "F.SilkS")
		)
		(fp_poly
			(pts
				(xy -2.2352 -0.298958) (xy -2.2352 -1.001014) (xy -1.533144 -0.649986)
			)
			(stroke
				(width 0)
				(type default)
			)
			(fill yes)
			(layer "F.SilkS")
		)
		(fp_line
			(start -0.674878 -1.100074)
			(end 0.674878 -1.100074)
			(stroke
				(width 0.1)
				(type default)
			)
			(layer "F.Fab")
		)
		(fp_line
			(start -0.674878 1.100074)
			(end -0.674878 -1.100074)
			(stroke
				(width 0.1)
				(type default)
			)
			(layer "F.Fab")
		)
		(fp_line
			(start 0.674878 -1.100074)
			(end 0.674878 1.100074)
			(stroke
				(width 0.1)
				(type default)
			)
			(layer "F.Fab")
		)
		(fp_line
			(start 0.674878 1.100074)
			(end -0.674878 1.100074)
			(stroke
				(width 0.1)
				(type default)
			)
			(layer "F.Fab")
		)
		(fp_poly
			(pts
				(xy -2.2352 -0.298958) (xy -2.2352 -1.001014) (xy -1.533144 -0.649986)
			)
			(stroke
				(width 0)
				(type default)
			)
			(fill yes)
			(layer "F.Fab")
		)
		(pad "1" smd rect
			(at -0.94996 -0.649986 90)
			(size 0.4318 0.508)
			(layers "F.Cu" "F.Mask" "F.Paste")
			(net "GND")
		)
		(pad "2" smd rect
			(at -0.94996 0 90)
			(size 0.4318 0.508)
			(layers "F.Cu" "F.Mask" "F.Paste")
			(net "SWB_HSC_PWRGD")
		)
		(pad "3" smd rect
			(at -0.94996 0.649986 90)
			(size 0.4318 0.508)
			(layers "F.Cu" "F.Mask" "F.Paste")
			(net "SWB_HSC_PWRGD_ISO")
		)
		(pad "4" smd rect
			(at 0.94996 0.649986 90)
			(size 0.4318 0.508)
			(layers "F.Cu" "F.Mask" "F.Paste")
			(net "GND")
		)
		(pad "5" smd rect
			(at 0.94996 0 90)
			(size 0.4318 0.508)
			(layers "F.Cu" "F.Mask" "F.Paste")
			(net "SWB_HSC_PWRGD_N")
		)
		(pad "6" smd rect
			(at 0.94996 -0.649986 90)
			(size 0.4318 0.508)
			(layers "F.Cu" "F.Mask" "F.Paste")
			(net "SWB_HSC_PWRGD_N")
		)
	)
	(footprint ""
		(layer "F.Cu")
		(at 424.204892 -385.282948)
		(property "Reference" "R2934"
			(at 0 0 0)
			(layer "F.SilkS")
			(hide yes)
			(effects
				(font
					(size 1.27 1.27)
				)
			)
		)
		(property "Value" ""
			(at 0 0 0)
			(layer "F.Fab")
			(effects
				(font
					(size 1.27 1.27)
				)
			)
		)
		(duplicate_pad_numbers_are_jumpers no)
		(fp_line
			(start -0.7874 -0.4064)
			(end 0.7874 -0.4064)
			(stroke
				(width 0.1524)
				(type default)
			)
			(layer "F.SilkS")
		)
		(fp_line
			(start -0.7874 0.4064)
			(end -0.7874 -0.4064)
			(stroke
				(width 0.1524)
				(type default)
			)
			(layer "F.SilkS")
		)
		(fp_line
			(start 0.7874 -0.4064)
			(end 0.7874 0.4064)
			(stroke
				(width 0.1524)
				(type default)
			)
			(layer "F.SilkS")
		)
		(fp_line
			(start 0.7874 0.4064)
			(end -0.7874 0.4064)
			(stroke
				(width 0.1524)
				(type default)
			)
			(layer "F.SilkS")
		)
		(fp_line
			(start -0.67945 -0.305054)
			(end -0.12065 -0.305054)
			(stroke
				(width 0.1)
				(type default)
			)
			(layer "F.Fab")
		)
		(fp_line
			(start -0.67945 0.3048)
			(end -0.67945 -0.305054)
			(stroke
				(width 0.1)
				(type default)
			)
			(layer "F.Fab")
		)
		(fp_line
			(start -0.12065 -0.305054)
			(end -0.12065 -0.2794)
			(stroke
				(width 0.1)
				(type default)
			)
			(layer "F.Fab")
		)
		(fp_line
			(start -0.12065 -0.2794)
			(end 0.12065 -0.2794)
			(stroke
				(width 0.1)
				(type default)
			)
			(layer "F.Fab")
		)
		(fp_line
			(start -0.12065 0.2794)
			(end -0.12065 0.3048)
			(stroke
				(width 0.1)
				(type default)
			)
			(layer "F.Fab")
		)
		(fp_line
			(start -0.12065 0.3048)
			(end -0.67945 0.3048)
			(stroke
				(width 0.1)
				(type default)
			)
			(layer "F.Fab")
		)
		(fp_line
			(start 0.120396 0.2794)
			(end -0.12065 0.2794)
			(stroke
				(width 0.1)
				(type default)
			)
			(layer "F.Fab")
		)
		(fp_line
			(start 0.120396 0.3048)
			(end 0.120396 0.2794)
			(stroke
				(width 0.1)
				(type default)
			)
			(layer "F.Fab")
		)
		(fp_line
			(start 0.12065 -0.3048)
			(end 0.67945 -0.3048)
			(stroke
				(width 0.1)
				(type default)
			)
			(layer "F.Fab")
		)
		(fp_line
			(start 0.12065 -0.2794)
			(end 0.12065 -0.3048)
			(stroke
				(width 0.1)
				(type default)
			)
			(layer "F.Fab")
		)
		(fp_line
			(start 0.67945 -0.3048)
			(end 0.67945 0.3048)
			(stroke
				(width 0.1)
				(type default)
			)
			(layer "F.Fab")
		)
		(fp_line
			(start 0.67945 0.3048)
			(end 0.120396 0.3048)
			(stroke
				(width 0.1)
				(type default)
			)
			(layer "F.Fab")
		)
		(pad "1" smd circle
			(at -0.40005 0)
			(size 0 0)
			(layers "F.Cu" "F.Mask" "F.Paste")
			(net "P3V3_AUX")
		)
		(pad "2" smd circle
			(at 0.40005 0)
			(size 0 0)
			(layers "F.Cu" "F.Mask" "F.Paste")
			(net "FM_SWB_PWRGD_ISO")
		)
	)
	(footprint ""
		(layer "F.Cu")
		(at 290.571936 -367.378996 -90)
		(property "Reference" "PC1178"
			(at 0 0 270)
			(layer "F.SilkS")
			(hide yes)
			(effects
				(font
					(size 1.27 1.27)
				)
			)
		)
		(property "Value" ""
			(at 0 0 270)
			(layer "F.Fab")
			(effects
				(font
					(size 1.27 1.27)
				)
			)
		)
		(duplicate_pad_numbers_are_jumpers no)
		(fp_line
			(start -0.7874 0.4064)
			(end -0.7874 -0.4064)
			(stroke
				(width 0.1524)
				(type default)
			)
			(layer "F.SilkS")
		)
		(fp_line
			(start 0.7874 0.4064)
			(end -0.7874 0.4064)
			(stroke
				(width 0.1524)
				(type default)
			)
			(layer "F.SilkS")
		)
		(fp_line
			(start -0.7874 -0.4064)
			(end 0.7874 -0.4064)
			(stroke
				(width 0.1524)
				(type default)
			)
			(layer "F.SilkS")
		)
		(fp_line
			(start 0.7874 -0.4064)
			(end 0.7874 0.4064)
			(stroke
				(width 0.1524)
				(type default)
			)
			(layer "F.SilkS")
		)
		(fp_line
			(start -0.67945 0.3048)
			(end -0.67945 -0.305054)
			(stroke
				(width 0.1)
				(type default)
			)
			(layer "F.Fab")
		)
		(fp_line
			(start -0.12065 0.3048)
			(end -0.67945 0.3048)
			(stroke
				(width 0.1)
				(type default)
			)
			(layer "F.Fab")
		)
		(fp_line
			(start 0.120396 0.3048)
			(end 0.120396 0.2794)
			(stroke
				(width 0.1)
				(type default)
			)
			(layer "F.Fab")
		)
		(fp_line
			(start 0.67945 0.3048)
			(end 0.120396 0.3048)
			(stroke
				(width 0.1)
				(type default)
			)
			(layer "F.Fab")
		)
		(fp_line
			(start -0.12065 0.2794)
			(end -0.12065 0.3048)
			(stroke
				(width 0.1)
				(type default)
			)
			(layer "F.Fab")
		)
		(fp_line
			(start 0.120396 0.2794)
			(end -0.12065 0.2794)
			(stroke
				(width 0.1)
				(type default)
			)
			(layer "F.Fab")
		)
		(fp_line
			(start -0.12065 -0.2794)
			(end 0.12065 -0.2794)
			(stroke
				(width 0.1)
				(type default)
			)
			(layer "F.Fab")
		)
		(fp_line
			(start 0.12065 -0.2794)
			(end 0.12065 -0.3048)
			(stroke
				(width 0.1)
				(type default)
			)
			(layer "F.Fab")
		)
		(fp_line
			(start 0.12065 -0.3048)
			(end 0.67945 -0.3048)
			(stroke
				(width 0.1)
				(type default)
			)
			(layer "F.Fab")
		)
		(fp_line
			(start 0.67945 -0.3048)
			(end 0.67945 0.3048)
			(stroke
				(width 0.1)
				(type default)
			)
			(layer "F.Fab")
		)
		(fp_line
			(start -0.67945 -0.305054)
			(end -0.12065 -0.305054)
			(stroke
				(width 0.1)
				(type default)
			)
			(layer "F.Fab")
		)
		(fp_line
			(start -0.12065 -0.305054)
			(end -0.12065 -0.2794)
			(stroke
				(width 0.1)
				(type default)
			)
			(layer "F.Fab")
		)
		(pad "1" smd circle
			(at -0.40005 0 270)
			(size 0 0)
			(layers "F.Cu" "F.Mask" "F.Paste")
			(net "SW_PVCCFA_EHV_FIVRA_CPU0_BOOT4_")
		)
		(pad "2" smd circle
			(at 0.40005 0 270)
			(size 0 0)
			(layers "F.Cu" "F.Mask" "F.Paste")
			(net "SW_PVCCFA_EHV_FIVRA_CPU0_BOOTR4")
		)
	)
	(footprint ""
		(layer "F.Cu")
		(at 351.189798 -359.53573 180)
		(property "Reference" "R4593"
			(at 0 0 180)
			(layer "F.SilkS")
			(hide yes)
			(effects
				(font
					(size 1.27 1.27)
				)
			)
		)
		(property "Value" ""
			(at 0 0 180)
			(layer "F.Fab")
			(effects
				(font
					(size 1.27 1.27)
				)
			)
		)
		(duplicate_pad_numbers_are_jumpers no)
		(fp_line
			(start 0.7874 0.4064)
			(end -0.7874 0.4064)
			(stroke
				(width 0.1524)
				(type default)
			)
			(layer "F.SilkS")
		)
		(fp_line
			(start 0.7874 -0.4064)
			(end 0.7874 0.4064)
			(stroke
				(width 0.1524)
				(type default)
			)
			(layer "F.SilkS")
		)
		(fp_line
			(start -0.7874 0.4064)
			(end -0.7874 -0.4064)
			(stroke
				(width 0.1524)
				(type default)
			)
			(layer "F.SilkS")
		)
		(fp_line
			(start -0.7874 -0.4064)
			(end 0.7874 -0.4064)
			(stroke
				(width 0.1524)
				(type default)
			)
			(layer "F.SilkS")
		)
		(fp_line
			(start 0.67945 0.3048)
			(end 0.120396 0.3048)
			(stroke
				(width 0.1)
				(type default)
			)
			(layer "F.Fab")
		)
		(fp_line
			(start 0.67945 -0.3048)
			(end 0.67945 0.3048)
			(stroke
				(width 0.1)
				(type default)
			)
			(layer "F.Fab")
		)
		(fp_line
			(start 0.12065 -0.2794)
			(end 0.12065 -0.3048)
			(stroke
				(width 0.1)
				(type default)
			)
			(layer "F.Fab")
		)
		(fp_line
			(start 0.12065 -0.3048)
			(end 0.67945 -0.3048)
			(stroke
				(width 0.1)
				(type default)
			)
			(layer "F.Fab")
		)
		(fp_line
			(start 0.120396 0.3048)
			(end 0.120396 0.2794)
			(stroke
				(width 0.1)
				(type default)
			)
			(layer "F.Fab")
		)
		(fp_line
			(start 0.120396 0.2794)
			(end -0.12065 0.2794)
			(stroke
				(width 0.1)
				(type default)
			)
			(layer "F.Fab")
		)
		(fp_line
			(start -0.12065 0.3048)
			(end -0.67945 0.3048)
			(stroke
				(width 0.1)
				(type default)
			)
			(layer "F.Fab")
		)
		(fp_line
			(start -0.12065 0.2794)
			(end -0.12065 0.3048)
			(stroke
				(width 0.1)
				(type default)
			)
			(layer "F.Fab")
		)
		(fp_line
			(start -0.12065 -0.2794)
			(end 0.12065 -0.2794)
			(stroke
				(width 0.1)
				(type default)
			)
			(layer "F.Fab")
		)
		(fp_line
			(start -0.12065 -0.305054)
			(end -0.12065 -0.2794)
			(stroke
				(width 0.1)
				(type default)
			)
			(layer "F.Fab")
		)
		(fp_line
			(start -0.67945 0.3048)
			(end -0.67945 -0.305054)
			(stroke
				(width 0.1)
				(type default)
			)
			(layer "F.Fab")
		)
		(fp_line
			(start -0.67945 -0.305054)
			(end -0.12065 -0.305054)
			(stroke
				(width 0.1)
				(type default)
			)
			(layer "F.Fab")
		)
		(pad "1" smd circle
			(at -0.40005 0 180)
			(size 0 0)
			(layers "F.Cu" "F.Mask" "F.Paste")
			(net "IRQ_PVCCIN_CPU0_VRHOT_R_N")
		)
		(pad "2" smd circle
			(at 0.40005 0 180)
			(size 0 0)
			(layers "F.Cu" "F.Mask" "F.Paste")
			(net "IRQ_PVCCIN_CPU0_VRHOT_N")
		)
	)
	(footprint ""
		(layer "F.Cu")
		(at 207.43418 -127.996188 90)
		(property "Reference" "R2531"
			(at 0 0 90)
			(layer "F.SilkS")
			(hide yes)
			(effects
				(font
					(size 1.27 1.27)
				)
			)
		)
		(property "Value" ""
			(at 0 0 90)
			(layer "F.Fab")
			(effects
				(font
					(size 1.27 1.27)
				)
			)
		)
		(duplicate_pad_numbers_are_jumpers no)
		(fp_line
			(start 0.7874 -0.4064)
			(end 0.7874 0.4064)
			(stroke
				(width 0.1524)
				(type default)
			)
			(layer "F.SilkS")
		)
		(fp_line
			(start -0.7874 -0.4064)
			(end 0.7874 -0.4064)
			(stroke
				(width 0.1524)
				(type default)
			)
			(layer "F.SilkS")
		)
		(fp_line
			(start 0.7874 0.4064)
			(end -0.7874 0.4064)
			(stroke
				(width 0.1524)
				(type default)
			)
			(layer "F.SilkS")
		)
		(fp_line
			(start -0.7874 0.4064)
			(end -0.7874 -0.4064)
			(stroke
				(width 0.1524)
				(type default)
			)
			(layer "F.SilkS")
		)
		(fp_line
			(start -0.12065 -0.305054)
			(end -0.12065 -0.2794)
			(stroke
				(width 0.1)
				(type default)
			)
			(layer "F.Fab")
		)
		(fp_line
			(start -0.67945 -0.305054)
			(end -0.12065 -0.305054)
			(stroke
				(width 0.1)
				(type default)
			)
			(layer "F.Fab")
		)
		(fp_line
			(start 0.67945 -0.3048)
			(end 0.67945 0.3048)
			(stroke
				(width 0.1)
				(type default)
			)
			(layer "F.Fab")
		)
		(fp_line
			(start 0.12065 -0.3048)
			(end 0.67945 -0.3048)
			(stroke
				(width 0.1)
				(type default)
			)
			(layer "F.Fab")
		)
		(fp_line
			(start 0.12065 -0.2794)
			(end 0.12065 -0.3048)
			(stroke
				(width 0.1)
				(type default)
			)
			(layer "F.Fab")
		)
		(fp_line
			(start -0.12065 -0.2794)
			(end 0.12065 -0.2794)
			(stroke
				(width 0.1)
				(type default)
			)
			(layer "F.Fab")
		)
		(fp_line
			(start 0.120396 0.2794)
			(end -0.12065 0.2794)
			(stroke
				(width 0.1)
				(type default)
			)
			(layer "F.Fab")
		)
		(fp_line
			(start -0.12065 0.2794)
			(end -0.12065 0.3048)
			(stroke
				(width 0.1)
				(type default)
			)
			(layer "F.Fab")
		)
		(fp_line
			(start 0.67945 0.3048)
			(end 0.120396 0.3048)
			(stroke
				(width 0.1)
				(type default)
			)
			(layer "F.Fab")
		)
		(fp_line
			(start 0.120396 0.3048)
			(end 0.120396 0.2794)
			(stroke
				(width 0.1)
				(type default)
			)
			(layer "F.Fab")
		)
		(fp_line
			(start -0.12065 0.3048)
			(end -0.67945 0.3048)
			(stroke
				(width 0.1)
				(type default)
			)
			(layer "F.Fab")
		)
		(fp_line
			(start -0.67945 0.3048)
			(end -0.67945 -0.305054)
			(stroke
				(width 0.1)
				(type default)
			)
			(layer "F.Fab")
		)
		(pad "1" smd circle
			(at -0.40005 0 90)
			(size 0 0)
			(layers "F.Cu" "F.Mask" "F.Paste")
			(net "MB0_P12V_STBY_PWRGD")
		)
		(pad "2" smd circle
			(at 0.40005 0 90)
			(size 0 0)
			(layers "F.Cu" "F.Mask" "F.Paste")
			(net "FM_P12V_HSC_EN_R")
		)
	)
	(footprint ""
		(layer "F.Cu")
		(at 432.50104 -122.988578 90)
		(property "Reference" "PU35"
			(at -1.01219 -8.547354 0)
			(unlocked yes)
			(layer "F.SilkS")
			(effects
				(font
					(size 0.7874 0.5842)
					(thickness 0.1524)
				)
				(justify left)
			)
		)
		(property "Value" ""
			(at 0 0 90)
			(layer "F.Fab")
			(effects
				(font
					(size 1.27 1.27)
				)
			)
		)
		(duplicate_pad_numbers_are_jumpers no)
		(fp_line
			(start 0.1778 -3.2385)
			(end 0.1778 -2.8575)
			(stroke
				(width 0.1524)
				(type default)
			)
			(layer "F.SilkS")
		)
		(fp_line
			(start -1.8034 -2.8702)
			(end -1.8034 -3.6322)
			(stroke
				(width 0.1524)
				(type default)
			)
			(layer "F.SilkS")
		)
		(fp_line
			(start 2.500122 -2.500122)
			(end 2.500122 -2.015998)
			(stroke
				(width 0.1524)
				(type default)
			)
			(layer "F.SilkS")
		)
		(fp_line
			(start 2.015998 -2.500122)
			(end 2.500122 -2.500122)
			(stroke
				(width 0.1524)
				(type default)
			)
			(layer "F.SilkS")
		)
		(fp_line
			(start -2.500122 -2.500122)
			(end -2.015998 -2.500122)
			(stroke
				(width 0.1524)
				(type default)
			)
			(layer "F.SilkS")
		)
		(fp_line
			(start -2.500122 -2.015998)
			(end -2.500122 -2.500122)
			(stroke
				(width 0.1524)
				(type default)
			)
			(layer "F.SilkS")
		)
		(fp_line
			(start 2.8702 -1.778)
			(end 3.6322 -1.778)
			(stroke
				(width 0.1524)
				(type default)
			)
			(layer "F.SilkS")
		)
		(fp_line
			(start -3.2639 -0.1778)
			(end -2.8829 -0.1778)
			(stroke
				(width 0.1524)
				(type default)
			)
			(layer "F.SilkS")
		)
		(fp_line
			(start 2.8829 0.2032)
			(end 3.2639 0.2032)
			(stroke
				(width 0.1524)
				(type default)
			)
			(layer "F.SilkS")
		)
		(fp_line
			(start -3.6576 1.8034)
			(end -2.8956 1.8034)
			(stroke
				(width 0.1524)
				(type default)
			)
			(layer "F.SilkS")
		)
		(fp_line
			(start 2.500122 2.015998)
			(end 2.500122 2.500122)
			(stroke
				(width 0.1524)
				(type default)
			)
			(layer "F.SilkS")
		)
		(fp_line
			(start 2.500122 2.500122)
			(end 2.015998 2.500122)
			(stroke
				(width 0.1524)
				(type default)
			)
			(layer "F.SilkS")
		)
		(fp_line
			(start -2.015998 2.500122)
			(end -2.500122 2.500122)
			(stroke
				(width 0.1524)
				(type default)
			)
			(layer "F.SilkS")
		)
		(fp_line
			(start -2.500122 2.500122)
			(end -2.500122 2.018538)
			(stroke
				(width 0.1524)
				(type default)
			)
			(layer "F.SilkS")
		)
		(fp_line
			(start -0.2032 2.8829)
			(end -0.2032 3.2639)
			(stroke
				(width 0.1524)
				(type default)
			)
			(layer "F.SilkS")
		)
		(fp_line
			(start 1.778 3.6322)
			(end 1.778 2.8702)
			(stroke
				(width 0.1524)
				(type default)
			)
			(layer "F.SilkS")
		)
		(fp_poly
			(pts
				(xy -2.855468 -2.635504) (xy -2.64922 -2.017014) (xy -3.26771 -2.223008)
			)
			(stroke
				(width 0)
				(type default)
			)
			(fill yes)
			(layer "F.SilkS")
		)
		(fp_line
			(start 0.1778 -3.2385)
			(end 0.1778 -2.8575)
			(stroke
				(width 0.1)
				(type default)
			)
			(layer "F.Fab")
		)
		(fp_line
			(start -1.8034 -2.8702)
			(end -1.8034 -3.6322)
			(stroke
				(width 0.1)
				(type default)
			)
			(layer "F.Fab")
		)
		(fp_line
			(start 2.500122 -2.500122)
			(end 2.500122 2.500122)
			(stroke
				(width 0.1)
				(type default)
			)
			(layer "F.Fab")
		)
		(fp_line
			(start -2.500122 -2.500122)
			(end 2.500122 -2.500122)
			(stroke
				(width 0.1)
				(type default)
			)
			(layer "F.Fab")
		)
		(fp_line
			(start 2.8702 -1.778)
			(end 3.6322 -1.778)
			(stroke
				(width 0.1)
				(type default)
			)
			(layer "F.Fab")
		)
		(fp_line
			(start -3.2639 -0.1778)
			(end -2.8829 -0.1778)
			(stroke
				(width 0.1)
				(type default)
			)
			(layer "F.Fab")
		)
		(fp_line
			(start 2.8829 0.2032)
			(end 3.2639 0.2032)
			(stroke
				(width 0.1)
				(type default)
			)
			(layer "F.Fab")
		)
		(fp_line
			(start -3.6576 1.8034)
			(end -2.8956 1.8034)
			(stroke
				(width 0.1)
				(type default)
			)
			(layer "F.Fab")
		)
		(fp_line
			(start 2.500122 2.500122)
			(end -2.500122 2.500122)
			(stroke
				(width 0.1)
				(type default)
			)
			(layer "F.Fab")
		)
		(fp_line
			(start -2.500122 2.500122)
			(end -2.500122 -2.500122)
			(stroke
				(width 0.1)
				(type default)
			)
			(layer "F.Fab")
		)
		(fp_line
			(start -0.2032 2.8829)
			(end -0.2032 3.2639)
			(stroke
				(width 0.1)
				(type default)
			)
			(layer "F.Fab")
		)
		(fp_line
			(start 1.778 3.6322)
			(end 1.778 2.8702)
			(stroke
				(width 0.1)
				(type default)
			)
			(layer "F.Fab")
		)
		(fp_poly
			(pts
				(xy -2.921 -1.800098) (xy -3.504184 -1.508506) (xy -3.504184 -2.09169)
			)
			(stroke
				(width 0)
				(type default)
			)
			(fill yes)
			(layer "F.Fab")
		)
		(fp_text user "31"
			(at 3.1877 -3.0988 0)
			(unlocked yes)
			(layer "F.SilkS")
			(effects
				(font
					(size 0.635 0.4064)
					(thickness 0.1524)
				)
				(justify left)
			)
		)
		(fp_text user "40"
			(at -5.81152 -1.8161 0)
			(unlocked yes)
			(layer "F.SilkS")
			(effects
				(font
					(size 0.635 0.4064)
					(thickness 0.1524)
				)
				(justify left)
			)
		)
		(fp_text user "30"
			(at 3.535172 -1.33604 0)
			(unlocked yes)
			(layer "F.SilkS")
			(effects
				(font
					(size 0.635 0.4064)
					(thickness 0.1524)
				)
				(justify left)
			)
		)
		(fp_text user "21"
			(at 3.627628 0.47498 0)
			(unlocked yes)
			(layer "F.SilkS")
			(effects
				(font
					(size 0.635 0.4064)
					(thickness 0.1524)
				)
				(justify left)
			)
		)
		(fp_text user "10"
			(at -3.100832 2.05232 0)
			(unlocked yes)
			(layer "F.SilkS")
			(effects
				(font
					(size 0.635 0.4064)
					(thickness 0.1524)
				)
				(justify left)
			)
		)
		(fp_text user "20"
			(at 2.77622 2.74828 0)
			(unlocked yes)
			(layer "F.SilkS")
			(effects
				(font
					(size 0.635 0.4064)
					(thickness 0.1524)
				)
				(justify left)
			)
		)
		(fp_text user "11"
			(at -2.18948 2.90068 0)
			(unlocked yes)
			(layer "F.SilkS")
			(effects
				(font
					(size 0.635 0.4064)
					(thickness 0.1524)
				)
				(justify left)
			)
		)
		(fp_text user "31"
			(at 1.8542 -3.172968 90)
			(unlocked yes)
			(layer "F.Fab")
			(effects
				(font
					(size 0.635 0.4064)
					(thickness 0.1524)
				)
				(justify left)
			)
		)
		(fp_text user "30"
			(at 3.223768 -3.0988 0)
			(unlocked yes)
			(layer "F.Fab")
			(effects
				(font
					(size 0.635 0.4064)
					(thickness 0.1524)
				)
				(justify left)
			)
		)
		(fp_text user "40"
			(at -3.2004 -3.096768 90)
			(unlocked yes)
			(layer "F.Fab")
			(effects
				(font
					(size 0.635 0.4064)
					(thickness 0.1524)
				)
				(justify left)
			)
		)
		(fp_text user "21"
			(at 3.274568 1.8796 0)
			(unlocked yes)
			(layer "F.Fab")
			(effects
				(font
					(size 0.635 0.4064)
					(thickness 0.1524)
				)
				(justify left)
			)
		)
		(fp_text user "10"
			(at -3.253232 2.1336 0)
			(unlocked yes)
			(layer "F.Fab")
			(effects
				(font
					(size 0.635 0.4064)
					(thickness 0.1524)
				)
				(justify left)
			)
		)
		(fp_text user "20"
			(at 2.0828 3.253232 90)
			(unlocked yes)
			(layer "F.Fab")
			(effects
				(font
					(size 0.635 0.4064)
					(thickness 0.1524)
				)
				(justify left)
			)
		)
		(fp_text user "11"
			(at -2.8702 3.278632 90)
			(unlocked yes)
			(layer "F.Fab")
			(effects
				(font
					(size 0.635 0.4064)
					(thickness 0.1524)
				)
				(justify left)
			)
		)
		(pad "1" smd rect
			(at -2.400046 -1.800098)
			(size 0.1778 0.6096)
			(layers "F.Cu" "F.Mask" "F.Paste")
			(net "NC_PVCCD_HV_CPU0_APWM8")
		)
		(pad "2" smd rect
			(at -2.400046 -1.400048)
			(size 0.1778 0.6096)
			(layers "F.Cu" "F.Mask" "F.Paste")
			(net "NC_PVCCD_HV_CPU0_APWM7")
		)
		(pad "3" smd rect
			(at -2.400046 -0.999998)
			(size 0.1778 0.6096)
			(layers "F.Cu" "F.Mask" "F.Paste")
			(net "NC_PVCCD_HV_CPU0_APWM6")
		)
		(pad "4" smd rect
			(at -2.400046 -0.599948)
			(size 0.1778 0.6096)
			(layers "F.Cu" "F.Mask" "F.Paste")
			(net "NC_PVCCD_HV_CPU0_APWM5")
		)
		(pad "5" smd rect
			(at -2.400046 -0.199898)
			(size 0.1778 0.6096)
			(layers "F.Cu" "F.Mask" "F.Paste")
			(net "NC_PVCCD_HV_CPU0_APWM4")
		)
		(pad "6" smd rect
			(at -2.400046 0.199898)
			(size 0.1778 0.6096)
			(layers "F.Cu" "F.Mask" "F.Paste")
			(net "NC_PVCCD_HV_CPU0_APWM3")
		)
		(pad "7" smd rect
			(at -2.400046 0.599948)
			(size 0.1778 0.6096)
			(layers "F.Cu" "F.Mask" "F.Paste")
			(net "NC_PVCCD_HV_CPU0_APWM2")
		)
		(pad "8" smd rect
			(at -2.400046 0.999998)
			(size 0.1778 0.6096)
			(layers "F.Cu" "F.Mask" "F.Paste")
			(net "PVCCD_HV_CPU0_APWM1")
		)
		(pad "9" smd rect
			(at -2.400046 1.400048)
			(size 0.1778 0.6096)
			(layers "F.Cu" "F.Mask" "F.Paste")
			(net "SMB_DIO_PVCCD_HV_CPU0")
		)
		(pad "10" smd rect
			(at -2.400046 1.800098)
			(size 0.1778 0.6096)
			(layers "F.Cu" "F.Mask" "F.Paste")
			(net "SMB_CLK_PVCCD_HV_CPU0")
		)
		(pad "11" smd rect
			(at -1.800098 2.400046 90)
			(size 0.1778 0.6096)
			(layers "F.Cu" "F.Mask" "F.Paste")
			(net "NC_PVCCD_HV_CPU0_SMB_ALERT")
		)
		(pad "12" smd rect
			(at -1.400048 2.400046 90)
			(size 0.1778 0.6096)
			(layers "F.Cu" "F.Mask" "F.Paste")
			(net "PWRGD_PVCCD_HV_CPU0_R")
		)
		(pad "13" smd rect
			(at -0.999998 2.400046 90)
			(size 0.1778 0.6096)
			(layers "F.Cu" "F.Mask" "F.Paste")
			(net "PVCCD_HV_CPU0_EN_R")
		)
		(pad "14" smd rect
			(at -0.599948 2.400046 90)
			(size 0.1778 0.6096)
			(layers "F.Cu" "F.Mask" "F.Paste")
			(net "IRQ_PVCCD_CPU0_VRHOT_LVC3_R_N")
		)
		(pad "15" smd rect
			(at -0.199898 2.400046 90)
			(size 0.1778 0.6096)
			(layers "F.Cu" "F.Mask" "F.Paste")
			(net "PVCCD_HV_CPU0_PIN_ALT")
		)
		(pad "16" smd rect
			(at 0.199898 2.400046 90)
			(size 0.1778 0.6096)
			(layers "F.Cu" "F.Mask" "F.Paste")
			(net "NC_PVCCD_HV_CPU0_BVR_RDY")
		)
		(pad "17" smd rect
			(at 0.599948 2.400046 90)
			(size 0.1778 0.6096)
			(layers "F.Cu" "F.Mask" "F.Paste")
			(net "SVID_CLK_PVCCD_HV_CPU0_R")
		)
		(pad "18" smd rect
			(at 0.999998 2.400046 90)
			(size 0.1778 0.6096)
			(layers "F.Cu" "F.Mask" "F.Paste")
			(net "SVID_DIO_PVCCD_HV_CPU0_R")
		)
		(pad "19" smd rect
			(at 1.400048 2.400046 90)
			(size 0.1778 0.6096)
			(layers "F.Cu" "F.Mask" "F.Paste")
			(net "SVID_ALERT_PVCCD_HV_CPU0_R")
		)
		(pad "20" smd rect
			(at 1.800098 2.400046 90)
			(size 0.1778 0.6096)
			(layers "F.Cu" "F.Mask" "F.Paste")
			(net "GND")
		)
		(pad "21" smd rect
			(at 2.400046 1.800098)
			(size 0.1778 0.6096)
			(layers "F.Cu" "F.Mask" "F.Paste")
			(net "SH_PVCCD_HV_CPU0_R")
		)
		(pad "22" smd rect
			(at 2.400046 1.400048)
			(size 0.1778 0.6096)
			(layers "F.Cu" "F.Mask" "F.Paste")
			(net "VSENSE_PVCCD_HV_CPU0_DN")
		)
		(pad "23" smd rect
			(at 2.400046 0.999998)
			(size 0.1778 0.6096)
			(layers "F.Cu" "F.Mask" "F.Paste")
			(net "PVCCD_HV_CPU0_ACSP1")
		)
		(pad "24" smd rect
			(at 2.400046 0.599948)
			(size 0.1778 0.6096)
			(layers "F.Cu" "F.Mask" "F.Paste")
			(net "NC_PVCCD_HV_CPU0_ACSP2")
		)
		(pad "25" smd rect
			(at 2.400046 0.199898)
			(size 0.1778 0.6096)
			(layers "F.Cu" "F.Mask" "F.Paste")
			(net "NC_PVCCD_HV_CPU0_ACSP3")
		)
		(pad "26" smd rect
			(at 2.400046 -0.199898)
			(size 0.1778 0.6096)
			(layers "F.Cu" "F.Mask" "F.Paste")
			(net "NC_PVCCD_HV_CPU0_ACSP4")
		)
		(pad "27" smd rect
			(at 2.400046 -0.599948)
			(size 0.1778 0.6096)
			(layers "F.Cu" "F.Mask" "F.Paste")
			(net "NC_PVCCD_HV_CPU0_ACSP5")
		)
		(pad "28" smd rect
			(at 2.400046 -0.999998)
			(size 0.1778 0.6096)
			(layers "F.Cu" "F.Mask" "F.Paste")
			(net "NC_PVCCD_HV_CPU0_ACSP6")
		)
		(pad "29" smd rect
			(at 2.400046 -1.400048)
			(size 0.1778 0.6096)
			(layers "F.Cu" "F.Mask" "F.Paste")
			(net "NC_PVCCD_HV_CPU0_ACSP7")
		)
		(pad "30" smd rect
			(at 2.400046 -1.800098)
			(size 0.1778 0.6096)
			(layers "F.Cu" "F.Mask" "F.Paste")
			(net "NC_PVCCD_HV_CPU0_ACSP8")
		)
		(pad "31" smd rect
			(at 1.800098 -2.400046 90)
			(size 0.1778 0.6096)
			(layers "F.Cu" "F.Mask" "F.Paste")
			(net "GND")
		)
		(pad "32" smd rect
			(at 1.400048 -2.400046 90)
			(size 0.1778 0.6096)
			(layers "F.Cu" "F.Mask" "F.Paste")
			(net "GND")
		)
		(pad "33" smd rect
			(at 0.999998 -2.400046 90)
			(size 0.1778 0.6096)
			(layers "F.Cu" "F.Mask" "F.Paste")
			(net "PVCCD_HV_CPU0_FAULT")
		)
		(pad "34" smd rect
			(at 0.599948 -2.400046 90)
			(size 0.1778 0.6096)
			(layers "F.Cu" "F.Mask" "F.Paste")
			(net "PVCCD_HV_CPU0_ADDR")
		)
		(pad "35" smd rect
			(at 0.199898 -2.400046 90)
			(size 0.1778 0.6096)
			(layers "F.Cu" "F.Mask" "F.Paste")
			(net "PVCCD_HV_CPU0_ATSEN")
		)
		(pad "36" smd rect
			(at -0.199898 -2.400046 90)
			(size 0.1778 0.6096)
			(layers "F.Cu" "F.Mask" "F.Paste")
			(net "PVCCD_HV_CPU0_ISYS_R")
		)
		(pad "37" smd rect
			(at -0.599948 -2.400046 90)
			(size 0.1778 0.6096)
			(layers "F.Cu" "F.Mask" "F.Paste")
			(net "PVCCD_HV_CPU0_ISENSE_P")
		)
		(pad "38" smd rect
			(at -0.999998 -2.400046 90)
			(size 0.1778 0.6096)
			(layers "F.Cu" "F.Mask" "F.Paste")
			(net "PVCCD_HV_CPU0_ISENSE_N")
		)
		(pad "39" smd rect
			(at -1.400048 -2.400046 90)
			(size 0.1778 0.6096)
			(layers "F.Cu" "F.Mask" "F.Paste")
			(net "PVCCD_HV_CPU0_VCC")
		)
		(pad "40" smd rect
			(at -1.800098 -2.400046 90)
			(size 0.1778 0.6096)
			(layers "F.Cu" "F.Mask" "F.Paste")
			(net "PVCCD_HV_CPU0_VREF")
		)
		(pad "TH" smd rect
			(at 0 0 90)
			(size 3.6576 3.6576)
			(layers "F.Cu" "F.Mask" "F.Paste")
			(net "GND")
		)
		(zone
			(layer "F.Cu")
			(hatch none 0.5)
			(connect_pads
				(clearance 0)
			)
			(min_thickness 0.25)
			(keepout
				(tracks not_allowed)
				(vias allowed)
				(pads allowed)
				(copperpour not_allowed)
				(footprints allowed)
			)
			(placement
				(enabled no)
				(sheetname "")
			)
			(fill
				(thermal_gap 0.5)
				(thermal_bridge_width 0.5)
				(island_removal_mode 0)
			)
			(polygon
				(pts
					(xy 434.38064 -124.678948) (xy 434.53304 -124.678948) (xy 434.53304 -120.956578) (xy 430.64684 -120.956578)
					(xy 430.64684 -121.108978) (xy 434.38064 -121.108978)
				)
			)
		)
	)
	(footprint ""
		(layer "F.Cu")
		(at 29.51988 -430.875948)
		(property "Reference" "C1977"
			(at 0 0 0)
			(layer "F.SilkS")
			(hide yes)
			(effects
				(font
					(size 1.27 1.27)
				)
			)
		)
		(property "Value" ""
			(at 0 0 0)
			(layer "F.Fab")
			(effects
				(font
					(size 1.27 1.27)
				)
			)
		)
		(duplicate_pad_numbers_are_jumpers no)
		(fp_line
			(start -0.7874 -0.4064)
			(end 0.7874 -0.4064)
			(stroke
				(width 0.1524)
				(type default)
			)
			(layer "F.SilkS")
		)
		(fp_line
			(start -0.7874 0.4064)
			(end -0.7874 -0.4064)
			(stroke
				(width 0.1524)
				(type default)
			)
			(layer "F.SilkS")
		)
		(fp_line
			(start 0.7874 -0.4064)
			(end 0.7874 0.4064)
			(stroke
				(width 0.1524)
				(type default)
			)
			(layer "F.SilkS")
		)
		(fp_line
			(start 0.7874 0.4064)
			(end -0.7874 0.4064)
			(stroke
				(width 0.1524)
				(type default)
			)
			(layer "F.SilkS")
		)
		(fp_line
			(start -0.67945 -0.305054)
			(end -0.12065 -0.305054)
			(stroke
				(width 0.1)
				(type default)
			)
			(layer "F.Fab")
		)
		(fp_line
			(start -0.67945 0.3048)
			(end -0.67945 -0.305054)
			(stroke
				(width 0.1)
				(type default)
			)
			(layer "F.Fab")
		)
		(fp_line
			(start -0.12065 -0.305054)
			(end -0.12065 -0.2794)
			(stroke
				(width 0.1)
				(type default)
			)
			(layer "F.Fab")
		)
		(fp_line
			(start -0.12065 -0.2794)
			(end 0.12065 -0.2794)
			(stroke
				(width 0.1)
				(type default)
			)
			(layer "F.Fab")
		)
		(fp_line
			(start -0.12065 0.2794)
			(end -0.12065 0.3048)
			(stroke
				(width 0.1)
				(type default)
			)
			(layer "F.Fab")
		)
		(fp_line
			(start -0.12065 0.3048)
			(end -0.67945 0.3048)
			(stroke
				(width 0.1)
				(type default)
			)
			(layer "F.Fab")
		)
		(fp_line
			(start 0.120396 0.2794)
			(end -0.12065 0.2794)
			(stroke
				(width 0.1)
				(type default)
			)
			(layer "F.Fab")
		)
		(fp_line
			(start 0.120396 0.3048)
			(end 0.120396 0.2794)
			(stroke
				(width 0.1)
				(type default)
			)
			(layer "F.Fab")
		)
		(fp_line
			(start 0.12065 -0.3048)
			(end 0.67945 -0.3048)
			(stroke
				(width 0.1)
				(type default)
			)
			(layer "F.Fab")
		)
		(fp_line
			(start 0.12065 -0.2794)
			(end 0.12065 -0.3048)
			(stroke
				(width 0.1)
				(type default)
			)
			(layer "F.Fab")
		)
		(fp_line
			(start 0.67945 -0.3048)
			(end 0.67945 0.3048)
			(stroke
				(width 0.1)
				(type default)
			)
			(layer "F.Fab")
		)
		(fp_line
			(start 0.67945 0.3048)
			(end 0.120396 0.3048)
			(stroke
				(width 0.1)
				(type default)
			)
			(layer "F.Fab")
		)
		(pad "1" smd circle
			(at -0.40005 0)
			(size 0 0)
			(layers "F.Cu" "F.Mask" "F.Paste")
			(net "P3V3_AUX")
		)
		(pad "2" smd circle
			(at 0.40005 0)
			(size 0 0)
			(layers "F.Cu" "F.Mask" "F.Paste")
			(net "GND")
		)
	)
	(footprint ""
		(layer "F.Cu")
		(at 425.705016 -136.41451 90)
		(property "Reference" "PU5"
			(at -5.203952 -1.067816 0)
			(unlocked yes)
			(layer "F.SilkS")
			(effects
				(font
					(size 0.7874 0.5842)
					(thickness 0.1524)
				)
				(justify left)
			)
		)
		(property "Value" ""
			(at 0 0 90)
			(layer "F.Fab")
			(effects
				(font
					(size 1.27 1.27)
				)
			)
		)
		(duplicate_pad_numbers_are_jumpers no)
		(fp_line
			(start 0.1778 -3.2385)
			(end 0.1778 -2.8575)
			(stroke
				(width 0.1524)
				(type default)
			)
			(layer "F.SilkS")
		)
		(fp_line
			(start -1.8034 -2.8702)
			(end -1.8034 -3.6322)
			(stroke
				(width 0.1524)
				(type default)
			)
			(layer "F.SilkS")
		)
		(fp_line
			(start 2.500122 -2.500122)
			(end 2.500122 -2.015998)
			(stroke
				(width 0.1524)
				(type default)
			)
			(layer "F.SilkS")
		)
		(fp_line
			(start 2.015998 -2.500122)
			(end 2.500122 -2.500122)
			(stroke
				(width 0.1524)
				(type default)
			)
			(layer "F.SilkS")
		)
		(fp_line
			(start -2.500122 -2.500122)
			(end -2.015998 -2.500122)
			(stroke
				(width 0.1524)
				(type default)
			)
			(layer "F.SilkS")
		)
		(fp_line
			(start -2.500122 -2.015998)
			(end -2.500122 -2.500122)
			(stroke
				(width 0.1524)
				(type default)
			)
			(layer "F.SilkS")
		)
		(fp_line
			(start 2.8702 -1.778)
			(end 3.6322 -1.778)
			(stroke
				(width 0.1524)
				(type default)
			)
			(layer "F.SilkS")
		)
		(fp_line
			(start -3.2639 -0.1778)
			(end -2.8829 -0.1778)
			(stroke
				(width 0.1524)
				(type default)
			)
			(layer "F.SilkS")
		)
		(fp_line
			(start 2.8829 0.2032)
			(end 3.2639 0.2032)
			(stroke
				(width 0.1524)
				(type default)
			)
			(layer "F.SilkS")
		)
		(fp_line
			(start -3.6576 1.8034)
			(end -2.8956 1.8034)
			(stroke
				(width 0.1524)
				(type default)
			)
			(layer "F.SilkS")
		)
		(fp_line
			(start 2.500122 2.015998)
			(end 2.500122 2.500122)
			(stroke
				(width 0.1524)
				(type default)
			)
			(layer "F.SilkS")
		)
		(fp_line
			(start 2.500122 2.500122)
			(end 2.015998 2.500122)
			(stroke
				(width 0.1524)
				(type default)
			)
			(layer "F.SilkS")
		)
		(fp_line
			(start -2.015998 2.500122)
			(end -2.500122 2.500122)
			(stroke
				(width 0.1524)
				(type default)
			)
			(layer "F.SilkS")
		)
		(fp_line
			(start -2.500122 2.500122)
			(end -2.500122 2.018538)
			(stroke
				(width 0.1524)
				(type default)
			)
			(layer "F.SilkS")
		)
		(fp_line
			(start -0.2032 2.8829)
			(end -0.2032 3.2639)
			(stroke
				(width 0.1524)
				(type default)
			)
			(layer "F.SilkS")
		)
		(fp_line
			(start 1.778 3.6322)
			(end 1.778 2.8702)
			(stroke
				(width 0.1524)
				(type default)
			)
			(layer "F.SilkS")
		)
		(fp_poly
			(pts
				(xy -3.504184 -2.09169) (xy -2.921 -1.800098) (xy -3.504184 -1.508506)
			)
			(stroke
				(width 0)
				(type default)
			)
			(fill yes)
			(layer "F.SilkS")
		)
		(fp_line
			(start 0.1778 -3.2385)
			(end 0.1778 -2.8575)
			(stroke
				(width 0.1)
				(type default)
			)
			(layer "F.Fab")
		)
		(fp_line
			(start -1.8034 -2.8702)
			(end -1.8034 -3.6322)
			(stroke
				(width 0.1)
				(type default)
			)
			(layer "F.Fab")
		)
		(fp_line
			(start 2.500122 -2.500122)
			(end 2.500122 2.500122)
			(stroke
				(width 0.1)
				(type default)
			)
			(layer "F.Fab")
		)
		(fp_line
			(start -2.500122 -2.500122)
			(end 2.500122 -2.500122)
			(stroke
				(width 0.1)
				(type default)
			)
			(layer "F.Fab")
		)
		(fp_line
			(start 2.8702 -1.778)
			(end 3.6322 -1.778)
			(stroke
				(width 0.1)
				(type default)
			)
			(layer "F.Fab")
		)
		(fp_line
			(start -3.2639 -0.1778)
			(end -2.8829 -0.1778)
			(stroke
				(width 0.1)
				(type default)
			)
			(layer "F.Fab")
		)
		(fp_line
			(start 2.8829 0.2032)
			(end 3.2639 0.2032)
			(stroke
				(width 0.1)
				(type default)
			)
			(layer "F.Fab")
		)
		(fp_line
			(start -3.6576 1.8034)
			(end -2.8956 1.8034)
			(stroke
				(width 0.1)
				(type default)
			)
			(layer "F.Fab")
		)
		(fp_line
			(start 2.500122 2.500122)
			(end -2.500122 2.500122)
			(stroke
				(width 0.1)
				(type default)
			)
			(layer "F.Fab")
		)
		(fp_line
			(start -2.500122 2.500122)
			(end -2.500122 -2.500122)
			(stroke
				(width 0.1)
				(type default)
			)
			(layer "F.Fab")
		)
		(fp_line
			(start -0.2032 2.8829)
			(end -0.2032 3.2639)
			(stroke
				(width 0.1)
				(type default)
			)
			(layer "F.Fab")
		)
		(fp_line
			(start 1.778 3.6322)
			(end 1.778 2.8702)
			(stroke
				(width 0.1)
				(type default)
			)
			(layer "F.Fab")
		)
		(fp_poly
			(pts
				(xy -2.921 -1.800098) (xy -3.504184 -1.508506) (xy -3.504184 -2.09169)
			)
			(stroke
				(width 0)
				(type default)
			)
			(fill yes)
			(layer "F.Fab")
		)
		(fp_text user "40"
			(at -2.684272 -3.844036 0)
			(unlocked yes)
			(layer "F.SilkS")
			(effects
				(font
					(size 0.635 0.4064)
					(thickness 0.1524)
				)
				(justify left)
			)
		)
		(fp_text user "31"
			(at 2.39268 -3.686556 0)
			(unlocked yes)
			(layer "F.SilkS")
			(effects
				(font
					(size 0.635 0.4064)
					(thickness 0.1524)
				)
				(justify left)
			)
		)
		(fp_text user "30"
			(at 3.363468 -1.184656 0)
			(unlocked yes)
			(layer "F.SilkS")
			(effects
				(font
					(size 0.635 0.4064)
					(thickness 0.1524)
				)
				(justify left)
			)
		)
		(fp_text user "21"
			(at 5.57276 2.102104 0)
			(unlocked yes)
			(layer "F.SilkS")
			(effects
				(font
					(size 0.635 0.4064)
					(thickness 0.1524)
				)
				(justify left)
			)
		)
		(fp_text user "10"
			(at -3.504692 2.1336 0)
			(unlocked yes)
			(layer "F.SilkS")
			(effects
				(font
					(size 0.635 0.4064)
					(thickness 0.1524)
				)
				(justify left)
			)
		)
		(fp_text user "20"
			(at 2.35712 2.881884 0)
			(unlocked yes)
			(layer "F.SilkS")
			(effects
				(font
					(size 0.635 0.4064)
					(thickness 0.1524)
				)
				(justify left)
			)
		)
		(fp_text user "11"
			(at -2.143252 2.955544 0)
			(unlocked yes)
			(layer "F.SilkS")
			(effects
				(font
					(size 0.635 0.4064)
					(thickness 0.1524)
				)
				(justify left)
			)
		)
		(fp_text user "31"
			(at 1.8542 -3.172968 90)
			(unlocked yes)
			(layer "F.Fab")
			(effects
				(font
					(size 0.635 0.4064)
					(thickness 0.1524)
				)
				(justify left)
			)
		)
		(fp_text user "40"
			(at -3.2004 -3.096768 90)
			(unlocked yes)
			(layer "F.Fab")
			(effects
				(font
					(size 0.635 0.4064)
					(thickness 0.1524)
				)
				(justify left)
			)
		)
		(fp_text user "30"
			(at 3.205988 -2.49682 0)
			(unlocked yes)
			(layer "F.Fab")
			(effects
				(font
					(size 0.635 0.4064)
					(thickness 0.1524)
				)
				(justify left)
			)
		)
		(fp_text user "21"
			(at 3.274568 1.8796 0)
			(unlocked yes)
			(layer "F.Fab")
			(effects
				(font
					(size 0.635 0.4064)
					(thickness 0.1524)
				)
				(justify left)
			)
		)
		(fp_text user "10"
			(at -3.253232 2.1336 0)
			(unlocked yes)
			(layer "F.Fab")
			(effects
				(font
					(size 0.635 0.4064)
					(thickness 0.1524)
				)
				(justify left)
			)
		)
		(fp_text user "20"
			(at 2.0828 3.253232 90)
			(unlocked yes)
			(layer "F.Fab")
			(effects
				(font
					(size 0.635 0.4064)
					(thickness 0.1524)
				)
				(justify left)
			)
		)
		(fp_text user "11"
			(at -2.8702 3.278632 90)
			(unlocked yes)
			(layer "F.Fab")
			(effects
				(font
					(size 0.635 0.4064)
					(thickness 0.1524)
				)
				(justify left)
			)
		)
		(pad "1" smd rect
			(at -2.400046 -1.800098)
			(size 0.1778 0.6096)
			(layers "F.Cu" "F.Mask" "F.Paste")
			(net "PVCCFA_EHV_CPU0_BPWM1")
		)
		(pad "2" smd rect
			(at -2.400046 -1.400048)
			(size 0.1778 0.6096)
			(layers "F.Cu" "F.Mask" "F.Paste")
			(net "NC_PVCCINFAON_CPU0_APWM7")
		)
		(pad "3" smd rect
			(at -2.400046 -0.999998)
			(size 0.1778 0.6096)
			(layers "F.Cu" "F.Mask" "F.Paste")
			(net "NC_PVCCINFAON_CPU0_APWM6")
		)
		(pad "4" smd rect
			(at -2.400046 -0.599948)
			(size 0.1778 0.6096)
			(layers "F.Cu" "F.Mask" "F.Paste")
			(net "NC_PVCCINFAON_CPU0_APWM5")
		)
		(pad "5" smd rect
			(at -2.400046 -0.199898)
			(size 0.1778 0.6096)
			(layers "F.Cu" "F.Mask" "F.Paste")
			(net "NC_PVCCINFAON_CPU0_APWM4")
		)
		(pad "6" smd rect
			(at -2.400046 0.199898)
			(size 0.1778 0.6096)
			(layers "F.Cu" "F.Mask" "F.Paste")
			(net "NC_PVCCINFAON_CPU0_APWM3")
		)
		(pad "7" smd rect
			(at -2.400046 0.599948)
			(size 0.1778 0.6096)
			(layers "F.Cu" "F.Mask" "F.Paste")
			(net "PVCCINFAON_CPU0_APWM2")
		)
		(pad "8" smd rect
			(at -2.400046 0.999998)
			(size 0.1778 0.6096)
			(layers "F.Cu" "F.Mask" "F.Paste")
			(net "PVCCINFAON_CPU0_APWM1")
		)
		(pad "9" smd rect
			(at -2.400046 1.400048)
			(size 0.1778 0.6096)
			(layers "F.Cu" "F.Mask" "F.Paste")
			(net "SMB_DIO_PVCCINFAON_CPU0")
		)
		(pad "10" smd rect
			(at -2.400046 1.800098)
			(size 0.1778 0.6096)
			(layers "F.Cu" "F.Mask" "F.Paste")
			(net "SMB_CLK_PVCCINFAON_CPU0")
		)
		(pad "11" smd rect
			(at -1.800098 2.400046 90)
			(size 0.1778 0.6096)
			(layers "F.Cu" "F.Mask" "F.Paste")
			(net "NC_PVCCINFAON_CPU0_SMB_ALERT")
		)
		(pad "12" smd rect
			(at -1.400048 2.400046 90)
			(size 0.1778 0.6096)
			(layers "F.Cu" "F.Mask" "F.Paste")
			(net "PWRGD_PVCCINFAON_CPU0_R")
		)
		(pad "13" smd rect
			(at -0.999998 2.400046 90)
			(size 0.1778 0.6096)
			(layers "F.Cu" "F.Mask" "F.Paste")
			(net "PVCCINFAON_CPU0_EN_R")
		)
		(pad "14" smd rect
			(at -0.599948 2.400046 90)
			(size 0.1778 0.6096)
			(layers "F.Cu" "F.Mask" "F.Paste")
			(net "IRQ_PVCCFA_CPU0_VRHOT_N")
		)
		(pad "15" smd rect
			(at -0.199898 2.400046 90)
			(size 0.1778 0.6096)
			(layers "F.Cu" "F.Mask" "F.Paste")
			(net "PVCCINFAON_CPU0_PIN_ALERT")
		)
		(pad "16" smd rect
			(at 0.199898 2.400046 90)
			(size 0.1778 0.6096)
			(layers "F.Cu" "F.Mask" "F.Paste")
			(net "PWRGD_PVCCFA_EHV_CPU0_R")
		)
		(pad "17" smd rect
			(at 0.599948 2.400046 90)
			(size 0.1778 0.6096)
			(layers "F.Cu" "F.Mask" "F.Paste")
			(net "SVID_CLK_PVCCINFAON_CPU0_R")
		)
		(pad "18" smd rect
			(at 0.999998 2.400046 90)
			(size 0.1778 0.6096)
			(layers "F.Cu" "F.Mask" "F.Paste")
			(net "SVID_DIO_PVCCINFAON_CPU0_R")
		)
		(pad "19" smd rect
			(at 1.400048 2.400046 90)
			(size 0.1778 0.6096)
			(layers "F.Cu" "F.Mask" "F.Paste")
			(net "SVID_ALERT_PVCCINFAON_CPU0_R")
		)
		(pad "20" smd rect
			(at 1.800098 2.400046 90)
			(size 0.1778 0.6096)
			(layers "F.Cu" "F.Mask" "F.Paste")
			(net "PVCCFA_EHV_CPU0_EN_R")
		)
		(pad "21" smd rect
			(at 2.400046 1.800098)
			(size 0.1778 0.6096)
			(layers "F.Cu" "F.Mask" "F.Paste")
			(net "SH_PVCCINFAON_CPU0_R")
		)
		(pad "22" smd rect
			(at 2.400046 1.400048)
			(size 0.1778 0.6096)
			(layers "F.Cu" "F.Mask" "F.Paste")
			(net "VSENSE_PVCCINFAON_CPU0_DN")
		)
		(pad "23" smd rect
			(at 2.400046 0.999998)
			(size 0.1778 0.6096)
			(layers "F.Cu" "F.Mask" "F.Paste")
			(net "PVCCINFAON_CPU0_ACSP1")
		)
		(pad "24" smd rect
			(at 2.400046 0.599948)
			(size 0.1778 0.6096)
			(layers "F.Cu" "F.Mask" "F.Paste")
			(net "PVCCINFAON_CPU0_ACSP2")
		)
		(pad "25" smd rect
			(at 2.400046 0.199898)
			(size 0.1778 0.6096)
			(layers "F.Cu" "F.Mask" "F.Paste")
			(net "NC_PVCCINFAON_CPU0_ACSP3")
		)
		(pad "26" smd rect
			(at 2.400046 -0.199898)
			(size 0.1778 0.6096)
			(layers "F.Cu" "F.Mask" "F.Paste")
			(net "NC_PVCCINFAON_CPU0_ACSP4")
		)
		(pad "27" smd rect
			(at 2.400046 -0.599948)
			(size 0.1778 0.6096)
			(layers "F.Cu" "F.Mask" "F.Paste")
			(net "NC_PVCCINFAON_CPU0_ACSP5")
		)
		(pad "28" smd rect
			(at 2.400046 -0.999998)
			(size 0.1778 0.6096)
			(layers "F.Cu" "F.Mask" "F.Paste")
			(net "NC_PVCCINFAON_CPU0_ACSP6")
		)
		(pad "29" smd rect
			(at 2.400046 -1.400048)
			(size 0.1778 0.6096)
			(layers "F.Cu" "F.Mask" "F.Paste")
			(net "NC_PVCCINFAON_CPU0_ACSP7")
		)
		(pad "30" smd rect
			(at 2.400046 -1.800098)
			(size 0.1778 0.6096)
			(layers "F.Cu" "F.Mask" "F.Paste")
			(net "PVCCFA_EHV_CPU0_BCSP1")
		)
		(pad "31" smd rect
			(at 1.800098 -2.400046 90)
			(size 0.1778 0.6096)
			(layers "F.Cu" "F.Mask" "F.Paste")
			(net "VSENSE_PVCCFA_EHV_CPU0_DN")
		)
		(pad "32" smd rect
			(at 1.400048 -2.400046 90)
			(size 0.1778 0.6096)
			(layers "F.Cu" "F.Mask" "F.Paste")
			(net "SH_PVCCFA_EHV_CPU0_R")
		)
		(pad "33" smd rect
			(at 0.999998 -2.400046 90)
			(size 0.1778 0.6096)
			(layers "F.Cu" "F.Mask" "F.Paste")
			(net "PVCCINFAON_CPU0_VR_FAULT")
		)
		(pad "34" smd rect
			(at 0.599948 -2.400046 90)
			(size 0.1778 0.6096)
			(layers "F.Cu" "F.Mask" "F.Paste")
			(net "PVCCINFAON_CPU0_ADDR")
		)
		(pad "35" smd rect
			(at 0.199898 -2.400046 90)
			(size 0.1778 0.6096)
			(layers "F.Cu" "F.Mask" "F.Paste")
			(net "PVCCINFAON_CPU0_ATSEN")
		)
		(pad "36" smd rect
			(at -0.199898 -2.400046 90)
			(size 0.1778 0.6096)
			(layers "F.Cu" "F.Mask" "F.Paste")
			(net "PVCCFA_EHV_CPU0_BTSEN")
		)
		(pad "37" smd rect
			(at -0.599948 -2.400046 90)
			(size 0.1778 0.6096)
			(layers "F.Cu" "F.Mask" "F.Paste")
			(net "PVCCINFAON_CPU0_CSPIN")
		)
		(pad "38" smd rect
			(at -0.999998 -2.400046 90)
			(size 0.1778 0.6096)
			(layers "F.Cu" "F.Mask" "F.Paste")
			(net "PVCCINFAON_CPU0_VIN_CSNIN")
		)
		(pad "39" smd rect
			(at -1.400048 -2.400046 90)
			(size 0.1778 0.6096)
			(layers "F.Cu" "F.Mask" "F.Paste")
			(net "PVCCINFAON_CPU0_VCC")
		)
		(pad "40" smd rect
			(at -1.800098 -2.400046 90)
			(size 0.1778 0.6096)
			(layers "F.Cu" "F.Mask" "F.Paste")
			(net "PVCCINFAON_CPU0_VREF")
		)
		(pad "TH" smd rect
			(at 0 0 90)
			(size 3.6576 3.6576)
			(layers "F.Cu" "F.Mask" "F.Paste")
			(net "GND")
		)
		(zone
			(layer "F.Cu")
			(hatch none 0.5)
			(connect_pads
				(clearance 0)
			)
			(min_thickness 0.25)
			(keepout
				(tracks not_allowed)
				(vias allowed)
				(pads allowed)
				(copperpour not_allowed)
				(footprints allowed)
			)
			(placement
				(enabled no)
				(sheetname "")
			)
			(fill
				(thermal_gap 0.5)
				(thermal_bridge_width 0.5)
				(island_removal_mode 0)
			)
			(polygon
				(pts
					(xy 423.673016 -134.38251) (xy 423.673016 -138.44651) (xy 427.737016 -138.44651) (xy 427.737016 -134.38251)
					(xy 423.850816 -134.38251) (xy 423.850816 -134.53491) (xy 427.584616 -134.53491) (xy 427.584616 -138.29411)
					(xy 423.825416 -138.29411) (xy 423.825416 -134.38251)
				)
			)
		)
	)
	(footprint ""
		(layer "F.Cu")
		(at 114.243612 -365.158274 90)
		(property "Reference" "PC553"
			(at 0 0 90)
			(layer "F.SilkS")
			(hide yes)
			(effects
				(font
					(size 1.27 1.27)
				)
			)
		)
		(property "Value" ""
			(at 0 0 90)
			(layer "F.Fab")
			(effects
				(font
					(size 1.27 1.27)
				)
			)
		)
		(duplicate_pad_numbers_are_jumpers no)
		(fp_line
			(start 0.7874 -0.4064)
			(end 0.7874 0.4064)
			(stroke
				(width 0.1524)
				(type default)
			)
			(layer "F.SilkS")
		)
		(fp_line
			(start -0.7874 -0.4064)
			(end 0.7874 -0.4064)
			(stroke
				(width 0.1524)
				(type default)
			)
			(layer "F.SilkS")
		)
		(fp_line
			(start 0.7874 0.4064)
			(end -0.7874 0.4064)
			(stroke
				(width 0.1524)
				(type default)
			)
			(layer "F.SilkS")
		)
		(fp_line
			(start -0.7874 0.4064)
			(end -0.7874 -0.4064)
			(stroke
				(width 0.1524)
				(type default)
			)
			(layer "F.SilkS")
		)
		(fp_line
			(start -0.12065 -0.305054)
			(end -0.12065 -0.2794)
			(stroke
				(width 0.1)
				(type default)
			)
			(layer "F.Fab")
		)
		(fp_line
			(start -0.67945 -0.305054)
			(end -0.12065 -0.305054)
			(stroke
				(width 0.1)
				(type default)
			)
			(layer "F.Fab")
		)
		(fp_line
			(start 0.67945 -0.3048)
			(end 0.67945 0.3048)
			(stroke
				(width 0.1)
				(type default)
			)
			(layer "F.Fab")
		)
		(fp_line
			(start 0.12065 -0.3048)
			(end 0.67945 -0.3048)
			(stroke
				(width 0.1)
				(type default)
			)
			(layer "F.Fab")
		)
		(fp_line
			(start 0.12065 -0.2794)
			(end 0.12065 -0.3048)
			(stroke
				(width 0.1)
				(type default)
			)
			(layer "F.Fab")
		)
		(fp_line
			(start -0.12065 -0.2794)
			(end 0.12065 -0.2794)
			(stroke
				(width 0.1)
				(type default)
			)
			(layer "F.Fab")
		)
		(fp_line
			(start 0.120396 0.2794)
			(end -0.12065 0.2794)
			(stroke
				(width 0.1)
				(type default)
			)
			(layer "F.Fab")
		)
		(fp_line
			(start -0.12065 0.2794)
			(end -0.12065 0.3048)
			(stroke
				(width 0.1)
				(type default)
			)
			(layer "F.Fab")
		)
		(fp_line
			(start 0.67945 0.3048)
			(end 0.120396 0.3048)
			(stroke
				(width 0.1)
				(type default)
			)
			(layer "F.Fab")
		)
		(fp_line
			(start 0.120396 0.3048)
			(end 0.120396 0.2794)
			(stroke
				(width 0.1)
				(type default)
			)
			(layer "F.Fab")
		)
		(fp_line
			(start -0.12065 0.3048)
			(end -0.67945 0.3048)
			(stroke
				(width 0.1)
				(type default)
			)
			(layer "F.Fab")
		)
		(fp_line
			(start -0.67945 0.3048)
			(end -0.67945 -0.305054)
			(stroke
				(width 0.1)
				(type default)
			)
			(layer "F.Fab")
		)
		(pad "1" smd circle
			(at -0.40005 0 90)
			(size 0 0)
			(layers "F.Cu" "F.Mask" "F.Paste")
			(net "PVCCIN_CPU1_VREF")
		)
		(pad "2" smd circle
			(at 0.40005 0 90)
			(size 0 0)
			(layers "F.Cu" "F.Mask" "F.Paste")
			(net "GND")
		)
	)
	(footprint ""
		(layer "F.Cu")
		(at 184.96788 -97.119948 -90)
		(property "Reference" "R1398"
			(at 0 0 270)
			(layer "F.SilkS")
			(hide yes)
			(effects
				(font
					(size 1.27 1.27)
				)
			)
		)
		(property "Value" ""
			(at 0 0 270)
			(layer "F.Fab")
			(effects
				(font
					(size 1.27 1.27)
				)
			)
		)
		(duplicate_pad_numbers_are_jumpers no)
		(fp_line
			(start -0.7874 0.4064)
			(end -0.7874 -0.4064)
			(stroke
				(width 0.1524)
				(type default)
			)
			(layer "F.SilkS")
		)
		(fp_line
			(start 0.7874 0.4064)
			(end -0.7874 0.4064)
			(stroke
				(width 0.1524)
				(type default)
			)
			(layer "F.SilkS")
		)
		(fp_line
			(start -0.7874 -0.4064)
			(end 0.7874 -0.4064)
			(stroke
				(width 0.1524)
				(type default)
			)
			(layer "F.SilkS")
		)
		(fp_line
			(start 0.7874 -0.4064)
			(end 0.7874 0.4064)
			(stroke
				(width 0.1524)
				(type default)
			)
			(layer "F.SilkS")
		)
		(fp_line
			(start -0.67945 0.3048)
			(end -0.67945 -0.305054)
			(stroke
				(width 0.1)
				(type default)
			)
			(layer "F.Fab")
		)
		(fp_line
			(start -0.12065 0.3048)
			(end -0.67945 0.3048)
			(stroke
				(width 0.1)
				(type default)
			)
			(layer "F.Fab")
		)
		(fp_line
			(start 0.120396 0.3048)
			(end 0.120396 0.2794)
			(stroke
				(width 0.1)
				(type default)
			)
			(layer "F.Fab")
		)
		(fp_line
			(start 0.67945 0.3048)
			(end 0.120396 0.3048)
			(stroke
				(width 0.1)
				(type default)
			)
			(layer "F.Fab")
		)
		(fp_line
			(start -0.12065 0.2794)
			(end -0.12065 0.3048)
			(stroke
				(width 0.1)
				(type default)
			)
			(layer "F.Fab")
		)
		(fp_line
			(start 0.120396 0.2794)
			(end -0.12065 0.2794)
			(stroke
				(width 0.1)
				(type default)
			)
			(layer "F.Fab")
		)
		(fp_line
			(start -0.12065 -0.2794)
			(end 0.12065 -0.2794)
			(stroke
				(width 0.1)
				(type default)
			)
			(layer "F.Fab")
		)
		(fp_line
			(start 0.12065 -0.2794)
			(end 0.12065 -0.3048)
			(stroke
				(width 0.1)
				(type default)
			)
			(layer "F.Fab")
		)
		(fp_line
			(start 0.12065 -0.3048)
			(end 0.67945 -0.3048)
			(stroke
				(width 0.1)
				(type default)
			)
			(layer "F.Fab")
		)
		(fp_line
			(start 0.67945 -0.3048)
			(end 0.67945 0.3048)
			(stroke
				(width 0.1)
				(type default)
			)
			(layer "F.Fab")
		)
		(fp_line
			(start -0.67945 -0.305054)
			(end -0.12065 -0.305054)
			(stroke
				(width 0.1)
				(type default)
			)
			(layer "F.Fab")
		)
		(fp_line
			(start -0.12065 -0.305054)
			(end -0.12065 -0.2794)
			(stroke
				(width 0.1)
				(type default)
			)
			(layer "F.Fab")
		)
		(pad "1" smd circle
			(at -0.40005 0 270)
			(size 0 0)
			(layers "F.Cu" "F.Mask" "F.Paste")
			(net "PWRGD_CPU1_LVC1_R")
		)
		(pad "2" smd circle
			(at 0.40005 0 270)
			(size 0 0)
			(layers "F.Cu" "F.Mask" "F.Paste")
			(net "GND")
		)
	)
	(footprint ""
		(layer "F.Cu")
		(at 420.682166 -136.162034 180)
		(property "Reference" "PC214"
			(at 0 0 180)
			(layer "F.SilkS")
			(hide yes)
			(effects
				(font
					(size 1.27 1.27)
				)
			)
		)
		(property "Value" ""
			(at 0 0 180)
			(layer "F.Fab")
			(effects
				(font
					(size 1.27 1.27)
				)
			)
		)
		(duplicate_pad_numbers_are_jumpers no)
		(fp_line
			(start 0.7874 0.4064)
			(end -0.7874 0.4064)
			(stroke
				(width 0.1524)
				(type default)
			)
			(layer "F.SilkS")
		)
		(fp_line
			(start 0.7874 -0.4064)
			(end 0.7874 0.4064)
			(stroke
				(width 0.1524)
				(type default)
			)
			(layer "F.SilkS")
		)
		(fp_line
			(start -0.7874 0.4064)
			(end -0.7874 -0.4064)
			(stroke
				(width 0.1524)
				(type default)
			)
			(layer "F.SilkS")
		)
		(fp_line
			(start -0.7874 -0.4064)
			(end 0.7874 -0.4064)
			(stroke
				(width 0.1524)
				(type default)
			)
			(layer "F.SilkS")
		)
		(fp_line
			(start 0.67945 0.3048)
			(end 0.120396 0.3048)
			(stroke
				(width 0.1)
				(type default)
			)
			(layer "F.Fab")
		)
		(fp_line
			(start 0.67945 -0.3048)
			(end 0.67945 0.3048)
			(stroke
				(width 0.1)
				(type default)
			)
			(layer "F.Fab")
		)
		(fp_line
			(start 0.12065 -0.2794)
			(end 0.12065 -0.3048)
			(stroke
				(width 0.1)
				(type default)
			)
			(layer "F.Fab")
		)
		(fp_line
			(start 0.12065 -0.3048)
			(end 0.67945 -0.3048)
			(stroke
				(width 0.1)
				(type default)
			)
			(layer "F.Fab")
		)
		(fp_line
			(start 0.120396 0.3048)
			(end 0.120396 0.2794)
			(stroke
				(width 0.1)
				(type default)
			)
			(layer "F.Fab")
		)
		(fp_line
			(start 0.120396 0.2794)
			(end -0.12065 0.2794)
			(stroke
				(width 0.1)
				(type default)
			)
			(layer "F.Fab")
		)
		(fp_line
			(start -0.12065 0.3048)
			(end -0.67945 0.3048)
			(stroke
				(width 0.1)
				(type default)
			)
			(layer "F.Fab")
		)
		(fp_line
			(start -0.12065 0.2794)
			(end -0.12065 0.3048)
			(stroke
				(width 0.1)
				(type default)
			)
			(layer "F.Fab")
		)
		(fp_line
			(start -0.12065 -0.2794)
			(end 0.12065 -0.2794)
			(stroke
				(width 0.1)
				(type default)
			)
			(layer "F.Fab")
		)
		(fp_line
			(start -0.12065 -0.305054)
			(end -0.12065 -0.2794)
			(stroke
				(width 0.1)
				(type default)
			)
			(layer "F.Fab")
		)
		(fp_line
			(start -0.67945 0.3048)
			(end -0.67945 -0.305054)
			(stroke
				(width 0.1)
				(type default)
			)
			(layer "F.Fab")
		)
		(fp_line
			(start -0.67945 -0.305054)
			(end -0.12065 -0.305054)
			(stroke
				(width 0.1)
				(type default)
			)
			(layer "F.Fab")
		)
		(pad "1" smd circle
			(at -0.40005 0 180)
			(size 0 0)
			(layers "F.Cu" "F.Mask" "F.Paste")
			(net "PVCCINFAON_CPU0_CSPIN")
		)
		(pad "2" smd circle
			(at 0.40005 0 180)
			(size 0 0)
			(layers "F.Cu" "F.Mask" "F.Paste")
			(net "GND")
		)
	)
	(footprint ""
		(layer "F.Cu")
		(at 239.152684 -52.92725 180)
		(property "Reference" "C1996"
			(at 0 0 180)
			(layer "F.SilkS")
			(hide yes)
			(effects
				(font
					(size 1.27 1.27)
				)
			)
		)
		(property "Value" ""
			(at 0 0 180)
			(layer "F.Fab")
			(effects
				(font
					(size 1.27 1.27)
				)
			)
		)
		(duplicate_pad_numbers_are_jumpers no)
		(fp_line
			(start 0.299974 0.150114)
			(end -0.299974 0.150114)
			(stroke
				(width 0.1)
				(type default)
			)
			(layer "F.Fab")
		)
		(fp_line
			(start 0.299974 -0.150114)
			(end 0.299974 0.150114)
			(stroke
				(width 0.1)
				(type default)
			)
			(layer "F.Fab")
		)
		(fp_line
			(start -0.299974 0.150114)
			(end -0.299974 -0.150114)
			(stroke
				(width 0.1)
				(type default)
			)
			(layer "F.Fab")
		)
		(fp_line
			(start -0.299974 -0.150114)
			(end 0.299974 -0.150114)
			(stroke
				(width 0.1)
				(type default)
			)
			(layer "F.Fab")
		)
		(pad "1" smd rect
			(at -0.2667 0 180)
			(size 0.3048 0.381)
			(layers "F.Cu" "F.Mask" "F.Paste")
			(net "P3E_PCH_E1S_TX_DN<0>")
		)
		(pad "2" smd rect
			(at 0.2667 0 180)
			(size 0.3048 0.381)
			(layers "F.Cu" "F.Mask" "F.Paste")
			(net "P3E_PCH_E1S_TX_C_DN<0>")
		)
		(zone
			(layer "In1.Cu")
			(hatch none 0.5)
			(connect_pads
				(clearance 0)
			)
			(min_thickness 0.25)
			(keepout
				(tracks not_allowed)
				(vias allowed)
				(pads allowed)
				(copperpour not_allowed)
				(footprints allowed)
			)
			(placement
				(enabled no)
				(sheetname "")
			)
			(fill
				(thermal_gap 0.5)
				(thermal_bridge_width 0.5)
				(island_removal_mode 0)
			)
			(polygon
				(pts
					(arc
						(start 239.012984 -53.167534)
						(mid 239.066866 -53.145216)
						(end 239.089184 -53.091334)
					)
					(arc
						(start 239.089184 -52.761134)
						(mid 239.066866 -52.707252)
						(end 239.012984 -52.684934)
					)
					(arc
						(start 238.758984 -52.684934)
						(mid 238.705102 -52.707252)
						(end 238.682784 -52.761134)
					)
					(arc
						(start 238.682784 -53.091334)
						(mid 238.705102 -53.145216)
						(end 238.758984 -53.167534)
					)
				)
			)
		)
		(zone
			(layer "In1.Cu")
			(hatch none 0.5)
			(connect_pads
				(clearance 0)
			)
			(min_thickness 0.25)
			(keepout
				(tracks not_allowed)
				(vias allowed)
				(pads allowed)
				(copperpour not_allowed)
				(footprints allowed)
			)
			(placement
				(enabled no)
				(sheetname "")
			)
			(fill
				(thermal_gap 0.5)
				(thermal_bridge_width 0.5)
				(island_removal_mode 0)
			)
			(polygon
				(pts
					(arc
						(start 239.546384 -53.167534)
						(mid 239.600266 -53.145216)
						(end 239.622584 -53.091334)
					)
					(arc
						(start 239.622584 -52.761134)
						(mid 239.600266 -52.707252)
						(end 239.546384 -52.684934)
					)
					(arc
						(start 239.292384 -52.684934)
						(mid 239.238502 -52.707252)
						(end 239.216184 -52.761134)
					)
					(arc
						(start 239.216184 -53.091334)
						(mid 239.238502 -53.145216)
						(end 239.292384 -53.167534)
					)
				)
			)
		)
	)
	(footprint ""
		(layer "F.Cu")
		(at 354.687632 -398.789398 180)
		(property "Reference" "R2675"
			(at 0 0 180)
			(layer "F.SilkS")
			(hide yes)
			(effects
				(font
					(size 1.27 1.27)
				)
			)
		)
		(property "Value" ""
			(at 0 0 180)
			(layer "F.Fab")
			(effects
				(font
					(size 1.27 1.27)
				)
			)
		)
		(duplicate_pad_numbers_are_jumpers no)
		(fp_line
			(start 0.7874 0.4064)
			(end -0.7874 0.4064)
			(stroke
				(width 0.1524)
				(type default)
			)
			(layer "F.SilkS")
		)
		(fp_line
			(start 0.7874 -0.4064)
			(end 0.7874 0.4064)
			(stroke
				(width 0.1524)
				(type default)
			)
			(layer "F.SilkS")
		)
		(fp_line
			(start -0.7874 0.4064)
			(end -0.7874 -0.4064)
			(stroke
				(width 0.1524)
				(type default)
			)
			(layer "F.SilkS")
		)
		(fp_line
			(start -0.7874 -0.4064)
			(end 0.7874 -0.4064)
			(stroke
				(width 0.1524)
				(type default)
			)
			(layer "F.SilkS")
		)
		(fp_line
			(start 0.67945 0.3048)
			(end 0.120396 0.3048)
			(stroke
				(width 0.1)
				(type default)
			)
			(layer "F.Fab")
		)
		(fp_line
			(start 0.67945 -0.3048)
			(end 0.67945 0.3048)
			(stroke
				(width 0.1)
				(type default)
			)
			(layer "F.Fab")
		)
		(fp_line
			(start 0.12065 -0.2794)
			(end 0.12065 -0.3048)
			(stroke
				(width 0.1)
				(type default)
			)
			(layer "F.Fab")
		)
		(fp_line
			(start 0.12065 -0.3048)
			(end 0.67945 -0.3048)
			(stroke
				(width 0.1)
				(type default)
			)
			(layer "F.Fab")
		)
		(fp_line
			(start 0.120396 0.3048)
			(end 0.120396 0.2794)
			(stroke
				(width 0.1)
				(type default)
			)
			(layer "F.Fab")
		)
		(fp_line
			(start 0.120396 0.2794)
			(end -0.12065 0.2794)
			(stroke
				(width 0.1)
				(type default)
			)
			(layer "F.Fab")
		)
		(fp_line
			(start -0.12065 0.3048)
			(end -0.67945 0.3048)
			(stroke
				(width 0.1)
				(type default)
			)
			(layer "F.Fab")
		)
		(fp_line
			(start -0.12065 0.2794)
			(end -0.12065 0.3048)
			(stroke
				(width 0.1)
				(type default)
			)
			(layer "F.Fab")
		)
		(fp_line
			(start -0.12065 -0.2794)
			(end 0.12065 -0.2794)
			(stroke
				(width 0.1)
				(type default)
			)
			(layer "F.Fab")
		)
		(fp_line
			(start -0.12065 -0.305054)
			(end -0.12065 -0.2794)
			(stroke
				(width 0.1)
				(type default)
			)
			(layer "F.Fab")
		)
		(fp_line
			(start -0.67945 0.3048)
			(end -0.67945 -0.305054)
			(stroke
				(width 0.1)
				(type default)
			)
			(layer "F.Fab")
		)
		(fp_line
			(start -0.67945 -0.305054)
			(end -0.12065 -0.305054)
			(stroke
				(width 0.1)
				(type default)
			)
			(layer "F.Fab")
		)
		(pad "1" smd circle
			(at -0.40005 0 180)
			(size 0 0)
			(layers "F.Cu" "F.Mask" "F.Paste")
			(net "I3C_BMC_SWB_BUF_R_SCL")
		)
		(pad "2" smd circle
			(at 0.40005 0 180)
			(size 0 0)
			(layers "F.Cu" "F.Mask" "F.Paste")
			(net "I3C_BMC_SWB_BUF_SCL")
		)
	)
	(footprint ""
		(layer "F.Cu")
		(at 141.372844 -343.018872 -90)
		(property "Reference" "PC485_P1_8"
			(at 0 0 270)
			(layer "F.SilkS")
			(hide yes)
			(effects
				(font
					(size 1.27 1.27)
				)
			)
		)
		(property "Value" ""
			(at 0 0 270)
			(layer "F.Fab")
			(effects
				(font
					(size 1.27 1.27)
				)
			)
		)
		(duplicate_pad_numbers_are_jumpers no)
		(fp_line
			(start -0.7874 0.4064)
			(end -0.7874 -0.4064)
			(stroke
				(width 0.1524)
				(type default)
			)
			(layer "F.SilkS")
		)
		(fp_line
			(start 0.7874 0.4064)
			(end -0.7874 0.4064)
			(stroke
				(width 0.1524)
				(type default)
			)
			(layer "F.SilkS")
		)
		(fp_line
			(start -0.7874 -0.4064)
			(end 0.7874 -0.4064)
			(stroke
				(width 0.1524)
				(type default)
			)
			(layer "F.SilkS")
		)
		(fp_line
			(start 0.7874 -0.4064)
			(end 0.7874 0.4064)
			(stroke
				(width 0.1524)
				(type default)
			)
			(layer "F.SilkS")
		)
		(fp_line
			(start -0.67945 0.3048)
			(end -0.67945 -0.305054)
			(stroke
				(width 0.1)
				(type default)
			)
			(layer "F.Fab")
		)
		(fp_line
			(start -0.12065 0.3048)
			(end -0.67945 0.3048)
			(stroke
				(width 0.1)
				(type default)
			)
			(layer "F.Fab")
		)
		(fp_line
			(start 0.120396 0.3048)
			(end 0.120396 0.2794)
			(stroke
				(width 0.1)
				(type default)
			)
			(layer "F.Fab")
		)
		(fp_line
			(start 0.67945 0.3048)
			(end 0.120396 0.3048)
			(stroke
				(width 0.1)
				(type default)
			)
			(layer "F.Fab")
		)
		(fp_line
			(start -0.12065 0.2794)
			(end -0.12065 0.3048)
			(stroke
				(width 0.1)
				(type default)
			)
			(layer "F.Fab")
		)
		(fp_line
			(start 0.120396 0.2794)
			(end -0.12065 0.2794)
			(stroke
				(width 0.1)
				(type default)
			)
			(layer "F.Fab")
		)
		(fp_line
			(start -0.12065 -0.2794)
			(end 0.12065 -0.2794)
			(stroke
				(width 0.1)
				(type default)
			)
			(layer "F.Fab")
		)
		(fp_line
			(start 0.12065 -0.2794)
			(end 0.12065 -0.3048)
			(stroke
				(width 0.1)
				(type default)
			)
			(layer "F.Fab")
		)
		(fp_line
			(start 0.12065 -0.3048)
			(end 0.67945 -0.3048)
			(stroke
				(width 0.1)
				(type default)
			)
			(layer "F.Fab")
		)
		(fp_line
			(start 0.67945 -0.3048)
			(end 0.67945 0.3048)
			(stroke
				(width 0.1)
				(type default)
			)
			(layer "F.Fab")
		)
		(fp_line
			(start -0.67945 -0.305054)
			(end -0.12065 -0.305054)
			(stroke
				(width 0.1)
				(type default)
			)
			(layer "F.Fab")
		)
		(fp_line
			(start -0.12065 -0.305054)
			(end -0.12065 -0.2794)
			(stroke
				(width 0.1)
				(type default)
			)
			(layer "F.Fab")
		)
		(pad "1" smd circle
			(at -0.40005 0 270)
			(size 0 0)
			(layers "F.Cu" "F.Mask" "F.Paste")
			(net "SW_P12V_PVCCIN_CPU1_FLT")
		)
		(pad "2" smd circle
			(at 0.40005 0 270)
			(size 0 0)
			(layers "F.Cu" "F.Mask" "F.Paste")
			(net "GND")
		)
	)
	(footprint ""
		(layer "F.Cu")
		(at 239.7125 -249.339608 -90)
		(property "Reference" "R4501"
			(at 0 0 270)
			(layer "F.SilkS")
			(hide yes)
			(effects
				(font
					(size 1.27 1.27)
				)
			)
		)
		(property "Value" ""
			(at 0 0 270)
			(layer "F.Fab")
			(effects
				(font
					(size 1.27 1.27)
				)
			)
		)
		(duplicate_pad_numbers_are_jumpers no)
		(fp_line
			(start -0.7874 0.4064)
			(end -0.7874 -0.4064)
			(stroke
				(width 0.1524)
				(type default)
			)
			(layer "F.SilkS")
		)
		(fp_line
			(start 0.7874 0.4064)
			(end -0.7874 0.4064)
			(stroke
				(width 0.1524)
				(type default)
			)
			(layer "F.SilkS")
		)
		(fp_line
			(start -0.7874 -0.4064)
			(end 0.7874 -0.4064)
			(stroke
				(width 0.1524)
				(type default)
			)
			(layer "F.SilkS")
		)
		(fp_line
			(start 0.7874 -0.4064)
			(end 0.7874 0.4064)
			(stroke
				(width 0.1524)
				(type default)
			)
			(layer "F.SilkS")
		)
		(fp_line
			(start -0.67945 0.3048)
			(end -0.67945 -0.305054)
			(stroke
				(width 0.1)
				(type default)
			)
			(layer "F.Fab")
		)
		(fp_line
			(start -0.12065 0.3048)
			(end -0.67945 0.3048)
			(stroke
				(width 0.1)
				(type default)
			)
			(layer "F.Fab")
		)
		(fp_line
			(start 0.120396 0.3048)
			(end 0.120396 0.2794)
			(stroke
				(width 0.1)
				(type default)
			)
			(layer "F.Fab")
		)
		(fp_line
			(start 0.67945 0.3048)
			(end 0.120396 0.3048)
			(stroke
				(width 0.1)
				(type default)
			)
			(layer "F.Fab")
		)
		(fp_line
			(start -0.12065 0.2794)
			(end -0.12065 0.3048)
			(stroke
				(width 0.1)
				(type default)
			)
			(layer "F.Fab")
		)
		(fp_line
			(start 0.120396 0.2794)
			(end -0.12065 0.2794)
			(stroke
				(width 0.1)
				(type default)
			)
			(layer "F.Fab")
		)
		(fp_line
			(start -0.12065 -0.2794)
			(end 0.12065 -0.2794)
			(stroke
				(width 0.1)
				(type default)
			)
			(layer "F.Fab")
		)
		(fp_line
			(start 0.12065 -0.2794)
			(end 0.12065 -0.3048)
			(stroke
				(width 0.1)
				(type default)
			)
			(layer "F.Fab")
		)
		(fp_line
			(start 0.12065 -0.3048)
			(end 0.67945 -0.3048)
			(stroke
				(width 0.1)
				(type default)
			)
			(layer "F.Fab")
		)
		(fp_line
			(start 0.67945 -0.3048)
			(end 0.67945 0.3048)
			(stroke
				(width 0.1)
				(type default)
			)
			(layer "F.Fab")
		)
		(fp_line
			(start -0.67945 -0.305054)
			(end -0.12065 -0.305054)
			(stroke
				(width 0.1)
				(type default)
			)
			(layer "F.Fab")
		)
		(fp_line
			(start -0.12065 -0.305054)
			(end -0.12065 -0.2794)
			(stroke
				(width 0.1)
				(type default)
			)
			(layer "F.Fab")
		)
		(pad "1" smd circle
			(at -0.40005 0 270)
			(size 0 0)
			(layers "F.Cu" "F.Mask" "F.Paste")
			(net "CLK_GEN2_XTAL_IN_R")
		)
		(pad "2" smd circle
			(at 0.40005 0 270)
			(size 0 0)
			(layers "F.Cu" "F.Mask" "F.Paste")
			(net "CLK_GEN2_XTAL_IN")
		)
	)
	(footprint ""
		(layer "F.Cu")
		(at 45.622972 -434.725318)
		(property "Reference" "U194"
			(at -2.747772 -2.051812 0)
			(unlocked yes)
			(layer "F.SilkS")
			(effects
				(font
					(size 0.7874 0.5842)
					(thickness 0.1524)
				)
				(justify left)
			)
		)
		(property "Value" ""
			(at 0 0 0)
			(layer "F.Fab")
			(effects
				(font
					(size 1.27 1.27)
				)
			)
		)
		(duplicate_pad_numbers_are_jumpers no)
		(fp_line
			(start -1.3716 -1.524)
			(end -0.508 -1.524)
			(stroke
				(width 0.1524)
				(type default)
			)
			(layer "F.SilkS")
		)
		(fp_line
			(start -1.3716 1.524)
			(end -1.3716 -1.524)
			(stroke
				(width 0.1524)
				(type default)
			)
			(layer "F.SilkS")
		)
		(fp_line
			(start -0.508 -1.524)
			(end 0 -1.016)
			(stroke
				(width 0.1524)
				(type default)
			)
			(layer "F.SilkS")
		)
		(fp_line
			(start 0 -1.016)
			(end 0.508 -1.524)
			(stroke
				(width 0.1524)
				(type default)
			)
			(layer "F.SilkS")
		)
		(fp_line
			(start 0.508 -1.524)
			(end 1.3716 -1.524)
			(stroke
				(width 0.1524)
				(type default)
			)
			(layer "F.SilkS")
		)
		(fp_line
			(start 1.3716 -1.524)
			(end 1.3716 1.524)
			(stroke
				(width 0.1524)
				(type default)
			)
			(layer "F.SilkS")
		)
		(fp_line
			(start 1.3716 1.524)
			(end -1.3716 1.524)
			(stroke
				(width 0.1524)
				(type default)
			)
			(layer "F.SilkS")
		)
		(fp_poly
			(pts
				(xy -3.6703 -1.331468) (xy -3.11658 -1.0033) (xy -3.6703 -0.706628)
			)
			(stroke
				(width 0)
				(type default)
			)
			(fill yes)
			(layer "F.SilkS")
		)
		(fp_line
			(start -2.54 -1.0668)
			(end -1.5494 -1.0668)
			(stroke
				(width 0.1)
				(type default)
			)
			(layer "F.Fab")
		)
		(fp_line
			(start -2.54 1.0668)
			(end -2.54 -1.0668)
			(stroke
				(width 0.1)
				(type default)
			)
			(layer "F.Fab")
		)
		(fp_line
			(start -1.5494 -1.524)
			(end 1.5494 -1.524)
			(stroke
				(width 0.1)
				(type default)
			)
			(layer "F.Fab")
		)
		(fp_line
			(start -1.5494 -1.0668)
			(end -1.5494 -1.524)
			(stroke
				(width 0.1)
				(type default)
			)
			(layer "F.Fab")
		)
		(fp_line
			(start -1.5494 1.0668)
			(end -2.54 1.0668)
			(stroke
				(width 0.1)
				(type default)
			)
			(layer "F.Fab")
		)
		(fp_line
			(start -1.5494 1.0668)
			(end -1.5494 -1.0668)
			(stroke
				(width 0.1)
				(type default)
			)
			(layer "F.Fab")
		)
		(fp_line
			(start -1.5494 1.524)
			(end -1.5494 1.0668)
			(stroke
				(width 0.1)
				(type default)
			)
			(layer "F.Fab")
		)
		(fp_line
			(start 1.5494 -1.524)
			(end 1.5494 -1.0668)
			(stroke
				(width 0.1)
				(type default)
			)
			(layer "F.Fab")
		)
		(fp_line
			(start 1.5494 -1.0668)
			(end 1.5494 1.0668)
			(stroke
				(width 0.1)
				(type default)
			)
			(layer "F.Fab")
		)
		(fp_line
			(start 1.5494 -1.0668)
			(end 2.54 -1.0668)
			(stroke
				(width 0.1)
				(type default)
			)
			(layer "F.Fab")
		)
		(fp_line
			(start 1.5494 1.0668)
			(end 1.5494 1.524)
			(stroke
				(width 0.1)
				(type default)
			)
			(layer "F.Fab")
		)
		(fp_line
			(start 1.5494 1.524)
			(end -1.5494 1.524)
			(stroke
				(width 0.1)
				(type default)
			)
			(layer "F.Fab")
		)
		(fp_line
			(start 2.54 -1.0668)
			(end 2.54 1.0668)
			(stroke
				(width 0.1)
				(type default)
			)
			(layer "F.Fab")
		)
		(fp_line
			(start 2.54 1.0668)
			(end 1.5494 1.0668)
			(stroke
				(width 0.1)
				(type default)
			)
			(layer "F.Fab")
		)
		(fp_poly
			(pts
				(xy -3.60172 -0.719328) (xy -3.60172 -1.344168) (xy -3.048 -1.016)
			)
			(stroke
				(width 0)
				(type default)
			)
			(fill yes)
			(layer "F.Fab")
		)
		(pad "1" smd rect
			(at -2.232406 -0.975106 270)
			(size 0.3556 1.4224)
			(layers "F.Cu" "F.Mask" "F.Paste")
			(net "SMB_BMC_GPU_EN_R1")
		)
		(pad "2" smd rect
			(at -2.232406 -0.32512 270)
			(size 0.3556 1.4224)
			(layers "F.Cu" "F.Mask" "F.Paste")
			(net "SMB_1_BMC_GPU_BUF_R_SCL")
		)
		(pad "3" smd rect
			(at -2.232406 0.32512 270)
			(size 0.3556 1.4224)
			(layers "F.Cu" "F.Mask" "F.Paste")
			(net "SMB_1_BMC_GPU_R_SCL")
		)
		(pad "4" smd rect
			(at -2.232406 0.975106 270)
			(size 0.3556 1.4224)
			(layers "F.Cu" "F.Mask" "F.Paste")
			(net "GND")
		)
		(pad "5" smd rect
			(at 2.232406 0.975106 270)
			(size 0.3556 1.4224)
			(layers "F.Cu" "F.Mask" "F.Paste")
			(net "Net_1936")
		)
		(pad "6" smd rect
			(at 2.232406 0.32512 270)
			(size 0.3556 1.4224)
			(layers "F.Cu" "F.Mask" "F.Paste")
			(net "SMB_1_BMC_GPU_R_SDA")
		)
		(pad "7" smd rect
			(at 2.232406 -0.32512 270)
			(size 0.3556 1.4224)
			(layers "F.Cu" "F.Mask" "F.Paste")
			(net "SMB_1_BMC_GPU_BUF_R_SDA")
		)
		(pad "8" smd rect
			(at 2.232406 -0.975106 270)
			(size 0.3556 1.4224)
			(layers "F.Cu" "F.Mask" "F.Paste")
			(net "P3V3_AUX")
		)
	)
	(footprint ""
		(layer "F.Cu")
		(at 15.436596 -392.199876 180)
		(property "Reference" "R3273"
			(at 0 0 180)
			(layer "F.SilkS")
			(hide yes)
			(effects
				(font
					(size 1.27 1.27)
				)
			)
		)
		(property "Value" ""
			(at 0 0 180)
			(layer "F.Fab")
			(effects
				(font
					(size 1.27 1.27)
				)
			)
		)
		(duplicate_pad_numbers_are_jumpers no)
		(fp_line
			(start 0.7874 0.4064)
			(end -0.7874 0.4064)
			(stroke
				(width 0.1524)
				(type default)
			)
			(layer "F.SilkS")
		)
		(fp_line
			(start 0.7874 -0.4064)
			(end 0.7874 0.4064)
			(stroke
				(width 0.1524)
				(type default)
			)
			(layer "F.SilkS")
		)
		(fp_line
			(start -0.7874 0.4064)
			(end -0.7874 -0.4064)
			(stroke
				(width 0.1524)
				(type default)
			)
			(layer "F.SilkS")
		)
		(fp_line
			(start -0.7874 -0.4064)
			(end 0.7874 -0.4064)
			(stroke
				(width 0.1524)
				(type default)
			)
			(layer "F.SilkS")
		)
		(fp_line
			(start 0.67945 0.3048)
			(end 0.120396 0.3048)
			(stroke
				(width 0.1)
				(type default)
			)
			(layer "F.Fab")
		)
		(fp_line
			(start 0.67945 -0.3048)
			(end 0.67945 0.3048)
			(stroke
				(width 0.1)
				(type default)
			)
			(layer "F.Fab")
		)
		(fp_line
			(start 0.12065 -0.2794)
			(end 0.12065 -0.3048)
			(stroke
				(width 0.1)
				(type default)
			)
			(layer "F.Fab")
		)
		(fp_line
			(start 0.12065 -0.3048)
			(end 0.67945 -0.3048)
			(stroke
				(width 0.1)
				(type default)
			)
			(layer "F.Fab")
		)
		(fp_line
			(start 0.120396 0.3048)
			(end 0.120396 0.2794)
			(stroke
				(width 0.1)
				(type default)
			)
			(layer "F.Fab")
		)
		(fp_line
			(start 0.120396 0.2794)
			(end -0.12065 0.2794)
			(stroke
				(width 0.1)
				(type default)
			)
			(layer "F.Fab")
		)
		(fp_line
			(start -0.12065 0.3048)
			(end -0.67945 0.3048)
			(stroke
				(width 0.1)
				(type default)
			)
			(layer "F.Fab")
		)
		(fp_line
			(start -0.12065 0.2794)
			(end -0.12065 0.3048)
			(stroke
				(width 0.1)
				(type default)
			)
			(layer "F.Fab")
		)
		(fp_line
			(start -0.12065 -0.2794)
			(end 0.12065 -0.2794)
			(stroke
				(width 0.1)
				(type default)
			)
			(layer "F.Fab")
		)
		(fp_line
			(start -0.12065 -0.305054)
			(end -0.12065 -0.2794)
			(stroke
				(width 0.1)
				(type default)
			)
			(layer "F.Fab")
		)
		(fp_line
			(start -0.67945 0.3048)
			(end -0.67945 -0.305054)
			(stroke
				(width 0.1)
				(type default)
			)
			(layer "F.Fab")
		)
		(fp_line
			(start -0.67945 -0.305054)
			(end -0.12065 -0.305054)
			(stroke
				(width 0.1)
				(type default)
			)
			(layer "F.Fab")
		)
		(pad "1" smd circle
			(at -0.40005 0 180)
			(size 0 0)
			(layers "F.Cu" "F.Mask" "F.Paste")
			(net "FM_P2E_FGA")
		)
		(pad "2" smd circle
			(at 0.40005 0 180)
			(size 0 0)
			(layers "F.Cu" "F.Mask" "F.Paste")
			(net "GND")
		)
	)
	(footprint ""
		(layer "F.Cu")
		(at 422.623742 -97.941892)
		(property "Reference" "PD103"
			(at -3.13182 2.806192 0)
			(unlocked yes)
			(layer "F.SilkS")
			(effects
				(font
					(size 0.7874 0.5842)
					(thickness 0.1524)
				)
				(justify left)
			)
		)
		(property "Value" ""
			(at 0 0 0)
			(layer "F.Fab")
			(effects
				(font
					(size 1.27 1.27)
				)
			)
		)
		(duplicate_pad_numbers_are_jumpers no)
		(fp_line
			(start -3.400044 -1.459992)
			(end 4.107942 -1.459992)
			(stroke
				(width 0.1524)
				(type default)
			)
			(layer "F.SilkS")
		)
		(fp_line
			(start -3.400044 1.459992)
			(end -3.400044 -1.459992)
			(stroke
				(width 0.1524)
				(type default)
			)
			(layer "F.SilkS")
		)
		(fp_line
			(start 4.107942 -1.459992)
			(end 4.107942 1.459992)
			(stroke
				(width 0.1524)
				(type default)
			)
			(layer "F.SilkS")
		)
		(fp_line
			(start 4.107942 1.459992)
			(end -3.400044 1.459992)
			(stroke
				(width 0.1524)
				(type default)
			)
			(layer "F.SilkS")
		)
		(fp_rect
			(start 3.308096 1.459992)
			(end 4.107942 -1.459992)
			(stroke
				(width 0)
				(type default)
			)
			(fill yes)
			(layer "F.SilkS")
		)
		(fp_line
			(start -2.29997 -1.459992)
			(end 2.29997 -1.459992)
			(stroke
				(width 0.1)
				(type default)
			)
			(layer "F.Fab")
		)
		(fp_line
			(start -2.29997 1.459992)
			(end -2.29997 -1.459992)
			(stroke
				(width 0.1)
				(type default)
			)
			(layer "F.Fab")
		)
		(fp_line
			(start 2.29997 -1.459992)
			(end 2.29997 1.459992)
			(stroke
				(width 0.1)
				(type default)
			)
			(layer "F.Fab")
		)
		(fp_line
			(start 2.29997 1.459992)
			(end -2.29997 1.459992)
			(stroke
				(width 0.1)
				(type default)
			)
			(layer "F.Fab")
		)
		(fp_text user "+"
			(at -4.7752 -0.12065 0)
			(unlocked yes)
			(layer "F.SilkS")
			(effects
				(font
					(size 1.905 1.4224)
					(thickness 0.1524)
				)
				(justify left)
			)
		)
		(fp_text user "-"
			(at 3.8735 2.64795 180)
			(unlocked yes)
			(layer "F.SilkS")
			(effects
				(font
					(size 1.905 1.4224)
					(thickness 0.1524)
				)
				(justify left)
			)
		)
		(fp_text user "+"
			(at -4.7752 -0.12065 0)
			(unlocked yes)
			(layer "F.Fab")
			(effects
				(font
					(size 1.905 1.4224)
					(thickness 0.1524)
				)
				(justify left)
			)
		)
		(fp_text user "-"
			(at 5.4102 0.29845 180)
			(unlocked yes)
			(layer "F.Fab")
			(effects
				(font
					(size 1.905 1.4224)
					(thickness 0.1524)
				)
				(justify left)
			)
		)
		(pad "A" smd rect
			(at -1.999996 0 90)
			(size 1.7018 2.5146)
			(layers "F.Cu" "F.Mask" "F.Paste")
			(net "GND")
		)
		(pad "C" smd rect
			(at 1.999996 0 90)
			(size 1.7018 2.5146)
			(layers "F.Cu" "F.Mask" "F.Paste")
			(net "P3V3_OCP_SFF_R")
		)
	)
	(footprint ""
		(layer "F.Cu")
		(at 77.966824 -142.587218 90)
		(property "Reference" "R666"
			(at 0 0 90)
			(layer "F.SilkS")
			(hide yes)
			(effects
				(font
					(size 1.27 1.27)
				)
			)
		)
		(property "Value" ""
			(at 0 0 90)
			(layer "F.Fab")
			(effects
				(font
					(size 1.27 1.27)
				)
			)
		)
		(duplicate_pad_numbers_are_jumpers no)
		(fp_line
			(start 0.7874 -0.4064)
			(end 0.7874 0.4064)
			(stroke
				(width 0.1524)
				(type default)
			)
			(layer "F.SilkS")
		)
		(fp_line
			(start -0.7874 -0.4064)
			(end 0.7874 -0.4064)
			(stroke
				(width 0.1524)
				(type default)
			)
			(layer "F.SilkS")
		)
		(fp_line
			(start 0.7874 0.4064)
			(end -0.7874 0.4064)
			(stroke
				(width 0.1524)
				(type default)
			)
			(layer "F.SilkS")
		)
		(fp_line
			(start -0.7874 0.4064)
			(end -0.7874 -0.4064)
			(stroke
				(width 0.1524)
				(type default)
			)
			(layer "F.SilkS")
		)
		(fp_line
			(start -0.12065 -0.305054)
			(end -0.12065 -0.2794)
			(stroke
				(width 0.1)
				(type default)
			)
			(layer "F.Fab")
		)
		(fp_line
			(start -0.67945 -0.305054)
			(end -0.12065 -0.305054)
			(stroke
				(width 0.1)
				(type default)
			)
			(layer "F.Fab")
		)
		(fp_line
			(start 0.67945 -0.3048)
			(end 0.67945 0.3048)
			(stroke
				(width 0.1)
				(type default)
			)
			(layer "F.Fab")
		)
		(fp_line
			(start 0.12065 -0.3048)
			(end 0.67945 -0.3048)
			(stroke
				(width 0.1)
				(type default)
			)
			(layer "F.Fab")
		)
		(fp_line
			(start 0.12065 -0.2794)
			(end 0.12065 -0.3048)
			(stroke
				(width 0.1)
				(type default)
			)
			(layer "F.Fab")
		)
		(fp_line
			(start -0.12065 -0.2794)
			(end 0.12065 -0.2794)
			(stroke
				(width 0.1)
				(type default)
			)
			(layer "F.Fab")
		)
		(fp_line
			(start 0.120396 0.2794)
			(end -0.12065 0.2794)
			(stroke
				(width 0.1)
				(type default)
			)
			(layer "F.Fab")
		)
		(fp_line
			(start -0.12065 0.2794)
			(end -0.12065 0.3048)
			(stroke
				(width 0.1)
				(type default)
			)
			(layer "F.Fab")
		)
		(fp_line
			(start 0.67945 0.3048)
			(end 0.120396 0.3048)
			(stroke
				(width 0.1)
				(type default)
			)
			(layer "F.Fab")
		)
		(fp_line
			(start 0.120396 0.3048)
			(end 0.120396 0.2794)
			(stroke
				(width 0.1)
				(type default)
			)
			(layer "F.Fab")
		)
		(fp_line
			(start -0.12065 0.3048)
			(end -0.67945 0.3048)
			(stroke
				(width 0.1)
				(type default)
			)
			(layer "F.Fab")
		)
		(fp_line
			(start -0.67945 0.3048)
			(end -0.67945 -0.305054)
			(stroke
				(width 0.1)
				(type default)
			)
			(layer "F.Fab")
		)
		(pad "1" smd circle
			(at -0.40005 0 90)
			(size 0 0)
			(layers "F.Cu" "F.Mask" "F.Paste")
			(net "I3C_SPD_DDRABCD_CPU1_R_SDA")
		)
		(pad "2" smd circle
			(at 0.40005 0 90)
			(size 0 0)
			(layers "F.Cu" "F.Mask" "F.Paste")
			(net "I3C_SPD_DDRABCD_CPU1_LVC1_R_SDA")
		)
	)
	(footprint ""
		(layer "F.Cu")
		(at 394.39088 -148.808948 -90)
		(property "Reference" "R448"
			(at 0 0 270)
			(layer "F.SilkS")
			(hide yes)
			(effects
				(font
					(size 1.27 1.27)
				)
			)
		)
		(property "Value" ""
			(at 0 0 270)
			(layer "F.Fab")
			(effects
				(font
					(size 1.27 1.27)
				)
			)
		)
		(duplicate_pad_numbers_are_jumpers no)
		(fp_line
			(start -0.7874 0.4064)
			(end -0.7874 -0.4064)
			(stroke
				(width 0.1524)
				(type default)
			)
			(layer "F.SilkS")
		)
		(fp_line
			(start 0.7874 0.4064)
			(end -0.7874 0.4064)
			(stroke
				(width 0.1524)
				(type default)
			)
			(layer "F.SilkS")
		)
		(fp_line
			(start -0.7874 -0.4064)
			(end 0.7874 -0.4064)
			(stroke
				(width 0.1524)
				(type default)
			)
			(layer "F.SilkS")
		)
		(fp_line
			(start 0.7874 -0.4064)
			(end 0.7874 0.4064)
			(stroke
				(width 0.1524)
				(type default)
			)
			(layer "F.SilkS")
		)
		(fp_line
			(start -0.67945 0.3048)
			(end -0.67945 -0.305054)
			(stroke
				(width 0.1)
				(type default)
			)
			(layer "F.Fab")
		)
		(fp_line
			(start -0.12065 0.3048)
			(end -0.67945 0.3048)
			(stroke
				(width 0.1)
				(type default)
			)
			(layer "F.Fab")
		)
		(fp_line
			(start 0.120396 0.3048)
			(end 0.120396 0.2794)
			(stroke
				(width 0.1)
				(type default)
			)
			(layer "F.Fab")
		)
		(fp_line
			(start 0.67945 0.3048)
			(end 0.120396 0.3048)
			(stroke
				(width 0.1)
				(type default)
			)
			(layer "F.Fab")
		)
		(fp_line
			(start -0.12065 0.2794)
			(end -0.12065 0.3048)
			(stroke
				(width 0.1)
				(type default)
			)
			(layer "F.Fab")
		)
		(fp_line
			(start 0.120396 0.2794)
			(end -0.12065 0.2794)
			(stroke
				(width 0.1)
				(type default)
			)
			(layer "F.Fab")
		)
		(fp_line
			(start -0.12065 -0.2794)
			(end 0.12065 -0.2794)
			(stroke
				(width 0.1)
				(type default)
			)
			(layer "F.Fab")
		)
		(fp_line
			(start 0.12065 -0.2794)
			(end 0.12065 -0.3048)
			(stroke
				(width 0.1)
				(type default)
			)
			(layer "F.Fab")
		)
		(fp_line
			(start 0.12065 -0.3048)
			(end 0.67945 -0.3048)
			(stroke
				(width 0.1)
				(type default)
			)
			(layer "F.Fab")
		)
		(fp_line
			(start 0.67945 -0.3048)
			(end 0.67945 0.3048)
			(stroke
				(width 0.1)
				(type default)
			)
			(layer "F.Fab")
		)
		(fp_line
			(start -0.67945 -0.305054)
			(end -0.12065 -0.305054)
			(stroke
				(width 0.1)
				(type default)
			)
			(layer "F.Fab")
		)
		(fp_line
			(start -0.12065 -0.305054)
			(end -0.12065 -0.2794)
			(stroke
				(width 0.1)
				(type default)
			)
			(layer "F.Fab")
		)
		(pad "1" smd circle
			(at -0.40005 0 270)
			(size 0 0)
			(layers "F.Cu" "F.Mask" "F.Paste")
			(net "SMB_S3M_CPU0_3V3AUX_SCL")
		)
		(pad "2" smd circle
			(at 0.40005 0 270)
			(size 0 0)
			(layers "F.Cu" "F.Mask" "F.Paste")
			(net "SMB_S3M_CPU1_3V3AUX_SCL")
		)
	)
	(footprint ""
		(layer "F.Cu")
		(at 420.124128 -175.135286 -90)
		(property "Reference" "PC192_P0_2"
			(at 0 0 270)
			(layer "F.SilkS")
			(hide yes)
			(effects
				(font
					(size 1.27 1.27)
				)
			)
		)
		(property "Value" ""
			(at 0 0 270)
			(layer "F.Fab")
			(effects
				(font
					(size 1.27 1.27)
				)
			)
		)
		(duplicate_pad_numbers_are_jumpers no)
		(fp_line
			(start -0.7874 0.4064)
			(end -0.7874 -0.4064)
			(stroke
				(width 0.1524)
				(type default)
			)
			(layer "F.SilkS")
		)
		(fp_line
			(start 0.7874 0.4064)
			(end -0.7874 0.4064)
			(stroke
				(width 0.1524)
				(type default)
			)
			(layer "F.SilkS")
		)
		(fp_line
			(start -0.7874 -0.4064)
			(end 0.7874 -0.4064)
			(stroke
				(width 0.1524)
				(type default)
			)
			(layer "F.SilkS")
		)
		(fp_line
			(start 0.7874 -0.4064)
			(end 0.7874 0.4064)
			(stroke
				(width 0.1524)
				(type default)
			)
			(layer "F.SilkS")
		)
		(fp_line
			(start -0.67945 0.3048)
			(end -0.67945 -0.305054)
			(stroke
				(width 0.1)
				(type default)
			)
			(layer "F.Fab")
		)
		(fp_line
			(start -0.12065 0.3048)
			(end -0.67945 0.3048)
			(stroke
				(width 0.1)
				(type default)
			)
			(layer "F.Fab")
		)
		(fp_line
			(start 0.120396 0.3048)
			(end 0.120396 0.2794)
			(stroke
				(width 0.1)
				(type default)
			)
			(layer "F.Fab")
		)
		(fp_line
			(start 0.67945 0.3048)
			(end 0.120396 0.3048)
			(stroke
				(width 0.1)
				(type default)
			)
			(layer "F.Fab")
		)
		(fp_line
			(start -0.12065 0.2794)
			(end -0.12065 0.3048)
			(stroke
				(width 0.1)
				(type default)
			)
			(layer "F.Fab")
		)
		(fp_line
			(start 0.120396 0.2794)
			(end -0.12065 0.2794)
			(stroke
				(width 0.1)
				(type default)
			)
			(layer "F.Fab")
		)
		(fp_line
			(start -0.12065 -0.2794)
			(end 0.12065 -0.2794)
			(stroke
				(width 0.1)
				(type default)
			)
			(layer "F.Fab")
		)
		(fp_line
			(start 0.12065 -0.2794)
			(end 0.12065 -0.3048)
			(stroke
				(width 0.1)
				(type default)
			)
			(layer "F.Fab")
		)
		(fp_line
			(start 0.12065 -0.3048)
			(end 0.67945 -0.3048)
			(stroke
				(width 0.1)
				(type default)
			)
			(layer "F.Fab")
		)
		(fp_line
			(start 0.67945 -0.3048)
			(end 0.67945 0.3048)
			(stroke
				(width 0.1)
				(type default)
			)
			(layer "F.Fab")
		)
		(fp_line
			(start -0.67945 -0.305054)
			(end -0.12065 -0.305054)
			(stroke
				(width 0.1)
				(type default)
			)
			(layer "F.Fab")
		)
		(fp_line
			(start -0.12065 -0.305054)
			(end -0.12065 -0.2794)
			(stroke
				(width 0.1)
				(type default)
			)
			(layer "F.Fab")
		)
		(pad "1" smd circle
			(at -0.40005 0 270)
			(size 0 0)
			(layers "F.Cu" "F.Mask" "F.Paste")
			(net "SW_P12V_PVCCINFAON_CPU0_FLT")
		)
		(pad "2" smd circle
			(at 0.40005 0 270)
			(size 0 0)
			(layers "F.Cu" "F.Mask" "F.Paste")
			(net "GND")
		)
	)
	(footprint ""
		(layer "F.Cu")
		(at 350.78416 -358.452674 180)
		(property "Reference" "C3269"
			(at 0 0 180)
			(layer "F.SilkS")
			(hide yes)
			(effects
				(font
					(size 1.27 1.27)
				)
			)
		)
		(property "Value" ""
			(at 0 0 180)
			(layer "F.Fab")
			(effects
				(font
					(size 1.27 1.27)
				)
			)
		)
		(duplicate_pad_numbers_are_jumpers no)
		(fp_line
			(start 0.7874 0.4064)
			(end -0.7874 0.4064)
			(stroke
				(width 0.1524)
				(type default)
			)
			(layer "F.SilkS")
		)
		(fp_line
			(start 0.7874 -0.4064)
			(end 0.7874 0.4064)
			(stroke
				(width 0.1524)
				(type default)
			)
			(layer "F.SilkS")
		)
		(fp_line
			(start -0.7874 0.4064)
			(end -0.7874 -0.4064)
			(stroke
				(width 0.1524)
				(type default)
			)
			(layer "F.SilkS")
		)
		(fp_line
			(start -0.7874 -0.4064)
			(end 0.7874 -0.4064)
			(stroke
				(width 0.1524)
				(type default)
			)
			(layer "F.SilkS")
		)
		(fp_line
			(start 0.67945 0.3048)
			(end 0.120396 0.3048)
			(stroke
				(width 0.1)
				(type default)
			)
			(layer "F.Fab")
		)
		(fp_line
			(start 0.67945 -0.3048)
			(end 0.67945 0.3048)
			(stroke
				(width 0.1)
				(type default)
			)
			(layer "F.Fab")
		)
		(fp_line
			(start 0.12065 -0.2794)
			(end 0.12065 -0.3048)
			(stroke
				(width 0.1)
				(type default)
			)
			(layer "F.Fab")
		)
		(fp_line
			(start 0.12065 -0.3048)
			(end 0.67945 -0.3048)
			(stroke
				(width 0.1)
				(type default)
			)
			(layer "F.Fab")
		)
		(fp_line
			(start 0.120396 0.3048)
			(end 0.120396 0.2794)
			(stroke
				(width 0.1)
				(type default)
			)
			(layer "F.Fab")
		)
		(fp_line
			(start 0.120396 0.2794)
			(end -0.12065 0.2794)
			(stroke
				(width 0.1)
				(type default)
			)
			(layer "F.Fab")
		)
		(fp_line
			(start -0.12065 0.3048)
			(end -0.67945 0.3048)
			(stroke
				(width 0.1)
				(type default)
			)
			(layer "F.Fab")
		)
		(fp_line
			(start -0.12065 0.2794)
			(end -0.12065 0.3048)
			(stroke
				(width 0.1)
				(type default)
			)
			(layer "F.Fab")
		)
		(fp_line
			(start -0.12065 -0.2794)
			(end 0.12065 -0.2794)
			(stroke
				(width 0.1)
				(type default)
			)
			(layer "F.Fab")
		)
		(fp_line
			(start -0.12065 -0.305054)
			(end -0.12065 -0.2794)
			(stroke
				(width 0.1)
				(type default)
			)
			(layer "F.Fab")
		)
		(fp_line
			(start -0.67945 0.3048)
			(end -0.67945 -0.305054)
			(stroke
				(width 0.1)
				(type default)
			)
			(layer "F.Fab")
		)
		(fp_line
			(start -0.67945 -0.305054)
			(end -0.12065 -0.305054)
			(stroke
				(width 0.1)
				(type default)
			)
			(layer "F.Fab")
		)
		(pad "1" smd circle
			(at -0.40005 0 180)
			(size 0 0)
			(layers "F.Cu" "F.Mask" "F.Paste")
			(net "PWRGD_PVCCFA_EHV_FIVRA_CPU0_R")
		)
		(pad "2" smd circle
			(at 0.40005 0 180)
			(size 0 0)
			(layers "F.Cu" "F.Mask" "F.Paste")
			(net "GND")
		)
	)
	(footprint ""
		(layer "F.Cu")
		(at 378.338842 -341.729822 90)
		(property "Reference" "PR1771"
			(at 0 0 90)
			(layer "F.SilkS")
			(hide yes)
			(effects
				(font
					(size 1.27 1.27)
				)
			)
		)
		(property "Value" ""
			(at 0 0 90)
			(layer "F.Fab")
			(effects
				(font
					(size 1.27 1.27)
				)
			)
		)
		(duplicate_pad_numbers_are_jumpers no)
		(fp_line
			(start 0.7874 -0.4064)
			(end 0.7874 0.4064)
			(stroke
				(width 0.1524)
				(type default)
			)
			(layer "F.SilkS")
		)
		(fp_line
			(start -0.7874 -0.4064)
			(end 0.7874 -0.4064)
			(stroke
				(width 0.1524)
				(type default)
			)
			(layer "F.SilkS")
		)
		(fp_line
			(start 0.7874 0.4064)
			(end -0.7874 0.4064)
			(stroke
				(width 0.1524)
				(type default)
			)
			(layer "F.SilkS")
		)
		(fp_line
			(start -0.7874 0.4064)
			(end -0.7874 -0.4064)
			(stroke
				(width 0.1524)
				(type default)
			)
			(layer "F.SilkS")
		)
		(fp_line
			(start -0.12065 -0.305054)
			(end -0.12065 -0.2794)
			(stroke
				(width 0.1)
				(type default)
			)
			(layer "F.Fab")
		)
		(fp_line
			(start -0.67945 -0.305054)
			(end -0.12065 -0.305054)
			(stroke
				(width 0.1)
				(type default)
			)
			(layer "F.Fab")
		)
		(fp_line
			(start 0.67945 -0.3048)
			(end 0.67945 0.3048)
			(stroke
				(width 0.1)
				(type default)
			)
			(layer "F.Fab")
		)
		(fp_line
			(start 0.12065 -0.3048)
			(end 0.67945 -0.3048)
			(stroke
				(width 0.1)
				(type default)
			)
			(layer "F.Fab")
		)
		(fp_line
			(start 0.12065 -0.2794)
			(end 0.12065 -0.3048)
			(stroke
				(width 0.1)
				(type default)
			)
			(layer "F.Fab")
		)
		(fp_line
			(start -0.12065 -0.2794)
			(end 0.12065 -0.2794)
			(stroke
				(width 0.1)
				(type default)
			)
			(layer "F.Fab")
		)
		(fp_line
			(start 0.120396 0.2794)
			(end -0.12065 0.2794)
			(stroke
				(width 0.1)
				(type default)
			)
			(layer "F.Fab")
		)
		(fp_line
			(start -0.12065 0.2794)
			(end -0.12065 0.3048)
			(stroke
				(width 0.1)
				(type default)
			)
			(layer "F.Fab")
		)
		(fp_line
			(start 0.67945 0.3048)
			(end 0.120396 0.3048)
			(stroke
				(width 0.1)
				(type default)
			)
			(layer "F.Fab")
		)
		(fp_line
			(start 0.120396 0.3048)
			(end 0.120396 0.2794)
			(stroke
				(width 0.1)
				(type default)
			)
			(layer "F.Fab")
		)
		(fp_line
			(start -0.12065 0.3048)
			(end -0.67945 0.3048)
			(stroke
				(width 0.1)
				(type default)
			)
			(layer "F.Fab")
		)
		(fp_line
			(start -0.67945 0.3048)
			(end -0.67945 -0.305054)
			(stroke
				(width 0.1)
				(type default)
			)
			(layer "F.Fab")
		)
		(pad "1" smd circle
			(at -0.40005 0 90)
			(size 0 0)
			(layers "F.Cu" "F.Mask" "F.Paste")
			(net "SW_PVCCIN_CPU0_BOOT5")
		)
		(pad "2" smd circle
			(at 0.40005 0 90)
			(size 0 0)
			(layers "F.Cu" "F.Mask" "F.Paste")
			(net "SW_PVCCIN_CPU0_BOOT5_R")
		)
	)
	(footprint ""
		(layer "F.Cu")
		(at 71.380096 -70.78599)
		(property "Reference" "D68"
			(at -37.474906 50.178462 90)
			(unlocked yes)
			(layer "F.SilkS")
			(effects
				(font
					(size 0.635 0.4064)
					(thickness 0.1524)
				)
				(justify left)
			)
		)
		(property "Value" ""
			(at 0 0 0)
			(layer "F.Fab")
			(effects
				(font
					(size 1.27 1.27)
				)
			)
		)
		(duplicate_pad_numbers_are_jumpers no)
		(fp_line
			(start -0.90678 0.4826)
			(end -0.90678 -0.4699)
			(stroke
				(width 0.1524)
				(type default)
			)
			(layer "F.SilkS")
		)
		(fp_line
			(start -0.89408 -0.4826)
			(end 0.90678 -0.4826)
			(stroke
				(width 0.1524)
				(type default)
			)
			(layer "F.SilkS")
		)
		(fp_line
			(start -0.79248 -0.4826)
			(end 1.03378 -0.4826)
			(stroke
				(width 0.1524)
				(type default)
			)
			(layer "F.SilkS")
		)
		(fp_line
			(start -0.64008 -0.4826)
			(end 1.16078 -0.4826)
			(stroke
				(width 0.1524)
				(type default)
			)
			(layer "F.SilkS")
		)
		(fp_line
			(start 0.90678 -0.4826)
			(end 0.90678 0.4826)
			(stroke
				(width 0.1524)
				(type default)
			)
			(layer "F.SilkS")
		)
		(fp_line
			(start 0.90678 0.4826)
			(end -0.90678 0.4826)
			(stroke
				(width 0.1524)
				(type default)
			)
			(layer "F.SilkS")
		)
		(fp_line
			(start 1.03378 -0.4826)
			(end 1.03378 0.4826)
			(stroke
				(width 0.1524)
				(type default)
			)
			(layer "F.SilkS")
		)
		(fp_line
			(start 1.03378 0.4826)
			(end -0.79248 0.4826)
			(stroke
				(width 0.1524)
				(type default)
			)
			(layer "F.SilkS")
		)
		(fp_line
			(start 1.16078 -0.4826)
			(end 1.16078 0.4826)
			(stroke
				(width 0.1524)
				(type default)
			)
			(layer "F.SilkS")
		)
		(fp_line
			(start 1.16078 0.4826)
			(end -0.64008 0.4826)
			(stroke
				(width 0.1524)
				(type default)
			)
			(layer "F.SilkS")
		)
		(fp_line
			(start -0.499872 -0.249936)
			(end 0.499872 -0.249936)
			(stroke
				(width 0.1)
				(type default)
			)
			(layer "F.Fab")
		)
		(fp_line
			(start -0.499872 0.249936)
			(end -0.499872 -0.249936)
			(stroke
				(width 0.1)
				(type default)
			)
			(layer "F.Fab")
		)
		(fp_line
			(start 0.499872 -0.249936)
			(end 0.499872 0.249936)
			(stroke
				(width 0.1)
				(type default)
			)
			(layer "F.Fab")
		)
		(fp_line
			(start 0.499872 0.249936)
			(end -0.499872 0.249936)
			(stroke
				(width 0.1)
				(type default)
			)
			(layer "F.Fab")
		)
		(pad "A" smd rect
			(at -0.47498 0)
			(size 0.6096 0.7112)
			(layers "F.Cu" "F.Mask" "F.Paste")
			(net "LED_RST_PLD_CPU0_DRAM_GH_N")
		)
		(pad "C" smd rect
			(at 0.47498 0)
			(size 0.6096 0.7112)
			(layers "F.Cu" "F.Mask" "F.Paste")
			(net "LED_RST_PLD_CPU0_DRAM_GH_N_D")
		)
	)
	(footprint ""
		(layer "F.Cu")
		(at 27.0383 -131.55295)
		(property "Reference" "R2568"
			(at 0 0 0)
			(layer "F.SilkS")
			(hide yes)
			(effects
				(font
					(size 1.27 1.27)
				)
			)
		)
		(property "Value" ""
			(at 0 0 0)
			(layer "F.Fab")
			(effects
				(font
					(size 1.27 1.27)
				)
			)
		)
		(duplicate_pad_numbers_are_jumpers no)
		(fp_line
			(start -0.7874 -0.4064)
			(end 0.7874 -0.4064)
			(stroke
				(width 0.1524)
				(type default)
			)
			(layer "F.SilkS")
		)
		(fp_line
			(start -0.7874 0.4064)
			(end -0.7874 -0.4064)
			(stroke
				(width 0.1524)
				(type default)
			)
			(layer "F.SilkS")
		)
		(fp_line
			(start 0.7874 -0.4064)
			(end 0.7874 0.4064)
			(stroke
				(width 0.1524)
				(type default)
			)
			(layer "F.SilkS")
		)
		(fp_line
			(start 0.7874 0.4064)
			(end -0.7874 0.4064)
			(stroke
				(width 0.1524)
				(type default)
			)
			(layer "F.SilkS")
		)
		(fp_line
			(start -0.67945 -0.305054)
			(end -0.12065 -0.305054)
			(stroke
				(width 0.1)
				(type default)
			)
			(layer "F.Fab")
		)
		(fp_line
			(start -0.67945 0.3048)
			(end -0.67945 -0.305054)
			(stroke
				(width 0.1)
				(type default)
			)
			(layer "F.Fab")
		)
		(fp_line
			(start -0.12065 -0.305054)
			(end -0.12065 -0.2794)
			(stroke
				(width 0.1)
				(type default)
			)
			(layer "F.Fab")
		)
		(fp_line
			(start -0.12065 -0.2794)
			(end 0.12065 -0.2794)
			(stroke
				(width 0.1)
				(type default)
			)
			(layer "F.Fab")
		)
		(fp_line
			(start -0.12065 0.2794)
			(end -0.12065 0.3048)
			(stroke
				(width 0.1)
				(type default)
			)
			(layer "F.Fab")
		)
		(fp_line
			(start -0.12065 0.3048)
			(end -0.67945 0.3048)
			(stroke
				(width 0.1)
				(type default)
			)
			(layer "F.Fab")
		)
		(fp_line
			(start 0.120396 0.2794)
			(end -0.12065 0.2794)
			(stroke
				(width 0.1)
				(type default)
			)
			(layer "F.Fab")
		)
		(fp_line
			(start 0.120396 0.3048)
			(end 0.120396 0.2794)
			(stroke
				(width 0.1)
				(type default)
			)
			(layer "F.Fab")
		)
		(fp_line
			(start 0.12065 -0.3048)
			(end 0.67945 -0.3048)
			(stroke
				(width 0.1)
				(type default)
			)
			(layer "F.Fab")
		)
		(fp_line
			(start 0.12065 -0.2794)
			(end 0.12065 -0.3048)
			(stroke
				(width 0.1)
				(type default)
			)
			(layer "F.Fab")
		)
		(fp_line
			(start 0.67945 -0.3048)
			(end 0.67945 0.3048)
			(stroke
				(width 0.1)
				(type default)
			)
			(layer "F.Fab")
		)
		(fp_line
			(start 0.67945 0.3048)
			(end 0.120396 0.3048)
			(stroke
				(width 0.1)
				(type default)
			)
			(layer "F.Fab")
		)
		(pad "1" smd circle
			(at -0.40005 0)
			(size 0 0)
			(layers "F.Cu" "F.Mask" "F.Paste")
			(net "P3V3_AUX")
		)
		(pad "2" smd circle
			(at 0.40005 0)
			(size 0 0)
			(layers "F.Cu" "F.Mask" "F.Paste")
			(net "PVCCINFAON_CPU1_VR_FAULT")
		)
	)
	(footprint ""
		(layer "F.Cu")
		(at 112.27308 -397.874998 -90)
		(property "Reference" "R3035"
			(at 0 0 270)
			(layer "F.SilkS")
			(hide yes)
			(effects
				(font
					(size 1.27 1.27)
				)
			)
		)
		(property "Value" ""
			(at 0 0 270)
			(layer "F.Fab")
			(effects
				(font
					(size 1.27 1.27)
				)
			)
		)
		(duplicate_pad_numbers_are_jumpers no)
		(fp_line
			(start -0.7874 0.4064)
			(end -0.7874 -0.4064)
			(stroke
				(width 0.1524)
				(type default)
			)
			(layer "F.SilkS")
		)
		(fp_line
			(start 0.7874 0.4064)
			(end -0.7874 0.4064)
			(stroke
				(width 0.1524)
				(type default)
			)
			(layer "F.SilkS")
		)
		(fp_line
			(start -0.7874 -0.4064)
			(end 0.7874 -0.4064)
			(stroke
				(width 0.1524)
				(type default)
			)
			(layer "F.SilkS")
		)
		(fp_line
			(start 0.7874 -0.4064)
			(end 0.7874 0.4064)
			(stroke
				(width 0.1524)
				(type default)
			)
			(layer "F.SilkS")
		)
		(fp_line
			(start -0.67945 0.3048)
			(end -0.67945 -0.305054)
			(stroke
				(width 0.1)
				(type default)
			)
			(layer "F.Fab")
		)
		(fp_line
			(start -0.12065 0.3048)
			(end -0.67945 0.3048)
			(stroke
				(width 0.1)
				(type default)
			)
			(layer "F.Fab")
		)
		(fp_line
			(start 0.120396 0.3048)
			(end 0.120396 0.2794)
			(stroke
				(width 0.1)
				(type default)
			)
			(layer "F.Fab")
		)
		(fp_line
			(start 0.67945 0.3048)
			(end 0.120396 0.3048)
			(stroke
				(width 0.1)
				(type default)
			)
			(layer "F.Fab")
		)
		(fp_line
			(start -0.12065 0.2794)
			(end -0.12065 0.3048)
			(stroke
				(width 0.1)
				(type default)
			)
			(layer "F.Fab")
		)
		(fp_line
			(start 0.120396 0.2794)
			(end -0.12065 0.2794)
			(stroke
				(width 0.1)
				(type default)
			)
			(layer "F.Fab")
		)
		(fp_line
			(start -0.12065 -0.2794)
			(end 0.12065 -0.2794)
			(stroke
				(width 0.1)
				(type default)
			)
			(layer "F.Fab")
		)
		(fp_line
			(start 0.12065 -0.2794)
			(end 0.12065 -0.3048)
			(stroke
				(width 0.1)
				(type default)
			)
			(layer "F.Fab")
		)
		(fp_line
			(start 0.12065 -0.3048)
			(end 0.67945 -0.3048)
			(stroke
				(width 0.1)
				(type default)
			)
			(layer "F.Fab")
		)
		(fp_line
			(start 0.67945 -0.3048)
			(end 0.67945 0.3048)
			(stroke
				(width 0.1)
				(type default)
			)
			(layer "F.Fab")
		)
		(fp_line
			(start -0.67945 -0.305054)
			(end -0.12065 -0.305054)
			(stroke
				(width 0.1)
				(type default)
			)
			(layer "F.Fab")
		)
		(fp_line
			(start -0.12065 -0.305054)
			(end -0.12065 -0.2794)
			(stroke
				(width 0.1)
				(type default)
			)
			(layer "F.Fab")
		)
		(pad "1" smd circle
			(at -0.40005 0 270)
			(size 0 0)
			(layers "F.Cu" "F.Mask" "F.Paste")
			(net "P3V3_AUX")
		)
		(pad "2" smd circle
			(at 0.40005 0 270)
			(size 0 0)
			(layers "F.Cu" "F.Mask" "F.Paste")
			(net "FM_SMB_2_ALERT_GPU_ISO_N")
		)
	)
	(footprint ""
		(layer "F.Cu")
		(at 376.72137 -408.517344 -90)
		(property "Reference" "C873"
			(at 0 0 270)
			(layer "F.SilkS")
			(hide yes)
			(effects
				(font
					(size 1.27 1.27)
				)
			)
		)
		(property "Value" ""
			(at 0 0 270)
			(layer "F.Fab")
			(effects
				(font
					(size 1.27 1.27)
				)
			)
		)
		(duplicate_pad_numbers_are_jumpers no)
		(fp_line
			(start -0.299974 0.150114)
			(end -0.299974 -0.150114)
			(stroke
				(width 0.1)
				(type default)
			)
			(layer "F.Fab")
		)
		(fp_line
			(start 0.299974 0.150114)
			(end -0.299974 0.150114)
			(stroke
				(width 0.1)
				(type default)
			)
			(layer "F.Fab")
		)
		(fp_line
			(start -0.299974 -0.150114)
			(end 0.299974 -0.150114)
			(stroke
				(width 0.1)
				(type default)
			)
			(layer "F.Fab")
		)
		(fp_line
			(start 0.299974 -0.150114)
			(end 0.299974 0.150114)
			(stroke
				(width 0.1)
				(type default)
			)
			(layer "F.Fab")
		)
		(pad "1" smd rect
			(at -0.2667 0 270)
			(size 0.3048 0.381)
			(layers "F.Cu" "F.Mask" "F.Paste")
			(net "P5E_CPU0_PE3_TX_C_DP<14>")
		)
		(pad "2" smd rect
			(at 0.2667 0 270)
			(size 0.3048 0.381)
			(layers "F.Cu" "F.Mask" "F.Paste")
			(net "P5E_CPU0_PE3_TX_DP<14>")
		)
	)
	(footprint ""
		(layer "F.Cu")
		(at 68.085716 -112.70869)
		(property "Reference" "R3704"
			(at 0 0 0)
			(layer "F.SilkS")
			(hide yes)
			(effects
				(font
					(size 1.27 1.27)
				)
			)
		)
		(property "Value" ""
			(at 0 0 0)
			(layer "F.Fab")
			(effects
				(font
					(size 1.27 1.27)
				)
			)
		)
		(duplicate_pad_numbers_are_jumpers no)
		(fp_line
			(start -0.7874 -0.4064)
			(end 0.7874 -0.4064)
			(stroke
				(width 0.1524)
				(type default)
			)
			(layer "F.SilkS")
		)
		(fp_line
			(start -0.7874 0.4064)
			(end -0.7874 -0.4064)
			(stroke
				(width 0.1524)
				(type default)
			)
			(layer "F.SilkS")
		)
		(fp_line
			(start 0.7874 -0.4064)
			(end 0.7874 0.4064)
			(stroke
				(width 0.1524)
				(type default)
			)
			(layer "F.SilkS")
		)
		(fp_line
			(start 0.7874 0.4064)
			(end -0.7874 0.4064)
			(stroke
				(width 0.1524)
				(type default)
			)
			(layer "F.SilkS")
		)
		(fp_line
			(start -0.67945 -0.305054)
			(end -0.12065 -0.305054)
			(stroke
				(width 0.1)
				(type default)
			)
			(layer "F.Fab")
		)
		(fp_line
			(start -0.67945 0.3048)
			(end -0.67945 -0.305054)
			(stroke
				(width 0.1)
				(type default)
			)
			(layer "F.Fab")
		)
		(fp_line
			(start -0.12065 -0.305054)
			(end -0.12065 -0.2794)
			(stroke
				(width 0.1)
				(type default)
			)
			(layer "F.Fab")
		)
		(fp_line
			(start -0.12065 -0.2794)
			(end 0.12065 -0.2794)
			(stroke
				(width 0.1)
				(type default)
			)
			(layer "F.Fab")
		)
		(fp_line
			(start -0.12065 0.2794)
			(end -0.12065 0.3048)
			(stroke
				(width 0.1)
				(type default)
			)
			(layer "F.Fab")
		)
		(fp_line
			(start -0.12065 0.3048)
			(end -0.67945 0.3048)
			(stroke
				(width 0.1)
				(type default)
			)
			(layer "F.Fab")
		)
		(fp_line
			(start 0.120396 0.2794)
			(end -0.12065 0.2794)
			(stroke
				(width 0.1)
				(type default)
			)
			(layer "F.Fab")
		)
		(fp_line
			(start 0.120396 0.3048)
			(end 0.120396 0.2794)
			(stroke
				(width 0.1)
				(type default)
			)
			(layer "F.Fab")
		)
		(fp_line
			(start 0.12065 -0.3048)
			(end 0.67945 -0.3048)
			(stroke
				(width 0.1)
				(type default)
			)
			(layer "F.Fab")
		)
		(fp_line
			(start 0.12065 -0.2794)
			(end 0.12065 -0.3048)
			(stroke
				(width 0.1)
				(type default)
			)
			(layer "F.Fab")
		)
		(fp_line
			(start 0.67945 -0.3048)
			(end 0.67945 0.3048)
			(stroke
				(width 0.1)
				(type default)
			)
			(layer "F.Fab")
		)
		(fp_line
			(start 0.67945 0.3048)
			(end 0.120396 0.3048)
			(stroke
				(width 0.1)
				(type default)
			)
			(layer "F.Fab")
		)
		(pad "1" smd circle
			(at -0.40005 0)
			(size 0 0)
			(layers "F.Cu" "F.Mask" "F.Paste")
			(net "PCA9548_PCIE0_ADDR2")
		)
		(pad "2" smd circle
			(at 0.40005 0)
			(size 0 0)
			(layers "F.Cu" "F.Mask" "F.Paste")
			(net "GND")
		)
	)
	(footprint ""
		(layer "F.Cu")
		(at 197.41388 -111.724948 -90)
		(property "Reference" "C1320"
			(at 0 0 270)
			(layer "F.SilkS")
			(hide yes)
			(effects
				(font
					(size 1.27 1.27)
				)
			)
		)
		(property "Value" ""
			(at 0 0 270)
			(layer "F.Fab")
			(effects
				(font
					(size 1.27 1.27)
				)
			)
		)
		(duplicate_pad_numbers_are_jumpers no)
		(fp_line
			(start -0.7874 0.4064)
			(end -0.7874 -0.4064)
			(stroke
				(width 0.1524)
				(type default)
			)
			(layer "F.SilkS")
		)
		(fp_line
			(start 0.7874 0.4064)
			(end -0.7874 0.4064)
			(stroke
				(width 0.1524)
				(type default)
			)
			(layer "F.SilkS")
		)
		(fp_line
			(start -0.7874 -0.4064)
			(end 0.7874 -0.4064)
			(stroke
				(width 0.1524)
				(type default)
			)
			(layer "F.SilkS")
		)
		(fp_line
			(start 0.7874 -0.4064)
			(end 0.7874 0.4064)
			(stroke
				(width 0.1524)
				(type default)
			)
			(layer "F.SilkS")
		)
		(fp_line
			(start -0.67945 0.3048)
			(end -0.67945 -0.305054)
			(stroke
				(width 0.1)
				(type default)
			)
			(layer "F.Fab")
		)
		(fp_line
			(start -0.12065 0.3048)
			(end -0.67945 0.3048)
			(stroke
				(width 0.1)
				(type default)
			)
			(layer "F.Fab")
		)
		(fp_line
			(start 0.120396 0.3048)
			(end 0.120396 0.2794)
			(stroke
				(width 0.1)
				(type default)
			)
			(layer "F.Fab")
		)
		(fp_line
			(start 0.67945 0.3048)
			(end 0.120396 0.3048)
			(stroke
				(width 0.1)
				(type default)
			)
			(layer "F.Fab")
		)
		(fp_line
			(start -0.12065 0.2794)
			(end -0.12065 0.3048)
			(stroke
				(width 0.1)
				(type default)
			)
			(layer "F.Fab")
		)
		(fp_line
			(start 0.120396 0.2794)
			(end -0.12065 0.2794)
			(stroke
				(width 0.1)
				(type default)
			)
			(layer "F.Fab")
		)
		(fp_line
			(start -0.12065 -0.2794)
			(end 0.12065 -0.2794)
			(stroke
				(width 0.1)
				(type default)
			)
			(layer "F.Fab")
		)
		(fp_line
			(start 0.12065 -0.2794)
			(end 0.12065 -0.3048)
			(stroke
				(width 0.1)
				(type default)
			)
			(layer "F.Fab")
		)
		(fp_line
			(start 0.12065 -0.3048)
			(end 0.67945 -0.3048)
			(stroke
				(width 0.1)
				(type default)
			)
			(layer "F.Fab")
		)
		(fp_line
			(start 0.67945 -0.3048)
			(end 0.67945 0.3048)
			(stroke
				(width 0.1)
				(type default)
			)
			(layer "F.Fab")
		)
		(fp_line
			(start -0.67945 -0.305054)
			(end -0.12065 -0.305054)
			(stroke
				(width 0.1)
				(type default)
			)
			(layer "F.Fab")
		)
		(fp_line
			(start -0.12065 -0.305054)
			(end -0.12065 -0.2794)
			(stroke
				(width 0.1)
				(type default)
			)
			(layer "F.Fab")
		)
		(pad "1" smd circle
			(at -0.40005 0 270)
			(size 0 0)
			(layers "F.Cu" "F.Mask" "F.Paste")
			(net "P3V3_AUX")
		)
		(pad "2" smd circle
			(at 0.40005 0 270)
			(size 0 0)
			(layers "F.Cu" "F.Mask" "F.Paste")
			(net "GND")
		)
	)
	(footprint ""
		(layer "F.Cu")
		(at 365.2012 -414.7566)
		(property "Reference" "C2391"
			(at 0 0 0)
			(layer "F.SilkS")
			(hide yes)
			(effects
				(font
					(size 1.27 1.27)
				)
			)
		)
		(property "Value" ""
			(at 0 0 0)
			(layer "F.Fab")
			(effects
				(font
					(size 1.27 1.27)
				)
			)
		)
		(duplicate_pad_numbers_are_jumpers no)
		(fp_line
			(start -0.7874 -0.4064)
			(end 0.7874 -0.4064)
			(stroke
				(width 0.1524)
				(type default)
			)
			(layer "F.SilkS")
		)
		(fp_line
			(start -0.7874 0.4064)
			(end -0.7874 -0.4064)
			(stroke
				(width 0.1524)
				(type default)
			)
			(layer "F.SilkS")
		)
		(fp_line
			(start 0.7874 -0.4064)
			(end 0.7874 0.4064)
			(stroke
				(width 0.1524)
				(type default)
			)
			(layer "F.SilkS")
		)
		(fp_line
			(start 0.7874 0.4064)
			(end -0.7874 0.4064)
			(stroke
				(width 0.1524)
				(type default)
			)
			(layer "F.SilkS")
		)
		(fp_line
			(start -0.67945 -0.305054)
			(end -0.12065 -0.305054)
			(stroke
				(width 0.1)
				(type default)
			)
			(layer "F.Fab")
		)
		(fp_line
			(start -0.67945 0.3048)
			(end -0.67945 -0.305054)
			(stroke
				(width 0.1)
				(type default)
			)
			(layer "F.Fab")
		)
		(fp_line
			(start -0.12065 -0.305054)
			(end -0.12065 -0.2794)
			(stroke
				(width 0.1)
				(type default)
			)
			(layer "F.Fab")
		)
		(fp_line
			(start -0.12065 -0.2794)
			(end 0.12065 -0.2794)
			(stroke
				(width 0.1)
				(type default)
			)
			(layer "F.Fab")
		)
		(fp_line
			(start -0.12065 0.2794)
			(end -0.12065 0.3048)
			(stroke
				(width 0.1)
				(type default)
			)
			(layer "F.Fab")
		)
		(fp_line
			(start -0.12065 0.3048)
			(end -0.67945 0.3048)
			(stroke
				(width 0.1)
				(type default)
			)
			(layer "F.Fab")
		)
		(fp_line
			(start 0.120396 0.2794)
			(end -0.12065 0.2794)
			(stroke
				(width 0.1)
				(type default)
			)
			(layer "F.Fab")
		)
		(fp_line
			(start 0.120396 0.3048)
			(end 0.120396 0.2794)
			(stroke
				(width 0.1)
				(type default)
			)
			(layer "F.Fab")
		)
		(fp_line
			(start 0.12065 -0.3048)
			(end 0.67945 -0.3048)
			(stroke
				(width 0.1)
				(type default)
			)
			(layer "F.Fab")
		)
		(fp_line
			(start 0.12065 -0.2794)
			(end 0.12065 -0.3048)
			(stroke
				(width 0.1)
				(type default)
			)
			(layer "F.Fab")
		)
		(fp_line
			(start 0.67945 -0.3048)
			(end 0.67945 0.3048)
			(stroke
				(width 0.1)
				(type default)
			)
			(layer "F.Fab")
		)
		(fp_line
			(start 0.67945 0.3048)
			(end 0.120396 0.3048)
			(stroke
				(width 0.1)
				(type default)
			)
			(layer "F.Fab")
		)
		(pad "1" smd circle
			(at -0.40005 0)
			(size 0 0)
			(layers "F.Cu" "F.Mask" "F.Paste")
			(net "PRSNT_CABLE_GPU_A3_ISO_N")
		)
		(pad "2" smd circle
			(at 0.40005 0)
			(size 0 0)
			(layers "F.Cu" "F.Mask" "F.Paste")
			(net "GND")
		)
	)
	(footprint ""
		(layer "F.Cu")
		(at 15.436596 -389.151876 180)
		(property "Reference" "R3290"
			(at 0 0 180)
			(layer "F.SilkS")
			(hide yes)
			(effects
				(font
					(size 1.27 1.27)
				)
			)
		)
		(property "Value" ""
			(at 0 0 180)
			(layer "F.Fab")
			(effects
				(font
					(size 1.27 1.27)
				)
			)
		)
		(duplicate_pad_numbers_are_jumpers no)
		(fp_line
			(start 0.7874 0.4064)
			(end -0.7874 0.4064)
			(stroke
				(width 0.1524)
				(type default)
			)
			(layer "F.SilkS")
		)
		(fp_line
			(start 0.7874 -0.4064)
			(end 0.7874 0.4064)
			(stroke
				(width 0.1524)
				(type default)
			)
			(layer "F.SilkS")
		)
		(fp_line
			(start -0.7874 0.4064)
			(end -0.7874 -0.4064)
			(stroke
				(width 0.1524)
				(type default)
			)
			(layer "F.SilkS")
		)
		(fp_line
			(start -0.7874 -0.4064)
			(end 0.7874 -0.4064)
			(stroke
				(width 0.1524)
				(type default)
			)
			(layer "F.SilkS")
		)
		(fp_line
			(start 0.67945 0.3048)
			(end 0.120396 0.3048)
			(stroke
				(width 0.1)
				(type default)
			)
			(layer "F.Fab")
		)
		(fp_line
			(start 0.67945 -0.3048)
			(end 0.67945 0.3048)
			(stroke
				(width 0.1)
				(type default)
			)
			(layer "F.Fab")
		)
		(fp_line
			(start 0.12065 -0.2794)
			(end 0.12065 -0.3048)
			(stroke
				(width 0.1)
				(type default)
			)
			(layer "F.Fab")
		)
		(fp_line
			(start 0.12065 -0.3048)
			(end 0.67945 -0.3048)
			(stroke
				(width 0.1)
				(type default)
			)
			(layer "F.Fab")
		)
		(fp_line
			(start 0.120396 0.3048)
			(end 0.120396 0.2794)
			(stroke
				(width 0.1)
				(type default)
			)
			(layer "F.Fab")
		)
		(fp_line
			(start 0.120396 0.2794)
			(end -0.12065 0.2794)
			(stroke
				(width 0.1)
				(type default)
			)
			(layer "F.Fab")
		)
		(fp_line
			(start -0.12065 0.3048)
			(end -0.67945 0.3048)
			(stroke
				(width 0.1)
				(type default)
			)
			(layer "F.Fab")
		)
		(fp_line
			(start -0.12065 0.2794)
			(end -0.12065 0.3048)
			(stroke
				(width 0.1)
				(type default)
			)
			(layer "F.Fab")
		)
		(fp_line
			(start -0.12065 -0.2794)
			(end 0.12065 -0.2794)
			(stroke
				(width 0.1)
				(type default)
			)
			(layer "F.Fab")
		)
		(fp_line
			(start -0.12065 -0.305054)
			(end -0.12065 -0.2794)
			(stroke
				(width 0.1)
				(type default)
			)
			(layer "F.Fab")
		)
		(fp_line
			(start -0.67945 0.3048)
			(end -0.67945 -0.305054)
			(stroke
				(width 0.1)
				(type default)
			)
			(layer "F.Fab")
		)
		(fp_line
			(start -0.67945 -0.305054)
			(end -0.12065 -0.305054)
			(stroke
				(width 0.1)
				(type default)
			)
			(layer "F.Fab")
		)
		(pad "1" smd circle
			(at -0.40005 0 180)
			(size 0 0)
			(layers "F.Cu" "F.Mask" "F.Paste")
			(net "FM_P2E_SWA")
		)
		(pad "2" smd circle
			(at 0.40005 0 180)
			(size 0 0)
			(layers "F.Cu" "F.Mask" "F.Paste")
			(net "GND")
		)
	)
	(footprint ""
		(layer "F.Cu")
		(at 62.35446 -156.47797)
		(property "Reference" "PL21"
			(at -3.47726 -4.491228 0)
			(unlocked yes)
			(layer "F.SilkS")
			(effects
				(font
					(size 0.7874 0.5842)
					(thickness 0.1524)
				)
				(justify left)
			)
		)
		(property "Value" ""
			(at 0 0 0)
			(layer "F.Fab")
			(effects
				(font
					(size 1.27 1.27)
				)
			)
		)
		(duplicate_pad_numbers_are_jumpers no)
		(fp_line
			(start -3.24993 -3.24993)
			(end 3.24993 -3.24993)
			(stroke
				(width 0.1524)
				(type default)
			)
			(layer "F.SilkS")
		)
		(fp_line
			(start -3.24993 -2.2352)
			(end -3.24993 -3.24993)
			(stroke
				(width 0.1524)
				(type default)
			)
			(layer "F.SilkS")
		)
		(fp_line
			(start -3.24993 3.24993)
			(end -3.24993 2.2352)
			(stroke
				(width 0.1524)
				(type default)
			)
			(layer "F.SilkS")
		)
		(fp_line
			(start 3.24993 -3.24993)
			(end 3.24993 -2.2352)
			(stroke
				(width 0.1524)
				(type default)
			)
			(layer "F.SilkS")
		)
		(fp_line
			(start 3.24993 2.2352)
			(end 3.24993 3.24993)
			(stroke
				(width 0.1524)
				(type default)
			)
			(layer "F.SilkS")
		)
		(fp_line
			(start 3.24993 3.24993)
			(end -3.24993 3.24993)
			(stroke
				(width 0.1524)
				(type default)
			)
			(layer "F.SilkS")
		)
		(fp_line
			(start -3.24993 -3.24993)
			(end 3.24993 -3.24993)
			(stroke
				(width 0.1)
				(type default)
			)
			(layer "F.Fab")
		)
		(fp_line
			(start -3.24993 3.24993)
			(end -3.24993 -3.24993)
			(stroke
				(width 0.1)
				(type default)
			)
			(layer "F.Fab")
		)
		(fp_line
			(start 3.24993 -3.24993)
			(end 3.24993 3.24993)
			(stroke
				(width 0.1)
				(type default)
			)
			(layer "F.Fab")
		)
		(fp_line
			(start 3.24993 3.24993)
			(end -3.24993 3.24993)
			(stroke
				(width 0.1)
				(type default)
			)
			(layer "F.Fab")
		)
		(pad "1" smd rect
			(at -2.29997 0)
			(size 2.0066 4.2164)
			(layers "F.Cu" "F.Mask" "F.Paste")
			(net "SW_PVCCINFAON_CPU1_SW1")
		)
		(pad "2" smd rect
			(at 2.29997 0)
			(size 2.0066 4.2164)
			(layers "F.Cu" "F.Mask" "F.Paste")
			(net "PVCCINFAON_CPU1")
		)
	)
	(footprint ""
		(layer "F.Cu")
		(at 257.87985 -39.484046 90)
		(property "Reference" "PR4528"
			(at 0 0 90)
			(layer "F.SilkS")
			(hide yes)
			(effects
				(font
					(size 1.27 1.27)
				)
			)
		)
		(property "Value" ""
			(at 0 0 90)
			(layer "F.Fab")
			(effects
				(font
					(size 1.27 1.27)
				)
			)
		)
		(duplicate_pad_numbers_are_jumpers no)
		(fp_line
			(start 0.7874 -0.4064)
			(end 0.7874 0.4064)
			(stroke
				(width 0.1524)
				(type default)
			)
			(layer "F.SilkS")
		)
		(fp_line
			(start -0.7874 -0.4064)
			(end 0.7874 -0.4064)
			(stroke
				(width 0.1524)
				(type default)
			)
			(layer "F.SilkS")
		)
		(fp_line
			(start 0.7874 0.4064)
			(end -0.7874 0.4064)
			(stroke
				(width 0.1524)
				(type default)
			)
			(layer "F.SilkS")
		)
		(fp_line
			(start -0.7874 0.4064)
			(end -0.7874 -0.4064)
			(stroke
				(width 0.1524)
				(type default)
			)
			(layer "F.SilkS")
		)
		(fp_line
			(start -0.12065 -0.305054)
			(end -0.12065 -0.2794)
			(stroke
				(width 0.1)
				(type default)
			)
			(layer "F.Fab")
		)
		(fp_line
			(start -0.67945 -0.305054)
			(end -0.12065 -0.305054)
			(stroke
				(width 0.1)
				(type default)
			)
			(layer "F.Fab")
		)
		(fp_line
			(start 0.67945 -0.3048)
			(end 0.67945 0.3048)
			(stroke
				(width 0.1)
				(type default)
			)
			(layer "F.Fab")
		)
		(fp_line
			(start 0.12065 -0.3048)
			(end 0.67945 -0.3048)
			(stroke
				(width 0.1)
				(type default)
			)
			(layer "F.Fab")
		)
		(fp_line
			(start 0.12065 -0.2794)
			(end 0.12065 -0.3048)
			(stroke
				(width 0.1)
				(type default)
			)
			(layer "F.Fab")
		)
		(fp_line
			(start -0.12065 -0.2794)
			(end 0.12065 -0.2794)
			(stroke
				(width 0.1)
				(type default)
			)
			(layer "F.Fab")
		)
		(fp_line
			(start 0.120396 0.2794)
			(end -0.12065 0.2794)
			(stroke
				(width 0.1)
				(type default)
			)
			(layer "F.Fab")
		)
		(fp_line
			(start -0.12065 0.2794)
			(end -0.12065 0.3048)
			(stroke
				(width 0.1)
				(type default)
			)
			(layer "F.Fab")
		)
		(fp_line
			(start 0.67945 0.3048)
			(end 0.120396 0.3048)
			(stroke
				(width 0.1)
				(type default)
			)
			(layer "F.Fab")
		)
		(fp_line
			(start 0.120396 0.3048)
			(end 0.120396 0.2794)
			(stroke
				(width 0.1)
				(type default)
			)
			(layer "F.Fab")
		)
		(fp_line
			(start -0.12065 0.3048)
			(end -0.67945 0.3048)
			(stroke
				(width 0.1)
				(type default)
			)
			(layer "F.Fab")
		)
		(fp_line
			(start -0.67945 0.3048)
			(end -0.67945 -0.305054)
			(stroke
				(width 0.1)
				(type default)
			)
			(layer "F.Fab")
		)
		(pad "1" smd circle
			(at -0.40005 0 90)
			(size 0 0)
			(layers "F.Cu" "F.Mask" "F.Paste")
			(net "P12V_E1S_0")
		)
		(pad "2" smd circle
			(at 0.40005 0 90)
			(size 0 0)
			(layers "F.Cu" "F.Mask" "F.Paste")
			(net "P12V_E1S_GATE_0")
		)
	)
	(footprint ""
		(layer "F.Cu")
		(at 365.390938 -417.15309 90)
		(property "Reference" "R4209"
			(at 0 0 90)
			(layer "F.SilkS")
			(hide yes)
			(effects
				(font
					(size 1.27 1.27)
				)
			)
		)
		(property "Value" ""
			(at 0 0 90)
			(layer "F.Fab")
			(effects
				(font
					(size 1.27 1.27)
				)
			)
		)
		(duplicate_pad_numbers_are_jumpers no)
		(fp_line
			(start 0.7874 -0.4064)
			(end 0.7874 0.4064)
			(stroke
				(width 0.1524)
				(type default)
			)
			(layer "F.SilkS")
		)
		(fp_line
			(start -0.7874 -0.4064)
			(end 0.7874 -0.4064)
			(stroke
				(width 0.1524)
				(type default)
			)
			(layer "F.SilkS")
		)
		(fp_line
			(start 0.7874 0.4064)
			(end -0.7874 0.4064)
			(stroke
				(width 0.1524)
				(type default)
			)
			(layer "F.SilkS")
		)
		(fp_line
			(start -0.7874 0.4064)
			(end -0.7874 -0.4064)
			(stroke
				(width 0.1524)
				(type default)
			)
			(layer "F.SilkS")
		)
		(fp_line
			(start -0.12065 -0.305054)
			(end -0.12065 -0.2794)
			(stroke
				(width 0.1)
				(type default)
			)
			(layer "F.Fab")
		)
		(fp_line
			(start -0.67945 -0.305054)
			(end -0.12065 -0.305054)
			(stroke
				(width 0.1)
				(type default)
			)
			(layer "F.Fab")
		)
		(fp_line
			(start 0.67945 -0.3048)
			(end 0.67945 0.3048)
			(stroke
				(width 0.1)
				(type default)
			)
			(layer "F.Fab")
		)
		(fp_line
			(start 0.12065 -0.3048)
			(end 0.67945 -0.3048)
			(stroke
				(width 0.1)
				(type default)
			)
			(layer "F.Fab")
		)
		(fp_line
			(start 0.12065 -0.2794)
			(end 0.12065 -0.3048)
			(stroke
				(width 0.1)
				(type default)
			)
			(layer "F.Fab")
		)
		(fp_line
			(start -0.12065 -0.2794)
			(end 0.12065 -0.2794)
			(stroke
				(width 0.1)
				(type default)
			)
			(layer "F.Fab")
		)
		(fp_line
			(start 0.120396 0.2794)
			(end -0.12065 0.2794)
			(stroke
				(width 0.1)
				(type default)
			)
			(layer "F.Fab")
		)
		(fp_line
			(start -0.12065 0.2794)
			(end -0.12065 0.3048)
			(stroke
				(width 0.1)
				(type default)
			)
			(layer "F.Fab")
		)
		(fp_line
			(start 0.67945 0.3048)
			(end 0.120396 0.3048)
			(stroke
				(width 0.1)
				(type default)
			)
			(layer "F.Fab")
		)
		(fp_line
			(start 0.120396 0.3048)
			(end 0.120396 0.2794)
			(stroke
				(width 0.1)
				(type default)
			)
			(layer "F.Fab")
		)
		(fp_line
			(start -0.12065 0.3048)
			(end -0.67945 0.3048)
			(stroke
				(width 0.1)
				(type default)
			)
			(layer "F.Fab")
		)
		(fp_line
			(start -0.67945 0.3048)
			(end -0.67945 -0.305054)
			(stroke
				(width 0.1)
				(type default)
			)
			(layer "F.Fab")
		)
		(pad "1" smd circle
			(at -0.40005 0 90)
			(size 0 0)
			(layers "F.Cu" "F.Mask" "F.Paste")
			(net "P3V3_AUX")
		)
		(pad "2" smd circle
			(at 0.40005 0 90)
			(size 0 0)
			(layers "F.Cu" "F.Mask" "F.Paste")
			(net "FM_THERMAL_ALERT_N")
		)
	)
	(footprint ""
		(layer "F.Cu")
		(at 182.471822 -358.15778 90)
		(property "Reference" "PR1802"
			(at 0 0 90)
			(layer "F.SilkS")
			(hide yes)
			(effects
				(font
					(size 1.27 1.27)
				)
			)
		)
		(property "Value" ""
			(at 0 0 90)
			(layer "F.Fab")
			(effects
				(font
					(size 1.27 1.27)
				)
			)
		)
		(duplicate_pad_numbers_are_jumpers no)
		(fp_line
			(start 0.7874 -0.4064)
			(end 0.7874 0.4064)
			(stroke
				(width 0.1524)
				(type default)
			)
			(layer "F.SilkS")
		)
		(fp_line
			(start -0.7874 -0.4064)
			(end 0.7874 -0.4064)
			(stroke
				(width 0.1524)
				(type default)
			)
			(layer "F.SilkS")
		)
		(fp_line
			(start 0.7874 0.4064)
			(end -0.7874 0.4064)
			(stroke
				(width 0.1524)
				(type default)
			)
			(layer "F.SilkS")
		)
		(fp_line
			(start -0.7874 0.4064)
			(end -0.7874 -0.4064)
			(stroke
				(width 0.1524)
				(type default)
			)
			(layer "F.SilkS")
		)
		(fp_line
			(start -0.12065 -0.305054)
			(end -0.12065 -0.2794)
			(stroke
				(width 0.1)
				(type default)
			)
			(layer "F.Fab")
		)
		(fp_line
			(start -0.67945 -0.305054)
			(end -0.12065 -0.305054)
			(stroke
				(width 0.1)
				(type default)
			)
			(layer "F.Fab")
		)
		(fp_line
			(start 0.67945 -0.3048)
			(end 0.67945 0.3048)
			(stroke
				(width 0.1)
				(type default)
			)
			(layer "F.Fab")
		)
		(fp_line
			(start 0.12065 -0.3048)
			(end 0.67945 -0.3048)
			(stroke
				(width 0.1)
				(type default)
			)
			(layer "F.Fab")
		)
		(fp_line
			(start 0.12065 -0.2794)
			(end 0.12065 -0.3048)
			(stroke
				(width 0.1)
				(type default)
			)
			(layer "F.Fab")
		)
		(fp_line
			(start -0.12065 -0.2794)
			(end 0.12065 -0.2794)
			(stroke
				(width 0.1)
				(type default)
			)
			(layer "F.Fab")
		)
		(fp_line
			(start 0.120396 0.2794)
			(end -0.12065 0.2794)
			(stroke
				(width 0.1)
				(type default)
			)
			(layer "F.Fab")
		)
		(fp_line
			(start -0.12065 0.2794)
			(end -0.12065 0.3048)
			(stroke
				(width 0.1)
				(type default)
			)
			(layer "F.Fab")
		)
		(fp_line
			(start 0.67945 0.3048)
			(end 0.120396 0.3048)
			(stroke
				(width 0.1)
				(type default)
			)
			(layer "F.Fab")
		)
		(fp_line
			(start 0.120396 0.3048)
			(end 0.120396 0.2794)
			(stroke
				(width 0.1)
				(type default)
			)
			(layer "F.Fab")
		)
		(fp_line
			(start -0.12065 0.3048)
			(end -0.67945 0.3048)
			(stroke
				(width 0.1)
				(type default)
			)
			(layer "F.Fab")
		)
		(fp_line
			(start -0.67945 0.3048)
			(end -0.67945 -0.305054)
			(stroke
				(width 0.1)
				(type default)
			)
			(layer "F.Fab")
		)
		(pad "1" smd circle
			(at -0.40005 0 90)
			(size 0 0)
			(layers "F.Cu" "F.Mask" "F.Paste")
			(net "SW_PVCCFA_EHV_FIVRA_CPU1_BOOT3")
		)
		(pad "2" smd circle
			(at 0.40005 0 90)
			(size 0 0)
			(layers "F.Cu" "F.Mask" "F.Paste")
			(net "SW_PVCCFA_EHV_FIVRA_CPU1_BOOT3_")
		)
	)
	(footprint ""
		(layer "F.Cu")
		(at 417.946332 -366.691164 -90)
		(property "Reference" "PC606"
			(at 0 0 270)
			(layer "F.SilkS")
			(hide yes)
			(effects
				(font
					(size 1.27 1.27)
				)
			)
		)
		(property "Value" ""
			(at 0 0 270)
			(layer "F.Fab")
			(effects
				(font
					(size 1.27 1.27)
				)
			)
		)
		(duplicate_pad_numbers_are_jumpers no)
		(fp_line
			(start -0.7874 0.4064)
			(end -0.7874 -0.4064)
			(stroke
				(width 0.1524)
				(type default)
			)
			(layer "F.SilkS")
		)
		(fp_line
			(start 0.7874 0.4064)
			(end -0.7874 0.4064)
			(stroke
				(width 0.1524)
				(type default)
			)
			(layer "F.SilkS")
		)
		(fp_line
			(start -0.7874 -0.4064)
			(end 0.7874 -0.4064)
			(stroke
				(width 0.1524)
				(type default)
			)
			(layer "F.SilkS")
		)
		(fp_line
			(start 0.7874 -0.4064)
			(end 0.7874 0.4064)
			(stroke
				(width 0.1524)
				(type default)
			)
			(layer "F.SilkS")
		)
		(fp_line
			(start -0.67945 0.3048)
			(end -0.67945 -0.305054)
			(stroke
				(width 0.1)
				(type default)
			)
			(layer "F.Fab")
		)
		(fp_line
			(start -0.12065 0.3048)
			(end -0.67945 0.3048)
			(stroke
				(width 0.1)
				(type default)
			)
			(layer "F.Fab")
		)
		(fp_line
			(start 0.120396 0.3048)
			(end 0.120396 0.2794)
			(stroke
				(width 0.1)
				(type default)
			)
			(layer "F.Fab")
		)
		(fp_line
			(start 0.67945 0.3048)
			(end 0.120396 0.3048)
			(stroke
				(width 0.1)
				(type default)
			)
			(layer "F.Fab")
		)
		(fp_line
			(start -0.12065 0.2794)
			(end -0.12065 0.3048)
			(stroke
				(width 0.1)
				(type default)
			)
			(layer "F.Fab")
		)
		(fp_line
			(start 0.120396 0.2794)
			(end -0.12065 0.2794)
			(stroke
				(width 0.1)
				(type default)
			)
			(layer "F.Fab")
		)
		(fp_line
			(start -0.12065 -0.2794)
			(end 0.12065 -0.2794)
			(stroke
				(width 0.1)
				(type default)
			)
			(layer "F.Fab")
		)
		(fp_line
			(start 0.12065 -0.2794)
			(end 0.12065 -0.3048)
			(stroke
				(width 0.1)
				(type default)
			)
			(layer "F.Fab")
		)
		(fp_line
			(start 0.12065 -0.3048)
			(end 0.67945 -0.3048)
			(stroke
				(width 0.1)
				(type default)
			)
			(layer "F.Fab")
		)
		(fp_line
			(start 0.67945 -0.3048)
			(end 0.67945 0.3048)
			(stroke
				(width 0.1)
				(type default)
			)
			(layer "F.Fab")
		)
		(fp_line
			(start -0.67945 -0.305054)
			(end -0.12065 -0.305054)
			(stroke
				(width 0.1)
				(type default)
			)
			(layer "F.Fab")
		)
		(fp_line
			(start -0.12065 -0.305054)
			(end -0.12065 -0.2794)
			(stroke
				(width 0.1)
				(type default)
			)
			(layer "F.Fab")
		)
		(pad "1" smd circle
			(at -0.40005 0 270)
			(size 0 0)
			(layers "F.Cu" "F.Mask" "F.Paste")
			(net "SW_PVCCFA_EHV_FIVRA_CPU0_BOOT1_")
		)
		(pad "2" smd circle
			(at 0.40005 0 270)
			(size 0 0)
			(layers "F.Cu" "F.Mask" "F.Paste")
			(net "SW_PVCCFA_EHV_FIVRA_CPU0_BOOTR1")
		)
	)
	(footprint ""
		(layer "F.Cu")
		(at 367.7412 -74.3458 90)
		(property "Reference" "R4702"
			(at 0 0 90)
			(layer "F.SilkS")
			(hide yes)
			(effects
				(font
					(size 1.27 1.27)
				)
			)
		)
		(property "Value" ""
			(at 0 0 90)
			(layer "F.Fab")
			(effects
				(font
					(size 1.27 1.27)
				)
			)
		)
		(duplicate_pad_numbers_are_jumpers no)
		(fp_line
			(start 0.7874 -0.4064)
			(end 0.7874 0.4064)
			(stroke
				(width 0.1524)
				(type default)
			)
			(layer "F.SilkS")
		)
		(fp_line
			(start -0.7874 -0.4064)
			(end 0.7874 -0.4064)
			(stroke
				(width 0.1524)
				(type default)
			)
			(layer "F.SilkS")
		)
		(fp_line
			(start 0.7874 0.4064)
			(end -0.7874 0.4064)
			(stroke
				(width 0.1524)
				(type default)
			)
			(layer "F.SilkS")
		)
		(fp_line
			(start -0.7874 0.4064)
			(end -0.7874 -0.4064)
			(stroke
				(width 0.1524)
				(type default)
			)
			(layer "F.SilkS")
		)
		(fp_line
			(start -0.12065 -0.305054)
			(end -0.12065 -0.2794)
			(stroke
				(width 0.1)
				(type default)
			)
			(layer "F.Fab")
		)
		(fp_line
			(start -0.67945 -0.305054)
			(end -0.12065 -0.305054)
			(stroke
				(width 0.1)
				(type default)
			)
			(layer "F.Fab")
		)
		(fp_line
			(start 0.67945 -0.3048)
			(end 0.67945 0.3048)
			(stroke
				(width 0.1)
				(type default)
			)
			(layer "F.Fab")
		)
		(fp_line
			(start 0.12065 -0.3048)
			(end 0.67945 -0.3048)
			(stroke
				(width 0.1)
				(type default)
			)
			(layer "F.Fab")
		)
		(fp_line
			(start 0.12065 -0.2794)
			(end 0.12065 -0.3048)
			(stroke
				(width 0.1)
				(type default)
			)
			(layer "F.Fab")
		)
		(fp_line
			(start -0.12065 -0.2794)
			(end 0.12065 -0.2794)
			(stroke
				(width 0.1)
				(type default)
			)
			(layer "F.Fab")
		)
		(fp_line
			(start 0.120396 0.2794)
			(end -0.12065 0.2794)
			(stroke
				(width 0.1)
				(type default)
			)
			(layer "F.Fab")
		)
		(fp_line
			(start -0.12065 0.2794)
			(end -0.12065 0.3048)
			(stroke
				(width 0.1)
				(type default)
			)
			(layer "F.Fab")
		)
		(fp_line
			(start 0.67945 0.3048)
			(end 0.120396 0.3048)
			(stroke
				(width 0.1)
				(type default)
			)
			(layer "F.Fab")
		)
		(fp_line
			(start 0.120396 0.3048)
			(end 0.120396 0.2794)
			(stroke
				(width 0.1)
				(type default)
			)
			(layer "F.Fab")
		)
		(fp_line
			(start -0.12065 0.3048)
			(end -0.67945 0.3048)
			(stroke
				(width 0.1)
				(type default)
			)
			(layer "F.Fab")
		)
		(fp_line
			(start -0.67945 0.3048)
			(end -0.67945 -0.305054)
			(stroke
				(width 0.1)
				(type default)
			)
			(layer "F.Fab")
		)
		(pad "1" smd circle
			(at -0.40005 0 90)
			(size 0 0)
			(layers "F.Cu" "F.Mask" "F.Paste")
			(net "LED_P12V_AUX_R1")
		)
		(pad "2" smd circle
			(at 0.40005 0 90)
			(size 0 0)
			(layers "F.Cu" "F.Mask" "F.Paste")
			(net "LED_P12V_AUX_R2")
		)
	)
	(footprint ""
		(layer "F.Cu")
		(at 88.451182 -180.33873)
		(property "Reference" "R4261"
			(at 0 0 0)
			(layer "F.SilkS")
			(hide yes)
			(effects
				(font
					(size 1.27 1.27)
				)
			)
		)
		(property "Value" ""
			(at 0 0 0)
			(layer "F.Fab")
			(effects
				(font
					(size 1.27 1.27)
				)
			)
		)
		(duplicate_pad_numbers_are_jumpers no)
		(fp_line
			(start -0.7874 -0.4064)
			(end 0.7874 -0.4064)
			(stroke
				(width 0.1524)
				(type default)
			)
			(layer "F.SilkS")
		)
		(fp_line
			(start -0.7874 0.4064)
			(end -0.7874 -0.4064)
			(stroke
				(width 0.1524)
				(type default)
			)
			(layer "F.SilkS")
		)
		(fp_line
			(start 0.7874 -0.4064)
			(end 0.7874 0.4064)
			(stroke
				(width 0.1524)
				(type default)
			)
			(layer "F.SilkS")
		)
		(fp_line
			(start 0.7874 0.4064)
			(end -0.7874 0.4064)
			(stroke
				(width 0.1524)
				(type default)
			)
			(layer "F.SilkS")
		)
		(fp_line
			(start -0.67945 -0.305054)
			(end -0.12065 -0.305054)
			(stroke
				(width 0.1)
				(type default)
			)
			(layer "F.Fab")
		)
		(fp_line
			(start -0.67945 0.3048)
			(end -0.67945 -0.305054)
			(stroke
				(width 0.1)
				(type default)
			)
			(layer "F.Fab")
		)
		(fp_line
			(start -0.12065 -0.305054)
			(end -0.12065 -0.2794)
			(stroke
				(width 0.1)
				(type default)
			)
			(layer "F.Fab")
		)
		(fp_line
			(start -0.12065 -0.2794)
			(end 0.12065 -0.2794)
			(stroke
				(width 0.1)
				(type default)
			)
			(layer "F.Fab")
		)
		(fp_line
			(start -0.12065 0.2794)
			(end -0.12065 0.3048)
			(stroke
				(width 0.1)
				(type default)
			)
			(layer "F.Fab")
		)
		(fp_line
			(start -0.12065 0.3048)
			(end -0.67945 0.3048)
			(stroke
				(width 0.1)
				(type default)
			)
			(layer "F.Fab")
		)
		(fp_line
			(start 0.120396 0.2794)
			(end -0.12065 0.2794)
			(stroke
				(width 0.1)
				(type default)
			)
			(layer "F.Fab")
		)
		(fp_line
			(start 0.120396 0.3048)
			(end 0.120396 0.2794)
			(stroke
				(width 0.1)
				(type default)
			)
			(layer "F.Fab")
		)
		(fp_line
			(start 0.12065 -0.3048)
			(end 0.67945 -0.3048)
			(stroke
				(width 0.1)
				(type default)
			)
			(layer "F.Fab")
		)
		(fp_line
			(start 0.12065 -0.2794)
			(end 0.12065 -0.3048)
			(stroke
				(width 0.1)
				(type default)
			)
			(layer "F.Fab")
		)
		(fp_line
			(start 0.67945 -0.3048)
			(end 0.67945 0.3048)
			(stroke
				(width 0.1)
				(type default)
			)
			(layer "F.Fab")
		)
		(fp_line
			(start 0.67945 0.3048)
			(end 0.120396 0.3048)
			(stroke
				(width 0.1)
				(type default)
			)
			(layer "F.Fab")
		)
		(pad "1" smd circle
			(at -0.40005 0)
			(size 0 0)
			(layers "F.Cu" "F.Mask" "F.Paste")
			(net "PD_CPU1_BIST_ENABLE")
		)
		(pad "2" smd circle
			(at 0.40005 0)
			(size 0 0)
			(layers "F.Cu" "F.Mask" "F.Paste")
			(net "GND")
		)
	)
	(footprint ""
		(layer "F.Cu")
		(at 14.265402 -105.537762 90)
		(property "Reference" "R4419"
			(at 0 0 90)
			(layer "F.SilkS")
			(hide yes)
			(effects
				(font
					(size 1.27 1.27)
				)
			)
		)
		(property "Value" ""
			(at 0 0 90)
			(layer "F.Fab")
			(effects
				(font
					(size 1.27 1.27)
				)
			)
		)
		(duplicate_pad_numbers_are_jumpers no)
		(fp_line
			(start 0.7874 -0.4064)
			(end 0.7874 0.4064)
			(stroke
				(width 0.1524)
				(type default)
			)
			(layer "F.SilkS")
		)
		(fp_line
			(start -0.7874 -0.4064)
			(end 0.7874 -0.4064)
			(stroke
				(width 0.1524)
				(type default)
			)
			(layer "F.SilkS")
		)
		(fp_line
			(start 0.7874 0.4064)
			(end 0.004318 0.4064)
			(stroke
				(width 0.1524)
				(type default)
			)
			(layer "F.SilkS")
		)
		(fp_line
			(start -0.7874 0.4064)
			(end -0.7874 -0.4064)
			(stroke
				(width 0.1524)
				(type default)
			)
			(layer "F.SilkS")
		)
		(fp_line
			(start -0.12065 -0.305054)
			(end -0.12065 -0.2794)
			(stroke
				(width 0.1)
				(type default)
			)
			(layer "F.Fab")
		)
		(fp_line
			(start -0.67945 -0.305054)
			(end -0.12065 -0.305054)
			(stroke
				(width 0.1)
				(type default)
			)
			(layer "F.Fab")
		)
		(fp_line
			(start 0.67945 -0.3048)
			(end 0.67945 0.3048)
			(stroke
				(width 0.1)
				(type default)
			)
			(layer "F.Fab")
		)
		(fp_line
			(start 0.12065 -0.3048)
			(end 0.67945 -0.3048)
			(stroke
				(width 0.1)
				(type default)
			)
			(layer "F.Fab")
		)
		(fp_line
			(start 0.12065 -0.2794)
			(end 0.12065 -0.3048)
			(stroke
				(width 0.1)
				(type default)
			)
			(layer "F.Fab")
		)
		(fp_line
			(start -0.12065 -0.2794)
			(end 0.12065 -0.2794)
			(stroke
				(width 0.1)
				(type default)
			)
			(layer "F.Fab")
		)
		(fp_line
			(start 0.120396 0.2794)
			(end -0.12065 0.2794)
			(stroke
				(width 0.1)
				(type default)
			)
			(layer "F.Fab")
		)
		(fp_line
			(start -0.12065 0.2794)
			(end -0.12065 0.3048)
			(stroke
				(width 0.1)
				(type default)
			)
			(layer "F.Fab")
		)
		(fp_line
			(start 0.67945 0.3048)
			(end 0.120396 0.3048)
			(stroke
				(width 0.1)
				(type default)
			)
			(layer "F.Fab")
		)
		(fp_line
			(start 0.120396 0.3048)
			(end 0.120396 0.2794)
			(stroke
				(width 0.1)
				(type default)
			)
			(layer "F.Fab")
		)
		(fp_line
			(start -0.12065 0.3048)
			(end -0.67945 0.3048)
			(stroke
				(width 0.1)
				(type default)
			)
			(layer "F.Fab")
		)
		(fp_line
			(start -0.67945 0.3048)
			(end -0.67945 -0.305054)
			(stroke
				(width 0.1)
				(type default)
			)
			(layer "F.Fab")
		)
		(pad "1" smd circle
			(at -0.40005 0 90)
			(size 0 0)
			(layers "F.Cu" "F.Mask" "F.Paste")
			(net "USB2_HOST_BMC_B_DP")
		)
		(pad "2" smd circle
			(at 0.40005 0 90)
			(size 0 0)
			(layers "F.Cu" "F.Mask" "F.Paste")
			(net "GND")
		)
	)
	(footprint ""
		(layer "F.Cu")
		(at 126.01448 -96.258126 -90)
		(property "Reference" "Q139"
			(at -4.103624 0.79248 0)
			(unlocked yes)
			(layer "F.SilkS")
			(effects
				(font
					(size 0.635 0.4064)
					(thickness 0.1524)
				)
			)
		)
		(property "Value" ""
			(at 0 0 270)
			(layer "F.Fab")
			(effects
				(font
					(size 1.27 1.27)
				)
			)
		)
		(duplicate_pad_numbers_are_jumpers no)
		(fp_line
			(start -1.376172 1.199896)
			(end -1.376172 -1.199896)
			(stroke
				(width 0.1524)
				(type default)
			)
			(layer "F.SilkS")
		)
		(fp_line
			(start 1.376172 1.199896)
			(end -1.376172 1.199896)
			(stroke
				(width 0.1524)
				(type default)
			)
			(layer "F.SilkS")
		)
		(fp_line
			(start 0 -0.762)
			(end 0.508 -1.199896)
			(stroke
				(width 0.1524)
				(type default)
			)
			(layer "F.SilkS")
		)
		(fp_line
			(start -1.376172 -1.199896)
			(end -0.508 -1.199896)
			(stroke
				(width 0.1524)
				(type default)
			)
			(layer "F.SilkS")
		)
		(fp_line
			(start -0.508 -1.199896)
			(end 0 -0.762)
			(stroke
				(width 0.1524)
				(type default)
			)
			(layer "F.SilkS")
		)
		(fp_line
			(start 0.508 -1.199896)
			(end 1.376172 -1.199896)
			(stroke
				(width 0.1524)
				(type default)
			)
			(layer "F.SilkS")
		)
		(fp_line
			(start 1.376172 -1.199896)
			(end 1.376172 1.199896)
			(stroke
				(width 0.1524)
				(type default)
			)
			(layer "F.SilkS")
		)
		(fp_poly
			(pts
				(xy -1.5875 -0.7493) (xy -2.3495 -1.1303) (xy -2.3495 -0.3683)
			)
			(stroke
				(width 0)
				(type default)
			)
			(fill yes)
			(layer "F.SilkS")
		)
		(fp_line
			(start -0.674878 1.100074)
			(end -0.674878 -1.100074)
			(stroke
				(width 0.1)
				(type default)
			)
			(layer "F.Fab")
		)
		(fp_line
			(start 0.674878 1.100074)
			(end -0.674878 1.100074)
			(stroke
				(width 0.1)
				(type default)
			)
			(layer "F.Fab")
		)
		(fp_line
			(start -0.674878 -1.100074)
			(end 0.674878 -1.100074)
			(stroke
				(width 0.1)
				(type default)
			)
			(layer "F.Fab")
		)
		(fp_line
			(start 0.674878 -1.100074)
			(end 0.674878 1.100074)
			(stroke
				(width 0.1)
				(type default)
			)
			(layer "F.Fab")
		)
		(fp_poly
			(pts
				(xy -1.4605 -0.7493) (xy -2.2225 -1.1303) (xy -2.2225 -0.3683)
			)
			(stroke
				(width 0)
				(type default)
			)
			(fill yes)
			(layer "F.Fab")
		)
		(pad "1" smd rect
			(at -0.899922 -0.750062 180)
			(size 0.6096 0.6096)
			(layers "F.Cu" "F.Mask" "F.Paste")
			(net "GND")
		)
		(pad "2" smd rect
			(at -0.899922 0 180)
			(size 0.4064 0.6096)
			(layers "F.Cu" "F.Mask" "F.Paste")
			(net "H_CPU1_THERMTRIP_R_N")
		)
		(pad "3" smd rect
			(at -0.899922 0.750062 180)
			(size 0.6096 0.6096)
			(layers "F.Cu" "F.Mask" "F.Paste")
			(net "H_CPU1_THERMTRIP_N")
		)
		(pad "4" smd rect
			(at 0.899922 0.750062 180)
			(size 0.6096 0.6096)
			(layers "F.Cu" "F.Mask" "F.Paste")
			(net "PVNN_TERM_CPU1")
		)
		(pad "5" smd rect
			(at 0.899922 0 180)
			(size 0.4064 0.6096)
			(layers "F.Cu" "F.Mask" "F.Paste")
			(net "H_CPU1_THERMTRIP_VT_R_N")
		)
		(pad "6" smd rect
			(at 0.899922 -0.750062 180)
			(size 0.6096 0.6096)
			(layers "F.Cu" "F.Mask" "F.Paste")
			(net "H_CPU1_THERMTRIP_VT_N")
		)
	)
	(footprint ""
		(layer "F.Cu")
		(at 416.097974 -167.25265 180)
		(property "Reference" "PC189_P0_1"
			(at 0 0 180)
			(layer "F.SilkS")
			(hide yes)
			(effects
				(font
					(size 1.27 1.27)
				)
			)
		)
		(property "Value" ""
			(at 0 0 180)
			(layer "F.Fab")
			(effects
				(font
					(size 1.27 1.27)
				)
			)
		)
		(duplicate_pad_numbers_are_jumpers no)
		(fp_line
			(start 0.7874 0.4064)
			(end -0.7874 0.4064)
			(stroke
				(width 0.1524)
				(type default)
			)
			(layer "F.SilkS")
		)
		(fp_line
			(start 0.7874 -0.4064)
			(end 0.7874 0.4064)
			(stroke
				(width 0.1524)
				(type default)
			)
			(layer "F.SilkS")
		)
		(fp_line
			(start -0.7874 0.4064)
			(end -0.7874 -0.4064)
			(stroke
				(width 0.1524)
				(type default)
			)
			(layer "F.SilkS")
		)
		(fp_line
			(start -0.7874 -0.4064)
			(end 0.7874 -0.4064)
			(stroke
				(width 0.1524)
				(type default)
			)
			(layer "F.SilkS")
		)
		(fp_line
			(start 0.67945 0.3048)
			(end 0.120396 0.3048)
			(stroke
				(width 0.1)
				(type default)
			)
			(layer "F.Fab")
		)
		(fp_line
			(start 0.67945 -0.3048)
			(end 0.67945 0.3048)
			(stroke
				(width 0.1)
				(type default)
			)
			(layer "F.Fab")
		)
		(fp_line
			(start 0.12065 -0.2794)
			(end 0.12065 -0.3048)
			(stroke
				(width 0.1)
				(type default)
			)
			(layer "F.Fab")
		)
		(fp_line
			(start 0.12065 -0.3048)
			(end 0.67945 -0.3048)
			(stroke
				(width 0.1)
				(type default)
			)
			(layer "F.Fab")
		)
		(fp_line
			(start 0.120396 0.3048)
			(end 0.120396 0.2794)
			(stroke
				(width 0.1)
				(type default)
			)
			(layer "F.Fab")
		)
		(fp_line
			(start 0.120396 0.2794)
			(end -0.12065 0.2794)
			(stroke
				(width 0.1)
				(type default)
			)
			(layer "F.Fab")
		)
		(fp_line
			(start -0.12065 0.3048)
			(end -0.67945 0.3048)
			(stroke
				(width 0.1)
				(type default)
			)
			(layer "F.Fab")
		)
		(fp_line
			(start -0.12065 0.2794)
			(end -0.12065 0.3048)
			(stroke
				(width 0.1)
				(type default)
			)
			(layer "F.Fab")
		)
		(fp_line
			(start -0.12065 -0.2794)
			(end 0.12065 -0.2794)
			(stroke
				(width 0.1)
				(type default)
			)
			(layer "F.Fab")
		)
		(fp_line
			(start -0.12065 -0.305054)
			(end -0.12065 -0.2794)
			(stroke
				(width 0.1)
				(type default)
			)
			(layer "F.Fab")
		)
		(fp_line
			(start -0.67945 0.3048)
			(end -0.67945 -0.305054)
			(stroke
				(width 0.1)
				(type default)
			)
			(layer "F.Fab")
		)
		(fp_line
			(start -0.67945 -0.305054)
			(end -0.12065 -0.305054)
			(stroke
				(width 0.1)
				(type default)
			)
			(layer "F.Fab")
		)
		(pad "1" smd circle
			(at -0.40005 0 180)
			(size 0 0)
			(layers "F.Cu" "F.Mask" "F.Paste")
			(net "SW_P12V_PVCCINFAON_CPU0_FLT")
		)
		(pad "2" smd circle
			(at 0.40005 0 180)
			(size 0 0)
			(layers "F.Cu" "F.Mask" "F.Paste")
			(net "GND")
		)
	)
	(footprint ""
		(layer "F.Cu")
		(at 157.135576 -37.790374 -90)
		(property "Reference" "U313"
			(at -3.6957 -3.129534 0)
			(unlocked yes)
			(layer "F.SilkS")
			(effects
				(font
					(size 0.7874 0.5842)
					(thickness 0.1524)
				)
				(justify left)
			)
		)
		(property "Value" ""
			(at 0 0 270)
			(layer "F.Fab")
			(effects
				(font
					(size 1.27 1.27)
				)
			)
		)
		(duplicate_pad_numbers_are_jumpers no)
		(fp_line
			(start -0.508 2.921)
			(end -0.508 3.683)
			(stroke
				(width 0.1524)
				(type default)
			)
			(layer "F.SilkS")
		)
		(fp_line
			(start -2.500122 2.500122)
			(end -2.500122 1.778)
			(stroke
				(width 0.1524)
				(type default)
			)
			(layer "F.SilkS")
		)
		(fp_line
			(start -1.778 2.500122)
			(end -2.500122 2.500122)
			(stroke
				(width 0.1524)
				(type default)
			)
			(layer "F.SilkS")
		)
		(fp_line
			(start 2.500122 2.500122)
			(end 1.778 2.500122)
			(stroke
				(width 0.1524)
				(type default)
			)
			(layer "F.SilkS")
		)
		(fp_line
			(start 2.500122 1.778)
			(end 2.500122 2.500122)
			(stroke
				(width 0.1524)
				(type default)
			)
			(layer "F.SilkS")
		)
		(fp_line
			(start 2.921 1.524)
			(end 3.302 1.524)
			(stroke
				(width 0.1524)
				(type default)
			)
			(layer "F.SilkS")
		)
		(fp_line
			(start -2.921 0.508)
			(end -3.302 0.508)
			(stroke
				(width 0.1524)
				(type default)
			)
			(layer "F.SilkS")
		)
		(fp_line
			(start 2.921 -1.016)
			(end 3.683 -1.016)
			(stroke
				(width 0.1524)
				(type default)
			)
			(layer "F.SilkS")
		)
		(fp_line
			(start -2.500122 -1.778)
			(end -2.500122 -2.500122)
			(stroke
				(width 0.1524)
				(type default)
			)
			(layer "F.SilkS")
		)
		(fp_line
			(start -2.500122 -2.500122)
			(end -1.778 -2.500122)
			(stroke
				(width 0.1524)
				(type default)
			)
			(layer "F.SilkS")
		)
		(fp_line
			(start 1.778 -2.500122)
			(end 2.500122 -2.500122)
			(stroke
				(width 0.1524)
				(type default)
			)
			(layer "F.SilkS")
		)
		(fp_line
			(start 2.500122 -2.500122)
			(end 2.500122 -1.778)
			(stroke
				(width 0.1524)
				(type default)
			)
			(layer "F.SilkS")
		)
		(fp_line
			(start 0 -2.921)
			(end 0 -3.302)
			(stroke
				(width 0.1524)
				(type default)
			)
			(layer "F.SilkS")
		)
		(fp_poly
			(pts
				(xy -2.72288 -2.24282) (xy -3.642106 -2.549144) (xy -3.029458 -3.161792)
			)
			(stroke
				(width 0)
				(type default)
			)
			(fill yes)
			(layer "F.SilkS")
		)
		(fp_line
			(start -0.508 2.921)
			(end -0.508 3.683)
			(stroke
				(width 0.1)
				(type default)
			)
			(layer "F.Fab")
		)
		(fp_line
			(start -2.500122 2.500122)
			(end -2.500122 -2.500122)
			(stroke
				(width 0.1)
				(type default)
			)
			(layer "F.Fab")
		)
		(fp_line
			(start 2.500122 2.500122)
			(end -2.500122 2.500122)
			(stroke
				(width 0.1)
				(type default)
			)
			(layer "F.Fab")
		)
		(fp_line
			(start 2.921 1.524)
			(end 3.302 1.524)
			(stroke
				(width 0.1)
				(type default)
			)
			(layer "F.Fab")
		)
		(fp_line
			(start -2.921 0.508)
			(end -3.302 0.508)
			(stroke
				(width 0.1)
				(type default)
			)
			(layer "F.Fab")
		)
		(fp_line
			(start 2.921 -1.016)
			(end 3.683 -1.016)
			(stroke
				(width 0.1)
				(type default)
			)
			(layer "F.Fab")
		)
		(fp_line
			(start -2.500122 -2.500122)
			(end 2.500122 -2.500122)
			(stroke
				(width 0.1)
				(type default)
			)
			(layer "F.Fab")
		)
		(fp_line
			(start 2.500122 -2.500122)
			(end 2.500122 2.500122)
			(stroke
				(width 0.1)
				(type default)
			)
			(layer "F.Fab")
		)
		(fp_line
			(start 0 -2.921)
			(end 0 -3.302)
			(stroke
				(width 0.1)
				(type default)
			)
			(layer "F.Fab")
		)
		(fp_poly
			(pts
				(xy -3.7592 -1.933194) (xy -2.892806 -1.500124) (xy -3.7592 -1.0668)
			)
			(stroke
				(width 0)
				(type default)
			)
			(fill yes)
			(layer "F.Fab")
		)
		(fp_text user "14"
			(at 1.507236 3.879596 0)
			(unlocked yes)
			(layer "F.SilkS")
			(effects
				(font
					(size 0.635 0.4064)
					(thickness 0.1524)
				)
			)
		)
		(fp_text user "8"
			(at -3.080004 2.513076 0)
			(unlocked yes)
			(layer "F.SilkS")
			(effects
				(font
					(size 0.635 0.4064)
					(thickness 0.1524)
				)
			)
		)
		(fp_text user "15"
			(at 3.253232 2.2352 0)
			(unlocked yes)
			(layer "F.SilkS")
			(effects
				(font
					(size 0.635 0.4064)
					(thickness 0.1524)
				)
			)
		)
		(fp_text user "7"
			(at -3.147568 1.8034 0)
			(unlocked yes)
			(layer "F.SilkS")
			(effects
				(font
					(size 0.635 0.4064)
					(thickness 0.1524)
				)
			)
		)
		(fp_text user "21"
			(at 3.291332 -1.75768 0)
			(unlocked yes)
			(layer "F.SilkS")
			(effects
				(font
					(size 0.635 0.4064)
					(thickness 0.1524)
				)
			)
		)
		(fp_text user "28"
			(at -2.091944 -3.461004 0)
			(unlocked yes)
			(layer "F.SilkS")
			(effects
				(font
					(size 0.635 0.4064)
					(thickness 0.1524)
				)
			)
		)
		(fp_text user "22"
			(at 2.942336 -3.930904 0)
			(unlocked yes)
			(layer "F.SilkS")
			(effects
				(font
					(size 0.635 0.4064)
					(thickness 0.1524)
				)
			)
		)
		(fp_text user "8"
			(at -1.8796 3.253232 270)
			(unlocked yes)
			(layer "F.Fab")
			(effects
				(font
					(size 0.635 0.4064)
					(thickness 0.1524)
				)
			)
		)
		(fp_text user "14"
			(at 2.1336 3.253232 270)
			(unlocked yes)
			(layer "F.Fab")
			(effects
				(font
					(size 0.635 0.4064)
					(thickness 0.1524)
				)
			)
		)
		(fp_text user "15"
			(at 3.253232 2.2352 0)
			(unlocked yes)
			(layer "F.Fab")
			(effects
				(font
					(size 0.635 0.4064)
					(thickness 0.1524)
				)
			)
		)
		(fp_text user "7"
			(at -3.147568 1.8034 0)
			(unlocked yes)
			(layer "F.Fab")
			(effects
				(font
					(size 0.635 0.4064)
					(thickness 0.1524)
				)
			)
		)
		(fp_text user "21"
			(at 3.227832 -2.2606 0)
			(unlocked yes)
			(layer "F.Fab")
			(effects
				(font
					(size 0.635 0.4064)
					(thickness 0.1524)
				)
			)
		)
		(fp_text user "28"
			(at -2.2098 -3.172968 270)
			(unlocked yes)
			(layer "F.Fab")
			(effects
				(font
					(size 0.635 0.4064)
					(thickness 0.1524)
				)
			)
		)
		(fp_text user "22"
			(at 2.2352 -3.172968 270)
			(unlocked yes)
			(layer "F.Fab")
			(effects
				(font
					(size 0.635 0.4064)
					(thickness 0.1524)
				)
			)
		)
		(pad "1" smd rect
			(at -2.412492 -1.500124)
			(size 0.254 0.7366)
			(layers "F.Cu" "F.Mask" "F.Paste")
			(net "USB2_PCH_0_R_DN")
		)
		(pad "2" smd rect
			(at -2.412492 -0.999998)
			(size 0.254 0.7366)
			(layers "F.Cu" "F.Mask" "F.Paste")
			(net "USB2_PCH_0_R_DP")
		)
		(pad "3" smd rect
			(at -2.412492 -0.499872)
			(size 0.254 0.7366)
			(layers "F.Cu" "F.Mask" "F.Paste")
			(net "USB2_HUB_2_EXT_DN")
		)
		(pad "4" smd rect
			(at -2.412492 0)
			(size 0.254 0.7366)
			(layers "F.Cu" "F.Mask" "F.Paste")
			(net "USB2_HUB_2_EXT_DP")
		)
		(pad "5" smd rect
			(at -2.412492 0.499872)
			(size 0.254 0.7366)
			(layers "F.Cu" "F.Mask" "F.Paste")
			(net "P3V3_AUX_USB_HUB_2")
		)
		(pad "6" smd rect
			(at -2.412492 0.999998)
			(size 0.254 0.7366)
			(layers "F.Cu" "F.Mask" "F.Paste")
			(net "NC_USB_HUB_2_DM2")
		)
		(pad "7" smd rect
			(at -2.412492 1.500124)
			(size 0.254 0.7366)
			(layers "F.Cu" "F.Mask" "F.Paste")
			(net "NC_USB_HUB_2_DP2")
		)
		(pad "8" smd rect
			(at -1.500124 2.412492 270)
			(size 0.254 0.7366)
			(layers "F.Cu" "F.Mask" "F.Paste")
			(net "USB_HUB_2_RREF")
		)
		(pad "9" smd rect
			(at -0.999998 2.412492 270)
			(size 0.254 0.7366)
			(layers "F.Cu" "F.Mask" "F.Paste")
			(net "P3V3_AUX_USB_HUB_2")
		)
		(pad "10" smd rect
			(at -0.499872 2.412492 270)
			(size 0.254 0.7366)
			(layers "F.Cu" "F.Mask" "F.Paste")
			(net "USB_HUB_2_XTAL_IN")
		)
		(pad "11" smd rect
			(at 0 2.412492 270)
			(size 0.254 0.7366)
			(layers "F.Cu" "F.Mask" "F.Paste")
			(net "USB_HUB_2_XTAL_OUT")
		)
		(pad "12" smd rect
			(at 0.499872 2.412492 270)
			(size 0.254 0.7366)
			(layers "F.Cu" "F.Mask" "F.Paste")
			(net "NC_USB_HUB_2_DM3")
		)
		(pad "13" smd rect
			(at 0.999998 2.412492 270)
			(size 0.254 0.7366)
			(layers "F.Cu" "F.Mask" "F.Paste")
			(net "NC_USB_HUB_2_DP3")
		)
		(pad "14" smd rect
			(at 1.500124 2.412492 270)
			(size 0.254 0.7366)
			(layers "F.Cu" "F.Mask" "F.Paste")
			(net "P3V3_AUX_USB_HUB_2")
		)
		(pad "15" smd rect
			(at 2.412492 1.500124)
			(size 0.254 0.7366)
			(layers "F.Cu" "F.Mask" "F.Paste")
			(net "NC_USB_HUB_2_DM4")
		)
		(pad "16" smd rect
			(at 2.412492 0.999998)
			(size 0.254 0.7366)
			(layers "F.Cu" "F.Mask" "F.Paste")
			(net "NC_USB_HUB_2_DP4")
		)
		(pad "17" smd rect
			(at 2.412492 0.499872)
			(size 0.254 0.7366)
			(layers "F.Cu" "F.Mask" "F.Paste")
			(net "RST_USB_HUB_2_R_N")
		)
		(pad "18" smd rect
			(at 2.412492 0)
			(size 0.254 0.7366)
			(layers "F.Cu" "F.Mask" "F.Paste")
			(net "USB_HUB_2_TEST")
		)
		(pad "19" smd rect
			(at 2.412492 -0.499872)
			(size 0.254 0.7366)
			(layers "F.Cu" "F.Mask" "F.Paste")
			(net "USB_HUB_2_OVCUR4")
		)
		(pad "20" smd rect
			(at 2.412492 -0.999998)
			(size 0.254 0.7366)
			(layers "F.Cu" "F.Mask" "F.Paste")
			(net "USB_HUB_2_OVCUR3")
		)
		(pad "21" smd rect
			(at 2.412492 -1.500124)
			(size 0.254 0.7366)
			(layers "F.Cu" "F.Mask" "F.Paste")
			(net "USB_HUB_2_DVDD")
		)
		(pad "22" smd rect
			(at 1.500124 -2.412492 270)
			(size 0.254 0.7366)
			(layers "F.Cu" "F.Mask" "F.Paste")
			(net "USB_HUB_2_PSELF")
		)
		(pad "23" smd rect
			(at 0.999998 -2.412492 270)
			(size 0.254 0.7366)
			(layers "F.Cu" "F.Mask" "F.Paste")
			(net "USB_HUB_2_PGANG")
		)
		(pad "24" smd rect
			(at 0.499872 -2.412492 270)
			(size 0.254 0.7366)
			(layers "F.Cu" "F.Mask" "F.Paste")
			(net "USB_HUB_2_OVCUR2")
		)
		(pad "25" smd rect
			(at 0 -2.412492 270)
			(size 0.254 0.7366)
			(layers "F.Cu" "F.Mask" "F.Paste")
			(net "USB_HUB_2_OVCUR1")
		)
		(pad "26" smd rect
			(at -0.499872 -2.412492 270)
			(size 0.254 0.7366)
			(layers "F.Cu" "F.Mask" "F.Paste")
			(net "NC_USB_HUB_2_SDA")
		)
		(pad "27" smd rect
			(at -0.999998 -2.412492 270)
			(size 0.254 0.7366)
			(layers "F.Cu" "F.Mask" "F.Paste")
			(net "P3V3_AUX_USB_HUB_2")
		)
		(pad "28" smd rect
			(at -1.500124 -2.412492 270)
			(size 0.254 0.7366)
			(layers "F.Cu" "F.Mask" "F.Paste")
			(net "P3V3_AUX_USB_HUB_2")
		)
		(pad "TH" smd rect
			(at 0 0 270)
			(size 3.556 3.556)
			(layers "F.Cu" "F.Mask" "F.Paste")
			(net "GND")
		)
		(zone
			(layer "F.Cu")
			(hatch none 0.5)
			(connect_pads
				(clearance 0)
			)
			(min_thickness 0.25)
			(keepout
				(tracks not_allowed)
				(vias allowed)
				(pads allowed)
				(copperpour not_allowed)
				(footprints allowed)
			)
			(placement
				(enabled no)
				(sheetname "")
			)
			(fill
				(thermal_gap 0.5)
				(thermal_bridge_width 0.5)
				(island_removal_mode 0)
			)
			(polygon
				(pts
					(xy 159.116776 -36.850574) (xy 158.964376 -36.850574) (xy 158.964376 -39.619174) (xy 155.306776 -39.619174)
					(xy 155.306776 -35.961574) (xy 158.964376 -35.961574) (xy 158.964376 -36.825174) (xy 159.116776 -36.825174)
					(xy 159.116776 -35.809174) (xy 155.154376 -35.809174) (xy 155.154376 -39.771574) (xy 159.116776 -39.771574)
				)
			)
		)
	)
	(footprint ""
		(layer "F.Cu")
		(at 118.542816 -247.715278 90)
		(property "Reference" "C249"
			(at 0 0 90)
			(layer "F.SilkS")
			(hide yes)
			(effects
				(font
					(size 1.27 1.27)
				)
			)
		)
		(property "Value" ""
			(at 0 0 90)
			(layer "F.Fab")
			(effects
				(font
					(size 1.27 1.27)
				)
			)
		)
		(duplicate_pad_numbers_are_jumpers no)
		(fp_line
			(start 0.7874 -0.4064)
			(end 0.7874 0.4064)
			(stroke
				(width 0.1524)
				(type default)
			)
			(layer "F.SilkS")
		)
		(fp_line
			(start -0.7874 -0.4064)
			(end 0.7874 -0.4064)
			(stroke
				(width 0.1524)
				(type default)
			)
			(layer "F.SilkS")
		)
		(fp_line
			(start 0.7874 0.4064)
			(end -0.7874 0.4064)
			(stroke
				(width 0.1524)
				(type default)
			)
			(layer "F.SilkS")
		)
		(fp_line
			(start -0.7874 0.4064)
			(end -0.7874 -0.4064)
			(stroke
				(width 0.1524)
				(type default)
			)
			(layer "F.SilkS")
		)
		(fp_line
			(start -0.12065 -0.305054)
			(end -0.12065 -0.2794)
			(stroke
				(width 0.1)
				(type default)
			)
			(layer "F.Fab")
		)
		(fp_line
			(start -0.67945 -0.305054)
			(end -0.12065 -0.305054)
			(stroke
				(width 0.1)
				(type default)
			)
			(layer "F.Fab")
		)
		(fp_line
			(start 0.67945 -0.3048)
			(end 0.67945 0.3048)
			(stroke
				(width 0.1)
				(type default)
			)
			(layer "F.Fab")
		)
		(fp_line
			(start 0.12065 -0.3048)
			(end 0.67945 -0.3048)
			(stroke
				(width 0.1)
				(type default)
			)
			(layer "F.Fab")
		)
		(fp_line
			(start 0.12065 -0.2794)
			(end 0.12065 -0.3048)
			(stroke
				(width 0.1)
				(type default)
			)
			(layer "F.Fab")
		)
		(fp_line
			(start -0.12065 -0.2794)
			(end 0.12065 -0.2794)
			(stroke
				(width 0.1)
				(type default)
			)
			(layer "F.Fab")
		)
		(fp_line
			(start 0.120396 0.2794)
			(end -0.12065 0.2794)
			(stroke
				(width 0.1)
				(type default)
			)
			(layer "F.Fab")
		)
		(fp_line
			(start -0.12065 0.2794)
			(end -0.12065 0.3048)
			(stroke
				(width 0.1)
				(type default)
			)
			(layer "F.Fab")
		)
		(fp_line
			(start 0.67945 0.3048)
			(end 0.120396 0.3048)
			(stroke
				(width 0.1)
				(type default)
			)
			(layer "F.Fab")
		)
		(fp_line
			(start 0.120396 0.3048)
			(end 0.120396 0.2794)
			(stroke
				(width 0.1)
				(type default)
			)
			(layer "F.Fab")
		)
		(fp_line
			(start -0.12065 0.3048)
			(end -0.67945 0.3048)
			(stroke
				(width 0.1)
				(type default)
			)
			(layer "F.Fab")
		)
		(fp_line
			(start -0.67945 0.3048)
			(end -0.67945 -0.305054)
			(stroke
				(width 0.1)
				(type default)
			)
			(layer "F.Fab")
		)
		(pad "1" smd circle
			(at -0.40005 0 90)
			(size 0 0)
			(layers "F.Cu" "F.Mask" "F.Paste")
			(net "PVCCIN_CPU1")
		)
		(pad "2" smd circle
			(at 0.40005 0 90)
			(size 0 0)
			(layers "F.Cu" "F.Mask" "F.Paste")
			(net "GND")
		)
	)
	(footprint ""
		(layer "F.Cu")
		(at 8.75919 -101.854 180)
		(property "Reference" "R3653"
			(at 0 0 180)
			(layer "F.SilkS")
			(hide yes)
			(effects
				(font
					(size 1.27 1.27)
				)
			)
		)
		(property "Value" ""
			(at 0 0 180)
			(layer "F.Fab")
			(effects
				(font
					(size 1.27 1.27)
				)
			)
		)
		(duplicate_pad_numbers_are_jumpers no)
		(fp_line
			(start 0.7874 0.4064)
			(end -0.7874 0.4064)
			(stroke
				(width 0.1524)
				(type default)
			)
			(layer "F.SilkS")
		)
		(fp_line
			(start 0.7874 -0.4064)
			(end 0.7874 0.4064)
			(stroke
				(width 0.1524)
				(type default)
			)
			(layer "F.SilkS")
		)
		(fp_line
			(start -0.7874 0.4064)
			(end -0.7874 -0.4064)
			(stroke
				(width 0.1524)
				(type default)
			)
			(layer "F.SilkS")
		)
		(fp_line
			(start -0.7874 -0.4064)
			(end 0.7874 -0.4064)
			(stroke
				(width 0.1524)
				(type default)
			)
			(layer "F.SilkS")
		)
		(fp_line
			(start 0.67945 0.3048)
			(end 0.120396 0.3048)
			(stroke
				(width 0.1)
				(type default)
			)
			(layer "F.Fab")
		)
		(fp_line
			(start 0.67945 -0.3048)
			(end 0.67945 0.3048)
			(stroke
				(width 0.1)
				(type default)
			)
			(layer "F.Fab")
		)
		(fp_line
			(start 0.12065 -0.2794)
			(end 0.12065 -0.3048)
			(stroke
				(width 0.1)
				(type default)
			)
			(layer "F.Fab")
		)
		(fp_line
			(start 0.12065 -0.3048)
			(end 0.67945 -0.3048)
			(stroke
				(width 0.1)
				(type default)
			)
			(layer "F.Fab")
		)
		(fp_line
			(start 0.120396 0.3048)
			(end 0.120396 0.2794)
			(stroke
				(width 0.1)
				(type default)
			)
			(layer "F.Fab")
		)
		(fp_line
			(start 0.120396 0.2794)
			(end -0.12065 0.2794)
			(stroke
				(width 0.1)
				(type default)
			)
			(layer "F.Fab")
		)
		(fp_line
			(start -0.12065 0.3048)
			(end -0.67945 0.3048)
			(stroke
				(width 0.1)
				(type default)
			)
			(layer "F.Fab")
		)
		(fp_line
			(start -0.12065 0.2794)
			(end -0.12065 0.3048)
			(stroke
				(width 0.1)
				(type default)
			)
			(layer "F.Fab")
		)
		(fp_line
			(start -0.12065 -0.2794)
			(end 0.12065 -0.2794)
			(stroke
				(width 0.1)
				(type default)
			)
			(layer "F.Fab")
		)
		(fp_line
			(start -0.12065 -0.305054)
			(end -0.12065 -0.2794)
			(stroke
				(width 0.1)
				(type default)
			)
			(layer "F.Fab")
		)
		(fp_line
			(start -0.67945 0.3048)
			(end -0.67945 -0.305054)
			(stroke
				(width 0.1)
				(type default)
			)
			(layer "F.Fab")
		)
		(fp_line
			(start -0.67945 -0.305054)
			(end -0.12065 -0.305054)
			(stroke
				(width 0.1)
				(type default)
			)
			(layer "F.Fab")
		)
		(pad "1" smd circle
			(at -0.40005 0 180)
			(size 0 0)
			(layers "F.Cu" "F.Mask" "F.Paste")
			(net "USB_HUB_RREF")
		)
		(pad "2" smd circle
			(at 0.40005 0 180)
			(size 0 0)
			(layers "F.Cu" "F.Mask" "F.Paste")
			(net "GND")
		)
	)
	(footprint ""
		(layer "F.Cu")
		(at 106.476038 -37.940742)
		(property "Reference" "R3188"
			(at 0 0 0)
			(layer "F.SilkS")
			(hide yes)
			(effects
				(font
					(size 1.27 1.27)
				)
			)
		)
		(property "Value" ""
			(at 0 0 0)
			(layer "F.Fab")
			(effects
				(font
					(size 1.27 1.27)
				)
			)
		)
		(duplicate_pad_numbers_are_jumpers no)
		(fp_line
			(start -0.7874 -0.4064)
			(end 0.7874 -0.4064)
			(stroke
				(width 0.1524)
				(type default)
			)
			(layer "F.SilkS")
		)
		(fp_line
			(start -0.7874 0.4064)
			(end -0.7874 -0.4064)
			(stroke
				(width 0.1524)
				(type default)
			)
			(layer "F.SilkS")
		)
		(fp_line
			(start 0.7874 -0.4064)
			(end 0.7874 0.4064)
			(stroke
				(width 0.1524)
				(type default)
			)
			(layer "F.SilkS")
		)
		(fp_line
			(start 0.7874 0.4064)
			(end -0.7874 0.4064)
			(stroke
				(width 0.1524)
				(type default)
			)
			(layer "F.SilkS")
		)
		(fp_line
			(start -0.67945 -0.305054)
			(end -0.12065 -0.305054)
			(stroke
				(width 0.1)
				(type default)
			)
			(layer "F.Fab")
		)
		(fp_line
			(start -0.67945 0.3048)
			(end -0.67945 -0.305054)
			(stroke
				(width 0.1)
				(type default)
			)
			(layer "F.Fab")
		)
		(fp_line
			(start -0.12065 -0.305054)
			(end -0.12065 -0.2794)
			(stroke
				(width 0.1)
				(type default)
			)
			(layer "F.Fab")
		)
		(fp_line
			(start -0.12065 -0.2794)
			(end 0.12065 -0.2794)
			(stroke
				(width 0.1)
				(type default)
			)
			(layer "F.Fab")
		)
		(fp_line
			(start -0.12065 0.2794)
			(end -0.12065 0.3048)
			(stroke
				(width 0.1)
				(type default)
			)
			(layer "F.Fab")
		)
		(fp_line
			(start -0.12065 0.3048)
			(end -0.67945 0.3048)
			(stroke
				(width 0.1)
				(type default)
			)
			(layer "F.Fab")
		)
		(fp_line
			(start 0.120396 0.2794)
			(end -0.12065 0.2794)
			(stroke
				(width 0.1)
				(type default)
			)
			(layer "F.Fab")
		)
		(fp_line
			(start 0.120396 0.3048)
			(end 0.120396 0.2794)
			(stroke
				(width 0.1)
				(type default)
			)
			(layer "F.Fab")
		)
		(fp_line
			(start 0.12065 -0.3048)
			(end 0.67945 -0.3048)
			(stroke
				(width 0.1)
				(type default)
			)
			(layer "F.Fab")
		)
		(fp_line
			(start 0.12065 -0.2794)
			(end 0.12065 -0.3048)
			(stroke
				(width 0.1)
				(type default)
			)
			(layer "F.Fab")
		)
		(fp_line
			(start 0.67945 -0.3048)
			(end 0.67945 0.3048)
			(stroke
				(width 0.1)
				(type default)
			)
			(layer "F.Fab")
		)
		(fp_line
			(start 0.67945 0.3048)
			(end 0.120396 0.3048)
			(stroke
				(width 0.1)
				(type default)
			)
			(layer "F.Fab")
		)
		(pad "1" smd circle
			(at -0.40005 0)
			(size 0 0)
			(layers "F.Cu" "F.Mask" "F.Paste")
			(net "RST_OCP_V3_2_BUF_N")
		)
		(pad "2" smd circle
			(at 0.40005 0)
			(size 0 0)
			(layers "F.Cu" "F.Mask" "F.Paste")
			(net "RST_PERST2_OCP_V3_2_N")
		)
	)
	(footprint ""
		(layer "F.Cu")
		(at 106.11231 -65.22212 -90)
		(property "Reference" "R3090"
			(at 0 0 270)
			(layer "F.SilkS")
			(hide yes)
			(effects
				(font
					(size 1.27 1.27)
				)
			)
		)
		(property "Value" ""
			(at 0 0 270)
			(layer "F.Fab")
			(effects
				(font
					(size 1.27 1.27)
				)
			)
		)
		(duplicate_pad_numbers_are_jumpers no)
		(fp_line
			(start -0.7874 0.4064)
			(end -0.7874 -0.4064)
			(stroke
				(width 0.1524)
				(type default)
			)
			(layer "F.SilkS")
		)
		(fp_line
			(start 0.7874 0.4064)
			(end -0.7874 0.4064)
			(stroke
				(width 0.1524)
				(type default)
			)
			(layer "F.SilkS")
		)
		(fp_line
			(start -0.7874 -0.4064)
			(end 0.7874 -0.4064)
			(stroke
				(width 0.1524)
				(type default)
			)
			(layer "F.SilkS")
		)
		(fp_line
			(start 0.7874 -0.4064)
			(end 0.7874 0.4064)
			(stroke
				(width 0.1524)
				(type default)
			)
			(layer "F.SilkS")
		)
		(fp_line
			(start -0.67945 0.3048)
			(end -0.67945 -0.305054)
			(stroke
				(width 0.1)
				(type default)
			)
			(layer "F.Fab")
		)
		(fp_line
			(start -0.12065 0.3048)
			(end -0.67945 0.3048)
			(stroke
				(width 0.1)
				(type default)
			)
			(layer "F.Fab")
		)
		(fp_line
			(start 0.120396 0.3048)
			(end 0.120396 0.2794)
			(stroke
				(width 0.1)
				(type default)
			)
			(layer "F.Fab")
		)
		(fp_line
			(start 0.67945 0.3048)
			(end 0.120396 0.3048)
			(stroke
				(width 0.1)
				(type default)
			)
			(layer "F.Fab")
		)
		(fp_line
			(start -0.12065 0.2794)
			(end -0.12065 0.3048)
			(stroke
				(width 0.1)
				(type default)
			)
			(layer "F.Fab")
		)
		(fp_line
			(start 0.120396 0.2794)
			(end -0.12065 0.2794)
			(stroke
				(width 0.1)
				(type default)
			)
			(layer "F.Fab")
		)
		(fp_line
			(start -0.12065 -0.2794)
			(end 0.12065 -0.2794)
			(stroke
				(width 0.1)
				(type default)
			)
			(layer "F.Fab")
		)
		(fp_line
			(start 0.12065 -0.2794)
			(end 0.12065 -0.3048)
			(stroke
				(width 0.1)
				(type default)
			)
			(layer "F.Fab")
		)
		(fp_line
			(start 0.12065 -0.3048)
			(end 0.67945 -0.3048)
			(stroke
				(width 0.1)
				(type default)
			)
			(layer "F.Fab")
		)
		(fp_line
			(start 0.67945 -0.3048)
			(end 0.67945 0.3048)
			(stroke
				(width 0.1)
				(type default)
			)
			(layer "F.Fab")
		)
		(fp_line
			(start -0.67945 -0.305054)
			(end -0.12065 -0.305054)
			(stroke
				(width 0.1)
				(type default)
			)
			(layer "F.Fab")
		)
		(fp_line
			(start -0.12065 -0.305054)
			(end -0.12065 -0.2794)
			(stroke
				(width 0.1)
				(type default)
			)
			(layer "F.Fab")
		)
		(pad "1" smd circle
			(at -0.40005 0 270)
			(size 0 0)
			(layers "F.Cu" "F.Mask" "F.Paste")
			(net "LED_PWRGD_PVNN_MAIN_CPU0")
		)
		(pad "2" smd circle
			(at 0.40005 0 270)
			(size 0 0)
			(layers "F.Cu" "F.Mask" "F.Paste")
			(net "P3V3_AUX")
		)
	)
	(footprint ""
		(layer "F.Cu")
		(at 440.687968 -94.077536 180)
		(property "Reference" "U266"
			(at 0.221996 2.912872 0)
			(unlocked yes)
			(layer "F.SilkS")
			(effects
				(font
					(size 0.7874 0.5842)
					(thickness 0.1524)
				)
			)
		)
		(property "Value" ""
			(at 0 0 180)
			(layer "F.Fab")
			(effects
				(font
					(size 1.27 1.27)
				)
			)
		)
		(duplicate_pad_numbers_are_jumpers no)
		(fp_line
			(start 1.500124 1.500124)
			(end 1.004062 1.500124)
			(stroke
				(width 0.1524)
				(type default)
			)
			(layer "F.SilkS")
		)
		(fp_line
			(start 1.500124 1.004062)
			(end 1.500124 1.500124)
			(stroke
				(width 0.1524)
				(type default)
			)
			(layer "F.SilkS")
		)
		(fp_line
			(start 1.500124 -1.500124)
			(end 1.500124 -1.004062)
			(stroke
				(width 0.1524)
				(type default)
			)
			(layer "F.SilkS")
		)
		(fp_line
			(start 1.004062 -1.500124)
			(end 1.500124 -1.500124)
			(stroke
				(width 0.1524)
				(type default)
			)
			(layer "F.SilkS")
		)
		(fp_line
			(start -1.004062 1.500124)
			(end -1.500124 1.500124)
			(stroke
				(width 0.1524)
				(type default)
			)
			(layer "F.SilkS")
		)
		(fp_line
			(start -1.500124 1.500124)
			(end -1.500124 1.004062)
			(stroke
				(width 0.1524)
				(type default)
			)
			(layer "F.SilkS")
		)
		(fp_line
			(start -1.500124 -1.004062)
			(end -1.500124 -1.500124)
			(stroke
				(width 0.1524)
				(type default)
			)
			(layer "F.SilkS")
		)
		(fp_line
			(start -1.500124 -1.500124)
			(end -1.004062 -1.500124)
			(stroke
				(width 0.1524)
				(type default)
			)
			(layer "F.SilkS")
		)
		(fp_poly
			(pts
				(xy -2.242312 -0.999744) (xy -1.783588 -0.770382) (xy -2.242312 -0.54102)
			)
			(stroke
				(width 0)
				(type default)
			)
			(fill yes)
			(layer "F.SilkS")
		)
		(fp_line
			(start 1.500124 1.500124)
			(end -1.500124 1.500124)
			(stroke
				(width 0.1)
				(type default)
			)
			(layer "F.Fab")
		)
		(fp_line
			(start 1.500124 -1.500124)
			(end 1.500124 1.500124)
			(stroke
				(width 0.1)
				(type default)
			)
			(layer "F.Fab")
		)
		(fp_line
			(start -1.500124 1.500124)
			(end -1.500124 -1.500124)
			(stroke
				(width 0.1)
				(type default)
			)
			(layer "F.Fab")
		)
		(fp_line
			(start -1.500124 -1.500124)
			(end 1.500124 -1.500124)
			(stroke
				(width 0.1)
				(type default)
			)
			(layer "F.Fab")
		)
		(fp_poly
			(pts
				(xy -2.847848 -1.258062) (xy -2.847848 -0.242062) (xy -1.831848 -0.750062)
			)
			(stroke
				(width 0)
				(type default)
			)
			(fill yes)
			(layer "F.Fab")
		)
		(pad "1" smd rect
			(at -1.400048 -0.750062 90)
			(size 0.2286 0.6096)
			(layers "F.Cu" "F.Mask" "F.Paste")
			(net "INA230_1_A1")
		)
		(pad "2" smd rect
			(at -1.400048 -0.249936 90)
			(size 0.2286 0.6096)
			(layers "F.Cu" "F.Mask" "F.Paste")
			(net "INA230_1_A0")
		)
		(pad "3" smd rect
			(at -1.400048 0.249936 90)
			(size 0.2286 0.6096)
			(layers "F.Cu" "F.Mask" "F.Paste")
			(net "OCP_SFF_P3V3_ADC_ALERT_R")
		)
		(pad "4" smd rect
			(at -1.400048 0.750062 90)
			(size 0.2286 0.6096)
			(layers "F.Cu" "F.Mask" "F.Paste")
			(net "SMB_INA230_1_3V3AUX_SDA_R1")
		)
		(pad "5" smd rect
			(at -0.750062 1.400048 180)
			(size 0.2286 0.6096)
			(layers "F.Cu" "F.Mask" "F.Paste")
			(net "SMB_INA230_1_3V3AUX_SCL_R1")
		)
		(pad "6" smd rect
			(at -0.249936 1.400048 180)
			(size 0.2286 0.6096)
			(layers "F.Cu" "F.Mask" "F.Paste")
			(net "NC_INA230_1_NC0")
		)
		(pad "7" smd rect
			(at 0.249936 1.400048 180)
			(size 0.2286 0.6096)
			(layers "F.Cu" "F.Mask" "F.Paste")
			(net "NC_INA230_1_NC1")
		)
		(pad "8" smd rect
			(at 0.750062 1.400048 180)
			(size 0.2286 0.6096)
			(layers "F.Cu" "F.Mask" "F.Paste")
			(net "NC_INA230_1_NC2")
		)
		(pad "9" smd rect
			(at 1.400048 0.750062 90)
			(size 0.2286 0.6096)
			(layers "F.Cu" "F.Mask" "F.Paste")
			(net "P3V3_AUX")
		)
		(pad "10" smd rect
			(at 1.400048 0.249936 90)
			(size 0.2286 0.6096)
			(layers "F.Cu" "F.Mask" "F.Paste")
			(net "GND")
		)
		(pad "11" smd rect
			(at 1.400048 -0.249936 90)
			(size 0.2286 0.6096)
			(layers "F.Cu" "F.Mask" "F.Paste")
			(net "P3V3_OCP_SFF_R")
		)
		(pad "12" smd rect
			(at 1.400048 -0.750062 90)
			(size 0.2286 0.6096)
			(layers "F.Cu" "F.Mask" "F.Paste")
			(net "VSENSE_P3V3_INA230_1_INN")
		)
		(pad "13" smd rect
			(at 0.750062 -1.400048 180)
			(size 0.2286 0.6096)
			(layers "F.Cu" "F.Mask" "F.Paste")
			(net "VSENSE_P3V3_INA230_1_INP")
		)
		(pad "14" smd rect
			(at 0.249936 -1.400048 180)
			(size 0.2286 0.6096)
			(layers "F.Cu" "F.Mask" "F.Paste")
			(net "NC_INA230_1_NC3")
		)
		(pad "15" smd rect
			(at -0.249936 -1.400048 180)
			(size 0.2286 0.6096)
			(layers "F.Cu" "F.Mask" "F.Paste")
			(net "NC_INA230_1_NC4")
		)
		(pad "16" smd rect
			(at -0.750062 -1.400048 180)
			(size 0.2286 0.6096)
			(layers "F.Cu" "F.Mask" "F.Paste")
			(net "NC_INA230_1_NC5")
		)
		(pad "TH" smd rect
			(at 0 0 180)
			(size 1.7018 1.7018)
			(layers "F.Cu" "F.Mask" "F.Paste")
			(net "GND")
		)
		(zone
			(layer "F.Cu")
			(hatch none 0.5)
			(connect_pads
				(clearance 0)
			)
			(min_thickness 0.25)
			(keepout
				(tracks not_allowed)
				(vias allowed)
				(pads allowed)
				(copperpour not_allowed)
				(footprints allowed)
			)
			(placement
				(enabled no)
				(sheetname "")
			)
			(fill
				(thermal_gap 0.5)
				(thermal_bridge_width 0.5)
				(island_removal_mode 0)
			)
			(polygon
				(pts
					(xy 441.732416 -94.052136) (xy 441.732416 -93.033088) (xy 439.64352 -93.033088) (xy 439.64352 -95.121984)
					(xy 441.732416 -95.121984) (xy 441.732416 -94.077536) (xy 441.589668 -94.077536) (xy 441.589668 -94.979236)
					(xy 439.786268 -94.979236) (xy 439.786268 -93.175836) (xy 441.589668 -93.175836) (xy 441.589668 -94.052136)
				)
			)
		)
	)
	(footprint ""
		(layer "F.Cu")
		(at 366.48263 -255.053846 90)
		(property "Reference" "C1008"
			(at 0 0 90)
			(layer "F.SilkS")
			(hide yes)
			(effects
				(font
					(size 1.27 1.27)
				)
			)
		)
		(property "Value" ""
			(at 0 0 90)
			(layer "F.Fab")
			(effects
				(font
					(size 1.27 1.27)
				)
			)
		)
		(duplicate_pad_numbers_are_jumpers no)
		(fp_line
			(start 0.7874 -0.4064)
			(end 0.7874 0.4064)
			(stroke
				(width 0.1524)
				(type default)
			)
			(layer "F.SilkS")
		)
		(fp_line
			(start -0.7874 -0.4064)
			(end 0.7874 -0.4064)
			(stroke
				(width 0.1524)
				(type default)
			)
			(layer "F.SilkS")
		)
		(fp_line
			(start 0.7874 0.4064)
			(end -0.7874 0.4064)
			(stroke
				(width 0.1524)
				(type default)
			)
			(layer "F.SilkS")
		)
		(fp_line
			(start -0.7874 0.4064)
			(end -0.7874 -0.4064)
			(stroke
				(width 0.1524)
				(type default)
			)
			(layer "F.SilkS")
		)
		(fp_line
			(start -0.12065 -0.305054)
			(end -0.12065 -0.2794)
			(stroke
				(width 0.1)
				(type default)
			)
			(layer "F.Fab")
		)
		(fp_line
			(start -0.67945 -0.305054)
			(end -0.12065 -0.305054)
			(stroke
				(width 0.1)
				(type default)
			)
			(layer "F.Fab")
		)
		(fp_line
			(start 0.67945 -0.3048)
			(end 0.67945 0.3048)
			(stroke
				(width 0.1)
				(type default)
			)
			(layer "F.Fab")
		)
		(fp_line
			(start 0.12065 -0.3048)
			(end 0.67945 -0.3048)
			(stroke
				(width 0.1)
				(type default)
			)
			(layer "F.Fab")
		)
		(fp_line
			(start 0.12065 -0.2794)
			(end 0.12065 -0.3048)
			(stroke
				(width 0.1)
				(type default)
			)
			(layer "F.Fab")
		)
		(fp_line
			(start -0.12065 -0.2794)
			(end 0.12065 -0.2794)
			(stroke
				(width 0.1)
				(type default)
			)
			(layer "F.Fab")
		)
		(fp_line
			(start 0.120396 0.2794)
			(end -0.12065 0.2794)
			(stroke
				(width 0.1)
				(type default)
			)
			(layer "F.Fab")
		)
		(fp_line
			(start -0.12065 0.2794)
			(end -0.12065 0.3048)
			(stroke
				(width 0.1)
				(type default)
			)
			(layer "F.Fab")
		)
		(fp_line
			(start 0.67945 0.3048)
			(end 0.120396 0.3048)
			(stroke
				(width 0.1)
				(type default)
			)
			(layer "F.Fab")
		)
		(fp_line
			(start 0.120396 0.3048)
			(end 0.120396 0.2794)
			(stroke
				(width 0.1)
				(type default)
			)
			(layer "F.Fab")
		)
		(fp_line
			(start -0.12065 0.3048)
			(end -0.67945 0.3048)
			(stroke
				(width 0.1)
				(type default)
			)
			(layer "F.Fab")
		)
		(fp_line
			(start -0.67945 0.3048)
			(end -0.67945 -0.305054)
			(stroke
				(width 0.1)
				(type default)
			)
			(layer "F.Fab")
		)
		(pad "1" smd circle
			(at -0.40005 0 90)
			(size 0 0)
			(layers "F.Cu" "F.Mask" "F.Paste")
			(net "PVCCIN_CPU0")
		)
		(pad "2" smd circle
			(at 0.40005 0 90)
			(size 0 0)
			(layers "F.Cu" "F.Mask" "F.Paste")
			(net "GND")
		)
	)
	(footprint ""
		(layer "F.Cu")
		(at 61.175646 -111.226346)
		(property "Reference" "U39"
			(at -2.1844 -4.587748 0)
			(unlocked yes)
			(layer "F.SilkS")
			(effects
				(font
					(size 0.7874 0.5842)
					(thickness 0.1524)
				)
				(justify left)
			)
		)
		(property "Value" ""
			(at 0 0 0)
			(layer "F.Fab")
			(effects
				(font
					(size 1.27 1.27)
				)
			)
		)
		(duplicate_pad_numbers_are_jumpers no)
		(fp_line
			(start -1.8542 -3.949954)
			(end -1.8542 3.949954)
			(stroke
				(width 0.1524)
				(type default)
			)
			(layer "F.SilkS")
		)
		(fp_line
			(start -1.8542 3.949954)
			(end 1.8542 3.949954)
			(stroke
				(width 0.1524)
				(type default)
			)
			(layer "F.SilkS")
		)
		(fp_line
			(start -1.282954 -3.949954)
			(end -1.8542 -3.949954)
			(stroke
				(width 0.1524)
				(type default)
			)
			(layer "F.SilkS")
		)
		(fp_line
			(start 0 -2.667)
			(end -1.282954 -3.949954)
			(stroke
				(width 0.1524)
				(type default)
			)
			(layer "F.SilkS")
		)
		(fp_line
			(start 1.282954 -3.949954)
			(end 0 -2.667)
			(stroke
				(width 0.1524)
				(type default)
			)
			(layer "F.SilkS")
		)
		(fp_line
			(start 1.8542 -3.949954)
			(end 1.282954 -3.949954)
			(stroke
				(width 0.1524)
				(type default)
			)
			(layer "F.SilkS")
		)
		(fp_line
			(start 1.8542 3.949954)
			(end 1.8542 -3.949954)
			(stroke
				(width 0.1524)
				(type default)
			)
			(layer "F.SilkS")
		)
		(fp_poly
			(pts
				(xy -4.8006 -4.08305) (xy -4.8006 -3.06705) (xy -3.7846 -3.57505)
			)
			(stroke
				(width 0)
				(type default)
			)
			(fill yes)
			(layer "F.SilkS")
		)
		(fp_line
			(start -2.249932 -3.949954)
			(end -2.249932 3.949954)
			(stroke
				(width 0.1)
				(type default)
			)
			(layer "F.Fab")
		)
		(fp_line
			(start -2.249932 3.949954)
			(end 2.249932 3.949954)
			(stroke
				(width 0.1)
				(type default)
			)
			(layer "F.Fab")
		)
		(fp_line
			(start 2.249932 -3.949954)
			(end -2.249932 -3.949954)
			(stroke
				(width 0.1)
				(type default)
			)
			(layer "F.Fab")
		)
		(fp_line
			(start 2.249932 3.949954)
			(end 2.249932 -3.949954)
			(stroke
				(width 0.1)
				(type default)
			)
			(layer "F.Fab")
		)
		(fp_poly
			(pts
				(xy -4.8006 -4.08305) (xy -4.8006 -3.06705) (xy -3.7846 -3.57505)
			)
			(stroke
				(width 0)
				(type default)
			)
			(fill yes)
			(layer "F.Fab")
		)
		(pad "1" smd rect
			(at -2.800096 -3.57505 270)
			(size 0.3048 1.6002)
			(layers "F.Cu" "F.Mask" "F.Paste")
			(net "PCA9548_PCIE0_ADDR0")
		)
		(pad "2" smd rect
			(at -2.800096 -2.925064 270)
			(size 0.3048 1.6002)
			(layers "F.Cu" "F.Mask" "F.Paste")
			(net "PCA9548_PCIE0_ADDR1")
		)
		(pad "3" smd rect
			(at -2.800096 -2.275078 270)
			(size 0.3048 1.6002)
			(layers "F.Cu" "F.Mask" "F.Paste")
			(net "PU_RST_SMB_PCIE2_N")
		)
		(pad "4" smd rect
			(at -2.800096 -1.625092 270)
			(size 0.3048 1.6002)
			(layers "F.Cu" "F.Mask" "F.Paste")
			(net "SMB_VR_3V3AUX_SDA_R6")
		)
		(pad "5" smd rect
			(at -2.800096 -0.975106 270)
			(size 0.3048 1.6002)
			(layers "F.Cu" "F.Mask" "F.Paste")
			(net "SMB_VR_3V3AUX_SCL_R6")
		)
		(pad "6" smd rect
			(at -2.800096 -0.32512 270)
			(size 0.3048 1.6002)
			(layers "F.Cu" "F.Mask" "F.Paste")
			(net "SMB_LM75_0_3V3AUX_SDA_R")
		)
		(pad "7" smd rect
			(at -2.800096 0.32512 270)
			(size 0.3048 1.6002)
			(layers "F.Cu" "F.Mask" "F.Paste")
			(net "SMB_LM75_0_3V3AUX_SCL_R")
		)
		(pad "8" smd rect
			(at -2.800096 0.975106 270)
			(size 0.3048 1.6002)
			(layers "F.Cu" "F.Mask" "F.Paste")
			(net "SMB_LM75_1_3V3AUX_SDA_R")
		)
		(pad "9" smd rect
			(at -2.800096 1.625092 270)
			(size 0.3048 1.6002)
			(layers "F.Cu" "F.Mask" "F.Paste")
			(net "SMB_LM75_1_3V3AUX_SCL_R")
		)
		(pad "10" smd rect
			(at -2.800096 2.275078 270)
			(size 0.3048 1.6002)
			(layers "F.Cu" "F.Mask" "F.Paste")
			(net "SMB_LM75_2_3V3AUX_SDA_R")
		)
		(pad "11" smd rect
			(at -2.800096 2.925064 270)
			(size 0.3048 1.6002)
			(layers "F.Cu" "F.Mask" "F.Paste")
			(net "SMB_LM75_2_3V3AUX_SCL_R")
		)
		(pad "12" smd rect
			(at -2.800096 3.57505 270)
			(size 0.3048 1.6002)
			(layers "F.Cu" "F.Mask" "F.Paste")
			(net "GND")
		)
		(pad "13" smd rect
			(at 2.800096 3.57505 270)
			(size 0.3048 1.6002)
			(layers "F.Cu" "F.Mask" "F.Paste")
			(net "SMB_LM75_3_3V3AUX_SDA_R")
		)
		(pad "14" smd rect
			(at 2.800096 2.925064 270)
			(size 0.3048 1.6002)
			(layers "F.Cu" "F.Mask" "F.Paste")
			(net "SMB_LM75_3_3V3AUX_SCL_R")
		)
		(pad "15" smd rect
			(at 2.800096 2.275078 270)
			(size 0.3048 1.6002)
			(layers "F.Cu" "F.Mask" "F.Paste")
			(net "Net_8618")
		)
		(pad "16" smd rect
			(at 2.800096 1.625092 270)
			(size 0.3048 1.6002)
			(layers "F.Cu" "F.Mask" "F.Paste")
			(net "Net_8621")
		)
		(pad "17" smd rect
			(at 2.800096 0.975106 270)
			(size 0.3048 1.6002)
			(layers "F.Cu" "F.Mask" "F.Paste")
			(net "Net_8617")
		)
		(pad "18" smd rect
			(at 2.800096 0.32512 270)
			(size 0.3048 1.6002)
			(layers "F.Cu" "F.Mask" "F.Paste")
			(net "Net_8620")
		)
		(pad "19" smd rect
			(at 2.800096 -0.32512 270)
			(size 0.3048 1.6002)
			(layers "F.Cu" "F.Mask" "F.Paste")
			(net "Net_8616")
		)
		(pad "20" smd rect
			(at 2.800096 -0.975106 270)
			(size 0.3048 1.6002)
			(layers "F.Cu" "F.Mask" "F.Paste")
			(net "Net_8619")
		)
		(pad "21" smd rect
			(at 2.800096 -1.625092 270)
			(size 0.3048 1.6002)
			(layers "F.Cu" "F.Mask" "F.Paste")
			(net "PCA9548_PCIE0_ADDR2")
		)
		(pad "22" smd rect
			(at 2.800096 -2.275078 270)
			(size 0.3048 1.6002)
			(layers "F.Cu" "F.Mask" "F.Paste")
			(net "SMB_VR_SENSOR_3V3AUX_SCL_R")
		)
		(pad "23" smd rect
			(at 2.800096 -2.925064 270)
			(size 0.3048 1.6002)
			(layers "F.Cu" "F.Mask" "F.Paste")
			(net "SMB_VR_SENSOR_3V3AUX_SDA_R")
		)
		(pad "24" smd rect
			(at 2.800096 -3.57505 270)
			(size 0.3048 1.6002)
			(layers "F.Cu" "F.Mask" "F.Paste")
			(net "P3V3_AUX")
		)
	)
	(footprint ""
		(layer "F.Cu")
		(at 93.27388 -56.225948)
		(property "Reference" "U87"
			(at -1.4224 -2.327148 0)
			(unlocked yes)
			(layer "F.SilkS")
			(effects
				(font
					(size 0.7874 0.5842)
					(thickness 0.1524)
				)
			)
		)
		(property "Value" ""
			(at 0 0 0)
			(layer "F.Fab")
			(effects
				(font
					(size 1.27 1.27)
				)
			)
		)
		(duplicate_pad_numbers_are_jumpers no)
		(fp_line
			(start -1.949958 -1.610106)
			(end 1.949958 -1.610106)
			(stroke
				(width 0.1524)
				(type default)
			)
			(layer "F.SilkS")
		)
		(fp_line
			(start -1.949958 1.610106)
			(end -1.949958 -1.610106)
			(stroke
				(width 0.1524)
				(type default)
			)
			(layer "F.SilkS")
		)
		(fp_line
			(start 1.949958 -1.560068)
			(end 1.949958 1.610106)
			(stroke
				(width 0.1524)
				(type default)
			)
			(layer "F.SilkS")
		)
		(fp_line
			(start 1.949958 1.610106)
			(end -1.949958 1.610106)
			(stroke
				(width 0.1524)
				(type default)
			)
			(layer "F.SilkS")
		)
		(fp_line
			(start -0.750062 -1.560068)
			(end 0.750062 -1.560068)
			(stroke
				(width 0.1)
				(type default)
			)
			(layer "F.Fab")
		)
		(fp_line
			(start -0.750062 1.560068)
			(end -0.750062 -1.560068)
			(stroke
				(width 0.1)
				(type default)
			)
			(layer "F.Fab")
		)
		(fp_line
			(start 0.750062 -1.560068)
			(end 0.750062 1.560068)
			(stroke
				(width 0.1)
				(type default)
			)
			(layer "F.Fab")
		)
		(fp_line
			(start 0.750062 1.560068)
			(end -0.750062 1.560068)
			(stroke
				(width 0.1)
				(type default)
			)
			(layer "F.Fab")
		)
		(pad "D" smd rect
			(at 1.100074 0 270)
			(size 1.016 1.4224)
			(layers "F.Cu" "F.Mask" "F.Paste")
			(net "P1V05_PCH_AUX")
		)
		(pad "G" smd rect
			(at -1.100074 -0.94996 270)
			(size 1.016 1.4224)
			(layers "F.Cu" "F.Mask" "F.Paste")
			(net "FM_REMOTE_DEBUG_DET_R")
		)
		(pad "S" smd rect
			(at -1.100074 0.94996 270)
			(size 1.016 1.4224)
			(layers "F.Cu" "F.Mask" "F.Paste")
			(net "FM_BMC_EN_DET")
		)
	)
	(footprint ""
		(layer "F.Cu")
		(at 356.616 -416.143948)
		(property "Reference" "R4562"
			(at 0 0 0)
			(layer "F.SilkS")
			(hide yes)
			(effects
				(font
					(size 1.27 1.27)
				)
			)
		)
		(property "Value" ""
			(at 0 0 0)
			(layer "F.Fab")
			(effects
				(font
					(size 1.27 1.27)
				)
			)
		)
		(duplicate_pad_numbers_are_jumpers no)
		(fp_line
			(start -0.7874 -0.4064)
			(end 0.7874 -0.4064)
			(stroke
				(width 0.1524)
				(type default)
			)
			(layer "F.SilkS")
		)
		(fp_line
			(start -0.7874 0.4064)
			(end -0.7874 -0.4064)
			(stroke
				(width 0.1524)
				(type default)
			)
			(layer "F.SilkS")
		)
		(fp_line
			(start 0.7874 -0.4064)
			(end 0.7874 0.4064)
			(stroke
				(width 0.1524)
				(type default)
			)
			(layer "F.SilkS")
		)
		(fp_line
			(start 0.7874 0.4064)
			(end -0.7874 0.4064)
			(stroke
				(width 0.1524)
				(type default)
			)
			(layer "F.SilkS")
		)
		(fp_line
			(start -0.67945 -0.305054)
			(end -0.12065 -0.305054)
			(stroke
				(width 0.1)
				(type default)
			)
			(layer "F.Fab")
		)
		(fp_line
			(start -0.67945 0.3048)
			(end -0.67945 -0.305054)
			(stroke
				(width 0.1)
				(type default)
			)
			(layer "F.Fab")
		)
		(fp_line
			(start -0.12065 -0.305054)
			(end -0.12065 -0.2794)
			(stroke
				(width 0.1)
				(type default)
			)
			(layer "F.Fab")
		)
		(fp_line
			(start -0.12065 -0.2794)
			(end 0.12065 -0.2794)
			(stroke
				(width 0.1)
				(type default)
			)
			(layer "F.Fab")
		)
		(fp_line
			(start -0.12065 0.2794)
			(end -0.12065 0.3048)
			(stroke
				(width 0.1)
				(type default)
			)
			(layer "F.Fab")
		)
		(fp_line
			(start -0.12065 0.3048)
			(end -0.67945 0.3048)
			(stroke
				(width 0.1)
				(type default)
			)
			(layer "F.Fab")
		)
		(fp_line
			(start 0.120396 0.2794)
			(end -0.12065 0.2794)
			(stroke
				(width 0.1)
				(type default)
			)
			(layer "F.Fab")
		)
		(fp_line
			(start 0.120396 0.3048)
			(end 0.120396 0.2794)
			(stroke
				(width 0.1)
				(type default)
			)
			(layer "F.Fab")
		)
		(fp_line
			(start 0.12065 -0.3048)
			(end 0.67945 -0.3048)
			(stroke
				(width 0.1)
				(type default)
			)
			(layer "F.Fab")
		)
		(fp_line
			(start 0.12065 -0.2794)
			(end 0.12065 -0.3048)
			(stroke
				(width 0.1)
				(type default)
			)
			(layer "F.Fab")
		)
		(fp_line
			(start 0.67945 -0.3048)
			(end 0.67945 0.3048)
			(stroke
				(width 0.1)
				(type default)
			)
			(layer "F.Fab")
		)
		(fp_line
			(start 0.67945 0.3048)
			(end 0.120396 0.3048)
			(stroke
				(width 0.1)
				(type default)
			)
			(layer "F.Fab")
		)
		(pad "1" smd circle
			(at -0.40005 0)
			(size 0 0)
			(layers "F.Cu" "F.Mask" "F.Paste")
			(net "P3V3_AUX")
		)
		(pad "2" smd circle
			(at 0.40005 0)
			(size 0 0)
			(layers "F.Cu" "F.Mask" "F.Paste")
			(net "SWB_HSC_PWRGD")
		)
	)
	(footprint ""
		(layer "F.Cu")
		(at 369.923822 -360.043222 90)
		(property "Reference" "PR1336"
			(at 0 0 90)
			(layer "F.SilkS")
			(hide yes)
			(effects
				(font
					(size 1.27 1.27)
				)
			)
		)
		(property "Value" ""
			(at 0 0 90)
			(layer "F.Fab")
			(effects
				(font
					(size 1.27 1.27)
				)
			)
		)
		(duplicate_pad_numbers_are_jumpers no)
		(fp_line
			(start 0.7874 -0.4064)
			(end 0.7874 0.4064)
			(stroke
				(width 0.1524)
				(type default)
			)
			(layer "F.SilkS")
		)
		(fp_line
			(start -0.7874 -0.4064)
			(end 0.7874 -0.4064)
			(stroke
				(width 0.1524)
				(type default)
			)
			(layer "F.SilkS")
		)
		(fp_line
			(start 0.7874 0.4064)
			(end -0.7874 0.4064)
			(stroke
				(width 0.1524)
				(type default)
			)
			(layer "F.SilkS")
		)
		(fp_line
			(start -0.7874 0.4064)
			(end -0.7874 -0.4064)
			(stroke
				(width 0.1524)
				(type default)
			)
			(layer "F.SilkS")
		)
		(fp_line
			(start -0.12065 -0.305054)
			(end -0.12065 -0.2794)
			(stroke
				(width 0.1)
				(type default)
			)
			(layer "F.Fab")
		)
		(fp_line
			(start -0.67945 -0.305054)
			(end -0.12065 -0.305054)
			(stroke
				(width 0.1)
				(type default)
			)
			(layer "F.Fab")
		)
		(fp_line
			(start 0.67945 -0.3048)
			(end 0.67945 0.3048)
			(stroke
				(width 0.1)
				(type default)
			)
			(layer "F.Fab")
		)
		(fp_line
			(start 0.12065 -0.3048)
			(end 0.67945 -0.3048)
			(stroke
				(width 0.1)
				(type default)
			)
			(layer "F.Fab")
		)
		(fp_line
			(start 0.12065 -0.2794)
			(end 0.12065 -0.3048)
			(stroke
				(width 0.1)
				(type default)
			)
			(layer "F.Fab")
		)
		(fp_line
			(start -0.12065 -0.2794)
			(end 0.12065 -0.2794)
			(stroke
				(width 0.1)
				(type default)
			)
			(layer "F.Fab")
		)
		(fp_line
			(start 0.120396 0.2794)
			(end -0.12065 0.2794)
			(stroke
				(width 0.1)
				(type default)
			)
			(layer "F.Fab")
		)
		(fp_line
			(start -0.12065 0.2794)
			(end -0.12065 0.3048)
			(stroke
				(width 0.1)
				(type default)
			)
			(layer "F.Fab")
		)
		(fp_line
			(start 0.67945 0.3048)
			(end 0.120396 0.3048)
			(stroke
				(width 0.1)
				(type default)
			)
			(layer "F.Fab")
		)
		(fp_line
			(start 0.120396 0.3048)
			(end 0.120396 0.2794)
			(stroke
				(width 0.1)
				(type default)
			)
			(layer "F.Fab")
		)
		(fp_line
			(start -0.12065 0.3048)
			(end -0.67945 0.3048)
			(stroke
				(width 0.1)
				(type default)
			)
			(layer "F.Fab")
		)
		(fp_line
			(start -0.67945 0.3048)
			(end -0.67945 -0.305054)
			(stroke
				(width 0.1)
				(type default)
			)
			(layer "F.Fab")
		)
		(pad "1" smd circle
			(at -0.40005 0 90)
			(size 0 0)
			(layers "F.Cu" "F.Mask" "F.Paste")
			(net "PVPP_HBM_CPU0_CS")
		)
		(pad "2" smd circle
			(at 0.40005 0 90)
			(size 0 0)
			(layers "F.Cu" "F.Mask" "F.Paste")
			(net "GND")
		)
	)
	(footprint ""
		(layer "F.Cu")
		(at 370.615718 -413.90443 -90)
		(property "Reference" "R4199"
			(at 0 0 270)
			(layer "F.SilkS")
			(hide yes)
			(effects
				(font
					(size 1.27 1.27)
				)
			)
		)
		(property "Value" ""
			(at 0 0 270)
			(layer "F.Fab")
			(effects
				(font
					(size 1.27 1.27)
				)
			)
		)
		(duplicate_pad_numbers_are_jumpers no)
		(fp_line
			(start -0.7874 0.4064)
			(end -0.7874 -0.4064)
			(stroke
				(width 0.1524)
				(type default)
			)
			(layer "F.SilkS")
		)
		(fp_line
			(start 0.7874 0.4064)
			(end -0.7874 0.4064)
			(stroke
				(width 0.1524)
				(type default)
			)
			(layer "F.SilkS")
		)
		(fp_line
			(start -0.7874 -0.4064)
			(end 0.7874 -0.4064)
			(stroke
				(width 0.1524)
				(type default)
			)
			(layer "F.SilkS")
		)
		(fp_line
			(start 0.7874 -0.4064)
			(end 0.7874 0.4064)
			(stroke
				(width 0.1524)
				(type default)
			)
			(layer "F.SilkS")
		)
		(fp_line
			(start -0.67945 0.3048)
			(end -0.67945 -0.305054)
			(stroke
				(width 0.1)
				(type default)
			)
			(layer "F.Fab")
		)
		(fp_line
			(start -0.12065 0.3048)
			(end -0.67945 0.3048)
			(stroke
				(width 0.1)
				(type default)
			)
			(layer "F.Fab")
		)
		(fp_line
			(start 0.120396 0.3048)
			(end 0.120396 0.2794)
			(stroke
				(width 0.1)
				(type default)
			)
			(layer "F.Fab")
		)
		(fp_line
			(start 0.67945 0.3048)
			(end 0.120396 0.3048)
			(stroke
				(width 0.1)
				(type default)
			)
			(layer "F.Fab")
		)
		(fp_line
			(start -0.12065 0.2794)
			(end -0.12065 0.3048)
			(stroke
				(width 0.1)
				(type default)
			)
			(layer "F.Fab")
		)
		(fp_line
			(start 0.120396 0.2794)
			(end -0.12065 0.2794)
			(stroke
				(width 0.1)
				(type default)
			)
			(layer "F.Fab")
		)
		(fp_line
			(start -0.12065 -0.2794)
			(end 0.12065 -0.2794)
			(stroke
				(width 0.1)
				(type default)
			)
			(layer "F.Fab")
		)
		(fp_line
			(start 0.12065 -0.2794)
			(end 0.12065 -0.3048)
			(stroke
				(width 0.1)
				(type default)
			)
			(layer "F.Fab")
		)
		(fp_line
			(start 0.12065 -0.3048)
			(end 0.67945 -0.3048)
			(stroke
				(width 0.1)
				(type default)
			)
			(layer "F.Fab")
		)
		(fp_line
			(start 0.67945 -0.3048)
			(end 0.67945 0.3048)
			(stroke
				(width 0.1)
				(type default)
			)
			(layer "F.Fab")
		)
		(fp_line
			(start -0.67945 -0.305054)
			(end -0.12065 -0.305054)
			(stroke
				(width 0.1)
				(type default)
			)
			(layer "F.Fab")
		)
		(fp_line
			(start -0.12065 -0.305054)
			(end -0.12065 -0.2794)
			(stroke
				(width 0.1)
				(type default)
			)
			(layer "F.Fab")
		)
		(pad "1" smd circle
			(at -0.40005 0 270)
			(size 0 0)
			(layers "F.Cu" "F.Mask" "F.Paste")
			(net "U270_0_ADD1")
		)
		(pad "2" smd circle
			(at 0.40005 0 270)
			(size 0 0)
			(layers "F.Cu" "F.Mask" "F.Paste")
			(net "GND")
		)
	)
	(footprint ""
		(layer "F.Cu")
		(at 400.558 -164.785548)
		(property "Reference" "PC1645"
			(at 0 0 0)
			(layer "F.SilkS")
			(hide yes)
			(effects
				(font
					(size 1.27 1.27)
				)
			)
		)
		(property "Value" ""
			(at 0 0 0)
			(layer "F.Fab")
			(effects
				(font
					(size 1.27 1.27)
				)
			)
		)
		(duplicate_pad_numbers_are_jumpers no)
		(fp_line
			(start 2.750058 0.999998)
			(end -2.750058 0.999998)
			(stroke
				(width 0.1524)
				(type default)
			)
			(layer "F.SilkS")
		)
		(fp_circle
			(center 0 0.999998)
			(end 2.750058 0.999998)
			(stroke
				(width 0.1524)
				(type default)
			)
			(fill no)
			(layer "F.SilkS")
		)
		(fp_poly
			(pts
				(arc
					(start 2.750058 0.999998)
					(mid 0 3.750056)
					(end -2.750058 0.999998)
				)
			)
			(stroke
				(width 0)
				(type default)
			)
			(fill yes)
			(layer "F.SilkS")
		)
		(fp_circle
			(center 0 0.999998)
			(end 2.750058 0.999998)
			(stroke
				(width 0.1)
				(type default)
			)
			(fill no)
			(layer "F.Fab")
		)
		(pad "1" thru_hole rect
			(at 0 0)
			(size 1.5748 1.5748)
			(drill 1.0668)
			(layers "*.Cu" "*.Mask")
			(remove_unused_layers no)
			(net "PVCCD_HV_CPU0")
			(clearance 0)
			(padstack
				(mode front_inner_back)
				(layer "Inner"
					(shape circle)
					(size 1.5748 1.5748)
					(clearance 0)
				)
				(layer "B.Cu"
					(shape rect)
					(size 1.5748 1.5748)
					(clearance 0)
				)
			)
		)
		(pad "2" thru_hole circle
			(at 0 1.999996)
			(size 1.5748 1.5748)
			(drill 1.0668)
			(layers "*.Cu" "*.Mask")
			(remove_unused_layers no)
			(net "GND")
			(clearance 0)
		)
	)
	(footprint ""
		(layer "F.Cu")
		(at 181.710584 -344.7796 -90)
		(property "Reference" "PL12"
			(at -3.214878 -4.197096 0)
			(unlocked yes)
			(layer "F.SilkS")
			(effects
				(font
					(size 0.7874 0.5842)
					(thickness 0.1524)
				)
				(justify left)
			)
		)
		(property "Value" ""
			(at 0 0 270)
			(layer "F.Fab")
			(effects
				(font
					(size 1.27 1.27)
				)
			)
		)
		(duplicate_pad_numbers_are_jumpers no)
		(fp_line
			(start -4.99999 3.750056)
			(end -4.99999 2.2479)
			(stroke
				(width 0.1524)
				(type default)
			)
			(layer "F.SilkS")
		)
		(fp_line
			(start 0 3.750056)
			(end -4.99999 3.750056)
			(stroke
				(width 0.1524)
				(type default)
			)
			(layer "F.SilkS")
		)
		(fp_line
			(start 4.99999 3.750056)
			(end 0 3.750056)
			(stroke
				(width 0.1524)
				(type default)
			)
			(layer "F.SilkS")
		)
		(fp_line
			(start 4.99999 2.2352)
			(end 4.99999 3.750056)
			(stroke
				(width 0.1524)
				(type default)
			)
			(layer "F.SilkS")
		)
		(fp_line
			(start -4.99999 -2.2479)
			(end -4.99999 -3.750056)
			(stroke
				(width 0.1524)
				(type default)
			)
			(layer "F.SilkS")
		)
		(fp_line
			(start -4.99999 -3.750056)
			(end 4.99999 -3.750056)
			(stroke
				(width 0.1524)
				(type default)
			)
			(layer "F.SilkS")
		)
		(fp_line
			(start 4.99999 -3.750056)
			(end 4.99999 -2.2479)
			(stroke
				(width 0.1524)
				(type default)
			)
			(layer "F.SilkS")
		)
		(fp_line
			(start -4.99999 3.750056)
			(end -4.99999 -3.750056)
			(stroke
				(width 0.1)
				(type default)
			)
			(layer "F.Fab")
		)
		(fp_line
			(start 0 3.750056)
			(end -4.99999 3.750056)
			(stroke
				(width 0.1)
				(type default)
			)
			(layer "F.Fab")
		)
		(fp_line
			(start 4.99999 3.750056)
			(end 0 3.750056)
			(stroke
				(width 0.1)
				(type default)
			)
			(layer "F.Fab")
		)
		(fp_line
			(start -4.99999 -3.750056)
			(end 4.99999 -3.750056)
			(stroke
				(width 0.1)
				(type default)
			)
			(layer "F.Fab")
		)
		(fp_line
			(start 4.99999 -3.750056)
			(end 4.99999 3.750056)
			(stroke
				(width 0.1)
				(type default)
			)
			(layer "F.Fab")
		)
		(pad "1" smd rect
			(at -3.299968 0 270)
			(size 3.302 4.2164)
			(layers "F.Cu" "F.Mask" "F.Paste")
			(net "SW_PVCCFA_EHV_FIVRA_CPU1_SW3")
		)
		(pad "2" smd rect
			(at 3.299968 0 270)
			(size 3.302 4.2164)
			(layers "F.Cu" "F.Mask" "F.Paste")
			(net "PVCCFA_EHV_FIVRA_CPU1")
		)
	)
	(footprint ""
		(layer "F.Cu")
		(at 183.49468 -258.091686)
		(property "Reference" "J27"
			(at 2.19456 -81.755488 0)
			(unlocked yes)
			(layer "F.SilkS")
			(effects
				(font
					(size 0.7874 0.5842)
					(thickness 0.1524)
				)
				(justify left)
			)
		)
		(property "Value" ""
			(at 0 0 0)
			(layer "F.Fab")
			(effects
				(font
					(size 1.27 1.27)
				)
			)
		)
		(duplicate_pad_numbers_are_jumpers no)
		(fp_line
			(start -3.24993 -81.000092)
			(end -3.24993 81.000092)
			(stroke
				(width 0.1524)
				(type default)
			)
			(layer "F.SilkS")
		)
		(fp_line
			(start -3.24993 81.000092)
			(end 3.24993 81.000092)
			(stroke
				(width 0.1524)
				(type default)
			)
			(layer "F.SilkS")
		)
		(fp_line
			(start -1.51892 -81.000092)
			(end -3.24993 -81.000092)
			(stroke
				(width 0.1524)
				(type default)
			)
			(layer "F.SilkS")
		)
		(fp_line
			(start 3.24993 -81.000092)
			(end 1.52146 -81.000092)
			(stroke
				(width 0.1524)
				(type default)
			)
			(layer "F.SilkS")
		)
		(fp_line
			(start 3.24993 -72.00011)
			(end -3.24993 -72.00011)
			(stroke
				(width 0.1524)
				(type default)
			)
			(layer "F.SilkS")
		)
		(fp_line
			(start 3.24993 72.00011)
			(end -3.24993 72.00011)
			(stroke
				(width 0.1524)
				(type default)
			)
			(layer "F.SilkS")
		)
		(fp_line
			(start 3.24993 81.000092)
			(end 3.24993 -81.000092)
			(stroke
				(width 0.1524)
				(type default)
			)
			(layer "F.SilkS")
		)
		(fp_poly
			(pts
				(xy -4.162298 -63.717678) (xy -3.355848 -63.314326) (xy -4.162298 -62.910974)
			)
			(stroke
				(width 0)
				(type default)
			)
			(fill yes)
			(layer "F.SilkS")
		)
		(fp_line
			(start -3.24993 -81.000092)
			(end -3.24993 81.000092)
			(stroke
				(width 0.1)
				(type default)
			)
			(layer "F.Fab")
		)
		(fp_line
			(start -3.24993 81.000092)
			(end 3.24993 81.000092)
			(stroke
				(width 0.1)
				(type default)
			)
			(layer "F.Fab")
		)
		(fp_line
			(start 3.24993 -81.000092)
			(end -3.24993 -81.000092)
			(stroke
				(width 0.1)
				(type default)
			)
			(layer "F.Fab")
		)
		(fp_line
			(start 3.24993 -72.00011)
			(end -3.24993 -72.00011)
			(stroke
				(width 0.1)
				(type default)
			)
			(layer "F.Fab")
		)
		(fp_line
			(start 3.24993 -71.000112)
			(end -3.24993 -71.000112)
			(stroke
				(width 0.1)
				(type default)
			)
			(layer "F.Fab")
		)
		(fp_line
			(start 3.24993 71.000112)
			(end -3.24993 71.000112)
			(stroke
				(width 0.1)
				(type default)
			)
			(layer "F.Fab")
		)
		(fp_line
			(start 3.24993 72.00011)
			(end -3.24993 72.00011)
			(stroke
				(width 0.1)
				(type default)
			)
			(layer "F.Fab")
		)
		(fp_line
			(start 3.24993 81.000092)
			(end 3.24993 -81.000092)
			(stroke
				(width 0.1)
				(type default)
			)
			(layer "F.Fab")
		)
		(fp_poly
			(pts
				(xy -4.445 -63.832994) (xy -4.445 -62.816994) (xy -3.429 -63.324994)
			)
			(stroke
				(width 0)
				(type default)
			)
			(fill yes)
			(layer "F.Fab")
		)
		(pad "1" smd rect
			(at -2.050034 -63.324994 270)
			(size 0.519938 1.4986)
			(layers "F.Cu" "F.Mask" "F.Paste")
			(net "P12V_S3_AUX_CPU1_NVDIMM")
		)
		(pad "2" smd rect
			(at -2.050034 -62.47511 270)
			(size 0.519938 1.4986)
			(layers "F.Cu" "F.Mask" "F.Paste")
			(net "TP_CHF_CPU1_DIMM1_FRU_0")
		)
		(pad "3" smd rect
			(at -2.050034 -61.624972 270)
			(size 0.519938 1.4986)
			(layers "F.Cu" "F.Mask" "F.Paste")
			(net "P3V3_AUX")
		)
		(pad "4" smd rect
			(at -2.050034 -60.775088 270)
			(size 0.519938 1.4986)
			(layers "F.Cu" "F.Mask" "F.Paste")
			(net "I3C_SPD_DDREFGH_CPU1_LVC1_SCL_2")
		)
		(pad "5" smd rect
			(at -2.050034 -59.92495 270)
			(size 0.519938 1.4986)
			(layers "F.Cu" "F.Mask" "F.Paste")
			(net "I3C_SPD_DDREFGH_CPU1_LVC1_SDA")
		)
		(pad "6" smd rect
			(at -2.050034 -59.075066 270)
			(size 0.519938 1.4986)
			(layers "F.Cu" "F.Mask" "F.Paste")
			(net "GND")
		)
		(pad "7" smd rect
			(at -2.050034 -58.224928 270)
			(size 0.519938 1.4986)
			(layers "F.Cu" "F.Mask" "F.Paste")
			(net "M_F_CPU1_SA_DQ<0>")
		)
		(pad "8" smd rect
			(at -2.050034 -57.375044 270)
			(size 0.519938 1.4986)
			(layers "F.Cu" "F.Mask" "F.Paste")
			(net "GND")
		)
		(pad "9" smd rect
			(at -2.050034 -56.524906 270)
			(size 0.519938 1.4986)
			(layers "F.Cu" "F.Mask" "F.Paste")
			(net "M_F_CPU1_SA_DQ<1>")
		)
		(pad "10" smd rect
			(at -2.050034 -55.675022 270)
			(size 0.519938 1.4986)
			(layers "F.Cu" "F.Mask" "F.Paste")
			(net "GND")
		)
		(pad "11" smd rect
			(at -2.050034 -54.824884 270)
			(size 0.519938 1.4986)
			(layers "F.Cu" "F.Mask" "F.Paste")
			(net "M_F_CPU1_SA_DQS_DP<0>")
		)
		(pad "12" smd rect
			(at -2.050034 -53.975 270)
			(size 0.519938 1.4986)
			(layers "F.Cu" "F.Mask" "F.Paste")
			(net "M_F_CPU1_SA_DQS_DN<0>")
		)
		(pad "13" smd rect
			(at -2.050034 -53.125116 270)
			(size 0.519938 1.4986)
			(layers "F.Cu" "F.Mask" "F.Paste")
			(net "GND")
		)
		(pad "14" smd rect
			(at -2.050034 -52.274978 270)
			(size 0.519938 1.4986)
			(layers "F.Cu" "F.Mask" "F.Paste")
			(net "M_F_CPU1_SA_DQ<4>")
		)
		(pad "15" smd rect
			(at -2.050034 -51.425094 270)
			(size 0.519938 1.4986)
			(layers "F.Cu" "F.Mask" "F.Paste")
			(net "GND")
		)
		(pad "16" smd rect
			(at -2.050034 -50.574956 270)
			(size 0.519938 1.4986)
			(layers "F.Cu" "F.Mask" "F.Paste")
			(net "M_F_CPU1_SA_DQ<5>")
		)
		(pad "17" smd rect
			(at -2.050034 -49.725072 270)
			(size 0.519938 1.4986)
			(layers "F.Cu" "F.Mask" "F.Paste")
			(net "GND")
		)
		(pad "18" smd rect
			(at -2.050034 -48.874934 270)
			(size 0.519938 1.4986)
			(layers "F.Cu" "F.Mask" "F.Paste")
			(net "M_F_CPU1_SA_DQ<8>")
		)
		(pad "19" smd rect
			(at -2.050034 -48.02505 270)
			(size 0.519938 1.4986)
			(layers "F.Cu" "F.Mask" "F.Paste")
			(net "GND")
		)
		(pad "20" smd rect
			(at -2.050034 -47.174912 270)
			(size 0.519938 1.4986)
			(layers "F.Cu" "F.Mask" "F.Paste")
			(net "M_F_CPU1_SA_DQ<9>")
		)
		(pad "21" smd rect
			(at -2.050034 -46.325028 270)
			(size 0.519938 1.4986)
			(layers "F.Cu" "F.Mask" "F.Paste")
			(net "GND")
		)
		(pad "22" smd rect
			(at -2.050034 -45.47489 270)
			(size 0.519938 1.4986)
			(layers "F.Cu" "F.Mask" "F.Paste")
			(net "M_F_CPU1_SA_DQS_DP<1>")
		)
		(pad "23" smd rect
			(at -2.050034 -44.625006 270)
			(size 0.519938 1.4986)
			(layers "F.Cu" "F.Mask" "F.Paste")
			(net "M_F_CPU1_SA_DQS_DN<1>")
		)
		(pad "24" smd rect
			(at -2.050034 -43.775122 270)
			(size 0.519938 1.4986)
			(layers "F.Cu" "F.Mask" "F.Paste")
			(net "GND")
		)
		(pad "25" smd rect
			(at -2.050034 -42.924984 270)
			(size 0.519938 1.4986)
			(layers "F.Cu" "F.Mask" "F.Paste")
			(net "M_F_CPU1_SA_DQ<12>")
		)
		(pad "26" smd rect
			(at -2.050034 -42.0751 270)
			(size 0.519938 1.4986)
			(layers "F.Cu" "F.Mask" "F.Paste")
			(net "GND")
		)
		(pad "27" smd rect
			(at -2.050034 -41.224962 270)
			(size 0.519938 1.4986)
			(layers "F.Cu" "F.Mask" "F.Paste")
			(net "M_F_CPU1_SA_DQ<13>")
		)
		(pad "28" smd rect
			(at -2.050034 -40.375078 270)
			(size 0.519938 1.4986)
			(layers "F.Cu" "F.Mask" "F.Paste")
			(net "GND")
		)
		(pad "29" smd rect
			(at -2.050034 -39.52494 270)
			(size 0.519938 1.4986)
			(layers "F.Cu" "F.Mask" "F.Paste")
			(net "M_F_CPU1_SA_DQ<16>")
		)
		(pad "30" smd rect
			(at -2.050034 -38.675056 270)
			(size 0.519938 1.4986)
			(layers "F.Cu" "F.Mask" "F.Paste")
			(net "GND")
		)
		(pad "31" smd rect
			(at -2.050034 -37.824918 270)
			(size 0.519938 1.4986)
			(layers "F.Cu" "F.Mask" "F.Paste")
			(net "M_F_CPU1_SA_DQ<17>")
		)
		(pad "32" smd rect
			(at -2.050034 -36.975034 270)
			(size 0.519938 1.4986)
			(layers "F.Cu" "F.Mask" "F.Paste")
			(net "GND")
		)
		(pad "33" smd rect
			(at -2.050034 -36.124896 270)
			(size 0.519938 1.4986)
			(layers "F.Cu" "F.Mask" "F.Paste")
			(net "M_F_CPU1_SA_DQS_DP<2>")
		)
		(pad "34" smd rect
			(at -2.050034 -35.275012 270)
			(size 0.519938 1.4986)
			(layers "F.Cu" "F.Mask" "F.Paste")
			(net "M_F_CPU1_SA_DQS_DN<2>")
		)
		(pad "35" smd rect
			(at -2.050034 -34.425128 270)
			(size 0.519938 1.4986)
			(layers "F.Cu" "F.Mask" "F.Paste")
			(net "GND")
		)
		(pad "36" smd rect
			(at -2.050034 -33.57499 270)
			(size 0.519938 1.4986)
			(layers "F.Cu" "F.Mask" "F.Paste")
			(net "M_F_CPU1_SA_DQ<20>")
		)
		(pad "37" smd rect
			(at -2.050034 -32.725106 270)
			(size 0.519938 1.4986)
			(layers "F.Cu" "F.Mask" "F.Paste")
			(net "GND")
		)
		(pad "38" smd rect
			(at -2.050034 -31.874968 270)
			(size 0.519938 1.4986)
			(layers "F.Cu" "F.Mask" "F.Paste")
			(net "M_F_CPU1_SA_DQ<21>")
		)
		(pad "39" smd rect
			(at -2.050034 -31.025084 270)
			(size 0.519938 1.4986)
			(layers "F.Cu" "F.Mask" "F.Paste")
			(net "GND")
		)
		(pad "40" smd rect
			(at -2.050034 -30.174946 270)
			(size 0.519938 1.4986)
			(layers "F.Cu" "F.Mask" "F.Paste")
			(net "M_F_CPU1_SA_DQ<24>")
		)
		(pad "41" smd rect
			(at -2.050034 -29.325062 270)
			(size 0.519938 1.4986)
			(layers "F.Cu" "F.Mask" "F.Paste")
			(net "GND")
		)
		(pad "42" smd rect
			(at -2.050034 -28.474924 270)
			(size 0.519938 1.4986)
			(layers "F.Cu" "F.Mask" "F.Paste")
			(net "M_F_CPU1_SA_DQ<25>")
		)
		(pad "43" smd rect
			(at -2.050034 -27.62504 270)
			(size 0.519938 1.4986)
			(layers "F.Cu" "F.Mask" "F.Paste")
			(net "GND")
		)
		(pad "44" smd rect
			(at -2.050034 -26.774902 270)
			(size 0.519938 1.4986)
			(layers "F.Cu" "F.Mask" "F.Paste")
			(net "M_F_CPU1_SA_DQS_DP<3>")
		)
		(pad "45" smd rect
			(at -2.050034 -25.925018 270)
			(size 0.519938 1.4986)
			(layers "F.Cu" "F.Mask" "F.Paste")
			(net "M_F_CPU1_SA_DQS_DN<3>")
		)
		(pad "46" smd rect
			(at -2.050034 -25.07488 270)
			(size 0.519938 1.4986)
			(layers "F.Cu" "F.Mask" "F.Paste")
			(net "GND")
		)
		(pad "47" smd rect
			(at -2.050034 -24.224996 270)
			(size 0.519938 1.4986)
			(layers "F.Cu" "F.Mask" "F.Paste")
			(net "M_F_CPU1_SA_DQ<28>")
		)
		(pad "48" smd rect
			(at -2.050034 -23.375112 270)
			(size 0.519938 1.4986)
			(layers "F.Cu" "F.Mask" "F.Paste")
			(net "GND")
		)
		(pad "49" smd rect
			(at -2.050034 -22.524974 270)
			(size 0.519938 1.4986)
			(layers "F.Cu" "F.Mask" "F.Paste")
			(net "M_F_CPU1_SA_DQ<29>")
		)
		(pad "50" smd rect
			(at -2.050034 -21.67509 270)
			(size 0.519938 1.4986)
			(layers "F.Cu" "F.Mask" "F.Paste")
			(net "GND")
		)
		(pad "51" smd rect
			(at -2.050034 -20.824952 270)
			(size 0.519938 1.4986)
			(layers "F.Cu" "F.Mask" "F.Paste")
			(net "M_F_CPU1_SA_CB<0>")
		)
		(pad "52" smd rect
			(at -2.050034 -19.975068 270)
			(size 0.519938 1.4986)
			(layers "F.Cu" "F.Mask" "F.Paste")
			(net "GND")
		)
		(pad "53" smd rect
			(at -2.050034 -19.12493 270)
			(size 0.519938 1.4986)
			(layers "F.Cu" "F.Mask" "F.Paste")
			(net "M_F_CPU1_SA_CB<1>")
		)
		(pad "54" smd rect
			(at -2.050034 -18.275046 270)
			(size 0.519938 1.4986)
			(layers "F.Cu" "F.Mask" "F.Paste")
			(net "GND")
		)
		(pad "55" smd rect
			(at -2.050034 -17.424908 270)
			(size 0.519938 1.4986)
			(layers "F.Cu" "F.Mask" "F.Paste")
			(net "M_F_CPU1_SA_DQS_DP<4>")
		)
		(pad "56" smd rect
			(at -2.050034 -16.575024 270)
			(size 0.519938 1.4986)
			(layers "F.Cu" "F.Mask" "F.Paste")
			(net "M_F_CPU1_SA_DQS_DN<4>")
		)
		(pad "57" smd rect
			(at -2.050034 -15.724886 270)
			(size 0.519938 1.4986)
			(layers "F.Cu" "F.Mask" "F.Paste")
			(net "GND")
		)
		(pad "58" smd rect
			(at -2.050034 -14.875002 270)
			(size 0.519938 1.4986)
			(layers "F.Cu" "F.Mask" "F.Paste")
			(net "M_F_CPU1_SA_CB<4>")
		)
		(pad "59" smd rect
			(at -2.050034 -14.025118 270)
			(size 0.519938 1.4986)
			(layers "F.Cu" "F.Mask" "F.Paste")
			(net "GND")
		)
		(pad "60" smd rect
			(at -2.050034 -13.17498 270)
			(size 0.519938 1.4986)
			(layers "F.Cu" "F.Mask" "F.Paste")
			(net "M_F_CPU1_SA_CB<5>")
		)
		(pad "61" smd rect
			(at -2.050034 -12.325096 270)
			(size 0.519938 1.4986)
			(layers "F.Cu" "F.Mask" "F.Paste")
			(net "GND")
		)
		(pad "62" smd rect
			(at -2.050034 -11.474958 270)
			(size 0.519938 1.4986)
			(layers "F.Cu" "F.Mask" "F.Paste")
			(net "M_F_CPU1_ALERT_N")
		)
		(pad "63" smd rect
			(at -2.050034 -10.625074 270)
			(size 0.519938 1.4986)
			(layers "F.Cu" "F.Mask" "F.Paste")
			(net "GND")
		)
		(pad "64" smd rect
			(at -2.050034 -9.774936 270)
			(size 0.519938 1.4986)
			(layers "F.Cu" "F.Mask" "F.Paste")
			(net "M_F_CPU1_SA_CS_N<0>")
		)
		(pad "65" smd rect
			(at -2.050034 -8.925052 270)
			(size 0.519938 1.4986)
			(layers "F.Cu" "F.Mask" "F.Paste")
			(net "GND")
		)
		(pad "66" smd rect
			(at -2.050034 -8.074914 270)
			(size 0.519938 1.4986)
			(layers "F.Cu" "F.Mask" "F.Paste")
			(net "M_F_CPU1_SA_CA<0>")
		)
		(pad "67" smd rect
			(at -2.050034 -7.22503 270)
			(size 0.519938 1.4986)
			(layers "F.Cu" "F.Mask" "F.Paste")
			(net "GND")
		)
		(pad "68" smd rect
			(at -2.050034 -6.374892 270)
			(size 0.519938 1.4986)
			(layers "F.Cu" "F.Mask" "F.Paste")
			(net "M_F_CPU1_SA_CA<2>")
		)
		(pad "69" smd rect
			(at -2.050034 -5.525008 270)
			(size 0.519938 1.4986)
			(layers "F.Cu" "F.Mask" "F.Paste")
			(net "GND")
		)
		(pad "70" smd rect
			(at -2.050034 -4.675124 270)
			(size 0.519938 1.4986)
			(layers "F.Cu" "F.Mask" "F.Paste")
			(net "M_F_CPU1_SA_CA<4>")
		)
		(pad "71" smd rect
			(at -2.050034 -3.824986 270)
			(size 0.519938 1.4986)
			(layers "F.Cu" "F.Mask" "F.Paste")
			(net "GND")
		)
		(pad "72" smd rect
			(at -2.050034 -2.975102 270)
			(size 0.519938 1.4986)
			(layers "F.Cu" "F.Mask" "F.Paste")
			(net "M_F_CPU1_SA_CA<6>")
		)
		(pad "73" smd rect
			(at -2.050034 -2.124964 270)
			(size 0.519938 1.4986)
			(layers "F.Cu" "F.Mask" "F.Paste")
			(net "GND")
		)
		(pad "74" smd rect
			(at -2.050034 -1.27508 270)
			(size 0.519938 1.4986)
			(layers "F.Cu" "F.Mask" "F.Paste")
			(net "M_F_CPU1_SA_PAR")
		)
		(pad "75" smd rect
			(at -2.050034 -0.424942 270)
			(size 0.519938 1.4986)
			(layers "F.Cu" "F.Mask" "F.Paste")
			(net "GND")
		)
		(pad "76" smd rect
			(at -2.050034 5.525008 270)
			(size 0.519938 1.4986)
			(layers "F.Cu" "F.Mask" "F.Paste")
			(net "M_F_CPU1_SB_CA<0>")
		)
		(pad "77" smd rect
			(at -2.050034 6.374892 270)
			(size 0.519938 1.4986)
			(layers "F.Cu" "F.Mask" "F.Paste")
			(net "GND")
		)
		(pad "78" smd rect
			(at -2.050034 7.22503 270)
			(size 0.519938 1.4986)
			(layers "F.Cu" "F.Mask" "F.Paste")
			(net "M_F_CPU1_SB_CA<2>")
		)
		(pad "79" smd rect
			(at -2.050034 8.074914 270)
			(size 0.519938 1.4986)
			(layers "F.Cu" "F.Mask" "F.Paste")
			(net "GND")
		)
		(pad "80" smd rect
			(at -2.050034 8.925052 270)
			(size 0.519938 1.4986)
			(layers "F.Cu" "F.Mask" "F.Paste")
			(net "M_F_CPU1_SB_CA<4>")
		)
		(pad "81" smd rect
			(at -2.050034 9.774936 270)
			(size 0.519938 1.4986)
			(layers "F.Cu" "F.Mask" "F.Paste")
			(net "GND")
		)
		(pad "82" smd rect
			(at -2.050034 10.625074 270)
			(size 0.519938 1.4986)
			(layers "F.Cu" "F.Mask" "F.Paste")
			(net "M_F_CPU1_SB_CA<6>")
		)
		(pad "83" smd rect
			(at -2.050034 11.474958 270)
			(size 0.519938 1.4986)
			(layers "F.Cu" "F.Mask" "F.Paste")
			(net "GND")
		)
		(pad "84" smd rect
			(at -2.050034 12.325096 270)
			(size 0.519938 1.4986)
			(layers "F.Cu" "F.Mask" "F.Paste")
			(net "M_F_CPU1_SB_CS_N<0>")
		)
		(pad "85" smd rect
			(at -2.050034 13.17498 270)
			(size 0.519938 1.4986)
			(layers "F.Cu" "F.Mask" "F.Paste")
			(net "GND")
		)
		(pad "86" smd rect
			(at -2.050034 14.025118 270)
			(size 0.519938 1.4986)
			(layers "F.Cu" "F.Mask" "F.Paste")
			(net "M_F_CPU1_SA_RSP<0>")
		)
		(pad "87" smd rect
			(at -2.050034 14.875002 270)
			(size 0.519938 1.4986)
			(layers "F.Cu" "F.Mask" "F.Paste")
			(net "M_F_CPU1_SB_RSP<0>")
		)
		(pad "88" smd rect
			(at -2.050034 15.724886 270)
			(size 0.519938 1.4986)
			(layers "F.Cu" "F.Mask" "F.Paste")
			(net "GND")
		)
		(pad "89" smd rect
			(at -2.050034 16.575024 270)
			(size 0.519938 1.4986)
			(layers "F.Cu" "F.Mask" "F.Paste")
			(net "M_F_CPU1_SB_CB<4>")
		)
		(pad "90" smd rect
			(at -2.050034 17.424908 270)
			(size 0.519938 1.4986)
			(layers "F.Cu" "F.Mask" "F.Paste")
			(net "GND")
		)
		(pad "91" smd rect
			(at -2.050034 18.275046 270)
			(size 0.519938 1.4986)
			(layers "F.Cu" "F.Mask" "F.Paste")
			(net "M_F_CPU1_SB_CB<5>")
		)
		(pad "92" smd rect
			(at -2.050034 19.12493 270)
			(size 0.519938 1.4986)
			(layers "F.Cu" "F.Mask" "F.Paste")
			(net "GND")
		)
		(pad "93" smd rect
			(at -2.050034 19.975068 270)
			(size 0.519938 1.4986)
			(layers "F.Cu" "F.Mask" "F.Paste")
			(net "M_F_CPU1_SB_DQS_DP<9>")
		)
		(pad "94" smd rect
			(at -2.050034 20.824952 270)
			(size 0.519938 1.4986)
			(layers "F.Cu" "F.Mask" "F.Paste")
			(net "M_F_CPU1_SB_DQS_DN<9>")
		)
		(pad "95" smd rect
			(at -2.050034 21.67509 270)
			(size 0.519938 1.4986)
			(layers "F.Cu" "F.Mask" "F.Paste")
			(net "GND")
		)
		(pad "96" smd rect
			(at -2.050034 22.524974 270)
			(size 0.519938 1.4986)
			(layers "F.Cu" "F.Mask" "F.Paste")
			(net "M_F_CPU1_SB_CB<0>")
		)
		(pad "97" smd rect
			(at -2.050034 23.375112 270)
			(size 0.519938 1.4986)
			(layers "F.Cu" "F.Mask" "F.Paste")
			(net "GND")
		)
		(pad "98" smd rect
			(at -2.050034 24.224996 270)
			(size 0.519938 1.4986)
			(layers "F.Cu" "F.Mask" "F.Paste")
			(net "M_F_CPU1_SB_CB<1>")
		)
		(pad "99" smd rect
			(at -2.050034 25.07488 270)
			(size 0.519938 1.4986)
			(layers "F.Cu" "F.Mask" "F.Paste")
			(net "GND")
		)
		(pad "100" smd rect
			(at -2.050034 25.925018 270)
			(size 0.519938 1.4986)
			(layers "F.Cu" "F.Mask" "F.Paste")
			(net "M_F_CPU1_SB_DQ<0>")
		)
		(pad "101" smd rect
			(at -2.050034 26.774902 270)
			(size 0.519938 1.4986)
			(layers "F.Cu" "F.Mask" "F.Paste")
			(net "GND")
		)
		(pad "102" smd rect
			(at -2.050034 27.62504 270)
			(size 0.519938 1.4986)
			(layers "F.Cu" "F.Mask" "F.Paste")
			(net "M_F_CPU1_SB_DQ<1>")
		)
		(pad "103" smd rect
			(at -2.050034 28.474924 270)
			(size 0.519938 1.4986)
			(layers "F.Cu" "F.Mask" "F.Paste")
			(net "GND")
		)
		(pad "104" smd rect
			(at -2.050034 29.325062 270)
			(size 0.519938 1.4986)
			(layers "F.Cu" "F.Mask" "F.Paste")
			(net "M_F_CPU1_SB_DQS_DP<0>")
		)
		(pad "105" smd rect
			(at -2.050034 30.174946 270)
			(size 0.519938 1.4986)
			(layers "F.Cu" "F.Mask" "F.Paste")
			(net "M_F_CPU1_SB_DQS_DN<0>")
		)
		(pad "106" smd rect
			(at -2.050034 31.025084 270)
			(size 0.519938 1.4986)
			(layers "F.Cu" "F.Mask" "F.Paste")
			(net "GND")
		)
		(pad "107" smd rect
			(at -2.050034 31.874968 270)
			(size 0.519938 1.4986)
			(layers "F.Cu" "F.Mask" "F.Paste")
			(net "M_F_CPU1_SB_DQ<4>")
		)
		(pad "108" smd rect
			(at -2.050034 32.725106 270)
			(size 0.519938 1.4986)
			(layers "F.Cu" "F.Mask" "F.Paste")
			(net "GND")
		)
		(pad "109" smd rect
			(at -2.050034 33.57499 270)
			(size 0.519938 1.4986)
			(layers "F.Cu" "F.Mask" "F.Paste")
			(net "M_F_CPU1_SB_DQ<5>")
		)
		(pad "110" smd rect
			(at -2.050034 34.425128 270)
			(size 0.519938 1.4986)
			(layers "F.Cu" "F.Mask" "F.Paste")
			(net "GND")
		)
		(pad "111" smd rect
			(at -2.050034 35.275012 270)
			(size 0.519938 1.4986)
			(layers "F.Cu" "F.Mask" "F.Paste")
			(net "M_F_CPU1_SB_DQ<8>")
		)
		(pad "112" smd rect
			(at -2.050034 36.124896 270)
			(size 0.519938 1.4986)
			(layers "F.Cu" "F.Mask" "F.Paste")
			(net "GND")
		)
		(pad "113" smd rect
			(at -2.050034 36.975034 270)
			(size 0.519938 1.4986)
			(layers "F.Cu" "F.Mask" "F.Paste")
			(net "M_F_CPU1_SB_DQ<9>")
		)
		(pad "114" smd rect
			(at -2.050034 37.824918 270)
			(size 0.519938 1.4986)
			(layers "F.Cu" "F.Mask" "F.Paste")
			(net "GND")
		)
		(pad "115" smd rect
			(at -2.050034 38.675056 270)
			(size 0.519938 1.4986)
			(layers "F.Cu" "F.Mask" "F.Paste")
			(net "M_F_CPU1_SB_DQS_DP<1>")
		)
		(pad "116" smd rect
			(at -2.050034 39.52494 270)
			(size 0.519938 1.4986)
			(layers "F.Cu" "F.Mask" "F.Paste")
			(net "M_F_CPU1_SB_DQS_DN<1>")
		)
		(pad "117" smd rect
			(at -2.050034 40.375078 270)
			(size 0.519938 1.4986)
			(layers "F.Cu" "F.Mask" "F.Paste")
			(net "GND")
		)
		(pad "118" smd rect
			(at -2.050034 41.224962 270)
			(size 0.519938 1.4986)
			(layers "F.Cu" "F.Mask" "F.Paste")
			(net "M_F_CPU1_SB_DQ<12>")
		)
		(pad "119" smd rect
			(at -2.050034 42.0751 270)
			(size 0.519938 1.4986)
			(layers "F.Cu" "F.Mask" "F.Paste")
			(net "GND")
		)
		(pad "120" smd rect
			(at -2.050034 42.924984 270)
			(size 0.519938 1.4986)
			(layers "F.Cu" "F.Mask" "F.Paste")
			(net "M_F_CPU1_SB_DQ<13>")
		)
		(pad "121" smd rect
			(at -2.050034 43.775122 270)
			(size 0.519938 1.4986)
			(layers "F.Cu" "F.Mask" "F.Paste")
			(net "GND")
		)
		(pad "122" smd rect
			(at -2.050034 44.625006 270)
			(size 0.519938 1.4986)
			(layers "F.Cu" "F.Mask" "F.Paste")
			(net "M_F_CPU1_SB_DQ<16>")
		)
		(pad "123" smd rect
			(at -2.050034 45.47489 270)
			(size 0.519938 1.4986)
			(layers "F.Cu" "F.Mask" "F.Paste")
			(net "GND")
		)
		(pad "124" smd rect
			(at -2.050034 46.325028 270)
			(size 0.519938 1.4986)
			(layers "F.Cu" "F.Mask" "F.Paste")
			(net "M_F_CPU1_SB_DQ<17>")
		)
		(pad "125" smd rect
			(at -2.050034 47.174912 270)
			(size 0.519938 1.4986)
			(layers "F.Cu" "F.Mask" "F.Paste")
			(net "GND")
		)
		(pad "126" smd rect
			(at -2.050034 48.02505 270)
			(size 0.519938 1.4986)
			(layers "F.Cu" "F.Mask" "F.Paste")
			(net "M_F_CPU1_SB_DQS_DP<2>")
		)
		(pad "127" smd rect
			(at -2.050034 48.874934 270)
			(size 0.519938 1.4986)
			(layers "F.Cu" "F.Mask" "F.Paste")
			(net "M_F_CPU1_SB_DQS_DN<2>")
		)
		(pad "128" smd rect
			(at -2.050034 49.725072 270)
			(size 0.519938 1.4986)
			(layers "F.Cu" "F.Mask" "F.Paste")
			(net "GND")
		)
		(pad "129" smd rect
			(at -2.050034 50.574956 270)
			(size 0.519938 1.4986)
			(layers "F.Cu" "F.Mask" "F.Paste")
			(net "M_F_CPU1_SB_DQ<20>")
		)
		(pad "130" smd rect
			(at -2.050034 51.425094 270)
			(size 0.519938 1.4986)
			(layers "F.Cu" "F.Mask" "F.Paste")
			(net "GND")
		)
		(pad "131" smd rect
			(at -2.050034 52.274978 270)
			(size 0.519938 1.4986)
			(layers "F.Cu" "F.Mask" "F.Paste")
			(net "M_F_CPU1_SB_DQ<21>")
		)
		(pad "132" smd rect
			(at -2.050034 53.125116 270)
			(size 0.519938 1.4986)
			(layers "F.Cu" "F.Mask" "F.Paste")
			(net "GND")
		)
		(pad "133" smd rect
			(at -2.050034 53.975 270)
			(size 0.519938 1.4986)
			(layers "F.Cu" "F.Mask" "F.Paste")
			(net "M_F_CPU1_SB_DQ<24>")
		)
		(pad "134" smd rect
			(at -2.050034 54.824884 270)
			(size 0.519938 1.4986)
			(layers "F.Cu" "F.Mask" "F.Paste")
			(net "GND")
		)
		(pad "135" smd rect
			(at -2.050034 55.675022 270)
			(size 0.519938 1.4986)
			(layers "F.Cu" "F.Mask" "F.Paste")
			(net "M_F_CPU1_SB_DQ<25>")
		)
		(pad "136" smd rect
			(at -2.050034 56.524906 270)
			(size 0.519938 1.4986)
			(layers "F.Cu" "F.Mask" "F.Paste")
			(net "GND")
		)
		(pad "137" smd rect
			(at -2.050034 57.375044 270)
			(size 0.519938 1.4986)
			(layers "F.Cu" "F.Mask" "F.Paste")
			(net "M_F_CPU1_SB_DQS_DP<3>")
		)
		(pad "138" smd rect
			(at -2.050034 58.224928 270)
			(size 0.519938 1.4986)
			(layers "F.Cu" "F.Mask" "F.Paste")
			(net "M_F_CPU1_SB_DQS_DN<3>")
		)
		(pad "139" smd rect
			(at -2.050034 59.075066 270)
			(size 0.519938 1.4986)
			(layers "F.Cu" "F.Mask" "F.Paste")
			(net "GND")
		)
		(pad "140" smd rect
			(at -2.050034 59.92495 270)
			(size 0.519938 1.4986)
			(layers "F.Cu" "F.Mask" "F.Paste")
			(net "M_F_CPU1_SB_DQ<28>")
		)
		(pad "141" smd rect
			(at -2.050034 60.775088 270)
			(size 0.519938 1.4986)
			(layers "F.Cu" "F.Mask" "F.Paste")
			(net "GND")
		)
		(pad "142" smd rect
			(at -2.050034 61.624972 270)
			(size 0.519938 1.4986)
			(layers "F.Cu" "F.Mask" "F.Paste")
			(net "M_F_CPU1_SB_DQ<29>")
		)
		(pad "143" smd rect
			(at -2.050034 62.47511 270)
			(size 0.519938 1.4986)
			(layers "F.Cu" "F.Mask" "F.Paste")
			(net "GND")
		)
		(pad "144" smd rect
			(at -2.050034 63.324994 270)
			(size 0.519938 1.4986)
			(layers "F.Cu" "F.Mask" "F.Paste")
			(net "TP_CHF_CPU1_DIMM1_FRU_1")
		)
		(pad "145" smd rect
			(at 2.050034 -63.324994 270)
			(size 0.519938 1.4986)
			(layers "F.Cu" "F.Mask" "F.Paste")
			(net "P12V_S3_AUX_CPU1_NVDIMM")
		)
		(pad "146" smd rect
			(at 2.050034 -62.47511 270)
			(size 0.519938 1.4986)
			(layers "F.Cu" "F.Mask" "F.Paste")
			(net "P12V_S3_AUX_CPU1_NVDIMM")
		)
		(pad "147" smd rect
			(at 2.050034 -61.624972 270)
			(size 0.519938 1.4986)
			(layers "F.Cu" "F.Mask" "F.Paste")
			(net "PWRGD_CHF_CPU1_DIMM1")
		)
		(pad "148" smd rect
			(at 2.050034 -60.775088 270)
			(size 0.519938 1.4986)
			(layers "F.Cu" "F.Mask" "F.Paste")
			(net "PD_CHF_CPU1_DIMM1_SAA")
		)
		(pad "149" smd rect
			(at 2.050034 -59.92495 270)
			(size 0.519938 1.4986)
			(layers "F.Cu" "F.Mask" "F.Paste")
			(net "TP_CHF_CPU1_DIMM1_FRU_2")
		)
		(pad "150" smd rect
			(at 2.050034 -59.075066 270)
			(size 0.519938 1.4986)
			(layers "F.Cu" "F.Mask" "F.Paste")
			(net "TP_CHF_CPU1_DIMM1_FRU_3")
		)
		(pad "151" smd rect
			(at 2.050034 -58.224928 270)
			(size 0.519938 1.4986)
			(layers "F.Cu" "F.Mask" "F.Paste")
			(net "GND")
		)
		(pad "152" smd rect
			(at 2.050034 -57.375044 270)
			(size 0.519938 1.4986)
			(layers "F.Cu" "F.Mask" "F.Paste")
			(net "M_F_CPU1_SA_DQ<2>")
		)
		(pad "153" smd rect
			(at 2.050034 -56.524906 270)
			(size 0.519938 1.4986)
			(layers "F.Cu" "F.Mask" "F.Paste")
			(net "GND")
		)
		(pad "154" smd rect
			(at 2.050034 -55.675022 270)
			(size 0.519938 1.4986)
			(layers "F.Cu" "F.Mask" "F.Paste")
			(net "M_F_CPU1_SA_DQ<3>")
		)
		(pad "155" smd rect
			(at 2.050034 -54.824884 270)
			(size 0.519938 1.4986)
			(layers "F.Cu" "F.Mask" "F.Paste")
			(net "GND")
		)
		(pad "156" smd rect
			(at 2.050034 -53.975 270)
			(size 0.519938 1.4986)
			(layers "F.Cu" "F.Mask" "F.Paste")
			(net "M_F_CPU1_SA_DQS_DN<5>")
		)
		(pad "157" smd rect
			(at 2.050034 -53.125116 270)
			(size 0.519938 1.4986)
			(layers "F.Cu" "F.Mask" "F.Paste")
			(net "M_F_CPU1_SA_DQS_DP<5>")
		)
		(pad "158" smd rect
			(at 2.050034 -52.274978 270)
			(size 0.519938 1.4986)
			(layers "F.Cu" "F.Mask" "F.Paste")
			(net "GND")
		)
		(pad "159" smd rect
			(at 2.050034 -51.425094 270)
			(size 0.519938 1.4986)
			(layers "F.Cu" "F.Mask" "F.Paste")
			(net "M_F_CPU1_SA_DQ<6>")
		)
		(pad "160" smd rect
			(at 2.050034 -50.574956 270)
			(size 0.519938 1.4986)
			(layers "F.Cu" "F.Mask" "F.Paste")
			(net "GND")
		)
		(pad "161" smd rect
			(at 2.050034 -49.725072 270)
			(size 0.519938 1.4986)
			(layers "F.Cu" "F.Mask" "F.Paste")
			(net "M_F_CPU1_SA_DQ<7>")
		)
		(pad "162" smd rect
			(at 2.050034 -48.874934 270)
			(size 0.519938 1.4986)
			(layers "F.Cu" "F.Mask" "F.Paste")
			(net "GND")
		)
		(pad "163" smd rect
			(at 2.050034 -48.02505 270)
			(size 0.519938 1.4986)
			(layers "F.Cu" "F.Mask" "F.Paste")
			(net "M_F_CPU1_SA_DQ<10>")
		)
		(pad "164" smd rect
			(at 2.050034 -47.174912 270)
			(size 0.519938 1.4986)
			(layers "F.Cu" "F.Mask" "F.Paste")
			(net "GND")
		)
		(pad "165" smd rect
			(at 2.050034 -46.325028 270)
			(size 0.519938 1.4986)
			(layers "F.Cu" "F.Mask" "F.Paste")
			(net "M_F_CPU1_SA_DQ<11>")
		)
		(pad "166" smd rect
			(at 2.050034 -45.47489 270)
			(size 0.519938 1.4986)
			(layers "F.Cu" "F.Mask" "F.Paste")
			(net "GND")
		)
		(pad "167" smd rect
			(at 2.050034 -44.625006 270)
			(size 0.519938 1.4986)
			(layers "F.Cu" "F.Mask" "F.Paste")
			(net "M_F_CPU1_SA_DQS_DN<6>")
		)
		(pad "168" smd rect
			(at 2.050034 -43.775122 270)
			(size 0.519938 1.4986)
			(layers "F.Cu" "F.Mask" "F.Paste")
			(net "M_F_CPU1_SA_DQS_DP<6>")
		)
		(pad "169" smd rect
			(at 2.050034 -42.924984 270)
			(size 0.519938 1.4986)
			(layers "F.Cu" "F.Mask" "F.Paste")
			(net "GND")
		)
		(pad "170" smd rect
			(at 2.050034 -42.0751 270)
			(size 0.519938 1.4986)
			(layers "F.Cu" "F.Mask" "F.Paste")
			(net "M_F_CPU1_SA_DQ<14>")
		)
		(pad "171" smd rect
			(at 2.050034 -41.224962 270)
			(size 0.519938 1.4986)
			(layers "F.Cu" "F.Mask" "F.Paste")
			(net "GND")
		)
		(pad "172" smd rect
			(at 2.050034 -40.375078 270)
			(size 0.519938 1.4986)
			(layers "F.Cu" "F.Mask" "F.Paste")
			(net "M_F_CPU1_SA_DQ<15>")
		)
		(pad "173" smd rect
			(at 2.050034 -39.52494 270)
			(size 0.519938 1.4986)
			(layers "F.Cu" "F.Mask" "F.Paste")
			(net "GND")
		)
		(pad "174" smd rect
			(at 2.050034 -38.675056 270)
			(size 0.519938 1.4986)
			(layers "F.Cu" "F.Mask" "F.Paste")
			(net "M_F_CPU1_SA_DQ<18>")
		)
		(pad "175" smd rect
			(at 2.050034 -37.824918 270)
			(size 0.519938 1.4986)
			(layers "F.Cu" "F.Mask" "F.Paste")
			(net "GND")
		)
		(pad "176" smd rect
			(at 2.050034 -36.975034 270)
			(size 0.519938 1.4986)
			(layers "F.Cu" "F.Mask" "F.Paste")
			(net "M_F_CPU1_SA_DQ<19>")
		)
		(pad "177" smd rect
			(at 2.050034 -36.124896 270)
			(size 0.519938 1.4986)
			(layers "F.Cu" "F.Mask" "F.Paste")
			(net "GND")
		)
		(pad "178" smd rect
			(at 2.050034 -35.275012 270)
			(size 0.519938 1.4986)
			(layers "F.Cu" "F.Mask" "F.Paste")
			(net "M_F_CPU1_SA_DQS_DN<7>")
		)
		(pad "179" smd rect
			(at 2.050034 -34.425128 270)
			(size 0.519938 1.4986)
			(layers "F.Cu" "F.Mask" "F.Paste")
			(net "M_F_CPU1_SA_DQS_DP<7>")
		)
		(pad "180" smd rect
			(at 2.050034 -33.57499 270)
			(size 0.519938 1.4986)
			(layers "F.Cu" "F.Mask" "F.Paste")
			(net "GND")
		)
		(pad "181" smd rect
			(at 2.050034 -32.725106 270)
			(size 0.519938 1.4986)
			(layers "F.Cu" "F.Mask" "F.Paste")
			(net "M_F_CPU1_SA_DQ<22>")
		)
		(pad "182" smd rect
			(at 2.050034 -31.874968 270)
			(size 0.519938 1.4986)
			(layers "F.Cu" "F.Mask" "F.Paste")
			(net "GND")
		)
		(pad "183" smd rect
			(at 2.050034 -31.025084 270)
			(size 0.519938 1.4986)
			(layers "F.Cu" "F.Mask" "F.Paste")
			(net "M_F_CPU1_SA_DQ<23>")
		)
		(pad "184" smd rect
			(at 2.050034 -30.174946 270)
			(size 0.519938 1.4986)
			(layers "F.Cu" "F.Mask" "F.Paste")
			(net "GND")
		)
		(pad "185" smd rect
			(at 2.050034 -29.325062 270)
			(size 0.519938 1.4986)
			(layers "F.Cu" "F.Mask" "F.Paste")
			(net "M_F_CPU1_SA_DQ<26>")
		)
		(pad "186" smd rect
			(at 2.050034 -28.474924 270)
			(size 0.519938 1.4986)
			(layers "F.Cu" "F.Mask" "F.Paste")
			(net "GND")
		)
		(pad "187" smd rect
			(at 2.050034 -27.62504 270)
			(size 0.519938 1.4986)
			(layers "F.Cu" "F.Mask" "F.Paste")
			(net "M_F_CPU1_SA_DQ<27>")
		)
		(pad "188" smd rect
			(at 2.050034 -26.774902 270)
			(size 0.519938 1.4986)
			(layers "F.Cu" "F.Mask" "F.Paste")
			(net "GND")
		)
		(pad "189" smd rect
			(at 2.050034 -25.925018 270)
			(size 0.519938 1.4986)
			(layers "F.Cu" "F.Mask" "F.Paste")
			(net "M_F_CPU1_SA_DQS_DN<8>")
		)
		(pad "190" smd rect
			(at 2.050034 -25.07488 270)
			(size 0.519938 1.4986)
			(layers "F.Cu" "F.Mask" "F.Paste")
			(net "M_F_CPU1_SA_DQS_DP<8>")
		)
		(pad "191" smd rect
			(at 2.050034 -24.224996 270)
			(size 0.519938 1.4986)
			(layers "F.Cu" "F.Mask" "F.Paste")
			(net "GND")
		)
		(pad "192" smd rect
			(at 2.050034 -23.375112 270)
			(size 0.519938 1.4986)
			(layers "F.Cu" "F.Mask" "F.Paste")
			(net "M_F_CPU1_SA_DQ<30>")
		)
		(pad "193" smd rect
			(at 2.050034 -22.524974 270)
			(size 0.519938 1.4986)
			(layers "F.Cu" "F.Mask" "F.Paste")
			(net "GND")
		)
		(pad "194" smd rect
			(at 2.050034 -21.67509 270)
			(size 0.519938 1.4986)
			(layers "F.Cu" "F.Mask" "F.Paste")
			(net "M_F_CPU1_SA_DQ<31>")
		)
		(pad "195" smd rect
			(at 2.050034 -20.824952 270)
			(size 0.519938 1.4986)
			(layers "F.Cu" "F.Mask" "F.Paste")
			(net "GND")
		)
		(pad "196" smd rect
			(at 2.050034 -19.975068 270)
			(size 0.519938 1.4986)
			(layers "F.Cu" "F.Mask" "F.Paste")
			(net "M_F_CPU1_SA_CB<2>")
		)
		(pad "197" smd rect
			(at 2.050034 -19.12493 270)
			(size 0.519938 1.4986)
			(layers "F.Cu" "F.Mask" "F.Paste")
			(net "GND")
		)
		(pad "198" smd rect
			(at 2.050034 -18.275046 270)
			(size 0.519938 1.4986)
			(layers "F.Cu" "F.Mask" "F.Paste")
			(net "M_F_CPU1_SA_CB<3>")
		)
		(pad "199" smd rect
			(at 2.050034 -17.424908 270)
			(size 0.519938 1.4986)
			(layers "F.Cu" "F.Mask" "F.Paste")
			(net "GND")
		)
		(pad "200" smd rect
			(at 2.050034 -16.575024 270)
			(size 0.519938 1.4986)
			(layers "F.Cu" "F.Mask" "F.Paste")
			(net "M_F_CPU1_SA_DQS_DN<9>")
		)
		(pad "201" smd rect
			(at 2.050034 -15.724886 270)
			(size 0.519938 1.4986)
			(layers "F.Cu" "F.Mask" "F.Paste")
			(net "M_F_CPU1_SA_DQS_DP<9>")
		)
		(pad "202" smd rect
			(at 2.050034 -14.875002 270)
			(size 0.519938 1.4986)
			(layers "F.Cu" "F.Mask" "F.Paste")
			(net "GND")
		)
		(pad "203" smd rect
			(at 2.050034 -14.025118 270)
			(size 0.519938 1.4986)
			(layers "F.Cu" "F.Mask" "F.Paste")
			(net "M_F_CPU1_SA_CB<6>")
		)
		(pad "204" smd rect
			(at 2.050034 -13.17498 270)
			(size 0.519938 1.4986)
			(layers "F.Cu" "F.Mask" "F.Paste")
			(net "GND")
		)
		(pad "205" smd rect
			(at 2.050034 -12.325096 270)
			(size 0.519938 1.4986)
			(layers "F.Cu" "F.Mask" "F.Paste")
			(net "M_F_CPU1_SA_CB<7>")
		)
		(pad "206" smd rect
			(at 2.050034 -11.474958 270)
			(size 0.519938 1.4986)
			(layers "F.Cu" "F.Mask" "F.Paste")
			(net "GND")
		)
		(pad "207" smd rect
			(at 2.050034 -10.625074 270)
			(size 0.519938 1.4986)
			(layers "F.Cu" "F.Mask" "F.Paste")
			(net "RST_M_EF_CPU1_FPGA_N")
		)
		(pad "208" smd rect
			(at 2.050034 -9.774936 270)
			(size 0.519938 1.4986)
			(layers "F.Cu" "F.Mask" "F.Paste")
			(net "GND")
		)
		(pad "209" smd rect
			(at 2.050034 -8.925052 270)
			(size 0.519938 1.4986)
			(layers "F.Cu" "F.Mask" "F.Paste")
			(net "M_F_CPU1_SA_CS_N<1>")
		)
		(pad "210" smd rect
			(at 2.050034 -8.074914 270)
			(size 0.519938 1.4986)
			(layers "F.Cu" "F.Mask" "F.Paste")
			(net "GND")
		)
		(pad "211" smd rect
			(at 2.050034 -7.22503 270)
			(size 0.519938 1.4986)
			(layers "F.Cu" "F.Mask" "F.Paste")
			(net "M_F_CPU1_SA_CA<1>")
		)
		(pad "212" smd rect
			(at 2.050034 -6.374892 270)
			(size 0.519938 1.4986)
			(layers "F.Cu" "F.Mask" "F.Paste")
			(net "GND")
		)
		(pad "213" smd rect
			(at 2.050034 -5.525008 270)
			(size 0.519938 1.4986)
			(layers "F.Cu" "F.Mask" "F.Paste")
			(net "M_F_CPU1_SA_CA<3>")
		)
		(pad "214" smd rect
			(at 2.050034 -4.675124 270)
			(size 0.519938 1.4986)
			(layers "F.Cu" "F.Mask" "F.Paste")
			(net "GND")
		)
		(pad "215" smd rect
			(at 2.050034 -3.824986 270)
			(size 0.519938 1.4986)
			(layers "F.Cu" "F.Mask" "F.Paste")
			(net "M_F_CPU1_SA_CA<5>")
		)
		(pad "216" smd rect
			(at 2.050034 -2.975102 270)
			(size 0.519938 1.4986)
			(layers "F.Cu" "F.Mask" "F.Paste")
			(net "GND")
		)
		(pad "217" smd rect
			(at 2.050034 -2.124964 270)
			(size 0.519938 1.4986)
			(layers "F.Cu" "F.Mask" "F.Paste")
			(net "M_F_CPU1_CLK_DP<0>")
		)
		(pad "218" smd rect
			(at 2.050034 -1.27508 270)
			(size 0.519938 1.4986)
			(layers "F.Cu" "F.Mask" "F.Paste")
			(net "M_F_CPU1_CLK_DN<0>")
		)
		(pad "219" smd rect
			(at 2.050034 -0.424942 270)
			(size 0.519938 1.4986)
			(layers "F.Cu" "F.Mask" "F.Paste")
			(net "GND")
		)
		(pad "220" smd rect
			(at 2.050034 5.525008 270)
			(size 0.519938 1.4986)
			(layers "F.Cu" "F.Mask" "F.Paste")
			(net "TP_CHF_CPU1_DIMM1_FRU_4")
		)
		(pad "221" smd rect
			(at 2.050034 6.374892 270)
			(size 0.519938 1.4986)
			(layers "F.Cu" "F.Mask" "F.Paste")
			(net "M_F_CPU1_SB_CA<1>")
		)
		(pad "222" smd rect
			(at 2.050034 7.22503 270)
			(size 0.519938 1.4986)
			(layers "F.Cu" "F.Mask" "F.Paste")
			(net "GND")
		)
		(pad "223" smd rect
			(at 2.050034 8.074914 270)
			(size 0.519938 1.4986)
			(layers "F.Cu" "F.Mask" "F.Paste")
			(net "M_F_CPU1_SB_CA<3>")
		)
		(pad "224" smd rect
			(at 2.050034 8.925052 270)
			(size 0.519938 1.4986)
			(layers "F.Cu" "F.Mask" "F.Paste")
			(net "GND")
		)
		(pad "225" smd rect
			(at 2.050034 9.774936 270)
			(size 0.519938 1.4986)
			(layers "F.Cu" "F.Mask" "F.Paste")
			(net "M_F_CPU1_SB_CA<5>")
		)
		(pad "226" smd rect
			(at 2.050034 10.625074 270)
			(size 0.519938 1.4986)
			(layers "F.Cu" "F.Mask" "F.Paste")
			(net "GND")
		)
		(pad "227" smd rect
			(at 2.050034 11.474958 270)
			(size 0.519938 1.4986)
			(layers "F.Cu" "F.Mask" "F.Paste")
			(net "M_F_CPU1_SB_PAR")
		)
		(pad "228" smd rect
			(at 2.050034 12.325096 270)
			(size 0.519938 1.4986)
			(layers "F.Cu" "F.Mask" "F.Paste")
			(net "GND")
		)
		(pad "229" smd rect
			(at 2.050034 13.17498 270)
			(size 0.519938 1.4986)
			(layers "F.Cu" "F.Mask" "F.Paste")
			(net "M_F_CPU1_SB_CS_N<1>")
		)
		(pad "230" smd rect
			(at 2.050034 14.025118 270)
			(size 0.519938 1.4986)
			(layers "F.Cu" "F.Mask" "F.Paste")
			(net "GND")
		)
		(pad "231" smd rect
			(at 2.050034 14.875002 270)
			(size 0.519938 1.4986)
			(layers "F.Cu" "F.Mask" "F.Paste")
			(net "TP_CHF_CPU1_DIMM1_FRU_5")
		)
		(pad "232" smd rect
			(at 2.050034 15.724886 270)
			(size 0.519938 1.4986)
			(layers "F.Cu" "F.Mask" "F.Paste")
			(net "TP_CHF_CPU1_DIMM1_FRU_6")
		)
		(pad "233" smd rect
			(at 2.050034 16.575024 270)
			(size 0.519938 1.4986)
			(layers "F.Cu" "F.Mask" "F.Paste")
			(net "GND")
		)
		(pad "234" smd rect
			(at 2.050034 17.424908 270)
			(size 0.519938 1.4986)
			(layers "F.Cu" "F.Mask" "F.Paste")
			(net "M_F_CPU1_SB_CB<6>")
		)
		(pad "235" smd rect
			(at 2.050034 18.275046 270)
			(size 0.519938 1.4986)
			(layers "F.Cu" "F.Mask" "F.Paste")
			(net "GND")
		)
		(pad "236" smd rect
			(at 2.050034 19.12493 270)
			(size 0.519938 1.4986)
			(layers "F.Cu" "F.Mask" "F.Paste")
			(net "M_F_CPU1_SB_CB<7>")
		)
		(pad "237" smd rect
			(at 2.050034 19.975068 270)
			(size 0.519938 1.4986)
			(layers "F.Cu" "F.Mask" "F.Paste")
			(net "GND")
		)
		(pad "238" smd rect
			(at 2.050034 20.824952 270)
			(size 0.519938 1.4986)
			(layers "F.Cu" "F.Mask" "F.Paste")
			(net "M_F_CPU1_SB_DQS_DN<4>")
		)
		(pad "239" smd rect
			(at 2.050034 21.67509 270)
			(size 0.519938 1.4986)
			(layers "F.Cu" "F.Mask" "F.Paste")
			(net "M_F_CPU1_SB_DQS_DP<4>")
		)
		(pad "240" smd rect
			(at 2.050034 22.524974 270)
			(size 0.519938 1.4986)
			(layers "F.Cu" "F.Mask" "F.Paste")
			(net "GND")
		)
		(pad "241" smd rect
			(at 2.050034 23.375112 270)
			(size 0.519938 1.4986)
			(layers "F.Cu" "F.Mask" "F.Paste")
			(net "M_F_CPU1_SB_CB<2>")
		)
		(pad "242" smd rect
			(at 2.050034 24.224996 270)
			(size 0.519938 1.4986)
			(layers "F.Cu" "F.Mask" "F.Paste")
			(net "GND")
		)
		(pad "243" smd rect
			(at 2.050034 25.07488 270)
			(size 0.519938 1.4986)
			(layers "F.Cu" "F.Mask" "F.Paste")
			(net "M_F_CPU1_SB_CB<3>")
		)
		(pad "244" smd rect
			(at 2.050034 25.925018 270)
			(size 0.519938 1.4986)
			(layers "F.Cu" "F.Mask" "F.Paste")
			(net "GND")
		)
		(pad "245" smd rect
			(at 2.050034 26.774902 270)
			(size 0.519938 1.4986)
			(layers "F.Cu" "F.Mask" "F.Paste")
			(net "M_F_CPU1_SB_DQ<2>")
		)
		(pad "246" smd rect
			(at 2.050034 27.62504 270)
			(size 0.519938 1.4986)
			(layers "F.Cu" "F.Mask" "F.Paste")
			(net "GND")
		)
		(pad "247" smd rect
			(at 2.050034 28.474924 270)
			(size 0.519938 1.4986)
			(layers "F.Cu" "F.Mask" "F.Paste")
			(net "M_F_CPU1_SB_DQ<3>")
		)
		(pad "248" smd rect
			(at 2.050034 29.325062 270)
			(size 0.519938 1.4986)
			(layers "F.Cu" "F.Mask" "F.Paste")
			(net "GND")
		)
		(pad "249" smd rect
			(at 2.050034 30.174946 270)
			(size 0.519938 1.4986)
			(layers "F.Cu" "F.Mask" "F.Paste")
			(net "M_F_CPU1_SB_DQS_DN<5>")
		)
		(pad "250" smd rect
			(at 2.050034 31.025084 270)
			(size 0.519938 1.4986)
			(layers "F.Cu" "F.Mask" "F.Paste")
			(net "M_F_CPU1_SB_DQS_DP<5>")
		)
		(pad "251" smd rect
			(at 2.050034 31.874968 270)
			(size 0.519938 1.4986)
			(layers "F.Cu" "F.Mask" "F.Paste")
			(net "GND")
		)
		(pad "252" smd rect
			(at 2.050034 32.725106 270)
			(size 0.519938 1.4986)
			(layers "F.Cu" "F.Mask" "F.Paste")
			(net "M_F_CPU1_SB_DQ<6>")
		)
		(pad "253" smd rect
			(at 2.050034 33.57499 270)
			(size 0.519938 1.4986)
			(layers "F.Cu" "F.Mask" "F.Paste")
			(net "GND")
		)
		(pad "254" smd rect
			(at 2.050034 34.425128 270)
			(size 0.519938 1.4986)
			(layers "F.Cu" "F.Mask" "F.Paste")
			(net "M_F_CPU1_SB_DQ<7>")
		)
		(pad "255" smd rect
			(at 2.050034 35.275012 270)
			(size 0.519938 1.4986)
			(layers "F.Cu" "F.Mask" "F.Paste")
			(net "GND")
		)
		(pad "256" smd rect
			(at 2.050034 36.124896 270)
			(size 0.519938 1.4986)
			(layers "F.Cu" "F.Mask" "F.Paste")
			(net "M_F_CPU1_SB_DQ<10>")
		)
		(pad "257" smd rect
			(at 2.050034 36.975034 270)
			(size 0.519938 1.4986)
			(layers "F.Cu" "F.Mask" "F.Paste")
			(net "GND")
		)
		(pad "258" smd rect
			(at 2.050034 37.824918 270)
			(size 0.519938 1.4986)
			(layers "F.Cu" "F.Mask" "F.Paste")
			(net "M_F_CPU1_SB_DQ<11>")
		)
		(pad "259" smd rect
			(at 2.050034 38.675056 270)
			(size 0.519938 1.4986)
			(layers "F.Cu" "F.Mask" "F.Paste")
			(net "GND")
		)
		(pad "260" smd rect
			(at 2.050034 39.52494 270)
			(size 0.519938 1.4986)
			(layers "F.Cu" "F.Mask" "F.Paste")
			(net "M_F_CPU1_SB_DQS_DN<6>")
		)
		(pad "261" smd rect
			(at 2.050034 40.375078 270)
			(size 0.519938 1.4986)
			(layers "F.Cu" "F.Mask" "F.Paste")
			(net "M_F_CPU1_SB_DQS_DP<6>")
		)
		(pad "262" smd rect
			(at 2.050034 41.224962 270)
			(size 0.519938 1.4986)
			(layers "F.Cu" "F.Mask" "F.Paste")
			(net "GND")
		)
		(pad "263" smd rect
			(at 2.050034 42.0751 270)
			(size 0.519938 1.4986)
			(layers "F.Cu" "F.Mask" "F.Paste")
			(net "M_F_CPU1_SB_DQ<14>")
		)
		(pad "264" smd rect
			(at 2.050034 42.924984 270)
			(size 0.519938 1.4986)
			(layers "F.Cu" "F.Mask" "F.Paste")
			(net "GND")
		)
		(pad "265" smd rect
			(at 2.050034 43.775122 270)
			(size 0.519938 1.4986)
			(layers "F.Cu" "F.Mask" "F.Paste")
			(net "M_F_CPU1_SB_DQ<15>")
		)
		(pad "266" smd rect
			(at 2.050034 44.625006 270)
			(size 0.519938 1.4986)
			(layers "F.Cu" "F.Mask" "F.Paste")
			(net "GND")
		)
		(pad "267" smd rect
			(at 2.050034 45.47489 270)
			(size 0.519938 1.4986)
			(layers "F.Cu" "F.Mask" "F.Paste")
			(net "M_F_CPU1_SB_DQ<18>")
		)
		(pad "268" smd rect
			(at 2.050034 46.325028 270)
			(size 0.519938 1.4986)
			(layers "F.Cu" "F.Mask" "F.Paste")
			(net "GND")
		)
		(pad "269" smd rect
			(at 2.050034 47.174912 270)
			(size 0.519938 1.4986)
			(layers "F.Cu" "F.Mask" "F.Paste")
			(net "M_F_CPU1_SB_DQ<19>")
		)
		(pad "270" smd rect
			(at 2.050034 48.02505 270)
			(size 0.519938 1.4986)
			(layers "F.Cu" "F.Mask" "F.Paste")
			(net "GND")
		)
		(pad "271" smd rect
			(at 2.050034 48.874934 270)
			(size 0.519938 1.4986)
			(layers "F.Cu" "F.Mask" "F.Paste")
			(net "M_F_CPU1_SB_DQS_DN<7>")
		)
		(pad "272" smd rect
			(at 2.050034 49.725072 270)
			(size 0.519938 1.4986)
			(layers "F.Cu" "F.Mask" "F.Paste")
			(net "M_F_CPU1_SB_DQS_DP<7>")
		)
		(pad "273" smd rect
			(at 2.050034 50.574956 270)
			(size 0.519938 1.4986)
			(layers "F.Cu" "F.Mask" "F.Paste")
			(net "GND")
		)
		(pad "274" smd rect
			(at 2.050034 51.425094 270)
			(size 0.519938 1.4986)
			(layers "F.Cu" "F.Mask" "F.Paste")
			(net "M_F_CPU1_SB_DQ<22>")
		)
		(pad "275" smd rect
			(at 2.050034 52.274978 270)
			(size 0.519938 1.4986)
			(layers "F.Cu" "F.Mask" "F.Paste")
			(net "GND")
		)
		(pad "276" smd rect
			(at 2.050034 53.125116 270)
			(size 0.519938 1.4986)
			(layers "F.Cu" "F.Mask" "F.Paste")
			(net "M_F_CPU1_SB_DQ<23>")
		)
		(pad "277" smd rect
			(at 2.050034 53.975 270)
			(size 0.519938 1.4986)
			(layers "F.Cu" "F.Mask" "F.Paste")
			(net "GND")
		)
		(pad "278" smd rect
			(at 2.050034 54.824884 270)
			(size 0.519938 1.4986)
			(layers "F.Cu" "F.Mask" "F.Paste")
			(net "M_F_CPU1_SB_DQ<26>")
		)
		(pad "279" smd rect
			(at 2.050034 55.675022 270)
			(size 0.519938 1.4986)
			(layers "F.Cu" "F.Mask" "F.Paste")
			(net "GND")
		)
		(pad "280" smd rect
			(at 2.050034 56.524906 270)
			(size 0.519938 1.4986)
			(layers "F.Cu" "F.Mask" "F.Paste")
			(net "M_F_CPU1_SB_DQ<27>")
		)
		(pad "281" smd rect
			(at 2.050034 57.375044 270)
			(size 0.519938 1.4986)
			(layers "F.Cu" "F.Mask" "F.Paste")
			(net "GND")
		)
		(pad "282" smd rect
			(at 2.050034 58.224928 270)
			(size 0.519938 1.4986)
			(layers "F.Cu" "F.Mask" "F.Paste")
			(net "M_F_CPU1_SB_DQS_DN<8>")
		)
		(pad "283" smd rect
			(at 2.050034 59.075066 270)
			(size 0.519938 1.4986)
			(layers "F.Cu" "F.Mask" "F.Paste")
			(net "M_F_CPU1_SB_DQS_DP<8>")
		)
		(pad "284" smd rect
			(at 2.050034 59.92495 270)
			(size 0.519938 1.4986)
			(layers "F.Cu" "F.Mask" "F.Paste")
			(net "GND")
		)
		(pad "285" smd rect
			(at 2.050034 60.775088 270)
			(size 0.519938 1.4986)
			(layers "F.Cu" "F.Mask" "F.Paste")
			(net "M_F_CPU1_SB_DQ<30>")
		)
		(pad "286" smd rect
			(at 2.050034 61.624972 270)
			(size 0.519938 1.4986)
			(layers "F.Cu" "F.Mask" "F.Paste")
			(net "GND")
		)
		(pad "287" smd rect
			(at 2.050034 62.47511 270)
			(size 0.519938 1.4986)
			(layers "F.Cu" "F.Mask" "F.Paste")
			(net "M_F_CPU1_SB_DQ<31>")
		)
		(pad "288" smd rect
			(at 2.050034 63.324994 270)
			(size 0.519938 1.4986)
			(layers "F.Cu" "F.Mask" "F.Paste")
			(net "GND")
		)
		(pad "G1" thru_hole oval
			(at 0 -68.97497)
			(size 2.8194 1.5748)
			(drill oval 2.4384 1.1938)
			(layers "*.Cu" "*.Mask")
			(remove_unused_layers no)
			(net "GND")
			(clearance 0.127)
			(thermal_gap 0.127)
		)
		(pad "G2" thru_hole oval
			(at 0 3.875024)
			(size 2.8194 1.5748)
			(drill oval 2.4384 1.1938)
			(layers "*.Cu" "*.Mask")
			(remove_unused_layers no)
			(net "GND")
			(clearance 0.127)
			(thermal_gap 0.127)
		)
		(pad "G3" thru_hole oval
			(at 0 68.97497)
			(size 2.8194 1.5748)
			(drill oval 2.4384 1.1938)
			(layers "*.Cu" "*.Mask")
			(remove_unused_layers no)
			(net "GND")
			(clearance 0.127)
			(thermal_gap 0.127)
		)
	)
	(footprint ""
		(layer "F.Cu")
		(at 112.78108 -106.238548 -90)
		(property "Reference" "R4042"
			(at 0 0 270)
			(layer "F.SilkS")
			(hide yes)
			(effects
				(font
					(size 1.27 1.27)
				)
			)
		)
		(property "Value" ""
			(at 0 0 270)
			(layer "F.Fab")
			(effects
				(font
					(size 1.27 1.27)
				)
			)
		)
		(duplicate_pad_numbers_are_jumpers no)
		(fp_line
			(start -0.7874 0.4064)
			(end -0.7874 -0.4064)
			(stroke
				(width 0.1524)
				(type default)
			)
			(layer "F.SilkS")
		)
		(fp_line
			(start 0.7874 0.4064)
			(end -0.7874 0.4064)
			(stroke
				(width 0.1524)
				(type default)
			)
			(layer "F.SilkS")
		)
		(fp_line
			(start -0.7874 -0.4064)
			(end 0.7874 -0.4064)
			(stroke
				(width 0.1524)
				(type default)
			)
			(layer "F.SilkS")
		)
		(fp_line
			(start 0.7874 -0.4064)
			(end 0.7874 0.4064)
			(stroke
				(width 0.1524)
				(type default)
			)
			(layer "F.SilkS")
		)
		(fp_line
			(start -0.67945 0.3048)
			(end -0.67945 -0.305054)
			(stroke
				(width 0.1)
				(type default)
			)
			(layer "F.Fab")
		)
		(fp_line
			(start -0.12065 0.3048)
			(end -0.67945 0.3048)
			(stroke
				(width 0.1)
				(type default)
			)
			(layer "F.Fab")
		)
		(fp_line
			(start 0.120396 0.3048)
			(end 0.120396 0.2794)
			(stroke
				(width 0.1)
				(type default)
			)
			(layer "F.Fab")
		)
		(fp_line
			(start 0.67945 0.3048)
			(end 0.120396 0.3048)
			(stroke
				(width 0.1)
				(type default)
			)
			(layer "F.Fab")
		)
		(fp_line
			(start -0.12065 0.2794)
			(end -0.12065 0.3048)
			(stroke
				(width 0.1)
				(type default)
			)
			(layer "F.Fab")
		)
		(fp_line
			(start 0.120396 0.2794)
			(end -0.12065 0.2794)
			(stroke
				(width 0.1)
				(type default)
			)
			(layer "F.Fab")
		)
		(fp_line
			(start -0.12065 -0.2794)
			(end 0.12065 -0.2794)
			(stroke
				(width 0.1)
				(type default)
			)
			(layer "F.Fab")
		)
		(fp_line
			(start 0.12065 -0.2794)
			(end 0.12065 -0.3048)
			(stroke
				(width 0.1)
				(type default)
			)
			(layer "F.Fab")
		)
		(fp_line
			(start 0.12065 -0.3048)
			(end 0.67945 -0.3048)
			(stroke
				(width 0.1)
				(type default)
			)
			(layer "F.Fab")
		)
		(fp_line
			(start 0.67945 -0.3048)
			(end 0.67945 0.3048)
			(stroke
				(width 0.1)
				(type default)
			)
			(layer "F.Fab")
		)
		(fp_line
			(start -0.67945 -0.305054)
			(end -0.12065 -0.305054)
			(stroke
				(width 0.1)
				(type default)
			)
			(layer "F.Fab")
		)
		(fp_line
			(start -0.12065 -0.305054)
			(end -0.12065 -0.2794)
			(stroke
				(width 0.1)
				(type default)
			)
			(layer "F.Fab")
		)
		(pad "1" smd circle
			(at -0.40005 0 270)
			(size 0 0)
			(layers "F.Cu" "F.Mask" "F.Paste")
			(net "RST_CPU0_DRAM_AB_PLD_LVT3_R_N")
		)
		(pad "2" smd circle
			(at 0.40005 0 270)
			(size 0 0)
			(layers "F.Cu" "F.Mask" "F.Paste")
			(net "RST_CPU0_DRAM_AB_PLD_LVT3_N")
		)
	)
	(footprint ""
		(layer "F.Cu")
		(at 201.8284 -92.6338 -90)
		(property "Reference" "C2379"
			(at 0 0 270)
			(layer "F.SilkS")
			(hide yes)
			(effects
				(font
					(size 1.27 1.27)
				)
			)
		)
		(property "Value" ""
			(at 0 0 270)
			(layer "F.Fab")
			(effects
				(font
					(size 1.27 1.27)
				)
			)
		)
		(duplicate_pad_numbers_are_jumpers no)
		(fp_line
			(start -0.7874 0.4064)
			(end -0.7874 -0.4064)
			(stroke
				(width 0.1524)
				(type default)
			)
			(layer "F.SilkS")
		)
		(fp_line
			(start 0.7874 0.4064)
			(end -0.7874 0.4064)
			(stroke
				(width 0.1524)
				(type default)
			)
			(layer "F.SilkS")
		)
		(fp_line
			(start -0.7874 -0.4064)
			(end 0.7874 -0.4064)
			(stroke
				(width 0.1524)
				(type default)
			)
			(layer "F.SilkS")
		)
		(fp_line
			(start 0.7874 -0.4064)
			(end 0.7874 0.4064)
			(stroke
				(width 0.1524)
				(type default)
			)
			(layer "F.SilkS")
		)
		(fp_line
			(start -0.67945 0.3048)
			(end -0.67945 -0.305054)
			(stroke
				(width 0.1)
				(type default)
			)
			(layer "F.Fab")
		)
		(fp_line
			(start -0.12065 0.3048)
			(end -0.67945 0.3048)
			(stroke
				(width 0.1)
				(type default)
			)
			(layer "F.Fab")
		)
		(fp_line
			(start 0.120396 0.3048)
			(end 0.120396 0.2794)
			(stroke
				(width 0.1)
				(type default)
			)
			(layer "F.Fab")
		)
		(fp_line
			(start 0.67945 0.3048)
			(end 0.120396 0.3048)
			(stroke
				(width 0.1)
				(type default)
			)
			(layer "F.Fab")
		)
		(fp_line
			(start -0.12065 0.2794)
			(end -0.12065 0.3048)
			(stroke
				(width 0.1)
				(type default)
			)
			(layer "F.Fab")
		)
		(fp_line
			(start 0.120396 0.2794)
			(end -0.12065 0.2794)
			(stroke
				(width 0.1)
				(type default)
			)
			(layer "F.Fab")
		)
		(fp_line
			(start -0.12065 -0.2794)
			(end 0.12065 -0.2794)
			(stroke
				(width 0.1)
				(type default)
			)
			(layer "F.Fab")
		)
		(fp_line
			(start 0.12065 -0.2794)
			(end 0.12065 -0.3048)
			(stroke
				(width 0.1)
				(type default)
			)
			(layer "F.Fab")
		)
		(fp_line
			(start 0.12065 -0.3048)
			(end 0.67945 -0.3048)
			(stroke
				(width 0.1)
				(type default)
			)
			(layer "F.Fab")
		)
		(fp_line
			(start 0.67945 -0.3048)
			(end 0.67945 0.3048)
			(stroke
				(width 0.1)
				(type default)
			)
			(layer "F.Fab")
		)
		(fp_line
			(start -0.67945 -0.305054)
			(end -0.12065 -0.305054)
			(stroke
				(width 0.1)
				(type default)
			)
			(layer "F.Fab")
		)
		(fp_line
			(start -0.12065 -0.305054)
			(end -0.12065 -0.2794)
			(stroke
				(width 0.1)
				(type default)
			)
			(layer "F.Fab")
		)
		(pad "1" smd circle
			(at -0.40005 0 270)
			(size 0 0)
			(layers "F.Cu" "F.Mask" "F.Paste")
			(net "UV_ADR_P2V5_COMP")
		)
		(pad "2" smd circle
			(at 0.40005 0 270)
			(size 0 0)
			(layers "F.Cu" "F.Mask" "F.Paste")
			(net "GND")
		)
	)
	(footprint ""
		(layer "F.Cu")
		(at 422.273984 -364.563914 90)
		(property "Reference" "PC1171"
			(at 0 0 90)
			(layer "F.SilkS")
			(hide yes)
			(effects
				(font
					(size 1.27 1.27)
				)
			)
		)
		(property "Value" ""
			(at 0 0 90)
			(layer "F.Fab")
			(effects
				(font
					(size 1.27 1.27)
				)
			)
		)
		(duplicate_pad_numbers_are_jumpers no)
		(fp_line
			(start 0.7874 -0.4064)
			(end 0.7874 0.4064)
			(stroke
				(width 0.1524)
				(type default)
			)
			(layer "F.SilkS")
		)
		(fp_line
			(start -0.7874 -0.4064)
			(end 0.7874 -0.4064)
			(stroke
				(width 0.1524)
				(type default)
			)
			(layer "F.SilkS")
		)
		(fp_line
			(start 0.7874 0.4064)
			(end -0.7874 0.4064)
			(stroke
				(width 0.1524)
				(type default)
			)
			(layer "F.SilkS")
		)
		(fp_line
			(start -0.7874 0.4064)
			(end -0.7874 -0.4064)
			(stroke
				(width 0.1524)
				(type default)
			)
			(layer "F.SilkS")
		)
		(fp_line
			(start -0.12065 -0.305054)
			(end -0.12065 -0.2794)
			(stroke
				(width 0.1)
				(type default)
			)
			(layer "F.Fab")
		)
		(fp_line
			(start -0.67945 -0.305054)
			(end -0.12065 -0.305054)
			(stroke
				(width 0.1)
				(type default)
			)
			(layer "F.Fab")
		)
		(fp_line
			(start 0.67945 -0.3048)
			(end 0.67945 0.3048)
			(stroke
				(width 0.1)
				(type default)
			)
			(layer "F.Fab")
		)
		(fp_line
			(start 0.12065 -0.3048)
			(end 0.67945 -0.3048)
			(stroke
				(width 0.1)
				(type default)
			)
			(layer "F.Fab")
		)
		(fp_line
			(start 0.12065 -0.2794)
			(end 0.12065 -0.3048)
			(stroke
				(width 0.1)
				(type default)
			)
			(layer "F.Fab")
		)
		(fp_line
			(start -0.12065 -0.2794)
			(end 0.12065 -0.2794)
			(stroke
				(width 0.1)
				(type default)
			)
			(layer "F.Fab")
		)
		(fp_line
			(start 0.120396 0.2794)
			(end -0.12065 0.2794)
			(stroke
				(width 0.1)
				(type default)
			)
			(layer "F.Fab")
		)
		(fp_line
			(start -0.12065 0.2794)
			(end -0.12065 0.3048)
			(stroke
				(width 0.1)
				(type default)
			)
			(layer "F.Fab")
		)
		(fp_line
			(start 0.67945 0.3048)
			(end 0.120396 0.3048)
			(stroke
				(width 0.1)
				(type default)
			)
			(layer "F.Fab")
		)
		(fp_line
			(start 0.120396 0.3048)
			(end 0.120396 0.2794)
			(stroke
				(width 0.1)
				(type default)
			)
			(layer "F.Fab")
		)
		(fp_line
			(start -0.12065 0.3048)
			(end -0.67945 0.3048)
			(stroke
				(width 0.1)
				(type default)
			)
			(layer "F.Fab")
		)
		(fp_line
			(start -0.67945 0.3048)
			(end -0.67945 -0.305054)
			(stroke
				(width 0.1)
				(type default)
			)
			(layer "F.Fab")
		)
		(pad "1" smd circle
			(at -0.40005 0 90)
			(size 0 0)
			(layers "F.Cu" "F.Mask" "F.Paste")
			(net "PVCCFA_EHV_FIVRA_CPU0_VDD3")
		)
		(pad "2" smd circle
			(at 0.40005 0 90)
			(size 0 0)
			(layers "F.Cu" "F.Mask" "F.Paste")
			(net "GND")
		)
	)
	(footprint ""
		(layer "F.Cu")
		(at 468.164164 -61.047884 90)
		(property "Reference" "PC1649"
			(at 0 0 90)
			(layer "F.SilkS")
			(hide yes)
			(effects
				(font
					(size 1.27 1.27)
				)
			)
		)
		(property "Value" ""
			(at 0 0 90)
			(layer "F.Fab")
			(effects
				(font
					(size 1.27 1.27)
				)
			)
		)
		(duplicate_pad_numbers_are_jumpers no)
		(fp_line
			(start 0.7874 -0.4064)
			(end 0.7874 0.4064)
			(stroke
				(width 0.1524)
				(type default)
			)
			(layer "F.SilkS")
		)
		(fp_line
			(start -0.7874 -0.4064)
			(end 0.7874 -0.4064)
			(stroke
				(width 0.1524)
				(type default)
			)
			(layer "F.SilkS")
		)
		(fp_line
			(start 0.7874 0.4064)
			(end -0.7874 0.4064)
			(stroke
				(width 0.1524)
				(type default)
			)
			(layer "F.SilkS")
		)
		(fp_line
			(start -0.7874 0.4064)
			(end -0.7874 -0.4064)
			(stroke
				(width 0.1524)
				(type default)
			)
			(layer "F.SilkS")
		)
		(fp_line
			(start -0.12065 -0.305054)
			(end -0.12065 -0.2794)
			(stroke
				(width 0.1)
				(type default)
			)
			(layer "F.Fab")
		)
		(fp_line
			(start -0.67945 -0.305054)
			(end -0.12065 -0.305054)
			(stroke
				(width 0.1)
				(type default)
			)
			(layer "F.Fab")
		)
		(fp_line
			(start 0.67945 -0.3048)
			(end 0.67945 0.3048)
			(stroke
				(width 0.1)
				(type default)
			)
			(layer "F.Fab")
		)
		(fp_line
			(start 0.12065 -0.3048)
			(end 0.67945 -0.3048)
			(stroke
				(width 0.1)
				(type default)
			)
			(layer "F.Fab")
		)
		(fp_line
			(start 0.12065 -0.2794)
			(end 0.12065 -0.3048)
			(stroke
				(width 0.1)
				(type default)
			)
			(layer "F.Fab")
		)
		(fp_line
			(start -0.12065 -0.2794)
			(end 0.12065 -0.2794)
			(stroke
				(width 0.1)
				(type default)
			)
			(layer "F.Fab")
		)
		(fp_line
			(start 0.120396 0.2794)
			(end -0.12065 0.2794)
			(stroke
				(width 0.1)
				(type default)
			)
			(layer "F.Fab")
		)
		(fp_line
			(start -0.12065 0.2794)
			(end -0.12065 0.3048)
			(stroke
				(width 0.1)
				(type default)
			)
			(layer "F.Fab")
		)
		(fp_line
			(start 0.67945 0.3048)
			(end 0.120396 0.3048)
			(stroke
				(width 0.1)
				(type default)
			)
			(layer "F.Fab")
		)
		(fp_line
			(start 0.120396 0.3048)
			(end 0.120396 0.2794)
			(stroke
				(width 0.1)
				(type default)
			)
			(layer "F.Fab")
		)
		(fp_line
			(start -0.12065 0.3048)
			(end -0.67945 0.3048)
			(stroke
				(width 0.1)
				(type default)
			)
			(layer "F.Fab")
		)
		(fp_line
			(start -0.67945 0.3048)
			(end -0.67945 -0.305054)
			(stroke
				(width 0.1)
				(type default)
			)
			(layer "F.Fab")
		)
		(pad "1" smd circle
			(at -0.40005 0 90)
			(size 0 0)
			(layers "F.Cu" "F.Mask" "F.Paste")
			(net "P12V_AUX")
		)
		(pad "2" smd circle
			(at 0.40005 0 90)
			(size 0 0)
			(layers "F.Cu" "F.Mask" "F.Paste")
			(net "GND")
		)
	)
	(footprint ""
		(layer "F.Cu")
		(at 101.833934 -390.60374 180)
		(property "Reference" "R3397"
			(at 0 0 180)
			(layer "F.SilkS")
			(hide yes)
			(effects
				(font
					(size 1.27 1.27)
				)
			)
		)
		(property "Value" ""
			(at 0 0 180)
			(layer "F.Fab")
			(effects
				(font
					(size 1.27 1.27)
				)
			)
		)
		(duplicate_pad_numbers_are_jumpers no)
		(fp_line
			(start 0.7874 0.4064)
			(end -0.7874 0.4064)
			(stroke
				(width 0.1524)
				(type default)
			)
			(layer "F.SilkS")
		)
		(fp_line
			(start 0.7874 -0.4064)
			(end 0.7874 0.4064)
			(stroke
				(width 0.1524)
				(type default)
			)
			(layer "F.SilkS")
		)
		(fp_line
			(start -0.7874 0.4064)
			(end -0.7874 -0.4064)
			(stroke
				(width 0.1524)
				(type default)
			)
			(layer "F.SilkS")
		)
		(fp_line
			(start -0.7874 -0.4064)
			(end 0.7874 -0.4064)
			(stroke
				(width 0.1524)
				(type default)
			)
			(layer "F.SilkS")
		)
		(fp_line
			(start 0.67945 0.3048)
			(end 0.120396 0.3048)
			(stroke
				(width 0.1)
				(type default)
			)
			(layer "F.Fab")
		)
		(fp_line
			(start 0.67945 -0.3048)
			(end 0.67945 0.3048)
			(stroke
				(width 0.1)
				(type default)
			)
			(layer "F.Fab")
		)
		(fp_line
			(start 0.12065 -0.2794)
			(end 0.12065 -0.3048)
			(stroke
				(width 0.1)
				(type default)
			)
			(layer "F.Fab")
		)
		(fp_line
			(start 0.12065 -0.3048)
			(end 0.67945 -0.3048)
			(stroke
				(width 0.1)
				(type default)
			)
			(layer "F.Fab")
		)
		(fp_line
			(start 0.120396 0.3048)
			(end 0.120396 0.2794)
			(stroke
				(width 0.1)
				(type default)
			)
			(layer "F.Fab")
		)
		(fp_line
			(start 0.120396 0.2794)
			(end -0.12065 0.2794)
			(stroke
				(width 0.1)
				(type default)
			)
			(layer "F.Fab")
		)
		(fp_line
			(start -0.12065 0.3048)
			(end -0.67945 0.3048)
			(stroke
				(width 0.1)
				(type default)
			)
			(layer "F.Fab")
		)
		(fp_line
			(start -0.12065 0.2794)
			(end -0.12065 0.3048)
			(stroke
				(width 0.1)
				(type default)
			)
			(layer "F.Fab")
		)
		(fp_line
			(start -0.12065 -0.2794)
			(end 0.12065 -0.2794)
			(stroke
				(width 0.1)
				(type default)
			)
			(layer "F.Fab")
		)
		(fp_line
			(start -0.12065 -0.305054)
			(end -0.12065 -0.2794)
			(stroke
				(width 0.1)
				(type default)
			)
			(layer "F.Fab")
		)
		(fp_line
			(start -0.67945 0.3048)
			(end -0.67945 -0.305054)
			(stroke
				(width 0.1)
				(type default)
			)
			(layer "F.Fab")
		)
		(fp_line
			(start -0.67945 -0.305054)
			(end -0.12065 -0.305054)
			(stroke
				(width 0.1)
				(type default)
			)
			(layer "F.Fab")
		)
		(pad "1" smd circle
			(at -0.40005 0 180)
			(size 0 0)
			(layers "F.Cu" "F.Mask" "F.Paste")
			(net "GPU_NVS_PWR_BRAKE_N_R")
		)
		(pad "2" smd circle
			(at 0.40005 0 180)
			(size 0 0)
			(layers "F.Cu" "F.Mask" "F.Paste")
			(net "GPU_NVS_PWR_BRAKE_N_BUF")
		)
	)
	(footprint ""
		(layer "F.Cu")
		(at 52.423314 -144.267174 180)
		(property "Reference" "PC441"
			(at 0 0 180)
			(layer "F.SilkS")
			(hide yes)
			(effects
				(font
					(size 1.27 1.27)
				)
			)
		)
		(property "Value" ""
			(at 0 0 180)
			(layer "F.Fab")
			(effects
				(font
					(size 1.27 1.27)
				)
			)
		)
		(duplicate_pad_numbers_are_jumpers no)
		(fp_line
			(start 0.7874 0.4064)
			(end -0.7874 0.4064)
			(stroke
				(width 0.1524)
				(type default)
			)
			(layer "F.SilkS")
		)
		(fp_line
			(start 0.7874 -0.4064)
			(end 0.7874 0.4064)
			(stroke
				(width 0.1524)
				(type default)
			)
			(layer "F.SilkS")
		)
		(fp_line
			(start -0.7874 0.4064)
			(end -0.7874 -0.4064)
			(stroke
				(width 0.1524)
				(type default)
			)
			(layer "F.SilkS")
		)
		(fp_line
			(start -0.7874 -0.4064)
			(end 0.7874 -0.4064)
			(stroke
				(width 0.1524)
				(type default)
			)
			(layer "F.SilkS")
		)
		(fp_line
			(start 0.67945 0.3048)
			(end 0.120396 0.3048)
			(stroke
				(width 0.1)
				(type default)
			)
			(layer "F.Fab")
		)
		(fp_line
			(start 0.67945 -0.3048)
			(end 0.67945 0.3048)
			(stroke
				(width 0.1)
				(type default)
			)
			(layer "F.Fab")
		)
		(fp_line
			(start 0.12065 -0.2794)
			(end 0.12065 -0.3048)
			(stroke
				(width 0.1)
				(type default)
			)
			(layer "F.Fab")
		)
		(fp_line
			(start 0.12065 -0.3048)
			(end 0.67945 -0.3048)
			(stroke
				(width 0.1)
				(type default)
			)
			(layer "F.Fab")
		)
		(fp_line
			(start 0.120396 0.3048)
			(end 0.120396 0.2794)
			(stroke
				(width 0.1)
				(type default)
			)
			(layer "F.Fab")
		)
		(fp_line
			(start 0.120396 0.2794)
			(end -0.12065 0.2794)
			(stroke
				(width 0.1)
				(type default)
			)
			(layer "F.Fab")
		)
		(fp_line
			(start -0.12065 0.3048)
			(end -0.67945 0.3048)
			(stroke
				(width 0.1)
				(type default)
			)
			(layer "F.Fab")
		)
		(fp_line
			(start -0.12065 0.2794)
			(end -0.12065 0.3048)
			(stroke
				(width 0.1)
				(type default)
			)
			(layer "F.Fab")
		)
		(fp_line
			(start -0.12065 -0.2794)
			(end 0.12065 -0.2794)
			(stroke
				(width 0.1)
				(type default)
			)
			(layer "F.Fab")
		)
		(fp_line
			(start -0.12065 -0.305054)
			(end -0.12065 -0.2794)
			(stroke
				(width 0.1)
				(type default)
			)
			(layer "F.Fab")
		)
		(fp_line
			(start -0.67945 0.3048)
			(end -0.67945 -0.305054)
			(stroke
				(width 0.1)
				(type default)
			)
			(layer "F.Fab")
		)
		(fp_line
			(start -0.67945 -0.305054)
			(end -0.12065 -0.305054)
			(stroke
				(width 0.1)
				(type default)
			)
			(layer "F.Fab")
		)
		(pad "1" smd circle
			(at -0.40005 0 180)
			(size 0 0)
			(layers "F.Cu" "F.Mask" "F.Paste")
			(net "PVCCINFAON_CPU1_VDD2")
		)
		(pad "2" smd circle
			(at 0.40005 0 180)
			(size 0 0)
			(layers "F.Cu" "F.Mask" "F.Paste")
			(net "GND")
		)
	)
	(footprint ""
		(layer "F.Cu")
		(at 180.528468 -50.060098 180)
		(property "Reference" "C1103"
			(at 0 0 180)
			(layer "F.SilkS")
			(hide yes)
			(effects
				(font
					(size 1.27 1.27)
				)
			)
		)
		(property "Value" ""
			(at 0 0 180)
			(layer "F.Fab")
			(effects
				(font
					(size 1.27 1.27)
				)
			)
		)
		(duplicate_pad_numbers_are_jumpers no)
		(fp_line
			(start 0.299974 0.150114)
			(end -0.299974 0.150114)
			(stroke
				(width 0.1)
				(type default)
			)
			(layer "F.Fab")
		)
		(fp_line
			(start 0.299974 -0.150114)
			(end 0.299974 0.150114)
			(stroke
				(width 0.1)
				(type default)
			)
			(layer "F.Fab")
		)
		(fp_line
			(start -0.299974 0.150114)
			(end -0.299974 -0.150114)
			(stroke
				(width 0.1)
				(type default)
			)
			(layer "F.Fab")
		)
		(fp_line
			(start -0.299974 -0.150114)
			(end 0.299974 -0.150114)
			(stroke
				(width 0.1)
				(type default)
			)
			(layer "F.Fab")
		)
		(pad "1" smd rect
			(at -0.2667 0 180)
			(size 0.3048 0.381)
			(layers "F.Cu" "F.Mask" "F.Paste")
			(net "P3E_PCH_M2_TX_DN<1>")
		)
		(pad "2" smd rect
			(at 0.2667 0 180)
			(size 0.3048 0.381)
			(layers "F.Cu" "F.Mask" "F.Paste")
			(net "P3E_PCH_M2_TX_C_DN<1>")
		)
		(zone
			(layer "In1.Cu")
			(hatch none 0.5)
			(connect_pads
				(clearance 0)
			)
			(min_thickness 0.25)
			(keepout
				(tracks not_allowed)
				(vias allowed)
				(pads allowed)
				(copperpour not_allowed)
				(footprints allowed)
			)
			(placement
				(enabled no)
				(sheetname "")
			)
			(fill
				(thermal_gap 0.5)
				(thermal_bridge_width 0.5)
				(island_removal_mode 0)
			)
			(polygon
				(pts
					(arc
						(start 180.388768 -50.301398)
						(mid 180.44265 -50.27908)
						(end 180.464968 -50.225198)
					)
					(arc
						(start 180.464968 -49.894998)
						(mid 180.44265 -49.841116)
						(end 180.388768 -49.818798)
					)
					(arc
						(start 180.134768 -49.818798)
						(mid 180.080886 -49.841116)
						(end 180.058568 -49.894998)
					)
					(arc
						(start 180.058568 -50.225198)
						(mid 180.080886 -50.27908)
						(end 180.134768 -50.301398)
					)
				)
			)
		)
		(zone
			(layer "In1.Cu")
			(hatch none 0.5)
			(connect_pads
				(clearance 0)
			)
			(min_thickness 0.25)
			(keepout
				(tracks not_allowed)
				(vias allowed)
				(pads allowed)
				(copperpour not_allowed)
				(footprints allowed)
			)
			(placement
				(enabled no)
				(sheetname "")
			)
			(fill
				(thermal_gap 0.5)
				(thermal_bridge_width 0.5)
				(island_removal_mode 0)
			)
			(polygon
				(pts
					(arc
						(start 180.922168 -50.301398)
						(mid 180.97605 -50.27908)
						(end 180.998368 -50.225198)
					)
					(arc
						(start 180.998368 -49.894998)
						(mid 180.97605 -49.841116)
						(end 180.922168 -49.818798)
					)
					(arc
						(start 180.668168 -49.818798)
						(mid 180.614286 -49.841116)
						(end 180.591968 -49.894998)
					)
					(arc
						(start 180.591968 -50.225198)
						(mid 180.614286 -50.27908)
						(end 180.668168 -50.301398)
					)
				)
			)
		)
	)
	(footprint ""
		(layer "F.Cu")
		(at 40.6146 -103.977948)
		(property "Reference" "R4568"
			(at 0 0 0)
			(layer "F.SilkS")
			(hide yes)
			(effects
				(font
					(size 1.27 1.27)
				)
			)
		)
		(property "Value" ""
			(at 0 0 0)
			(layer "F.Fab")
			(effects
				(font
					(size 1.27 1.27)
				)
			)
		)
		(duplicate_pad_numbers_are_jumpers no)
		(fp_line
			(start -0.7874 -0.4064)
			(end 0.7874 -0.4064)
			(stroke
				(width 0.1524)
				(type default)
			)
			(layer "F.SilkS")
		)
		(fp_line
			(start -0.7874 0.4064)
			(end -0.7874 -0.4064)
			(stroke
				(width 0.1524)
				(type default)
			)
			(layer "F.SilkS")
		)
		(fp_line
			(start 0.7874 -0.4064)
			(end 0.7874 0.4064)
			(stroke
				(width 0.1524)
				(type default)
			)
			(layer "F.SilkS")
		)
		(fp_line
			(start 0.7874 0.4064)
			(end -0.7874 0.4064)
			(stroke
				(width 0.1524)
				(type default)
			)
			(layer "F.SilkS")
		)
		(fp_line
			(start -0.67945 -0.305054)
			(end -0.12065 -0.305054)
			(stroke
				(width 0.1)
				(type default)
			)
			(layer "F.Fab")
		)
		(fp_line
			(start -0.67945 0.3048)
			(end -0.67945 -0.305054)
			(stroke
				(width 0.1)
				(type default)
			)
			(layer "F.Fab")
		)
		(fp_line
			(start -0.12065 -0.305054)
			(end -0.12065 -0.2794)
			(stroke
				(width 0.1)
				(type default)
			)
			(layer "F.Fab")
		)
		(fp_line
			(start -0.12065 -0.2794)
			(end 0.12065 -0.2794)
			(stroke
				(width 0.1)
				(type default)
			)
			(layer "F.Fab")
		)
		(fp_line
			(start -0.12065 0.2794)
			(end -0.12065 0.3048)
			(stroke
				(width 0.1)
				(type default)
			)
			(layer "F.Fab")
		)
		(fp_line
			(start -0.12065 0.3048)
			(end -0.67945 0.3048)
			(stroke
				(width 0.1)
				(type default)
			)
			(layer "F.Fab")
		)
		(fp_line
			(start 0.120396 0.2794)
			(end -0.12065 0.2794)
			(stroke
				(width 0.1)
				(type default)
			)
			(layer "F.Fab")
		)
		(fp_line
			(start 0.120396 0.3048)
			(end 0.120396 0.2794)
			(stroke
				(width 0.1)
				(type default)
			)
			(layer "F.Fab")
		)
		(fp_line
			(start 0.12065 -0.3048)
			(end 0.67945 -0.3048)
			(stroke
				(width 0.1)
				(type default)
			)
			(layer "F.Fab")
		)
		(fp_line
			(start 0.12065 -0.2794)
			(end 0.12065 -0.3048)
			(stroke
				(width 0.1)
				(type default)
			)
			(layer "F.Fab")
		)
		(fp_line
			(start 0.67945 -0.3048)
			(end 0.67945 0.3048)
			(stroke
				(width 0.1)
				(type default)
			)
			(layer "F.Fab")
		)
		(fp_line
			(start 0.67945 0.3048)
			(end 0.120396 0.3048)
			(stroke
				(width 0.1)
				(type default)
			)
			(layer "F.Fab")
		)
		(pad "1" smd circle
			(at -0.40005 0)
			(size 0 0)
			(layers "F.Cu" "F.Mask" "F.Paste")
			(net "P1V581_PDB_ADC")
		)
		(pad "2" smd circle
			(at 0.40005 0)
			(size 0 0)
			(layers "F.Cu" "F.Mask" "F.Paste")
			(net "GND")
		)
	)
	(footprint ""
		(layer "F.Cu")
		(at 498.89918 -467.976966)
		(property "Reference" "DM13"
			(at -0.3937 -0.588518 0)
			(unlocked yes)
			(layer "F.SilkS")
			(effects
				(font
					(size 0.254 0.127)
					(thickness 0.000001)
				)
				(justify left)
			)
		)
		(property "Value" ""
			(at 0 0 0)
			(layer "F.Fab")
			(effects
				(font
					(size 1.27 1.27)
				)
			)
		)
		(duplicate_pad_numbers_are_jumpers no)
		(pad "1" smd circle
			(at 0 0)
			(size 0.762 0.762)
			(layers "F.Cu" "F.Mask" "F.Paste")
			(net "Net_8588")
		)
	)
	(footprint ""
		(layer "F.Cu")
		(at 356.945184 -337.830668)
		(property "Reference" "PC296_P0_2"
			(at 0 0 0)
			(layer "F.SilkS")
			(hide yes)
			(effects
				(font
					(size 1.27 1.27)
				)
			)
		)
		(property "Value" ""
			(at 0 0 0)
			(layer "F.Fab")
			(effects
				(font
					(size 1.27 1.27)
				)
			)
		)
		(duplicate_pad_numbers_are_jumpers no)
		(fp_line
			(start -0.7874 -0.4064)
			(end 0.7874 -0.4064)
			(stroke
				(width 0.1524)
				(type default)
			)
			(layer "F.SilkS")
		)
		(fp_line
			(start -0.7874 0.4064)
			(end -0.7874 -0.4064)
			(stroke
				(width 0.1524)
				(type default)
			)
			(layer "F.SilkS")
		)
		(fp_line
			(start 0.7874 -0.4064)
			(end 0.7874 0.4064)
			(stroke
				(width 0.1524)
				(type default)
			)
			(layer "F.SilkS")
		)
		(fp_line
			(start 0.7874 0.4064)
			(end -0.7874 0.4064)
			(stroke
				(width 0.1524)
				(type default)
			)
			(layer "F.SilkS")
		)
		(fp_line
			(start -0.67945 -0.305054)
			(end -0.12065 -0.305054)
			(stroke
				(width 0.1)
				(type default)
			)
			(layer "F.Fab")
		)
		(fp_line
			(start -0.67945 0.3048)
			(end -0.67945 -0.305054)
			(stroke
				(width 0.1)
				(type default)
			)
			(layer "F.Fab")
		)
		(fp_line
			(start -0.12065 -0.305054)
			(end -0.12065 -0.2794)
			(stroke
				(width 0.1)
				(type default)
			)
			(layer "F.Fab")
		)
		(fp_line
			(start -0.12065 -0.2794)
			(end 0.12065 -0.2794)
			(stroke
				(width 0.1)
				(type default)
			)
			(layer "F.Fab")
		)
		(fp_line
			(start -0.12065 0.2794)
			(end -0.12065 0.3048)
			(stroke
				(width 0.1)
				(type default)
			)
			(layer "F.Fab")
		)
		(fp_line
			(start -0.12065 0.3048)
			(end -0.67945 0.3048)
			(stroke
				(width 0.1)
				(type default)
			)
			(layer "F.Fab")
		)
		(fp_line
			(start 0.120396 0.2794)
			(end -0.12065 0.2794)
			(stroke
				(width 0.1)
				(type default)
			)
			(layer "F.Fab")
		)
		(fp_line
			(start 0.120396 0.3048)
			(end 0.120396 0.2794)
			(stroke
				(width 0.1)
				(type default)
			)
			(layer "F.Fab")
		)
		(fp_line
			(start 0.12065 -0.3048)
			(end 0.67945 -0.3048)
			(stroke
				(width 0.1)
				(type default)
			)
			(layer "F.Fab")
		)
		(fp_line
			(start 0.12065 -0.2794)
			(end 0.12065 -0.3048)
			(stroke
				(width 0.1)
				(type default)
			)
			(layer "F.Fab")
		)
		(fp_line
			(start 0.67945 -0.3048)
			(end 0.67945 0.3048)
			(stroke
				(width 0.1)
				(type default)
			)
			(layer "F.Fab")
		)
		(fp_line
			(start 0.67945 0.3048)
			(end 0.120396 0.3048)
			(stroke
				(width 0.1)
				(type default)
			)
			(layer "F.Fab")
		)
		(pad "1" smd circle
			(at -0.40005 0)
			(size 0 0)
			(layers "F.Cu" "F.Mask" "F.Paste")
			(net "SW_P12V_PVCCIN_CPU0_FLT")
		)
		(pad "2" smd circle
			(at 0.40005 0)
			(size 0 0)
			(layers "F.Cu" "F.Mask" "F.Paste")
			(net "GND")
		)
	)
	(footprint ""
		(layer "F.Cu")
		(at 352.287078 -238.162338 -90)
		(property "Reference" "C417"
			(at 0 0 270)
			(layer "F.SilkS")
			(hide yes)
			(effects
				(font
					(size 1.27 1.27)
				)
			)
		)
		(property "Value" ""
			(at 0 0 270)
			(layer "F.Fab")
			(effects
				(font
					(size 1.27 1.27)
				)
			)
		)
		(duplicate_pad_numbers_are_jumpers no)
		(fp_line
			(start -0.7874 0.4064)
			(end -0.7874 -0.4064)
			(stroke
				(width 0.1524)
				(type default)
			)
			(layer "F.SilkS")
		)
		(fp_line
			(start 0.7874 0.4064)
			(end -0.7874 0.4064)
			(stroke
				(width 0.1524)
				(type default)
			)
			(layer "F.SilkS")
		)
		(fp_line
			(start -0.7874 -0.4064)
			(end 0.7874 -0.4064)
			(stroke
				(width 0.1524)
				(type default)
			)
			(layer "F.SilkS")
		)
		(fp_line
			(start 0.7874 -0.4064)
			(end 0.7874 0.4064)
			(stroke
				(width 0.1524)
				(type default)
			)
			(layer "F.SilkS")
		)
		(fp_line
			(start -0.67945 0.3048)
			(end -0.67945 -0.305054)
			(stroke
				(width 0.1)
				(type default)
			)
			(layer "F.Fab")
		)
		(fp_line
			(start -0.12065 0.3048)
			(end -0.67945 0.3048)
			(stroke
				(width 0.1)
				(type default)
			)
			(layer "F.Fab")
		)
		(fp_line
			(start 0.120396 0.3048)
			(end 0.120396 0.2794)
			(stroke
				(width 0.1)
				(type default)
			)
			(layer "F.Fab")
		)
		(fp_line
			(start 0.67945 0.3048)
			(end 0.120396 0.3048)
			(stroke
				(width 0.1)
				(type default)
			)
			(layer "F.Fab")
		)
		(fp_line
			(start -0.12065 0.2794)
			(end -0.12065 0.3048)
			(stroke
				(width 0.1)
				(type default)
			)
			(layer "F.Fab")
		)
		(fp_line
			(start 0.120396 0.2794)
			(end -0.12065 0.2794)
			(stroke
				(width 0.1)
				(type default)
			)
			(layer "F.Fab")
		)
		(fp_line
			(start -0.12065 -0.2794)
			(end 0.12065 -0.2794)
			(stroke
				(width 0.1)
				(type default)
			)
			(layer "F.Fab")
		)
		(fp_line
			(start 0.12065 -0.2794)
			(end 0.12065 -0.3048)
			(stroke
				(width 0.1)
				(type default)
			)
			(layer "F.Fab")
		)
		(fp_line
			(start 0.12065 -0.3048)
			(end 0.67945 -0.3048)
			(stroke
				(width 0.1)
				(type default)
			)
			(layer "F.Fab")
		)
		(fp_line
			(start 0.67945 -0.3048)
			(end 0.67945 0.3048)
			(stroke
				(width 0.1)
				(type default)
			)
			(layer "F.Fab")
		)
		(fp_line
			(start -0.67945 -0.305054)
			(end -0.12065 -0.305054)
			(stroke
				(width 0.1)
				(type default)
			)
			(layer "F.Fab")
		)
		(fp_line
			(start -0.12065 -0.305054)
			(end -0.12065 -0.2794)
			(stroke
				(width 0.1)
				(type default)
			)
			(layer "F.Fab")
		)
		(pad "1" smd circle
			(at -0.40005 0 270)
			(size 0 0)
			(layers "F.Cu" "F.Mask" "F.Paste")
			(net "PVCCFA_EHV_FIVRA_CPU0")
		)
		(pad "2" smd circle
			(at 0.40005 0 270)
			(size 0 0)
			(layers "F.Cu" "F.Mask" "F.Paste")
			(net "GND")
		)
	)
	(footprint ""
		(layer "F.Cu")
		(at 109.14888 -54.574948)
		(property "Reference" "R3026"
			(at 0 0 0)
			(layer "F.SilkS")
			(hide yes)
			(effects
				(font
					(size 1.27 1.27)
				)
			)
		)
		(property "Value" ""
			(at 0 0 0)
			(layer "F.Fab")
			(effects
				(font
					(size 1.27 1.27)
				)
			)
		)
		(duplicate_pad_numbers_are_jumpers no)
		(fp_line
			(start -0.7874 -0.4064)
			(end 0.7874 -0.4064)
			(stroke
				(width 0.1524)
				(type default)
			)
			(layer "F.SilkS")
		)
		(fp_line
			(start -0.7874 0.4064)
			(end -0.7874 -0.4064)
			(stroke
				(width 0.1524)
				(type default)
			)
			(layer "F.SilkS")
		)
		(fp_line
			(start 0.7874 -0.4064)
			(end 0.7874 0.4064)
			(stroke
				(width 0.1524)
				(type default)
			)
			(layer "F.SilkS")
		)
		(fp_line
			(start 0.7874 0.4064)
			(end -0.7874 0.4064)
			(stroke
				(width 0.1524)
				(type default)
			)
			(layer "F.SilkS")
		)
		(fp_line
			(start -0.67945 -0.305054)
			(end -0.12065 -0.305054)
			(stroke
				(width 0.1)
				(type default)
			)
			(layer "F.Fab")
		)
		(fp_line
			(start -0.67945 0.3048)
			(end -0.67945 -0.305054)
			(stroke
				(width 0.1)
				(type default)
			)
			(layer "F.Fab")
		)
		(fp_line
			(start -0.12065 -0.305054)
			(end -0.12065 -0.2794)
			(stroke
				(width 0.1)
				(type default)
			)
			(layer "F.Fab")
		)
		(fp_line
			(start -0.12065 -0.2794)
			(end 0.12065 -0.2794)
			(stroke
				(width 0.1)
				(type default)
			)
			(layer "F.Fab")
		)
		(fp_line
			(start -0.12065 0.2794)
			(end -0.12065 0.3048)
			(stroke
				(width 0.1)
				(type default)
			)
			(layer "F.Fab")
		)
		(fp_line
			(start -0.12065 0.3048)
			(end -0.67945 0.3048)
			(stroke
				(width 0.1)
				(type default)
			)
			(layer "F.Fab")
		)
		(fp_line
			(start 0.120396 0.2794)
			(end -0.12065 0.2794)
			(stroke
				(width 0.1)
				(type default)
			)
			(layer "F.Fab")
		)
		(fp_line
			(start 0.120396 0.3048)
			(end 0.120396 0.2794)
			(stroke
				(width 0.1)
				(type default)
			)
			(layer "F.Fab")
		)
		(fp_line
			(start 0.12065 -0.3048)
			(end 0.67945 -0.3048)
			(stroke
				(width 0.1)
				(type default)
			)
			(layer "F.Fab")
		)
		(fp_line
			(start 0.12065 -0.2794)
			(end 0.12065 -0.3048)
			(stroke
				(width 0.1)
				(type default)
			)
			(layer "F.Fab")
		)
		(fp_line
			(start 0.67945 -0.3048)
			(end 0.67945 0.3048)
			(stroke
				(width 0.1)
				(type default)
			)
			(layer "F.Fab")
		)
		(fp_line
			(start 0.67945 0.3048)
			(end 0.120396 0.3048)
			(stroke
				(width 0.1)
				(type default)
			)
			(layer "F.Fab")
		)
		(pad "1" smd circle
			(at -0.40005 0)
			(size 0 0)
			(layers "F.Cu" "F.Mask" "F.Paste")
			(net "JTAG_BMC_PCH_TCK")
		)
		(pad "2" smd circle
			(at 0.40005 0)
			(size 0 0)
			(layers "F.Cu" "F.Mask" "F.Paste")
			(net "GND")
		)
	)
	(footprint ""
		(layer "F.Cu")
		(at 325.61276 -22.675088 90)
		(property "Reference" "R1207"
			(at 0 0 90)
			(layer "F.SilkS")
			(hide yes)
			(effects
				(font
					(size 1.27 1.27)
				)
			)
		)
		(property "Value" ""
			(at 0 0 90)
			(layer "F.Fab")
			(effects
				(font
					(size 1.27 1.27)
				)
			)
		)
		(duplicate_pad_numbers_are_jumpers no)
		(fp_line
			(start 0.7874 -0.4064)
			(end 0.7874 0.4064)
			(stroke
				(width 0.1524)
				(type default)
			)
			(layer "F.SilkS")
		)
		(fp_line
			(start -0.7874 -0.4064)
			(end 0.7874 -0.4064)
			(stroke
				(width 0.1524)
				(type default)
			)
			(layer "F.SilkS")
		)
		(fp_line
			(start 0.7874 0.4064)
			(end -0.7874 0.4064)
			(stroke
				(width 0.1524)
				(type default)
			)
			(layer "F.SilkS")
		)
		(fp_line
			(start -0.7874 0.4064)
			(end -0.7874 -0.4064)
			(stroke
				(width 0.1524)
				(type default)
			)
			(layer "F.SilkS")
		)
		(fp_line
			(start -0.12065 -0.305054)
			(end -0.12065 -0.2794)
			(stroke
				(width 0.1)
				(type default)
			)
			(layer "F.Fab")
		)
		(fp_line
			(start -0.67945 -0.305054)
			(end -0.12065 -0.305054)
			(stroke
				(width 0.1)
				(type default)
			)
			(layer "F.Fab")
		)
		(fp_line
			(start 0.67945 -0.3048)
			(end 0.67945 0.3048)
			(stroke
				(width 0.1)
				(type default)
			)
			(layer "F.Fab")
		)
		(fp_line
			(start 0.12065 -0.3048)
			(end 0.67945 -0.3048)
			(stroke
				(width 0.1)
				(type default)
			)
			(layer "F.Fab")
		)
		(fp_line
			(start 0.12065 -0.2794)
			(end 0.12065 -0.3048)
			(stroke
				(width 0.1)
				(type default)
			)
			(layer "F.Fab")
		)
		(fp_line
			(start -0.12065 -0.2794)
			(end 0.12065 -0.2794)
			(stroke
				(width 0.1)
				(type default)
			)
			(layer "F.Fab")
		)
		(fp_line
			(start 0.120396 0.2794)
			(end -0.12065 0.2794)
			(stroke
				(width 0.1)
				(type default)
			)
			(layer "F.Fab")
		)
		(fp_line
			(start -0.12065 0.2794)
			(end -0.12065 0.3048)
			(stroke
				(width 0.1)
				(type default)
			)
			(layer "F.Fab")
		)
		(fp_line
			(start 0.67945 0.3048)
			(end 0.120396 0.3048)
			(stroke
				(width 0.1)
				(type default)
			)
			(layer "F.Fab")
		)
		(fp_line
			(start 0.120396 0.3048)
			(end 0.120396 0.2794)
			(stroke
				(width 0.1)
				(type default)
			)
			(layer "F.Fab")
		)
		(fp_line
			(start -0.12065 0.3048)
			(end -0.67945 0.3048)
			(stroke
				(width 0.1)
				(type default)
			)
			(layer "F.Fab")
		)
		(fp_line
			(start -0.67945 0.3048)
			(end -0.67945 -0.305054)
			(stroke
				(width 0.1)
				(type default)
			)
			(layer "F.Fab")
		)
		(pad "1" smd circle
			(at -0.40005 0 90)
			(size 0 0)
			(layers "F.Cu" "F.Mask" "F.Paste")
			(net "RST_RSMRST_PLD_R_N")
		)
		(pad "2" smd circle
			(at 0.40005 0 90)
			(size 0 0)
			(layers "F.Cu" "F.Mask" "F.Paste")
			(net "RST_RSMRST_PCH_N")
		)
	)
	(footprint ""
		(layer "F.Cu")
		(at 204.99578 -112.02924 180)
		(property "Reference" "R4722"
			(at 0 0 180)
			(layer "F.SilkS")
			(hide yes)
			(effects
				(font
					(size 1.27 1.27)
				)
			)
		)
		(property "Value" ""
			(at 0 0 180)
			(layer "F.Fab")
			(effects
				(font
					(size 1.27 1.27)
				)
			)
		)
		(duplicate_pad_numbers_are_jumpers no)
		(fp_line
			(start 0.7874 0.4064)
			(end -0.7874 0.4064)
			(stroke
				(width 0.1524)
				(type default)
			)
			(layer "F.SilkS")
		)
		(fp_line
			(start 0.7874 -0.4064)
			(end 0.7874 0.4064)
			(stroke
				(width 0.1524)
				(type default)
			)
			(layer "F.SilkS")
		)
		(fp_line
			(start -0.7874 0.4064)
			(end -0.7874 -0.4064)
			(stroke
				(width 0.1524)
				(type default)
			)
			(layer "F.SilkS")
		)
		(fp_line
			(start -0.7874 -0.4064)
			(end 0.7874 -0.4064)
			(stroke
				(width 0.1524)
				(type default)
			)
			(layer "F.SilkS")
		)
		(fp_line
			(start 0.67945 0.3048)
			(end 0.120396 0.3048)
			(stroke
				(width 0.1)
				(type default)
			)
			(layer "F.Fab")
		)
		(fp_line
			(start 0.67945 -0.3048)
			(end 0.67945 0.3048)
			(stroke
				(width 0.1)
				(type default)
			)
			(layer "F.Fab")
		)
		(fp_line
			(start 0.12065 -0.2794)
			(end 0.12065 -0.3048)
			(stroke
				(width 0.1)
				(type default)
			)
			(layer "F.Fab")
		)
		(fp_line
			(start 0.12065 -0.3048)
			(end 0.67945 -0.3048)
			(stroke
				(width 0.1)
				(type default)
			)
			(layer "F.Fab")
		)
		(fp_line
			(start 0.120396 0.3048)
			(end 0.120396 0.2794)
			(stroke
				(width 0.1)
				(type default)
			)
			(layer "F.Fab")
		)
		(fp_line
			(start 0.120396 0.2794)
			(end -0.12065 0.2794)
			(stroke
				(width 0.1)
				(type default)
			)
			(layer "F.Fab")
		)
		(fp_line
			(start -0.12065 0.3048)
			(end -0.67945 0.3048)
			(stroke
				(width 0.1)
				(type default)
			)
			(layer "F.Fab")
		)
		(fp_line
			(start -0.12065 0.2794)
			(end -0.12065 0.3048)
			(stroke
				(width 0.1)
				(type default)
			)
			(layer "F.Fab")
		)
		(fp_line
			(start -0.12065 -0.2794)
			(end 0.12065 -0.2794)
			(stroke
				(width 0.1)
				(type default)
			)
			(layer "F.Fab")
		)
		(fp_line
			(start -0.12065 -0.305054)
			(end -0.12065 -0.2794)
			(stroke
				(width 0.1)
				(type default)
			)
			(layer "F.Fab")
		)
		(fp_line
			(start -0.67945 0.3048)
			(end -0.67945 -0.305054)
			(stroke
				(width 0.1)
				(type default)
			)
			(layer "F.Fab")
		)
		(fp_line
			(start -0.67945 -0.305054)
			(end -0.12065 -0.305054)
			(stroke
				(width 0.1)
				(type default)
			)
			(layer "F.Fab")
		)
		(pad "1" smd circle
			(at -0.40005 0 180)
			(size 0 0)
			(layers "F.Cu" "F.Mask" "F.Paste")
			(net "FM_PCH_BMC_RST_R_N")
		)
		(pad "2" smd circle
			(at 0.40005 0 180)
			(size 0 0)
			(layers "F.Cu" "F.Mask" "F.Paste")
			(net "P3V3_AUX")
		)
	)
	(footprint ""
		(layer "F.Cu")
		(at 428.179992 -396.448534)
		(property "Reference" "Q104"
			(at 0.079248 -1.848104 0)
			(unlocked yes)
			(layer "F.SilkS")
			(effects
				(font
					(size 0.7874 0.5842)
					(thickness 0.1524)
				)
				(justify left)
			)
		)
		(property "Value" ""
			(at 0 0 0)
			(layer "F.Fab")
			(effects
				(font
					(size 1.27 1.27)
				)
			)
		)
		(duplicate_pad_numbers_are_jumpers no)
		(fp_line
			(start -1.332738 -1.100074)
			(end -0.4826 -1.100074)
			(stroke
				(width 0.1524)
				(type default)
			)
			(layer "F.SilkS")
		)
		(fp_line
			(start -1.332738 1.100074)
			(end -1.332738 -1.100074)
			(stroke
				(width 0.1524)
				(type default)
			)
			(layer "F.SilkS")
		)
		(fp_line
			(start -0.4826 -1.100074)
			(end 0 -0.541274)
			(stroke
				(width 0.1524)
				(type default)
			)
			(layer "F.SilkS")
		)
		(fp_line
			(start 0 -0.541274)
			(end 0.4826 -1.100074)
			(stroke
				(width 0.1524)
				(type default)
			)
			(layer "F.SilkS")
		)
		(fp_line
			(start 0.4826 -1.100074)
			(end 1.332738 -1.100074)
			(stroke
				(width 0.1524)
				(type default)
			)
			(layer "F.SilkS")
		)
		(fp_line
			(start 1.332738 -1.100074)
			(end 1.332738 1.100074)
			(stroke
				(width 0.1524)
				(type default)
			)
			(layer "F.SilkS")
		)
		(fp_line
			(start 1.332738 1.100074)
			(end -1.332738 1.100074)
			(stroke
				(width 0.1524)
				(type default)
			)
			(layer "F.SilkS")
		)
		(fp_poly
			(pts
				(xy -0.647192 -2.136902) (xy -0.99822 -1.434846) (xy -1.349248 -2.136902)
			)
			(stroke
				(width 0)
				(type default)
			)
			(fill yes)
			(layer "F.SilkS")
		)
		(fp_line
			(start -0.674878 -1.100074)
			(end 0.674878 -1.100074)
			(stroke
				(width 0.1)
				(type default)
			)
			(layer "F.Fab")
		)
		(fp_line
			(start -0.674878 1.100074)
			(end -0.674878 -1.100074)
			(stroke
				(width 0.1)
				(type default)
			)
			(layer "F.Fab")
		)
		(fp_line
			(start 0.674878 -1.100074)
			(end 0.674878 1.100074)
			(stroke
				(width 0.1)
				(type default)
			)
			(layer "F.Fab")
		)
		(fp_line
			(start 0.674878 1.100074)
			(end -0.674878 1.100074)
			(stroke
				(width 0.1)
				(type default)
			)
			(layer "F.Fab")
		)
		(fp_poly
			(pts
				(xy -2.2352 -0.298958) (xy -2.2352 -1.001014) (xy -1.533144 -0.649986)
			)
			(stroke
				(width 0)
				(type default)
			)
			(fill yes)
			(layer "F.Fab")
		)
		(pad "1" smd rect
			(at -0.94996 -0.649986 90)
			(size 0.4318 0.508)
			(layers "F.Cu" "F.Mask" "F.Paste")
			(net "GND")
		)
		(pad "2" smd rect
			(at -0.94996 0 90)
			(size 0.4318 0.508)
			(layers "F.Cu" "F.Mask" "F.Paste")
			(net "GPU_FPGA_OVERT_N")
		)
		(pad "3" smd rect
			(at -0.94996 0.649986 90)
			(size 0.4318 0.508)
			(layers "F.Cu" "F.Mask" "F.Paste")
			(net "GPU_FPGA_OVERT_ISO_N")
		)
		(pad "4" smd rect
			(at 0.94996 0.649986 90)
			(size 0.4318 0.508)
			(layers "F.Cu" "F.Mask" "F.Paste")
			(net "GND")
		)
		(pad "5" smd rect
			(at 0.94996 0 90)
			(size 0.4318 0.508)
			(layers "F.Cu" "F.Mask" "F.Paste")
			(net "GPU_FPGA_OVERT")
		)
		(pad "6" smd rect
			(at 0.94996 -0.649986 90)
			(size 0.4318 0.508)
			(layers "F.Cu" "F.Mask" "F.Paste")
			(net "GPU_FPGA_OVERT")
		)
	)
	(footprint ""
		(layer "F.Cu")
		(at 128.948434 -361.313476 180)
		(property "Reference" "PR1338"
			(at 0 0 180)
			(layer "F.SilkS")
			(hide yes)
			(effects
				(font
					(size 1.27 1.27)
				)
			)
		)
		(property "Value" ""
			(at 0 0 180)
			(layer "F.Fab")
			(effects
				(font
					(size 1.27 1.27)
				)
			)
		)
		(duplicate_pad_numbers_are_jumpers no)
		(fp_line
			(start 0.7874 0.4064)
			(end -0.7874 0.4064)
			(stroke
				(width 0.1524)
				(type default)
			)
			(layer "F.SilkS")
		)
		(fp_line
			(start 0.7874 -0.4064)
			(end 0.7874 0.4064)
			(stroke
				(width 0.1524)
				(type default)
			)
			(layer "F.SilkS")
		)
		(fp_line
			(start -0.7874 0.4064)
			(end -0.7874 -0.4064)
			(stroke
				(width 0.1524)
				(type default)
			)
			(layer "F.SilkS")
		)
		(fp_line
			(start -0.7874 -0.4064)
			(end 0.7874 -0.4064)
			(stroke
				(width 0.1524)
				(type default)
			)
			(layer "F.SilkS")
		)
		(fp_line
			(start 0.67945 0.3048)
			(end 0.120396 0.3048)
			(stroke
				(width 0.1)
				(type default)
			)
			(layer "F.Fab")
		)
		(fp_line
			(start 0.67945 -0.3048)
			(end 0.67945 0.3048)
			(stroke
				(width 0.1)
				(type default)
			)
			(layer "F.Fab")
		)
		(fp_line
			(start 0.12065 -0.2794)
			(end 0.12065 -0.3048)
			(stroke
				(width 0.1)
				(type default)
			)
			(layer "F.Fab")
		)
		(fp_line
			(start 0.12065 -0.3048)
			(end 0.67945 -0.3048)
			(stroke
				(width 0.1)
				(type default)
			)
			(layer "F.Fab")
		)
		(fp_line
			(start 0.120396 0.3048)
			(end 0.120396 0.2794)
			(stroke
				(width 0.1)
				(type default)
			)
			(layer "F.Fab")
		)
		(fp_line
			(start 0.120396 0.2794)
			(end -0.12065 0.2794)
			(stroke
				(width 0.1)
				(type default)
			)
			(layer "F.Fab")
		)
		(fp_line
			(start -0.12065 0.3048)
			(end -0.67945 0.3048)
			(stroke
				(width 0.1)
				(type default)
			)
			(layer "F.Fab")
		)
		(fp_line
			(start -0.12065 0.2794)
			(end -0.12065 0.3048)
			(stroke
				(width 0.1)
				(type default)
			)
			(layer "F.Fab")
		)
		(fp_line
			(start -0.12065 -0.2794)
			(end 0.12065 -0.2794)
			(stroke
				(width 0.1)
				(type default)
			)
			(layer "F.Fab")
		)
		(fp_line
			(start -0.12065 -0.305054)
			(end -0.12065 -0.2794)
			(stroke
				(width 0.1)
				(type default)
			)
			(layer "F.Fab")
		)
		(fp_line
			(start -0.67945 0.3048)
			(end -0.67945 -0.305054)
			(stroke
				(width 0.1)
				(type default)
			)
			(layer "F.Fab")
		)
		(fp_line
			(start -0.67945 -0.305054)
			(end -0.12065 -0.305054)
			(stroke
				(width 0.1)
				(type default)
			)
			(layer "F.Fab")
		)
		(pad "1" smd circle
			(at -0.40005 0 180)
			(size 0 0)
			(layers "F.Cu" "F.Mask" "F.Paste")
			(net "P3V3_AUX")
		)
		(pad "2" smd circle
			(at 0.40005 0 180)
			(size 0 0)
			(layers "F.Cu" "F.Mask" "F.Paste")
			(net "PVPP_HBM_CPU1_VCC")
		)
	)
	(footprint ""
		(layer "F.Cu")
		(at 465.823554 -115.295934 180)
		(property "Reference" "R1127"
			(at 0 0 180)
			(layer "F.SilkS")
			(hide yes)
			(effects
				(font
					(size 1.27 1.27)
				)
			)
		)
		(property "Value" ""
			(at 0 0 180)
			(layer "F.Fab")
			(effects
				(font
					(size 1.27 1.27)
				)
			)
		)
		(duplicate_pad_numbers_are_jumpers no)
		(fp_line
			(start 0.7874 0.4064)
			(end -0.7874 0.4064)
			(stroke
				(width 0.1524)
				(type default)
			)
			(layer "F.SilkS")
		)
		(fp_line
			(start 0.7874 -0.4064)
			(end 0.7874 0.4064)
			(stroke
				(width 0.1524)
				(type default)
			)
			(layer "F.SilkS")
		)
		(fp_line
			(start -0.7874 0.4064)
			(end -0.7874 -0.4064)
			(stroke
				(width 0.1524)
				(type default)
			)
			(layer "F.SilkS")
		)
		(fp_line
			(start -0.7874 -0.4064)
			(end 0.7874 -0.4064)
			(stroke
				(width 0.1524)
				(type default)
			)
			(layer "F.SilkS")
		)
		(fp_line
			(start 0.67945 0.3048)
			(end 0.120396 0.3048)
			(stroke
				(width 0.1)
				(type default)
			)
			(layer "F.Fab")
		)
		(fp_line
			(start 0.67945 -0.3048)
			(end 0.67945 0.3048)
			(stroke
				(width 0.1)
				(type default)
			)
			(layer "F.Fab")
		)
		(fp_line
			(start 0.12065 -0.2794)
			(end 0.12065 -0.3048)
			(stroke
				(width 0.1)
				(type default)
			)
			(layer "F.Fab")
		)
		(fp_line
			(start 0.12065 -0.3048)
			(end 0.67945 -0.3048)
			(stroke
				(width 0.1)
				(type default)
			)
			(layer "F.Fab")
		)
		(fp_line
			(start 0.120396 0.3048)
			(end 0.120396 0.2794)
			(stroke
				(width 0.1)
				(type default)
			)
			(layer "F.Fab")
		)
		(fp_line
			(start 0.120396 0.2794)
			(end -0.12065 0.2794)
			(stroke
				(width 0.1)
				(type default)
			)
			(layer "F.Fab")
		)
		(fp_line
			(start -0.12065 0.3048)
			(end -0.67945 0.3048)
			(stroke
				(width 0.1)
				(type default)
			)
			(layer "F.Fab")
		)
		(fp_line
			(start -0.12065 0.2794)
			(end -0.12065 0.3048)
			(stroke
				(width 0.1)
				(type default)
			)
			(layer "F.Fab")
		)
		(fp_line
			(start -0.12065 -0.2794)
			(end 0.12065 -0.2794)
			(stroke
				(width 0.1)
				(type default)
			)
			(layer "F.Fab")
		)
		(fp_line
			(start -0.12065 -0.305054)
			(end -0.12065 -0.2794)
			(stroke
				(width 0.1)
				(type default)
			)
			(layer "F.Fab")
		)
		(fp_line
			(start -0.67945 0.3048)
			(end -0.67945 -0.305054)
			(stroke
				(width 0.1)
				(type default)
			)
			(layer "F.Fab")
		)
		(fp_line
			(start -0.67945 -0.305054)
			(end -0.12065 -0.305054)
			(stroke
				(width 0.1)
				(type default)
			)
			(layer "F.Fab")
		)
		(pad "1" smd circle
			(at -0.40005 0 180)
			(size 0 0)
			(layers "F.Cu" "F.Mask" "F.Paste")
			(net "P3V3_AUX")
		)
		(pad "2" smd circle
			(at 0.40005 0 180)
			(size 0 0)
			(layers "F.Cu" "F.Mask" "F.Paste")
			(net "PD_SMB_OCP1_HP_ADD0")
		)
	)
	(footprint ""
		(layer "F.Cu")
		(at 303.9872 -25.8064 180)
		(property "Reference" "R4787"
			(at 0 0 180)
			(layer "F.SilkS")
			(hide yes)
			(effects
				(font
					(size 1.27 1.27)
				)
			)
		)
		(property "Value" ""
			(at 0 0 180)
			(layer "F.Fab")
			(effects
				(font
					(size 1.27 1.27)
				)
			)
		)
		(duplicate_pad_numbers_are_jumpers no)
		(fp_line
			(start 0.7874 0.4064)
			(end -0.7874 0.4064)
			(stroke
				(width 0.1524)
				(type default)
			)
			(layer "F.SilkS")
		)
		(fp_line
			(start 0.7874 -0.4064)
			(end 0.7874 0.4064)
			(stroke
				(width 0.1524)
				(type default)
			)
			(layer "F.SilkS")
		)
		(fp_line
			(start -0.7874 0.4064)
			(end -0.7874 -0.4064)
			(stroke
				(width 0.1524)
				(type default)
			)
			(layer "F.SilkS")
		)
		(fp_line
			(start -0.7874 -0.4064)
			(end 0.7874 -0.4064)
			(stroke
				(width 0.1524)
				(type default)
			)
			(layer "F.SilkS")
		)
		(fp_line
			(start 0.67945 0.3048)
			(end 0.120396 0.3048)
			(stroke
				(width 0.1)
				(type default)
			)
			(layer "F.Fab")
		)
		(fp_line
			(start 0.67945 -0.3048)
			(end 0.67945 0.3048)
			(stroke
				(width 0.1)
				(type default)
			)
			(layer "F.Fab")
		)
		(fp_line
			(start 0.12065 -0.2794)
			(end 0.12065 -0.3048)
			(stroke
				(width 0.1)
				(type default)
			)
			(layer "F.Fab")
		)
		(fp_line
			(start 0.12065 -0.3048)
			(end 0.67945 -0.3048)
			(stroke
				(width 0.1)
				(type default)
			)
			(layer "F.Fab")
		)
		(fp_line
			(start 0.120396 0.3048)
			(end 0.120396 0.2794)
			(stroke
				(width 0.1)
				(type default)
			)
			(layer "F.Fab")
		)
		(fp_line
			(start 0.120396 0.2794)
			(end -0.12065 0.2794)
			(stroke
				(width 0.1)
				(type default)
			)
			(layer "F.Fab")
		)
		(fp_line
			(start -0.12065 0.3048)
			(end -0.67945 0.3048)
			(stroke
				(width 0.1)
				(type default)
			)
			(layer "F.Fab")
		)
		(fp_line
			(start -0.12065 0.2794)
			(end -0.12065 0.3048)
			(stroke
				(width 0.1)
				(type default)
			)
			(layer "F.Fab")
		)
		(fp_line
			(start -0.12065 -0.2794)
			(end 0.12065 -0.2794)
			(stroke
				(width 0.1)
				(type default)
			)
			(layer "F.Fab")
		)
		(fp_line
			(start -0.12065 -0.305054)
			(end -0.12065 -0.2794)
			(stroke
				(width 0.1)
				(type default)
			)
			(layer "F.Fab")
		)
		(fp_line
			(start -0.67945 0.3048)
			(end -0.67945 -0.305054)
			(stroke
				(width 0.1)
				(type default)
			)
			(layer "F.Fab")
		)
		(fp_line
			(start -0.67945 -0.305054)
			(end -0.12065 -0.305054)
			(stroke
				(width 0.1)
				(type default)
			)
			(layer "F.Fab")
		)
		(pad "1" smd circle
			(at -0.40005 0 180)
			(size 0 0)
			(layers "F.Cu" "F.Mask" "F.Paste")
			(net "PWRGD_DSW_PWROK_TRIGGER")
		)
		(pad "2" smd circle
			(at 0.40005 0 180)
			(size 0 0)
			(layers "F.Cu" "F.Mask" "F.Paste")
			(net "PWRGD_DSW_PWROK_R5")
		)
	)
	(footprint ""
		(layer "F.Cu")
		(at 150.67788 -47.970948 90)
		(property "Reference" "R3573"
			(at 0 0 90)
			(layer "F.SilkS")
			(hide yes)
			(effects
				(font
					(size 1.27 1.27)
				)
			)
		)
		(property "Value" ""
			(at 0 0 90)
			(layer "F.Fab")
			(effects
				(font
					(size 1.27 1.27)
				)
			)
		)
		(duplicate_pad_numbers_are_jumpers no)
		(fp_line
			(start 0.7874 -0.4064)
			(end 0.7874 0.4064)
			(stroke
				(width 0.1524)
				(type default)
			)
			(layer "F.SilkS")
		)
		(fp_line
			(start -0.7874 -0.4064)
			(end 0.7874 -0.4064)
			(stroke
				(width 0.1524)
				(type default)
			)
			(layer "F.SilkS")
		)
		(fp_line
			(start 0.7874 0.4064)
			(end -0.7874 0.4064)
			(stroke
				(width 0.1524)
				(type default)
			)
			(layer "F.SilkS")
		)
		(fp_line
			(start -0.7874 0.4064)
			(end -0.7874 -0.4064)
			(stroke
				(width 0.1524)
				(type default)
			)
			(layer "F.SilkS")
		)
		(fp_line
			(start -0.12065 -0.305054)
			(end -0.12065 -0.2794)
			(stroke
				(width 0.1)
				(type default)
			)
			(layer "F.Fab")
		)
		(fp_line
			(start -0.67945 -0.305054)
			(end -0.12065 -0.305054)
			(stroke
				(width 0.1)
				(type default)
			)
			(layer "F.Fab")
		)
		(fp_line
			(start 0.67945 -0.3048)
			(end 0.67945 0.3048)
			(stroke
				(width 0.1)
				(type default)
			)
			(layer "F.Fab")
		)
		(fp_line
			(start 0.12065 -0.3048)
			(end 0.67945 -0.3048)
			(stroke
				(width 0.1)
				(type default)
			)
			(layer "F.Fab")
		)
		(fp_line
			(start 0.12065 -0.2794)
			(end 0.12065 -0.3048)
			(stroke
				(width 0.1)
				(type default)
			)
			(layer "F.Fab")
		)
		(fp_line
			(start -0.12065 -0.2794)
			(end 0.12065 -0.2794)
			(stroke
				(width 0.1)
				(type default)
			)
			(layer "F.Fab")
		)
		(fp_line
			(start 0.120396 0.2794)
			(end -0.12065 0.2794)
			(stroke
				(width 0.1)
				(type default)
			)
			(layer "F.Fab")
		)
		(fp_line
			(start -0.12065 0.2794)
			(end -0.12065 0.3048)
			(stroke
				(width 0.1)
				(type default)
			)
			(layer "F.Fab")
		)
		(fp_line
			(start 0.67945 0.3048)
			(end 0.120396 0.3048)
			(stroke
				(width 0.1)
				(type default)
			)
			(layer "F.Fab")
		)
		(fp_line
			(start 0.120396 0.3048)
			(end 0.120396 0.2794)
			(stroke
				(width 0.1)
				(type default)
			)
			(layer "F.Fab")
		)
		(fp_line
			(start -0.12065 0.3048)
			(end -0.67945 0.3048)
			(stroke
				(width 0.1)
				(type default)
			)
			(layer "F.Fab")
		)
		(fp_line
			(start -0.67945 0.3048)
			(end -0.67945 -0.305054)
			(stroke
				(width 0.1)
				(type default)
			)
			(layer "F.Fab")
		)
		(pad "1" smd circle
			(at -0.40005 0 90)
			(size 0 0)
			(layers "F.Cu" "F.Mask" "F.Paste")
			(net "SMB_INA230_4_3V3AUX_SDA_R")
		)
		(pad "2" smd circle
			(at 0.40005 0 90)
			(size 0 0)
			(layers "F.Cu" "F.Mask" "F.Paste")
			(net "SMB_INA230_4_3V3AUX_SDA_R1")
		)
	)
	(footprint ""
		(layer "F.Cu")
		(at 262.401558 -394.17117)
		(property "Reference" "PR2529"
			(at 0 0 0)
			(layer "F.SilkS")
			(hide yes)
			(effects
				(font
					(size 1.27 1.27)
				)
			)
		)
		(property "Value" ""
			(at 0 0 0)
			(layer "F.Fab")
			(effects
				(font
					(size 1.27 1.27)
				)
			)
		)
		(duplicate_pad_numbers_are_jumpers no)
		(fp_line
			(start -0.7874 -0.4064)
			(end 0.7874 -0.4064)
			(stroke
				(width 0.1524)
				(type default)
			)
			(layer "F.SilkS")
		)
		(fp_line
			(start -0.7874 0.4064)
			(end -0.7874 -0.4064)
			(stroke
				(width 0.1524)
				(type default)
			)
			(layer "F.SilkS")
		)
		(fp_line
			(start 0.7874 -0.4064)
			(end 0.7874 0.4064)
			(stroke
				(width 0.1524)
				(type default)
			)
			(layer "F.SilkS")
		)
		(fp_line
			(start 0.7874 0.4064)
			(end -0.7874 0.4064)
			(stroke
				(width 0.1524)
				(type default)
			)
			(layer "F.SilkS")
		)
		(fp_line
			(start -0.67945 -0.305054)
			(end -0.12065 -0.305054)
			(stroke
				(width 0.1)
				(type default)
			)
			(layer "F.Fab")
		)
		(fp_line
			(start -0.67945 0.3048)
			(end -0.67945 -0.305054)
			(stroke
				(width 0.1)
				(type default)
			)
			(layer "F.Fab")
		)
		(fp_line
			(start -0.12065 -0.305054)
			(end -0.12065 -0.2794)
			(stroke
				(width 0.1)
				(type default)
			)
			(layer "F.Fab")
		)
		(fp_line
			(start -0.12065 -0.2794)
			(end 0.12065 -0.2794)
			(stroke
				(width 0.1)
				(type default)
			)
			(layer "F.Fab")
		)
		(fp_line
			(start -0.12065 0.2794)
			(end -0.12065 0.3048)
			(stroke
				(width 0.1)
				(type default)
			)
			(layer "F.Fab")
		)
		(fp_line
			(start -0.12065 0.3048)
			(end -0.67945 0.3048)
			(stroke
				(width 0.1)
				(type default)
			)
			(layer "F.Fab")
		)
		(fp_line
			(start 0.120396 0.2794)
			(end -0.12065 0.2794)
			(stroke
				(width 0.1)
				(type default)
			)
			(layer "F.Fab")
		)
		(fp_line
			(start 0.120396 0.3048)
			(end 0.120396 0.2794)
			(stroke
				(width 0.1)
				(type default)
			)
			(layer "F.Fab")
		)
		(fp_line
			(start 0.12065 -0.3048)
			(end 0.67945 -0.3048)
			(stroke
				(width 0.1)
				(type default)
			)
			(layer "F.Fab")
		)
		(fp_line
			(start 0.12065 -0.2794)
			(end 0.12065 -0.3048)
			(stroke
				(width 0.1)
				(type default)
			)
			(layer "F.Fab")
		)
		(fp_line
			(start 0.67945 -0.3048)
			(end 0.67945 0.3048)
			(stroke
				(width 0.1)
				(type default)
			)
			(layer "F.Fab")
		)
		(fp_line
			(start 0.67945 0.3048)
			(end 0.120396 0.3048)
			(stroke
				(width 0.1)
				(type default)
			)
			(layer "F.Fab")
		)
		(pad "1" smd circle
			(at -0.40005 0)
			(size 0 0)
			(layers "F.Cu" "F.Mask" "F.Paste")
			(net "P12V_HSC_GATE_G2")
		)
		(pad "2" smd circle
			(at 0.40005 0)
			(size 0 0)
			(layers "F.Cu" "F.Mask" "F.Paste")
			(net "P12V_HSC_GATE2")
		)
	)
	(footprint ""
		(layer "F.Cu")
		(at 520.044426 -148.123148 90)
		(property "Reference" "X19"
			(at -3.511804 2.541524 90)
			(unlocked yes)
			(layer "F.SilkS")
			(effects
				(font
					(size 0.7874 0.5842)
					(thickness 0.1524)
				)
				(justify left)
			)
		)
		(property "Value" ""
			(at 0 0 90)
			(layer "F.Fab")
			(effects
				(font
					(size 1.27 1.27)
				)
			)
		)
		(property "Device Type" "TP_TDR_4P_FTS_MPKT4_H025P0200_I"
			(at 1.30175 1.27 180)
			(unlocked yes)
			(layer "F.Fab")
			(hide yes)
			(effects
				(font
					(size 0.635 0.4064)
					(thickness 0.1524)
				)
			)
		)
		(property "User Part Number" "TP15"
			(at 1.30175 1.27 180)
			(unlocked yes)
			(layer "Cmts.User")
			(hide yes)
			(effects
				(font
					(size 0.635 0.4064)
					(thickness 0.1524)
				)
			)
		)
		(duplicate_pad_numbers_are_jumpers no)
		(fp_line
			(start 2.54 -1.27)
			(end 0 -1.27)
			(stroke
				(width 0.1524)
				(type default)
			)
			(layer "F.SilkS")
		)
		(fp_line
			(start 0 -1.27)
			(end 0 -0.635)
			(stroke
				(width 0.1524)
				(type default)
			)
			(layer "F.SilkS")
		)
		(fp_line
			(start 2.54 -1.1303)
			(end 2.54 -1.27)
			(stroke
				(width 0.1524)
				(type default)
			)
			(layer "F.SilkS")
		)
		(fp_line
			(start 0 0.635)
			(end 0 1.905)
			(stroke
				(width 0.1524)
				(type default)
			)
			(layer "F.SilkS")
		)
		(fp_line
			(start 2.54 1.4097)
			(end 2.54 1.1303)
			(stroke
				(width 0.1524)
				(type default)
			)
			(layer "F.SilkS")
		)
		(fp_line
			(start 0 3.175)
			(end 0 3.81)
			(stroke
				(width 0.1524)
				(type default)
			)
			(layer "F.SilkS")
		)
		(fp_line
			(start 2.54 3.81)
			(end 2.54 3.6703)
			(stroke
				(width 0.1524)
				(type default)
			)
			(layer "F.SilkS")
		)
		(fp_line
			(start 0 3.81)
			(end 2.54 3.81)
			(stroke
				(width 0.1524)
				(type default)
			)
			(layer "F.SilkS")
		)
		(fp_poly
			(pts
				(xy -1.330706 0) (xy -2.854706 0.762) (xy -2.854706 -0.762)
			)
			(stroke
				(width 0)
				(type default)
			)
			(fill yes)
			(layer "F.SilkS")
		)
		(fp_line
			(start 2.54 -1.27)
			(end 0 -1.27)
			(stroke
				(width 0.1)
				(type default)
			)
			(layer "F.Fab")
		)
		(fp_line
			(start 0 -1.27)
			(end 0 3.81)
			(stroke
				(width 0.1)
				(type default)
			)
			(layer "F.Fab")
		)
		(fp_line
			(start 2.54 3.81)
			(end 2.54 -1.27)
			(stroke
				(width 0.1)
				(type default)
			)
			(layer "F.Fab")
		)
		(fp_line
			(start 0 3.81)
			(end 2.54 3.81)
			(stroke
				(width 0.1)
				(type default)
			)
			(layer "F.Fab")
		)
		(fp_poly
			(pts
				(xy -0.761746 0) (xy -2.285746 -0.762) (xy -2.285746 0.762)
			)
			(stroke
				(width 0)
				(type default)
			)
			(fill yes)
			(layer "F.Fab")
		)
		(pad "1" thru_hole circle
			(at 0 0 90)
			(size 1.0033 1.0033)
			(drill 0.249936)
			(layers "*.Cu" "*.Mask")
			(remove_unused_layers no)
			(net "TDR_DIFF_100_TOP_DN")
			(clearance 0.10795)
			(thermal_gap 0.10795)
			(padstack
				(mode front_inner_back)
				(layer "Inner"
					(shape circle)
					(size 0.8001 0.8001)
					(clearance 0.1524)
				)
				(layer "B.Cu"
					(shape circle)
					(size 1.0033 1.0033)
					(clearance 0.10795)
				)
			)
		)
		(pad "2" thru_hole circle
			(at 2.54 0 90)
			(size 1.9939 1.9939)
			(drill 0.249936)
			(layers "*.Cu" "*.Mask")
			(remove_unused_layers no)
			(net "T1_GND")
			(clearance 0.10795)
			(thermal_gap 0.10795)
			(padstack
				(mode front_inner_back)
				(layer "Inner"
					(shape circle)
					(size 0.8001 0.8001)
					(clearance 0.1524)
				)
				(layer "B.Cu"
					(shape circle)
					(size 1.9939 1.9939)
					(clearance 0.10795)
				)
			)
		)
		(pad "3" thru_hole circle
			(at 2.54 2.54 90)
			(size 1.9939 1.9939)
			(drill 0.249936)
			(layers "*.Cu" "*.Mask")
			(remove_unused_layers no)
			(net "T1_GND")
			(clearance 0.10795)
			(thermal_gap 0.10795)
			(padstack
				(mode front_inner_back)
				(layer "Inner"
					(shape circle)
					(size 0.8001 0.8001)
					(clearance 0.1524)
				)
				(layer "B.Cu"
					(shape circle)
					(size 1.9939 1.9939)
					(clearance 0.10795)
				)
			)
		)
		(pad "4" thru_hole circle
			(at 0 2.54 90)
			(size 1.0033 1.0033)
			(drill 0.249936)
			(layers "*.Cu" "*.Mask")
			(remove_unused_layers no)
			(net "TDR_DIFF_100_TOP_DP")
			(clearance 0.10795)
			(thermal_gap 0.10795)
			(padstack
				(mode front_inner_back)
				(layer "Inner"
					(shape circle)
					(size 0.8001 0.8001)
					(clearance 0.1524)
				)
				(layer "B.Cu"
					(shape circle)
					(size 1.0033 1.0033)
					(clearance 0.10795)
				)
			)
		)
	)
	(footprint ""
		(layer "F.Cu")
		(at 369.368578 -413.90951 -90)
		(property "Reference" "R4191"
			(at 0 0 270)
			(layer "F.SilkS")
			(hide yes)
			(effects
				(font
					(size 1.27 1.27)
				)
			)
		)
		(property "Value" ""
			(at 0 0 270)
			(layer "F.Fab")
			(effects
				(font
					(size 1.27 1.27)
				)
			)
		)
		(duplicate_pad_numbers_are_jumpers no)
		(fp_line
			(start -0.7874 0.4064)
			(end -0.7874 -0.4064)
			(stroke
				(width 0.1524)
				(type default)
			)
			(layer "F.SilkS")
		)
		(fp_line
			(start 0.7874 0.4064)
			(end -0.7874 0.4064)
			(stroke
				(width 0.1524)
				(type default)
			)
			(layer "F.SilkS")
		)
		(fp_line
			(start -0.7874 -0.4064)
			(end 0.7874 -0.4064)
			(stroke
				(width 0.1524)
				(type default)
			)
			(layer "F.SilkS")
		)
		(fp_line
			(start 0.7874 -0.4064)
			(end 0.7874 0.4064)
			(stroke
				(width 0.1524)
				(type default)
			)
			(layer "F.SilkS")
		)
		(fp_line
			(start -0.67945 0.3048)
			(end -0.67945 -0.305054)
			(stroke
				(width 0.1)
				(type default)
			)
			(layer "F.Fab")
		)
		(fp_line
			(start -0.12065 0.3048)
			(end -0.67945 0.3048)
			(stroke
				(width 0.1)
				(type default)
			)
			(layer "F.Fab")
		)
		(fp_line
			(start 0.120396 0.3048)
			(end 0.120396 0.2794)
			(stroke
				(width 0.1)
				(type default)
			)
			(layer "F.Fab")
		)
		(fp_line
			(start 0.67945 0.3048)
			(end 0.120396 0.3048)
			(stroke
				(width 0.1)
				(type default)
			)
			(layer "F.Fab")
		)
		(fp_line
			(start -0.12065 0.2794)
			(end -0.12065 0.3048)
			(stroke
				(width 0.1)
				(type default)
			)
			(layer "F.Fab")
		)
		(fp_line
			(start 0.120396 0.2794)
			(end -0.12065 0.2794)
			(stroke
				(width 0.1)
				(type default)
			)
			(layer "F.Fab")
		)
		(fp_line
			(start -0.12065 -0.2794)
			(end 0.12065 -0.2794)
			(stroke
				(width 0.1)
				(type default)
			)
			(layer "F.Fab")
		)
		(fp_line
			(start 0.12065 -0.2794)
			(end 0.12065 -0.3048)
			(stroke
				(width 0.1)
				(type default)
			)
			(layer "F.Fab")
		)
		(fp_line
			(start 0.12065 -0.3048)
			(end 0.67945 -0.3048)
			(stroke
				(width 0.1)
				(type default)
			)
			(layer "F.Fab")
		)
		(fp_line
			(start 0.67945 -0.3048)
			(end 0.67945 0.3048)
			(stroke
				(width 0.1)
				(type default)
			)
			(layer "F.Fab")
		)
		(fp_line
			(start -0.67945 -0.305054)
			(end -0.12065 -0.305054)
			(stroke
				(width 0.1)
				(type default)
			)
			(layer "F.Fab")
		)
		(fp_line
			(start -0.12065 -0.305054)
			(end -0.12065 -0.2794)
			(stroke
				(width 0.1)
				(type default)
			)
			(layer "F.Fab")
		)
		(pad "1" smd circle
			(at -0.40005 0 270)
			(size 0 0)
			(layers "F.Cu" "F.Mask" "F.Paste")
			(net "U270_0_ADD2")
		)
		(pad "2" smd circle
			(at 0.40005 0 270)
			(size 0 0)
			(layers "F.Cu" "F.Mask" "F.Paste")
			(net "GND")
		)
	)
	(footprint ""
		(layer "F.Cu")
		(at 201.00036 -114.264948 180)
		(property "Reference" "R4146"
			(at 0 0 180)
			(layer "F.SilkS")
			(hide yes)
			(effects
				(font
					(size 1.27 1.27)
				)
			)
		)
		(property "Value" ""
			(at 0 0 180)
			(layer "F.Fab")
			(effects
				(font
					(size 1.27 1.27)
				)
			)
		)
		(duplicate_pad_numbers_are_jumpers no)
		(fp_line
			(start 0.7874 0.4064)
			(end -0.7874 0.4064)
			(stroke
				(width 0.1524)
				(type default)
			)
			(layer "F.SilkS")
		)
		(fp_line
			(start 0.7874 -0.4064)
			(end 0.7874 0.4064)
			(stroke
				(width 0.1524)
				(type default)
			)
			(layer "F.SilkS")
		)
		(fp_line
			(start -0.7874 0.4064)
			(end -0.7874 -0.4064)
			(stroke
				(width 0.1524)
				(type default)
			)
			(layer "F.SilkS")
		)
		(fp_line
			(start -0.7874 -0.4064)
			(end 0.7874 -0.4064)
			(stroke
				(width 0.1524)
				(type default)
			)
			(layer "F.SilkS")
		)
		(fp_line
			(start 0.67945 0.3048)
			(end 0.120396 0.3048)
			(stroke
				(width 0.1)
				(type default)
			)
			(layer "F.Fab")
		)
		(fp_line
			(start 0.67945 -0.3048)
			(end 0.67945 0.3048)
			(stroke
				(width 0.1)
				(type default)
			)
			(layer "F.Fab")
		)
		(fp_line
			(start 0.12065 -0.2794)
			(end 0.12065 -0.3048)
			(stroke
				(width 0.1)
				(type default)
			)
			(layer "F.Fab")
		)
		(fp_line
			(start 0.12065 -0.3048)
			(end 0.67945 -0.3048)
			(stroke
				(width 0.1)
				(type default)
			)
			(layer "F.Fab")
		)
		(fp_line
			(start 0.120396 0.3048)
			(end 0.120396 0.2794)
			(stroke
				(width 0.1)
				(type default)
			)
			(layer "F.Fab")
		)
		(fp_line
			(start 0.120396 0.2794)
			(end -0.12065 0.2794)
			(stroke
				(width 0.1)
				(type default)
			)
			(layer "F.Fab")
		)
		(fp_line
			(start -0.12065 0.3048)
			(end -0.67945 0.3048)
			(stroke
				(width 0.1)
				(type default)
			)
			(layer "F.Fab")
		)
		(fp_line
			(start -0.12065 0.2794)
			(end -0.12065 0.3048)
			(stroke
				(width 0.1)
				(type default)
			)
			(layer "F.Fab")
		)
		(fp_line
			(start -0.12065 -0.2794)
			(end 0.12065 -0.2794)
			(stroke
				(width 0.1)
				(type default)
			)
			(layer "F.Fab")
		)
		(fp_line
			(start -0.12065 -0.305054)
			(end -0.12065 -0.2794)
			(stroke
				(width 0.1)
				(type default)
			)
			(layer "F.Fab")
		)
		(fp_line
			(start -0.67945 0.3048)
			(end -0.67945 -0.305054)
			(stroke
				(width 0.1)
				(type default)
			)
			(layer "F.Fab")
		)
		(fp_line
			(start -0.67945 -0.305054)
			(end -0.12065 -0.305054)
			(stroke
				(width 0.1)
				(type default)
			)
			(layer "F.Fab")
		)
		(pad "1" smd circle
			(at -0.40005 0 180)
			(size 0 0)
			(layers "F.Cu" "F.Mask" "F.Paste")
			(net "GPU_3V3IO_RSVD3_FFU_ISO")
		)
		(pad "2" smd circle
			(at 0.40005 0 180)
			(size 0 0)
			(layers "F.Cu" "F.Mask" "F.Paste")
			(net "GPU_3V3IO_RSVD3_FFU_ISO_R")
		)
	)
	(footprint ""
		(layer "F.Cu")
		(at 203.399898 -22.29993)
		(property "Reference" "H103"
			(at -4.60502 -5.580888 0)
			(unlocked yes)
			(layer "F.SilkS")
			(effects
				(font
					(size 0.7874 0.5842)
					(thickness 0.1524)
				)
				(justify left)
			)
		)
		(property "Value" ""
			(at 0 0 0)
			(layer "F.Fab")
			(effects
				(font
					(size 1.27 1.27)
				)
			)
		)
		(duplicate_pad_numbers_are_jumpers no)
		(pad "1" thru_hole circle
			(at 0 0)
			(size 10.0076 10.0076)
			(drill 5.6134)
			(layers "*.Cu" "*.Mask")
			(remove_unused_layers no)
			(net "GND")
			(clearance -1.9431)
		)
	)
	(footprint ""
		(layer "F.Cu")
		(at 317.396622 -57.775348 180)
		(property "Reference" "R618"
			(at 0 0 180)
			(layer "F.SilkS")
			(hide yes)
			(effects
				(font
					(size 1.27 1.27)
				)
			)
		)
		(property "Value" ""
			(at 0 0 180)
			(layer "F.Fab")
			(effects
				(font
					(size 1.27 1.27)
				)
			)
		)
		(duplicate_pad_numbers_are_jumpers no)
		(fp_line
			(start 0.7874 0.4064)
			(end -0.7874 0.4064)
			(stroke
				(width 0.1524)
				(type default)
			)
			(layer "F.SilkS")
		)
		(fp_line
			(start 0.7874 -0.4064)
			(end 0.7874 0.4064)
			(stroke
				(width 0.1524)
				(type default)
			)
			(layer "F.SilkS")
		)
		(fp_line
			(start -0.7874 0.4064)
			(end -0.7874 -0.4064)
			(stroke
				(width 0.1524)
				(type default)
			)
			(layer "F.SilkS")
		)
		(fp_line
			(start -0.7874 -0.4064)
			(end 0.7874 -0.4064)
			(stroke
				(width 0.1524)
				(type default)
			)
			(layer "F.SilkS")
		)
		(fp_line
			(start 0.67945 0.3048)
			(end 0.120396 0.3048)
			(stroke
				(width 0.1)
				(type default)
			)
			(layer "F.Fab")
		)
		(fp_line
			(start 0.67945 -0.3048)
			(end 0.67945 0.3048)
			(stroke
				(width 0.1)
				(type default)
			)
			(layer "F.Fab")
		)
		(fp_line
			(start 0.12065 -0.2794)
			(end 0.12065 -0.3048)
			(stroke
				(width 0.1)
				(type default)
			)
			(layer "F.Fab")
		)
		(fp_line
			(start 0.12065 -0.3048)
			(end 0.67945 -0.3048)
			(stroke
				(width 0.1)
				(type default)
			)
			(layer "F.Fab")
		)
		(fp_line
			(start 0.120396 0.3048)
			(end 0.120396 0.2794)
			(stroke
				(width 0.1)
				(type default)
			)
			(layer "F.Fab")
		)
		(fp_line
			(start 0.120396 0.2794)
			(end -0.12065 0.2794)
			(stroke
				(width 0.1)
				(type default)
			)
			(layer "F.Fab")
		)
		(fp_line
			(start -0.12065 0.3048)
			(end -0.67945 0.3048)
			(stroke
				(width 0.1)
				(type default)
			)
			(layer "F.Fab")
		)
		(fp_line
			(start -0.12065 0.2794)
			(end -0.12065 0.3048)
			(stroke
				(width 0.1)
				(type default)
			)
			(layer "F.Fab")
		)
		(fp_line
			(start -0.12065 -0.2794)
			(end 0.12065 -0.2794)
			(stroke
				(width 0.1)
				(type default)
			)
			(layer "F.Fab")
		)
		(fp_line
			(start -0.12065 -0.305054)
			(end -0.12065 -0.2794)
			(stroke
				(width 0.1)
				(type default)
			)
			(layer "F.Fab")
		)
		(fp_line
			(start -0.67945 0.3048)
			(end -0.67945 -0.305054)
			(stroke
				(width 0.1)
				(type default)
			)
			(layer "F.Fab")
		)
		(fp_line
			(start -0.67945 -0.305054)
			(end -0.12065 -0.305054)
			(stroke
				(width 0.1)
				(type default)
			)
			(layer "F.Fab")
		)
		(pad "1" smd circle
			(at -0.40005 0 180)
			(size 0 0)
			(layers "F.Cu" "F.Mask" "F.Paste")
			(net "FM_PCH_IO_EXPANDER")
		)
		(pad "2" smd circle
			(at 0.40005 0 180)
			(size 0 0)
			(layers "F.Cu" "F.Mask" "F.Paste")
			(net "GND")
		)
	)
	(footprint ""
		(layer "F.Cu")
		(at 343.646252 -338.86013)
		(property "Reference" "PR151"
			(at 0 0 0)
			(layer "F.SilkS")
			(hide yes)
			(effects
				(font
					(size 1.27 1.27)
				)
			)
		)
		(property "Value" ""
			(at 0 0 0)
			(layer "F.Fab")
			(effects
				(font
					(size 1.27 1.27)
				)
			)
		)
		(duplicate_pad_numbers_are_jumpers no)
		(fp_line
			(start -0.7874 -0.4064)
			(end 0.7874 -0.4064)
			(stroke
				(width 0.1524)
				(type default)
			)
			(layer "F.SilkS")
		)
		(fp_line
			(start -0.7874 0.4064)
			(end -0.7874 -0.4064)
			(stroke
				(width 0.1524)
				(type default)
			)
			(layer "F.SilkS")
		)
		(fp_line
			(start 0.7874 -0.4064)
			(end 0.7874 0.4064)
			(stroke
				(width 0.1524)
				(type default)
			)
			(layer "F.SilkS")
		)
		(fp_line
			(start 0.7874 0.4064)
			(end -0.7874 0.4064)
			(stroke
				(width 0.1524)
				(type default)
			)
			(layer "F.SilkS")
		)
		(fp_line
			(start -0.67945 -0.305054)
			(end -0.12065 -0.305054)
			(stroke
				(width 0.1)
				(type default)
			)
			(layer "F.Fab")
		)
		(fp_line
			(start -0.67945 0.3048)
			(end -0.67945 -0.305054)
			(stroke
				(width 0.1)
				(type default)
			)
			(layer "F.Fab")
		)
		(fp_line
			(start -0.12065 -0.305054)
			(end -0.12065 -0.2794)
			(stroke
				(width 0.1)
				(type default)
			)
			(layer "F.Fab")
		)
		(fp_line
			(start -0.12065 -0.2794)
			(end 0.12065 -0.2794)
			(stroke
				(width 0.1)
				(type default)
			)
			(layer "F.Fab")
		)
		(fp_line
			(start -0.12065 0.2794)
			(end -0.12065 0.3048)
			(stroke
				(width 0.1)
				(type default)
			)
			(layer "F.Fab")
		)
		(fp_line
			(start -0.12065 0.3048)
			(end -0.67945 0.3048)
			(stroke
				(width 0.1)
				(type default)
			)
			(layer "F.Fab")
		)
		(fp_line
			(start 0.120396 0.2794)
			(end -0.12065 0.2794)
			(stroke
				(width 0.1)
				(type default)
			)
			(layer "F.Fab")
		)
		(fp_line
			(start 0.120396 0.3048)
			(end 0.120396 0.2794)
			(stroke
				(width 0.1)
				(type default)
			)
			(layer "F.Fab")
		)
		(fp_line
			(start 0.12065 -0.3048)
			(end 0.67945 -0.3048)
			(stroke
				(width 0.1)
				(type default)
			)
			(layer "F.Fab")
		)
		(fp_line
			(start 0.12065 -0.2794)
			(end 0.12065 -0.3048)
			(stroke
				(width 0.1)
				(type default)
			)
			(layer "F.Fab")
		)
		(fp_line
			(start 0.67945 -0.3048)
			(end 0.67945 0.3048)
			(stroke
				(width 0.1)
				(type default)
			)
			(layer "F.Fab")
		)
		(fp_line
			(start 0.67945 0.3048)
			(end 0.120396 0.3048)
			(stroke
				(width 0.1)
				(type default)
			)
			(layer "F.Fab")
		)
		(pad "1" smd circle
			(at -0.40005 0)
			(size 0 0)
			(layers "F.Cu" "F.Mask" "F.Paste")
			(net "PVCCIN_CPU0_LSET1")
		)
		(pad "2" smd circle
			(at 0.40005 0)
			(size 0 0)
			(layers "F.Cu" "F.Mask" "F.Paste")
			(net "GND")
		)
	)
	(footprint ""
		(layer "F.Cu")
		(at 157.061408 -44.662598 90)
		(property "Reference" "R4455"
			(at 0 0 90)
			(layer "F.SilkS")
			(hide yes)
			(effects
				(font
					(size 1.27 1.27)
				)
			)
		)
		(property "Value" ""
			(at 0 0 90)
			(layer "F.Fab")
			(effects
				(font
					(size 1.27 1.27)
				)
			)
		)
		(duplicate_pad_numbers_are_jumpers no)
		(fp_line
			(start 0.7874 -0.4064)
			(end 0.7874 0.4064)
			(stroke
				(width 0.1524)
				(type default)
			)
			(layer "F.SilkS")
		)
		(fp_line
			(start 0.7874 0.4064)
			(end -0.7874 0.4064)
			(stroke
				(width 0.1524)
				(type default)
			)
			(layer "F.SilkS")
		)
		(fp_line
			(start -0.12065 -0.305054)
			(end -0.12065 -0.2794)
			(stroke
				(width 0.1)
				(type default)
			)
			(layer "F.Fab")
		)
		(fp_line
			(start -0.67945 -0.305054)
			(end -0.12065 -0.305054)
			(stroke
				(width 0.1)
				(type default)
			)
			(layer "F.Fab")
		)
		(fp_line
			(start 0.67945 -0.3048)
			(end 0.67945 0.3048)
			(stroke
				(width 0.1)
				(type default)
			)
			(layer "F.Fab")
		)
		(fp_line
			(start 0.12065 -0.3048)
			(end 0.67945 -0.3048)
			(stroke
				(width 0.1)
				(type default)
			)
			(layer "F.Fab")
		)
		(fp_line
			(start 0.12065 -0.2794)
			(end 0.12065 -0.3048)
			(stroke
				(width 0.1)
				(type default)
			)
			(layer "F.Fab")
		)
		(fp_line
			(start -0.12065 -0.2794)
			(end 0.12065 -0.2794)
			(stroke
				(width 0.1)
				(type default)
			)
			(layer "F.Fab")
		)
		(fp_line
			(start 0.120396 0.2794)
			(end -0.12065 0.2794)
			(stroke
				(width 0.1)
				(type default)
			)
			(layer "F.Fab")
		)
		(fp_line
			(start -0.12065 0.2794)
			(end -0.12065 0.3048)
			(stroke
				(width 0.1)
				(type default)
			)
			(layer "F.Fab")
		)
		(fp_line
			(start 0.67945 0.3048)
			(end 0.120396 0.3048)
			(stroke
				(width 0.1)
				(type default)
			)
			(layer "F.Fab")
		)
		(fp_line
			(start 0.120396 0.3048)
			(end 0.120396 0.2794)
			(stroke
				(width 0.1)
				(type default)
			)
			(layer "F.Fab")
		)
		(fp_line
			(start -0.12065 0.3048)
			(end -0.67945 0.3048)
			(stroke
				(width 0.1)
				(type default)
			)
			(layer "F.Fab")
		)
		(fp_line
			(start -0.67945 0.3048)
			(end -0.67945 -0.305054)
			(stroke
				(width 0.1)
				(type default)
			)
			(layer "F.Fab")
		)
		(pad "1" smd rect
			(at -0.40005 0 270)
			(size 0.4572 0.508)
			(layers "F.Cu" "F.Mask" "F.Paste")
			(net "USB2_HUB_2_EXT_DN")
		)
		(pad "2" smd rect
			(at 0.40005 0 270)
			(size 0.4572 0.508)
			(layers "F.Cu" "F.Mask" "F.Paste")
			(net "USB2_HUB_2_BUF_EXT_R_DN")
		)
	)
	(footprint ""
		(layer "F.Cu")
		(at 334.024732 -341.707978 -90)
		(property "Reference" "PC1342"
			(at 0 0 270)
			(layer "F.SilkS")
			(hide yes)
			(effects
				(font
					(size 1.27 1.27)
				)
			)
		)
		(property "Value" ""
			(at 0 0 270)
			(layer "F.Fab")
			(effects
				(font
					(size 1.27 1.27)
				)
			)
		)
		(duplicate_pad_numbers_are_jumpers no)
		(fp_line
			(start -0.7874 0.4064)
			(end -0.7874 -0.4064)
			(stroke
				(width 0.1524)
				(type default)
			)
			(layer "F.SilkS")
		)
		(fp_line
			(start 0.7874 0.4064)
			(end -0.7874 0.4064)
			(stroke
				(width 0.1524)
				(type default)
			)
			(layer "F.SilkS")
		)
		(fp_line
			(start -0.7874 -0.4064)
			(end 0.7874 -0.4064)
			(stroke
				(width 0.1524)
				(type default)
			)
			(layer "F.SilkS")
		)
		(fp_line
			(start 0.7874 -0.4064)
			(end 0.7874 0.4064)
			(stroke
				(width 0.1524)
				(type default)
			)
			(layer "F.SilkS")
		)
		(fp_line
			(start -0.67945 0.3048)
			(end -0.67945 -0.305054)
			(stroke
				(width 0.1)
				(type default)
			)
			(layer "F.Fab")
		)
		(fp_line
			(start -0.12065 0.3048)
			(end -0.67945 0.3048)
			(stroke
				(width 0.1)
				(type default)
			)
			(layer "F.Fab")
		)
		(fp_line
			(start 0.120396 0.3048)
			(end 0.120396 0.2794)
			(stroke
				(width 0.1)
				(type default)
			)
			(layer "F.Fab")
		)
		(fp_line
			(start 0.67945 0.3048)
			(end 0.120396 0.3048)
			(stroke
				(width 0.1)
				(type default)
			)
			(layer "F.Fab")
		)
		(fp_line
			(start -0.12065 0.2794)
			(end -0.12065 0.3048)
			(stroke
				(width 0.1)
				(type default)
			)
			(layer "F.Fab")
		)
		(fp_line
			(start 0.120396 0.2794)
			(end -0.12065 0.2794)
			(stroke
				(width 0.1)
				(type default)
			)
			(layer "F.Fab")
		)
		(fp_line
			(start -0.12065 -0.2794)
			(end 0.12065 -0.2794)
			(stroke
				(width 0.1)
				(type default)
			)
			(layer "F.Fab")
		)
		(fp_line
			(start 0.12065 -0.2794)
			(end 0.12065 -0.3048)
			(stroke
				(width 0.1)
				(type default)
			)
			(layer "F.Fab")
		)
		(fp_line
			(start 0.12065 -0.3048)
			(end 0.67945 -0.3048)
			(stroke
				(width 0.1)
				(type default)
			)
			(layer "F.Fab")
		)
		(fp_line
			(start 0.67945 -0.3048)
			(end 0.67945 0.3048)
			(stroke
				(width 0.1)
				(type default)
			)
			(layer "F.Fab")
		)
		(fp_line
			(start -0.67945 -0.305054)
			(end -0.12065 -0.305054)
			(stroke
				(width 0.1)
				(type default)
			)
			(layer "F.Fab")
		)
		(fp_line
			(start -0.12065 -0.305054)
			(end -0.12065 -0.2794)
			(stroke
				(width 0.1)
				(type default)
			)
			(layer "F.Fab")
		)
		(pad "1" smd circle
			(at -0.40005 0 270)
			(size 0 0)
			(layers "F.Cu" "F.Mask" "F.Paste")
			(net "GND")
		)
		(pad "2" smd circle
			(at 0.40005 0 270)
			(size 0 0)
			(layers "F.Cu" "F.Mask" "F.Paste")
			(net "PVCCIN_CPU0_VREF")
		)
	)
	(footprint ""
		(layer "F.Cu")
		(at 294.899588 -365.251746 90)
		(property "Reference" "PC601"
			(at 0 0 90)
			(layer "F.SilkS")
			(hide yes)
			(effects
				(font
					(size 1.27 1.27)
				)
			)
		)
		(property "Value" ""
			(at 0 0 90)
			(layer "F.Fab")
			(effects
				(font
					(size 1.27 1.27)
				)
			)
		)
		(duplicate_pad_numbers_are_jumpers no)
		(fp_line
			(start 0.7874 -0.4064)
			(end 0.7874 0.4064)
			(stroke
				(width 0.1524)
				(type default)
			)
			(layer "F.SilkS")
		)
		(fp_line
			(start -0.7874 -0.4064)
			(end 0.7874 -0.4064)
			(stroke
				(width 0.1524)
				(type default)
			)
			(layer "F.SilkS")
		)
		(fp_line
			(start 0.7874 0.4064)
			(end -0.7874 0.4064)
			(stroke
				(width 0.1524)
				(type default)
			)
			(layer "F.SilkS")
		)
		(fp_line
			(start -0.7874 0.4064)
			(end -0.7874 -0.4064)
			(stroke
				(width 0.1524)
				(type default)
			)
			(layer "F.SilkS")
		)
		(fp_line
			(start -0.12065 -0.305054)
			(end -0.12065 -0.2794)
			(stroke
				(width 0.1)
				(type default)
			)
			(layer "F.Fab")
		)
		(fp_line
			(start -0.67945 -0.305054)
			(end -0.12065 -0.305054)
			(stroke
				(width 0.1)
				(type default)
			)
			(layer "F.Fab")
		)
		(fp_line
			(start 0.67945 -0.3048)
			(end 0.67945 0.3048)
			(stroke
				(width 0.1)
				(type default)
			)
			(layer "F.Fab")
		)
		(fp_line
			(start 0.12065 -0.3048)
			(end 0.67945 -0.3048)
			(stroke
				(width 0.1)
				(type default)
			)
			(layer "F.Fab")
		)
		(fp_line
			(start 0.12065 -0.2794)
			(end 0.12065 -0.3048)
			(stroke
				(width 0.1)
				(type default)
			)
			(layer "F.Fab")
		)
		(fp_line
			(start -0.12065 -0.2794)
			(end 0.12065 -0.2794)
			(stroke
				(width 0.1)
				(type default)
			)
			(layer "F.Fab")
		)
		(fp_line
			(start 0.120396 0.2794)
			(end -0.12065 0.2794)
			(stroke
				(width 0.1)
				(type default)
			)
			(layer "F.Fab")
		)
		(fp_line
			(start -0.12065 0.2794)
			(end -0.12065 0.3048)
			(stroke
				(width 0.1)
				(type default)
			)
			(layer "F.Fab")
		)
		(fp_line
			(start 0.67945 0.3048)
			(end 0.120396 0.3048)
			(stroke
				(width 0.1)
				(type default)
			)
			(layer "F.Fab")
		)
		(fp_line
			(start 0.120396 0.3048)
			(end 0.120396 0.2794)
			(stroke
				(width 0.1)
				(type default)
			)
			(layer "F.Fab")
		)
		(fp_line
			(start -0.12065 0.3048)
			(end -0.67945 0.3048)
			(stroke
				(width 0.1)
				(type default)
			)
			(layer "F.Fab")
		)
		(fp_line
			(start -0.67945 0.3048)
			(end -0.67945 -0.305054)
			(stroke
				(width 0.1)
				(type default)
			)
			(layer "F.Fab")
		)
		(pad "1" smd circle
			(at -0.40005 0 90)
			(size 0 0)
			(layers "F.Cu" "F.Mask" "F.Paste")
			(net "PVCCFA_EHV_FIVRA_CPU0_VDD2")
		)
		(pad "2" smd circle
			(at 0.40005 0 90)
			(size 0 0)
			(layers "F.Cu" "F.Mask" "F.Paste")
			(net "GND")
		)
	)
	(footprint ""
		(layer "F.Cu")
		(at 295.548304 -426.478446 -90)
		(property "Reference" "R4155"
			(at 0 0 270)
			(layer "F.SilkS")
			(hide yes)
			(effects
				(font
					(size 1.27 1.27)
				)
			)
		)
		(property "Value" ""
			(at 0 0 270)
			(layer "F.Fab")
			(effects
				(font
					(size 1.27 1.27)
				)
			)
		)
		(duplicate_pad_numbers_are_jumpers no)
		(fp_line
			(start -0.7874 0.4064)
			(end -0.7874 -0.4064)
			(stroke
				(width 0.1524)
				(type default)
			)
			(layer "F.SilkS")
		)
		(fp_line
			(start 0.7874 0.4064)
			(end -0.7874 0.4064)
			(stroke
				(width 0.1524)
				(type default)
			)
			(layer "F.SilkS")
		)
		(fp_line
			(start -0.7874 -0.4064)
			(end 0.7874 -0.4064)
			(stroke
				(width 0.1524)
				(type default)
			)
			(layer "F.SilkS")
		)
		(fp_line
			(start 0.7874 -0.4064)
			(end 0.7874 0.4064)
			(stroke
				(width 0.1524)
				(type default)
			)
			(layer "F.SilkS")
		)
		(fp_line
			(start -0.67945 0.3048)
			(end -0.67945 -0.305054)
			(stroke
				(width 0.1)
				(type default)
			)
			(layer "F.Fab")
		)
		(fp_line
			(start -0.12065 0.3048)
			(end -0.67945 0.3048)
			(stroke
				(width 0.1)
				(type default)
			)
			(layer "F.Fab")
		)
		(fp_line
			(start 0.120396 0.3048)
			(end 0.120396 0.2794)
			(stroke
				(width 0.1)
				(type default)
			)
			(layer "F.Fab")
		)
		(fp_line
			(start 0.67945 0.3048)
			(end 0.120396 0.3048)
			(stroke
				(width 0.1)
				(type default)
			)
			(layer "F.Fab")
		)
		(fp_line
			(start -0.12065 0.2794)
			(end -0.12065 0.3048)
			(stroke
				(width 0.1)
				(type default)
			)
			(layer "F.Fab")
		)
		(fp_line
			(start 0.120396 0.2794)
			(end -0.12065 0.2794)
			(stroke
				(width 0.1)
				(type default)
			)
			(layer "F.Fab")
		)
		(fp_line
			(start -0.12065 -0.2794)
			(end 0.12065 -0.2794)
			(stroke
				(width 0.1)
				(type default)
			)
			(layer "F.Fab")
		)
		(fp_line
			(start 0.12065 -0.2794)
			(end 0.12065 -0.3048)
			(stroke
				(width 0.1)
				(type default)
			)
			(layer "F.Fab")
		)
		(fp_line
			(start 0.12065 -0.3048)
			(end 0.67945 -0.3048)
			(stroke
				(width 0.1)
				(type default)
			)
			(layer "F.Fab")
		)
		(fp_line
			(start 0.67945 -0.3048)
			(end 0.67945 0.3048)
			(stroke
				(width 0.1)
				(type default)
			)
			(layer "F.Fab")
		)
		(fp_line
			(start -0.67945 -0.305054)
			(end -0.12065 -0.305054)
			(stroke
				(width 0.1)
				(type default)
			)
			(layer "F.Fab")
		)
		(fp_line
			(start -0.12065 -0.305054)
			(end -0.12065 -0.2794)
			(stroke
				(width 0.1)
				(type default)
			)
			(layer "F.Fab")
		)
		(pad "1" smd circle
			(at -0.40005 0 270)
			(size 0 0)
			(layers "F.Cu" "F.Mask" "F.Paste")
			(net "P3V3_AUX")
		)
		(pad "2" smd circle
			(at 0.40005 0 270)
			(size 0 0)
			(layers "F.Cu" "F.Mask" "F.Paste")
			(net "PRSNT_CABLE_GPU_A1")
		)
	)
	(footprint ""
		(layer "F.Cu")
		(at 164.211 -125.73 180)
		(property "Reference" "U324"
			(at -3.07721 -2.33426 90)
			(unlocked yes)
			(layer "F.SilkS")
			(effects
				(font
					(size 0.7874 0.5842)
					(thickness 0.1524)
				)
				(justify left)
			)
		)
		(property "Value" ""
			(at 0 0 180)
			(layer "F.Fab")
			(effects
				(font
					(size 1.27 1.27)
				)
			)
		)
		(duplicate_pad_numbers_are_jumpers no)
		(fp_line
			(start 1.603248 1.500124)
			(end -1.603248 1.500124)
			(stroke
				(width 0.1524)
				(type default)
			)
			(layer "F.SilkS")
		)
		(fp_line
			(start 1.603248 -1.500124)
			(end 1.603248 1.500124)
			(stroke
				(width 0.1524)
				(type default)
			)
			(layer "F.SilkS")
		)
		(fp_line
			(start -1.603248 1.500124)
			(end -1.603248 -1.500124)
			(stroke
				(width 0.1524)
				(type default)
			)
			(layer "F.SilkS")
		)
		(fp_line
			(start -1.603248 -1.500124)
			(end 1.603248 -1.500124)
			(stroke
				(width 0.1524)
				(type default)
			)
			(layer "F.SilkS")
		)
		(fp_line
			(start 1.249934 0.219964)
			(end 1.249934 -0.219964)
			(stroke
				(width 0.1)
				(type default)
			)
			(layer "F.Fab")
		)
		(fp_line
			(start 1.249934 -0.219964)
			(end 0.700024 -0.219964)
			(stroke
				(width 0.1)
				(type default)
			)
			(layer "F.Fab")
		)
		(fp_line
			(start 0.700024 1.500124)
			(end 0.700024 0.219964)
			(stroke
				(width 0.1)
				(type default)
			)
			(layer "F.Fab")
		)
		(fp_line
			(start 0.700024 0.219964)
			(end 1.249934 0.219964)
			(stroke
				(width 0.1)
				(type default)
			)
			(layer "F.Fab")
		)
		(fp_line
			(start 0.700024 -0.219964)
			(end 0.700024 -1.500124)
			(stroke
				(width 0.1)
				(type default)
			)
			(layer "F.Fab")
		)
		(fp_line
			(start 0.700024 -1.500124)
			(end -0.700024 -1.500124)
			(stroke
				(width 0.1)
				(type default)
			)
			(layer "F.Fab")
		)
		(fp_line
			(start -0.6985 0.729996)
			(end -1.249934 0.729996)
			(stroke
				(width 0.1)
				(type default)
			)
			(layer "F.Fab")
		)
		(fp_line
			(start -0.6985 -0.729996)
			(end -0.6985 0.729996)
			(stroke
				(width 0.1)
				(type default)
			)
			(layer "F.Fab")
		)
		(fp_line
			(start -0.700024 1.500124)
			(end 0.700024 1.500124)
			(stroke
				(width 0.1)
				(type default)
			)
			(layer "F.Fab")
		)
		(fp_line
			(start -0.700024 1.169924)
			(end -0.700024 1.500124)
			(stroke
				(width 0.1)
				(type default)
			)
			(layer "F.Fab")
		)
		(fp_line
			(start -0.700024 -1.169924)
			(end -1.249934 -1.169924)
			(stroke
				(width 0.1)
				(type default)
			)
			(layer "F.Fab")
		)
		(fp_line
			(start -0.700024 -1.500124)
			(end -0.700024 -1.169924)
			(stroke
				(width 0.1)
				(type default)
			)
			(layer "F.Fab")
		)
		(fp_line
			(start -1.249934 1.169924)
			(end -0.700024 1.169924)
			(stroke
				(width 0.1)
				(type default)
			)
			(layer "F.Fab")
		)
		(fp_line
			(start -1.249934 0.729996)
			(end -1.249934 1.169924)
			(stroke
				(width 0.1)
				(type default)
			)
			(layer "F.Fab")
		)
		(fp_line
			(start -1.249934 -0.729996)
			(end -0.6985 -0.729996)
			(stroke
				(width 0.1)
				(type default)
			)
			(layer "F.Fab")
		)
		(fp_line
			(start -1.249934 -1.169924)
			(end -1.249934 -0.729996)
			(stroke
				(width 0.1)
				(type default)
			)
			(layer "F.Fab")
		)
		(fp_rect
			(start -0.700024 1.500124)
			(end 0.700024 -1.500124)
			(stroke
				(width 0)
				(type default)
			)
			(fill no)
			(layer "F.Fab")
		)
		(pad "D" smd rect
			(at 0.999998 0 90)
			(size 0.8128 0.9144)
			(layers "F.Cu" "F.Mask" "F.Paste")
			(net "VR_P5V_EN_D")
		)
		(pad "G" smd rect
			(at -0.999998 -0.94996 90)
			(size 0.8128 0.9144)
			(layers "F.Cu" "F.Mask" "F.Paste")
			(net "VR_P5V_EN_N")
		)
		(pad "S" smd rect
			(at -0.999998 0.94996 90)
			(size 0.8128 0.9144)
			(layers "F.Cu" "F.Mask" "F.Paste")
			(net "GND")
		)
	)
	(footprint ""
		(layer "F.Cu")
		(at 367.44783 -247.715024 90)
		(property "Reference" "C399"
			(at 0 0 90)
			(layer "F.SilkS")
			(hide yes)
			(effects
				(font
					(size 1.27 1.27)
				)
			)
		)
		(property "Value" ""
			(at 0 0 90)
			(layer "F.Fab")
			(effects
				(font
					(size 1.27 1.27)
				)
			)
		)
		(duplicate_pad_numbers_are_jumpers no)
		(fp_line
			(start 0.7874 -0.4064)
			(end 0.7874 0.4064)
			(stroke
				(width 0.1524)
				(type default)
			)
			(layer "F.SilkS")
		)
		(fp_line
			(start -0.7874 -0.4064)
			(end 0.7874 -0.4064)
			(stroke
				(width 0.1524)
				(type default)
			)
			(layer "F.SilkS")
		)
		(fp_line
			(start 0.7874 0.4064)
			(end -0.7874 0.4064)
			(stroke
				(width 0.1524)
				(type default)
			)
			(layer "F.SilkS")
		)
		(fp_line
			(start -0.7874 0.4064)
			(end -0.7874 -0.4064)
			(stroke
				(width 0.1524)
				(type default)
			)
			(layer "F.SilkS")
		)
		(fp_line
			(start -0.12065 -0.305054)
			(end -0.12065 -0.2794)
			(stroke
				(width 0.1)
				(type default)
			)
			(layer "F.Fab")
		)
		(fp_line
			(start -0.67945 -0.305054)
			(end -0.12065 -0.305054)
			(stroke
				(width 0.1)
				(type default)
			)
			(layer "F.Fab")
		)
		(fp_line
			(start 0.67945 -0.3048)
			(end 0.67945 0.3048)
			(stroke
				(width 0.1)
				(type default)
			)
			(layer "F.Fab")
		)
		(fp_line
			(start 0.12065 -0.3048)
			(end 0.67945 -0.3048)
			(stroke
				(width 0.1)
				(type default)
			)
			(layer "F.Fab")
		)
		(fp_line
			(start 0.12065 -0.2794)
			(end 0.12065 -0.3048)
			(stroke
				(width 0.1)
				(type default)
			)
			(layer "F.Fab")
		)
		(fp_line
			(start -0.12065 -0.2794)
			(end 0.12065 -0.2794)
			(stroke
				(width 0.1)
				(type default)
			)
			(layer "F.Fab")
		)
		(fp_line
			(start 0.120396 0.2794)
			(end -0.12065 0.2794)
			(stroke
				(width 0.1)
				(type default)
			)
			(layer "F.Fab")
		)
		(fp_line
			(start -0.12065 0.2794)
			(end -0.12065 0.3048)
			(stroke
				(width 0.1)
				(type default)
			)
			(layer "F.Fab")
		)
		(fp_line
			(start 0.67945 0.3048)
			(end 0.120396 0.3048)
			(stroke
				(width 0.1)
				(type default)
			)
			(layer "F.Fab")
		)
		(fp_line
			(start 0.120396 0.3048)
			(end 0.120396 0.2794)
			(stroke
				(width 0.1)
				(type default)
			)
			(layer "F.Fab")
		)
		(fp_line
			(start -0.12065 0.3048)
			(end -0.67945 0.3048)
			(stroke
				(width 0.1)
				(type default)
			)
			(layer "F.Fab")
		)
		(fp_line
			(start -0.67945 0.3048)
			(end -0.67945 -0.305054)
			(stroke
				(width 0.1)
				(type default)
			)
			(layer "F.Fab")
		)
		(pad "1" smd circle
			(at -0.40005 0 90)
			(size 0 0)
			(layers "F.Cu" "F.Mask" "F.Paste")
			(net "PVCCD_HV_CPU0")
		)
		(pad "2" smd circle
			(at 0.40005 0 90)
			(size 0 0)
			(layers "F.Cu" "F.Mask" "F.Paste")
			(net "GND")
		)
	)
	(footprint ""
		(layer "F.Cu")
		(at 68.212462 -37.389562 180)
		(property "Reference" "R3559"
			(at 0 0 180)
			(layer "F.SilkS")
			(hide yes)
			(effects
				(font
					(size 1.27 1.27)
				)
			)
		)
		(property "Value" ""
			(at 0 0 180)
			(layer "F.Fab")
			(effects
				(font
					(size 1.27 1.27)
				)
			)
		)
		(duplicate_pad_numbers_are_jumpers no)
		(fp_line
			(start 0.7874 0.4064)
			(end -0.7874 0.4064)
			(stroke
				(width 0.1524)
				(type default)
			)
			(layer "F.SilkS")
		)
		(fp_line
			(start 0.7874 -0.4064)
			(end 0.7874 0.4064)
			(stroke
				(width 0.1524)
				(type default)
			)
			(layer "F.SilkS")
		)
		(fp_line
			(start -0.7874 0.4064)
			(end -0.7874 -0.4064)
			(stroke
				(width 0.1524)
				(type default)
			)
			(layer "F.SilkS")
		)
		(fp_line
			(start -0.7874 -0.4064)
			(end 0.7874 -0.4064)
			(stroke
				(width 0.1524)
				(type default)
			)
			(layer "F.SilkS")
		)
		(fp_line
			(start 0.67945 0.3048)
			(end 0.120396 0.3048)
			(stroke
				(width 0.1)
				(type default)
			)
			(layer "F.Fab")
		)
		(fp_line
			(start 0.67945 -0.3048)
			(end 0.67945 0.3048)
			(stroke
				(width 0.1)
				(type default)
			)
			(layer "F.Fab")
		)
		(fp_line
			(start 0.12065 -0.2794)
			(end 0.12065 -0.3048)
			(stroke
				(width 0.1)
				(type default)
			)
			(layer "F.Fab")
		)
		(fp_line
			(start 0.12065 -0.3048)
			(end 0.67945 -0.3048)
			(stroke
				(width 0.1)
				(type default)
			)
			(layer "F.Fab")
		)
		(fp_line
			(start 0.120396 0.3048)
			(end 0.120396 0.2794)
			(stroke
				(width 0.1)
				(type default)
			)
			(layer "F.Fab")
		)
		(fp_line
			(start 0.120396 0.2794)
			(end -0.12065 0.2794)
			(stroke
				(width 0.1)
				(type default)
			)
			(layer "F.Fab")
		)
		(fp_line
			(start -0.12065 0.3048)
			(end -0.67945 0.3048)
			(stroke
				(width 0.1)
				(type default)
			)
			(layer "F.Fab")
		)
		(fp_line
			(start -0.12065 0.2794)
			(end -0.12065 0.3048)
			(stroke
				(width 0.1)
				(type default)
			)
			(layer "F.Fab")
		)
		(fp_line
			(start -0.12065 -0.2794)
			(end 0.12065 -0.2794)
			(stroke
				(width 0.1)
				(type default)
			)
			(layer "F.Fab")
		)
		(fp_line
			(start -0.12065 -0.305054)
			(end -0.12065 -0.2794)
			(stroke
				(width 0.1)
				(type default)
			)
			(layer "F.Fab")
		)
		(fp_line
			(start -0.67945 0.3048)
			(end -0.67945 -0.305054)
			(stroke
				(width 0.1)
				(type default)
			)
			(layer "F.Fab")
		)
		(fp_line
			(start -0.67945 -0.305054)
			(end -0.12065 -0.305054)
			(stroke
				(width 0.1)
				(type default)
			)
			(layer "F.Fab")
		)
		(pad "1" smd circle
			(at -0.40005 0 180)
			(size 0 0)
			(layers "F.Cu" "F.Mask" "F.Paste")
			(net "OCP_V3_2_P3V3_ADC_ALERT_R")
		)
		(pad "2" smd circle
			(at 0.40005 0 180)
			(size 0 0)
			(layers "F.Cu" "F.Mask" "F.Paste")
			(net "OCP_V3_2_P3V3_ADC_ALERT")
		)
	)
	(footprint ""
		(layer "F.Cu")
		(at 55.45328 -258.091686)
		(property "Reference" "J17"
			(at -0.178562 -81.717134 0)
			(unlocked yes)
			(layer "F.SilkS")
			(effects
				(font
					(size 0.7874 0.5842)
					(thickness 0.1524)
				)
				(justify left)
			)
		)
		(property "Value" ""
			(at 0 0 0)
			(layer "F.Fab")
			(effects
				(font
					(size 1.27 1.27)
				)
			)
		)
		(duplicate_pad_numbers_are_jumpers no)
		(fp_line
			(start -3.24993 -75.283314)
			(end -3.24993 81.000092)
			(stroke
				(width 0.1524)
				(type default)
			)
			(layer "F.SilkS")
		)
		(fp_line
			(start -3.24993 81.000092)
			(end 3.24993 81.000092)
			(stroke
				(width 0.1524)
				(type default)
			)
			(layer "F.SilkS")
		)
		(fp_line
			(start 3.24993 -81.000092)
			(end -0.55372 -81.000092)
			(stroke
				(width 0.1524)
				(type default)
			)
			(layer "F.SilkS")
		)
		(fp_line
			(start 3.24993 -72.00011)
			(end -3.24993 -72.00011)
			(stroke
				(width 0.1524)
				(type default)
			)
			(layer "F.SilkS")
		)
		(fp_line
			(start 3.24993 72.00011)
			(end -3.24993 72.00011)
			(stroke
				(width 0.1524)
				(type default)
			)
			(layer "F.SilkS")
		)
		(fp_line
			(start 3.24993 81.000092)
			(end 3.24993 -81.000092)
			(stroke
				(width 0.1524)
				(type default)
			)
			(layer "F.SilkS")
		)
		(fp_poly
			(pts
				(xy -4.229608 -63.758318) (xy -3.3274 -63.307214) (xy -4.229608 -62.85611)
			)
			(stroke
				(width 0)
				(type default)
			)
			(fill yes)
			(layer "F.SilkS")
		)
		(fp_line
			(start -3.24993 -81.000092)
			(end -3.24993 81.000092)
			(stroke
				(width 0.1)
				(type default)
			)
			(layer "F.Fab")
		)
		(fp_line
			(start -3.24993 81.000092)
			(end 3.24993 81.000092)
			(stroke
				(width 0.1)
				(type default)
			)
			(layer "F.Fab")
		)
		(fp_line
			(start 3.24993 -81.000092)
			(end -3.24993 -81.000092)
			(stroke
				(width 0.1)
				(type default)
			)
			(layer "F.Fab")
		)
		(fp_line
			(start 3.24993 -72.00011)
			(end -3.24993 -72.00011)
			(stroke
				(width 0.1)
				(type default)
			)
			(layer "F.Fab")
		)
		(fp_line
			(start 3.24993 -71.000112)
			(end -3.24993 -71.000112)
			(stroke
				(width 0.1)
				(type default)
			)
			(layer "F.Fab")
		)
		(fp_line
			(start 3.24993 71.000112)
			(end -3.24993 71.000112)
			(stroke
				(width 0.1)
				(type default)
			)
			(layer "F.Fab")
		)
		(fp_line
			(start 3.24993 72.00011)
			(end -3.24993 72.00011)
			(stroke
				(width 0.1)
				(type default)
			)
			(layer "F.Fab")
		)
		(fp_line
			(start 3.24993 81.000092)
			(end 3.24993 -81.000092)
			(stroke
				(width 0.1)
				(type default)
			)
			(layer "F.Fab")
		)
		(fp_poly
			(pts
				(xy -4.445 -63.832994) (xy -4.445 -62.816994) (xy -3.429 -63.324994)
			)
			(stroke
				(width 0)
				(type default)
			)
			(fill yes)
			(layer "F.Fab")
		)
		(pad "1" smd rect
			(at -2.050034 -63.324994 270)
			(size 0.519938 1.4986)
			(layers "F.Cu" "F.Mask" "F.Paste")
			(net "P12V_S3_AUX_CPU1_NVDIMM")
		)
		(pad "2" smd rect
			(at -2.050034 -62.47511 270)
			(size 0.519938 1.4986)
			(layers "F.Cu" "F.Mask" "F.Paste")
			(net "TP_CHA_CPU1_DIMM1_FRU_0")
		)
		(pad "3" smd rect
			(at -2.050034 -61.624972 270)
			(size 0.519938 1.4986)
			(layers "F.Cu" "F.Mask" "F.Paste")
			(net "P3V3_AUX")
		)
		(pad "4" smd rect
			(at -2.050034 -60.775088 270)
			(size 0.519938 1.4986)
			(layers "F.Cu" "F.Mask" "F.Paste")
			(net "I3C_SPD_DDRABCD_CPU1_LVC1_SCL_R")
		)
		(pad "5" smd rect
			(at -2.050034 -59.92495 270)
			(size 0.519938 1.4986)
			(layers "F.Cu" "F.Mask" "F.Paste")
			(net "I3C_SPD_DDRABCD_CPU1_LVC1_SDA")
		)
		(pad "6" smd rect
			(at -2.050034 -59.075066 270)
			(size 0.519938 1.4986)
			(layers "F.Cu" "F.Mask" "F.Paste")
			(net "GND")
		)
		(pad "7" smd rect
			(at -2.050034 -58.224928 270)
			(size 0.519938 1.4986)
			(layers "F.Cu" "F.Mask" "F.Paste")
			(net "M_A_CPU1_SA_DQ<0>")
		)
		(pad "8" smd rect
			(at -2.050034 -57.375044 270)
			(size 0.519938 1.4986)
			(layers "F.Cu" "F.Mask" "F.Paste")
			(net "GND")
		)
		(pad "9" smd rect
			(at -2.050034 -56.524906 270)
			(size 0.519938 1.4986)
			(layers "F.Cu" "F.Mask" "F.Paste")
			(net "M_A_CPU1_SA_DQ<1>")
		)
		(pad "10" smd rect
			(at -2.050034 -55.675022 270)
			(size 0.519938 1.4986)
			(layers "F.Cu" "F.Mask" "F.Paste")
			(net "GND")
		)
		(pad "11" smd rect
			(at -2.050034 -54.824884 270)
			(size 0.519938 1.4986)
			(layers "F.Cu" "F.Mask" "F.Paste")
			(net "M_A_CPU1_SA_DQS_DP<0>")
		)
		(pad "12" smd rect
			(at -2.050034 -53.975 270)
			(size 0.519938 1.4986)
			(layers "F.Cu" "F.Mask" "F.Paste")
			(net "M_A_CPU1_SA_DQS_DN<0>")
		)
		(pad "13" smd rect
			(at -2.050034 -53.125116 270)
			(size 0.519938 1.4986)
			(layers "F.Cu" "F.Mask" "F.Paste")
			(net "GND")
		)
		(pad "14" smd rect
			(at -2.050034 -52.274978 270)
			(size 0.519938 1.4986)
			(layers "F.Cu" "F.Mask" "F.Paste")
			(net "M_A_CPU1_SA_DQ<4>")
		)
		(pad "15" smd rect
			(at -2.050034 -51.425094 270)
			(size 0.519938 1.4986)
			(layers "F.Cu" "F.Mask" "F.Paste")
			(net "GND")
		)
		(pad "16" smd rect
			(at -2.050034 -50.574956 270)
			(size 0.519938 1.4986)
			(layers "F.Cu" "F.Mask" "F.Paste")
			(net "M_A_CPU1_SA_DQ<5>")
		)
		(pad "17" smd rect
			(at -2.050034 -49.725072 270)
			(size 0.519938 1.4986)
			(layers "F.Cu" "F.Mask" "F.Paste")
			(net "GND")
		)
		(pad "18" smd rect
			(at -2.050034 -48.874934 270)
			(size 0.519938 1.4986)
			(layers "F.Cu" "F.Mask" "F.Paste")
			(net "M_A_CPU1_SA_DQ<8>")
		)
		(pad "19" smd rect
			(at -2.050034 -48.02505 270)
			(size 0.519938 1.4986)
			(layers "F.Cu" "F.Mask" "F.Paste")
			(net "GND")
		)
		(pad "20" smd rect
			(at -2.050034 -47.174912 270)
			(size 0.519938 1.4986)
			(layers "F.Cu" "F.Mask" "F.Paste")
			(net "M_A_CPU1_SA_DQ<9>")
		)
		(pad "21" smd rect
			(at -2.050034 -46.325028 270)
			(size 0.519938 1.4986)
			(layers "F.Cu" "F.Mask" "F.Paste")
			(net "GND")
		)
		(pad "22" smd rect
			(at -2.050034 -45.47489 270)
			(size 0.519938 1.4986)
			(layers "F.Cu" "F.Mask" "F.Paste")
			(net "M_A_CPU1_SA_DQS_DP<1>")
		)
		(pad "23" smd rect
			(at -2.050034 -44.625006 270)
			(size 0.519938 1.4986)
			(layers "F.Cu" "F.Mask" "F.Paste")
			(net "M_A_CPU1_SA_DQS_DN<1>")
		)
		(pad "24" smd rect
			(at -2.050034 -43.775122 270)
			(size 0.519938 1.4986)
			(layers "F.Cu" "F.Mask" "F.Paste")
			(net "GND")
		)
		(pad "25" smd rect
			(at -2.050034 -42.924984 270)
			(size 0.519938 1.4986)
			(layers "F.Cu" "F.Mask" "F.Paste")
			(net "M_A_CPU1_SA_DQ<12>")
		)
		(pad "26" smd rect
			(at -2.050034 -42.0751 270)
			(size 0.519938 1.4986)
			(layers "F.Cu" "F.Mask" "F.Paste")
			(net "GND")
		)
		(pad "27" smd rect
			(at -2.050034 -41.224962 270)
			(size 0.519938 1.4986)
			(layers "F.Cu" "F.Mask" "F.Paste")
			(net "M_A_CPU1_SA_DQ<13>")
		)
		(pad "28" smd rect
			(at -2.050034 -40.375078 270)
			(size 0.519938 1.4986)
			(layers "F.Cu" "F.Mask" "F.Paste")
			(net "GND")
		)
		(pad "29" smd rect
			(at -2.050034 -39.52494 270)
			(size 0.519938 1.4986)
			(layers "F.Cu" "F.Mask" "F.Paste")
			(net "M_A_CPU1_SA_DQ<16>")
		)
		(pad "30" smd rect
			(at -2.050034 -38.675056 270)
			(size 0.519938 1.4986)
			(layers "F.Cu" "F.Mask" "F.Paste")
			(net "GND")
		)
		(pad "31" smd rect
			(at -2.050034 -37.824918 270)
			(size 0.519938 1.4986)
			(layers "F.Cu" "F.Mask" "F.Paste")
			(net "M_A_CPU1_SA_DQ<17>")
		)
		(pad "32" smd rect
			(at -2.050034 -36.975034 270)
			(size 0.519938 1.4986)
			(layers "F.Cu" "F.Mask" "F.Paste")
			(net "GND")
		)
		(pad "33" smd rect
			(at -2.050034 -36.124896 270)
			(size 0.519938 1.4986)
			(layers "F.Cu" "F.Mask" "F.Paste")
			(net "M_A_CPU1_SA_DQS_DP<2>")
		)
		(pad "34" smd rect
			(at -2.050034 -35.275012 270)
			(size 0.519938 1.4986)
			(layers "F.Cu" "F.Mask" "F.Paste")
			(net "M_A_CPU1_SA_DQS_DN<2>")
		)
		(pad "35" smd rect
			(at -2.050034 -34.425128 270)
			(size 0.519938 1.4986)
			(layers "F.Cu" "F.Mask" "F.Paste")
			(net "GND")
		)
		(pad "36" smd rect
			(at -2.050034 -33.57499 270)
			(size 0.519938 1.4986)
			(layers "F.Cu" "F.Mask" "F.Paste")
			(net "M_A_CPU1_SA_DQ<20>")
		)
		(pad "37" smd rect
			(at -2.050034 -32.725106 270)
			(size 0.519938 1.4986)
			(layers "F.Cu" "F.Mask" "F.Paste")
			(net "GND")
		)
		(pad "38" smd rect
			(at -2.050034 -31.874968 270)
			(size 0.519938 1.4986)
			(layers "F.Cu" "F.Mask" "F.Paste")
			(net "M_A_CPU1_SA_DQ<21>")
		)
		(pad "39" smd rect
			(at -2.050034 -31.025084 270)
			(size 0.519938 1.4986)
			(layers "F.Cu" "F.Mask" "F.Paste")
			(net "GND")
		)
		(pad "40" smd rect
			(at -2.050034 -30.174946 270)
			(size 0.519938 1.4986)
			(layers "F.Cu" "F.Mask" "F.Paste")
			(net "M_A_CPU1_SA_DQ<24>")
		)
		(pad "41" smd rect
			(at -2.050034 -29.325062 270)
			(size 0.519938 1.4986)
			(layers "F.Cu" "F.Mask" "F.Paste")
			(net "GND")
		)
		(pad "42" smd rect
			(at -2.050034 -28.474924 270)
			(size 0.519938 1.4986)
			(layers "F.Cu" "F.Mask" "F.Paste")
			(net "M_A_CPU1_SA_DQ<25>")
		)
		(pad "43" smd rect
			(at -2.050034 -27.62504 270)
			(size 0.519938 1.4986)
			(layers "F.Cu" "F.Mask" "F.Paste")
			(net "GND")
		)
		(pad "44" smd rect
			(at -2.050034 -26.774902 270)
			(size 0.519938 1.4986)
			(layers "F.Cu" "F.Mask" "F.Paste")
			(net "M_A_CPU1_SA_DQS_DP<3>")
		)
		(pad "45" smd rect
			(at -2.050034 -25.925018 270)
			(size 0.519938 1.4986)
			(layers "F.Cu" "F.Mask" "F.Paste")
			(net "M_A_CPU1_SA_DQS_DN<3>")
		)
		(pad "46" smd rect
			(at -2.050034 -25.07488 270)
			(size 0.519938 1.4986)
			(layers "F.Cu" "F.Mask" "F.Paste")
			(net "GND")
		)
		(pad "47" smd rect
			(at -2.050034 -24.224996 270)
			(size 0.519938 1.4986)
			(layers "F.Cu" "F.Mask" "F.Paste")
			(net "M_A_CPU1_SA_DQ<28>")
		)
		(pad "48" smd rect
			(at -2.050034 -23.375112 270)
			(size 0.519938 1.4986)
			(layers "F.Cu" "F.Mask" "F.Paste")
			(net "GND")
		)
		(pad "49" smd rect
			(at -2.050034 -22.524974 270)
			(size 0.519938 1.4986)
			(layers "F.Cu" "F.Mask" "F.Paste")
			(net "M_A_CPU1_SA_DQ<29>")
		)
		(pad "50" smd rect
			(at -2.050034 -21.67509 270)
			(size 0.519938 1.4986)
			(layers "F.Cu" "F.Mask" "F.Paste")
			(net "GND")
		)
		(pad "51" smd rect
			(at -2.050034 -20.824952 270)
			(size 0.519938 1.4986)
			(layers "F.Cu" "F.Mask" "F.Paste")
			(net "M_A_CPU1_SA_CB<0>")
		)
		(pad "52" smd rect
			(at -2.050034 -19.975068 270)
			(size 0.519938 1.4986)
			(layers "F.Cu" "F.Mask" "F.Paste")
			(net "GND")
		)
		(pad "53" smd rect
			(at -2.050034 -19.12493 270)
			(size 0.519938 1.4986)
			(layers "F.Cu" "F.Mask" "F.Paste")
			(net "M_A_CPU1_SA_CB<1>")
		)
		(pad "54" smd rect
			(at -2.050034 -18.275046 270)
			(size 0.519938 1.4986)
			(layers "F.Cu" "F.Mask" "F.Paste")
			(net "GND")
		)
		(pad "55" smd rect
			(at -2.050034 -17.424908 270)
			(size 0.519938 1.4986)
			(layers "F.Cu" "F.Mask" "F.Paste")
			(net "M_A_CPU1_SA_DQS_DP<4>")
		)
		(pad "56" smd rect
			(at -2.050034 -16.575024 270)
			(size 0.519938 1.4986)
			(layers "F.Cu" "F.Mask" "F.Paste")
			(net "M_A_CPU1_SA_DQS_DN<4>")
		)
		(pad "57" smd rect
			(at -2.050034 -15.724886 270)
			(size 0.519938 1.4986)
			(layers "F.Cu" "F.Mask" "F.Paste")
			(net "GND")
		)
		(pad "58" smd rect
			(at -2.050034 -14.875002 270)
			(size 0.519938 1.4986)
			(layers "F.Cu" "F.Mask" "F.Paste")
			(net "M_A_CPU1_SA_CB<4>")
		)
		(pad "59" smd rect
			(at -2.050034 -14.025118 270)
			(size 0.519938 1.4986)
			(layers "F.Cu" "F.Mask" "F.Paste")
			(net "GND")
		)
		(pad "60" smd rect
			(at -2.050034 -13.17498 270)
			(size 0.519938 1.4986)
			(layers "F.Cu" "F.Mask" "F.Paste")
			(net "M_A_CPU1_SA_CB<5>")
		)
		(pad "61" smd rect
			(at -2.050034 -12.325096 270)
			(size 0.519938 1.4986)
			(layers "F.Cu" "F.Mask" "F.Paste")
			(net "GND")
		)
		(pad "62" smd rect
			(at -2.050034 -11.474958 270)
			(size 0.519938 1.4986)
			(layers "F.Cu" "F.Mask" "F.Paste")
			(net "M_A_CPU1_ALERT_N")
		)
		(pad "63" smd rect
			(at -2.050034 -10.625074 270)
			(size 0.519938 1.4986)
			(layers "F.Cu" "F.Mask" "F.Paste")
			(net "GND")
		)
		(pad "64" smd rect
			(at -2.050034 -9.774936 270)
			(size 0.519938 1.4986)
			(layers "F.Cu" "F.Mask" "F.Paste")
			(net "M_A_CPU1_SA_CS_N<0>")
		)
		(pad "65" smd rect
			(at -2.050034 -8.925052 270)
			(size 0.519938 1.4986)
			(layers "F.Cu" "F.Mask" "F.Paste")
			(net "GND")
		)
		(pad "66" smd rect
			(at -2.050034 -8.074914 270)
			(size 0.519938 1.4986)
			(layers "F.Cu" "F.Mask" "F.Paste")
			(net "M_A_CPU1_SA_CA<0>")
		)
		(pad "67" smd rect
			(at -2.050034 -7.22503 270)
			(size 0.519938 1.4986)
			(layers "F.Cu" "F.Mask" "F.Paste")
			(net "GND")
		)
		(pad "68" smd rect
			(at -2.050034 -6.374892 270)
			(size 0.519938 1.4986)
			(layers "F.Cu" "F.Mask" "F.Paste")
			(net "M_A_CPU1_SA_CA<2>")
		)
		(pad "69" smd rect
			(at -2.050034 -5.525008 270)
			(size 0.519938 1.4986)
			(layers "F.Cu" "F.Mask" "F.Paste")
			(net "GND")
		)
		(pad "70" smd rect
			(at -2.050034 -4.675124 270)
			(size 0.519938 1.4986)
			(layers "F.Cu" "F.Mask" "F.Paste")
			(net "M_A_CPU1_SA_CA<4>")
		)
		(pad "71" smd rect
			(at -2.050034 -3.824986 270)
			(size 0.519938 1.4986)
			(layers "F.Cu" "F.Mask" "F.Paste")
			(net "GND")
		)
		(pad "72" smd rect
			(at -2.050034 -2.975102 270)
			(size 0.519938 1.4986)
			(layers "F.Cu" "F.Mask" "F.Paste")
			(net "M_A_CPU1_SA_CA<6>")
		)
		(pad "73" smd rect
			(at -2.050034 -2.124964 270)
			(size 0.519938 1.4986)
			(layers "F.Cu" "F.Mask" "F.Paste")
			(net "GND")
		)
		(pad "74" smd rect
			(at -2.050034 -1.27508 270)
			(size 0.519938 1.4986)
			(layers "F.Cu" "F.Mask" "F.Paste")
			(net "M_A_CPU1_SA_PAR")
		)
		(pad "75" smd rect
			(at -2.050034 -0.424942 270)
			(size 0.519938 1.4986)
			(layers "F.Cu" "F.Mask" "F.Paste")
			(net "GND")
		)
		(pad "76" smd rect
			(at -2.050034 5.525008 270)
			(size 0.519938 1.4986)
			(layers "F.Cu" "F.Mask" "F.Paste")
			(net "M_A_CPU1_SB_CA<0>")
		)
		(pad "77" smd rect
			(at -2.050034 6.374892 270)
			(size 0.519938 1.4986)
			(layers "F.Cu" "F.Mask" "F.Paste")
			(net "GND")
		)
		(pad "78" smd rect
			(at -2.050034 7.22503 270)
			(size 0.519938 1.4986)
			(layers "F.Cu" "F.Mask" "F.Paste")
			(net "M_A_CPU1_SB_CA<2>")
		)
		(pad "79" smd rect
			(at -2.050034 8.074914 270)
			(size 0.519938 1.4986)
			(layers "F.Cu" "F.Mask" "F.Paste")
			(net "GND")
		)
		(pad "80" smd rect
			(at -2.050034 8.925052 270)
			(size 0.519938 1.4986)
			(layers "F.Cu" "F.Mask" "F.Paste")
			(net "M_A_CPU1_SB_CA<4>")
		)
		(pad "81" smd rect
			(at -2.050034 9.774936 270)
			(size 0.519938 1.4986)
			(layers "F.Cu" "F.Mask" "F.Paste")
			(net "GND")
		)
		(pad "82" smd rect
			(at -2.050034 10.625074 270)
			(size 0.519938 1.4986)
			(layers "F.Cu" "F.Mask" "F.Paste")
			(net "M_A_CPU1_SB_CA<6>")
		)
		(pad "83" smd rect
			(at -2.050034 11.474958 270)
			(size 0.519938 1.4986)
			(layers "F.Cu" "F.Mask" "F.Paste")
			(net "GND")
		)
		(pad "84" smd rect
			(at -2.050034 12.325096 270)
			(size 0.519938 1.4986)
			(layers "F.Cu" "F.Mask" "F.Paste")
			(net "M_A_CPU1_SB_CS_N<0>")
		)
		(pad "85" smd rect
			(at -2.050034 13.17498 270)
			(size 0.519938 1.4986)
			(layers "F.Cu" "F.Mask" "F.Paste")
			(net "GND")
		)
		(pad "86" smd rect
			(at -2.050034 14.025118 270)
			(size 0.519938 1.4986)
			(layers "F.Cu" "F.Mask" "F.Paste")
			(net "M_A_CPU1_SA_RSP<0>")
		)
		(pad "87" smd rect
			(at -2.050034 14.875002 270)
			(size 0.519938 1.4986)
			(layers "F.Cu" "F.Mask" "F.Paste")
			(net "M_A_CPU1_SB_RSP<0>")
		)
		(pad "88" smd rect
			(at -2.050034 15.724886 270)
			(size 0.519938 1.4986)
			(layers "F.Cu" "F.Mask" "F.Paste")
			(net "GND")
		)
		(pad "89" smd rect
			(at -2.050034 16.575024 270)
			(size 0.519938 1.4986)
			(layers "F.Cu" "F.Mask" "F.Paste")
			(net "M_A_CPU1_SB_CB<4>")
		)
		(pad "90" smd rect
			(at -2.050034 17.424908 270)
			(size 0.519938 1.4986)
			(layers "F.Cu" "F.Mask" "F.Paste")
			(net "GND")
		)
		(pad "91" smd rect
			(at -2.050034 18.275046 270)
			(size 0.519938 1.4986)
			(layers "F.Cu" "F.Mask" "F.Paste")
			(net "M_A_CPU1_SB_CB<5>")
		)
		(pad "92" smd rect
			(at -2.050034 19.12493 270)
			(size 0.519938 1.4986)
			(layers "F.Cu" "F.Mask" "F.Paste")
			(net "GND")
		)
		(pad "93" smd rect
			(at -2.050034 19.975068 270)
			(size 0.519938 1.4986)
			(layers "F.Cu" "F.Mask" "F.Paste")
			(net "M_A_CPU1_SB_DQS_DP<9>")
		)
		(pad "94" smd rect
			(at -2.050034 20.824952 270)
			(size 0.519938 1.4986)
			(layers "F.Cu" "F.Mask" "F.Paste")
			(net "M_A_CPU1_SB_DQS_DN<9>")
		)
		(pad "95" smd rect
			(at -2.050034 21.67509 270)
			(size 0.519938 1.4986)
			(layers "F.Cu" "F.Mask" "F.Paste")
			(net "GND")
		)
		(pad "96" smd rect
			(at -2.050034 22.524974 270)
			(size 0.519938 1.4986)
			(layers "F.Cu" "F.Mask" "F.Paste")
			(net "M_A_CPU1_SB_CB<0>")
		)
		(pad "97" smd rect
			(at -2.050034 23.375112 270)
			(size 0.519938 1.4986)
			(layers "F.Cu" "F.Mask" "F.Paste")
			(net "GND")
		)
		(pad "98" smd rect
			(at -2.050034 24.224996 270)
			(size 0.519938 1.4986)
			(layers "F.Cu" "F.Mask" "F.Paste")
			(net "M_A_CPU1_SB_CB<1>")
		)
		(pad "99" smd rect
			(at -2.050034 25.07488 270)
			(size 0.519938 1.4986)
			(layers "F.Cu" "F.Mask" "F.Paste")
			(net "GND")
		)
		(pad "100" smd rect
			(at -2.050034 25.925018 270)
			(size 0.519938 1.4986)
			(layers "F.Cu" "F.Mask" "F.Paste")
			(net "M_A_CPU1_SB_DQ<0>")
		)
		(pad "101" smd rect
			(at -2.050034 26.774902 270)
			(size 0.519938 1.4986)
			(layers "F.Cu" "F.Mask" "F.Paste")
			(net "GND")
		)
		(pad "102" smd rect
			(at -2.050034 27.62504 270)
			(size 0.519938 1.4986)
			(layers "F.Cu" "F.Mask" "F.Paste")
			(net "M_A_CPU1_SB_DQ<1>")
		)
		(pad "103" smd rect
			(at -2.050034 28.474924 270)
			(size 0.519938 1.4986)
			(layers "F.Cu" "F.Mask" "F.Paste")
			(net "GND")
		)
		(pad "104" smd rect
			(at -2.050034 29.325062 270)
			(size 0.519938 1.4986)
			(layers "F.Cu" "F.Mask" "F.Paste")
			(net "M_A_CPU1_SB_DQS_DP<0>")
		)
		(pad "105" smd rect
			(at -2.050034 30.174946 270)
			(size 0.519938 1.4986)
			(layers "F.Cu" "F.Mask" "F.Paste")
			(net "M_A_CPU1_SB_DQS_DN<0>")
		)
		(pad "106" smd rect
			(at -2.050034 31.025084 270)
			(size 0.519938 1.4986)
			(layers "F.Cu" "F.Mask" "F.Paste")
			(net "GND")
		)
		(pad "107" smd rect
			(at -2.050034 31.874968 270)
			(size 0.519938 1.4986)
			(layers "F.Cu" "F.Mask" "F.Paste")
			(net "M_A_CPU1_SB_DQ<4>")
		)
		(pad "108" smd rect
			(at -2.050034 32.725106 270)
			(size 0.519938 1.4986)
			(layers "F.Cu" "F.Mask" "F.Paste")
			(net "GND")
		)
		(pad "109" smd rect
			(at -2.050034 33.57499 270)
			(size 0.519938 1.4986)
			(layers "F.Cu" "F.Mask" "F.Paste")
			(net "M_A_CPU1_SB_DQ<5>")
		)
		(pad "110" smd rect
			(at -2.050034 34.425128 270)
			(size 0.519938 1.4986)
			(layers "F.Cu" "F.Mask" "F.Paste")
			(net "GND")
		)
		(pad "111" smd rect
			(at -2.050034 35.275012 270)
			(size 0.519938 1.4986)
			(layers "F.Cu" "F.Mask" "F.Paste")
			(net "M_A_CPU1_SB_DQ<8>")
		)
		(pad "112" smd rect
			(at -2.050034 36.124896 270)
			(size 0.519938 1.4986)
			(layers "F.Cu" "F.Mask" "F.Paste")
			(net "GND")
		)
		(pad "113" smd rect
			(at -2.050034 36.975034 270)
			(size 0.519938 1.4986)
			(layers "F.Cu" "F.Mask" "F.Paste")
			(net "M_A_CPU1_SB_DQ<9>")
		)
		(pad "114" smd rect
			(at -2.050034 37.824918 270)
			(size 0.519938 1.4986)
			(layers "F.Cu" "F.Mask" "F.Paste")
			(net "GND")
		)
		(pad "115" smd rect
			(at -2.050034 38.675056 270)
			(size 0.519938 1.4986)
			(layers "F.Cu" "F.Mask" "F.Paste")
			(net "M_A_CPU1_SB_DQS_DP<1>")
		)
		(pad "116" smd rect
			(at -2.050034 39.52494 270)
			(size 0.519938 1.4986)
			(layers "F.Cu" "F.Mask" "F.Paste")
			(net "M_A_CPU1_SB_DQS_DN<1>")
		)
		(pad "117" smd rect
			(at -2.050034 40.375078 270)
			(size 0.519938 1.4986)
			(layers "F.Cu" "F.Mask" "F.Paste")
			(net "GND")
		)
		(pad "118" smd rect
			(at -2.050034 41.224962 270)
			(size 0.519938 1.4986)
			(layers "F.Cu" "F.Mask" "F.Paste")
			(net "M_A_CPU1_SB_DQ<12>")
		)
		(pad "119" smd rect
			(at -2.050034 42.0751 270)
			(size 0.519938 1.4986)
			(layers "F.Cu" "F.Mask" "F.Paste")
			(net "GND")
		)
		(pad "120" smd rect
			(at -2.050034 42.924984 270)
			(size 0.519938 1.4986)
			(layers "F.Cu" "F.Mask" "F.Paste")
			(net "M_A_CPU1_SB_DQ<13>")
		)
		(pad "121" smd rect
			(at -2.050034 43.775122 270)
			(size 0.519938 1.4986)
			(layers "F.Cu" "F.Mask" "F.Paste")
			(net "GND")
		)
		(pad "122" smd rect
			(at -2.050034 44.625006 270)
			(size 0.519938 1.4986)
			(layers "F.Cu" "F.Mask" "F.Paste")
			(net "M_A_CPU1_SB_DQ<16>")
		)
		(pad "123" smd rect
			(at -2.050034 45.47489 270)
			(size 0.519938 1.4986)
			(layers "F.Cu" "F.Mask" "F.Paste")
			(net "GND")
		)
		(pad "124" smd rect
			(at -2.050034 46.325028 270)
			(size 0.519938 1.4986)
			(layers "F.Cu" "F.Mask" "F.Paste")
			(net "M_A_CPU1_SB_DQ<17>")
		)
		(pad "125" smd rect
			(at -2.050034 47.174912 270)
			(size 0.519938 1.4986)
			(layers "F.Cu" "F.Mask" "F.Paste")
			(net "GND")
		)
		(pad "126" smd rect
			(at -2.050034 48.02505 270)
			(size 0.519938 1.4986)
			(layers "F.Cu" "F.Mask" "F.Paste")
			(net "M_A_CPU1_SB_DQS_DP<2>")
		)
		(pad "127" smd rect
			(at -2.050034 48.874934 270)
			(size 0.519938 1.4986)
			(layers "F.Cu" "F.Mask" "F.Paste")
			(net "M_A_CPU1_SB_DQS_DN<2>")
		)
		(pad "128" smd rect
			(at -2.050034 49.725072 270)
			(size 0.519938 1.4986)
			(layers "F.Cu" "F.Mask" "F.Paste")
			(net "GND")
		)
		(pad "129" smd rect
			(at -2.050034 50.574956 270)
			(size 0.519938 1.4986)
			(layers "F.Cu" "F.Mask" "F.Paste")
			(net "M_A_CPU1_SB_DQ<20>")
		)
		(pad "130" smd rect
			(at -2.050034 51.425094 270)
			(size 0.519938 1.4986)
			(layers "F.Cu" "F.Mask" "F.Paste")
			(net "GND")
		)
		(pad "131" smd rect
			(at -2.050034 52.274978 270)
			(size 0.519938 1.4986)
			(layers "F.Cu" "F.Mask" "F.Paste")
			(net "M_A_CPU1_SB_DQ<21>")
		)
		(pad "132" smd rect
			(at -2.050034 53.125116 270)
			(size 0.519938 1.4986)
			(layers "F.Cu" "F.Mask" "F.Paste")
			(net "GND")
		)
		(pad "133" smd rect
			(at -2.050034 53.975 270)
			(size 0.519938 1.4986)
			(layers "F.Cu" "F.Mask" "F.Paste")
			(net "M_A_CPU1_SB_DQ<24>")
		)
		(pad "134" smd rect
			(at -2.050034 54.824884 270)
			(size 0.519938 1.4986)
			(layers "F.Cu" "F.Mask" "F.Paste")
			(net "GND")
		)
		(pad "135" smd rect
			(at -2.050034 55.675022 270)
			(size 0.519938 1.4986)
			(layers "F.Cu" "F.Mask" "F.Paste")
			(net "M_A_CPU1_SB_DQ<25>")
		)
		(pad "136" smd rect
			(at -2.050034 56.524906 270)
			(size 0.519938 1.4986)
			(layers "F.Cu" "F.Mask" "F.Paste")
			(net "GND")
		)
		(pad "137" smd rect
			(at -2.050034 57.375044 270)
			(size 0.519938 1.4986)
			(layers "F.Cu" "F.Mask" "F.Paste")
			(net "M_A_CPU1_SB_DQS_DP<3>")
		)
		(pad "138" smd rect
			(at -2.050034 58.224928 270)
			(size 0.519938 1.4986)
			(layers "F.Cu" "F.Mask" "F.Paste")
			(net "M_A_CPU1_SB_DQS_DN<3>")
		)
		(pad "139" smd rect
			(at -2.050034 59.075066 270)
			(size 0.519938 1.4986)
			(layers "F.Cu" "F.Mask" "F.Paste")
			(net "GND")
		)
		(pad "140" smd rect
			(at -2.050034 59.92495 270)
			(size 0.519938 1.4986)
			(layers "F.Cu" "F.Mask" "F.Paste")
			(net "M_A_CPU1_SB_DQ<28>")
		)
		(pad "141" smd rect
			(at -2.050034 60.775088 270)
			(size 0.519938 1.4986)
			(layers "F.Cu" "F.Mask" "F.Paste")
			(net "GND")
		)
		(pad "142" smd rect
			(at -2.050034 61.624972 270)
			(size 0.519938 1.4986)
			(layers "F.Cu" "F.Mask" "F.Paste")
			(net "M_A_CPU1_SB_DQ<29>")
		)
		(pad "143" smd rect
			(at -2.050034 62.47511 270)
			(size 0.519938 1.4986)
			(layers "F.Cu" "F.Mask" "F.Paste")
			(net "GND")
		)
		(pad "144" smd rect
			(at -2.050034 63.324994 270)
			(size 0.519938 1.4986)
			(layers "F.Cu" "F.Mask" "F.Paste")
			(net "TP_CHA_CPU1_DIMM1_FRU_1")
		)
		(pad "145" smd rect
			(at 2.050034 -63.324994 270)
			(size 0.519938 1.4986)
			(layers "F.Cu" "F.Mask" "F.Paste")
			(net "P12V_S3_AUX_CPU1_NVDIMM")
		)
		(pad "146" smd rect
			(at 2.050034 -62.47511 270)
			(size 0.519938 1.4986)
			(layers "F.Cu" "F.Mask" "F.Paste")
			(net "P12V_S3_AUX_CPU1_NVDIMM")
		)
		(pad "147" smd rect
			(at 2.050034 -61.624972 270)
			(size 0.519938 1.4986)
			(layers "F.Cu" "F.Mask" "F.Paste")
			(net "PWRGD_CHA_CPU1_DIMM1")
		)
		(pad "148" smd rect
			(at 2.050034 -60.775088 270)
			(size 0.519938 1.4986)
			(layers "F.Cu" "F.Mask" "F.Paste")
			(net "PD_CHA_CPU1_DIMM1_SAA")
		)
		(pad "149" smd rect
			(at 2.050034 -59.92495 270)
			(size 0.519938 1.4986)
			(layers "F.Cu" "F.Mask" "F.Paste")
			(net "TP_CHA_CPU1_DIMM1_FRU_2")
		)
		(pad "150" smd rect
			(at 2.050034 -59.075066 270)
			(size 0.519938 1.4986)
			(layers "F.Cu" "F.Mask" "F.Paste")
			(net "TP_CHA_CPU1_DIMM1_FRU_3")
		)
		(pad "151" smd rect
			(at 2.050034 -58.224928 270)
			(size 0.519938 1.4986)
			(layers "F.Cu" "F.Mask" "F.Paste")
			(net "GND")
		)
		(pad "152" smd rect
			(at 2.050034 -57.375044 270)
			(size 0.519938 1.4986)
			(layers "F.Cu" "F.Mask" "F.Paste")
			(net "M_A_CPU1_SA_DQ<2>")
		)
		(pad "153" smd rect
			(at 2.050034 -56.524906 270)
			(size 0.519938 1.4986)
			(layers "F.Cu" "F.Mask" "F.Paste")
			(net "GND")
		)
		(pad "154" smd rect
			(at 2.050034 -55.675022 270)
			(size 0.519938 1.4986)
			(layers "F.Cu" "F.Mask" "F.Paste")
			(net "M_A_CPU1_SA_DQ<3>")
		)
		(pad "155" smd rect
			(at 2.050034 -54.824884 270)
			(size 0.519938 1.4986)
			(layers "F.Cu" "F.Mask" "F.Paste")
			(net "GND")
		)
		(pad "156" smd rect
			(at 2.050034 -53.975 270)
			(size 0.519938 1.4986)
			(layers "F.Cu" "F.Mask" "F.Paste")
			(net "M_A_CPU1_SA_DQS_DN<5>")
		)
		(pad "157" smd rect
			(at 2.050034 -53.125116 270)
			(size 0.519938 1.4986)
			(layers "F.Cu" "F.Mask" "F.Paste")
			(net "M_A_CPU1_SA_DQS_DP<5>")
		)
		(pad "158" smd rect
			(at 2.050034 -52.274978 270)
			(size 0.519938 1.4986)
			(layers "F.Cu" "F.Mask" "F.Paste")
			(net "GND")
		)
		(pad "159" smd rect
			(at 2.050034 -51.425094 270)
			(size 0.519938 1.4986)
			(layers "F.Cu" "F.Mask" "F.Paste")
			(net "M_A_CPU1_SA_DQ<6>")
		)
		(pad "160" smd rect
			(at 2.050034 -50.574956 270)
			(size 0.519938 1.4986)
			(layers "F.Cu" "F.Mask" "F.Paste")
			(net "GND")
		)
		(pad "161" smd rect
			(at 2.050034 -49.725072 270)
			(size 0.519938 1.4986)
			(layers "F.Cu" "F.Mask" "F.Paste")
			(net "M_A_CPU1_SA_DQ<7>")
		)
		(pad "162" smd rect
			(at 2.050034 -48.874934 270)
			(size 0.519938 1.4986)
			(layers "F.Cu" "F.Mask" "F.Paste")
			(net "GND")
		)
		(pad "163" smd rect
			(at 2.050034 -48.02505 270)
			(size 0.519938 1.4986)
			(layers "F.Cu" "F.Mask" "F.Paste")
			(net "M_A_CPU1_SA_DQ<10>")
		)
		(pad "164" smd rect
			(at 2.050034 -47.174912 270)
			(size 0.519938 1.4986)
			(layers "F.Cu" "F.Mask" "F.Paste")
			(net "GND")
		)
		(pad "165" smd rect
			(at 2.050034 -46.325028 270)
			(size 0.519938 1.4986)
			(layers "F.Cu" "F.Mask" "F.Paste")
			(net "M_A_CPU1_SA_DQ<11>")
		)
		(pad "166" smd rect
			(at 2.050034 -45.47489 270)
			(size 0.519938 1.4986)
			(layers "F.Cu" "F.Mask" "F.Paste")
			(net "GND")
		)
		(pad "167" smd rect
			(at 2.050034 -44.625006 270)
			(size 0.519938 1.4986)
			(layers "F.Cu" "F.Mask" "F.Paste")
			(net "M_A_CPU1_SA_DQS_DN<6>")
		)
		(pad "168" smd rect
			(at 2.050034 -43.775122 270)
			(size 0.519938 1.4986)
			(layers "F.Cu" "F.Mask" "F.Paste")
			(net "M_A_CPU1_SA_DQS_DP<6>")
		)
		(pad "169" smd rect
			(at 2.050034 -42.924984 270)
			(size 0.519938 1.4986)
			(layers "F.Cu" "F.Mask" "F.Paste")
			(net "GND")
		)
		(pad "170" smd rect
			(at 2.050034 -42.0751 270)
			(size 0.519938 1.4986)
			(layers "F.Cu" "F.Mask" "F.Paste")
			(net "M_A_CPU1_SA_DQ<14>")
		)
		(pad "171" smd rect
			(at 2.050034 -41.224962 270)
			(size 0.519938 1.4986)
			(layers "F.Cu" "F.Mask" "F.Paste")
			(net "GND")
		)
		(pad "172" smd rect
			(at 2.050034 -40.375078 270)
			(size 0.519938 1.4986)
			(layers "F.Cu" "F.Mask" "F.Paste")
			(net "M_A_CPU1_SA_DQ<15>")
		)
		(pad "173" smd rect
			(at 2.050034 -39.52494 270)
			(size 0.519938 1.4986)
			(layers "F.Cu" "F.Mask" "F.Paste")
			(net "GND")
		)
		(pad "174" smd rect
			(at 2.050034 -38.675056 270)
			(size 0.519938 1.4986)
			(layers "F.Cu" "F.Mask" "F.Paste")
			(net "M_A_CPU1_SA_DQ<18>")
		)
		(pad "175" smd rect
			(at 2.050034 -37.824918 270)
			(size 0.519938 1.4986)
			(layers "F.Cu" "F.Mask" "F.Paste")
			(net "GND")
		)
		(pad "176" smd rect
			(at 2.050034 -36.975034 270)
			(size 0.519938 1.4986)
			(layers "F.Cu" "F.Mask" "F.Paste")
			(net "M_A_CPU1_SA_DQ<19>")
		)
		(pad "177" smd rect
			(at 2.050034 -36.124896 270)
			(size 0.519938 1.4986)
			(layers "F.Cu" "F.Mask" "F.Paste")
			(net "GND")
		)
		(pad "178" smd rect
			(at 2.050034 -35.275012 270)
			(size 0.519938 1.4986)
			(layers "F.Cu" "F.Mask" "F.Paste")
			(net "M_A_CPU1_SA_DQS_DN<7>")
		)
		(pad "179" smd rect
			(at 2.050034 -34.425128 270)
			(size 0.519938 1.4986)
			(layers "F.Cu" "F.Mask" "F.Paste")
			(net "M_A_CPU1_SA_DQS_DP<7>")
		)
		(pad "180" smd rect
			(at 2.050034 -33.57499 270)
			(size 0.519938 1.4986)
			(layers "F.Cu" "F.Mask" "F.Paste")
			(net "GND")
		)
		(pad "181" smd rect
			(at 2.050034 -32.725106 270)
			(size 0.519938 1.4986)
			(layers "F.Cu" "F.Mask" "F.Paste")
			(net "M_A_CPU1_SA_DQ<22>")
		)
		(pad "182" smd rect
			(at 2.050034 -31.874968 270)
			(size 0.519938 1.4986)
			(layers "F.Cu" "F.Mask" "F.Paste")
			(net "GND")
		)
		(pad "183" smd rect
			(at 2.050034 -31.025084 270)
			(size 0.519938 1.4986)
			(layers "F.Cu" "F.Mask" "F.Paste")
			(net "M_A_CPU1_SA_DQ<23>")
		)
		(pad "184" smd rect
			(at 2.050034 -30.174946 270)
			(size 0.519938 1.4986)
			(layers "F.Cu" "F.Mask" "F.Paste")
			(net "GND")
		)
		(pad "185" smd rect
			(at 2.050034 -29.325062 270)
			(size 0.519938 1.4986)
			(layers "F.Cu" "F.Mask" "F.Paste")
			(net "M_A_CPU1_SA_DQ<26>")
		)
		(pad "186" smd rect
			(at 2.050034 -28.474924 270)
			(size 0.519938 1.4986)
			(layers "F.Cu" "F.Mask" "F.Paste")
			(net "GND")
		)
		(pad "187" smd rect
			(at 2.050034 -27.62504 270)
			(size 0.519938 1.4986)
			(layers "F.Cu" "F.Mask" "F.Paste")
			(net "M_A_CPU1_SA_DQ<27>")
		)
		(pad "188" smd rect
			(at 2.050034 -26.774902 270)
			(size 0.519938 1.4986)
			(layers "F.Cu" "F.Mask" "F.Paste")
			(net "GND")
		)
		(pad "189" smd rect
			(at 2.050034 -25.925018 270)
			(size 0.519938 1.4986)
			(layers "F.Cu" "F.Mask" "F.Paste")
			(net "M_A_CPU1_SA_DQS_DN<8>")
		)
		(pad "190" smd rect
			(at 2.050034 -25.07488 270)
			(size 0.519938 1.4986)
			(layers "F.Cu" "F.Mask" "F.Paste")
			(net "M_A_CPU1_SA_DQS_DP<8>")
		)
		(pad "191" smd rect
			(at 2.050034 -24.224996 270)
			(size 0.519938 1.4986)
			(layers "F.Cu" "F.Mask" "F.Paste")
			(net "GND")
		)
		(pad "192" smd rect
			(at 2.050034 -23.375112 270)
			(size 0.519938 1.4986)
			(layers "F.Cu" "F.Mask" "F.Paste")
			(net "M_A_CPU1_SA_DQ<30>")
		)
		(pad "193" smd rect
			(at 2.050034 -22.524974 270)
			(size 0.519938 1.4986)
			(layers "F.Cu" "F.Mask" "F.Paste")
			(net "GND")
		)
		(pad "194" smd rect
			(at 2.050034 -21.67509 270)
			(size 0.519938 1.4986)
			(layers "F.Cu" "F.Mask" "F.Paste")
			(net "M_A_CPU1_SA_DQ<31>")
		)
		(pad "195" smd rect
			(at 2.050034 -20.824952 270)
			(size 0.519938 1.4986)
			(layers "F.Cu" "F.Mask" "F.Paste")
			(net "GND")
		)
		(pad "196" smd rect
			(at 2.050034 -19.975068 270)
			(size 0.519938 1.4986)
			(layers "F.Cu" "F.Mask" "F.Paste")
			(net "M_A_CPU1_SA_CB<2>")
		)
		(pad "197" smd rect
			(at 2.050034 -19.12493 270)
			(size 0.519938 1.4986)
			(layers "F.Cu" "F.Mask" "F.Paste")
			(net "GND")
		)
		(pad "198" smd rect
			(at 2.050034 -18.275046 270)
			(size 0.519938 1.4986)
			(layers "F.Cu" "F.Mask" "F.Paste")
			(net "M_A_CPU1_SA_CB<3>")
		)
		(pad "199" smd rect
			(at 2.050034 -17.424908 270)
			(size 0.519938 1.4986)
			(layers "F.Cu" "F.Mask" "F.Paste")
			(net "GND")
		)
		(pad "200" smd rect
			(at 2.050034 -16.575024 270)
			(size 0.519938 1.4986)
			(layers "F.Cu" "F.Mask" "F.Paste")
			(net "M_A_CPU1_SA_DQS_DN<9>")
		)
		(pad "201" smd rect
			(at 2.050034 -15.724886 270)
			(size 0.519938 1.4986)
			(layers "F.Cu" "F.Mask" "F.Paste")
			(net "M_A_CPU1_SA_DQS_DP<9>")
		)
		(pad "202" smd rect
			(at 2.050034 -14.875002 270)
			(size 0.519938 1.4986)
			(layers "F.Cu" "F.Mask" "F.Paste")
			(net "GND")
		)
		(pad "203" smd rect
			(at 2.050034 -14.025118 270)
			(size 0.519938 1.4986)
			(layers "F.Cu" "F.Mask" "F.Paste")
			(net "M_A_CPU1_SA_CB<6>")
		)
		(pad "204" smd rect
			(at 2.050034 -13.17498 270)
			(size 0.519938 1.4986)
			(layers "F.Cu" "F.Mask" "F.Paste")
			(net "GND")
		)
		(pad "205" smd rect
			(at 2.050034 -12.325096 270)
			(size 0.519938 1.4986)
			(layers "F.Cu" "F.Mask" "F.Paste")
			(net "M_A_CPU1_SA_CB<7>")
		)
		(pad "206" smd rect
			(at 2.050034 -11.474958 270)
			(size 0.519938 1.4986)
			(layers "F.Cu" "F.Mask" "F.Paste")
			(net "GND")
		)
		(pad "207" smd rect
			(at 2.050034 -10.625074 270)
			(size 0.519938 1.4986)
			(layers "F.Cu" "F.Mask" "F.Paste")
			(net "RST_M_AB_CPU1_FPGA_N")
		)
		(pad "208" smd rect
			(at 2.050034 -9.774936 270)
			(size 0.519938 1.4986)
			(layers "F.Cu" "F.Mask" "F.Paste")
			(net "GND")
		)
		(pad "209" smd rect
			(at 2.050034 -8.925052 270)
			(size 0.519938 1.4986)
			(layers "F.Cu" "F.Mask" "F.Paste")
			(net "M_A_CPU1_SA_CS_N<1>")
		)
		(pad "210" smd rect
			(at 2.050034 -8.074914 270)
			(size 0.519938 1.4986)
			(layers "F.Cu" "F.Mask" "F.Paste")
			(net "GND")
		)
		(pad "211" smd rect
			(at 2.050034 -7.22503 270)
			(size 0.519938 1.4986)
			(layers "F.Cu" "F.Mask" "F.Paste")
			(net "M_A_CPU1_SA_CA<1>")
		)
		(pad "212" smd rect
			(at 2.050034 -6.374892 270)
			(size 0.519938 1.4986)
			(layers "F.Cu" "F.Mask" "F.Paste")
			(net "GND")
		)
		(pad "213" smd rect
			(at 2.050034 -5.525008 270)
			(size 0.519938 1.4986)
			(layers "F.Cu" "F.Mask" "F.Paste")
			(net "M_A_CPU1_SA_CA<3>")
		)
		(pad "214" smd rect
			(at 2.050034 -4.675124 270)
			(size 0.519938 1.4986)
			(layers "F.Cu" "F.Mask" "F.Paste")
			(net "GND")
		)
		(pad "215" smd rect
			(at 2.050034 -3.824986 270)
			(size 0.519938 1.4986)
			(layers "F.Cu" "F.Mask" "F.Paste")
			(net "M_A_CPU1_SA_CA<5>")
		)
		(pad "216" smd rect
			(at 2.050034 -2.975102 270)
			(size 0.519938 1.4986)
			(layers "F.Cu" "F.Mask" "F.Paste")
			(net "GND")
		)
		(pad "217" smd rect
			(at 2.050034 -2.124964 270)
			(size 0.519938 1.4986)
			(layers "F.Cu" "F.Mask" "F.Paste")
			(net "M_A_CPU1_CLK_DP<0>")
		)
		(pad "218" smd rect
			(at 2.050034 -1.27508 270)
			(size 0.519938 1.4986)
			(layers "F.Cu" "F.Mask" "F.Paste")
			(net "M_A_CPU1_CLK_DN<0>")
		)
		(pad "219" smd rect
			(at 2.050034 -0.424942 270)
			(size 0.519938 1.4986)
			(layers "F.Cu" "F.Mask" "F.Paste")
			(net "GND")
		)
		(pad "220" smd rect
			(at 2.050034 5.525008 270)
			(size 0.519938 1.4986)
			(layers "F.Cu" "F.Mask" "F.Paste")
			(net "TP_CHA_CPU1_DIMM1_FRU_4")
		)
		(pad "221" smd rect
			(at 2.050034 6.374892 270)
			(size 0.519938 1.4986)
			(layers "F.Cu" "F.Mask" "F.Paste")
			(net "M_A_CPU1_SB_CA<1>")
		)
		(pad "222" smd rect
			(at 2.050034 7.22503 270)
			(size 0.519938 1.4986)
			(layers "F.Cu" "F.Mask" "F.Paste")
			(net "GND")
		)
		(pad "223" smd rect
			(at 2.050034 8.074914 270)
			(size 0.519938 1.4986)
			(layers "F.Cu" "F.Mask" "F.Paste")
			(net "M_A_CPU1_SB_CA<3>")
		)
		(pad "224" smd rect
			(at 2.050034 8.925052 270)
			(size 0.519938 1.4986)
			(layers "F.Cu" "F.Mask" "F.Paste")
			(net "GND")
		)
		(pad "225" smd rect
			(at 2.050034 9.774936 270)
			(size 0.519938 1.4986)
			(layers "F.Cu" "F.Mask" "F.Paste")
			(net "M_A_CPU1_SB_CA<5>")
		)
		(pad "226" smd rect
			(at 2.050034 10.625074 270)
			(size 0.519938 1.4986)
			(layers "F.Cu" "F.Mask" "F.Paste")
			(net "GND")
		)
		(pad "227" smd rect
			(at 2.050034 11.474958 270)
			(size 0.519938 1.4986)
			(layers "F.Cu" "F.Mask" "F.Paste")
			(net "M_A_CPU1_SB_PAR")
		)
		(pad "228" smd rect
			(at 2.050034 12.325096 270)
			(size 0.519938 1.4986)
			(layers "F.Cu" "F.Mask" "F.Paste")
			(net "GND")
		)
		(pad "229" smd rect
			(at 2.050034 13.17498 270)
			(size 0.519938 1.4986)
			(layers "F.Cu" "F.Mask" "F.Paste")
			(net "M_A_CPU1_SB_CS_N<1>")
		)
		(pad "230" smd rect
			(at 2.050034 14.025118 270)
			(size 0.519938 1.4986)
			(layers "F.Cu" "F.Mask" "F.Paste")
			(net "GND")
		)
		(pad "231" smd rect
			(at 2.050034 14.875002 270)
			(size 0.519938 1.4986)
			(layers "F.Cu" "F.Mask" "F.Paste")
			(net "TP_CHA_CPU1_DIMM1_FRU_5")
		)
		(pad "232" smd rect
			(at 2.050034 15.724886 270)
			(size 0.519938 1.4986)
			(layers "F.Cu" "F.Mask" "F.Paste")
			(net "TP_CHA_CPU1_DIMM1_FRU_6")
		)
		(pad "233" smd rect
			(at 2.050034 16.575024 270)
			(size 0.519938 1.4986)
			(layers "F.Cu" "F.Mask" "F.Paste")
			(net "GND")
		)
		(pad "234" smd rect
			(at 2.050034 17.424908 270)
			(size 0.519938 1.4986)
			(layers "F.Cu" "F.Mask" "F.Paste")
			(net "M_A_CPU1_SB_CB<6>")
		)
		(pad "235" smd rect
			(at 2.050034 18.275046 270)
			(size 0.519938 1.4986)
			(layers "F.Cu" "F.Mask" "F.Paste")
			(net "GND")
		)
		(pad "236" smd rect
			(at 2.050034 19.12493 270)
			(size 0.519938 1.4986)
			(layers "F.Cu" "F.Mask" "F.Paste")
			(net "M_A_CPU1_SB_CB<7>")
		)
		(pad "237" smd rect
			(at 2.050034 19.975068 270)
			(size 0.519938 1.4986)
			(layers "F.Cu" "F.Mask" "F.Paste")
			(net "GND")
		)
		(pad "238" smd rect
			(at 2.050034 20.824952 270)
			(size 0.519938 1.4986)
			(layers "F.Cu" "F.Mask" "F.Paste")
			(net "M_A_CPU1_SB_DQS_DN<4>")
		)
		(pad "239" smd rect
			(at 2.050034 21.67509 270)
			(size 0.519938 1.4986)
			(layers "F.Cu" "F.Mask" "F.Paste")
			(net "M_A_CPU1_SB_DQS_DP<4>")
		)
		(pad "240" smd rect
			(at 2.050034 22.524974 270)
			(size 0.519938 1.4986)
			(layers "F.Cu" "F.Mask" "F.Paste")
			(net "GND")
		)
		(pad "241" smd rect
			(at 2.050034 23.375112 270)
			(size 0.519938 1.4986)
			(layers "F.Cu" "F.Mask" "F.Paste")
			(net "M_A_CPU1_SB_CB<2>")
		)
		(pad "242" smd rect
			(at 2.050034 24.224996 270)
			(size 0.519938 1.4986)
			(layers "F.Cu" "F.Mask" "F.Paste")
			(net "GND")
		)
		(pad "243" smd rect
			(at 2.050034 25.07488 270)
			(size 0.519938 1.4986)
			(layers "F.Cu" "F.Mask" "F.Paste")
			(net "M_A_CPU1_SB_CB<3>")
		)
		(pad "244" smd rect
			(at 2.050034 25.925018 270)
			(size 0.519938 1.4986)
			(layers "F.Cu" "F.Mask" "F.Paste")
			(net "GND")
		)
		(pad "245" smd rect
			(at 2.050034 26.774902 270)
			(size 0.519938 1.4986)
			(layers "F.Cu" "F.Mask" "F.Paste")
			(net "M_A_CPU1_SB_DQ<2>")
		)
		(pad "246" smd rect
			(at 2.050034 27.62504 270)
			(size 0.519938 1.4986)
			(layers "F.Cu" "F.Mask" "F.Paste")
			(net "GND")
		)
		(pad "247" smd rect
			(at 2.050034 28.474924 270)
			(size 0.519938 1.4986)
			(layers "F.Cu" "F.Mask" "F.Paste")
			(net "M_A_CPU1_SB_DQ<3>")
		)
		(pad "248" smd rect
			(at 2.050034 29.325062 270)
			(size 0.519938 1.4986)
			(layers "F.Cu" "F.Mask" "F.Paste")
			(net "GND")
		)
		(pad "249" smd rect
			(at 2.050034 30.174946 270)
			(size 0.519938 1.4986)
			(layers "F.Cu" "F.Mask" "F.Paste")
			(net "M_A_CPU1_SB_DQS_DN<5>")
		)
		(pad "250" smd rect
			(at 2.050034 31.025084 270)
			(size 0.519938 1.4986)
			(layers "F.Cu" "F.Mask" "F.Paste")
			(net "M_A_CPU1_SB_DQS_DP<5>")
		)
		(pad "251" smd rect
			(at 2.050034 31.874968 270)
			(size 0.519938 1.4986)
			(layers "F.Cu" "F.Mask" "F.Paste")
			(net "GND")
		)
		(pad "252" smd rect
			(at 2.050034 32.725106 270)
			(size 0.519938 1.4986)
			(layers "F.Cu" "F.Mask" "F.Paste")
			(net "M_A_CPU1_SB_DQ<6>")
		)
		(pad "253" smd rect
			(at 2.050034 33.57499 270)
			(size 0.519938 1.4986)
			(layers "F.Cu" "F.Mask" "F.Paste")
			(net "GND")
		)
		(pad "254" smd rect
			(at 2.050034 34.425128 270)
			(size 0.519938 1.4986)
			(layers "F.Cu" "F.Mask" "F.Paste")
			(net "M_A_CPU1_SB_DQ<7>")
		)
		(pad "255" smd rect
			(at 2.050034 35.275012 270)
			(size 0.519938 1.4986)
			(layers "F.Cu" "F.Mask" "F.Paste")
			(net "GND")
		)
		(pad "256" smd rect
			(at 2.050034 36.124896 270)
			(size 0.519938 1.4986)
			(layers "F.Cu" "F.Mask" "F.Paste")
			(net "M_A_CPU1_SB_DQ<10>")
		)
		(pad "257" smd rect
			(at 2.050034 36.975034 270)
			(size 0.519938 1.4986)
			(layers "F.Cu" "F.Mask" "F.Paste")
			(net "GND")
		)
		(pad "258" smd rect
			(at 2.050034 37.824918 270)
			(size 0.519938 1.4986)
			(layers "F.Cu" "F.Mask" "F.Paste")
			(net "M_A_CPU1_SB_DQ<11>")
		)
		(pad "259" smd rect
			(at 2.050034 38.675056 270)
			(size 0.519938 1.4986)
			(layers "F.Cu" "F.Mask" "F.Paste")
			(net "GND")
		)
		(pad "260" smd rect
			(at 2.050034 39.52494 270)
			(size 0.519938 1.4986)
			(layers "F.Cu" "F.Mask" "F.Paste")
			(net "M_A_CPU1_SB_DQS_DN<6>")
		)
		(pad "261" smd rect
			(at 2.050034 40.375078 270)
			(size 0.519938 1.4986)
			(layers "F.Cu" "F.Mask" "F.Paste")
			(net "M_A_CPU1_SB_DQS_DP<6>")
		)
		(pad "262" smd rect
			(at 2.050034 41.224962 270)
			(size 0.519938 1.4986)
			(layers "F.Cu" "F.Mask" "F.Paste")
			(net "GND")
		)
		(pad "263" smd rect
			(at 2.050034 42.0751 270)
			(size 0.519938 1.4986)
			(layers "F.Cu" "F.Mask" "F.Paste")
			(net "M_A_CPU1_SB_DQ<14>")
		)
		(pad "264" smd rect
			(at 2.050034 42.924984 270)
			(size 0.519938 1.4986)
			(layers "F.Cu" "F.Mask" "F.Paste")
			(net "GND")
		)
		(pad "265" smd rect
			(at 2.050034 43.775122 270)
			(size 0.519938 1.4986)
			(layers "F.Cu" "F.Mask" "F.Paste")
			(net "M_A_CPU1_SB_DQ<15>")
		)
		(pad "266" smd rect
			(at 2.050034 44.625006 270)
			(size 0.519938 1.4986)
			(layers "F.Cu" "F.Mask" "F.Paste")
			(net "GND")
		)
		(pad "267" smd rect
			(at 2.050034 45.47489 270)
			(size 0.519938 1.4986)
			(layers "F.Cu" "F.Mask" "F.Paste")
			(net "M_A_CPU1_SB_DQ<18>")
		)
		(pad "268" smd rect
			(at 2.050034 46.325028 270)
			(size 0.519938 1.4986)
			(layers "F.Cu" "F.Mask" "F.Paste")
			(net "GND")
		)
		(pad "269" smd rect
			(at 2.050034 47.174912 270)
			(size 0.519938 1.4986)
			(layers "F.Cu" "F.Mask" "F.Paste")
			(net "M_A_CPU1_SB_DQ<19>")
		)
		(pad "270" smd rect
			(at 2.050034 48.02505 270)
			(size 0.519938 1.4986)
			(layers "F.Cu" "F.Mask" "F.Paste")
			(net "GND")
		)
		(pad "271" smd rect
			(at 2.050034 48.874934 270)
			(size 0.519938 1.4986)
			(layers "F.Cu" "F.Mask" "F.Paste")
			(net "M_A_CPU1_SB_DQS_DN<7>")
		)
		(pad "272" smd rect
			(at 2.050034 49.725072 270)
			(size 0.519938 1.4986)
			(layers "F.Cu" "F.Mask" "F.Paste")
			(net "M_A_CPU1_SB_DQS_DP<7>")
		)
		(pad "273" smd rect
			(at 2.050034 50.574956 270)
			(size 0.519938 1.4986)
			(layers "F.Cu" "F.Mask" "F.Paste")
			(net "GND")
		)
		(pad "274" smd rect
			(at 2.050034 51.425094 270)
			(size 0.519938 1.4986)
			(layers "F.Cu" "F.Mask" "F.Paste")
			(net "M_A_CPU1_SB_DQ<22>")
		)
		(pad "275" smd rect
			(at 2.050034 52.274978 270)
			(size 0.519938 1.4986)
			(layers "F.Cu" "F.Mask" "F.Paste")
			(net "GND")
		)
		(pad "276" smd rect
			(at 2.050034 53.125116 270)
			(size 0.519938 1.4986)
			(layers "F.Cu" "F.Mask" "F.Paste")
			(net "M_A_CPU1_SB_DQ<23>")
		)
		(pad "277" smd rect
			(at 2.050034 53.975 270)
			(size 0.519938 1.4986)
			(layers "F.Cu" "F.Mask" "F.Paste")
			(net "GND")
		)
		(pad "278" smd rect
			(at 2.050034 54.824884 270)
			(size 0.519938 1.4986)
			(layers "F.Cu" "F.Mask" "F.Paste")
			(net "M_A_CPU1_SB_DQ<26>")
		)
		(pad "279" smd rect
			(at 2.050034 55.675022 270)
			(size 0.519938 1.4986)
			(layers "F.Cu" "F.Mask" "F.Paste")
			(net "GND")
		)
		(pad "280" smd rect
			(at 2.050034 56.524906 270)
			(size 0.519938 1.4986)
			(layers "F.Cu" "F.Mask" "F.Paste")
			(net "M_A_CPU1_SB_DQ<27>")
		)
		(pad "281" smd rect
			(at 2.050034 57.375044 270)
			(size 0.519938 1.4986)
			(layers "F.Cu" "F.Mask" "F.Paste")
			(net "GND")
		)
		(pad "282" smd rect
			(at 2.050034 58.224928 270)
			(size 0.519938 1.4986)
			(layers "F.Cu" "F.Mask" "F.Paste")
			(net "M_A_CPU1_SB_DQS_DN<8>")
		)
		(pad "283" smd rect
			(at 2.050034 59.075066 270)
			(size 0.519938 1.4986)
			(layers "F.Cu" "F.Mask" "F.Paste")
			(net "M_A_CPU1_SB_DQS_DP<8>")
		)
		(pad "284" smd rect
			(at 2.050034 59.92495 270)
			(size 0.519938 1.4986)
			(layers "F.Cu" "F.Mask" "F.Paste")
			(net "GND")
		)
		(pad "285" smd rect
			(at 2.050034 60.775088 270)
			(size 0.519938 1.4986)
			(layers "F.Cu" "F.Mask" "F.Paste")
			(net "M_A_CPU1_SB_DQ<30>")
		)
		(pad "286" smd rect
			(at 2.050034 61.624972 270)
			(size 0.519938 1.4986)
			(layers "F.Cu" "F.Mask" "F.Paste")
			(net "GND")
		)
		(pad "287" smd rect
			(at 2.050034 62.47511 270)
			(size 0.519938 1.4986)
			(layers "F.Cu" "F.Mask" "F.Paste")
			(net "M_A_CPU1_SB_DQ<31>")
		)
		(pad "288" smd rect
			(at 2.050034 63.324994 270)
			(size 0.519938 1.4986)
			(layers "F.Cu" "F.Mask" "F.Paste")
			(net "GND")
		)
		(pad "G1" thru_hole oval
			(at 0 -68.97497)
			(size 2.8194 1.5748)
			(drill oval 2.4384 1.1938)
			(layers "*.Cu" "*.Mask")
			(remove_unused_layers no)
			(net "GND")
			(clearance 0.127)
			(thermal_gap 0.127)
		)
		(pad "G2" thru_hole oval
			(at 0 3.875024)
			(size 2.8194 1.5748)
			(drill oval 2.4384 1.1938)
			(layers "*.Cu" "*.Mask")
			(remove_unused_layers no)
			(net "GND")
			(clearance 0.127)
			(thermal_gap 0.127)
		)
		(pad "G3" thru_hole oval
			(at 0 68.97497)
			(size 2.8194 1.5748)
			(drill oval 2.4384 1.1938)
			(layers "*.Cu" "*.Mask")
			(remove_unused_layers no)
			(net "GND")
			(clearance 0.127)
			(thermal_gap 0.127)
		)
	)
	(footprint ""
		(layer "F.Cu")
		(at 348.606364 -358.906826)
		(property "Reference" "R2375"
			(at 0 0 0)
			(layer "F.SilkS")
			(hide yes)
			(effects
				(font
					(size 1.27 1.27)
				)
			)
		)
		(property "Value" ""
			(at 0 0 0)
			(layer "F.Fab")
			(effects
				(font
					(size 1.27 1.27)
				)
			)
		)
		(duplicate_pad_numbers_are_jumpers no)
		(fp_line
			(start -0.7874 -0.4064)
			(end 0.7874 -0.4064)
			(stroke
				(width 0.1524)
				(type default)
			)
			(layer "F.SilkS")
		)
		(fp_line
			(start -0.7874 0.4064)
			(end -0.7874 -0.4064)
			(stroke
				(width 0.1524)
				(type default)
			)
			(layer "F.SilkS")
		)
		(fp_line
			(start 0.7874 -0.4064)
			(end 0.7874 0.4064)
			(stroke
				(width 0.1524)
				(type default)
			)
			(layer "F.SilkS")
		)
		(fp_line
			(start 0.7874 0.4064)
			(end -0.7874 0.4064)
			(stroke
				(width 0.1524)
				(type default)
			)
			(layer "F.SilkS")
		)
		(fp_line
			(start -0.67945 -0.305054)
			(end -0.12065 -0.305054)
			(stroke
				(width 0.1)
				(type default)
			)
			(layer "F.Fab")
		)
		(fp_line
			(start -0.67945 0.3048)
			(end -0.67945 -0.305054)
			(stroke
				(width 0.1)
				(type default)
			)
			(layer "F.Fab")
		)
		(fp_line
			(start -0.12065 -0.305054)
			(end -0.12065 -0.2794)
			(stroke
				(width 0.1)
				(type default)
			)
			(layer "F.Fab")
		)
		(fp_line
			(start -0.12065 -0.2794)
			(end 0.12065 -0.2794)
			(stroke
				(width 0.1)
				(type default)
			)
			(layer "F.Fab")
		)
		(fp_line
			(start -0.12065 0.2794)
			(end -0.12065 0.3048)
			(stroke
				(width 0.1)
				(type default)
			)
			(layer "F.Fab")
		)
		(fp_line
			(start -0.12065 0.3048)
			(end -0.67945 0.3048)
			(stroke
				(width 0.1)
				(type default)
			)
			(layer "F.Fab")
		)
		(fp_line
			(start 0.120396 0.2794)
			(end -0.12065 0.2794)
			(stroke
				(width 0.1)
				(type default)
			)
			(layer "F.Fab")
		)
		(fp_line
			(start 0.120396 0.3048)
			(end 0.120396 0.2794)
			(stroke
				(width 0.1)
				(type default)
			)
			(layer "F.Fab")
		)
		(fp_line
			(start 0.12065 -0.3048)
			(end 0.67945 -0.3048)
			(stroke
				(width 0.1)
				(type default)
			)
			(layer "F.Fab")
		)
		(fp_line
			(start 0.12065 -0.2794)
			(end 0.12065 -0.3048)
			(stroke
				(width 0.1)
				(type default)
			)
			(layer "F.Fab")
		)
		(fp_line
			(start 0.67945 -0.3048)
			(end 0.67945 0.3048)
			(stroke
				(width 0.1)
				(type default)
			)
			(layer "F.Fab")
		)
		(fp_line
			(start 0.67945 0.3048)
			(end 0.120396 0.3048)
			(stroke
				(width 0.1)
				(type default)
			)
			(layer "F.Fab")
		)
		(pad "1" smd circle
			(at -0.40005 0)
			(size 0 0)
			(layers "F.Cu" "F.Mask" "F.Paste")
			(net "P3V3_AUX")
		)
		(pad "2" smd circle
			(at 0.40005 0)
			(size 0 0)
			(layers "F.Cu" "F.Mask" "F.Paste")
			(net "PVCCIN_CPU0_PIN_ALERT")
		)
	)
	(footprint ""
		(layer "F.Cu")
		(at 107.019598 -15.91691)
		(property "Reference" "R3553"
			(at 0 0 0)
			(layer "F.SilkS")
			(hide yes)
			(effects
				(font
					(size 1.27 1.27)
				)
			)
		)
		(property "Value" ""
			(at 0 0 0)
			(layer "F.Fab")
			(effects
				(font
					(size 1.27 1.27)
				)
			)
		)
		(duplicate_pad_numbers_are_jumpers no)
		(fp_line
			(start -0.7874 -0.4064)
			(end 0.7874 -0.4064)
			(stroke
				(width 0.1524)
				(type default)
			)
			(layer "F.SilkS")
		)
		(fp_line
			(start -0.7874 0.4064)
			(end -0.7874 -0.4064)
			(stroke
				(width 0.1524)
				(type default)
			)
			(layer "F.SilkS")
		)
		(fp_line
			(start 0.7874 -0.4064)
			(end 0.7874 0.4064)
			(stroke
				(width 0.1524)
				(type default)
			)
			(layer "F.SilkS")
		)
		(fp_line
			(start 0.7874 0.4064)
			(end -0.7874 0.4064)
			(stroke
				(width 0.1524)
				(type default)
			)
			(layer "F.SilkS")
		)
		(fp_line
			(start -0.67945 -0.305054)
			(end -0.12065 -0.305054)
			(stroke
				(width 0.1)
				(type default)
			)
			(layer "F.Fab")
		)
		(fp_line
			(start -0.67945 0.3048)
			(end -0.67945 -0.305054)
			(stroke
				(width 0.1)
				(type default)
			)
			(layer "F.Fab")
		)
		(fp_line
			(start -0.12065 -0.305054)
			(end -0.12065 -0.2794)
			(stroke
				(width 0.1)
				(type default)
			)
			(layer "F.Fab")
		)
		(fp_line
			(start -0.12065 -0.2794)
			(end 0.12065 -0.2794)
			(stroke
				(width 0.1)
				(type default)
			)
			(layer "F.Fab")
		)
		(fp_line
			(start -0.12065 0.2794)
			(end -0.12065 0.3048)
			(stroke
				(width 0.1)
				(type default)
			)
			(layer "F.Fab")
		)
		(fp_line
			(start -0.12065 0.3048)
			(end -0.67945 0.3048)
			(stroke
				(width 0.1)
				(type default)
			)
			(layer "F.Fab")
		)
		(fp_line
			(start 0.120396 0.2794)
			(end -0.12065 0.2794)
			(stroke
				(width 0.1)
				(type default)
			)
			(layer "F.Fab")
		)
		(fp_line
			(start 0.120396 0.3048)
			(end 0.120396 0.2794)
			(stroke
				(width 0.1)
				(type default)
			)
			(layer "F.Fab")
		)
		(fp_line
			(start 0.12065 -0.3048)
			(end 0.67945 -0.3048)
			(stroke
				(width 0.1)
				(type default)
			)
			(layer "F.Fab")
		)
		(fp_line
			(start 0.12065 -0.2794)
			(end 0.12065 -0.3048)
			(stroke
				(width 0.1)
				(type default)
			)
			(layer "F.Fab")
		)
		(fp_line
			(start 0.67945 -0.3048)
			(end 0.67945 0.3048)
			(stroke
				(width 0.1)
				(type default)
			)
			(layer "F.Fab")
		)
		(fp_line
			(start 0.67945 0.3048)
			(end 0.120396 0.3048)
			(stroke
				(width 0.1)
				(type default)
			)
			(layer "F.Fab")
		)
		(pad "1" smd circle
			(at -0.40005 0)
			(size 0 0)
			(layers "F.Cu" "F.Mask" "F.Paste")
			(net "SMB_LM75_3_3V3AUX_SCL")
		)
		(pad "2" smd circle
			(at 0.40005 0)
			(size 0 0)
			(layers "F.Cu" "F.Mask" "F.Paste")
			(net "SMB_LM75_3_3V3AUX_SCL_R1")
		)
	)
	(footprint ""
		(layer "F.Cu")
		(at 118.542816 -260.36524 -90)
		(property "Reference" "C442"
			(at 0 0 270)
			(layer "F.SilkS")
			(hide yes)
			(effects
				(font
					(size 1.27 1.27)
				)
			)
		)
		(property "Value" ""
			(at 0 0 270)
			(layer "F.Fab")
			(effects
				(font
					(size 1.27 1.27)
				)
			)
		)
		(duplicate_pad_numbers_are_jumpers no)
		(fp_line
			(start -0.7874 0.4064)
			(end -0.7874 -0.4064)
			(stroke
				(width 0.1524)
				(type default)
			)
			(layer "F.SilkS")
		)
		(fp_line
			(start 0.7874 0.4064)
			(end -0.7874 0.4064)
			(stroke
				(width 0.1524)
				(type default)
			)
			(layer "F.SilkS")
		)
		(fp_line
			(start -0.7874 -0.4064)
			(end 0.7874 -0.4064)
			(stroke
				(width 0.1524)
				(type default)
			)
			(layer "F.SilkS")
		)
		(fp_line
			(start 0.7874 -0.4064)
			(end 0.7874 0.4064)
			(stroke
				(width 0.1524)
				(type default)
			)
			(layer "F.SilkS")
		)
		(fp_line
			(start -0.67945 0.3048)
			(end -0.67945 -0.305054)
			(stroke
				(width 0.1)
				(type default)
			)
			(layer "F.Fab")
		)
		(fp_line
			(start -0.12065 0.3048)
			(end -0.67945 0.3048)
			(stroke
				(width 0.1)
				(type default)
			)
			(layer "F.Fab")
		)
		(fp_line
			(start 0.120396 0.3048)
			(end 0.120396 0.2794)
			(stroke
				(width 0.1)
				(type default)
			)
			(layer "F.Fab")
		)
		(fp_line
			(start 0.67945 0.3048)
			(end 0.120396 0.3048)
			(stroke
				(width 0.1)
				(type default)
			)
			(layer "F.Fab")
		)
		(fp_line
			(start -0.12065 0.2794)
			(end -0.12065 0.3048)
			(stroke
				(width 0.1)
				(type default)
			)
			(layer "F.Fab")
		)
		(fp_line
			(start 0.120396 0.2794)
			(end -0.12065 0.2794)
			(stroke
				(width 0.1)
				(type default)
			)
			(layer "F.Fab")
		)
		(fp_line
			(start -0.12065 -0.2794)
			(end 0.12065 -0.2794)
			(stroke
				(width 0.1)
				(type default)
			)
			(layer "F.Fab")
		)
		(fp_line
			(start 0.12065 -0.2794)
			(end 0.12065 -0.3048)
			(stroke
				(width 0.1)
				(type default)
			)
			(layer "F.Fab")
		)
		(fp_line
			(start 0.12065 -0.3048)
			(end 0.67945 -0.3048)
			(stroke
				(width 0.1)
				(type default)
			)
			(layer "F.Fab")
		)
		(fp_line
			(start 0.67945 -0.3048)
			(end 0.67945 0.3048)
			(stroke
				(width 0.1)
				(type default)
			)
			(layer "F.Fab")
		)
		(fp_line
			(start -0.67945 -0.305054)
			(end -0.12065 -0.305054)
			(stroke
				(width 0.1)
				(type default)
			)
			(layer "F.Fab")
		)
		(fp_line
			(start -0.12065 -0.305054)
			(end -0.12065 -0.2794)
			(stroke
				(width 0.1)
				(type default)
			)
			(layer "F.Fab")
		)
		(pad "1" smd circle
			(at -0.40005 0 270)
			(size 0 0)
			(layers "F.Cu" "F.Mask" "F.Paste")
			(net "PVCCFA_EHV_FIVRA_CPU1")
		)
		(pad "2" smd circle
			(at 0.40005 0 270)
			(size 0 0)
			(layers "F.Cu" "F.Mask" "F.Paste")
			(net "GND")
		)
	)
	(footprint ""
		(layer "F.Cu")
		(at 180.074062 -32.935672 -90)
		(property "Reference" "R3998"
			(at 0 0 270)
			(layer "F.SilkS")
			(hide yes)
			(effects
				(font
					(size 1.27 1.27)
				)
			)
		)
		(property "Value" ""
			(at 0 0 270)
			(layer "F.Fab")
			(effects
				(font
					(size 1.27 1.27)
				)
			)
		)
		(duplicate_pad_numbers_are_jumpers no)
		(fp_line
			(start -0.7874 0.4064)
			(end -0.7874 -0.4064)
			(stroke
				(width 0.1524)
				(type default)
			)
			(layer "F.SilkS")
		)
		(fp_line
			(start 0.7874 0.4064)
			(end -0.7874 0.4064)
			(stroke
				(width 0.1524)
				(type default)
			)
			(layer "F.SilkS")
		)
		(fp_line
			(start -0.7874 -0.4064)
			(end 0.7874 -0.4064)
			(stroke
				(width 0.1524)
				(type default)
			)
			(layer "F.SilkS")
		)
		(fp_line
			(start 0.7874 -0.4064)
			(end 0.7874 0.4064)
			(stroke
				(width 0.1524)
				(type default)
			)
			(layer "F.SilkS")
		)
		(fp_line
			(start -0.67945 0.3048)
			(end -0.67945 -0.305054)
			(stroke
				(width 0.1)
				(type default)
			)
			(layer "F.Fab")
		)
		(fp_line
			(start -0.12065 0.3048)
			(end -0.67945 0.3048)
			(stroke
				(width 0.1)
				(type default)
			)
			(layer "F.Fab")
		)
		(fp_line
			(start 0.120396 0.3048)
			(end 0.120396 0.2794)
			(stroke
				(width 0.1)
				(type default)
			)
			(layer "F.Fab")
		)
		(fp_line
			(start 0.67945 0.3048)
			(end 0.120396 0.3048)
			(stroke
				(width 0.1)
				(type default)
			)
			(layer "F.Fab")
		)
		(fp_line
			(start -0.12065 0.2794)
			(end -0.12065 0.3048)
			(stroke
				(width 0.1)
				(type default)
			)
			(layer "F.Fab")
		)
		(fp_line
			(start 0.120396 0.2794)
			(end -0.12065 0.2794)
			(stroke
				(width 0.1)
				(type default)
			)
			(layer "F.Fab")
		)
		(fp_line
			(start -0.12065 -0.2794)
			(end 0.12065 -0.2794)
			(stroke
				(width 0.1)
				(type default)
			)
			(layer "F.Fab")
		)
		(fp_line
			(start 0.12065 -0.2794)
			(end 0.12065 -0.3048)
			(stroke
				(width 0.1)
				(type default)
			)
			(layer "F.Fab")
		)
		(fp_line
			(start 0.12065 -0.3048)
			(end 0.67945 -0.3048)
			(stroke
				(width 0.1)
				(type default)
			)
			(layer "F.Fab")
		)
		(fp_line
			(start 0.67945 -0.3048)
			(end 0.67945 0.3048)
			(stroke
				(width 0.1)
				(type default)
			)
			(layer "F.Fab")
		)
		(fp_line
			(start -0.67945 -0.305054)
			(end -0.12065 -0.305054)
			(stroke
				(width 0.1)
				(type default)
			)
			(layer "F.Fab")
		)
		(fp_line
			(start -0.12065 -0.305054)
			(end -0.12065 -0.2794)
			(stroke
				(width 0.1)
				(type default)
			)
			(layer "F.Fab")
		)
		(pad "1" smd circle
			(at -0.40005 0 270)
			(size 0 0)
			(layers "F.Cu" "F.Mask" "F.Paste")
			(net "P12V_SCM_EN")
		)
		(pad "2" smd circle
			(at 0.40005 0 270)
			(size 0 0)
			(layers "F.Cu" "F.Mask" "F.Paste")
			(net "P12V_SCM_EN_R2")
		)
	)
	(footprint ""
		(layer "F.Cu")
		(at 348.404942 -355.359462 180)
		(property "Reference" "R2382"
			(at 0 0 180)
			(layer "F.SilkS")
			(hide yes)
			(effects
				(font
					(size 1.27 1.27)
				)
			)
		)
		(property "Value" ""
			(at 0 0 180)
			(layer "F.Fab")
			(effects
				(font
					(size 1.27 1.27)
				)
			)
		)
		(duplicate_pad_numbers_are_jumpers no)
		(fp_line
			(start 0.7874 0.4064)
			(end -0.7874 0.4064)
			(stroke
				(width 0.1524)
				(type default)
			)
			(layer "F.SilkS")
		)
		(fp_line
			(start 0.7874 -0.4064)
			(end 0.7874 0.4064)
			(stroke
				(width 0.1524)
				(type default)
			)
			(layer "F.SilkS")
		)
		(fp_line
			(start -0.7874 0.4064)
			(end -0.7874 -0.4064)
			(stroke
				(width 0.1524)
				(type default)
			)
			(layer "F.SilkS")
		)
		(fp_line
			(start -0.7874 -0.4064)
			(end 0.7874 -0.4064)
			(stroke
				(width 0.1524)
				(type default)
			)
			(layer "F.SilkS")
		)
		(fp_line
			(start 0.67945 0.3048)
			(end 0.120396 0.3048)
			(stroke
				(width 0.1)
				(type default)
			)
			(layer "F.Fab")
		)
		(fp_line
			(start 0.67945 -0.3048)
			(end 0.67945 0.3048)
			(stroke
				(width 0.1)
				(type default)
			)
			(layer "F.Fab")
		)
		(fp_line
			(start 0.12065 -0.2794)
			(end 0.12065 -0.3048)
			(stroke
				(width 0.1)
				(type default)
			)
			(layer "F.Fab")
		)
		(fp_line
			(start 0.12065 -0.3048)
			(end 0.67945 -0.3048)
			(stroke
				(width 0.1)
				(type default)
			)
			(layer "F.Fab")
		)
		(fp_line
			(start 0.120396 0.3048)
			(end 0.120396 0.2794)
			(stroke
				(width 0.1)
				(type default)
			)
			(layer "F.Fab")
		)
		(fp_line
			(start 0.120396 0.2794)
			(end -0.12065 0.2794)
			(stroke
				(width 0.1)
				(type default)
			)
			(layer "F.Fab")
		)
		(fp_line
			(start -0.12065 0.3048)
			(end -0.67945 0.3048)
			(stroke
				(width 0.1)
				(type default)
			)
			(layer "F.Fab")
		)
		(fp_line
			(start -0.12065 0.2794)
			(end -0.12065 0.3048)
			(stroke
				(width 0.1)
				(type default)
			)
			(layer "F.Fab")
		)
		(fp_line
			(start -0.12065 -0.2794)
			(end 0.12065 -0.2794)
			(stroke
				(width 0.1)
				(type default)
			)
			(layer "F.Fab")
		)
		(fp_line
			(start -0.12065 -0.305054)
			(end -0.12065 -0.2794)
			(stroke
				(width 0.1)
				(type default)
			)
			(layer "F.Fab")
		)
		(fp_line
			(start -0.67945 0.3048)
			(end -0.67945 -0.305054)
			(stroke
				(width 0.1)
				(type default)
			)
			(layer "F.Fab")
		)
		(fp_line
			(start -0.67945 -0.305054)
			(end -0.12065 -0.305054)
			(stroke
				(width 0.1)
				(type default)
			)
			(layer "F.Fab")
		)
		(pad "1" smd circle
			(at -0.40005 0 180)
			(size 0 0)
			(layers "F.Cu" "F.Mask" "F.Paste")
			(net "SVID_ALERT0_CPU0_R_N")
		)
		(pad "2" smd circle
			(at 0.40005 0 180)
			(size 0 0)
			(layers "F.Cu" "F.Mask" "F.Paste")
			(net "PVNN_TERM_CPU0")
		)
	)
	(footprint ""
		(layer "F.Cu")
		(at 432.680618 -183.64327 180)
		(property "Reference" "PC2221"
			(at 0 0 180)
			(layer "F.SilkS")
			(hide yes)
			(effects
				(font
					(size 1.27 1.27)
				)
			)
		)
		(property "Value" ""
			(at 0 0 180)
			(layer "F.Fab")
			(effects
				(font
					(size 1.27 1.27)
				)
			)
		)
		(duplicate_pad_numbers_are_jumpers no)
		(fp_line
			(start 0.7874 0.4064)
			(end -0.7874 0.4064)
			(stroke
				(width 0.1524)
				(type default)
			)
			(layer "F.SilkS")
		)
		(fp_line
			(start 0.7874 -0.4064)
			(end 0.7874 0.4064)
			(stroke
				(width 0.1524)
				(type default)
			)
			(layer "F.SilkS")
		)
		(fp_line
			(start -0.7874 0.4064)
			(end -0.7874 -0.4064)
			(stroke
				(width 0.1524)
				(type default)
			)
			(layer "F.SilkS")
		)
		(fp_line
			(start -0.7874 -0.4064)
			(end 0.7874 -0.4064)
			(stroke
				(width 0.1524)
				(type default)
			)
			(layer "F.SilkS")
		)
		(fp_line
			(start 0.67945 0.3048)
			(end 0.120396 0.3048)
			(stroke
				(width 0.1)
				(type default)
			)
			(layer "F.Fab")
		)
		(fp_line
			(start 0.67945 -0.3048)
			(end 0.67945 0.3048)
			(stroke
				(width 0.1)
				(type default)
			)
			(layer "F.Fab")
		)
		(fp_line
			(start 0.12065 -0.2794)
			(end 0.12065 -0.3048)
			(stroke
				(width 0.1)
				(type default)
			)
			(layer "F.Fab")
		)
		(fp_line
			(start 0.12065 -0.3048)
			(end 0.67945 -0.3048)
			(stroke
				(width 0.1)
				(type default)
			)
			(layer "F.Fab")
		)
		(fp_line
			(start 0.120396 0.3048)
			(end 0.120396 0.2794)
			(stroke
				(width 0.1)
				(type default)
			)
			(layer "F.Fab")
		)
		(fp_line
			(start 0.120396 0.2794)
			(end -0.12065 0.2794)
			(stroke
				(width 0.1)
				(type default)
			)
			(layer "F.Fab")
		)
		(fp_line
			(start -0.12065 0.3048)
			(end -0.67945 0.3048)
			(stroke
				(width 0.1)
				(type default)
			)
			(layer "F.Fab")
		)
		(fp_line
			(start -0.12065 0.2794)
			(end -0.12065 0.3048)
			(stroke
				(width 0.1)
				(type default)
			)
			(layer "F.Fab")
		)
		(fp_line
			(start -0.12065 -0.2794)
			(end 0.12065 -0.2794)
			(stroke
				(width 0.1)
				(type default)
			)
			(layer "F.Fab")
		)
		(fp_line
			(start -0.12065 -0.305054)
			(end -0.12065 -0.2794)
			(stroke
				(width 0.1)
				(type default)
			)
			(layer "F.Fab")
		)
		(fp_line
			(start -0.67945 0.3048)
			(end -0.67945 -0.305054)
			(stroke
				(width 0.1)
				(type default)
			)
			(layer "F.Fab")
		)
		(fp_line
			(start -0.67945 -0.305054)
			(end -0.12065 -0.305054)
			(stroke
				(width 0.1)
				(type default)
			)
			(layer "F.Fab")
		)
		(pad "1" smd circle
			(at -0.40005 0 180)
			(size 0 0)
			(layers "F.Cu" "F.Mask" "F.Paste")
			(net "PVNN_MAIN_CPU0_VCC")
		)
		(pad "2" smd circle
			(at 0.40005 0 180)
			(size 0 0)
			(layers "F.Cu" "F.Mask" "F.Paste")
			(net "GND")
		)
	)
	(footprint ""
		(layer "F.Cu")
		(at 148.13788 -58.638948 180)
		(property "Reference" "C1323"
			(at 0 0 180)
			(layer "F.SilkS")
			(hide yes)
			(effects
				(font
					(size 1.27 1.27)
				)
			)
		)
		(property "Value" ""
			(at 0 0 180)
			(layer "F.Fab")
			(effects
				(font
					(size 1.27 1.27)
				)
			)
		)
		(duplicate_pad_numbers_are_jumpers no)
		(fp_line
			(start 0.7874 0.4064)
			(end -0.7874 0.4064)
			(stroke
				(width 0.1524)
				(type default)
			)
			(layer "F.SilkS")
		)
		(fp_line
			(start 0.7874 -0.4064)
			(end 0.7874 0.4064)
			(stroke
				(width 0.1524)
				(type default)
			)
			(layer "F.SilkS")
		)
		(fp_line
			(start -0.7874 0.4064)
			(end -0.7874 -0.4064)
			(stroke
				(width 0.1524)
				(type default)
			)
			(layer "F.SilkS")
		)
		(fp_line
			(start -0.7874 -0.4064)
			(end 0.7874 -0.4064)
			(stroke
				(width 0.1524)
				(type default)
			)
			(layer "F.SilkS")
		)
		(fp_line
			(start 0.67945 0.3048)
			(end 0.120396 0.3048)
			(stroke
				(width 0.1)
				(type default)
			)
			(layer "F.Fab")
		)
		(fp_line
			(start 0.67945 -0.3048)
			(end 0.67945 0.3048)
			(stroke
				(width 0.1)
				(type default)
			)
			(layer "F.Fab")
		)
		(fp_line
			(start 0.12065 -0.2794)
			(end 0.12065 -0.3048)
			(stroke
				(width 0.1)
				(type default)
			)
			(layer "F.Fab")
		)
		(fp_line
			(start 0.12065 -0.3048)
			(end 0.67945 -0.3048)
			(stroke
				(width 0.1)
				(type default)
			)
			(layer "F.Fab")
		)
		(fp_line
			(start 0.120396 0.3048)
			(end 0.120396 0.2794)
			(stroke
				(width 0.1)
				(type default)
			)
			(layer "F.Fab")
		)
		(fp_line
			(start 0.120396 0.2794)
			(end -0.12065 0.2794)
			(stroke
				(width 0.1)
				(type default)
			)
			(layer "F.Fab")
		)
		(fp_line
			(start -0.12065 0.3048)
			(end -0.67945 0.3048)
			(stroke
				(width 0.1)
				(type default)
			)
			(layer "F.Fab")
		)
		(fp_line
			(start -0.12065 0.2794)
			(end -0.12065 0.3048)
			(stroke
				(width 0.1)
				(type default)
			)
			(layer "F.Fab")
		)
		(fp_line
			(start -0.12065 -0.2794)
			(end 0.12065 -0.2794)
			(stroke
				(width 0.1)
				(type default)
			)
			(layer "F.Fab")
		)
		(fp_line
			(start -0.12065 -0.305054)
			(end -0.12065 -0.2794)
			(stroke
				(width 0.1)
				(type default)
			)
			(layer "F.Fab")
		)
		(fp_line
			(start -0.67945 0.3048)
			(end -0.67945 -0.305054)
			(stroke
				(width 0.1)
				(type default)
			)
			(layer "F.Fab")
		)
		(fp_line
			(start -0.67945 -0.305054)
			(end -0.12065 -0.305054)
			(stroke
				(width 0.1)
				(type default)
			)
			(layer "F.Fab")
		)
		(pad "1" smd circle
			(at -0.40005 0 180)
			(size 0 0)
			(layers "F.Cu" "F.Mask" "F.Paste")
			(net "P1V8_PCH_AUX")
		)
		(pad "2" smd circle
			(at 0.40005 0 180)
			(size 0 0)
			(layers "F.Cu" "F.Mask" "F.Paste")
			(net "GND")
		)
	)
	(footprint ""
		(layer "F.Cu")
		(at 362.646468 -361.72775)
		(property "Reference" "PC337"
			(at 0 0 0)
			(layer "F.SilkS")
			(hide yes)
			(effects
				(font
					(size 1.27 1.27)
				)
			)
		)
		(property "Value" ""
			(at 0 0 0)
			(layer "F.Fab")
			(effects
				(font
					(size 1.27 1.27)
				)
			)
		)
		(duplicate_pad_numbers_are_jumpers no)
		(fp_line
			(start -0.7874 -0.4064)
			(end 0.7874 -0.4064)
			(stroke
				(width 0.1524)
				(type default)
			)
			(layer "F.SilkS")
		)
		(fp_line
			(start -0.7874 0.4064)
			(end -0.7874 -0.4064)
			(stroke
				(width 0.1524)
				(type default)
			)
			(layer "F.SilkS")
		)
		(fp_line
			(start 0.7874 -0.4064)
			(end 0.7874 0.4064)
			(stroke
				(width 0.1524)
				(type default)
			)
			(layer "F.SilkS")
		)
		(fp_line
			(start 0.7874 0.4064)
			(end -0.7874 0.4064)
			(stroke
				(width 0.1524)
				(type default)
			)
			(layer "F.SilkS")
		)
		(fp_line
			(start -0.67945 -0.305054)
			(end -0.12065 -0.305054)
			(stroke
				(width 0.1)
				(type default)
			)
			(layer "F.Fab")
		)
		(fp_line
			(start -0.67945 0.3048)
			(end -0.67945 -0.305054)
			(stroke
				(width 0.1)
				(type default)
			)
			(layer "F.Fab")
		)
		(fp_line
			(start -0.12065 -0.305054)
			(end -0.12065 -0.2794)
			(stroke
				(width 0.1)
				(type default)
			)
			(layer "F.Fab")
		)
		(fp_line
			(start -0.12065 -0.2794)
			(end 0.12065 -0.2794)
			(stroke
				(width 0.1)
				(type default)
			)
			(layer "F.Fab")
		)
		(fp_line
			(start -0.12065 0.2794)
			(end -0.12065 0.3048)
			(stroke
				(width 0.1)
				(type default)
			)
			(layer "F.Fab")
		)
		(fp_line
			(start -0.12065 0.3048)
			(end -0.67945 0.3048)
			(stroke
				(width 0.1)
				(type default)
			)
			(layer "F.Fab")
		)
		(fp_line
			(start 0.120396 0.2794)
			(end -0.12065 0.2794)
			(stroke
				(width 0.1)
				(type default)
			)
			(layer "F.Fab")
		)
		(fp_line
			(start 0.120396 0.3048)
			(end 0.120396 0.2794)
			(stroke
				(width 0.1)
				(type default)
			)
			(layer "F.Fab")
		)
		(fp_line
			(start 0.12065 -0.3048)
			(end 0.67945 -0.3048)
			(stroke
				(width 0.1)
				(type default)
			)
			(layer "F.Fab")
		)
		(fp_line
			(start 0.12065 -0.2794)
			(end 0.12065 -0.3048)
			(stroke
				(width 0.1)
				(type default)
			)
			(layer "F.Fab")
		)
		(fp_line
			(start 0.67945 -0.3048)
			(end 0.67945 0.3048)
			(stroke
				(width 0.1)
				(type default)
			)
			(layer "F.Fab")
		)
		(fp_line
			(start 0.67945 0.3048)
			(end 0.120396 0.3048)
			(stroke
				(width 0.1)
				(type default)
			)
			(layer "F.Fab")
		)
		(pad "1" smd circle
			(at -0.40005 0)
			(size 0 0)
			(layers "F.Cu" "F.Mask" "F.Paste")
			(net "PVCCIN_CPU0_VCC")
		)
		(pad "2" smd circle
			(at 0.40005 0)
			(size 0 0)
			(layers "F.Cu" "F.Mask" "F.Paste")
			(net "GND")
		)
	)
	(footprint ""
		(layer "F.Cu")
		(at 61.121798 -402.371052 -90)
		(property "Reference" "C719"
			(at 0 0 270)
			(layer "F.SilkS")
			(hide yes)
			(effects
				(font
					(size 1.27 1.27)
				)
			)
		)
		(property "Value" ""
			(at 0 0 270)
			(layer "F.Fab")
			(effects
				(font
					(size 1.27 1.27)
				)
			)
		)
		(duplicate_pad_numbers_are_jumpers no)
		(fp_line
			(start -0.299974 0.150114)
			(end -0.299974 -0.150114)
			(stroke
				(width 0.1)
				(type default)
			)
			(layer "F.Fab")
		)
		(fp_line
			(start 0.299974 0.150114)
			(end -0.299974 0.150114)
			(stroke
				(width 0.1)
				(type default)
			)
			(layer "F.Fab")
		)
		(fp_line
			(start -0.299974 -0.150114)
			(end 0.299974 -0.150114)
			(stroke
				(width 0.1)
				(type default)
			)
			(layer "F.Fab")
		)
		(fp_line
			(start 0.299974 -0.150114)
			(end 0.299974 0.150114)
			(stroke
				(width 0.1)
				(type default)
			)
			(layer "F.Fab")
		)
		(pad "1" smd rect
			(at -0.2667 0 270)
			(size 0.3048 0.381)
			(layers "F.Cu" "F.Mask" "F.Paste")
			(net "P5E_CPU1_PE0_TX_C_DP<11>")
		)
		(pad "2" smd rect
			(at 0.2667 0 270)
			(size 0.3048 0.381)
			(layers "F.Cu" "F.Mask" "F.Paste")
			(net "P5E_CPU1_PE0_TX_DP<11>")
		)
	)
	(footprint ""
		(layer "F.Cu")
		(at 171.50588 -130.266948 90)
		(property "Reference" "R991"
			(at 0 0 90)
			(layer "F.SilkS")
			(hide yes)
			(effects
				(font
					(size 1.27 1.27)
				)
			)
		)
		(property "Value" ""
			(at 0 0 90)
			(layer "F.Fab")
			(effects
				(font
					(size 1.27 1.27)
				)
			)
		)
		(duplicate_pad_numbers_are_jumpers no)
		(fp_line
			(start 0.7874 -0.4064)
			(end 0.7874 0.4064)
			(stroke
				(width 0.1524)
				(type default)
			)
			(layer "F.SilkS")
		)
		(fp_line
			(start -0.7874 -0.4064)
			(end 0.7874 -0.4064)
			(stroke
				(width 0.1524)
				(type default)
			)
			(layer "F.SilkS")
		)
		(fp_line
			(start 0.7874 0.4064)
			(end -0.7874 0.4064)
			(stroke
				(width 0.1524)
				(type default)
			)
			(layer "F.SilkS")
		)
		(fp_line
			(start -0.7874 0.4064)
			(end -0.7874 -0.4064)
			(stroke
				(width 0.1524)
				(type default)
			)
			(layer "F.SilkS")
		)
		(fp_line
			(start -0.12065 -0.305054)
			(end -0.12065 -0.2794)
			(stroke
				(width 0.1)
				(type default)
			)
			(layer "F.Fab")
		)
		(fp_line
			(start -0.67945 -0.305054)
			(end -0.12065 -0.305054)
			(stroke
				(width 0.1)
				(type default)
			)
			(layer "F.Fab")
		)
		(fp_line
			(start 0.67945 -0.3048)
			(end 0.67945 0.3048)
			(stroke
				(width 0.1)
				(type default)
			)
			(layer "F.Fab")
		)
		(fp_line
			(start 0.12065 -0.3048)
			(end 0.67945 -0.3048)
			(stroke
				(width 0.1)
				(type default)
			)
			(layer "F.Fab")
		)
		(fp_line
			(start 0.12065 -0.2794)
			(end 0.12065 -0.3048)
			(stroke
				(width 0.1)
				(type default)
			)
			(layer "F.Fab")
		)
		(fp_line
			(start -0.12065 -0.2794)
			(end 0.12065 -0.2794)
			(stroke
				(width 0.1)
				(type default)
			)
			(layer "F.Fab")
		)
		(fp_line
			(start 0.120396 0.2794)
			(end -0.12065 0.2794)
			(stroke
				(width 0.1)
				(type default)
			)
			(layer "F.Fab")
		)
		(fp_line
			(start -0.12065 0.2794)
			(end -0.12065 0.3048)
			(stroke
				(width 0.1)
				(type default)
			)
			(layer "F.Fab")
		)
		(fp_line
			(start 0.67945 0.3048)
			(end 0.120396 0.3048)
			(stroke
				(width 0.1)
				(type default)
			)
			(layer "F.Fab")
		)
		(fp_line
			(start 0.120396 0.3048)
			(end 0.120396 0.2794)
			(stroke
				(width 0.1)
				(type default)
			)
			(layer "F.Fab")
		)
		(fp_line
			(start -0.12065 0.3048)
			(end -0.67945 0.3048)
			(stroke
				(width 0.1)
				(type default)
			)
			(layer "F.Fab")
		)
		(fp_line
			(start -0.67945 0.3048)
			(end -0.67945 -0.305054)
			(stroke
				(width 0.1)
				(type default)
			)
			(layer "F.Fab")
		)
		(pad "1" smd circle
			(at -0.40005 0 90)
			(size 0 0)
			(layers "F.Cu" "F.Mask" "F.Paste")
			(net "FM_AUX_SW_EN")
		)
		(pad "2" smd circle
			(at 0.40005 0 90)
			(size 0 0)
			(layers "F.Cu" "F.Mask" "F.Paste")
			(net "GND")
		)
	)
	(footprint ""
		(layer "F.Cu")
		(at 128.401572 -137.114026)
		(property "Reference" "R537"
			(at 0 0 0)
			(layer "F.SilkS")
			(hide yes)
			(effects
				(font
					(size 1.27 1.27)
				)
			)
		)
		(property "Value" ""
			(at 0 0 0)
			(layer "F.Fab")
			(effects
				(font
					(size 1.27 1.27)
				)
			)
		)
		(duplicate_pad_numbers_are_jumpers no)
		(fp_line
			(start -0.7874 -0.4064)
			(end 0.7874 -0.4064)
			(stroke
				(width 0.1524)
				(type default)
			)
			(layer "F.SilkS")
		)
		(fp_line
			(start -0.7874 0.4064)
			(end -0.7874 -0.4064)
			(stroke
				(width 0.1524)
				(type default)
			)
			(layer "F.SilkS")
		)
		(fp_line
			(start 0.7874 -0.4064)
			(end 0.7874 0.4064)
			(stroke
				(width 0.1524)
				(type default)
			)
			(layer "F.SilkS")
		)
		(fp_line
			(start 0.7874 0.4064)
			(end -0.7874 0.4064)
			(stroke
				(width 0.1524)
				(type default)
			)
			(layer "F.SilkS")
		)
		(fp_line
			(start -0.67945 -0.305054)
			(end -0.12065 -0.305054)
			(stroke
				(width 0.1)
				(type default)
			)
			(layer "F.Fab")
		)
		(fp_line
			(start -0.67945 0.3048)
			(end -0.67945 -0.305054)
			(stroke
				(width 0.1)
				(type default)
			)
			(layer "F.Fab")
		)
		(fp_line
			(start -0.12065 -0.305054)
			(end -0.12065 -0.2794)
			(stroke
				(width 0.1)
				(type default)
			)
			(layer "F.Fab")
		)
		(fp_line
			(start -0.12065 -0.2794)
			(end 0.12065 -0.2794)
			(stroke
				(width 0.1)
				(type default)
			)
			(layer "F.Fab")
		)
		(fp_line
			(start -0.12065 0.2794)
			(end -0.12065 0.3048)
			(stroke
				(width 0.1)
				(type default)
			)
			(layer "F.Fab")
		)
		(fp_line
			(start -0.12065 0.3048)
			(end -0.67945 0.3048)
			(stroke
				(width 0.1)
				(type default)
			)
			(layer "F.Fab")
		)
		(fp_line
			(start 0.120396 0.2794)
			(end -0.12065 0.2794)
			(stroke
				(width 0.1)
				(type default)
			)
			(layer "F.Fab")
		)
		(fp_line
			(start 0.120396 0.3048)
			(end 0.120396 0.2794)
			(stroke
				(width 0.1)
				(type default)
			)
			(layer "F.Fab")
		)
		(fp_line
			(start 0.12065 -0.3048)
			(end 0.67945 -0.3048)
			(stroke
				(width 0.1)
				(type default)
			)
			(layer "F.Fab")
		)
		(fp_line
			(start 0.12065 -0.2794)
			(end 0.12065 -0.3048)
			(stroke
				(width 0.1)
				(type default)
			)
			(layer "F.Fab")
		)
		(fp_line
			(start 0.67945 -0.3048)
			(end 0.67945 0.3048)
			(stroke
				(width 0.1)
				(type default)
			)
			(layer "F.Fab")
		)
		(fp_line
			(start 0.67945 0.3048)
			(end 0.120396 0.3048)
			(stroke
				(width 0.1)
				(type default)
			)
			(layer "F.Fab")
		)
		(pad "1" smd circle
			(at -0.40005 0)
			(size 0 0)
			(layers "F.Cu" "F.Mask" "F.Paste")
			(net "PCA9548_PCIE3_ADDR2")
		)
		(pad "2" smd circle
			(at 0.40005 0)
			(size 0 0)
			(layers "F.Cu" "F.Mask" "F.Paste")
			(net "GND")
		)
	)
	(footprint ""
		(layer "F.Cu")
		(at 329.240388 -4.696206 180)
		(property "Reference" "J81"
			(at -4.415282 -1.140206 90)
			(unlocked yes)
			(layer "F.SilkS")
			(effects
				(font
					(size 0.7874 0.5842)
					(thickness 0.1524)
				)
				(justify left)
			)
		)
		(property "Value" ""
			(at 0 0 180)
			(layer "F.Fab")
			(effects
				(font
					(size 1.27 1.27)
				)
			)
		)
		(duplicate_pad_numbers_are_jumpers no)
		(fp_line
			(start 1.2192 2.1082)
			(end -1.2192 2.1082)
			(stroke
				(width 0.1524)
				(type default)
			)
			(layer "F.SilkS")
		)
		(fp_line
			(start 1.2192 -2.1082)
			(end 1.2192 2.1082)
			(stroke
				(width 0.1524)
				(type default)
			)
			(layer "F.SilkS")
		)
		(fp_line
			(start -1.2192 2.1082)
			(end -1.2192 -2.1082)
			(stroke
				(width 0.1524)
				(type default)
			)
			(layer "F.SilkS")
		)
		(fp_line
			(start -1.2192 -2.1082)
			(end 1.2192 -2.1082)
			(stroke
				(width 0.1524)
				(type default)
			)
			(layer "F.SilkS")
		)
		(pad "" np_thru_hole circle
			(at -2.8829 -1.27 90)
			(size 1.0414 1.0414)
			(drill 1.0414)
			(layers "*.Cu" "*.Mask")
			(clearance 0.381)
			(thermal_gap 0.381)
		)
		(pad "" np_thru_hole circle
			(at -2.8829 1.27 90)
			(size 1.0414 1.0414)
			(drill 1.0414)
			(layers "*.Cu" "*.Mask")
			(clearance 0.381)
			(thermal_gap 0.381)
		)
		(pad "" np_thru_hole circle
			(at 3.4671 -1.27 90)
			(size 1.0414 1.0414)
			(drill 1.0414)
			(layers "*.Cu" "*.Mask")
			(clearance 0.381)
			(thermal_gap 0.381)
		)
		(pad "" np_thru_hole circle
			(at 3.4671 1.27 90)
			(size 1.0414 1.0414)
			(drill 1.0414)
			(layers "*.Cu" "*.Mask")
			(clearance 0.381)
			(thermal_gap 0.381)
		)
		(pad "1" smd rect
			(at 0.8255 -0.249936 90)
			(size 0.3048 0.508)
			(layers "F.Cu" "F.Mask" "F.Paste")
			(net "DELTA_L_85_10INCH_TOP_DN")
		)
		(pad "2" smd rect
			(at 0.8255 0.249936 90)
			(size 0.3048 0.508)
			(layers "F.Cu" "F.Mask" "F.Paste")
			(net "DELTA_L_85_10INCH_TOP_DP")
		)
		(pad "3" smd circle
			(at 0 0 180)
			(size 0 0)
			(layers "F.Cu" "F.Mask" "F.Paste")
			(net "DELTA_L_GND_1")
		)
		(zone
			(layer "F.Cu")
			(hatch none 0.5)
			(connect_pads
				(clearance 0)
			)
			(min_thickness 0.25)
			(keepout
				(tracks not_allowed)
				(vias allowed)
				(pads allowed)
				(copperpour not_allowed)
				(footprints allowed)
			)
			(placement
				(enabled no)
				(sheetname "")
			)
			(fill
				(thermal_gap 0.5)
				(thermal_bridge_width 0.5)
				(island_removal_mode 0)
			)
			(polygon
				(pts
					(xy 328.122788 -4.147566) (xy 328.122788 -4.24307) (xy 328.719688 -4.24307) (xy 328.719688 -4.64947)
					(xy 328.122788 -4.64947) (xy 328.122788 -4.742942) (xy 328.719688 -4.742942) (xy 328.719688 -5.149342)
					(xy 328.122788 -5.149342) (xy 328.122788 -5.244846) (xy 328.821288 -5.244846) (xy 328.821288 -4.147566)
				)
			)
		)
		(zone
			(layers "F.Cu" "B.Cu" "In1.Cu" "In2.Cu" "In3.Cu" "In4.Cu" "In5.Cu" "In6.Cu"
				"In7.Cu" "In8.Cu" "In9.Cu" "In10.Cu" "In11.Cu" "In12.Cu" "In13.Cu" "In14.Cu"
				"In15.Cu" "In16.Cu"
			)
			(hatch none 0.5)
			(connect_pads
				(clearance 0)
			)
			(min_thickness 0.25)
			(keepout
				(tracks not_allowed)
				(vias allowed)
				(pads allowed)
				(copperpour not_allowed)
				(footprints allowed)
			)
			(placement
				(enabled no)
				(sheetname "")
			)
			(fill
				(thermal_gap 0.5)
				(thermal_bridge_width 0.5)
				(island_removal_mode 0)
			)
			(polygon
				(pts
					(arc
						(start 326.700388 -5.966206)
						(mid 324.846188 -5.966206)
						(end 326.700388 -5.966206)
					)
				)
			)
		)
		(zone
			(layers "F.Cu" "B.Cu" "In1.Cu" "In2.Cu" "In3.Cu" "In4.Cu" "In5.Cu" "In6.Cu"
				"In7.Cu" "In8.Cu" "In9.Cu" "In10.Cu" "In11.Cu" "In12.Cu" "In13.Cu" "In14.Cu"
				"In15.Cu" "In16.Cu"
			)
			(hatch none 0.5)
			(connect_pads
				(clearance 0)
			)
			(min_thickness 0.25)
			(keepout
				(tracks not_allowed)
				(vias allowed)
				(pads allowed)
				(copperpour not_allowed)
				(footprints allowed)
			)
			(placement
				(enabled no)
				(sheetname "")
			)
			(fill
				(thermal_gap 0.5)
				(thermal_bridge_width 0.5)
				(island_removal_mode 0)
			)
			(polygon
				(pts
					(arc
						(start 326.700388 -3.426206)
						(mid 324.846188 -3.426206)
						(end 326.700388 -3.426206)
					)
				)
			)
		)
		(zone
			(layers "F.Cu" "B.Cu" "In1.Cu" "In2.Cu" "In3.Cu" "In4.Cu" "In5.Cu" "In6.Cu"
				"In7.Cu" "In8.Cu" "In9.Cu" "In10.Cu" "In11.Cu" "In12.Cu" "In13.Cu" "In14.Cu"
				"In15.Cu" "In16.Cu"
			)
			(hatch none 0.5)
			(connect_pads
				(clearance 0)
			)
			(min_thickness 0.25)
			(keepout
				(tracks not_allowed)
				(vias allowed)
				(pads allowed)
				(copperpour not_allowed)
				(footprints allowed)
			)
			(placement
				(enabled no)
				(sheetname "")
			)
			(fill
				(thermal_gap 0.5)
				(thermal_bridge_width 0.5)
				(island_removal_mode 0)
			)
			(polygon
				(pts
					(arc
						(start 333.050388 -5.966206)
						(mid 331.196188 -5.966206)
						(end 333.050388 -5.966206)
					)
				)
			)
		)
		(zone
			(layers "F.Cu" "B.Cu" "In1.Cu" "In2.Cu" "In3.Cu" "In4.Cu" "In5.Cu" "In6.Cu"
				"In7.Cu" "In8.Cu" "In9.Cu" "In10.Cu" "In11.Cu" "In12.Cu" "In13.Cu" "In14.Cu"
				"In15.Cu" "In16.Cu"
			)
			(hatch none 0.5)
			(connect_pads
				(clearance 0)
			)
			(min_thickness 0.25)
			(keepout
				(tracks not_allowed)
				(vias allowed)
				(pads allowed)
				(copperpour not_allowed)
				(footprints allowed)
			)
			(placement
				(enabled no)
				(sheetname "")
			)
			(fill
				(thermal_gap 0.5)
				(thermal_bridge_width 0.5)
				(island_removal_mode 0)
			)
			(polygon
				(pts
					(arc
						(start 333.050388 -3.426206)
						(mid 331.196188 -3.426206)
						(end 333.050388 -3.426206)
					)
				)
			)
		)
	)
	(footprint ""
		(layer "F.Cu")
		(at 152.96388 -109.311948 90)
		(property "Reference" "U225"
			(at -2.224532 -4.60248 0)
			(unlocked yes)
			(layer "F.SilkS")
			(effects
				(font
					(size 0.7874 0.5842)
					(thickness 0.1524)
				)
				(justify left)
			)
		)
		(property "Value" ""
			(at 0 0 90)
			(layer "F.Fab")
			(effects
				(font
					(size 1.27 1.27)
				)
			)
		)
		(duplicate_pad_numbers_are_jumpers no)
		(fp_line
			(start 1.400048 -1.100074)
			(end -1.400048 -1.100074)
			(stroke
				(width 0.1524)
				(type default)
			)
			(layer "F.SilkS")
		)
		(fp_line
			(start 1.400048 -1.100074)
			(end 1.400048 1.100074)
			(stroke
				(width 0.1524)
				(type default)
			)
			(layer "F.SilkS")
		)
		(fp_line
			(start 1.400048 1.100074)
			(end -1.400048 1.100074)
			(stroke
				(width 0.1524)
				(type default)
			)
			(layer "F.SilkS")
		)
		(fp_line
			(start -1.400048 1.100074)
			(end -1.400048 -1.100074)
			(stroke
				(width 0.1524)
				(type default)
			)
			(layer "F.SilkS")
		)
		(fp_poly
			(pts
				(xy -0.960374 -1.217168) (xy -1.468374 -2.233168) (xy -0.452374 -2.233168)
			)
			(stroke
				(width 0)
				(type default)
			)
			(fill yes)
			(layer "F.SilkS")
		)
		(fp_line
			(start 0.674878 -1.100074)
			(end 0.674878 1.100074)
			(stroke
				(width 0.1)
				(type default)
			)
			(layer "F.Fab")
		)
		(fp_line
			(start -0.674878 -1.100074)
			(end 0.674878 -1.100074)
			(stroke
				(width 0.1)
				(type default)
			)
			(layer "F.Fab")
		)
		(fp_line
			(start 0.674878 1.100074)
			(end -0.674878 1.100074)
			(stroke
				(width 0.1)
				(type default)
			)
			(layer "F.Fab")
		)
		(fp_line
			(start -0.674878 1.100074)
			(end -0.674878 -1.100074)
			(stroke
				(width 0.1)
				(type default)
			)
			(layer "F.Fab")
		)
		(fp_poly
			(pts
				(xy -1.590548 -0.649986) (xy -2.606548 -1.157986) (xy -2.606548 -0.141986)
			)
			(stroke
				(width 0)
				(type default)
			)
			(fill yes)
			(layer "F.Fab")
		)
		(pad "1" smd rect
			(at -0.94996 -0.649986)
			(size 0.4318 0.6096)
			(layers "F.Cu" "F.Mask" "F.Paste")
			(net "OCP_V3_2_AUX_PWR_EN_R3")
		)
		(pad "2" smd rect
			(at -0.94996 0)
			(size 0.4318 0.6096)
			(layers "F.Cu" "F.Mask" "F.Paste")
			(net "RST_SMB_SWITCH_N")
		)
		(pad "3" smd rect
			(at -0.94996 0.649986)
			(size 0.4318 0.6096)
			(layers "F.Cu" "F.Mask" "F.Paste")
			(net "GND")
		)
		(pad "4" smd rect
			(at 0.94996 0.649986)
			(size 0.4318 0.6096)
			(layers "F.Cu" "F.Mask" "F.Paste")
			(net "RST_HP_OCP_V3_2_R_N")
		)
		(pad "5" smd rect
			(at 0.94996 -0.649986)
			(size 0.4318 0.6096)
			(layers "F.Cu" "F.Mask" "F.Paste")
			(net "P3V3_AUX")
		)
	)
	(footprint ""
		(layer "F.Cu")
		(at 400.558 -177.206148)
		(property "Reference" "PC1574"
			(at 0 0 0)
			(layer "F.SilkS")
			(hide yes)
			(effects
				(font
					(size 1.27 1.27)
				)
			)
		)
		(property "Value" ""
			(at 0 0 0)
			(layer "F.Fab")
			(effects
				(font
					(size 1.27 1.27)
				)
			)
		)
		(duplicate_pad_numbers_are_jumpers no)
		(fp_line
			(start 2.750058 0.999998)
			(end -2.750058 0.999998)
			(stroke
				(width 0.1524)
				(type default)
			)
			(layer "F.SilkS")
		)
		(fp_circle
			(center 0 0.999998)
			(end 2.750058 0.999998)
			(stroke
				(width 0.1524)
				(type default)
			)
			(fill no)
			(layer "F.SilkS")
		)
		(fp_poly
			(pts
				(arc
					(start 2.750058 0.999998)
					(mid 0 3.750056)
					(end -2.750058 0.999998)
				)
			)
			(stroke
				(width 0)
				(type default)
			)
			(fill yes)
			(layer "F.SilkS")
		)
		(fp_circle
			(center 0 0.999998)
			(end 2.750058 0.999998)
			(stroke
				(width 0.1)
				(type default)
			)
			(fill no)
			(layer "F.Fab")
		)
		(pad "1" thru_hole rect
			(at 0 0)
			(size 1.5748 1.5748)
			(drill 1.0668)
			(layers "*.Cu" "*.Mask")
			(remove_unused_layers no)
			(net "PVCCINFAON_CPU0")
			(clearance 0)
			(padstack
				(mode front_inner_back)
				(layer "Inner"
					(shape circle)
					(size 1.5748 1.5748)
					(clearance 0)
				)
				(layer "B.Cu"
					(shape rect)
					(size 1.5748 1.5748)
					(clearance 0)
				)
			)
		)
		(pad "2" thru_hole circle
			(at 0 1.999996)
			(size 1.5748 1.5748)
			(drill 1.0668)
			(layers "*.Cu" "*.Mask")
			(remove_unused_layers no)
			(net "GND")
			(clearance 0)
		)
	)
	(footprint ""
		(layer "F.Cu")
		(at 134.54888 -100.167948 90)
		(property "Reference" "R4412"
			(at 0 0 90)
			(layer "F.SilkS")
			(hide yes)
			(effects
				(font
					(size 1.27 1.27)
				)
			)
		)
		(property "Value" ""
			(at 0 0 90)
			(layer "F.Fab")
			(effects
				(font
					(size 1.27 1.27)
				)
			)
		)
		(duplicate_pad_numbers_are_jumpers no)
		(fp_line
			(start 0.7874 -0.4064)
			(end 0.7874 0.4064)
			(stroke
				(width 0.1524)
				(type default)
			)
			(layer "F.SilkS")
		)
		(fp_line
			(start -0.7874 -0.4064)
			(end 0.7874 -0.4064)
			(stroke
				(width 0.1524)
				(type default)
			)
			(layer "F.SilkS")
		)
		(fp_line
			(start 0.7874 0.4064)
			(end -0.7874 0.4064)
			(stroke
				(width 0.1524)
				(type default)
			)
			(layer "F.SilkS")
		)
		(fp_line
			(start -0.7874 0.4064)
			(end -0.7874 -0.4064)
			(stroke
				(width 0.1524)
				(type default)
			)
			(layer "F.SilkS")
		)
		(fp_line
			(start -0.12065 -0.305054)
			(end -0.12065 -0.2794)
			(stroke
				(width 0.1)
				(type default)
			)
			(layer "F.Fab")
		)
		(fp_line
			(start -0.67945 -0.305054)
			(end -0.12065 -0.305054)
			(stroke
				(width 0.1)
				(type default)
			)
			(layer "F.Fab")
		)
		(fp_line
			(start 0.67945 -0.3048)
			(end 0.67945 0.3048)
			(stroke
				(width 0.1)
				(type default)
			)
			(layer "F.Fab")
		)
		(fp_line
			(start 0.12065 -0.3048)
			(end 0.67945 -0.3048)
			(stroke
				(width 0.1)
				(type default)
			)
			(layer "F.Fab")
		)
		(fp_line
			(start 0.12065 -0.2794)
			(end 0.12065 -0.3048)
			(stroke
				(width 0.1)
				(type default)
			)
			(layer "F.Fab")
		)
		(fp_line
			(start -0.12065 -0.2794)
			(end 0.12065 -0.2794)
			(stroke
				(width 0.1)
				(type default)
			)
			(layer "F.Fab")
		)
		(fp_line
			(start 0.120396 0.2794)
			(end -0.12065 0.2794)
			(stroke
				(width 0.1)
				(type default)
			)
			(layer "F.Fab")
		)
		(fp_line
			(start -0.12065 0.2794)
			(end -0.12065 0.3048)
			(stroke
				(width 0.1)
				(type default)
			)
			(layer "F.Fab")
		)
		(fp_line
			(start 0.67945 0.3048)
			(end 0.120396 0.3048)
			(stroke
				(width 0.1)
				(type default)
			)
			(layer "F.Fab")
		)
		(fp_line
			(start 0.120396 0.3048)
			(end 0.120396 0.2794)
			(stroke
				(width 0.1)
				(type default)
			)
			(layer "F.Fab")
		)
		(fp_line
			(start -0.12065 0.3048)
			(end -0.67945 0.3048)
			(stroke
				(width 0.1)
				(type default)
			)
			(layer "F.Fab")
		)
		(fp_line
			(start -0.67945 0.3048)
			(end -0.67945 -0.305054)
			(stroke
				(width 0.1)
				(type default)
			)
			(layer "F.Fab")
		)
		(pad "1" smd circle
			(at -0.40005 0 90)
			(size 0 0)
			(layers "F.Cu" "F.Mask" "F.Paste")
			(net "P3V3")
		)
		(pad "2" smd circle
			(at 0.40005 0 90)
			(size 0 0)
			(layers "F.Cu" "F.Mask" "F.Paste")
			(net "H_CPU1_MEMTRIP_VT_N")
		)
	)
	(footprint ""
		(layer "F.Cu")
		(at 440.592972 -22.551898 180)
		(property "Reference" "PR3838"
			(at 0 0 180)
			(layer "F.SilkS")
			(hide yes)
			(effects
				(font
					(size 1.27 1.27)
				)
			)
		)
		(property "Value" ""
			(at 0 0 180)
			(layer "F.Fab")
			(effects
				(font
					(size 1.27 1.27)
				)
			)
		)
		(duplicate_pad_numbers_are_jumpers no)
		(fp_line
			(start 0.7874 0.4064)
			(end -0.7874 0.4064)
			(stroke
				(width 0.1524)
				(type default)
			)
			(layer "F.SilkS")
		)
		(fp_line
			(start 0.7874 -0.4064)
			(end 0.7874 0.4064)
			(stroke
				(width 0.1524)
				(type default)
			)
			(layer "F.SilkS")
		)
		(fp_line
			(start -0.7874 0.4064)
			(end -0.7874 -0.4064)
			(stroke
				(width 0.1524)
				(type default)
			)
			(layer "F.SilkS")
		)
		(fp_line
			(start -0.7874 -0.4064)
			(end 0.7874 -0.4064)
			(stroke
				(width 0.1524)
				(type default)
			)
			(layer "F.SilkS")
		)
		(fp_line
			(start 0.67945 0.3048)
			(end 0.120396 0.3048)
			(stroke
				(width 0.1)
				(type default)
			)
			(layer "F.Fab")
		)
		(fp_line
			(start 0.67945 -0.3048)
			(end 0.67945 0.3048)
			(stroke
				(width 0.1)
				(type default)
			)
			(layer "F.Fab")
		)
		(fp_line
			(start 0.12065 -0.2794)
			(end 0.12065 -0.3048)
			(stroke
				(width 0.1)
				(type default)
			)
			(layer "F.Fab")
		)
		(fp_line
			(start 0.12065 -0.3048)
			(end 0.67945 -0.3048)
			(stroke
				(width 0.1)
				(type default)
			)
			(layer "F.Fab")
		)
		(fp_line
			(start 0.120396 0.3048)
			(end 0.120396 0.2794)
			(stroke
				(width 0.1)
				(type default)
			)
			(layer "F.Fab")
		)
		(fp_line
			(start 0.120396 0.2794)
			(end -0.12065 0.2794)
			(stroke
				(width 0.1)
				(type default)
			)
			(layer "F.Fab")
		)
		(fp_line
			(start -0.12065 0.3048)
			(end -0.67945 0.3048)
			(stroke
				(width 0.1)
				(type default)
			)
			(layer "F.Fab")
		)
		(fp_line
			(start -0.12065 0.2794)
			(end -0.12065 0.3048)
			(stroke
				(width 0.1)
				(type default)
			)
			(layer "F.Fab")
		)
		(fp_line
			(start -0.12065 -0.2794)
			(end 0.12065 -0.2794)
			(stroke
				(width 0.1)
				(type default)
			)
			(layer "F.Fab")
		)
		(fp_line
			(start -0.12065 -0.305054)
			(end -0.12065 -0.2794)
			(stroke
				(width 0.1)
				(type default)
			)
			(layer "F.Fab")
		)
		(fp_line
			(start -0.67945 0.3048)
			(end -0.67945 -0.305054)
			(stroke
				(width 0.1)
				(type default)
			)
			(layer "F.Fab")
		)
		(fp_line
			(start -0.67945 -0.305054)
			(end -0.12065 -0.305054)
			(stroke
				(width 0.1)
				(type default)
			)
			(layer "F.Fab")
		)
		(pad "1" smd circle
			(at -0.40005 0 180)
			(size 0 0)
			(layers "F.Cu" "F.Mask" "F.Paste")
			(net "P12V_OCP_SFF")
		)
		(pad "2" smd circle
			(at 0.40005 0 180)
			(size 0 0)
			(layers "F.Cu" "F.Mask" "F.Paste")
			(net "P12V_OCP_AVIN_PD_1")
		)
	)
	(footprint ""
		(layer "F.Cu")
		(at 329.60691 -20.616926)
		(property "Reference" "R1268"
			(at 0 0 0)
			(layer "F.SilkS")
			(hide yes)
			(effects
				(font
					(size 1.27 1.27)
				)
			)
		)
		(property "Value" ""
			(at 0 0 0)
			(layer "F.Fab")
			(effects
				(font
					(size 1.27 1.27)
				)
			)
		)
		(duplicate_pad_numbers_are_jumpers no)
		(fp_line
			(start -0.7874 -0.4064)
			(end 0.7874 -0.4064)
			(stroke
				(width 0.1524)
				(type default)
			)
			(layer "F.SilkS")
		)
		(fp_line
			(start -0.7874 0.4064)
			(end -0.7874 -0.4064)
			(stroke
				(width 0.1524)
				(type default)
			)
			(layer "F.SilkS")
		)
		(fp_line
			(start 0.7874 -0.4064)
			(end 0.7874 0.4064)
			(stroke
				(width 0.1524)
				(type default)
			)
			(layer "F.SilkS")
		)
		(fp_line
			(start 0.7874 0.4064)
			(end -0.7874 0.4064)
			(stroke
				(width 0.1524)
				(type default)
			)
			(layer "F.SilkS")
		)
		(fp_line
			(start -0.67945 -0.305054)
			(end -0.12065 -0.305054)
			(stroke
				(width 0.1)
				(type default)
			)
			(layer "F.Fab")
		)
		(fp_line
			(start -0.67945 0.3048)
			(end -0.67945 -0.305054)
			(stroke
				(width 0.1)
				(type default)
			)
			(layer "F.Fab")
		)
		(fp_line
			(start -0.12065 -0.305054)
			(end -0.12065 -0.2794)
			(stroke
				(width 0.1)
				(type default)
			)
			(layer "F.Fab")
		)
		(fp_line
			(start -0.12065 -0.2794)
			(end 0.12065 -0.2794)
			(stroke
				(width 0.1)
				(type default)
			)
			(layer "F.Fab")
		)
		(fp_line
			(start -0.12065 0.2794)
			(end -0.12065 0.3048)
			(stroke
				(width 0.1)
				(type default)
			)
			(layer "F.Fab")
		)
		(fp_line
			(start -0.12065 0.3048)
			(end -0.67945 0.3048)
			(stroke
				(width 0.1)
				(type default)
			)
			(layer "F.Fab")
		)
		(fp_line
			(start 0.120396 0.2794)
			(end -0.12065 0.2794)
			(stroke
				(width 0.1)
				(type default)
			)
			(layer "F.Fab")
		)
		(fp_line
			(start 0.120396 0.3048)
			(end 0.120396 0.2794)
			(stroke
				(width 0.1)
				(type default)
			)
			(layer "F.Fab")
		)
		(fp_line
			(start 0.12065 -0.3048)
			(end 0.67945 -0.3048)
			(stroke
				(width 0.1)
				(type default)
			)
			(layer "F.Fab")
		)
		(fp_line
			(start 0.12065 -0.2794)
			(end 0.12065 -0.3048)
			(stroke
				(width 0.1)
				(type default)
			)
			(layer "F.Fab")
		)
		(fp_line
			(start 0.67945 -0.3048)
			(end 0.67945 0.3048)
			(stroke
				(width 0.1)
				(type default)
			)
			(layer "F.Fab")
		)
		(fp_line
			(start 0.67945 0.3048)
			(end 0.120396 0.3048)
			(stroke
				(width 0.1)
				(type default)
			)
			(layer "F.Fab")
		)
		(pad "1" smd circle
			(at -0.40005 0)
			(size 0 0)
			(layers "F.Cu" "F.Mask" "F.Paste")
			(net "IRQ_BMC_PCH_NMI_R")
		)
		(pad "2" smd circle
			(at 0.40005 0)
			(size 0 0)
			(layers "F.Cu" "F.Mask" "F.Paste")
			(net "IRQ_BMC_PCH_NMI")
		)
	)
	(footprint ""
		(layer "F.Cu")
		(at 112.027462 -338.86013)
		(property "Reference" "PR298"
			(at 0 0 0)
			(layer "F.SilkS")
			(hide yes)
			(effects
				(font
					(size 1.27 1.27)
				)
			)
		)
		(property "Value" ""
			(at 0 0 0)
			(layer "F.Fab")
			(effects
				(font
					(size 1.27 1.27)
				)
			)
		)
		(duplicate_pad_numbers_are_jumpers no)
		(fp_line
			(start -0.7874 -0.4064)
			(end 0.7874 -0.4064)
			(stroke
				(width 0.1524)
				(type default)
			)
			(layer "F.SilkS")
		)
		(fp_line
			(start -0.7874 0.4064)
			(end -0.7874 -0.4064)
			(stroke
				(width 0.1524)
				(type default)
			)
			(layer "F.SilkS")
		)
		(fp_line
			(start 0.7874 -0.4064)
			(end 0.7874 0.4064)
			(stroke
				(width 0.1524)
				(type default)
			)
			(layer "F.SilkS")
		)
		(fp_line
			(start 0.7874 0.4064)
			(end -0.7874 0.4064)
			(stroke
				(width 0.1524)
				(type default)
			)
			(layer "F.SilkS")
		)
		(fp_line
			(start -0.67945 -0.305054)
			(end -0.12065 -0.305054)
			(stroke
				(width 0.1)
				(type default)
			)
			(layer "F.Fab")
		)
		(fp_line
			(start -0.67945 0.3048)
			(end -0.67945 -0.305054)
			(stroke
				(width 0.1)
				(type default)
			)
			(layer "F.Fab")
		)
		(fp_line
			(start -0.12065 -0.305054)
			(end -0.12065 -0.2794)
			(stroke
				(width 0.1)
				(type default)
			)
			(layer "F.Fab")
		)
		(fp_line
			(start -0.12065 -0.2794)
			(end 0.12065 -0.2794)
			(stroke
				(width 0.1)
				(type default)
			)
			(layer "F.Fab")
		)
		(fp_line
			(start -0.12065 0.2794)
			(end -0.12065 0.3048)
			(stroke
				(width 0.1)
				(type default)
			)
			(layer "F.Fab")
		)
		(fp_line
			(start -0.12065 0.3048)
			(end -0.67945 0.3048)
			(stroke
				(width 0.1)
				(type default)
			)
			(layer "F.Fab")
		)
		(fp_line
			(start 0.120396 0.2794)
			(end -0.12065 0.2794)
			(stroke
				(width 0.1)
				(type default)
			)
			(layer "F.Fab")
		)
		(fp_line
			(start 0.120396 0.3048)
			(end 0.120396 0.2794)
			(stroke
				(width 0.1)
				(type default)
			)
			(layer "F.Fab")
		)
		(fp_line
			(start 0.12065 -0.3048)
			(end 0.67945 -0.3048)
			(stroke
				(width 0.1)
				(type default)
			)
			(layer "F.Fab")
		)
		(fp_line
			(start 0.12065 -0.2794)
			(end 0.12065 -0.3048)
			(stroke
				(width 0.1)
				(type default)
			)
			(layer "F.Fab")
		)
		(fp_line
			(start 0.67945 -0.3048)
			(end 0.67945 0.3048)
			(stroke
				(width 0.1)
				(type default)
			)
			(layer "F.Fab")
		)
		(fp_line
			(start 0.67945 0.3048)
			(end 0.120396 0.3048)
			(stroke
				(width 0.1)
				(type default)
			)
			(layer "F.Fab")
		)
		(pad "1" smd circle
			(at -0.40005 0)
			(size 0 0)
			(layers "F.Cu" "F.Mask" "F.Paste")
			(net "PVCCIN_CPU1_LSET3")
		)
		(pad "2" smd circle
			(at 0.40005 0)
			(size 0 0)
			(layers "F.Cu" "F.Mask" "F.Paste")
			(net "GND")
		)
	)
	(footprint ""
		(layer "F.Cu")
		(at 191.03848 -258.091686)
		(property "Reference" "J30"
			(at -2.98196 -81.740248 0)
			(unlocked yes)
			(layer "F.SilkS")
			(effects
				(font
					(size 0.7874 0.5842)
					(thickness 0.1524)
				)
				(justify left)
			)
		)
		(property "Value" ""
			(at 0 0 0)
			(layer "F.Fab")
			(effects
				(font
					(size 1.27 1.27)
				)
			)
		)
		(duplicate_pad_numbers_are_jumpers no)
		(fp_line
			(start -3.24993 -81.000092)
			(end -3.24993 81.000092)
			(stroke
				(width 0.1524)
				(type default)
			)
			(layer "F.SilkS")
		)
		(fp_line
			(start -3.24993 81.000092)
			(end -0.01778 81.000092)
			(stroke
				(width 0.1524)
				(type default)
			)
			(layer "F.SilkS")
		)
		(fp_line
			(start 1.87706 81.000092)
			(end 3.24993 81.000092)
			(stroke
				(width 0.1524)
				(type default)
			)
			(layer "F.SilkS")
		)
		(fp_line
			(start 3.24993 -81.000092)
			(end -3.24993 -81.000092)
			(stroke
				(width 0.1524)
				(type default)
			)
			(layer "F.SilkS")
		)
		(fp_line
			(start 3.24993 -72.00011)
			(end -3.24993 -72.00011)
			(stroke
				(width 0.1524)
				(type default)
			)
			(layer "F.SilkS")
		)
		(fp_line
			(start 3.24993 72.00011)
			(end -3.24993 72.00011)
			(stroke
				(width 0.1524)
				(type default)
			)
			(layer "F.SilkS")
		)
		(fp_line
			(start 3.24993 79.480918)
			(end 3.24993 -81.000092)
			(stroke
				(width 0.1524)
				(type default)
			)
			(layer "F.SilkS")
		)
		(fp_line
			(start 3.24993 81.000092)
			(end 3.24993 80.550258)
			(stroke
				(width 0.1524)
				(type default)
			)
			(layer "F.SilkS")
		)
		(fp_poly
			(pts
				(xy -4.172966 -63.823342) (xy -3.353308 -63.413386) (xy -4.172966 -63.00343)
			)
			(stroke
				(width 0)
				(type default)
			)
			(fill yes)
			(layer "F.SilkS")
		)
		(fp_line
			(start -3.24993 -81.000092)
			(end -3.24993 81.000092)
			(stroke
				(width 0.1)
				(type default)
			)
			(layer "F.Fab")
		)
		(fp_line
			(start -3.24993 81.000092)
			(end 3.24993 81.000092)
			(stroke
				(width 0.1)
				(type default)
			)
			(layer "F.Fab")
		)
		(fp_line
			(start 3.24993 -81.000092)
			(end -3.24993 -81.000092)
			(stroke
				(width 0.1)
				(type default)
			)
			(layer "F.Fab")
		)
		(fp_line
			(start 3.24993 -72.00011)
			(end -3.24993 -72.00011)
			(stroke
				(width 0.1)
				(type default)
			)
			(layer "F.Fab")
		)
		(fp_line
			(start 3.24993 -71.000112)
			(end -3.24993 -71.000112)
			(stroke
				(width 0.1)
				(type default)
			)
			(layer "F.Fab")
		)
		(fp_line
			(start 3.24993 71.000112)
			(end -3.24993 71.000112)
			(stroke
				(width 0.1)
				(type default)
			)
			(layer "F.Fab")
		)
		(fp_line
			(start 3.24993 72.00011)
			(end -3.24993 72.00011)
			(stroke
				(width 0.1)
				(type default)
			)
			(layer "F.Fab")
		)
		(fp_line
			(start 3.24993 81.000092)
			(end 3.24993 -81.000092)
			(stroke
				(width 0.1)
				(type default)
			)
			(layer "F.Fab")
		)
		(fp_poly
			(pts
				(xy -4.445 -63.832994) (xy -4.445 -62.816994) (xy -3.429 -63.324994)
			)
			(stroke
				(width 0)
				(type default)
			)
			(fill yes)
			(layer "F.Fab")
		)
		(pad "1" smd rect
			(at -2.050034 -63.324994 270)
			(size 0.519938 1.4986)
			(layers "F.Cu" "F.Mask" "F.Paste")
			(net "P12V_S3_AUX_CPU1_NVDIMM")
		)
		(pad "2" smd rect
			(at -2.050034 -62.47511 270)
			(size 0.519938 1.4986)
			(layers "F.Cu" "F.Mask" "F.Paste")
			(net "TP_CHG_CPU1_DIMM2_FRU_0")
		)
		(pad "3" smd rect
			(at -2.050034 -61.624972 270)
			(size 0.519938 1.4986)
			(layers "F.Cu" "F.Mask" "F.Paste")
			(net "P3V3_AUX")
		)
		(pad "4" smd rect
			(at -2.050034 -60.775088 270)
			(size 0.519938 1.4986)
			(layers "F.Cu" "F.Mask" "F.Paste")
			(net "I3C_SPD_DDREFGH_CPU1_LVC1_SCL_5")
		)
		(pad "5" smd rect
			(at -2.050034 -59.92495 270)
			(size 0.519938 1.4986)
			(layers "F.Cu" "F.Mask" "F.Paste")
			(net "I3C_SPD_DDREFGH_CPU1_LVC1_SDA")
		)
		(pad "6" smd rect
			(at -2.050034 -59.075066 270)
			(size 0.519938 1.4986)
			(layers "F.Cu" "F.Mask" "F.Paste")
			(net "GND")
		)
		(pad "7" smd rect
			(at -2.050034 -58.224928 270)
			(size 0.519938 1.4986)
			(layers "F.Cu" "F.Mask" "F.Paste")
			(net "M_G_CPU1_SA_DQ<0>")
		)
		(pad "8" smd rect
			(at -2.050034 -57.375044 270)
			(size 0.519938 1.4986)
			(layers "F.Cu" "F.Mask" "F.Paste")
			(net "GND")
		)
		(pad "9" smd rect
			(at -2.050034 -56.524906 270)
			(size 0.519938 1.4986)
			(layers "F.Cu" "F.Mask" "F.Paste")
			(net "M_G_CPU1_SA_DQ<1>")
		)
		(pad "10" smd rect
			(at -2.050034 -55.675022 270)
			(size 0.519938 1.4986)
			(layers "F.Cu" "F.Mask" "F.Paste")
			(net "GND")
		)
		(pad "11" smd rect
			(at -2.050034 -54.824884 270)
			(size 0.519938 1.4986)
			(layers "F.Cu" "F.Mask" "F.Paste")
			(net "M_G_CPU1_SA_DQS_DP<0>")
		)
		(pad "12" smd rect
			(at -2.050034 -53.975 270)
			(size 0.519938 1.4986)
			(layers "F.Cu" "F.Mask" "F.Paste")
			(net "M_G_CPU1_SA_DQS_DN<0>")
		)
		(pad "13" smd rect
			(at -2.050034 -53.125116 270)
			(size 0.519938 1.4986)
			(layers "F.Cu" "F.Mask" "F.Paste")
			(net "GND")
		)
		(pad "14" smd rect
			(at -2.050034 -52.274978 270)
			(size 0.519938 1.4986)
			(layers "F.Cu" "F.Mask" "F.Paste")
			(net "M_G_CPU1_SA_DQ<4>")
		)
		(pad "15" smd rect
			(at -2.050034 -51.425094 270)
			(size 0.519938 1.4986)
			(layers "F.Cu" "F.Mask" "F.Paste")
			(net "GND")
		)
		(pad "16" smd rect
			(at -2.050034 -50.574956 270)
			(size 0.519938 1.4986)
			(layers "F.Cu" "F.Mask" "F.Paste")
			(net "M_G_CPU1_SA_DQ<5>")
		)
		(pad "17" smd rect
			(at -2.050034 -49.725072 270)
			(size 0.519938 1.4986)
			(layers "F.Cu" "F.Mask" "F.Paste")
			(net "GND")
		)
		(pad "18" smd rect
			(at -2.050034 -48.874934 270)
			(size 0.519938 1.4986)
			(layers "F.Cu" "F.Mask" "F.Paste")
			(net "M_G_CPU1_SA_DQ<8>")
		)
		(pad "19" smd rect
			(at -2.050034 -48.02505 270)
			(size 0.519938 1.4986)
			(layers "F.Cu" "F.Mask" "F.Paste")
			(net "GND")
		)
		(pad "20" smd rect
			(at -2.050034 -47.174912 270)
			(size 0.519938 1.4986)
			(layers "F.Cu" "F.Mask" "F.Paste")
			(net "M_G_CPU1_SA_DQ<9>")
		)
		(pad "21" smd rect
			(at -2.050034 -46.325028 270)
			(size 0.519938 1.4986)
			(layers "F.Cu" "F.Mask" "F.Paste")
			(net "GND")
		)
		(pad "22" smd rect
			(at -2.050034 -45.47489 270)
			(size 0.519938 1.4986)
			(layers "F.Cu" "F.Mask" "F.Paste")
			(net "M_G_CPU1_SA_DQS_DP<1>")
		)
		(pad "23" smd rect
			(at -2.050034 -44.625006 270)
			(size 0.519938 1.4986)
			(layers "F.Cu" "F.Mask" "F.Paste")
			(net "M_G_CPU1_SA_DQS_DN<1>")
		)
		(pad "24" smd rect
			(at -2.050034 -43.775122 270)
			(size 0.519938 1.4986)
			(layers "F.Cu" "F.Mask" "F.Paste")
			(net "GND")
		)
		(pad "25" smd rect
			(at -2.050034 -42.924984 270)
			(size 0.519938 1.4986)
			(layers "F.Cu" "F.Mask" "F.Paste")
			(net "M_G_CPU1_SA_DQ<12>")
		)
		(pad "26" smd rect
			(at -2.050034 -42.0751 270)
			(size 0.519938 1.4986)
			(layers "F.Cu" "F.Mask" "F.Paste")
			(net "GND")
		)
		(pad "27" smd rect
			(at -2.050034 -41.224962 270)
			(size 0.519938 1.4986)
			(layers "F.Cu" "F.Mask" "F.Paste")
			(net "M_G_CPU1_SA_DQ<13>")
		)
		(pad "28" smd rect
			(at -2.050034 -40.375078 270)
			(size 0.519938 1.4986)
			(layers "F.Cu" "F.Mask" "F.Paste")
			(net "GND")
		)
		(pad "29" smd rect
			(at -2.050034 -39.52494 270)
			(size 0.519938 1.4986)
			(layers "F.Cu" "F.Mask" "F.Paste")
			(net "M_G_CPU1_SA_DQ<16>")
		)
		(pad "30" smd rect
			(at -2.050034 -38.675056 270)
			(size 0.519938 1.4986)
			(layers "F.Cu" "F.Mask" "F.Paste")
			(net "GND")
		)
		(pad "31" smd rect
			(at -2.050034 -37.824918 270)
			(size 0.519938 1.4986)
			(layers "F.Cu" "F.Mask" "F.Paste")
			(net "M_G_CPU1_SA_DQ<17>")
		)
		(pad "32" smd rect
			(at -2.050034 -36.975034 270)
			(size 0.519938 1.4986)
			(layers "F.Cu" "F.Mask" "F.Paste")
			(net "GND")
		)
		(pad "33" smd rect
			(at -2.050034 -36.124896 270)
			(size 0.519938 1.4986)
			(layers "F.Cu" "F.Mask" "F.Paste")
			(net "M_G_CPU1_SA_DQS_DP<2>")
		)
		(pad "34" smd rect
			(at -2.050034 -35.275012 270)
			(size 0.519938 1.4986)
			(layers "F.Cu" "F.Mask" "F.Paste")
			(net "M_G_CPU1_SA_DQS_DN<2>")
		)
		(pad "35" smd rect
			(at -2.050034 -34.425128 270)
			(size 0.519938 1.4986)
			(layers "F.Cu" "F.Mask" "F.Paste")
			(net "GND")
		)
		(pad "36" smd rect
			(at -2.050034 -33.57499 270)
			(size 0.519938 1.4986)
			(layers "F.Cu" "F.Mask" "F.Paste")
			(net "M_G_CPU1_SA_DQ<20>")
		)
		(pad "37" smd rect
			(at -2.050034 -32.725106 270)
			(size 0.519938 1.4986)
			(layers "F.Cu" "F.Mask" "F.Paste")
			(net "GND")
		)
		(pad "38" smd rect
			(at -2.050034 -31.874968 270)
			(size 0.519938 1.4986)
			(layers "F.Cu" "F.Mask" "F.Paste")
			(net "M_G_CPU1_SA_DQ<21>")
		)
		(pad "39" smd rect
			(at -2.050034 -31.025084 270)
			(size 0.519938 1.4986)
			(layers "F.Cu" "F.Mask" "F.Paste")
			(net "GND")
		)
		(pad "40" smd rect
			(at -2.050034 -30.174946 270)
			(size 0.519938 1.4986)
			(layers "F.Cu" "F.Mask" "F.Paste")
			(net "M_G_CPU1_SA_DQ<24>")
		)
		(pad "41" smd rect
			(at -2.050034 -29.325062 270)
			(size 0.519938 1.4986)
			(layers "F.Cu" "F.Mask" "F.Paste")
			(net "GND")
		)
		(pad "42" smd rect
			(at -2.050034 -28.474924 270)
			(size 0.519938 1.4986)
			(layers "F.Cu" "F.Mask" "F.Paste")
			(net "M_G_CPU1_SA_DQ<25>")
		)
		(pad "43" smd rect
			(at -2.050034 -27.62504 270)
			(size 0.519938 1.4986)
			(layers "F.Cu" "F.Mask" "F.Paste")
			(net "GND")
		)
		(pad "44" smd rect
			(at -2.050034 -26.774902 270)
			(size 0.519938 1.4986)
			(layers "F.Cu" "F.Mask" "F.Paste")
			(net "M_G_CPU1_SA_DQS_DP<3>")
		)
		(pad "45" smd rect
			(at -2.050034 -25.925018 270)
			(size 0.519938 1.4986)
			(layers "F.Cu" "F.Mask" "F.Paste")
			(net "M_G_CPU1_SA_DQS_DN<3>")
		)
		(pad "46" smd rect
			(at -2.050034 -25.07488 270)
			(size 0.519938 1.4986)
			(layers "F.Cu" "F.Mask" "F.Paste")
			(net "GND")
		)
		(pad "47" smd rect
			(at -2.050034 -24.224996 270)
			(size 0.519938 1.4986)
			(layers "F.Cu" "F.Mask" "F.Paste")
			(net "M_G_CPU1_SA_DQ<28>")
		)
		(pad "48" smd rect
			(at -2.050034 -23.375112 270)
			(size 0.519938 1.4986)
			(layers "F.Cu" "F.Mask" "F.Paste")
			(net "GND")
		)
		(pad "49" smd rect
			(at -2.050034 -22.524974 270)
			(size 0.519938 1.4986)
			(layers "F.Cu" "F.Mask" "F.Paste")
			(net "M_G_CPU1_SA_DQ<29>")
		)
		(pad "50" smd rect
			(at -2.050034 -21.67509 270)
			(size 0.519938 1.4986)
			(layers "F.Cu" "F.Mask" "F.Paste")
			(net "GND")
		)
		(pad "51" smd rect
			(at -2.050034 -20.824952 270)
			(size 0.519938 1.4986)
			(layers "F.Cu" "F.Mask" "F.Paste")
			(net "M_G_CPU1_SA_CB<0>")
		)
		(pad "52" smd rect
			(at -2.050034 -19.975068 270)
			(size 0.519938 1.4986)
			(layers "F.Cu" "F.Mask" "F.Paste")
			(net "GND")
		)
		(pad "53" smd rect
			(at -2.050034 -19.12493 270)
			(size 0.519938 1.4986)
			(layers "F.Cu" "F.Mask" "F.Paste")
			(net "M_G_CPU1_SA_CB<1>")
		)
		(pad "54" smd rect
			(at -2.050034 -18.275046 270)
			(size 0.519938 1.4986)
			(layers "F.Cu" "F.Mask" "F.Paste")
			(net "GND")
		)
		(pad "55" smd rect
			(at -2.050034 -17.424908 270)
			(size 0.519938 1.4986)
			(layers "F.Cu" "F.Mask" "F.Paste")
			(net "M_G_CPU1_SA_DQS_DP<4>")
		)
		(pad "56" smd rect
			(at -2.050034 -16.575024 270)
			(size 0.519938 1.4986)
			(layers "F.Cu" "F.Mask" "F.Paste")
			(net "M_G_CPU1_SA_DQS_DN<4>")
		)
		(pad "57" smd rect
			(at -2.050034 -15.724886 270)
			(size 0.519938 1.4986)
			(layers "F.Cu" "F.Mask" "F.Paste")
			(net "GND")
		)
		(pad "58" smd rect
			(at -2.050034 -14.875002 270)
			(size 0.519938 1.4986)
			(layers "F.Cu" "F.Mask" "F.Paste")
			(net "M_G_CPU1_SA_CB<4>")
		)
		(pad "59" smd rect
			(at -2.050034 -14.025118 270)
			(size 0.519938 1.4986)
			(layers "F.Cu" "F.Mask" "F.Paste")
			(net "GND")
		)
		(pad "60" smd rect
			(at -2.050034 -13.17498 270)
			(size 0.519938 1.4986)
			(layers "F.Cu" "F.Mask" "F.Paste")
			(net "M_G_CPU1_SA_CB<5>")
		)
		(pad "61" smd rect
			(at -2.050034 -12.325096 270)
			(size 0.519938 1.4986)
			(layers "F.Cu" "F.Mask" "F.Paste")
			(net "GND")
		)
		(pad "62" smd rect
			(at -2.050034 -11.474958 270)
			(size 0.519938 1.4986)
			(layers "F.Cu" "F.Mask" "F.Paste")
			(net "M_G_CPU1_ALERT_N")
		)
		(pad "63" smd rect
			(at -2.050034 -10.625074 270)
			(size 0.519938 1.4986)
			(layers "F.Cu" "F.Mask" "F.Paste")
			(net "GND")
		)
		(pad "64" smd rect
			(at -2.050034 -9.774936 270)
			(size 0.519938 1.4986)
			(layers "F.Cu" "F.Mask" "F.Paste")
			(net "M_G_CPU1_SA_CS_N<2>")
		)
		(pad "65" smd rect
			(at -2.050034 -8.925052 270)
			(size 0.519938 1.4986)
			(layers "F.Cu" "F.Mask" "F.Paste")
			(net "GND")
		)
		(pad "66" smd rect
			(at -2.050034 -8.074914 270)
			(size 0.519938 1.4986)
			(layers "F.Cu" "F.Mask" "F.Paste")
			(net "M_G_CPU1_SA_CA<0>")
		)
		(pad "67" smd rect
			(at -2.050034 -7.22503 270)
			(size 0.519938 1.4986)
			(layers "F.Cu" "F.Mask" "F.Paste")
			(net "GND")
		)
		(pad "68" smd rect
			(at -2.050034 -6.374892 270)
			(size 0.519938 1.4986)
			(layers "F.Cu" "F.Mask" "F.Paste")
			(net "M_G_CPU1_SA_CA<2>")
		)
		(pad "69" smd rect
			(at -2.050034 -5.525008 270)
			(size 0.519938 1.4986)
			(layers "F.Cu" "F.Mask" "F.Paste")
			(net "GND")
		)
		(pad "70" smd rect
			(at -2.050034 -4.675124 270)
			(size 0.519938 1.4986)
			(layers "F.Cu" "F.Mask" "F.Paste")
			(net "M_G_CPU1_SA_CA<4>")
		)
		(pad "71" smd rect
			(at -2.050034 -3.824986 270)
			(size 0.519938 1.4986)
			(layers "F.Cu" "F.Mask" "F.Paste")
			(net "GND")
		)
		(pad "72" smd rect
			(at -2.050034 -2.975102 270)
			(size 0.519938 1.4986)
			(layers "F.Cu" "F.Mask" "F.Paste")
			(net "M_G_CPU1_SA_CA<6>")
		)
		(pad "73" smd rect
			(at -2.050034 -2.124964 270)
			(size 0.519938 1.4986)
			(layers "F.Cu" "F.Mask" "F.Paste")
			(net "GND")
		)
		(pad "74" smd rect
			(at -2.050034 -1.27508 270)
			(size 0.519938 1.4986)
			(layers "F.Cu" "F.Mask" "F.Paste")
			(net "M_G_CPU1_SA_PAR")
		)
		(pad "75" smd rect
			(at -2.050034 -0.424942 270)
			(size 0.519938 1.4986)
			(layers "F.Cu" "F.Mask" "F.Paste")
			(net "GND")
		)
		(pad "76" smd rect
			(at -2.050034 5.525008 270)
			(size 0.519938 1.4986)
			(layers "F.Cu" "F.Mask" "F.Paste")
			(net "M_G_CPU1_SB_CA<0>")
		)
		(pad "77" smd rect
			(at -2.050034 6.374892 270)
			(size 0.519938 1.4986)
			(layers "F.Cu" "F.Mask" "F.Paste")
			(net "GND")
		)
		(pad "78" smd rect
			(at -2.050034 7.22503 270)
			(size 0.519938 1.4986)
			(layers "F.Cu" "F.Mask" "F.Paste")
			(net "M_G_CPU1_SB_CA<2>")
		)
		(pad "79" smd rect
			(at -2.050034 8.074914 270)
			(size 0.519938 1.4986)
			(layers "F.Cu" "F.Mask" "F.Paste")
			(net "GND")
		)
		(pad "80" smd rect
			(at -2.050034 8.925052 270)
			(size 0.519938 1.4986)
			(layers "F.Cu" "F.Mask" "F.Paste")
			(net "M_G_CPU1_SB_CA<4>")
		)
		(pad "81" smd rect
			(at -2.050034 9.774936 270)
			(size 0.519938 1.4986)
			(layers "F.Cu" "F.Mask" "F.Paste")
			(net "GND")
		)
		(pad "82" smd rect
			(at -2.050034 10.625074 270)
			(size 0.519938 1.4986)
			(layers "F.Cu" "F.Mask" "F.Paste")
			(net "M_G_CPU1_SB_CA<6>")
		)
		(pad "83" smd rect
			(at -2.050034 11.474958 270)
			(size 0.519938 1.4986)
			(layers "F.Cu" "F.Mask" "F.Paste")
			(net "GND")
		)
		(pad "84" smd rect
			(at -2.050034 12.325096 270)
			(size 0.519938 1.4986)
			(layers "F.Cu" "F.Mask" "F.Paste")
			(net "M_G_CPU1_SB_CS_N<2>")
		)
		(pad "85" smd rect
			(at -2.050034 13.17498 270)
			(size 0.519938 1.4986)
			(layers "F.Cu" "F.Mask" "F.Paste")
			(net "GND")
		)
		(pad "86" smd rect
			(at -2.050034 14.025118 270)
			(size 0.519938 1.4986)
			(layers "F.Cu" "F.Mask" "F.Paste")
			(net "M_G_CPU1_SA_RSP<1>")
		)
		(pad "87" smd rect
			(at -2.050034 14.875002 270)
			(size 0.519938 1.4986)
			(layers "F.Cu" "F.Mask" "F.Paste")
			(net "M_G_CPU1_SB_RSP<1>")
		)
		(pad "88" smd rect
			(at -2.050034 15.724886 270)
			(size 0.519938 1.4986)
			(layers "F.Cu" "F.Mask" "F.Paste")
			(net "GND")
		)
		(pad "89" smd rect
			(at -2.050034 16.575024 270)
			(size 0.519938 1.4986)
			(layers "F.Cu" "F.Mask" "F.Paste")
			(net "M_G_CPU1_SB_CB<4>")
		)
		(pad "90" smd rect
			(at -2.050034 17.424908 270)
			(size 0.519938 1.4986)
			(layers "F.Cu" "F.Mask" "F.Paste")
			(net "GND")
		)
		(pad "91" smd rect
			(at -2.050034 18.275046 270)
			(size 0.519938 1.4986)
			(layers "F.Cu" "F.Mask" "F.Paste")
			(net "M_G_CPU1_SB_CB<5>")
		)
		(pad "92" smd rect
			(at -2.050034 19.12493 270)
			(size 0.519938 1.4986)
			(layers "F.Cu" "F.Mask" "F.Paste")
			(net "GND")
		)
		(pad "93" smd rect
			(at -2.050034 19.975068 270)
			(size 0.519938 1.4986)
			(layers "F.Cu" "F.Mask" "F.Paste")
			(net "M_G_CPU1_SB_DQS_DP<9>")
		)
		(pad "94" smd rect
			(at -2.050034 20.824952 270)
			(size 0.519938 1.4986)
			(layers "F.Cu" "F.Mask" "F.Paste")
			(net "M_G_CPU1_SB_DQS_DN<9>")
		)
		(pad "95" smd rect
			(at -2.050034 21.67509 270)
			(size 0.519938 1.4986)
			(layers "F.Cu" "F.Mask" "F.Paste")
			(net "GND")
		)
		(pad "96" smd rect
			(at -2.050034 22.524974 270)
			(size 0.519938 1.4986)
			(layers "F.Cu" "F.Mask" "F.Paste")
			(net "M_G_CPU1_SB_CB<0>")
		)
		(pad "97" smd rect
			(at -2.050034 23.375112 270)
			(size 0.519938 1.4986)
			(layers "F.Cu" "F.Mask" "F.Paste")
			(net "GND")
		)
		(pad "98" smd rect
			(at -2.050034 24.224996 270)
			(size 0.519938 1.4986)
			(layers "F.Cu" "F.Mask" "F.Paste")
			(net "M_G_CPU1_SB_CB<1>")
		)
		(pad "99" smd rect
			(at -2.050034 25.07488 270)
			(size 0.519938 1.4986)
			(layers "F.Cu" "F.Mask" "F.Paste")
			(net "GND")
		)
		(pad "100" smd rect
			(at -2.050034 25.925018 270)
			(size 0.519938 1.4986)
			(layers "F.Cu" "F.Mask" "F.Paste")
			(net "M_G_CPU1_SB_DQ<0>")
		)
		(pad "101" smd rect
			(at -2.050034 26.774902 270)
			(size 0.519938 1.4986)
			(layers "F.Cu" "F.Mask" "F.Paste")
			(net "GND")
		)
		(pad "102" smd rect
			(at -2.050034 27.62504 270)
			(size 0.519938 1.4986)
			(layers "F.Cu" "F.Mask" "F.Paste")
			(net "M_G_CPU1_SB_DQ<1>")
		)
		(pad "103" smd rect
			(at -2.050034 28.474924 270)
			(size 0.519938 1.4986)
			(layers "F.Cu" "F.Mask" "F.Paste")
			(net "GND")
		)
		(pad "104" smd rect
			(at -2.050034 29.325062 270)
			(size 0.519938 1.4986)
			(layers "F.Cu" "F.Mask" "F.Paste")
			(net "M_G_CPU1_SB_DQS_DP<0>")
		)
		(pad "105" smd rect
			(at -2.050034 30.174946 270)
			(size 0.519938 1.4986)
			(layers "F.Cu" "F.Mask" "F.Paste")
			(net "M_G_CPU1_SB_DQS_DN<0>")
		)
		(pad "106" smd rect
			(at -2.050034 31.025084 270)
			(size 0.519938 1.4986)
			(layers "F.Cu" "F.Mask" "F.Paste")
			(net "GND")
		)
		(pad "107" smd rect
			(at -2.050034 31.874968 270)
			(size 0.519938 1.4986)
			(layers "F.Cu" "F.Mask" "F.Paste")
			(net "M_G_CPU1_SB_DQ<4>")
		)
		(pad "108" smd rect
			(at -2.050034 32.725106 270)
			(size 0.519938 1.4986)
			(layers "F.Cu" "F.Mask" "F.Paste")
			(net "GND")
		)
		(pad "109" smd rect
			(at -2.050034 33.57499 270)
			(size 0.519938 1.4986)
			(layers "F.Cu" "F.Mask" "F.Paste")
			(net "M_G_CPU1_SB_DQ<5>")
		)
		(pad "110" smd rect
			(at -2.050034 34.425128 270)
			(size 0.519938 1.4986)
			(layers "F.Cu" "F.Mask" "F.Paste")
			(net "GND")
		)
		(pad "111" smd rect
			(at -2.050034 35.275012 270)
			(size 0.519938 1.4986)
			(layers "F.Cu" "F.Mask" "F.Paste")
			(net "M_G_CPU1_SB_DQ<8>")
		)
		(pad "112" smd rect
			(at -2.050034 36.124896 270)
			(size 0.519938 1.4986)
			(layers "F.Cu" "F.Mask" "F.Paste")
			(net "GND")
		)
		(pad "113" smd rect
			(at -2.050034 36.975034 270)
			(size 0.519938 1.4986)
			(layers "F.Cu" "F.Mask" "F.Paste")
			(net "M_G_CPU1_SB_DQ<9>")
		)
		(pad "114" smd rect
			(at -2.050034 37.824918 270)
			(size 0.519938 1.4986)
			(layers "F.Cu" "F.Mask" "F.Paste")
			(net "GND")
		)
		(pad "115" smd rect
			(at -2.050034 38.675056 270)
			(size 0.519938 1.4986)
			(layers "F.Cu" "F.Mask" "F.Paste")
			(net "M_G_CPU1_SB_DQS_DP<1>")
		)
		(pad "116" smd rect
			(at -2.050034 39.52494 270)
			(size 0.519938 1.4986)
			(layers "F.Cu" "F.Mask" "F.Paste")
			(net "M_G_CPU1_SB_DQS_DN<1>")
		)
		(pad "117" smd rect
			(at -2.050034 40.375078 270)
			(size 0.519938 1.4986)
			(layers "F.Cu" "F.Mask" "F.Paste")
			(net "GND")
		)
		(pad "118" smd rect
			(at -2.050034 41.224962 270)
			(size 0.519938 1.4986)
			(layers "F.Cu" "F.Mask" "F.Paste")
			(net "M_G_CPU1_SB_DQ<12>")
		)
		(pad "119" smd rect
			(at -2.050034 42.0751 270)
			(size 0.519938 1.4986)
			(layers "F.Cu" "F.Mask" "F.Paste")
			(net "GND")
		)
		(pad "120" smd rect
			(at -2.050034 42.924984 270)
			(size 0.519938 1.4986)
			(layers "F.Cu" "F.Mask" "F.Paste")
			(net "M_G_CPU1_SB_DQ<13>")
		)
		(pad "121" smd rect
			(at -2.050034 43.775122 270)
			(size 0.519938 1.4986)
			(layers "F.Cu" "F.Mask" "F.Paste")
			(net "GND")
		)
		(pad "122" smd rect
			(at -2.050034 44.625006 270)
			(size 0.519938 1.4986)
			(layers "F.Cu" "F.Mask" "F.Paste")
			(net "M_G_CPU1_SB_DQ<16>")
		)
		(pad "123" smd rect
			(at -2.050034 45.47489 270)
			(size 0.519938 1.4986)
			(layers "F.Cu" "F.Mask" "F.Paste")
			(net "GND")
		)
		(pad "124" smd rect
			(at -2.050034 46.325028 270)
			(size 0.519938 1.4986)
			(layers "F.Cu" "F.Mask" "F.Paste")
			(net "M_G_CPU1_SB_DQ<17>")
		)
		(pad "125" smd rect
			(at -2.050034 47.174912 270)
			(size 0.519938 1.4986)
			(layers "F.Cu" "F.Mask" "F.Paste")
			(net "GND")
		)
		(pad "126" smd rect
			(at -2.050034 48.02505 270)
			(size 0.519938 1.4986)
			(layers "F.Cu" "F.Mask" "F.Paste")
			(net "M_G_CPU1_SB_DQS_DP<2>")
		)
		(pad "127" smd rect
			(at -2.050034 48.874934 270)
			(size 0.519938 1.4986)
			(layers "F.Cu" "F.Mask" "F.Paste")
			(net "M_G_CPU1_SB_DQS_DN<2>")
		)
		(pad "128" smd rect
			(at -2.050034 49.725072 270)
			(size 0.519938 1.4986)
			(layers "F.Cu" "F.Mask" "F.Paste")
			(net "GND")
		)
		(pad "129" smd rect
			(at -2.050034 50.574956 270)
			(size 0.519938 1.4986)
			(layers "F.Cu" "F.Mask" "F.Paste")
			(net "M_G_CPU1_SB_DQ<20>")
		)
		(pad "130" smd rect
			(at -2.050034 51.425094 270)
			(size 0.519938 1.4986)
			(layers "F.Cu" "F.Mask" "F.Paste")
			(net "GND")
		)
		(pad "131" smd rect
			(at -2.050034 52.274978 270)
			(size 0.519938 1.4986)
			(layers "F.Cu" "F.Mask" "F.Paste")
			(net "M_G_CPU1_SB_DQ<21>")
		)
		(pad "132" smd rect
			(at -2.050034 53.125116 270)
			(size 0.519938 1.4986)
			(layers "F.Cu" "F.Mask" "F.Paste")
			(net "GND")
		)
		(pad "133" smd rect
			(at -2.050034 53.975 270)
			(size 0.519938 1.4986)
			(layers "F.Cu" "F.Mask" "F.Paste")
			(net "M_G_CPU1_SB_DQ<24>")
		)
		(pad "134" smd rect
			(at -2.050034 54.824884 270)
			(size 0.519938 1.4986)
			(layers "F.Cu" "F.Mask" "F.Paste")
			(net "GND")
		)
		(pad "135" smd rect
			(at -2.050034 55.675022 270)
			(size 0.519938 1.4986)
			(layers "F.Cu" "F.Mask" "F.Paste")
			(net "M_G_CPU1_SB_DQ<25>")
		)
		(pad "136" smd rect
			(at -2.050034 56.524906 270)
			(size 0.519938 1.4986)
			(layers "F.Cu" "F.Mask" "F.Paste")
			(net "GND")
		)
		(pad "137" smd rect
			(at -2.050034 57.375044 270)
			(size 0.519938 1.4986)
			(layers "F.Cu" "F.Mask" "F.Paste")
			(net "M_G_CPU1_SB_DQS_DP<3>")
		)
		(pad "138" smd rect
			(at -2.050034 58.224928 270)
			(size 0.519938 1.4986)
			(layers "F.Cu" "F.Mask" "F.Paste")
			(net "M_G_CPU1_SB_DQS_DN<3>")
		)
		(pad "139" smd rect
			(at -2.050034 59.075066 270)
			(size 0.519938 1.4986)
			(layers "F.Cu" "F.Mask" "F.Paste")
			(net "GND")
		)
		(pad "140" smd rect
			(at -2.050034 59.92495 270)
			(size 0.519938 1.4986)
			(layers "F.Cu" "F.Mask" "F.Paste")
			(net "M_G_CPU1_SB_DQ<28>")
		)
		(pad "141" smd rect
			(at -2.050034 60.775088 270)
			(size 0.519938 1.4986)
			(layers "F.Cu" "F.Mask" "F.Paste")
			(net "GND")
		)
		(pad "142" smd rect
			(at -2.050034 61.624972 270)
			(size 0.519938 1.4986)
			(layers "F.Cu" "F.Mask" "F.Paste")
			(net "M_G_CPU1_SB_DQ<29>")
		)
		(pad "143" smd rect
			(at -2.050034 62.47511 270)
			(size 0.519938 1.4986)
			(layers "F.Cu" "F.Mask" "F.Paste")
			(net "GND")
		)
		(pad "144" smd rect
			(at -2.050034 63.324994 270)
			(size 0.519938 1.4986)
			(layers "F.Cu" "F.Mask" "F.Paste")
			(net "TP_CHG_CPU1_DIMM2_FRU_1")
		)
		(pad "145" smd rect
			(at 2.050034 -63.324994 270)
			(size 0.519938 1.4986)
			(layers "F.Cu" "F.Mask" "F.Paste")
			(net "P12V_S3_AUX_CPU1_NVDIMM")
		)
		(pad "146" smd rect
			(at 2.050034 -62.47511 270)
			(size 0.519938 1.4986)
			(layers "F.Cu" "F.Mask" "F.Paste")
			(net "P12V_S3_AUX_CPU1_NVDIMM")
		)
		(pad "147" smd rect
			(at 2.050034 -61.624972 270)
			(size 0.519938 1.4986)
			(layers "F.Cu" "F.Mask" "F.Paste")
			(net "PWRGD_CHG_CPU1_DIMM2")
		)
		(pad "148" smd rect
			(at 2.050034 -60.775088 270)
			(size 0.519938 1.4986)
			(layers "F.Cu" "F.Mask" "F.Paste")
			(net "PD_CHG_CPU1_DIMM2_SAA")
		)
		(pad "149" smd rect
			(at 2.050034 -59.92495 270)
			(size 0.519938 1.4986)
			(layers "F.Cu" "F.Mask" "F.Paste")
			(net "TP_CHG_CPU1_DIMM2_FRU_2")
		)
		(pad "150" smd rect
			(at 2.050034 -59.075066 270)
			(size 0.519938 1.4986)
			(layers "F.Cu" "F.Mask" "F.Paste")
			(net "TP_CHG_CPU1_DIMM2_FRU_3")
		)
		(pad "151" smd rect
			(at 2.050034 -58.224928 270)
			(size 0.519938 1.4986)
			(layers "F.Cu" "F.Mask" "F.Paste")
			(net "GND")
		)
		(pad "152" smd rect
			(at 2.050034 -57.375044 270)
			(size 0.519938 1.4986)
			(layers "F.Cu" "F.Mask" "F.Paste")
			(net "M_G_CPU1_SA_DQ<2>")
		)
		(pad "153" smd rect
			(at 2.050034 -56.524906 270)
			(size 0.519938 1.4986)
			(layers "F.Cu" "F.Mask" "F.Paste")
			(net "GND")
		)
		(pad "154" smd rect
			(at 2.050034 -55.675022 270)
			(size 0.519938 1.4986)
			(layers "F.Cu" "F.Mask" "F.Paste")
			(net "M_G_CPU1_SA_DQ<3>")
		)
		(pad "155" smd rect
			(at 2.050034 -54.824884 270)
			(size 0.519938 1.4986)
			(layers "F.Cu" "F.Mask" "F.Paste")
			(net "GND")
		)
		(pad "156" smd rect
			(at 2.050034 -53.975 270)
			(size 0.519938 1.4986)
			(layers "F.Cu" "F.Mask" "F.Paste")
			(net "M_G_CPU1_SA_DQS_DN<5>")
		)
		(pad "157" smd rect
			(at 2.050034 -53.125116 270)
			(size 0.519938 1.4986)
			(layers "F.Cu" "F.Mask" "F.Paste")
			(net "M_G_CPU1_SA_DQS_DP<5>")
		)
		(pad "158" smd rect
			(at 2.050034 -52.274978 270)
			(size 0.519938 1.4986)
			(layers "F.Cu" "F.Mask" "F.Paste")
			(net "GND")
		)
		(pad "159" smd rect
			(at 2.050034 -51.425094 270)
			(size 0.519938 1.4986)
			(layers "F.Cu" "F.Mask" "F.Paste")
			(net "M_G_CPU1_SA_DQ<6>")
		)
		(pad "160" smd rect
			(at 2.050034 -50.574956 270)
			(size 0.519938 1.4986)
			(layers "F.Cu" "F.Mask" "F.Paste")
			(net "GND")
		)
		(pad "161" smd rect
			(at 2.050034 -49.725072 270)
			(size 0.519938 1.4986)
			(layers "F.Cu" "F.Mask" "F.Paste")
			(net "M_G_CPU1_SA_DQ<7>")
		)
		(pad "162" smd rect
			(at 2.050034 -48.874934 270)
			(size 0.519938 1.4986)
			(layers "F.Cu" "F.Mask" "F.Paste")
			(net "GND")
		)
		(pad "163" smd rect
			(at 2.050034 -48.02505 270)
			(size 0.519938 1.4986)
			(layers "F.Cu" "F.Mask" "F.Paste")
			(net "M_G_CPU1_SA_DQ<10>")
		)
		(pad "164" smd rect
			(at 2.050034 -47.174912 270)
			(size 0.519938 1.4986)
			(layers "F.Cu" "F.Mask" "F.Paste")
			(net "GND")
		)
		(pad "165" smd rect
			(at 2.050034 -46.325028 270)
			(size 0.519938 1.4986)
			(layers "F.Cu" "F.Mask" "F.Paste")
			(net "M_G_CPU1_SA_DQ<11>")
		)
		(pad "166" smd rect
			(at 2.050034 -45.47489 270)
			(size 0.519938 1.4986)
			(layers "F.Cu" "F.Mask" "F.Paste")
			(net "GND")
		)
		(pad "167" smd rect
			(at 2.050034 -44.625006 270)
			(size 0.519938 1.4986)
			(layers "F.Cu" "F.Mask" "F.Paste")
			(net "M_G_CPU1_SA_DQS_DN<6>")
		)
		(pad "168" smd rect
			(at 2.050034 -43.775122 270)
			(size 0.519938 1.4986)
			(layers "F.Cu" "F.Mask" "F.Paste")
			(net "M_G_CPU1_SA_DQS_DP<6>")
		)
		(pad "169" smd rect
			(at 2.050034 -42.924984 270)
			(size 0.519938 1.4986)
			(layers "F.Cu" "F.Mask" "F.Paste")
			(net "GND")
		)
		(pad "170" smd rect
			(at 2.050034 -42.0751 270)
			(size 0.519938 1.4986)
			(layers "F.Cu" "F.Mask" "F.Paste")
			(net "M_G_CPU1_SA_DQ<14>")
		)
		(pad "171" smd rect
			(at 2.050034 -41.224962 270)
			(size 0.519938 1.4986)
			(layers "F.Cu" "F.Mask" "F.Paste")
			(net "GND")
		)
		(pad "172" smd rect
			(at 2.050034 -40.375078 270)
			(size 0.519938 1.4986)
			(layers "F.Cu" "F.Mask" "F.Paste")
			(net "M_G_CPU1_SA_DQ<15>")
		)
		(pad "173" smd rect
			(at 2.050034 -39.52494 270)
			(size 0.519938 1.4986)
			(layers "F.Cu" "F.Mask" "F.Paste")
			(net "GND")
		)
		(pad "174" smd rect
			(at 2.050034 -38.675056 270)
			(size 0.519938 1.4986)
			(layers "F.Cu" "F.Mask" "F.Paste")
			(net "M_G_CPU1_SA_DQ<18>")
		)
		(pad "175" smd rect
			(at 2.050034 -37.824918 270)
			(size 0.519938 1.4986)
			(layers "F.Cu" "F.Mask" "F.Paste")
			(net "GND")
		)
		(pad "176" smd rect
			(at 2.050034 -36.975034 270)
			(size 0.519938 1.4986)
			(layers "F.Cu" "F.Mask" "F.Paste")
			(net "M_G_CPU1_SA_DQ<19>")
		)
		(pad "177" smd rect
			(at 2.050034 -36.124896 270)
			(size 0.519938 1.4986)
			(layers "F.Cu" "F.Mask" "F.Paste")
			(net "GND")
		)
		(pad "178" smd rect
			(at 2.050034 -35.275012 270)
			(size 0.519938 1.4986)
			(layers "F.Cu" "F.Mask" "F.Paste")
			(net "M_G_CPU1_SA_DQS_DN<7>")
		)
		(pad "179" smd rect
			(at 2.050034 -34.425128 270)
			(size 0.519938 1.4986)
			(layers "F.Cu" "F.Mask" "F.Paste")
			(net "M_G_CPU1_SA_DQS_DP<7>")
		)
		(pad "180" smd rect
			(at 2.050034 -33.57499 270)
			(size 0.519938 1.4986)
			(layers "F.Cu" "F.Mask" "F.Paste")
			(net "GND")
		)
		(pad "181" smd rect
			(at 2.050034 -32.725106 270)
			(size 0.519938 1.4986)
			(layers "F.Cu" "F.Mask" "F.Paste")
			(net "M_G_CPU1_SA_DQ<22>")
		)
		(pad "182" smd rect
			(at 2.050034 -31.874968 270)
			(size 0.519938 1.4986)
			(layers "F.Cu" "F.Mask" "F.Paste")
			(net "GND")
		)
		(pad "183" smd rect
			(at 2.050034 -31.025084 270)
			(size 0.519938 1.4986)
			(layers "F.Cu" "F.Mask" "F.Paste")
			(net "M_G_CPU1_SA_DQ<23>")
		)
		(pad "184" smd rect
			(at 2.050034 -30.174946 270)
			(size 0.519938 1.4986)
			(layers "F.Cu" "F.Mask" "F.Paste")
			(net "GND")
		)
		(pad "185" smd rect
			(at 2.050034 -29.325062 270)
			(size 0.519938 1.4986)
			(layers "F.Cu" "F.Mask" "F.Paste")
			(net "M_G_CPU1_SA_DQ<26>")
		)
		(pad "186" smd rect
			(at 2.050034 -28.474924 270)
			(size 0.519938 1.4986)
			(layers "F.Cu" "F.Mask" "F.Paste")
			(net "GND")
		)
		(pad "187" smd rect
			(at 2.050034 -27.62504 270)
			(size 0.519938 1.4986)
			(layers "F.Cu" "F.Mask" "F.Paste")
			(net "M_G_CPU1_SA_DQ<27>")
		)
		(pad "188" smd rect
			(at 2.050034 -26.774902 270)
			(size 0.519938 1.4986)
			(layers "F.Cu" "F.Mask" "F.Paste")
			(net "GND")
		)
		(pad "189" smd rect
			(at 2.050034 -25.925018 270)
			(size 0.519938 1.4986)
			(layers "F.Cu" "F.Mask" "F.Paste")
			(net "M_G_CPU1_SA_DQS_DN<8>")
		)
		(pad "190" smd rect
			(at 2.050034 -25.07488 270)
			(size 0.519938 1.4986)
			(layers "F.Cu" "F.Mask" "F.Paste")
			(net "M_G_CPU1_SA_DQS_DP<8>")
		)
		(pad "191" smd rect
			(at 2.050034 -24.224996 270)
			(size 0.519938 1.4986)
			(layers "F.Cu" "F.Mask" "F.Paste")
			(net "GND")
		)
		(pad "192" smd rect
			(at 2.050034 -23.375112 270)
			(size 0.519938 1.4986)
			(layers "F.Cu" "F.Mask" "F.Paste")
			(net "M_G_CPU1_SA_DQ<30>")
		)
		(pad "193" smd rect
			(at 2.050034 -22.524974 270)
			(size 0.519938 1.4986)
			(layers "F.Cu" "F.Mask" "F.Paste")
			(net "GND")
		)
		(pad "194" smd rect
			(at 2.050034 -21.67509 270)
			(size 0.519938 1.4986)
			(layers "F.Cu" "F.Mask" "F.Paste")
			(net "M_G_CPU1_SA_DQ<31>")
		)
		(pad "195" smd rect
			(at 2.050034 -20.824952 270)
			(size 0.519938 1.4986)
			(layers "F.Cu" "F.Mask" "F.Paste")
			(net "GND")
		)
		(pad "196" smd rect
			(at 2.050034 -19.975068 270)
			(size 0.519938 1.4986)
			(layers "F.Cu" "F.Mask" "F.Paste")
			(net "M_G_CPU1_SA_CB<2>")
		)
		(pad "197" smd rect
			(at 2.050034 -19.12493 270)
			(size 0.519938 1.4986)
			(layers "F.Cu" "F.Mask" "F.Paste")
			(net "GND")
		)
		(pad "198" smd rect
			(at 2.050034 -18.275046 270)
			(size 0.519938 1.4986)
			(layers "F.Cu" "F.Mask" "F.Paste")
			(net "M_G_CPU1_SA_CB<3>")
		)
		(pad "199" smd rect
			(at 2.050034 -17.424908 270)
			(size 0.519938 1.4986)
			(layers "F.Cu" "F.Mask" "F.Paste")
			(net "GND")
		)
		(pad "200" smd rect
			(at 2.050034 -16.575024 270)
			(size 0.519938 1.4986)
			(layers "F.Cu" "F.Mask" "F.Paste")
			(net "M_G_CPU1_SA_DQS_DN<9>")
		)
		(pad "201" smd rect
			(at 2.050034 -15.724886 270)
			(size 0.519938 1.4986)
			(layers "F.Cu" "F.Mask" "F.Paste")
			(net "M_G_CPU1_SA_DQS_DP<9>")
		)
		(pad "202" smd rect
			(at 2.050034 -14.875002 270)
			(size 0.519938 1.4986)
			(layers "F.Cu" "F.Mask" "F.Paste")
			(net "GND")
		)
		(pad "203" smd rect
			(at 2.050034 -14.025118 270)
			(size 0.519938 1.4986)
			(layers "F.Cu" "F.Mask" "F.Paste")
			(net "M_G_CPU1_SA_CB<6>")
		)
		(pad "204" smd rect
			(at 2.050034 -13.17498 270)
			(size 0.519938 1.4986)
			(layers "F.Cu" "F.Mask" "F.Paste")
			(net "GND")
		)
		(pad "205" smd rect
			(at 2.050034 -12.325096 270)
			(size 0.519938 1.4986)
			(layers "F.Cu" "F.Mask" "F.Paste")
			(net "M_G_CPU1_SA_CB<7>")
		)
		(pad "206" smd rect
			(at 2.050034 -11.474958 270)
			(size 0.519938 1.4986)
			(layers "F.Cu" "F.Mask" "F.Paste")
			(net "GND")
		)
		(pad "207" smd rect
			(at 2.050034 -10.625074 270)
			(size 0.519938 1.4986)
			(layers "F.Cu" "F.Mask" "F.Paste")
			(net "RST_M_GH_CPU1_FPGA_N")
		)
		(pad "208" smd rect
			(at 2.050034 -9.774936 270)
			(size 0.519938 1.4986)
			(layers "F.Cu" "F.Mask" "F.Paste")
			(net "GND")
		)
		(pad "209" smd rect
			(at 2.050034 -8.925052 270)
			(size 0.519938 1.4986)
			(layers "F.Cu" "F.Mask" "F.Paste")
			(net "M_G_CPU1_SA_CS_N<3>")
		)
		(pad "210" smd rect
			(at 2.050034 -8.074914 270)
			(size 0.519938 1.4986)
			(layers "F.Cu" "F.Mask" "F.Paste")
			(net "GND")
		)
		(pad "211" smd rect
			(at 2.050034 -7.22503 270)
			(size 0.519938 1.4986)
			(layers "F.Cu" "F.Mask" "F.Paste")
			(net "M_G_CPU1_SA_CA<1>")
		)
		(pad "212" smd rect
			(at 2.050034 -6.374892 270)
			(size 0.519938 1.4986)
			(layers "F.Cu" "F.Mask" "F.Paste")
			(net "GND")
		)
		(pad "213" smd rect
			(at 2.050034 -5.525008 270)
			(size 0.519938 1.4986)
			(layers "F.Cu" "F.Mask" "F.Paste")
			(net "M_G_CPU1_SA_CA<3>")
		)
		(pad "214" smd rect
			(at 2.050034 -4.675124 270)
			(size 0.519938 1.4986)
			(layers "F.Cu" "F.Mask" "F.Paste")
			(net "GND")
		)
		(pad "215" smd rect
			(at 2.050034 -3.824986 270)
			(size 0.519938 1.4986)
			(layers "F.Cu" "F.Mask" "F.Paste")
			(net "M_G_CPU1_SA_CA<5>")
		)
		(pad "216" smd rect
			(at 2.050034 -2.975102 270)
			(size 0.519938 1.4986)
			(layers "F.Cu" "F.Mask" "F.Paste")
			(net "GND")
		)
		(pad "217" smd rect
			(at 2.050034 -2.124964 270)
			(size 0.519938 1.4986)
			(layers "F.Cu" "F.Mask" "F.Paste")
			(net "M_G_CPU1_CLK_DP<1>")
		)
		(pad "218" smd rect
			(at 2.050034 -1.27508 270)
			(size 0.519938 1.4986)
			(layers "F.Cu" "F.Mask" "F.Paste")
			(net "M_G_CPU1_CLK_DN<1>")
		)
		(pad "219" smd rect
			(at 2.050034 -0.424942 270)
			(size 0.519938 1.4986)
			(layers "F.Cu" "F.Mask" "F.Paste")
			(net "GND")
		)
		(pad "220" smd rect
			(at 2.050034 5.525008 270)
			(size 0.519938 1.4986)
			(layers "F.Cu" "F.Mask" "F.Paste")
			(net "TP_CHG_CPU1_DIMM2_FRU_4")
		)
		(pad "221" smd rect
			(at 2.050034 6.374892 270)
			(size 0.519938 1.4986)
			(layers "F.Cu" "F.Mask" "F.Paste")
			(net "M_G_CPU1_SB_CA<1>")
		)
		(pad "222" smd rect
			(at 2.050034 7.22503 270)
			(size 0.519938 1.4986)
			(layers "F.Cu" "F.Mask" "F.Paste")
			(net "GND")
		)
		(pad "223" smd rect
			(at 2.050034 8.074914 270)
			(size 0.519938 1.4986)
			(layers "F.Cu" "F.Mask" "F.Paste")
			(net "M_G_CPU1_SB_CA<3>")
		)
		(pad "224" smd rect
			(at 2.050034 8.925052 270)
			(size 0.519938 1.4986)
			(layers "F.Cu" "F.Mask" "F.Paste")
			(net "GND")
		)
		(pad "225" smd rect
			(at 2.050034 9.774936 270)
			(size 0.519938 1.4986)
			(layers "F.Cu" "F.Mask" "F.Paste")
			(net "M_G_CPU1_SB_CA<5>")
		)
		(pad "226" smd rect
			(at 2.050034 10.625074 270)
			(size 0.519938 1.4986)
			(layers "F.Cu" "F.Mask" "F.Paste")
			(net "GND")
		)
		(pad "227" smd rect
			(at 2.050034 11.474958 270)
			(size 0.519938 1.4986)
			(layers "F.Cu" "F.Mask" "F.Paste")
			(net "M_G_CPU1_SB_PAR")
		)
		(pad "228" smd rect
			(at 2.050034 12.325096 270)
			(size 0.519938 1.4986)
			(layers "F.Cu" "F.Mask" "F.Paste")
			(net "GND")
		)
		(pad "229" smd rect
			(at 2.050034 13.17498 270)
			(size 0.519938 1.4986)
			(layers "F.Cu" "F.Mask" "F.Paste")
			(net "M_G_CPU1_SB_CS_N<3>")
		)
		(pad "230" smd rect
			(at 2.050034 14.025118 270)
			(size 0.519938 1.4986)
			(layers "F.Cu" "F.Mask" "F.Paste")
			(net "GND")
		)
		(pad "231" smd rect
			(at 2.050034 14.875002 270)
			(size 0.519938 1.4986)
			(layers "F.Cu" "F.Mask" "F.Paste")
			(net "TP_CHG_CPU1_DIMM2_FRU_5")
		)
		(pad "232" smd rect
			(at 2.050034 15.724886 270)
			(size 0.519938 1.4986)
			(layers "F.Cu" "F.Mask" "F.Paste")
			(net "TP_CHG_CPU1_DIMM2_FRU_6")
		)
		(pad "233" smd rect
			(at 2.050034 16.575024 270)
			(size 0.519938 1.4986)
			(layers "F.Cu" "F.Mask" "F.Paste")
			(net "GND")
		)
		(pad "234" smd rect
			(at 2.050034 17.424908 270)
			(size 0.519938 1.4986)
			(layers "F.Cu" "F.Mask" "F.Paste")
			(net "M_G_CPU1_SB_CB<6>")
		)
		(pad "235" smd rect
			(at 2.050034 18.275046 270)
			(size 0.519938 1.4986)
			(layers "F.Cu" "F.Mask" "F.Paste")
			(net "GND")
		)
		(pad "236" smd rect
			(at 2.050034 19.12493 270)
			(size 0.519938 1.4986)
			(layers "F.Cu" "F.Mask" "F.Paste")
			(net "M_G_CPU1_SB_CB<7>")
		)
		(pad "237" smd rect
			(at 2.050034 19.975068 270)
			(size 0.519938 1.4986)
			(layers "F.Cu" "F.Mask" "F.Paste")
			(net "GND")
		)
		(pad "238" smd rect
			(at 2.050034 20.824952 270)
			(size 0.519938 1.4986)
			(layers "F.Cu" "F.Mask" "F.Paste")
			(net "M_G_CPU1_SB_DQS_DN<4>")
		)
		(pad "239" smd rect
			(at 2.050034 21.67509 270)
			(size 0.519938 1.4986)
			(layers "F.Cu" "F.Mask" "F.Paste")
			(net "M_G_CPU1_SB_DQS_DP<4>")
		)
		(pad "240" smd rect
			(at 2.050034 22.524974 270)
			(size 0.519938 1.4986)
			(layers "F.Cu" "F.Mask" "F.Paste")
			(net "GND")
		)
		(pad "241" smd rect
			(at 2.050034 23.375112 270)
			(size 0.519938 1.4986)
			(layers "F.Cu" "F.Mask" "F.Paste")
			(net "M_G_CPU1_SB_CB<2>")
		)
		(pad "242" smd rect
			(at 2.050034 24.224996 270)
			(size 0.519938 1.4986)
			(layers "F.Cu" "F.Mask" "F.Paste")
			(net "GND")
		)
		(pad "243" smd rect
			(at 2.050034 25.07488 270)
			(size 0.519938 1.4986)
			(layers "F.Cu" "F.Mask" "F.Paste")
			(net "M_G_CPU1_SB_CB<3>")
		)
		(pad "244" smd rect
			(at 2.050034 25.925018 270)
			(size 0.519938 1.4986)
			(layers "F.Cu" "F.Mask" "F.Paste")
			(net "GND")
		)
		(pad "245" smd rect
			(at 2.050034 26.774902 270)
			(size 0.519938 1.4986)
			(layers "F.Cu" "F.Mask" "F.Paste")
			(net "M_G_CPU1_SB_DQ<2>")
		)
		(pad "246" smd rect
			(at 2.050034 27.62504 270)
			(size 0.519938 1.4986)
			(layers "F.Cu" "F.Mask" "F.Paste")
			(net "GND")
		)
		(pad "247" smd rect
			(at 2.050034 28.474924 270)
			(size 0.519938 1.4986)
			(layers "F.Cu" "F.Mask" "F.Paste")
			(net "M_G_CPU1_SB_DQ<3>")
		)
		(pad "248" smd rect
			(at 2.050034 29.325062 270)
			(size 0.519938 1.4986)
			(layers "F.Cu" "F.Mask" "F.Paste")
			(net "GND")
		)
		(pad "249" smd rect
			(at 2.050034 30.174946 270)
			(size 0.519938 1.4986)
			(layers "F.Cu" "F.Mask" "F.Paste")
			(net "M_G_CPU1_SB_DQS_DN<5>")
		)
		(pad "250" smd rect
			(at 2.050034 31.025084 270)
			(size 0.519938 1.4986)
			(layers "F.Cu" "F.Mask" "F.Paste")
			(net "M_G_CPU1_SB_DQS_DP<5>")
		)
		(pad "251" smd rect
			(at 2.050034 31.874968 270)
			(size 0.519938 1.4986)
			(layers "F.Cu" "F.Mask" "F.Paste")
			(net "GND")
		)
		(pad "252" smd rect
			(at 2.050034 32.725106 270)
			(size 0.519938 1.4986)
			(layers "F.Cu" "F.Mask" "F.Paste")
			(net "M_G_CPU1_SB_DQ<6>")
		)
		(pad "253" smd rect
			(at 2.050034 33.57499 270)
			(size 0.519938 1.4986)
			(layers "F.Cu" "F.Mask" "F.Paste")
			(net "GND")
		)
		(pad "254" smd rect
			(at 2.050034 34.425128 270)
			(size 0.519938 1.4986)
			(layers "F.Cu" "F.Mask" "F.Paste")
			(net "M_G_CPU1_SB_DQ<7>")
		)
		(pad "255" smd rect
			(at 2.050034 35.275012 270)
			(size 0.519938 1.4986)
			(layers "F.Cu" "F.Mask" "F.Paste")
			(net "GND")
		)
		(pad "256" smd rect
			(at 2.050034 36.124896 270)
			(size 0.519938 1.4986)
			(layers "F.Cu" "F.Mask" "F.Paste")
			(net "M_G_CPU1_SB_DQ<10>")
		)
		(pad "257" smd rect
			(at 2.050034 36.975034 270)
			(size 0.519938 1.4986)
			(layers "F.Cu" "F.Mask" "F.Paste")
			(net "GND")
		)
		(pad "258" smd rect
			(at 2.050034 37.824918 270)
			(size 0.519938 1.4986)
			(layers "F.Cu" "F.Mask" "F.Paste")
			(net "M_G_CPU1_SB_DQ<11>")
		)
		(pad "259" smd rect
			(at 2.050034 38.675056 270)
			(size 0.519938 1.4986)
			(layers "F.Cu" "F.Mask" "F.Paste")
			(net "GND")
		)
		(pad "260" smd rect
			(at 2.050034 39.52494 270)
			(size 0.519938 1.4986)
			(layers "F.Cu" "F.Mask" "F.Paste")
			(net "M_G_CPU1_SB_DQS_DN<6>")
		)
		(pad "261" smd rect
			(at 2.050034 40.375078 270)
			(size 0.519938 1.4986)
			(layers "F.Cu" "F.Mask" "F.Paste")
			(net "M_G_CPU1_SB_DQS_DP<6>")
		)
		(pad "262" smd rect
			(at 2.050034 41.224962 270)
			(size 0.519938 1.4986)
			(layers "F.Cu" "F.Mask" "F.Paste")
			(net "GND")
		)
		(pad "263" smd rect
			(at 2.050034 42.0751 270)
			(size 0.519938 1.4986)
			(layers "F.Cu" "F.Mask" "F.Paste")
			(net "M_G_CPU1_SB_DQ<14>")
		)
		(pad "264" smd rect
			(at 2.050034 42.924984 270)
			(size 0.519938 1.4986)
			(layers "F.Cu" "F.Mask" "F.Paste")
			(net "GND")
		)
		(pad "265" smd rect
			(at 2.050034 43.775122 270)
			(size 0.519938 1.4986)
			(layers "F.Cu" "F.Mask" "F.Paste")
			(net "M_G_CPU1_SB_DQ<15>")
		)
		(pad "266" smd rect
			(at 2.050034 44.625006 270)
			(size 0.519938 1.4986)
			(layers "F.Cu" "F.Mask" "F.Paste")
			(net "GND")
		)
		(pad "267" smd rect
			(at 2.050034 45.47489 270)
			(size 0.519938 1.4986)
			(layers "F.Cu" "F.Mask" "F.Paste")
			(net "M_G_CPU1_SB_DQ<18>")
		)
		(pad "268" smd rect
			(at 2.050034 46.325028 270)
			(size 0.519938 1.4986)
			(layers "F.Cu" "F.Mask" "F.Paste")
			(net "GND")
		)
		(pad "269" smd rect
			(at 2.050034 47.174912 270)
			(size 0.519938 1.4986)
			(layers "F.Cu" "F.Mask" "F.Paste")
			(net "M_G_CPU1_SB_DQ<19>")
		)
		(pad "270" smd rect
			(at 2.050034 48.02505 270)
			(size 0.519938 1.4986)
			(layers "F.Cu" "F.Mask" "F.Paste")
			(net "GND")
		)
		(pad "271" smd rect
			(at 2.050034 48.874934 270)
			(size 0.519938 1.4986)
			(layers "F.Cu" "F.Mask" "F.Paste")
			(net "M_G_CPU1_SB_DQS_DN<7>")
		)
		(pad "272" smd rect
			(at 2.050034 49.725072 270)
			(size 0.519938 1.4986)
			(layers "F.Cu" "F.Mask" "F.Paste")
			(net "M_G_CPU1_SB_DQS_DP<7>")
		)
		(pad "273" smd rect
			(at 2.050034 50.574956 270)
			(size 0.519938 1.4986)
			(layers "F.Cu" "F.Mask" "F.Paste")
			(net "GND")
		)
		(pad "274" smd rect
			(at 2.050034 51.425094 270)
			(size 0.519938 1.4986)
			(layers "F.Cu" "F.Mask" "F.Paste")
			(net "M_G_CPU1_SB_DQ<22>")
		)
		(pad "275" smd rect
			(at 2.050034 52.274978 270)
			(size 0.519938 1.4986)
			(layers "F.Cu" "F.Mask" "F.Paste")
			(net "GND")
		)
		(pad "276" smd rect
			(at 2.050034 53.125116 270)
			(size 0.519938 1.4986)
			(layers "F.Cu" "F.Mask" "F.Paste")
			(net "M_G_CPU1_SB_DQ<23>")
		)
		(pad "277" smd rect
			(at 2.050034 53.975 270)
			(size 0.519938 1.4986)
			(layers "F.Cu" "F.Mask" "F.Paste")
			(net "GND")
		)
		(pad "278" smd rect
			(at 2.050034 54.824884 270)
			(size 0.519938 1.4986)
			(layers "F.Cu" "F.Mask" "F.Paste")
			(net "M_G_CPU1_SB_DQ<26>")
		)
		(pad "279" smd rect
			(at 2.050034 55.675022 270)
			(size 0.519938 1.4986)
			(layers "F.Cu" "F.Mask" "F.Paste")
			(net "GND")
		)
		(pad "280" smd rect
			(at 2.050034 56.524906 270)
			(size 0.519938 1.4986)
			(layers "F.Cu" "F.Mask" "F.Paste")
			(net "M_G_CPU1_SB_DQ<27>")
		)
		(pad "281" smd rect
			(at 2.050034 57.375044 270)
			(size 0.519938 1.4986)
			(layers "F.Cu" "F.Mask" "F.Paste")
			(net "GND")
		)
		(pad "282" smd rect
			(at 2.050034 58.224928 270)
			(size 0.519938 1.4986)
			(layers "F.Cu" "F.Mask" "F.Paste")
			(net "M_G_CPU1_SB_DQS_DN<8>")
		)
		(pad "283" smd rect
			(at 2.050034 59.075066 270)
			(size 0.519938 1.4986)
			(layers "F.Cu" "F.Mask" "F.Paste")
			(net "M_G_CPU1_SB_DQS_DP<8>")
		)
		(pad "284" smd rect
			(at 2.050034 59.92495 270)
			(size 0.519938 1.4986)
			(layers "F.Cu" "F.Mask" "F.Paste")
			(net "GND")
		)
		(pad "285" smd rect
			(at 2.050034 60.775088 270)
			(size 0.519938 1.4986)
			(layers "F.Cu" "F.Mask" "F.Paste")
			(net "M_G_CPU1_SB_DQ<30>")
		)
		(pad "286" smd rect
			(at 2.050034 61.624972 270)
			(size 0.519938 1.4986)
			(layers "F.Cu" "F.Mask" "F.Paste")
			(net "GND")
		)
		(pad "287" smd rect
			(at 2.050034 62.47511 270)
			(size 0.519938 1.4986)
			(layers "F.Cu" "F.Mask" "F.Paste")
			(net "M_G_CPU1_SB_DQ<31>")
		)
		(pad "288" smd rect
			(at 2.050034 63.324994 270)
			(size 0.519938 1.4986)
			(layers "F.Cu" "F.Mask" "F.Paste")
			(net "GND")
		)
		(pad "G1" thru_hole oval
			(at 0 -68.97497)
			(size 2.8194 1.5748)
			(drill oval 2.4384 1.1938)
			(layers "*.Cu" "*.Mask")
			(remove_unused_layers no)
			(net "GND")
			(clearance 0.127)
			(thermal_gap 0.127)
		)
		(pad "G2" thru_hole oval
			(at 0 3.875024)
			(size 2.8194 1.5748)
			(drill oval 2.4384 1.1938)
			(layers "*.Cu" "*.Mask")
			(remove_unused_layers no)
			(net "GND")
			(clearance 0.127)
			(thermal_gap 0.127)
		)
		(pad "G3" thru_hole oval
			(at 0 68.97497)
			(size 2.8194 1.5748)
			(drill oval 2.4384 1.1938)
			(layers "*.Cu" "*.Mask")
			(remove_unused_layers no)
			(net "GND")
			(clearance 0.127)
			(thermal_gap 0.127)
		)
	)
	(footprint ""
		(layer "F.Cu")
		(at 83.566508 -74.901552 -90)
		(property "Reference" "R3086"
			(at 0 0 270)
			(layer "F.SilkS")
			(hide yes)
			(effects
				(font
					(size 1.27 1.27)
				)
			)
		)
		(property "Value" ""
			(at 0 0 270)
			(layer "F.Fab")
			(effects
				(font
					(size 1.27 1.27)
				)
			)
		)
		(duplicate_pad_numbers_are_jumpers no)
		(fp_line
			(start -0.7874 0.4064)
			(end -0.7874 -0.4064)
			(stroke
				(width 0.1524)
				(type default)
			)
			(layer "F.SilkS")
		)
		(fp_line
			(start 0.7874 0.4064)
			(end -0.7874 0.4064)
			(stroke
				(width 0.1524)
				(type default)
			)
			(layer "F.SilkS")
		)
		(fp_line
			(start -0.7874 -0.4064)
			(end 0.7874 -0.4064)
			(stroke
				(width 0.1524)
				(type default)
			)
			(layer "F.SilkS")
		)
		(fp_line
			(start 0.7874 -0.4064)
			(end 0.7874 0.4064)
			(stroke
				(width 0.1524)
				(type default)
			)
			(layer "F.SilkS")
		)
		(fp_line
			(start -0.67945 0.3048)
			(end -0.67945 -0.305054)
			(stroke
				(width 0.1)
				(type default)
			)
			(layer "F.Fab")
		)
		(fp_line
			(start -0.12065 0.3048)
			(end -0.67945 0.3048)
			(stroke
				(width 0.1)
				(type default)
			)
			(layer "F.Fab")
		)
		(fp_line
			(start 0.120396 0.3048)
			(end 0.120396 0.2794)
			(stroke
				(width 0.1)
				(type default)
			)
			(layer "F.Fab")
		)
		(fp_line
			(start 0.67945 0.3048)
			(end 0.120396 0.3048)
			(stroke
				(width 0.1)
				(type default)
			)
			(layer "F.Fab")
		)
		(fp_line
			(start -0.12065 0.2794)
			(end -0.12065 0.3048)
			(stroke
				(width 0.1)
				(type default)
			)
			(layer "F.Fab")
		)
		(fp_line
			(start 0.120396 0.2794)
			(end -0.12065 0.2794)
			(stroke
				(width 0.1)
				(type default)
			)
			(layer "F.Fab")
		)
		(fp_line
			(start -0.12065 -0.2794)
			(end 0.12065 -0.2794)
			(stroke
				(width 0.1)
				(type default)
			)
			(layer "F.Fab")
		)
		(fp_line
			(start 0.12065 -0.2794)
			(end 0.12065 -0.3048)
			(stroke
				(width 0.1)
				(type default)
			)
			(layer "F.Fab")
		)
		(fp_line
			(start 0.12065 -0.3048)
			(end 0.67945 -0.3048)
			(stroke
				(width 0.1)
				(type default)
			)
			(layer "F.Fab")
		)
		(fp_line
			(start 0.67945 -0.3048)
			(end 0.67945 0.3048)
			(stroke
				(width 0.1)
				(type default)
			)
			(layer "F.Fab")
		)
		(fp_line
			(start -0.67945 -0.305054)
			(end -0.12065 -0.305054)
			(stroke
				(width 0.1)
				(type default)
			)
			(layer "F.Fab")
		)
		(fp_line
			(start -0.12065 -0.305054)
			(end -0.12065 -0.2794)
			(stroke
				(width 0.1)
				(type default)
			)
			(layer "F.Fab")
		)
		(pad "1" smd circle
			(at -0.40005 0 270)
			(size 0 0)
			(layers "F.Cu" "F.Mask" "F.Paste")
			(net "LED_PWRGD_PVCCD_HV_CPU0")
		)
		(pad "2" smd circle
			(at 0.40005 0 270)
			(size 0 0)
			(layers "F.Cu" "F.Mask" "F.Paste")
			(net "P3V3_AUX")
		)
	)
	(footprint ""
		(layer "F.Cu")
		(at 194.35064 -71.836788 90)
		(property "Reference" "PC2200"
			(at 0 0 90)
			(layer "F.SilkS")
			(hide yes)
			(effects
				(font
					(size 1.27 1.27)
				)
			)
		)
		(property "Value" ""
			(at 0 0 90)
			(layer "F.Fab")
			(effects
				(font
					(size 1.27 1.27)
				)
			)
		)
		(duplicate_pad_numbers_are_jumpers no)
		(fp_line
			(start 0.7874 -0.4064)
			(end 0.7874 0.4064)
			(stroke
				(width 0.1524)
				(type default)
			)
			(layer "F.SilkS")
		)
		(fp_line
			(start -0.7874 -0.4064)
			(end 0.7874 -0.4064)
			(stroke
				(width 0.1524)
				(type default)
			)
			(layer "F.SilkS")
		)
		(fp_line
			(start 0.7874 0.4064)
			(end -0.7874 0.4064)
			(stroke
				(width 0.1524)
				(type default)
			)
			(layer "F.SilkS")
		)
		(fp_line
			(start -0.7874 0.4064)
			(end -0.7874 -0.4064)
			(stroke
				(width 0.1524)
				(type default)
			)
			(layer "F.SilkS")
		)
		(fp_line
			(start -0.12065 -0.305054)
			(end -0.12065 -0.2794)
			(stroke
				(width 0.1)
				(type default)
			)
			(layer "F.Fab")
		)
		(fp_line
			(start -0.67945 -0.305054)
			(end -0.12065 -0.305054)
			(stroke
				(width 0.1)
				(type default)
			)
			(layer "F.Fab")
		)
		(fp_line
			(start 0.67945 -0.3048)
			(end 0.67945 0.3048)
			(stroke
				(width 0.1)
				(type default)
			)
			(layer "F.Fab")
		)
		(fp_line
			(start 0.12065 -0.3048)
			(end 0.67945 -0.3048)
			(stroke
				(width 0.1)
				(type default)
			)
			(layer "F.Fab")
		)
		(fp_line
			(start 0.12065 -0.2794)
			(end 0.12065 -0.3048)
			(stroke
				(width 0.1)
				(type default)
			)
			(layer "F.Fab")
		)
		(fp_line
			(start -0.12065 -0.2794)
			(end 0.12065 -0.2794)
			(stroke
				(width 0.1)
				(type default)
			)
			(layer "F.Fab")
		)
		(fp_line
			(start 0.120396 0.2794)
			(end -0.12065 0.2794)
			(stroke
				(width 0.1)
				(type default)
			)
			(layer "F.Fab")
		)
		(fp_line
			(start -0.12065 0.2794)
			(end -0.12065 0.3048)
			(stroke
				(width 0.1)
				(type default)
			)
			(layer "F.Fab")
		)
		(fp_line
			(start 0.67945 0.3048)
			(end 0.120396 0.3048)
			(stroke
				(width 0.1)
				(type default)
			)
			(layer "F.Fab")
		)
		(fp_line
			(start 0.120396 0.3048)
			(end 0.120396 0.2794)
			(stroke
				(width 0.1)
				(type default)
			)
			(layer "F.Fab")
		)
		(fp_line
			(start -0.12065 0.3048)
			(end -0.67945 0.3048)
			(stroke
				(width 0.1)
				(type default)
			)
			(layer "F.Fab")
		)
		(fp_line
			(start -0.67945 0.3048)
			(end -0.67945 -0.305054)
			(stroke
				(width 0.1)
				(type default)
			)
			(layer "F.Fab")
		)
		(pad "1" smd circle
			(at -0.40005 0 90)
			(size 0 0)
			(layers "F.Cu" "F.Mask" "F.Paste")
			(net "P3V3_AUX")
		)
		(pad "2" smd circle
			(at 0.40005 0 90)
			(size 0 0)
			(layers "F.Cu" "F.Mask" "F.Paste")
			(net "GND")
		)
	)
	(footprint ""
		(layer "F.Cu")
		(at 172.024294 -353.554284)
		(property "Reference" "PU75_P1_1"
			(at -2.245614 -6.277356 0)
			(unlocked yes)
			(layer "F.SilkS")
			(effects
				(font
					(size 0.7874 0.5842)
					(thickness 0.1524)
				)
				(justify left)
			)
		)
		(property "Value" ""
			(at 0 0 0)
			(layer "F.Fab")
			(effects
				(font
					(size 1.27 1.27)
				)
			)
		)
		(duplicate_pad_numbers_are_jumpers no)
		(fp_line
			(start -2.500122 -2.999994)
			(end -2.24409 -2.999994)
			(stroke
				(width 0.1524)
				(type default)
			)
			(layer "F.SilkS")
		)
		(fp_line
			(start -2.500122 -2.529078)
			(end -2.500122 -2.999994)
			(stroke
				(width 0.1524)
				(type default)
			)
			(layer "F.SilkS")
		)
		(fp_line
			(start -2.500122 0.6604)
			(end -2.500122 0.229108)
			(stroke
				(width 0.1524)
				(type default)
			)
			(layer "F.SilkS")
		)
		(fp_line
			(start -2.500122 2.999994)
			(end -2.500122 2.339594)
			(stroke
				(width 0.1524)
				(type default)
			)
			(layer "F.SilkS")
		)
		(fp_line
			(start -2.2987 2.999994)
			(end -2.500122 2.999994)
			(stroke
				(width 0.1524)
				(type default)
			)
			(layer "F.SilkS")
		)
		(fp_line
			(start 2.31394 -2.999994)
			(end 2.500122 -2.999994)
			(stroke
				(width 0.1524)
				(type default)
			)
			(layer "F.SilkS")
		)
		(fp_line
			(start 2.500122 -2.999994)
			(end 2.500122 -2.44348)
			(stroke
				(width 0.1524)
				(type default)
			)
			(layer "F.SilkS")
		)
		(fp_line
			(start 2.500122 2.339594)
			(end 2.500122 2.999994)
			(stroke
				(width 0.1524)
				(type default)
			)
			(layer "F.SilkS")
		)
		(fp_line
			(start 2.500122 2.999994)
			(end 2.2987 2.999994)
			(stroke
				(width 0.1524)
				(type default)
			)
			(layer "F.SilkS")
		)
		(fp_poly
			(pts
				(xy -5.275072 -2.780538) (xy -4.259072 -2.272538) (xy -5.275072 -1.764538)
			)
			(stroke
				(width 0)
				(type default)
			)
			(fill yes)
			(layer "F.SilkS")
		)
		(fp_line
			(start -2.500122 -2.999994)
			(end 2.500122 -2.999994)
			(stroke
				(width 0.1)
				(type default)
			)
			(layer "F.Fab")
		)
		(fp_line
			(start -2.500122 2.999994)
			(end -2.500122 -2.999994)
			(stroke
				(width 0.1)
				(type default)
			)
			(layer "F.Fab")
		)
		(fp_line
			(start 2.500122 -2.999994)
			(end 2.500122 2.999994)
			(stroke
				(width 0.1)
				(type default)
			)
			(layer "F.Fab")
		)
		(fp_line
			(start 2.500122 2.999994)
			(end -2.500122 2.999994)
			(stroke
				(width 0.1)
				(type default)
			)
			(layer "F.Fab")
		)
		(fp_poly
			(pts
				(xy -4.218432 -2.783078) (xy -4.218432 -1.767078) (xy -3.202432 -2.275078)
			)
			(stroke
				(width 0)
				(type default)
			)
			(fill yes)
			(layer "F.Fab")
		)
		(pad "1" smd rect
			(at -2.400046 -2.275078 90)
			(size 0.2286 0.6096)
			(layers "F.Cu" "F.Mask" "F.Paste")
			(net "PVCCFA_EHV_FIVRA_CPU1_VOS1")
		)
		(pad "2" smd rect
			(at -2.400046 -1.82499 90)
			(size 0.2286 0.6096)
			(layers "F.Cu" "F.Mask" "F.Paste")
			(net "GND")
		)
		(pad "3" smd rect
			(at -2.400046 -1.374902 90)
			(size 0.2286 0.6096)
			(layers "F.Cu" "F.Mask" "F.Paste")
			(net "PVCCFA_EHV_FIVRA_CPU1_VDD1")
		)
		(pad "4" smd rect
			(at -2.400046 -0.925068 90)
			(size 0.2286 0.6096)
			(layers "F.Cu" "F.Mask" "F.Paste")
			(net "PVCCFA_EHV_FIVRA_CPU1_PVCC1")
		)
		(pad "5" smd rect
			(at -2.400046 -0.47498 90)
			(size 0.2286 0.6096)
			(layers "F.Cu" "F.Mask" "F.Paste")
			(net "GND")
		)
		(pad "6" smd rect
			(at -2.400046 -0.024892 90)
			(size 0.2286 0.6096)
			(layers "F.Cu" "F.Mask" "F.Paste")
			(net "Net_8505")
		)
		(pad "7_9-20_24" smd circle
			(at 0 1.150112 90)
			(size 0 0)
			(layers "F.Cu" "F.Mask" "F.Paste")
			(net "GND")
		)
		(pad "10_19" smd rect
			(at 0 2.899918 90)
			(size 0.6096 4.318)
			(layers "F.Cu" "F.Mask" "F.Paste")
			(net "SW_PVCCFA_EHV_FIVRA_CPU1_SW1")
		)
		(pad "25_29" smd rect
			(at 1.549908 -1.279906 270)
			(size 2.0574 2.3114)
			(layers "F.Cu" "F.Mask" "F.Paste")
			(net "SW_P12V_PVCCFA_EHV_FIVRA_CPU1_R")
		)
		(pad "30" smd rect
			(at 2.05994 -2.899918)
			(size 0.2286 0.6096)
			(layers "F.Cu" "F.Mask" "F.Paste")
			(net "SW_P12V_PVCCFA_EHV_FIVRA_CPU1_R")
		)
		(pad "31" smd rect
			(at 1.610106 -2.899918)
			(size 0.2286 0.6096)
			(layers "F.Cu" "F.Mask" "F.Paste")
			(net "Net_8506")
		)
		(pad "32" smd rect
			(at 1.160018 -2.899918)
			(size 0.2286 0.6096)
			(layers "F.Cu" "F.Mask" "F.Paste")
			(net "SW_PVCCFA_EHV_FIVRA_CPU1_BOOTR1")
		)
		(pad "33" smd rect
			(at 0.70993 -2.899918)
			(size 0.2286 0.6096)
			(layers "F.Cu" "F.Mask" "F.Paste")
			(net "SW_PVCCFA_EHV_FIVRA_CPU1_BOOT1")
		)
		(pad "34" smd rect
			(at 0.260096 -2.899918)
			(size 0.2286 0.6096)
			(layers "F.Cu" "F.Mask" "F.Paste")
			(net "PVCCFA_EHV_FIVRA_CPU1_PWM1")
		)
		(pad "35" smd rect
			(at -0.189992 -2.899918)
			(size 0.2286 0.6096)
			(layers "F.Cu" "F.Mask" "F.Paste")
			(net "PVCCFA_EHV_FIVRA_CPU1_VDD1")
		)
		(pad "36" smd rect
			(at -0.64008 -2.899918)
			(size 0.2286 0.6096)
			(layers "F.Cu" "F.Mask" "F.Paste")
			(net "PVCCFA_EHV_FIVRA_CPU1_BTSEN")
		)
		(pad "37" smd rect
			(at -1.089914 -2.899918)
			(size 0.2286 0.6096)
			(layers "F.Cu" "F.Mask" "F.Paste")
			(net "PVCCFA_EHV_FIVRA_CPU1_LSET1")
		)
		(pad "38" smd rect
			(at -1.540002 -2.899918)
			(size 0.2286 0.6096)
			(layers "F.Cu" "F.Mask" "F.Paste")
			(net "PVCCFA_EHV_FIVRA_CPU1_IMON1")
		)
		(pad "39" smd rect
			(at -1.99009 -2.899918)
			(size 0.2286 0.6096)
			(layers "F.Cu" "F.Mask" "F.Paste")
			(net "PVCCIN_CPU1_VREF")
		)
		(pad "40" smd rect
			(at -0.87503 -1.27508)
			(size 1.7526 1.9558)
			(layers "F.Cu" "F.Mask" "F.Paste")
			(net "GND")
		)
		(pad "41" smd rect
			(at -1.525016 0.249936 270)
			(size 0.3048 0.4572)
			(layers "F.Cu" "F.Mask" "F.Paste")
			(net "Net_8504")
		)
		(zone
			(layer "F.Cu")
			(hatch none 0.5)
			(connect_pads
				(clearance 0)
			)
			(min_thickness 0.25)
			(keepout
				(tracks not_allowed)
				(vias allowed)
				(pads allowed)
				(copperpour not_allowed)
				(footprints allowed)
			)
			(placement
				(enabled no)
				(sheetname "")
			)
			(fill
				(thermal_gap 0.5)
				(thermal_bridge_width 0.5)
				(island_removal_mode 0)
			)
			(polygon
				(pts
					(xy 169.524172 -350.55429) (xy 169.524172 -351.285048) (xy 174.524416 -351.285048) (xy 174.524416 -350.55429)
					(xy 174.234094 -350.55429) (xy 174.234094 -351.009966) (xy 169.814494 -351.009966) (xy 169.814494 -350.55429)
				)
			)
		)
		(zone
			(layer "F.Cu")
			(hatch none 0.5)
			(connect_pads
				(clearance 0)
			)
			(min_thickness 0.25)
			(keepout
				(tracks not_allowed)
				(vias allowed)
				(pads allowed)
				(copperpour not_allowed)
				(footprints allowed)
			)
			(placement
				(enabled no)
				(sheetname "")
			)
			(fill
				(thermal_gap 0.5)
				(thermal_bridge_width 0.5)
				(island_removal_mode 0)
			)
			(polygon
				(pts
					(xy 170.26636 -353.800664) (xy 171.03344 -353.800664) (xy 171.03344 -353.471988) (xy 171.073572 -353.471988)
					(xy 171.073572 -352.859848) (xy 171.018708 -352.804984) (xy 169.524172 -352.804984) (xy 169.524172 -353.261676)
					(xy 170.219878 -353.261676) (xy 170.219878 -353.101148) (xy 170.778678 -353.101148) (xy 170.778678 -353.507548)
					(xy 170.219878 -353.507548) (xy 170.219878 -353.287076) (xy 169.524172 -353.287076) (xy 169.524172 -353.414076)
					(xy 169.979848 -353.414076) (xy 169.979848 -353.786948) (xy 170.26636 -353.786948)
				)
			)
		)
	)
	(footprint ""
		(layer "F.Cu")
		(at 80.384396 -57.977532 180)
		(property "Reference" "PR3829"
			(at 0 0 180)
			(layer "F.SilkS")
			(hide yes)
			(effects
				(font
					(size 1.27 1.27)
				)
			)
		)
		(property "Value" ""
			(at 0 0 180)
			(layer "F.Fab")
			(effects
				(font
					(size 1.27 1.27)
				)
			)
		)
		(duplicate_pad_numbers_are_jumpers no)
		(fp_line
			(start 0.7874 0.4064)
			(end -0.7874 0.4064)
			(stroke
				(width 0.1524)
				(type default)
			)
			(layer "F.SilkS")
		)
		(fp_line
			(start 0.7874 -0.4064)
			(end 0.7874 0.4064)
			(stroke
				(width 0.1524)
				(type default)
			)
			(layer "F.SilkS")
		)
		(fp_line
			(start -0.7874 0.4064)
			(end -0.7874 -0.4064)
			(stroke
				(width 0.1524)
				(type default)
			)
			(layer "F.SilkS")
		)
		(fp_line
			(start -0.7874 -0.4064)
			(end 0.7874 -0.4064)
			(stroke
				(width 0.1524)
				(type default)
			)
			(layer "F.SilkS")
		)
		(fp_line
			(start 0.67945 0.3048)
			(end 0.120396 0.3048)
			(stroke
				(width 0.1)
				(type default)
			)
			(layer "F.Fab")
		)
		(fp_line
			(start 0.67945 -0.3048)
			(end 0.67945 0.3048)
			(stroke
				(width 0.1)
				(type default)
			)
			(layer "F.Fab")
		)
		(fp_line
			(start 0.12065 -0.2794)
			(end 0.12065 -0.3048)
			(stroke
				(width 0.1)
				(type default)
			)
			(layer "F.Fab")
		)
		(fp_line
			(start 0.12065 -0.3048)
			(end 0.67945 -0.3048)
			(stroke
				(width 0.1)
				(type default)
			)
			(layer "F.Fab")
		)
		(fp_line
			(start 0.120396 0.3048)
			(end 0.120396 0.2794)
			(stroke
				(width 0.1)
				(type default)
			)
			(layer "F.Fab")
		)
		(fp_line
			(start 0.120396 0.2794)
			(end -0.12065 0.2794)
			(stroke
				(width 0.1)
				(type default)
			)
			(layer "F.Fab")
		)
		(fp_line
			(start -0.12065 0.3048)
			(end -0.67945 0.3048)
			(stroke
				(width 0.1)
				(type default)
			)
			(layer "F.Fab")
		)
		(fp_line
			(start -0.12065 0.2794)
			(end -0.12065 0.3048)
			(stroke
				(width 0.1)
				(type default)
			)
			(layer "F.Fab")
		)
		(fp_line
			(start -0.12065 -0.2794)
			(end 0.12065 -0.2794)
			(stroke
				(width 0.1)
				(type default)
			)
			(layer "F.Fab")
		)
		(fp_line
			(start -0.12065 -0.305054)
			(end -0.12065 -0.2794)
			(stroke
				(width 0.1)
				(type default)
			)
			(layer "F.Fab")
		)
		(fp_line
			(start -0.67945 0.3048)
			(end -0.67945 -0.305054)
			(stroke
				(width 0.1)
				(type default)
			)
			(layer "F.Fab")
		)
		(fp_line
			(start -0.67945 -0.305054)
			(end -0.12065 -0.305054)
			(stroke
				(width 0.1)
				(type default)
			)
			(layer "F.Fab")
		)
		(pad "1" smd circle
			(at -0.40005 0 180)
			(size 0 0)
			(layers "F.Cu" "F.Mask" "F.Paste")
			(net "P3V3_OCP_UV_2")
		)
		(pad "2" smd circle
			(at 0.40005 0 180)
			(size 0 0)
			(layers "F.Cu" "F.Mask" "F.Paste")
			(net "P3V3_OCP_OV_2")
		)
	)
	(footprint ""
		(layer "F.Cu")
		(at 438.277 -96.357948 90)
		(property "Reference" "C2015"
			(at 0 0 90)
			(layer "F.SilkS")
			(hide yes)
			(effects
				(font
					(size 1.27 1.27)
				)
			)
		)
		(property "Value" ""
			(at 0 0 90)
			(layer "F.Fab")
			(effects
				(font
					(size 1.27 1.27)
				)
			)
		)
		(duplicate_pad_numbers_are_jumpers no)
		(fp_line
			(start 0.7874 -0.4064)
			(end 0.7874 0.4064)
			(stroke
				(width 0.1524)
				(type default)
			)
			(layer "F.SilkS")
		)
		(fp_line
			(start -0.7874 -0.4064)
			(end 0.7874 -0.4064)
			(stroke
				(width 0.1524)
				(type default)
			)
			(layer "F.SilkS")
		)
		(fp_line
			(start 0.7874 0.4064)
			(end -0.7874 0.4064)
			(stroke
				(width 0.1524)
				(type default)
			)
			(layer "F.SilkS")
		)
		(fp_line
			(start -0.7874 0.4064)
			(end -0.7874 -0.4064)
			(stroke
				(width 0.1524)
				(type default)
			)
			(layer "F.SilkS")
		)
		(fp_line
			(start -0.12065 -0.305054)
			(end -0.12065 -0.2794)
			(stroke
				(width 0.1)
				(type default)
			)
			(layer "F.Fab")
		)
		(fp_line
			(start -0.67945 -0.305054)
			(end -0.12065 -0.305054)
			(stroke
				(width 0.1)
				(type default)
			)
			(layer "F.Fab")
		)
		(fp_line
			(start 0.67945 -0.3048)
			(end 0.67945 0.3048)
			(stroke
				(width 0.1)
				(type default)
			)
			(layer "F.Fab")
		)
		(fp_line
			(start 0.12065 -0.3048)
			(end 0.67945 -0.3048)
			(stroke
				(width 0.1)
				(type default)
			)
			(layer "F.Fab")
		)
		(fp_line
			(start 0.12065 -0.2794)
			(end 0.12065 -0.3048)
			(stroke
				(width 0.1)
				(type default)
			)
			(layer "F.Fab")
		)
		(fp_line
			(start -0.12065 -0.2794)
			(end 0.12065 -0.2794)
			(stroke
				(width 0.1)
				(type default)
			)
			(layer "F.Fab")
		)
		(fp_line
			(start 0.120396 0.2794)
			(end -0.12065 0.2794)
			(stroke
				(width 0.1)
				(type default)
			)
			(layer "F.Fab")
		)
		(fp_line
			(start -0.12065 0.2794)
			(end -0.12065 0.3048)
			(stroke
				(width 0.1)
				(type default)
			)
			(layer "F.Fab")
		)
		(fp_line
			(start 0.67945 0.3048)
			(end 0.120396 0.3048)
			(stroke
				(width 0.1)
				(type default)
			)
			(layer "F.Fab")
		)
		(fp_line
			(start 0.120396 0.3048)
			(end 0.120396 0.2794)
			(stroke
				(width 0.1)
				(type default)
			)
			(layer "F.Fab")
		)
		(fp_line
			(start -0.12065 0.3048)
			(end -0.67945 0.3048)
			(stroke
				(width 0.1)
				(type default)
			)
			(layer "F.Fab")
		)
		(fp_line
			(start -0.67945 0.3048)
			(end -0.67945 -0.305054)
			(stroke
				(width 0.1)
				(type default)
			)
			(layer "F.Fab")
		)
		(pad "1" smd circle
			(at -0.40005 0 90)
			(size 0 0)
			(layers "F.Cu" "F.Mask" "F.Paste")
			(net "P3V3_AUX")
		)
		(pad "2" smd circle
			(at 0.40005 0 90)
			(size 0 0)
			(layers "F.Cu" "F.Mask" "F.Paste")
			(net "GND")
		)
	)
	(footprint ""
		(layer "F.Cu")
		(at 415.19729 -402.371052 -90)
		(property "Reference" "C962"
			(at 0 0 270)
			(layer "F.SilkS")
			(hide yes)
			(effects
				(font
					(size 1.27 1.27)
				)
			)
		)
		(property "Value" ""
			(at 0 0 270)
			(layer "F.Fab")
			(effects
				(font
					(size 1.27 1.27)
				)
			)
		)
		(duplicate_pad_numbers_are_jumpers no)
		(fp_line
			(start -0.299974 0.150114)
			(end -0.299974 -0.150114)
			(stroke
				(width 0.1)
				(type default)
			)
			(layer "F.Fab")
		)
		(fp_line
			(start 0.299974 0.150114)
			(end -0.299974 0.150114)
			(stroke
				(width 0.1)
				(type default)
			)
			(layer "F.Fab")
		)
		(fp_line
			(start -0.299974 -0.150114)
			(end 0.299974 -0.150114)
			(stroke
				(width 0.1)
				(type default)
			)
			(layer "F.Fab")
		)
		(fp_line
			(start 0.299974 -0.150114)
			(end 0.299974 0.150114)
			(stroke
				(width 0.1)
				(type default)
			)
			(layer "F.Fab")
		)
		(pad "1" smd rect
			(at -0.2667 0 270)
			(size 0.3048 0.381)
			(layers "F.Cu" "F.Mask" "F.Paste")
			(net "P5E_CPU0_PE2_TX_C_DN<1>")
		)
		(pad "2" smd rect
			(at 0.2667 0 270)
			(size 0.3048 0.381)
			(layers "F.Cu" "F.Mask" "F.Paste")
			(net "P5E_CPU0_PE2_TX_DN<1>")
		)
	)
	(footprint ""
		(layer "F.Cu")
		(at 339.298534 5.463794)
		(property "Reference" "J72"
			(at -4.245864 1.140206 90)
			(unlocked yes)
			(layer "F.SilkS")
			(effects
				(font
					(size 0.7874 0.5842)
					(thickness 0.1524)
				)
				(justify left)
			)
		)
		(property "Value" ""
			(at 0 0 0)
			(layer "F.Fab")
			(effects
				(font
					(size 1.27 1.27)
				)
			)
		)
		(duplicate_pad_numbers_are_jumpers no)
		(fp_line
			(start -1.2192 -2.1082)
			(end 1.2192 -2.1082)
			(stroke
				(width 0.1524)
				(type default)
			)
			(layer "F.SilkS")
		)
		(fp_line
			(start -1.2192 2.1082)
			(end -1.2192 -2.1082)
			(stroke
				(width 0.1524)
				(type default)
			)
			(layer "F.SilkS")
		)
		(fp_line
			(start 1.2192 -2.1082)
			(end 1.2192 2.1082)
			(stroke
				(width 0.1524)
				(type default)
			)
			(layer "F.SilkS")
		)
		(fp_line
			(start 1.2192 2.1082)
			(end -1.2192 2.1082)
			(stroke
				(width 0.1524)
				(type default)
			)
			(layer "F.SilkS")
		)
		(pad "" np_thru_hole circle
			(at -2.8829 -1.27 270)
			(size 1.0414 1.0414)
			(drill 1.0414)
			(layers "*.Cu" "*.Mask")
			(clearance 0.381)
			(thermal_gap 0.381)
		)
		(pad "" np_thru_hole circle
			(at -2.8829 1.27 270)
			(size 1.0414 1.0414)
			(drill 1.0414)
			(layers "*.Cu" "*.Mask")
			(clearance 0.381)
			(thermal_gap 0.381)
		)
		(pad "" np_thru_hole circle
			(at 3.4671 -1.27 270)
			(size 1.0414 1.0414)
			(drill 1.0414)
			(layers "*.Cu" "*.Mask")
			(clearance 0.381)
			(thermal_gap 0.381)
		)
		(pad "" np_thru_hole circle
			(at 3.4671 1.27 270)
			(size 1.0414 1.0414)
			(drill 1.0414)
			(layers "*.Cu" "*.Mask")
			(clearance 0.381)
			(thermal_gap 0.381)
		)
		(pad "1" smd rect
			(at 0.8255 -0.249936 270)
			(size 0.3048 0.508)
			(layers "F.Cu" "F.Mask" "F.Paste")
			(net "DELTA_L_85_5INCH_IN2_DN")
		)
		(pad "2" smd rect
			(at 0.8255 0.249936 270)
			(size 0.3048 0.508)
			(layers "F.Cu" "F.Mask" "F.Paste")
			(net "DELTA_L_85_5INCH_IN2_DP")
		)
		(pad "3" smd circle
			(at 0 0)
			(size 0 0)
			(layers "F.Cu" "F.Mask" "F.Paste")
			(net "DELTA_L_GND_1")
		)
		(zone
			(layer "F.Cu")
			(hatch none 0.5)
			(connect_pads
				(clearance 0)
			)
			(min_thickness 0.25)
			(keepout
				(tracks not_allowed)
				(vias allowed)
				(pads allowed)
				(copperpour not_allowed)
				(footprints allowed)
			)
			(placement
				(enabled no)
				(sheetname "")
			)
			(fill
				(thermal_gap 0.5)
				(thermal_bridge_width 0.5)
				(island_removal_mode 0)
			)
			(polygon
				(pts
					(xy 340.416134 4.915154) (xy 340.416134 5.010658) (xy 339.819234 5.010658) (xy 339.819234 5.417058)
					(xy 340.416134 5.417058) (xy 340.416134 5.51053) (xy 339.819234 5.51053) (xy 339.819234 5.91693)
					(xy 340.416134 5.91693) (xy 340.416134 6.012434) (xy 339.717634 6.012434) (xy 339.717634 4.915154)
				)
			)
		)
		(zone
			(layers "F.Cu" "B.Cu" "In1.Cu" "In2.Cu" "In3.Cu" "In4.Cu" "In5.Cu" "In6.Cu"
				"In7.Cu" "In8.Cu" "In9.Cu" "In10.Cu" "In11.Cu" "In12.Cu" "In13.Cu" "In14.Cu"
				"In15.Cu" "In16.Cu"
			)
			(hatch none 0.5)
			(connect_pads
				(clearance 0)
			)
			(min_thickness 0.25)
			(keepout
				(tracks not_allowed)
				(vias allowed)
				(pads allowed)
				(copperpour not_allowed)
				(footprints allowed)
			)
			(placement
				(enabled no)
				(sheetname "")
			)
			(fill
				(thermal_gap 0.5)
				(thermal_bridge_width 0.5)
				(island_removal_mode 0)
			)
			(polygon
				(pts
					(arc
						(start 337.342734 4.193794)
						(mid 335.488534 4.193794)
						(end 337.342734 4.193794)
					)
				)
			)
		)
		(zone
			(layers "F.Cu" "B.Cu" "In1.Cu" "In2.Cu" "In3.Cu" "In4.Cu" "In5.Cu" "In6.Cu"
				"In7.Cu" "In8.Cu" "In9.Cu" "In10.Cu" "In11.Cu" "In12.Cu" "In13.Cu" "In14.Cu"
				"In15.Cu" "In16.Cu"
			)
			(hatch none 0.5)
			(connect_pads
				(clearance 0)
			)
			(min_thickness 0.25)
			(keepout
				(tracks not_allowed)
				(vias allowed)
				(pads allowed)
				(copperpour not_allowed)
				(footprints allowed)
			)
			(placement
				(enabled no)
				(sheetname "")
			)
			(fill
				(thermal_gap 0.5)
				(thermal_bridge_width 0.5)
				(island_removal_mode 0)
			)
			(polygon
				(pts
					(arc
						(start 337.342734 6.733794)
						(mid 335.488534 6.733794)
						(end 337.342734 6.733794)
					)
				)
			)
		)
		(zone
			(layers "F.Cu" "B.Cu" "In1.Cu" "In2.Cu" "In3.Cu" "In4.Cu" "In5.Cu" "In6.Cu"
				"In7.Cu" "In8.Cu" "In9.Cu" "In10.Cu" "In11.Cu" "In12.Cu" "In13.Cu" "In14.Cu"
				"In15.Cu" "In16.Cu"
			)
			(hatch none 0.5)
			(connect_pads
				(clearance 0)
			)
			(min_thickness 0.25)
			(keepout
				(tracks not_allowed)
				(vias allowed)
				(pads allowed)
				(copperpour not_allowed)
				(footprints allowed)
			)
			(placement
				(enabled no)
				(sheetname "")
			)
			(fill
				(thermal_gap 0.5)
				(thermal_bridge_width 0.5)
				(island_removal_mode 0)
			)
			(polygon
				(pts
					(arc
						(start 343.692734 4.193794)
						(mid 341.838534 4.193794)
						(end 343.692734 4.193794)
					)
				)
			)
		)
		(zone
			(layers "F.Cu" "B.Cu" "In1.Cu" "In2.Cu" "In3.Cu" "In4.Cu" "In5.Cu" "In6.Cu"
				"In7.Cu" "In8.Cu" "In9.Cu" "In10.Cu" "In11.Cu" "In12.Cu" "In13.Cu" "In14.Cu"
				"In15.Cu" "In16.Cu"
			)
			(hatch none 0.5)
			(connect_pads
				(clearance 0)
			)
			(min_thickness 0.25)
			(keepout
				(tracks not_allowed)
				(vias allowed)
				(pads allowed)
				(copperpour not_allowed)
				(footprints allowed)
			)
			(placement
				(enabled no)
				(sheetname "")
			)
			(fill
				(thermal_gap 0.5)
				(thermal_bridge_width 0.5)
				(island_removal_mode 0)
			)
			(polygon
				(pts
					(arc
						(start 343.692734 6.733794)
						(mid 341.838534 6.733794)
						(end 343.692734 6.733794)
					)
				)
			)
		)
	)
	(footprint ""
		(layer "F.Cu")
		(at 320.185288 -402.371052 -90)
		(property "Reference" "C1569"
			(at 0 0 270)
			(layer "F.SilkS")
			(hide yes)
			(effects
				(font
					(size 1.27 1.27)
				)
			)
		)
		(property "Value" ""
			(at 0 0 270)
			(layer "F.Fab")
			(effects
				(font
					(size 1.27 1.27)
				)
			)
		)
		(duplicate_pad_numbers_are_jumpers no)
		(fp_line
			(start -0.299974 0.150114)
			(end -0.299974 -0.150114)
			(stroke
				(width 0.1)
				(type default)
			)
			(layer "F.Fab")
		)
		(fp_line
			(start 0.299974 0.150114)
			(end -0.299974 0.150114)
			(stroke
				(width 0.1)
				(type default)
			)
			(layer "F.Fab")
		)
		(fp_line
			(start -0.299974 -0.150114)
			(end 0.299974 -0.150114)
			(stroke
				(width 0.1)
				(type default)
			)
			(layer "F.Fab")
		)
		(fp_line
			(start 0.299974 -0.150114)
			(end 0.299974 0.150114)
			(stroke
				(width 0.1)
				(type default)
			)
			(layer "F.Fab")
		)
		(pad "1" smd rect
			(at -0.2667 0 270)
			(size 0.3048 0.381)
			(layers "F.Cu" "F.Mask" "F.Paste")
			(net "P5E_CPU0_PE4_TX_C_DP<5>")
		)
		(pad "2" smd rect
			(at 0.2667 0 270)
			(size 0.3048 0.381)
			(layers "F.Cu" "F.Mask" "F.Paste")
			(net "P5E_CPU0_PE4_TX_DP<5>")
		)
	)
	(footprint ""
		(layer "F.Cu")
		(at 127.635 -58.003948)
		(property "Reference" "C2348"
			(at 0 0 0)
			(layer "F.SilkS")
			(hide yes)
			(effects
				(font
					(size 1.27 1.27)
				)
			)
		)
		(property "Value" ""
			(at 0 0 0)
			(layer "F.Fab")
			(effects
				(font
					(size 1.27 1.27)
				)
			)
		)
		(duplicate_pad_numbers_are_jumpers no)
		(fp_line
			(start -0.7874 -0.4064)
			(end 0.7874 -0.4064)
			(stroke
				(width 0.1524)
				(type default)
			)
			(layer "F.SilkS")
		)
		(fp_line
			(start -0.7874 0.4064)
			(end -0.7874 -0.4064)
			(stroke
				(width 0.1524)
				(type default)
			)
			(layer "F.SilkS")
		)
		(fp_line
			(start 0.7874 -0.4064)
			(end 0.7874 0.4064)
			(stroke
				(width 0.1524)
				(type default)
			)
			(layer "F.SilkS")
		)
		(fp_line
			(start 0.7874 0.4064)
			(end -0.7874 0.4064)
			(stroke
				(width 0.1524)
				(type default)
			)
			(layer "F.SilkS")
		)
		(fp_line
			(start -0.67945 -0.305054)
			(end -0.12065 -0.305054)
			(stroke
				(width 0.1)
				(type default)
			)
			(layer "F.Fab")
		)
		(fp_line
			(start -0.67945 0.3048)
			(end -0.67945 -0.305054)
			(stroke
				(width 0.1)
				(type default)
			)
			(layer "F.Fab")
		)
		(fp_line
			(start -0.12065 -0.305054)
			(end -0.12065 -0.2794)
			(stroke
				(width 0.1)
				(type default)
			)
			(layer "F.Fab")
		)
		(fp_line
			(start -0.12065 -0.2794)
			(end 0.12065 -0.2794)
			(stroke
				(width 0.1)
				(type default)
			)
			(layer "F.Fab")
		)
		(fp_line
			(start -0.12065 0.2794)
			(end -0.12065 0.3048)
			(stroke
				(width 0.1)
				(type default)
			)
			(layer "F.Fab")
		)
		(fp_line
			(start -0.12065 0.3048)
			(end -0.67945 0.3048)
			(stroke
				(width 0.1)
				(type default)
			)
			(layer "F.Fab")
		)
		(fp_line
			(start 0.120396 0.2794)
			(end -0.12065 0.2794)
			(stroke
				(width 0.1)
				(type default)
			)
			(layer "F.Fab")
		)
		(fp_line
			(start 0.120396 0.3048)
			(end 0.120396 0.2794)
			(stroke
				(width 0.1)
				(type default)
			)
			(layer "F.Fab")
		)
		(fp_line
			(start 0.12065 -0.3048)
			(end 0.67945 -0.3048)
			(stroke
				(width 0.1)
				(type default)
			)
			(layer "F.Fab")
		)
		(fp_line
			(start 0.12065 -0.2794)
			(end 0.12065 -0.3048)
			(stroke
				(width 0.1)
				(type default)
			)
			(layer "F.Fab")
		)
		(fp_line
			(start 0.67945 -0.3048)
			(end 0.67945 0.3048)
			(stroke
				(width 0.1)
				(type default)
			)
			(layer "F.Fab")
		)
		(fp_line
			(start 0.67945 0.3048)
			(end 0.120396 0.3048)
			(stroke
				(width 0.1)
				(type default)
			)
			(layer "F.Fab")
		)
		(pad "1" smd circle
			(at -0.40005 0)
			(size 0 0)
			(layers "F.Cu" "F.Mask" "F.Paste")
			(net "P3V3_AUX")
		)
		(pad "2" smd circle
			(at 0.40005 0)
			(size 0 0)
			(layers "F.Cu" "F.Mask" "F.Paste")
			(net "GND")
		)
	)
	(footprint ""
		(layer "F.Cu")
		(at 136.00684 -38.049708)
		(property "Reference" "U246"
			(at -2.84988 1.82499 0)
			(unlocked yes)
			(layer "F.SilkS")
			(effects
				(font
					(size 0.7874 0.5842)
					(thickness 0.1524)
				)
			)
		)
		(property "Value" ""
			(at 0 0 0)
			(layer "F.Fab")
			(effects
				(font
					(size 1.27 1.27)
				)
			)
		)
		(duplicate_pad_numbers_are_jumpers no)
		(fp_line
			(start -1.7272 1.1176)
			(end -1.7272 -1.1176)
			(stroke
				(width 0.1524)
				(type default)
			)
			(layer "F.SilkS")
		)
		(fp_line
			(start -0.254 -1.1176)
			(end -1.7272 -1.1176)
			(stroke
				(width 0.1524)
				(type default)
			)
			(layer "F.SilkS")
		)
		(fp_line
			(start 0 -0.7366)
			(end -0.254 -1.1176)
			(stroke
				(width 0.1524)
				(type default)
			)
			(layer "F.SilkS")
		)
		(fp_line
			(start 0.254 -1.1176)
			(end 0 -0.7366)
			(stroke
				(width 0.1524)
				(type default)
			)
			(layer "F.SilkS")
		)
		(fp_line
			(start 1.7272 -1.1176)
			(end 0.254 -1.1176)
			(stroke
				(width 0.1524)
				(type default)
			)
			(layer "F.SilkS")
		)
		(fp_line
			(start 1.7272 -1.1176)
			(end 1.7272 1.1176)
			(stroke
				(width 0.1524)
				(type default)
			)
			(layer "F.SilkS")
		)
		(fp_line
			(start 1.7272 1.1176)
			(end -1.7272 1.1176)
			(stroke
				(width 0.1524)
				(type default)
			)
			(layer "F.SilkS")
		)
		(fp_poly
			(pts
				(xy -2.7178 -0.268986) (xy -2.7178 -1.030986) (xy -1.9558 -0.649986)
			)
			(stroke
				(width 0)
				(type default)
			)
			(fill yes)
			(layer "F.SilkS")
		)
		(fp_line
			(start -1.5748 -1.1176)
			(end -1.5748 1.1176)
			(stroke
				(width 0.1)
				(type default)
			)
			(layer "F.Fab")
		)
		(fp_line
			(start -1.5748 1.1176)
			(end 1.5748 1.1176)
			(stroke
				(width 0.1)
				(type default)
			)
			(layer "F.Fab")
		)
		(fp_line
			(start 1.5748 -1.1176)
			(end -1.5748 -1.1176)
			(stroke
				(width 0.1)
				(type default)
			)
			(layer "F.Fab")
		)
		(fp_line
			(start 1.5748 1.1176)
			(end 1.5748 -1.1176)
			(stroke
				(width 0.1)
				(type default)
			)
			(layer "F.Fab")
		)
		(fp_poly
			(pts
				(xy -1.9558 -0.649986) (xy -2.7178 -0.268986) (xy -2.7178 -1.030986)
			)
			(stroke
				(width 0)
				(type default)
			)
			(fill yes)
			(layer "F.Fab")
		)
		(pad "1" smd rect
			(at -0.999998 -0.649986 270)
			(size 0.3556 1.1176)
			(layers "F.Cu" "F.Mask" "F.Paste")
			(net "OCP_V3_2_NOT_PRSNT_RBT_ARB_IN")
		)
		(pad "2" smd rect
			(at -0.999998 0 270)
			(size 0.3556 1.1176)
			(layers "F.Cu" "F.Mask" "F.Paste")
			(net "GND")
		)
		(pad "3" smd rect
			(at -0.999998 0.649986 270)
			(size 0.3556 1.1176)
			(layers "F.Cu" "F.Mask" "F.Paste")
			(net "OCP_V3_2_RBT_ARB_OUT")
		)
		(pad "4" smd rect
			(at 0.999998 0.649986 270)
			(size 0.3556 1.1176)
			(layers "F.Cu" "F.Mask" "F.Paste")
			(net "OCP_SFF_RBT_ARB_IN_MUX1")
		)
		(pad "5" smd rect
			(at 0.999998 0 270)
			(size 0.3556 1.1176)
			(layers "F.Cu" "F.Mask" "F.Paste")
			(net "P3V3_AUX")
		)
		(pad "6" smd rect
			(at 0.999998 -0.649986 270)
			(size 0.3556 1.1176)
			(layers "F.Cu" "F.Mask" "F.Paste")
			(net "OCP_V3_2_PRSNT_ALL_R1_N")
		)
	)
	(footprint ""
		(layer "F.Cu")
		(at 456.444858 -387.950964)
		(property "Reference" "PC1848"
			(at 0 0 0)
			(layer "F.SilkS")
			(hide yes)
			(effects
				(font
					(size 1.27 1.27)
				)
			)
		)
		(property "Value" ""
			(at 0 0 0)
			(layer "F.Fab")
			(effects
				(font
					(size 1.27 1.27)
				)
			)
		)
		(duplicate_pad_numbers_are_jumpers no)
		(fp_line
			(start -0.7874 -0.4064)
			(end 0.7874 -0.4064)
			(stroke
				(width 0.1524)
				(type default)
			)
			(layer "F.SilkS")
		)
		(fp_line
			(start -0.7874 0.4064)
			(end -0.7874 -0.4064)
			(stroke
				(width 0.1524)
				(type default)
			)
			(layer "F.SilkS")
		)
		(fp_line
			(start 0.7874 -0.4064)
			(end 0.7874 0.4064)
			(stroke
				(width 0.1524)
				(type default)
			)
			(layer "F.SilkS")
		)
		(fp_line
			(start 0.7874 0.4064)
			(end -0.7874 0.4064)
			(stroke
				(width 0.1524)
				(type default)
			)
			(layer "F.SilkS")
		)
		(fp_line
			(start -0.67945 -0.305054)
			(end -0.12065 -0.305054)
			(stroke
				(width 0.1)
				(type default)
			)
			(layer "F.Fab")
		)
		(fp_line
			(start -0.67945 0.3048)
			(end -0.67945 -0.305054)
			(stroke
				(width 0.1)
				(type default)
			)
			(layer "F.Fab")
		)
		(fp_line
			(start -0.12065 -0.305054)
			(end -0.12065 -0.2794)
			(stroke
				(width 0.1)
				(type default)
			)
			(layer "F.Fab")
		)
		(fp_line
			(start -0.12065 -0.2794)
			(end 0.12065 -0.2794)
			(stroke
				(width 0.1)
				(type default)
			)
			(layer "F.Fab")
		)
		(fp_line
			(start -0.12065 0.2794)
			(end -0.12065 0.3048)
			(stroke
				(width 0.1)
				(type default)
			)
			(layer "F.Fab")
		)
		(fp_line
			(start -0.12065 0.3048)
			(end -0.67945 0.3048)
			(stroke
				(width 0.1)
				(type default)
			)
			(layer "F.Fab")
		)
		(fp_line
			(start 0.120396 0.2794)
			(end -0.12065 0.2794)
			(stroke
				(width 0.1)
				(type default)
			)
			(layer "F.Fab")
		)
		(fp_line
			(start 0.120396 0.3048)
			(end 0.120396 0.2794)
			(stroke
				(width 0.1)
				(type default)
			)
			(layer "F.Fab")
		)
		(fp_line
			(start 0.12065 -0.3048)
			(end 0.67945 -0.3048)
			(stroke
				(width 0.1)
				(type default)
			)
			(layer "F.Fab")
		)
		(fp_line
			(start 0.12065 -0.2794)
			(end 0.12065 -0.3048)
			(stroke
				(width 0.1)
				(type default)
			)
			(layer "F.Fab")
		)
		(fp_line
			(start 0.67945 -0.3048)
			(end 0.67945 0.3048)
			(stroke
				(width 0.1)
				(type default)
			)
			(layer "F.Fab")
		)
		(fp_line
			(start 0.67945 0.3048)
			(end 0.120396 0.3048)
			(stroke
				(width 0.1)
				(type default)
			)
			(layer "F.Fab")
		)
		(pad "1" smd circle
			(at -0.40005 0)
			(size 0 0)
			(layers "F.Cu" "F.Mask" "F.Paste")
			(net "P5V_AUX_VCC")
		)
		(pad "2" smd circle
			(at 0.40005 0)
			(size 0 0)
			(layers "F.Cu" "F.Mask" "F.Paste")
			(net "GND")
		)
	)
	(footprint ""
		(layer "F.Cu")
		(at 131.32308 -122.542808 -90)
		(property "Reference" "R3155"
			(at 0 0 270)
			(layer "F.SilkS")
			(hide yes)
			(effects
				(font
					(size 1.27 1.27)
				)
			)
		)
		(property "Value" ""
			(at 0 0 270)
			(layer "F.Fab")
			(effects
				(font
					(size 1.27 1.27)
				)
			)
		)
		(duplicate_pad_numbers_are_jumpers no)
		(fp_line
			(start -0.7874 0.4064)
			(end -0.7874 -0.4064)
			(stroke
				(width 0.1524)
				(type default)
			)
			(layer "F.SilkS")
		)
		(fp_line
			(start 0.7874 0.4064)
			(end -0.7874 0.4064)
			(stroke
				(width 0.1524)
				(type default)
			)
			(layer "F.SilkS")
		)
		(fp_line
			(start -0.7874 -0.4064)
			(end 0.7874 -0.4064)
			(stroke
				(width 0.1524)
				(type default)
			)
			(layer "F.SilkS")
		)
		(fp_line
			(start 0.7874 -0.4064)
			(end 0.7874 0.4064)
			(stroke
				(width 0.1524)
				(type default)
			)
			(layer "F.SilkS")
		)
		(fp_line
			(start -0.67945 0.3048)
			(end -0.67945 -0.305054)
			(stroke
				(width 0.1)
				(type default)
			)
			(layer "F.Fab")
		)
		(fp_line
			(start -0.12065 0.3048)
			(end -0.67945 0.3048)
			(stroke
				(width 0.1)
				(type default)
			)
			(layer "F.Fab")
		)
		(fp_line
			(start 0.120396 0.3048)
			(end 0.120396 0.2794)
			(stroke
				(width 0.1)
				(type default)
			)
			(layer "F.Fab")
		)
		(fp_line
			(start 0.67945 0.3048)
			(end 0.120396 0.3048)
			(stroke
				(width 0.1)
				(type default)
			)
			(layer "F.Fab")
		)
		(fp_line
			(start -0.12065 0.2794)
			(end -0.12065 0.3048)
			(stroke
				(width 0.1)
				(type default)
			)
			(layer "F.Fab")
		)
		(fp_line
			(start 0.120396 0.2794)
			(end -0.12065 0.2794)
			(stroke
				(width 0.1)
				(type default)
			)
			(layer "F.Fab")
		)
		(fp_line
			(start -0.12065 -0.2794)
			(end 0.12065 -0.2794)
			(stroke
				(width 0.1)
				(type default)
			)
			(layer "F.Fab")
		)
		(fp_line
			(start 0.12065 -0.2794)
			(end 0.12065 -0.3048)
			(stroke
				(width 0.1)
				(type default)
			)
			(layer "F.Fab")
		)
		(fp_line
			(start 0.12065 -0.3048)
			(end 0.67945 -0.3048)
			(stroke
				(width 0.1)
				(type default)
			)
			(layer "F.Fab")
		)
		(fp_line
			(start 0.67945 -0.3048)
			(end 0.67945 0.3048)
			(stroke
				(width 0.1)
				(type default)
			)
			(layer "F.Fab")
		)
		(fp_line
			(start -0.67945 -0.305054)
			(end -0.12065 -0.305054)
			(stroke
				(width 0.1)
				(type default)
			)
			(layer "F.Fab")
		)
		(fp_line
			(start -0.12065 -0.305054)
			(end -0.12065 -0.2794)
			(stroke
				(width 0.1)
				(type default)
			)
			(layer "F.Fab")
		)
		(pad "1" smd circle
			(at -0.40005 0 270)
			(size 0 0)
			(layers "F.Cu" "F.Mask" "F.Paste")
			(net "P3V3_AUX")
		)
		(pad "2" smd circle
			(at 0.40005 0 270)
			(size 0 0)
			(layers "F.Cu" "F.Mask" "F.Paste")
			(net "HP_LVC3_OCP_V3_2_PRSNT2")
		)
	)
	(footprint ""
		(layer "F.Cu")
		(at 390.056878 -28.309824 90)
		(property "Reference" "U104"
			(at -0.177546 2.754122 0)
			(unlocked yes)
			(layer "F.SilkS")
			(effects
				(font
					(size 0.7874 0.5842)
					(thickness 0.1524)
				)
				(justify left)
			)
		)
		(property "Value" ""
			(at 0 0 90)
			(layer "F.Fab")
			(effects
				(font
					(size 1.27 1.27)
				)
			)
		)
		(duplicate_pad_numbers_are_jumpers no)
		(fp_line
			(start 1.733296 -1.549908)
			(end 0.660908 -1.549908)
			(stroke
				(width 0.1524)
				(type default)
			)
			(layer "F.SilkS")
		)
		(fp_line
			(start 0.660908 -1.549908)
			(end 0 -0.889)
			(stroke
				(width 0.1524)
				(type default)
			)
			(layer "F.SilkS")
		)
		(fp_line
			(start -0.660908 -1.549908)
			(end -1.733296 -1.549908)
			(stroke
				(width 0.1524)
				(type default)
			)
			(layer "F.SilkS")
		)
		(fp_line
			(start -1.733296 -1.549908)
			(end -1.733296 1.549908)
			(stroke
				(width 0.1524)
				(type default)
			)
			(layer "F.SilkS")
		)
		(fp_line
			(start 0 -0.889)
			(end -0.660908 -1.549908)
			(stroke
				(width 0.1524)
				(type default)
			)
			(layer "F.SilkS")
		)
		(fp_line
			(start 1.733296 1.549908)
			(end 1.733296 -1.549908)
			(stroke
				(width 0.1524)
				(type default)
			)
			(layer "F.SilkS")
		)
		(fp_line
			(start -1.733296 1.549908)
			(end 1.733296 1.549908)
			(stroke
				(width 0.1524)
				(type default)
			)
			(layer "F.SilkS")
		)
		(fp_poly
			(pts
				(xy -1.227836 -2.218436) (xy -1.481836 -1.710436) (xy -1.735836 -2.218436)
			)
			(stroke
				(width 0)
				(type default)
			)
			(fill yes)
			(layer "F.SilkS")
		)
		(fp_line
			(start 0.849884 -1.549908)
			(end -0.849884 -1.549908)
			(stroke
				(width 0.1)
				(type default)
			)
			(layer "F.Fab")
		)
		(fp_line
			(start -0.849884 -1.549908)
			(end -0.849884 1.549908)
			(stroke
				(width 0.1)
				(type default)
			)
			(layer "F.Fab")
		)
		(fp_line
			(start 0.849884 1.549908)
			(end 0.849884 -1.549908)
			(stroke
				(width 0.1)
				(type default)
			)
			(layer "F.Fab")
		)
		(fp_line
			(start -0.849884 1.549908)
			(end 0.849884 1.549908)
			(stroke
				(width 0.1)
				(type default)
			)
			(layer "F.Fab")
		)
		(fp_poly
			(pts
				(xy -2.4384 -1.20396) (xy -2.4384 -0.69596) (xy -1.9304 -0.94996)
			)
			(stroke
				(width 0)
				(type default)
			)
			(fill yes)
			(layer "F.Fab")
		)
		(pad "1" smd rect
			(at -1.199896 -0.94996)
			(size 0.5588 0.8128)
			(layers "F.Cu" "F.Mask" "F.Paste")
			(net "NC_U104_NC1")
		)
		(pad "2" smd rect
			(at -1.199896 0)
			(size 0.5588 0.8128)
			(layers "F.Cu" "F.Mask" "F.Paste")
			(net "FM_SYS_THROTTLE_R_N")
		)
		(pad "3" smd rect
			(at -1.199896 0.94996)
			(size 0.5588 0.8128)
			(layers "F.Cu" "F.Mask" "F.Paste")
			(net "GND")
		)
		(pad "4" smd rect
			(at 1.199896 0.94996)
			(size 0.5588 0.8128)
			(layers "F.Cu" "F.Mask" "F.Paste")
			(net "OCP_SFF_PWRBRK_BUFF_N")
		)
		(pad "5" smd rect
			(at 1.199896 -0.94996)
			(size 0.5588 0.8128)
			(layers "F.Cu" "F.Mask" "F.Paste")
			(net "P3V3_AUX")
		)
	)
	(footprint ""
		(layer "F.Cu")
		(at 446.522348 -258.091686)
		(property "Reference" "J13"
			(at -3.683 -81.702148 0)
			(unlocked yes)
			(layer "F.SilkS")
			(effects
				(font
					(size 0.7874 0.5842)
					(thickness 0.1524)
				)
				(justify left)
			)
		)
		(property "Value" ""
			(at 0 0 0)
			(layer "F.Fab")
			(effects
				(font
					(size 1.27 1.27)
				)
			)
		)
		(duplicate_pad_numbers_are_jumpers no)
		(fp_line
			(start -3.24993 -81.000092)
			(end -3.24993 -80.216502)
			(stroke
				(width 0.1524)
				(type default)
			)
			(layer "F.SilkS")
		)
		(fp_line
			(start -3.24993 -74.836782)
			(end -3.24993 76.049378)
			(stroke
				(width 0.1524)
				(type default)
			)
			(layer "F.SilkS")
		)
		(fp_line
			(start -3.24993 80.154018)
			(end -3.24993 81.000092)
			(stroke
				(width 0.1524)
				(type default)
			)
			(layer "F.SilkS")
		)
		(fp_line
			(start -3.24993 81.000092)
			(end -2.494788 81.000092)
			(stroke
				(width 0.1524)
				(type default)
			)
			(layer "F.SilkS")
		)
		(fp_line
			(start -1.816608 81.000092)
			(end -1.483868 81.000092)
			(stroke
				(width 0.1524)
				(type default)
			)
			(layer "F.SilkS")
		)
		(fp_line
			(start 0.591312 -81.000092)
			(end -3.24993 -81.000092)
			(stroke
				(width 0.1524)
				(type default)
			)
			(layer "F.SilkS")
		)
		(fp_line
			(start 2.161032 81.000092)
			(end 3.24993 81.000092)
			(stroke
				(width 0.1524)
				(type default)
			)
			(layer "F.SilkS")
		)
		(fp_line
			(start 3.24993 -75.852782)
			(end 3.24993 -79.264002)
			(stroke
				(width 0.1524)
				(type default)
			)
			(layer "F.SilkS")
		)
		(fp_line
			(start 3.24993 -72.00011)
			(end -3.24993 -72.00011)
			(stroke
				(width 0.1524)
				(type default)
			)
			(layer "F.SilkS")
		)
		(fp_line
			(start 3.24993 72.00011)
			(end -3.24993 72.00011)
			(stroke
				(width 0.1524)
				(type default)
			)
			(layer "F.SilkS")
		)
		(fp_line
			(start 3.24993 81.000092)
			(end 3.24993 -72.825102)
			(stroke
				(width 0.1524)
				(type default)
			)
			(layer "F.SilkS")
		)
		(fp_poly
			(pts
				(xy -4.19354 -63.751206) (xy -3.330956 -63.319914) (xy -4.19354 -62.888622)
			)
			(stroke
				(width 0)
				(type default)
			)
			(fill yes)
			(layer "F.SilkS")
		)
		(fp_line
			(start -3.24993 -81.000092)
			(end -3.24993 81.000092)
			(stroke
				(width 0.1)
				(type default)
			)
			(layer "F.Fab")
		)
		(fp_line
			(start -3.24993 81.000092)
			(end 3.24993 81.000092)
			(stroke
				(width 0.1)
				(type default)
			)
			(layer "F.Fab")
		)
		(fp_line
			(start 3.24993 -81.000092)
			(end -3.24993 -81.000092)
			(stroke
				(width 0.1)
				(type default)
			)
			(layer "F.Fab")
		)
		(fp_line
			(start 3.24993 -72.00011)
			(end -3.24993 -72.00011)
			(stroke
				(width 0.1)
				(type default)
			)
			(layer "F.Fab")
		)
		(fp_line
			(start 3.24993 -71.000112)
			(end -3.24993 -71.000112)
			(stroke
				(width 0.1)
				(type default)
			)
			(layer "F.Fab")
		)
		(fp_line
			(start 3.24993 71.000112)
			(end -3.24993 71.000112)
			(stroke
				(width 0.1)
				(type default)
			)
			(layer "F.Fab")
		)
		(fp_line
			(start 3.24993 72.00011)
			(end -3.24993 72.00011)
			(stroke
				(width 0.1)
				(type default)
			)
			(layer "F.Fab")
		)
		(fp_line
			(start 3.24993 81.000092)
			(end 3.24993 -81.000092)
			(stroke
				(width 0.1)
				(type default)
			)
			(layer "F.Fab")
		)
		(fp_poly
			(pts
				(xy -4.445 -63.832994) (xy -4.445 -62.816994) (xy -3.429 -63.324994)
			)
			(stroke
				(width 0)
				(type default)
			)
			(fill yes)
			(layer "F.Fab")
		)
		(pad "1" smd rect
			(at -2.050034 -63.324994 270)
			(size 0.519938 1.4986)
			(layers "F.Cu" "F.Mask" "F.Paste")
			(net "P12V_S3_AUX_CPU0_NVDIMM")
		)
		(pad "2" smd rect
			(at -2.050034 -62.47511 270)
			(size 0.519938 1.4986)
			(layers "F.Cu" "F.Mask" "F.Paste")
			(net "TP_CHG_CPU0_DIMM1_FRU_0")
		)
		(pad "3" smd rect
			(at -2.050034 -61.624972 270)
			(size 0.519938 1.4986)
			(layers "F.Cu" "F.Mask" "F.Paste")
			(net "P3V3_AUX")
		)
		(pad "4" smd rect
			(at -2.050034 -60.775088 270)
			(size 0.519938 1.4986)
			(layers "F.Cu" "F.Mask" "F.Paste")
			(net "I3C_SPD_DDREFGH_CPU0_LVC1_SCL_4")
		)
		(pad "5" smd rect
			(at -2.050034 -59.92495 270)
			(size 0.519938 1.4986)
			(layers "F.Cu" "F.Mask" "F.Paste")
			(net "I3C_SPD_DDREFGH_CPU0_LVC1_SDA")
		)
		(pad "6" smd rect
			(at -2.050034 -59.075066 270)
			(size 0.519938 1.4986)
			(layers "F.Cu" "F.Mask" "F.Paste")
			(net "GND")
		)
		(pad "7" smd rect
			(at -2.050034 -58.224928 270)
			(size 0.519938 1.4986)
			(layers "F.Cu" "F.Mask" "F.Paste")
			(net "M_G_CPU0_SA_DQ<0>")
		)
		(pad "8" smd rect
			(at -2.050034 -57.375044 270)
			(size 0.519938 1.4986)
			(layers "F.Cu" "F.Mask" "F.Paste")
			(net "GND")
		)
		(pad "9" smd rect
			(at -2.050034 -56.524906 270)
			(size 0.519938 1.4986)
			(layers "F.Cu" "F.Mask" "F.Paste")
			(net "M_G_CPU0_SA_DQ<1>")
		)
		(pad "10" smd rect
			(at -2.050034 -55.675022 270)
			(size 0.519938 1.4986)
			(layers "F.Cu" "F.Mask" "F.Paste")
			(net "GND")
		)
		(pad "11" smd rect
			(at -2.050034 -54.824884 270)
			(size 0.519938 1.4986)
			(layers "F.Cu" "F.Mask" "F.Paste")
			(net "M_G_CPU0_SA_DQS_DP<0>")
		)
		(pad "12" smd rect
			(at -2.050034 -53.975 270)
			(size 0.519938 1.4986)
			(layers "F.Cu" "F.Mask" "F.Paste")
			(net "M_G_CPU0_SA_DQS_DN<0>")
		)
		(pad "13" smd rect
			(at -2.050034 -53.125116 270)
			(size 0.519938 1.4986)
			(layers "F.Cu" "F.Mask" "F.Paste")
			(net "GND")
		)
		(pad "14" smd rect
			(at -2.050034 -52.274978 270)
			(size 0.519938 1.4986)
			(layers "F.Cu" "F.Mask" "F.Paste")
			(net "M_G_CPU0_SA_DQ<4>")
		)
		(pad "15" smd rect
			(at -2.050034 -51.425094 270)
			(size 0.519938 1.4986)
			(layers "F.Cu" "F.Mask" "F.Paste")
			(net "GND")
		)
		(pad "16" smd rect
			(at -2.050034 -50.574956 270)
			(size 0.519938 1.4986)
			(layers "F.Cu" "F.Mask" "F.Paste")
			(net "M_G_CPU0_SA_DQ<5>")
		)
		(pad "17" smd rect
			(at -2.050034 -49.725072 270)
			(size 0.519938 1.4986)
			(layers "F.Cu" "F.Mask" "F.Paste")
			(net "GND")
		)
		(pad "18" smd rect
			(at -2.050034 -48.874934 270)
			(size 0.519938 1.4986)
			(layers "F.Cu" "F.Mask" "F.Paste")
			(net "M_G_CPU0_SA_DQ<8>")
		)
		(pad "19" smd rect
			(at -2.050034 -48.02505 270)
			(size 0.519938 1.4986)
			(layers "F.Cu" "F.Mask" "F.Paste")
			(net "GND")
		)
		(pad "20" smd rect
			(at -2.050034 -47.174912 270)
			(size 0.519938 1.4986)
			(layers "F.Cu" "F.Mask" "F.Paste")
			(net "M_G_CPU0_SA_DQ<9>")
		)
		(pad "21" smd rect
			(at -2.050034 -46.325028 270)
			(size 0.519938 1.4986)
			(layers "F.Cu" "F.Mask" "F.Paste")
			(net "GND")
		)
		(pad "22" smd rect
			(at -2.050034 -45.47489 270)
			(size 0.519938 1.4986)
			(layers "F.Cu" "F.Mask" "F.Paste")
			(net "M_G_CPU0_SA_DQS_DP<1>")
		)
		(pad "23" smd rect
			(at -2.050034 -44.625006 270)
			(size 0.519938 1.4986)
			(layers "F.Cu" "F.Mask" "F.Paste")
			(net "M_G_CPU0_SA_DQS_DN<1>")
		)
		(pad "24" smd rect
			(at -2.050034 -43.775122 270)
			(size 0.519938 1.4986)
			(layers "F.Cu" "F.Mask" "F.Paste")
			(net "GND")
		)
		(pad "25" smd rect
			(at -2.050034 -42.924984 270)
			(size 0.519938 1.4986)
			(layers "F.Cu" "F.Mask" "F.Paste")
			(net "M_G_CPU0_SA_DQ<12>")
		)
		(pad "26" smd rect
			(at -2.050034 -42.0751 270)
			(size 0.519938 1.4986)
			(layers "F.Cu" "F.Mask" "F.Paste")
			(net "GND")
		)
		(pad "27" smd rect
			(at -2.050034 -41.224962 270)
			(size 0.519938 1.4986)
			(layers "F.Cu" "F.Mask" "F.Paste")
			(net "M_G_CPU0_SA_DQ<13>")
		)
		(pad "28" smd rect
			(at -2.050034 -40.375078 270)
			(size 0.519938 1.4986)
			(layers "F.Cu" "F.Mask" "F.Paste")
			(net "GND")
		)
		(pad "29" smd rect
			(at -2.050034 -39.52494 270)
			(size 0.519938 1.4986)
			(layers "F.Cu" "F.Mask" "F.Paste")
			(net "M_G_CPU0_SA_DQ<16>")
		)
		(pad "30" smd rect
			(at -2.050034 -38.675056 270)
			(size 0.519938 1.4986)
			(layers "F.Cu" "F.Mask" "F.Paste")
			(net "GND")
		)
		(pad "31" smd rect
			(at -2.050034 -37.824918 270)
			(size 0.519938 1.4986)
			(layers "F.Cu" "F.Mask" "F.Paste")
			(net "M_G_CPU0_SA_DQ<17>")
		)
		(pad "32" smd rect
			(at -2.050034 -36.975034 270)
			(size 0.519938 1.4986)
			(layers "F.Cu" "F.Mask" "F.Paste")
			(net "GND")
		)
		(pad "33" smd rect
			(at -2.050034 -36.124896 270)
			(size 0.519938 1.4986)
			(layers "F.Cu" "F.Mask" "F.Paste")
			(net "M_G_CPU0_SA_DQS_DP<2>")
		)
		(pad "34" smd rect
			(at -2.050034 -35.275012 270)
			(size 0.519938 1.4986)
			(layers "F.Cu" "F.Mask" "F.Paste")
			(net "M_G_CPU0_SA_DQS_DN<2>")
		)
		(pad "35" smd rect
			(at -2.050034 -34.425128 270)
			(size 0.519938 1.4986)
			(layers "F.Cu" "F.Mask" "F.Paste")
			(net "GND")
		)
		(pad "36" smd rect
			(at -2.050034 -33.57499 270)
			(size 0.519938 1.4986)
			(layers "F.Cu" "F.Mask" "F.Paste")
			(net "M_G_CPU0_SA_DQ<20>")
		)
		(pad "37" smd rect
			(at -2.050034 -32.725106 270)
			(size 0.519938 1.4986)
			(layers "F.Cu" "F.Mask" "F.Paste")
			(net "GND")
		)
		(pad "38" smd rect
			(at -2.050034 -31.874968 270)
			(size 0.519938 1.4986)
			(layers "F.Cu" "F.Mask" "F.Paste")
			(net "M_G_CPU0_SA_DQ<21>")
		)
		(pad "39" smd rect
			(at -2.050034 -31.025084 270)
			(size 0.519938 1.4986)
			(layers "F.Cu" "F.Mask" "F.Paste")
			(net "GND")
		)
		(pad "40" smd rect
			(at -2.050034 -30.174946 270)
			(size 0.519938 1.4986)
			(layers "F.Cu" "F.Mask" "F.Paste")
			(net "M_G_CPU0_SA_DQ<24>")
		)
		(pad "41" smd rect
			(at -2.050034 -29.325062 270)
			(size 0.519938 1.4986)
			(layers "F.Cu" "F.Mask" "F.Paste")
			(net "GND")
		)
		(pad "42" smd rect
			(at -2.050034 -28.474924 270)
			(size 0.519938 1.4986)
			(layers "F.Cu" "F.Mask" "F.Paste")
			(net "M_G_CPU0_SA_DQ<25>")
		)
		(pad "43" smd rect
			(at -2.050034 -27.62504 270)
			(size 0.519938 1.4986)
			(layers "F.Cu" "F.Mask" "F.Paste")
			(net "GND")
		)
		(pad "44" smd rect
			(at -2.050034 -26.774902 270)
			(size 0.519938 1.4986)
			(layers "F.Cu" "F.Mask" "F.Paste")
			(net "M_G_CPU0_SA_DQS_DP<3>")
		)
		(pad "45" smd rect
			(at -2.050034 -25.925018 270)
			(size 0.519938 1.4986)
			(layers "F.Cu" "F.Mask" "F.Paste")
			(net "M_G_CPU0_SA_DQS_DN<3>")
		)
		(pad "46" smd rect
			(at -2.050034 -25.07488 270)
			(size 0.519938 1.4986)
			(layers "F.Cu" "F.Mask" "F.Paste")
			(net "GND")
		)
		(pad "47" smd rect
			(at -2.050034 -24.224996 270)
			(size 0.519938 1.4986)
			(layers "F.Cu" "F.Mask" "F.Paste")
			(net "M_G_CPU0_SA_DQ<28>")
		)
		(pad "48" smd rect
			(at -2.050034 -23.375112 270)
			(size 0.519938 1.4986)
			(layers "F.Cu" "F.Mask" "F.Paste")
			(net "GND")
		)
		(pad "49" smd rect
			(at -2.050034 -22.524974 270)
			(size 0.519938 1.4986)
			(layers "F.Cu" "F.Mask" "F.Paste")
			(net "M_G_CPU0_SA_DQ<29>")
		)
		(pad "50" smd rect
			(at -2.050034 -21.67509 270)
			(size 0.519938 1.4986)
			(layers "F.Cu" "F.Mask" "F.Paste")
			(net "GND")
		)
		(pad "51" smd rect
			(at -2.050034 -20.824952 270)
			(size 0.519938 1.4986)
			(layers "F.Cu" "F.Mask" "F.Paste")
			(net "M_G_CPU0_SA_CB<0>")
		)
		(pad "52" smd rect
			(at -2.050034 -19.975068 270)
			(size 0.519938 1.4986)
			(layers "F.Cu" "F.Mask" "F.Paste")
			(net "GND")
		)
		(pad "53" smd rect
			(at -2.050034 -19.12493 270)
			(size 0.519938 1.4986)
			(layers "F.Cu" "F.Mask" "F.Paste")
			(net "M_G_CPU0_SA_CB<1>")
		)
		(pad "54" smd rect
			(at -2.050034 -18.275046 270)
			(size 0.519938 1.4986)
			(layers "F.Cu" "F.Mask" "F.Paste")
			(net "GND")
		)
		(pad "55" smd rect
			(at -2.050034 -17.424908 270)
			(size 0.519938 1.4986)
			(layers "F.Cu" "F.Mask" "F.Paste")
			(net "M_G_CPU0_SA_DQS_DP<4>")
		)
		(pad "56" smd rect
			(at -2.050034 -16.575024 270)
			(size 0.519938 1.4986)
			(layers "F.Cu" "F.Mask" "F.Paste")
			(net "M_G_CPU0_SA_DQS_DN<4>")
		)
		(pad "57" smd rect
			(at -2.050034 -15.724886 270)
			(size 0.519938 1.4986)
			(layers "F.Cu" "F.Mask" "F.Paste")
			(net "GND")
		)
		(pad "58" smd rect
			(at -2.050034 -14.875002 270)
			(size 0.519938 1.4986)
			(layers "F.Cu" "F.Mask" "F.Paste")
			(net "M_G_CPU0_SA_CB<4>")
		)
		(pad "59" smd rect
			(at -2.050034 -14.025118 270)
			(size 0.519938 1.4986)
			(layers "F.Cu" "F.Mask" "F.Paste")
			(net "GND")
		)
		(pad "60" smd rect
			(at -2.050034 -13.17498 270)
			(size 0.519938 1.4986)
			(layers "F.Cu" "F.Mask" "F.Paste")
			(net "M_G_CPU0_SA_CB<5>")
		)
		(pad "61" smd rect
			(at -2.050034 -12.325096 270)
			(size 0.519938 1.4986)
			(layers "F.Cu" "F.Mask" "F.Paste")
			(net "GND")
		)
		(pad "62" smd rect
			(at -2.050034 -11.474958 270)
			(size 0.519938 1.4986)
			(layers "F.Cu" "F.Mask" "F.Paste")
			(net "M_G_CPU0_ALERT_N")
		)
		(pad "63" smd rect
			(at -2.050034 -10.625074 270)
			(size 0.519938 1.4986)
			(layers "F.Cu" "F.Mask" "F.Paste")
			(net "GND")
		)
		(pad "64" smd rect
			(at -2.050034 -9.774936 270)
			(size 0.519938 1.4986)
			(layers "F.Cu" "F.Mask" "F.Paste")
			(net "M_G_CPU0_SA_CS_N<0>")
		)
		(pad "65" smd rect
			(at -2.050034 -8.925052 270)
			(size 0.519938 1.4986)
			(layers "F.Cu" "F.Mask" "F.Paste")
			(net "GND")
		)
		(pad "66" smd rect
			(at -2.050034 -8.074914 270)
			(size 0.519938 1.4986)
			(layers "F.Cu" "F.Mask" "F.Paste")
			(net "M_G_CPU0_SA_CA<0>")
		)
		(pad "67" smd rect
			(at -2.050034 -7.22503 270)
			(size 0.519938 1.4986)
			(layers "F.Cu" "F.Mask" "F.Paste")
			(net "GND")
		)
		(pad "68" smd rect
			(at -2.050034 -6.374892 270)
			(size 0.519938 1.4986)
			(layers "F.Cu" "F.Mask" "F.Paste")
			(net "M_G_CPU0_SA_CA<2>")
		)
		(pad "69" smd rect
			(at -2.050034 -5.525008 270)
			(size 0.519938 1.4986)
			(layers "F.Cu" "F.Mask" "F.Paste")
			(net "GND")
		)
		(pad "70" smd rect
			(at -2.050034 -4.675124 270)
			(size 0.519938 1.4986)
			(layers "F.Cu" "F.Mask" "F.Paste")
			(net "M_G_CPU0_SA_CA<4>")
		)
		(pad "71" smd rect
			(at -2.050034 -3.824986 270)
			(size 0.519938 1.4986)
			(layers "F.Cu" "F.Mask" "F.Paste")
			(net "GND")
		)
		(pad "72" smd rect
			(at -2.050034 -2.975102 270)
			(size 0.519938 1.4986)
			(layers "F.Cu" "F.Mask" "F.Paste")
			(net "M_G_CPU0_SA_CA<6>")
		)
		(pad "73" smd rect
			(at -2.050034 -2.124964 270)
			(size 0.519938 1.4986)
			(layers "F.Cu" "F.Mask" "F.Paste")
			(net "GND")
		)
		(pad "74" smd rect
			(at -2.050034 -1.27508 270)
			(size 0.519938 1.4986)
			(layers "F.Cu" "F.Mask" "F.Paste")
			(net "M_G_CPU0_SA_PAR")
		)
		(pad "75" smd rect
			(at -2.050034 -0.424942 270)
			(size 0.519938 1.4986)
			(layers "F.Cu" "F.Mask" "F.Paste")
			(net "GND")
		)
		(pad "76" smd rect
			(at -2.050034 5.525008 270)
			(size 0.519938 1.4986)
			(layers "F.Cu" "F.Mask" "F.Paste")
			(net "M_G_CPU0_SB_CA<0>")
		)
		(pad "77" smd rect
			(at -2.050034 6.374892 270)
			(size 0.519938 1.4986)
			(layers "F.Cu" "F.Mask" "F.Paste")
			(net "GND")
		)
		(pad "78" smd rect
			(at -2.050034 7.22503 270)
			(size 0.519938 1.4986)
			(layers "F.Cu" "F.Mask" "F.Paste")
			(net "M_G_CPU0_SB_CA<2>")
		)
		(pad "79" smd rect
			(at -2.050034 8.074914 270)
			(size 0.519938 1.4986)
			(layers "F.Cu" "F.Mask" "F.Paste")
			(net "GND")
		)
		(pad "80" smd rect
			(at -2.050034 8.925052 270)
			(size 0.519938 1.4986)
			(layers "F.Cu" "F.Mask" "F.Paste")
			(net "M_G_CPU0_SB_CA<4>")
		)
		(pad "81" smd rect
			(at -2.050034 9.774936 270)
			(size 0.519938 1.4986)
			(layers "F.Cu" "F.Mask" "F.Paste")
			(net "GND")
		)
		(pad "82" smd rect
			(at -2.050034 10.625074 270)
			(size 0.519938 1.4986)
			(layers "F.Cu" "F.Mask" "F.Paste")
			(net "M_G_CPU0_SB_CA<6>")
		)
		(pad "83" smd rect
			(at -2.050034 11.474958 270)
			(size 0.519938 1.4986)
			(layers "F.Cu" "F.Mask" "F.Paste")
			(net "GND")
		)
		(pad "84" smd rect
			(at -2.050034 12.325096 270)
			(size 0.519938 1.4986)
			(layers "F.Cu" "F.Mask" "F.Paste")
			(net "M_G_CPU0_SB_CS_N<0>")
		)
		(pad "85" smd rect
			(at -2.050034 13.17498 270)
			(size 0.519938 1.4986)
			(layers "F.Cu" "F.Mask" "F.Paste")
			(net "GND")
		)
		(pad "86" smd rect
			(at -2.050034 14.025118 270)
			(size 0.519938 1.4986)
			(layers "F.Cu" "F.Mask" "F.Paste")
			(net "M_G_CPU0_SA_RSP<0>")
		)
		(pad "87" smd rect
			(at -2.050034 14.875002 270)
			(size 0.519938 1.4986)
			(layers "F.Cu" "F.Mask" "F.Paste")
			(net "M_G_CPU0_SB_RSP<0>")
		)
		(pad "88" smd rect
			(at -2.050034 15.724886 270)
			(size 0.519938 1.4986)
			(layers "F.Cu" "F.Mask" "F.Paste")
			(net "GND")
		)
		(pad "89" smd rect
			(at -2.050034 16.575024 270)
			(size 0.519938 1.4986)
			(layers "F.Cu" "F.Mask" "F.Paste")
			(net "M_G_CPU0_SB_CB<4>")
		)
		(pad "90" smd rect
			(at -2.050034 17.424908 270)
			(size 0.519938 1.4986)
			(layers "F.Cu" "F.Mask" "F.Paste")
			(net "GND")
		)
		(pad "91" smd rect
			(at -2.050034 18.275046 270)
			(size 0.519938 1.4986)
			(layers "F.Cu" "F.Mask" "F.Paste")
			(net "M_G_CPU0_SB_CB<5>")
		)
		(pad "92" smd rect
			(at -2.050034 19.12493 270)
			(size 0.519938 1.4986)
			(layers "F.Cu" "F.Mask" "F.Paste")
			(net "GND")
		)
		(pad "93" smd rect
			(at -2.050034 19.975068 270)
			(size 0.519938 1.4986)
			(layers "F.Cu" "F.Mask" "F.Paste")
			(net "M_G_CPU0_SB_DQS_DP<9>")
		)
		(pad "94" smd rect
			(at -2.050034 20.824952 270)
			(size 0.519938 1.4986)
			(layers "F.Cu" "F.Mask" "F.Paste")
			(net "M_G_CPU0_SB_DQS_DN<9>")
		)
		(pad "95" smd rect
			(at -2.050034 21.67509 270)
			(size 0.519938 1.4986)
			(layers "F.Cu" "F.Mask" "F.Paste")
			(net "GND")
		)
		(pad "96" smd rect
			(at -2.050034 22.524974 270)
			(size 0.519938 1.4986)
			(layers "F.Cu" "F.Mask" "F.Paste")
			(net "M_G_CPU0_SB_CB<0>")
		)
		(pad "97" smd rect
			(at -2.050034 23.375112 270)
			(size 0.519938 1.4986)
			(layers "F.Cu" "F.Mask" "F.Paste")
			(net "GND")
		)
		(pad "98" smd rect
			(at -2.050034 24.224996 270)
			(size 0.519938 1.4986)
			(layers "F.Cu" "F.Mask" "F.Paste")
			(net "M_G_CPU0_SB_CB<1>")
		)
		(pad "99" smd rect
			(at -2.050034 25.07488 270)
			(size 0.519938 1.4986)
			(layers "F.Cu" "F.Mask" "F.Paste")
			(net "GND")
		)
		(pad "100" smd rect
			(at -2.050034 25.925018 270)
			(size 0.519938 1.4986)
			(layers "F.Cu" "F.Mask" "F.Paste")
			(net "M_G_CPU0_SB_DQ<0>")
		)
		(pad "101" smd rect
			(at -2.050034 26.774902 270)
			(size 0.519938 1.4986)
			(layers "F.Cu" "F.Mask" "F.Paste")
			(net "GND")
		)
		(pad "102" smd rect
			(at -2.050034 27.62504 270)
			(size 0.519938 1.4986)
			(layers "F.Cu" "F.Mask" "F.Paste")
			(net "M_G_CPU0_SB_DQ<1>")
		)
		(pad "103" smd rect
			(at -2.050034 28.474924 270)
			(size 0.519938 1.4986)
			(layers "F.Cu" "F.Mask" "F.Paste")
			(net "GND")
		)
		(pad "104" smd rect
			(at -2.050034 29.325062 270)
			(size 0.519938 1.4986)
			(layers "F.Cu" "F.Mask" "F.Paste")
			(net "M_G_CPU0_SB_DQS_DP<0>")
		)
		(pad "105" smd rect
			(at -2.050034 30.174946 270)
			(size 0.519938 1.4986)
			(layers "F.Cu" "F.Mask" "F.Paste")
			(net "M_G_CPU0_SB_DQS_DN<0>")
		)
		(pad "106" smd rect
			(at -2.050034 31.025084 270)
			(size 0.519938 1.4986)
			(layers "F.Cu" "F.Mask" "F.Paste")
			(net "GND")
		)
		(pad "107" smd rect
			(at -2.050034 31.874968 270)
			(size 0.519938 1.4986)
			(layers "F.Cu" "F.Mask" "F.Paste")
			(net "M_G_CPU0_SB_DQ<4>")
		)
		(pad "108" smd rect
			(at -2.050034 32.725106 270)
			(size 0.519938 1.4986)
			(layers "F.Cu" "F.Mask" "F.Paste")
			(net "GND")
		)
		(pad "109" smd rect
			(at -2.050034 33.57499 270)
			(size 0.519938 1.4986)
			(layers "F.Cu" "F.Mask" "F.Paste")
			(net "M_G_CPU0_SB_DQ<5>")
		)
		(pad "110" smd rect
			(at -2.050034 34.425128 270)
			(size 0.519938 1.4986)
			(layers "F.Cu" "F.Mask" "F.Paste")
			(net "GND")
		)
		(pad "111" smd rect
			(at -2.050034 35.275012 270)
			(size 0.519938 1.4986)
			(layers "F.Cu" "F.Mask" "F.Paste")
			(net "M_G_CPU0_SB_DQ<8>")
		)
		(pad "112" smd rect
			(at -2.050034 36.124896 270)
			(size 0.519938 1.4986)
			(layers "F.Cu" "F.Mask" "F.Paste")
			(net "GND")
		)
		(pad "113" smd rect
			(at -2.050034 36.975034 270)
			(size 0.519938 1.4986)
			(layers "F.Cu" "F.Mask" "F.Paste")
			(net "M_G_CPU0_SB_DQ<9>")
		)
		(pad "114" smd rect
			(at -2.050034 37.824918 270)
			(size 0.519938 1.4986)
			(layers "F.Cu" "F.Mask" "F.Paste")
			(net "GND")
		)
		(pad "115" smd rect
			(at -2.050034 38.675056 270)
			(size 0.519938 1.4986)
			(layers "F.Cu" "F.Mask" "F.Paste")
			(net "M_G_CPU0_SB_DQS_DP<1>")
		)
		(pad "116" smd rect
			(at -2.050034 39.52494 270)
			(size 0.519938 1.4986)
			(layers "F.Cu" "F.Mask" "F.Paste")
			(net "M_G_CPU0_SB_DQS_DN<1>")
		)
		(pad "117" smd rect
			(at -2.050034 40.375078 270)
			(size 0.519938 1.4986)
			(layers "F.Cu" "F.Mask" "F.Paste")
			(net "GND")
		)
		(pad "118" smd rect
			(at -2.050034 41.224962 270)
			(size 0.519938 1.4986)
			(layers "F.Cu" "F.Mask" "F.Paste")
			(net "M_G_CPU0_SB_DQ<12>")
		)
		(pad "119" smd rect
			(at -2.050034 42.0751 270)
			(size 0.519938 1.4986)
			(layers "F.Cu" "F.Mask" "F.Paste")
			(net "GND")
		)
		(pad "120" smd rect
			(at -2.050034 42.924984 270)
			(size 0.519938 1.4986)
			(layers "F.Cu" "F.Mask" "F.Paste")
			(net "M_G_CPU0_SB_DQ<13>")
		)
		(pad "121" smd rect
			(at -2.050034 43.775122 270)
			(size 0.519938 1.4986)
			(layers "F.Cu" "F.Mask" "F.Paste")
			(net "GND")
		)
		(pad "122" smd rect
			(at -2.050034 44.625006 270)
			(size 0.519938 1.4986)
			(layers "F.Cu" "F.Mask" "F.Paste")
			(net "M_G_CPU0_SB_DQ<16>")
		)
		(pad "123" smd rect
			(at -2.050034 45.47489 270)
			(size 0.519938 1.4986)
			(layers "F.Cu" "F.Mask" "F.Paste")
			(net "GND")
		)
		(pad "124" smd rect
			(at -2.050034 46.325028 270)
			(size 0.519938 1.4986)
			(layers "F.Cu" "F.Mask" "F.Paste")
			(net "M_G_CPU0_SB_DQ<17>")
		)
		(pad "125" smd rect
			(at -2.050034 47.174912 270)
			(size 0.519938 1.4986)
			(layers "F.Cu" "F.Mask" "F.Paste")
			(net "GND")
		)
		(pad "126" smd rect
			(at -2.050034 48.02505 270)
			(size 0.519938 1.4986)
			(layers "F.Cu" "F.Mask" "F.Paste")
			(net "M_G_CPU0_SB_DQS_DP<2>")
		)
		(pad "127" smd rect
			(at -2.050034 48.874934 270)
			(size 0.519938 1.4986)
			(layers "F.Cu" "F.Mask" "F.Paste")
			(net "M_G_CPU0_SB_DQS_DN<2>")
		)
		(pad "128" smd rect
			(at -2.050034 49.725072 270)
			(size 0.519938 1.4986)
			(layers "F.Cu" "F.Mask" "F.Paste")
			(net "GND")
		)
		(pad "129" smd rect
			(at -2.050034 50.574956 270)
			(size 0.519938 1.4986)
			(layers "F.Cu" "F.Mask" "F.Paste")
			(net "M_G_CPU0_SB_DQ<20>")
		)
		(pad "130" smd rect
			(at -2.050034 51.425094 270)
			(size 0.519938 1.4986)
			(layers "F.Cu" "F.Mask" "F.Paste")
			(net "GND")
		)
		(pad "131" smd rect
			(at -2.050034 52.274978 270)
			(size 0.519938 1.4986)
			(layers "F.Cu" "F.Mask" "F.Paste")
			(net "M_G_CPU0_SB_DQ<21>")
		)
		(pad "132" smd rect
			(at -2.050034 53.125116 270)
			(size 0.519938 1.4986)
			(layers "F.Cu" "F.Mask" "F.Paste")
			(net "GND")
		)
		(pad "133" smd rect
			(at -2.050034 53.975 270)
			(size 0.519938 1.4986)
			(layers "F.Cu" "F.Mask" "F.Paste")
			(net "M_G_CPU0_SB_DQ<24>")
		)
		(pad "134" smd rect
			(at -2.050034 54.824884 270)
			(size 0.519938 1.4986)
			(layers "F.Cu" "F.Mask" "F.Paste")
			(net "GND")
		)
		(pad "135" smd rect
			(at -2.050034 55.675022 270)
			(size 0.519938 1.4986)
			(layers "F.Cu" "F.Mask" "F.Paste")
			(net "M_G_CPU0_SB_DQ<25>")
		)
		(pad "136" smd rect
			(at -2.050034 56.524906 270)
			(size 0.519938 1.4986)
			(layers "F.Cu" "F.Mask" "F.Paste")
			(net "GND")
		)
		(pad "137" smd rect
			(at -2.050034 57.375044 270)
			(size 0.519938 1.4986)
			(layers "F.Cu" "F.Mask" "F.Paste")
			(net "M_G_CPU0_SB_DQS_DP<3>")
		)
		(pad "138" smd rect
			(at -2.050034 58.224928 270)
			(size 0.519938 1.4986)
			(layers "F.Cu" "F.Mask" "F.Paste")
			(net "M_G_CPU0_SB_DQS_DN<3>")
		)
		(pad "139" smd rect
			(at -2.050034 59.075066 270)
			(size 0.519938 1.4986)
			(layers "F.Cu" "F.Mask" "F.Paste")
			(net "GND")
		)
		(pad "140" smd rect
			(at -2.050034 59.92495 270)
			(size 0.519938 1.4986)
			(layers "F.Cu" "F.Mask" "F.Paste")
			(net "M_G_CPU0_SB_DQ<28>")
		)
		(pad "141" smd rect
			(at -2.050034 60.775088 270)
			(size 0.519938 1.4986)
			(layers "F.Cu" "F.Mask" "F.Paste")
			(net "GND")
		)
		(pad "142" smd rect
			(at -2.050034 61.624972 270)
			(size 0.519938 1.4986)
			(layers "F.Cu" "F.Mask" "F.Paste")
			(net "M_G_CPU0_SB_DQ<29>")
		)
		(pad "143" smd rect
			(at -2.050034 62.47511 270)
			(size 0.519938 1.4986)
			(layers "F.Cu" "F.Mask" "F.Paste")
			(net "GND")
		)
		(pad "144" smd rect
			(at -2.050034 63.324994 270)
			(size 0.519938 1.4986)
			(layers "F.Cu" "F.Mask" "F.Paste")
			(net "TP_CHG_CPU0_DIMM1_FRU_1")
		)
		(pad "145" smd rect
			(at 2.050034 -63.324994 270)
			(size 0.519938 1.4986)
			(layers "F.Cu" "F.Mask" "F.Paste")
			(net "P12V_S3_AUX_CPU0_NVDIMM")
		)
		(pad "146" smd rect
			(at 2.050034 -62.47511 270)
			(size 0.519938 1.4986)
			(layers "F.Cu" "F.Mask" "F.Paste")
			(net "P12V_S3_AUX_CPU0_NVDIMM")
		)
		(pad "147" smd rect
			(at 2.050034 -61.624972 270)
			(size 0.519938 1.4986)
			(layers "F.Cu" "F.Mask" "F.Paste")
			(net "PWRGD_CHG_CPU0_DIMM1")
		)
		(pad "148" smd rect
			(at 2.050034 -60.775088 270)
			(size 0.519938 1.4986)
			(layers "F.Cu" "F.Mask" "F.Paste")
			(net "PD_CHG_CPU0_DIMM1_SAA")
		)
		(pad "149" smd rect
			(at 2.050034 -59.92495 270)
			(size 0.519938 1.4986)
			(layers "F.Cu" "F.Mask" "F.Paste")
			(net "TP_CHG_CPU0_DIMM1_FRU_2")
		)
		(pad "150" smd rect
			(at 2.050034 -59.075066 270)
			(size 0.519938 1.4986)
			(layers "F.Cu" "F.Mask" "F.Paste")
			(net "TP_CHG_CPU0_DIMM1_FRU_3")
		)
		(pad "151" smd rect
			(at 2.050034 -58.224928 270)
			(size 0.519938 1.4986)
			(layers "F.Cu" "F.Mask" "F.Paste")
			(net "GND")
		)
		(pad "152" smd rect
			(at 2.050034 -57.375044 270)
			(size 0.519938 1.4986)
			(layers "F.Cu" "F.Mask" "F.Paste")
			(net "M_G_CPU0_SA_DQ<2>")
		)
		(pad "153" smd rect
			(at 2.050034 -56.524906 270)
			(size 0.519938 1.4986)
			(layers "F.Cu" "F.Mask" "F.Paste")
			(net "GND")
		)
		(pad "154" smd rect
			(at 2.050034 -55.675022 270)
			(size 0.519938 1.4986)
			(layers "F.Cu" "F.Mask" "F.Paste")
			(net "M_G_CPU0_SA_DQ<3>")
		)
		(pad "155" smd rect
			(at 2.050034 -54.824884 270)
			(size 0.519938 1.4986)
			(layers "F.Cu" "F.Mask" "F.Paste")
			(net "GND")
		)
		(pad "156" smd rect
			(at 2.050034 -53.975 270)
			(size 0.519938 1.4986)
			(layers "F.Cu" "F.Mask" "F.Paste")
			(net "M_G_CPU0_SA_DQS_DN<5>")
		)
		(pad "157" smd rect
			(at 2.050034 -53.125116 270)
			(size 0.519938 1.4986)
			(layers "F.Cu" "F.Mask" "F.Paste")
			(net "M_G_CPU0_SA_DQS_DP<5>")
		)
		(pad "158" smd rect
			(at 2.050034 -52.274978 270)
			(size 0.519938 1.4986)
			(layers "F.Cu" "F.Mask" "F.Paste")
			(net "GND")
		)
		(pad "159" smd rect
			(at 2.050034 -51.425094 270)
			(size 0.519938 1.4986)
			(layers "F.Cu" "F.Mask" "F.Paste")
			(net "M_G_CPU0_SA_DQ<6>")
		)
		(pad "160" smd rect
			(at 2.050034 -50.574956 270)
			(size 0.519938 1.4986)
			(layers "F.Cu" "F.Mask" "F.Paste")
			(net "GND")
		)
		(pad "161" smd rect
			(at 2.050034 -49.725072 270)
			(size 0.519938 1.4986)
			(layers "F.Cu" "F.Mask" "F.Paste")
			(net "M_G_CPU0_SA_DQ<7>")
		)
		(pad "162" smd rect
			(at 2.050034 -48.874934 270)
			(size 0.519938 1.4986)
			(layers "F.Cu" "F.Mask" "F.Paste")
			(net "GND")
		)
		(pad "163" smd rect
			(at 2.050034 -48.02505 270)
			(size 0.519938 1.4986)
			(layers "F.Cu" "F.Mask" "F.Paste")
			(net "M_G_CPU0_SA_DQ<10>")
		)
		(pad "164" smd rect
			(at 2.050034 -47.174912 270)
			(size 0.519938 1.4986)
			(layers "F.Cu" "F.Mask" "F.Paste")
			(net "GND")
		)
		(pad "165" smd rect
			(at 2.050034 -46.325028 270)
			(size 0.519938 1.4986)
			(layers "F.Cu" "F.Mask" "F.Paste")
			(net "M_G_CPU0_SA_DQ<11>")
		)
		(pad "166" smd rect
			(at 2.050034 -45.47489 270)
			(size 0.519938 1.4986)
			(layers "F.Cu" "F.Mask" "F.Paste")
			(net "GND")
		)
		(pad "167" smd rect
			(at 2.050034 -44.625006 270)
			(size 0.519938 1.4986)
			(layers "F.Cu" "F.Mask" "F.Paste")
			(net "M_G_CPU0_SA_DQS_DN<6>")
		)
		(pad "168" smd rect
			(at 2.050034 -43.775122 270)
			(size 0.519938 1.4986)
			(layers "F.Cu" "F.Mask" "F.Paste")
			(net "M_G_CPU0_SA_DQS_DP<6>")
		)
		(pad "169" smd rect
			(at 2.050034 -42.924984 270)
			(size 0.519938 1.4986)
			(layers "F.Cu" "F.Mask" "F.Paste")
			(net "GND")
		)
		(pad "170" smd rect
			(at 2.050034 -42.0751 270)
			(size 0.519938 1.4986)
			(layers "F.Cu" "F.Mask" "F.Paste")
			(net "M_G_CPU0_SA_DQ<14>")
		)
		(pad "171" smd rect
			(at 2.050034 -41.224962 270)
			(size 0.519938 1.4986)
			(layers "F.Cu" "F.Mask" "F.Paste")
			(net "GND")
		)
		(pad "172" smd rect
			(at 2.050034 -40.375078 270)
			(size 0.519938 1.4986)
			(layers "F.Cu" "F.Mask" "F.Paste")
			(net "M_G_CPU0_SA_DQ<15>")
		)
		(pad "173" smd rect
			(at 2.050034 -39.52494 270)
			(size 0.519938 1.4986)
			(layers "F.Cu" "F.Mask" "F.Paste")
			(net "GND")
		)
		(pad "174" smd rect
			(at 2.050034 -38.675056 270)
			(size 0.519938 1.4986)
			(layers "F.Cu" "F.Mask" "F.Paste")
			(net "M_G_CPU0_SA_DQ<18>")
		)
		(pad "175" smd rect
			(at 2.050034 -37.824918 270)
			(size 0.519938 1.4986)
			(layers "F.Cu" "F.Mask" "F.Paste")
			(net "GND")
		)
		(pad "176" smd rect
			(at 2.050034 -36.975034 270)
			(size 0.519938 1.4986)
			(layers "F.Cu" "F.Mask" "F.Paste")
			(net "M_G_CPU0_SA_DQ<19>")
		)
		(pad "177" smd rect
			(at 2.050034 -36.124896 270)
			(size 0.519938 1.4986)
			(layers "F.Cu" "F.Mask" "F.Paste")
			(net "GND")
		)
		(pad "178" smd rect
			(at 2.050034 -35.275012 270)
			(size 0.519938 1.4986)
			(layers "F.Cu" "F.Mask" "F.Paste")
			(net "M_G_CPU0_SA_DQS_DN<7>")
		)
		(pad "179" smd rect
			(at 2.050034 -34.425128 270)
			(size 0.519938 1.4986)
			(layers "F.Cu" "F.Mask" "F.Paste")
			(net "M_G_CPU0_SA_DQS_DP<7>")
		)
		(pad "180" smd rect
			(at 2.050034 -33.57499 270)
			(size 0.519938 1.4986)
			(layers "F.Cu" "F.Mask" "F.Paste")
			(net "GND")
		)
		(pad "181" smd rect
			(at 2.050034 -32.725106 270)
			(size 0.519938 1.4986)
			(layers "F.Cu" "F.Mask" "F.Paste")
			(net "M_G_CPU0_SA_DQ<22>")
		)
		(pad "182" smd rect
			(at 2.050034 -31.874968 270)
			(size 0.519938 1.4986)
			(layers "F.Cu" "F.Mask" "F.Paste")
			(net "GND")
		)
		(pad "183" smd rect
			(at 2.050034 -31.025084 270)
			(size 0.519938 1.4986)
			(layers "F.Cu" "F.Mask" "F.Paste")
			(net "M_G_CPU0_SA_DQ<23>")
		)
		(pad "184" smd rect
			(at 2.050034 -30.174946 270)
			(size 0.519938 1.4986)
			(layers "F.Cu" "F.Mask" "F.Paste")
			(net "GND")
		)
		(pad "185" smd rect
			(at 2.050034 -29.325062 270)
			(size 0.519938 1.4986)
			(layers "F.Cu" "F.Mask" "F.Paste")
			(net "M_G_CPU0_SA_DQ<26>")
		)
		(pad "186" smd rect
			(at 2.050034 -28.474924 270)
			(size 0.519938 1.4986)
			(layers "F.Cu" "F.Mask" "F.Paste")
			(net "GND")
		)
		(pad "187" smd rect
			(at 2.050034 -27.62504 270)
			(size 0.519938 1.4986)
			(layers "F.Cu" "F.Mask" "F.Paste")
			(net "M_G_CPU0_SA_DQ<27>")
		)
		(pad "188" smd rect
			(at 2.050034 -26.774902 270)
			(size 0.519938 1.4986)
			(layers "F.Cu" "F.Mask" "F.Paste")
			(net "GND")
		)
		(pad "189" smd rect
			(at 2.050034 -25.925018 270)
			(size 0.519938 1.4986)
			(layers "F.Cu" "F.Mask" "F.Paste")
			(net "M_G_CPU0_SA_DQS_DN<8>")
		)
		(pad "190" smd rect
			(at 2.050034 -25.07488 270)
			(size 0.519938 1.4986)
			(layers "F.Cu" "F.Mask" "F.Paste")
			(net "M_G_CPU0_SA_DQS_DP<8>")
		)
		(pad "191" smd rect
			(at 2.050034 -24.224996 270)
			(size 0.519938 1.4986)
			(layers "F.Cu" "F.Mask" "F.Paste")
			(net "GND")
		)
		(pad "192" smd rect
			(at 2.050034 -23.375112 270)
			(size 0.519938 1.4986)
			(layers "F.Cu" "F.Mask" "F.Paste")
			(net "M_G_CPU0_SA_DQ<30>")
		)
		(pad "193" smd rect
			(at 2.050034 -22.524974 270)
			(size 0.519938 1.4986)
			(layers "F.Cu" "F.Mask" "F.Paste")
			(net "GND")
		)
		(pad "194" smd rect
			(at 2.050034 -21.67509 270)
			(size 0.519938 1.4986)
			(layers "F.Cu" "F.Mask" "F.Paste")
			(net "M_G_CPU0_SA_DQ<31>")
		)
		(pad "195" smd rect
			(at 2.050034 -20.824952 270)
			(size 0.519938 1.4986)
			(layers "F.Cu" "F.Mask" "F.Paste")
			(net "GND")
		)
		(pad "196" smd rect
			(at 2.050034 -19.975068 270)
			(size 0.519938 1.4986)
			(layers "F.Cu" "F.Mask" "F.Paste")
			(net "M_G_CPU0_SA_CB<2>")
		)
		(pad "197" smd rect
			(at 2.050034 -19.12493 270)
			(size 0.519938 1.4986)
			(layers "F.Cu" "F.Mask" "F.Paste")
			(net "GND")
		)
		(pad "198" smd rect
			(at 2.050034 -18.275046 270)
			(size 0.519938 1.4986)
			(layers "F.Cu" "F.Mask" "F.Paste")
			(net "M_G_CPU0_SA_CB<3>")
		)
		(pad "199" smd rect
			(at 2.050034 -17.424908 270)
			(size 0.519938 1.4986)
			(layers "F.Cu" "F.Mask" "F.Paste")
			(net "GND")
		)
		(pad "200" smd rect
			(at 2.050034 -16.575024 270)
			(size 0.519938 1.4986)
			(layers "F.Cu" "F.Mask" "F.Paste")
			(net "M_G_CPU0_SA_DQS_DN<9>")
		)
		(pad "201" smd rect
			(at 2.050034 -15.724886 270)
			(size 0.519938 1.4986)
			(layers "F.Cu" "F.Mask" "F.Paste")
			(net "M_G_CPU0_SA_DQS_DP<9>")
		)
		(pad "202" smd rect
			(at 2.050034 -14.875002 270)
			(size 0.519938 1.4986)
			(layers "F.Cu" "F.Mask" "F.Paste")
			(net "GND")
		)
		(pad "203" smd rect
			(at 2.050034 -14.025118 270)
			(size 0.519938 1.4986)
			(layers "F.Cu" "F.Mask" "F.Paste")
			(net "M_G_CPU0_SA_CB<6>")
		)
		(pad "204" smd rect
			(at 2.050034 -13.17498 270)
			(size 0.519938 1.4986)
			(layers "F.Cu" "F.Mask" "F.Paste")
			(net "GND")
		)
		(pad "205" smd rect
			(at 2.050034 -12.325096 270)
			(size 0.519938 1.4986)
			(layers "F.Cu" "F.Mask" "F.Paste")
			(net "M_G_CPU0_SA_CB<7>")
		)
		(pad "206" smd rect
			(at 2.050034 -11.474958 270)
			(size 0.519938 1.4986)
			(layers "F.Cu" "F.Mask" "F.Paste")
			(net "GND")
		)
		(pad "207" smd rect
			(at 2.050034 -10.625074 270)
			(size 0.519938 1.4986)
			(layers "F.Cu" "F.Mask" "F.Paste")
			(net "RST_M_GH_CPU0_FPGA_N")
		)
		(pad "208" smd rect
			(at 2.050034 -9.774936 270)
			(size 0.519938 1.4986)
			(layers "F.Cu" "F.Mask" "F.Paste")
			(net "GND")
		)
		(pad "209" smd rect
			(at 2.050034 -8.925052 270)
			(size 0.519938 1.4986)
			(layers "F.Cu" "F.Mask" "F.Paste")
			(net "M_G_CPU0_SA_CS_N<1>")
		)
		(pad "210" smd rect
			(at 2.050034 -8.074914 270)
			(size 0.519938 1.4986)
			(layers "F.Cu" "F.Mask" "F.Paste")
			(net "GND")
		)
		(pad "211" smd rect
			(at 2.050034 -7.22503 270)
			(size 0.519938 1.4986)
			(layers "F.Cu" "F.Mask" "F.Paste")
			(net "M_G_CPU0_SA_CA<1>")
		)
		(pad "212" smd rect
			(at 2.050034 -6.374892 270)
			(size 0.519938 1.4986)
			(layers "F.Cu" "F.Mask" "F.Paste")
			(net "GND")
		)
		(pad "213" smd rect
			(at 2.050034 -5.525008 270)
			(size 0.519938 1.4986)
			(layers "F.Cu" "F.Mask" "F.Paste")
			(net "M_G_CPU0_SA_CA<3>")
		)
		(pad "214" smd rect
			(at 2.050034 -4.675124 270)
			(size 0.519938 1.4986)
			(layers "F.Cu" "F.Mask" "F.Paste")
			(net "GND")
		)
		(pad "215" smd rect
			(at 2.050034 -3.824986 270)
			(size 0.519938 1.4986)
			(layers "F.Cu" "F.Mask" "F.Paste")
			(net "M_G_CPU0_SA_CA<5>")
		)
		(pad "216" smd rect
			(at 2.050034 -2.975102 270)
			(size 0.519938 1.4986)
			(layers "F.Cu" "F.Mask" "F.Paste")
			(net "GND")
		)
		(pad "217" smd rect
			(at 2.050034 -2.124964 270)
			(size 0.519938 1.4986)
			(layers "F.Cu" "F.Mask" "F.Paste")
			(net "M_G_CPU0_CLK_DP<0>")
		)
		(pad "218" smd rect
			(at 2.050034 -1.27508 270)
			(size 0.519938 1.4986)
			(layers "F.Cu" "F.Mask" "F.Paste")
			(net "M_G_CPU0_CLK_DN<0>")
		)
		(pad "219" smd rect
			(at 2.050034 -0.424942 270)
			(size 0.519938 1.4986)
			(layers "F.Cu" "F.Mask" "F.Paste")
			(net "GND")
		)
		(pad "220" smd rect
			(at 2.050034 5.525008 270)
			(size 0.519938 1.4986)
			(layers "F.Cu" "F.Mask" "F.Paste")
			(net "TP_CHG_CPU0_DIMM1_FRU_4")
		)
		(pad "221" smd rect
			(at 2.050034 6.374892 270)
			(size 0.519938 1.4986)
			(layers "F.Cu" "F.Mask" "F.Paste")
			(net "M_G_CPU0_SB_CA<1>")
		)
		(pad "222" smd rect
			(at 2.050034 7.22503 270)
			(size 0.519938 1.4986)
			(layers "F.Cu" "F.Mask" "F.Paste")
			(net "GND")
		)
		(pad "223" smd rect
			(at 2.050034 8.074914 270)
			(size 0.519938 1.4986)
			(layers "F.Cu" "F.Mask" "F.Paste")
			(net "M_G_CPU0_SB_CA<3>")
		)
		(pad "224" smd rect
			(at 2.050034 8.925052 270)
			(size 0.519938 1.4986)
			(layers "F.Cu" "F.Mask" "F.Paste")
			(net "GND")
		)
		(pad "225" smd rect
			(at 2.050034 9.774936 270)
			(size 0.519938 1.4986)
			(layers "F.Cu" "F.Mask" "F.Paste")
			(net "M_G_CPU0_SB_CA<5>")
		)
		(pad "226" smd rect
			(at 2.050034 10.625074 270)
			(size 0.519938 1.4986)
			(layers "F.Cu" "F.Mask" "F.Paste")
			(net "GND")
		)
		(pad "227" smd rect
			(at 2.050034 11.474958 270)
			(size 0.519938 1.4986)
			(layers "F.Cu" "F.Mask" "F.Paste")
			(net "M_G_CPU0_SB_PAR")
		)
		(pad "228" smd rect
			(at 2.050034 12.325096 270)
			(size 0.519938 1.4986)
			(layers "F.Cu" "F.Mask" "F.Paste")
			(net "GND")
		)
		(pad "229" smd rect
			(at 2.050034 13.17498 270)
			(size 0.519938 1.4986)
			(layers "F.Cu" "F.Mask" "F.Paste")
			(net "M_G_CPU0_SB_CS_N<1>")
		)
		(pad "230" smd rect
			(at 2.050034 14.025118 270)
			(size 0.519938 1.4986)
			(layers "F.Cu" "F.Mask" "F.Paste")
			(net "GND")
		)
		(pad "231" smd rect
			(at 2.050034 14.875002 270)
			(size 0.519938 1.4986)
			(layers "F.Cu" "F.Mask" "F.Paste")
			(net "TP_CHG_CPU0_DIMM1_FRU_5")
		)
		(pad "232" smd rect
			(at 2.050034 15.724886 270)
			(size 0.519938 1.4986)
			(layers "F.Cu" "F.Mask" "F.Paste")
			(net "TP_CHG_CPU0_DIMM1_FRU_6")
		)
		(pad "233" smd rect
			(at 2.050034 16.575024 270)
			(size 0.519938 1.4986)
			(layers "F.Cu" "F.Mask" "F.Paste")
			(net "GND")
		)
		(pad "234" smd rect
			(at 2.050034 17.424908 270)
			(size 0.519938 1.4986)
			(layers "F.Cu" "F.Mask" "F.Paste")
			(net "M_G_CPU0_SB_CB<6>")
		)
		(pad "235" smd rect
			(at 2.050034 18.275046 270)
			(size 0.519938 1.4986)
			(layers "F.Cu" "F.Mask" "F.Paste")
			(net "GND")
		)
		(pad "236" smd rect
			(at 2.050034 19.12493 270)
			(size 0.519938 1.4986)
			(layers "F.Cu" "F.Mask" "F.Paste")
			(net "M_G_CPU0_SB_CB<7>")
		)
		(pad "237" smd rect
			(at 2.050034 19.975068 270)
			(size 0.519938 1.4986)
			(layers "F.Cu" "F.Mask" "F.Paste")
			(net "GND")
		)
		(pad "238" smd rect
			(at 2.050034 20.824952 270)
			(size 0.519938 1.4986)
			(layers "F.Cu" "F.Mask" "F.Paste")
			(net "M_G_CPU0_SB_DQS_DN<4>")
		)
		(pad "239" smd rect
			(at 2.050034 21.67509 270)
			(size 0.519938 1.4986)
			(layers "F.Cu" "F.Mask" "F.Paste")
			(net "M_G_CPU0_SB_DQS_DP<4>")
		)
		(pad "240" smd rect
			(at 2.050034 22.524974 270)
			(size 0.519938 1.4986)
			(layers "F.Cu" "F.Mask" "F.Paste")
			(net "GND")
		)
		(pad "241" smd rect
			(at 2.050034 23.375112 270)
			(size 0.519938 1.4986)
			(layers "F.Cu" "F.Mask" "F.Paste")
			(net "M_G_CPU0_SB_CB<2>")
		)
		(pad "242" smd rect
			(at 2.050034 24.224996 270)
			(size 0.519938 1.4986)
			(layers "F.Cu" "F.Mask" "F.Paste")
			(net "GND")
		)
		(pad "243" smd rect
			(at 2.050034 25.07488 270)
			(size 0.519938 1.4986)
			(layers "F.Cu" "F.Mask" "F.Paste")
			(net "M_G_CPU0_SB_CB<3>")
		)
		(pad "244" smd rect
			(at 2.050034 25.925018 270)
			(size 0.519938 1.4986)
			(layers "F.Cu" "F.Mask" "F.Paste")
			(net "GND")
		)
		(pad "245" smd rect
			(at 2.050034 26.774902 270)
			(size 0.519938 1.4986)
			(layers "F.Cu" "F.Mask" "F.Paste")
			(net "M_G_CPU0_SB_DQ<2>")
		)
		(pad "246" smd rect
			(at 2.050034 27.62504 270)
			(size 0.519938 1.4986)
			(layers "F.Cu" "F.Mask" "F.Paste")
			(net "GND")
		)
		(pad "247" smd rect
			(at 2.050034 28.474924 270)
			(size 0.519938 1.4986)
			(layers "F.Cu" "F.Mask" "F.Paste")
			(net "M_G_CPU0_SB_DQ<3>")
		)
		(pad "248" smd rect
			(at 2.050034 29.325062 270)
			(size 0.519938 1.4986)
			(layers "F.Cu" "F.Mask" "F.Paste")
			(net "GND")
		)
		(pad "249" smd rect
			(at 2.050034 30.174946 270)
			(size 0.519938 1.4986)
			(layers "F.Cu" "F.Mask" "F.Paste")
			(net "M_G_CPU0_SB_DQS_DN<5>")
		)
		(pad "250" smd rect
			(at 2.050034 31.025084 270)
			(size 0.519938 1.4986)
			(layers "F.Cu" "F.Mask" "F.Paste")
			(net "M_G_CPU0_SB_DQS_DP<5>")
		)
		(pad "251" smd rect
			(at 2.050034 31.874968 270)
			(size 0.519938 1.4986)
			(layers "F.Cu" "F.Mask" "F.Paste")
			(net "GND")
		)
		(pad "252" smd rect
			(at 2.050034 32.725106 270)
			(size 0.519938 1.4986)
			(layers "F.Cu" "F.Mask" "F.Paste")
			(net "M_G_CPU0_SB_DQ<6>")
		)
		(pad "253" smd rect
			(at 2.050034 33.57499 270)
			(size 0.519938 1.4986)
			(layers "F.Cu" "F.Mask" "F.Paste")
			(net "GND")
		)
		(pad "254" smd rect
			(at 2.050034 34.425128 270)
			(size 0.519938 1.4986)
			(layers "F.Cu" "F.Mask" "F.Paste")
			(net "M_G_CPU0_SB_DQ<7>")
		)
		(pad "255" smd rect
			(at 2.050034 35.275012 270)
			(size 0.519938 1.4986)
			(layers "F.Cu" "F.Mask" "F.Paste")
			(net "GND")
		)
		(pad "256" smd rect
			(at 2.050034 36.124896 270)
			(size 0.519938 1.4986)
			(layers "F.Cu" "F.Mask" "F.Paste")
			(net "M_G_CPU0_SB_DQ<10>")
		)
		(pad "257" smd rect
			(at 2.050034 36.975034 270)
			(size 0.519938 1.4986)
			(layers "F.Cu" "F.Mask" "F.Paste")
			(net "GND")
		)
		(pad "258" smd rect
			(at 2.050034 37.824918 270)
			(size 0.519938 1.4986)
			(layers "F.Cu" "F.Mask" "F.Paste")
			(net "M_G_CPU0_SB_DQ<11>")
		)
		(pad "259" smd rect
			(at 2.050034 38.675056 270)
			(size 0.519938 1.4986)
			(layers "F.Cu" "F.Mask" "F.Paste")
			(net "GND")
		)
		(pad "260" smd rect
			(at 2.050034 39.52494 270)
			(size 0.519938 1.4986)
			(layers "F.Cu" "F.Mask" "F.Paste")
			(net "M_G_CPU0_SB_DQS_DN<6>")
		)
		(pad "261" smd rect
			(at 2.050034 40.375078 270)
			(size 0.519938 1.4986)
			(layers "F.Cu" "F.Mask" "F.Paste")
			(net "M_G_CPU0_SB_DQS_DP<6>")
		)
		(pad "262" smd rect
			(at 2.050034 41.224962 270)
			(size 0.519938 1.4986)
			(layers "F.Cu" "F.Mask" "F.Paste")
			(net "GND")
		)
		(pad "263" smd rect
			(at 2.050034 42.0751 270)
			(size 0.519938 1.4986)
			(layers "F.Cu" "F.Mask" "F.Paste")
			(net "M_G_CPU0_SB_DQ<14>")
		)
		(pad "264" smd rect
			(at 2.050034 42.924984 270)
			(size 0.519938 1.4986)
			(layers "F.Cu" "F.Mask" "F.Paste")
			(net "GND")
		)
		(pad "265" smd rect
			(at 2.050034 43.775122 270)
			(size 0.519938 1.4986)
			(layers "F.Cu" "F.Mask" "F.Paste")
			(net "M_G_CPU0_SB_DQ<15>")
		)
		(pad "266" smd rect
			(at 2.050034 44.625006 270)
			(size 0.519938 1.4986)
			(layers "F.Cu" "F.Mask" "F.Paste")
			(net "GND")
		)
		(pad "267" smd rect
			(at 2.050034 45.47489 270)
			(size 0.519938 1.4986)
			(layers "F.Cu" "F.Mask" "F.Paste")
			(net "M_G_CPU0_SB_DQ<18>")
		)
		(pad "268" smd rect
			(at 2.050034 46.325028 270)
			(size 0.519938 1.4986)
			(layers "F.Cu" "F.Mask" "F.Paste")
			(net "GND")
		)
		(pad "269" smd rect
			(at 2.050034 47.174912 270)
			(size 0.519938 1.4986)
			(layers "F.Cu" "F.Mask" "F.Paste")
			(net "M_G_CPU0_SB_DQ<19>")
		)
		(pad "270" smd rect
			(at 2.050034 48.02505 270)
			(size 0.519938 1.4986)
			(layers "F.Cu" "F.Mask" "F.Paste")
			(net "GND")
		)
		(pad "271" smd rect
			(at 2.050034 48.874934 270)
			(size 0.519938 1.4986)
			(layers "F.Cu" "F.Mask" "F.Paste")
			(net "M_G_CPU0_SB_DQS_DN<7>")
		)
		(pad "272" smd rect
			(at 2.050034 49.725072 270)
			(size 0.519938 1.4986)
			(layers "F.Cu" "F.Mask" "F.Paste")
			(net "M_G_CPU0_SB_DQS_DP<7>")
		)
		(pad "273" smd rect
			(at 2.050034 50.574956 270)
			(size 0.519938 1.4986)
			(layers "F.Cu" "F.Mask" "F.Paste")
			(net "GND")
		)
		(pad "274" smd rect
			(at 2.050034 51.425094 270)
			(size 0.519938 1.4986)
			(layers "F.Cu" "F.Mask" "F.Paste")
			(net "M_G_CPU0_SB_DQ<22>")
		)
		(pad "275" smd rect
			(at 2.050034 52.274978 270)
			(size 0.519938 1.4986)
			(layers "F.Cu" "F.Mask" "F.Paste")
			(net "GND")
		)
		(pad "276" smd rect
			(at 2.050034 53.125116 270)
			(size 0.519938 1.4986)
			(layers "F.Cu" "F.Mask" "F.Paste")
			(net "M_G_CPU0_SB_DQ<23>")
		)
		(pad "277" smd rect
			(at 2.050034 53.975 270)
			(size 0.519938 1.4986)
			(layers "F.Cu" "F.Mask" "F.Paste")
			(net "GND")
		)
		(pad "278" smd rect
			(at 2.050034 54.824884 270)
			(size 0.519938 1.4986)
			(layers "F.Cu" "F.Mask" "F.Paste")
			(net "M_G_CPU0_SB_DQ<26>")
		)
		(pad "279" smd rect
			(at 2.050034 55.675022 270)
			(size 0.519938 1.4986)
			(layers "F.Cu" "F.Mask" "F.Paste")
			(net "GND")
		)
		(pad "280" smd rect
			(at 2.050034 56.524906 270)
			(size 0.519938 1.4986)
			(layers "F.Cu" "F.Mask" "F.Paste")
			(net "M_G_CPU0_SB_DQ<27>")
		)
		(pad "281" smd rect
			(at 2.050034 57.375044 270)
			(size 0.519938 1.4986)
			(layers "F.Cu" "F.Mask" "F.Paste")
			(net "GND")
		)
		(pad "282" smd rect
			(at 2.050034 58.224928 270)
			(size 0.519938 1.4986)
			(layers "F.Cu" "F.Mask" "F.Paste")
			(net "M_G_CPU0_SB_DQS_DN<8>")
		)
		(pad "283" smd rect
			(at 2.050034 59.075066 270)
			(size 0.519938 1.4986)
			(layers "F.Cu" "F.Mask" "F.Paste")
			(net "M_G_CPU0_SB_DQS_DP<8>")
		)
		(pad "284" smd rect
			(at 2.050034 59.92495 270)
			(size 0.519938 1.4986)
			(layers "F.Cu" "F.Mask" "F.Paste")
			(net "GND")
		)
		(pad "285" smd rect
			(at 2.050034 60.775088 270)
			(size 0.519938 1.4986)
			(layers "F.Cu" "F.Mask" "F.Paste")
			(net "M_G_CPU0_SB_DQ<30>")
		)
		(pad "286" smd rect
			(at 2.050034 61.624972 270)
			(size 0.519938 1.4986)
			(layers "F.Cu" "F.Mask" "F.Paste")
			(net "GND")
		)
		(pad "287" smd rect
			(at 2.050034 62.47511 270)
			(size 0.519938 1.4986)
			(layers "F.Cu" "F.Mask" "F.Paste")
			(net "M_G_CPU0_SB_DQ<31>")
		)
		(pad "288" smd rect
			(at 2.050034 63.324994 270)
			(size 0.519938 1.4986)
			(layers "F.Cu" "F.Mask" "F.Paste")
			(net "GND")
		)
		(pad "G1" thru_hole oval
			(at 0 -68.97497)
			(size 2.8194 1.5748)
			(drill oval 2.4384 1.1938)
			(layers "*.Cu" "*.Mask")
			(remove_unused_layers no)
			(net "GND")
			(clearance 0.127)
			(thermal_gap 0.127)
		)
		(pad "G2" thru_hole oval
			(at 0 3.875024)
			(size 2.8194 1.5748)
			(drill oval 2.4384 1.1938)
			(layers "*.Cu" "*.Mask")
			(remove_unused_layers no)
			(net "GND")
			(clearance 0.127)
			(thermal_gap 0.127)
		)
		(pad "G3" thru_hole oval
			(at 0 68.97497)
			(size 2.8194 1.5748)
			(drill oval 2.4384 1.1938)
			(layers "*.Cu" "*.Mask")
			(remove_unused_layers no)
			(net "GND")
			(clearance 0.127)
			(thermal_gap 0.127)
		)
	)
	(footprint ""
		(layer "F.Cu")
		(at 352.663252 -315.66739 90)
		(property "Reference" "PC322"
			(at 0 0 90)
			(layer "F.SilkS")
			(hide yes)
			(effects
				(font
					(size 1.27 1.27)
				)
			)
		)
		(property "Value" ""
			(at 0 0 90)
			(layer "F.Fab")
			(effects
				(font
					(size 1.27 1.27)
				)
			)
		)
		(duplicate_pad_numbers_are_jumpers no)
		(fp_line
			(start 2.750058 0.999998)
			(end -2.750058 0.999998)
			(stroke
				(width 0.1524)
				(type default)
			)
			(layer "F.SilkS")
		)
		(fp_circle
			(center 0 0.999998)
			(end 0 3.750056)
			(stroke
				(width 0.1524)
				(type default)
			)
			(fill no)
			(layer "F.SilkS")
		)
		(fp_poly
			(pts
				(arc
					(start 2.750058 0.999998)
					(mid 0 3.750056)
					(end -2.750058 0.999998)
				)
			)
			(stroke
				(width 0)
				(type default)
			)
			(fill yes)
			(layer "F.SilkS")
		)
		(fp_circle
			(center 0 0.999998)
			(end 0 3.750056)
			(stroke
				(width 0.1)
				(type default)
			)
			(fill no)
			(layer "F.Fab")
		)
		(pad "1" thru_hole rect
			(at 0 0 90)
			(size 1.5748 1.5748)
			(drill 1.0668)
			(layers "*.Cu" "*.Mask")
			(remove_unused_layers no)
			(net "PVCCIN_CPU0")
			(clearance 0)
			(padstack
				(mode front_inner_back)
				(layer "Inner"
					(shape circle)
					(size 1.5748 1.5748)
					(clearance 0)
				)
				(layer "B.Cu"
					(shape rect)
					(size 1.5748 1.5748)
					(clearance 0)
				)
			)
		)
		(pad "2" thru_hole circle
			(at 0 1.999996 90)
			(size 1.5748 1.5748)
			(drill 1.0668)
			(layers "*.Cu" "*.Mask")
			(remove_unused_layers no)
			(net "GND")
			(clearance 0)
		)
	)
	(footprint ""
		(layer "F.Cu")
		(at 54.89956 -165.11397 90)
		(property "Reference" "PU17"
			(at 1.74498 -9.2075 0)
			(unlocked yes)
			(layer "F.SilkS")
			(effects
				(font
					(size 0.7874 0.5842)
					(thickness 0.1524)
				)
				(justify left)
			)
		)
		(property "Value" ""
			(at 0 0 90)
			(layer "F.Fab")
			(effects
				(font
					(size 1.27 1.27)
				)
			)
		)
		(duplicate_pad_numbers_are_jumpers no)
		(fp_line
			(start 2.500122 -2.999994)
			(end 2.500122 -2.44348)
			(stroke
				(width 0.1524)
				(type default)
			)
			(layer "F.SilkS")
		)
		(fp_line
			(start 2.31394 -2.999994)
			(end 2.500122 -2.999994)
			(stroke
				(width 0.1524)
				(type default)
			)
			(layer "F.SilkS")
		)
		(fp_line
			(start -2.500122 -2.999994)
			(end -2.24409 -2.999994)
			(stroke
				(width 0.1524)
				(type default)
			)
			(layer "F.SilkS")
		)
		(fp_line
			(start -2.500122 -2.529078)
			(end -2.500122 -2.999994)
			(stroke
				(width 0.1524)
				(type default)
			)
			(layer "F.SilkS")
		)
		(fp_line
			(start -2.500122 0.6604)
			(end -2.500122 0.229108)
			(stroke
				(width 0.1524)
				(type default)
			)
			(layer "F.SilkS")
		)
		(fp_line
			(start 2.500122 2.339594)
			(end 2.500122 2.999994)
			(stroke
				(width 0.1524)
				(type default)
			)
			(layer "F.SilkS")
		)
		(fp_line
			(start 2.500122 2.999994)
			(end 2.2987 2.999994)
			(stroke
				(width 0.1524)
				(type default)
			)
			(layer "F.SilkS")
		)
		(fp_line
			(start -2.2987 2.999994)
			(end -2.500122 2.999994)
			(stroke
				(width 0.1524)
				(type default)
			)
			(layer "F.SilkS")
		)
		(fp_line
			(start -2.500122 2.999994)
			(end -2.500122 2.339594)
			(stroke
				(width 0.1524)
				(type default)
			)
			(layer "F.SilkS")
		)
		(fp_poly
			(pts
				(xy -5.130292 -2.813558) (xy -5.130292 -1.797558) (xy -4.114292 -2.305558)
			)
			(stroke
				(width 0)
				(type default)
			)
			(fill yes)
			(layer "F.SilkS")
		)
		(fp_line
			(start 2.500122 -2.999994)
			(end 2.500122 2.999994)
			(stroke
				(width 0.1)
				(type default)
			)
			(layer "F.Fab")
		)
		(fp_line
			(start -2.500122 -2.999994)
			(end 2.500122 -2.999994)
			(stroke
				(width 0.1)
				(type default)
			)
			(layer "F.Fab")
		)
		(fp_line
			(start 2.500122 2.999994)
			(end -2.500122 2.999994)
			(stroke
				(width 0.1)
				(type default)
			)
			(layer "F.Fab")
		)
		(fp_line
			(start -2.500122 2.999994)
			(end -2.500122 -2.999994)
			(stroke
				(width 0.1)
				(type default)
			)
			(layer "F.Fab")
		)
		(fp_poly
			(pts
				(xy -4.218432 -2.783078) (xy -4.218432 -1.767078) (xy -3.202432 -2.275078)
			)
			(stroke
				(width 0)
				(type default)
			)
			(fill yes)
			(layer "F.Fab")
		)
		(pad "1" smd rect
			(at -2.400046 -2.275078 180)
			(size 0.2286 0.6096)
			(layers "F.Cu" "F.Mask" "F.Paste")
			(net "PVCCD_HV_CPU1_VOS")
		)
		(pad "2" smd rect
			(at -2.400046 -1.82499 180)
			(size 0.2286 0.6096)
			(layers "F.Cu" "F.Mask" "F.Paste")
			(net "GND")
		)
		(pad "3" smd rect
			(at -2.400046 -1.374902 180)
			(size 0.2286 0.6096)
			(layers "F.Cu" "F.Mask" "F.Paste")
			(net "PVCCD_HV_CPU1_VDD1")
		)
		(pad "4" smd rect
			(at -2.400046 -0.925068 180)
			(size 0.2286 0.6096)
			(layers "F.Cu" "F.Mask" "F.Paste")
			(net "PVCCFA_EHV_CPU1_PVCC")
		)
		(pad "5" smd rect
			(at -2.400046 -0.47498 180)
			(size 0.2286 0.6096)
			(layers "F.Cu" "F.Mask" "F.Paste")
			(net "GND")
		)
		(pad "6" smd rect
			(at -2.400046 -0.024892 180)
			(size 0.2286 0.6096)
			(layers "F.Cu" "F.Mask" "F.Paste")
			(net "Net_1917")
		)
		(pad "7_9-20_24" smd circle
			(at 0 1.150112 180)
			(size 0 0)
			(layers "F.Cu" "F.Mask" "F.Paste")
			(net "GND")
		)
		(pad "10_19" smd rect
			(at 0 2.899918 180)
			(size 0.6096 4.318)
			(layers "F.Cu" "F.Mask" "F.Paste")
			(net "SW_PVCCD_HV_CPU1_SW1")
		)
		(pad "25_29" smd rect
			(at 1.549908 -1.279906)
			(size 2.0574 2.3114)
			(layers "F.Cu" "F.Mask" "F.Paste")
			(net "SW_P12V_PVCCINFAON_CPU1_FLT")
		)
		(pad "30" smd rect
			(at 2.05994 -2.899918 90)
			(size 0.2286 0.6096)
			(layers "F.Cu" "F.Mask" "F.Paste")
			(net "SW_P12V_PVCCINFAON_CPU1_FLT")
		)
		(pad "31" smd rect
			(at 1.610106 -2.899918 90)
			(size 0.2286 0.6096)
			(layers "F.Cu" "F.Mask" "F.Paste")
			(net "Net_1916")
		)
		(pad "32" smd rect
			(at 1.160018 -2.899918 90)
			(size 0.2286 0.6096)
			(layers "F.Cu" "F.Mask" "F.Paste")
			(net "SW_PVCCD_HV_CPU1_BOOTR1")
		)
		(pad "33" smd rect
			(at 0.70993 -2.899918 90)
			(size 0.2286 0.6096)
			(layers "F.Cu" "F.Mask" "F.Paste")
			(net "SW_PVCCD_HV_CPU1_BOOT1")
		)
		(pad "34" smd rect
			(at 0.260096 -2.899918 90)
			(size 0.2286 0.6096)
			(layers "F.Cu" "F.Mask" "F.Paste")
			(net "PVCCD_HV_CPU1_APWM1")
		)
		(pad "35" smd rect
			(at -0.189992 -2.899918 90)
			(size 0.2286 0.6096)
			(layers "F.Cu" "F.Mask" "F.Paste")
			(net "PVCCD_HV_CPU1_VDD1")
		)
		(pad "36" smd rect
			(at -0.64008 -2.899918 90)
			(size 0.2286 0.6096)
			(layers "F.Cu" "F.Mask" "F.Paste")
			(net "PVCCD_HV_CPU1_ATSEN")
		)
		(pad "37" smd rect
			(at -1.089914 -2.899918 90)
			(size 0.2286 0.6096)
			(layers "F.Cu" "F.Mask" "F.Paste")
			(net "PVCCD_HV_CPU1_LSET1")
		)
		(pad "38" smd rect
			(at -1.540002 -2.899918 90)
			(size 0.2286 0.6096)
			(layers "F.Cu" "F.Mask" "F.Paste")
			(net "PVCCD_HV_CPU1_ACSP1")
		)
		(pad "39" smd rect
			(at -1.99009 -2.899918 90)
			(size 0.2286 0.6096)
			(layers "F.Cu" "F.Mask" "F.Paste")
			(net "PVCCD_HV_CPU1_VREF")
		)
		(pad "40" smd rect
			(at -0.87503 -1.27508 90)
			(size 1.7526 1.9558)
			(layers "F.Cu" "F.Mask" "F.Paste")
			(net "GND")
		)
		(pad "41" smd rect
			(at -1.525016 0.249936)
			(size 0.3048 0.4572)
			(layers "F.Cu" "F.Mask" "F.Paste")
			(net "Net_1918")
		)
		(zone
			(layer "F.Cu")
			(hatch none 0.5)
			(connect_pads
				(clearance 0)
			)
			(min_thickness 0.25)
			(keepout
				(tracks not_allowed)
				(vias allowed)
				(pads allowed)
				(copperpour not_allowed)
				(footprints allowed)
			)
			(placement
				(enabled no)
				(sheetname "")
			)
			(fill
				(thermal_gap 0.5)
				(thermal_bridge_width 0.5)
				(island_removal_mode 0)
			)
			(polygon
				(pts
					(xy 57.899554 -162.613848) (xy 57.385966 -162.613848) (xy 57.150254 -162.84956) (xy 57.150254 -167.408606)
					(xy 57.35574 -167.614092) (xy 57.899554 -167.614092) (xy 57.899554 -167.32377) (xy 57.443878 -167.32377)
					(xy 57.443878 -162.90417) (xy 57.899554 -162.90417)
				)
			)
		)
	)
	(footprint ""
		(layer "F.Cu")
		(at 27.628596 -392.326876)
		(property "Reference" "R3267"
			(at 0 0 0)
			(layer "F.SilkS")
			(hide yes)
			(effects
				(font
					(size 1.27 1.27)
				)
			)
		)
		(property "Value" ""
			(at 0 0 0)
			(layer "F.Fab")
			(effects
				(font
					(size 1.27 1.27)
				)
			)
		)
		(duplicate_pad_numbers_are_jumpers no)
		(fp_line
			(start -0.7874 -0.4064)
			(end 0.7874 -0.4064)
			(stroke
				(width 0.1524)
				(type default)
			)
			(layer "F.SilkS")
		)
		(fp_line
			(start -0.7874 0.4064)
			(end -0.7874 -0.4064)
			(stroke
				(width 0.1524)
				(type default)
			)
			(layer "F.SilkS")
		)
		(fp_line
			(start 0.7874 -0.4064)
			(end 0.7874 0.4064)
			(stroke
				(width 0.1524)
				(type default)
			)
			(layer "F.SilkS")
		)
		(fp_line
			(start 0.7874 0.4064)
			(end -0.7874 0.4064)
			(stroke
				(width 0.1524)
				(type default)
			)
			(layer "F.SilkS")
		)
		(fp_line
			(start -0.67945 -0.305054)
			(end -0.12065 -0.305054)
			(stroke
				(width 0.1)
				(type default)
			)
			(layer "F.Fab")
		)
		(fp_line
			(start -0.67945 0.3048)
			(end -0.67945 -0.305054)
			(stroke
				(width 0.1)
				(type default)
			)
			(layer "F.Fab")
		)
		(fp_line
			(start -0.12065 -0.305054)
			(end -0.12065 -0.2794)
			(stroke
				(width 0.1)
				(type default)
			)
			(layer "F.Fab")
		)
		(fp_line
			(start -0.12065 -0.2794)
			(end 0.12065 -0.2794)
			(stroke
				(width 0.1)
				(type default)
			)
			(layer "F.Fab")
		)
		(fp_line
			(start -0.12065 0.2794)
			(end -0.12065 0.3048)
			(stroke
				(width 0.1)
				(type default)
			)
			(layer "F.Fab")
		)
		(fp_line
			(start -0.12065 0.3048)
			(end -0.67945 0.3048)
			(stroke
				(width 0.1)
				(type default)
			)
			(layer "F.Fab")
		)
		(fp_line
			(start 0.120396 0.2794)
			(end -0.12065 0.2794)
			(stroke
				(width 0.1)
				(type default)
			)
			(layer "F.Fab")
		)
		(fp_line
			(start 0.120396 0.3048)
			(end 0.120396 0.2794)
			(stroke
				(width 0.1)
				(type default)
			)
			(layer "F.Fab")
		)
		(fp_line
			(start 0.12065 -0.3048)
			(end 0.67945 -0.3048)
			(stroke
				(width 0.1)
				(type default)
			)
			(layer "F.Fab")
		)
		(fp_line
			(start 0.12065 -0.2794)
			(end 0.12065 -0.3048)
			(stroke
				(width 0.1)
				(type default)
			)
			(layer "F.Fab")
		)
		(fp_line
			(start 0.67945 -0.3048)
			(end 0.67945 0.3048)
			(stroke
				(width 0.1)
				(type default)
			)
			(layer "F.Fab")
		)
		(fp_line
			(start 0.67945 0.3048)
			(end 0.120396 0.3048)
			(stroke
				(width 0.1)
				(type default)
			)
			(layer "F.Fab")
		)
		(pad "1" smd circle
			(at -0.40005 0)
			(size 0 0)
			(layers "F.Cu" "F.Mask" "F.Paste")
			(net "FM_P2E_FGB")
		)
		(pad "2" smd circle
			(at 0.40005 0)
			(size 0 0)
			(layers "F.Cu" "F.Mask" "F.Paste")
			(net "GND")
		)
	)
	(footprint ""
		(layer "F.Cu")
		(at 180.4924 -93.538548 90)
		(property "Reference" "R4579"
			(at 0 0 90)
			(layer "F.SilkS")
			(hide yes)
			(effects
				(font
					(size 1.27 1.27)
				)
			)
		)
		(property "Value" ""
			(at 0 0 90)
			(layer "F.Fab")
			(effects
				(font
					(size 1.27 1.27)
				)
			)
		)
		(duplicate_pad_numbers_are_jumpers no)
		(fp_line
			(start 0.7874 -0.4064)
			(end 0.7874 0.4064)
			(stroke
				(width 0.1524)
				(type default)
			)
			(layer "F.SilkS")
		)
		(fp_line
			(start -0.7874 -0.4064)
			(end 0.7874 -0.4064)
			(stroke
				(width 0.1524)
				(type default)
			)
			(layer "F.SilkS")
		)
		(fp_line
			(start 0.7874 0.4064)
			(end -0.7874 0.4064)
			(stroke
				(width 0.1524)
				(type default)
			)
			(layer "F.SilkS")
		)
		(fp_line
			(start -0.7874 0.4064)
			(end -0.7874 -0.4064)
			(stroke
				(width 0.1524)
				(type default)
			)
			(layer "F.SilkS")
		)
		(fp_line
			(start -0.12065 -0.305054)
			(end -0.12065 -0.2794)
			(stroke
				(width 0.1)
				(type default)
			)
			(layer "F.Fab")
		)
		(fp_line
			(start -0.67945 -0.305054)
			(end -0.12065 -0.305054)
			(stroke
				(width 0.1)
				(type default)
			)
			(layer "F.Fab")
		)
		(fp_line
			(start 0.67945 -0.3048)
			(end 0.67945 0.3048)
			(stroke
				(width 0.1)
				(type default)
			)
			(layer "F.Fab")
		)
		(fp_line
			(start 0.12065 -0.3048)
			(end 0.67945 -0.3048)
			(stroke
				(width 0.1)
				(type default)
			)
			(layer "F.Fab")
		)
		(fp_line
			(start 0.12065 -0.2794)
			(end 0.12065 -0.3048)
			(stroke
				(width 0.1)
				(type default)
			)
			(layer "F.Fab")
		)
		(fp_line
			(start -0.12065 -0.2794)
			(end 0.12065 -0.2794)
			(stroke
				(width 0.1)
				(type default)
			)
			(layer "F.Fab")
		)
		(fp_line
			(start 0.120396 0.2794)
			(end -0.12065 0.2794)
			(stroke
				(width 0.1)
				(type default)
			)
			(layer "F.Fab")
		)
		(fp_line
			(start -0.12065 0.2794)
			(end -0.12065 0.3048)
			(stroke
				(width 0.1)
				(type default)
			)
			(layer "F.Fab")
		)
		(fp_line
			(start 0.67945 0.3048)
			(end 0.120396 0.3048)
			(stroke
				(width 0.1)
				(type default)
			)
			(layer "F.Fab")
		)
		(fp_line
			(start 0.120396 0.3048)
			(end 0.120396 0.2794)
			(stroke
				(width 0.1)
				(type default)
			)
			(layer "F.Fab")
		)
		(fp_line
			(start -0.12065 0.3048)
			(end -0.67945 0.3048)
			(stroke
				(width 0.1)
				(type default)
			)
			(layer "F.Fab")
		)
		(fp_line
			(start -0.67945 0.3048)
			(end -0.67945 -0.305054)
			(stroke
				(width 0.1)
				(type default)
			)
			(layer "F.Fab")
		)
		(pad "1" smd rect
			(at -0.40005 0 270)
			(size 0.4572 0.508)
			(layers "F.Cu" "F.Mask" "F.Paste")
			(net "P3V3_AUX")
		)
		(pad "2" smd rect
			(at 0.40005 0 270)
			(size 0.4572 0.508)
			(layers "F.Cu" "F.Mask" "F.Paste")
			(net "FAB_BMC_REV_ID0")
		)
	)
	(footprint ""
		(layer "F.Cu")
		(at 17.314926 -417.202366 90)
		(property "Reference" "U181"
			(at 1.322324 -8.237728 0)
			(unlocked yes)
			(layer "F.SilkS")
			(effects
				(font
					(size 0.7874 0.5842)
					(thickness 0.1524)
				)
				(justify left)
			)
		)
		(property "Value" ""
			(at 0 0 90)
			(layer "F.Fab")
			(effects
				(font
					(size 1.27 1.27)
				)
			)
		)
		(duplicate_pad_numbers_are_jumpers no)
		(fp_line
			(start 2.097532 -3.949954)
			(end 1.409954 -3.949954)
			(stroke
				(width 0.1524)
				(type default)
			)
			(layer "F.SilkS")
		)
		(fp_line
			(start 1.409954 -3.949954)
			(end 0 -2.54)
			(stroke
				(width 0.1524)
				(type default)
			)
			(layer "F.SilkS")
		)
		(fp_line
			(start -1.409954 -3.949954)
			(end -2.097532 -3.949954)
			(stroke
				(width 0.1524)
				(type default)
			)
			(layer "F.SilkS")
		)
		(fp_line
			(start -2.097532 -3.949954)
			(end -2.097532 3.949954)
			(stroke
				(width 0.1524)
				(type default)
			)
			(layer "F.SilkS")
		)
		(fp_line
			(start 0 -2.54)
			(end -1.409954 -3.949954)
			(stroke
				(width 0.1524)
				(type default)
			)
			(layer "F.SilkS")
		)
		(fp_line
			(start 2.097532 3.949954)
			(end 2.097532 -3.949954)
			(stroke
				(width 0.1524)
				(type default)
			)
			(layer "F.SilkS")
		)
		(fp_line
			(start -2.097532 3.949954)
			(end 2.097532 3.949954)
			(stroke
				(width 0.1524)
				(type default)
			)
			(layer "F.SilkS")
		)
		(fp_poly
			(pts
				(xy -2.496312 -5.281168) (xy -3.004312 -4.265168) (xy -3.512312 -5.281168)
			)
			(stroke
				(width 0)
				(type default)
			)
			(fill yes)
			(layer "F.SilkS")
		)
		(fp_line
			(start 2.249932 -3.949954)
			(end -2.249932 -3.949954)
			(stroke
				(width 0.1)
				(type default)
			)
			(layer "F.Fab")
		)
		(fp_line
			(start -2.249932 -3.949954)
			(end -2.249932 3.949954)
			(stroke
				(width 0.1)
				(type default)
			)
			(layer "F.Fab")
		)
		(fp_line
			(start 2.249932 3.949954)
			(end 2.249932 -3.949954)
			(stroke
				(width 0.1)
				(type default)
			)
			(layer "F.Fab")
		)
		(fp_line
			(start -2.249932 3.949954)
			(end 2.249932 3.949954)
			(stroke
				(width 0.1)
				(type default)
			)
			(layer "F.Fab")
		)
		(fp_poly
			(pts
				(xy -4.7498 -4.182872) (xy -4.7498 -3.166872) (xy -3.7338 -3.674872)
			)
			(stroke
				(width 0)
				(type default)
			)
			(fill yes)
			(layer "F.Fab")
		)
		(pad "1" smd rect
			(at -2.925064 -3.674872)
			(size 0.6096 1.3716)
			(layers "F.Cu" "F.Mask" "F.Paste")
			(net "PU_U181_INT")
		)
		(pad "2" smd rect
			(at -2.925064 -2.925064)
			(size 0.4064 1.3716)
			(layers "F.Cu" "F.Mask" "F.Paste")
			(net "TCA9539_0_ADD1")
		)
		(pad "3" smd rect
			(at -2.925064 -2.275078)
			(size 0.4064 1.3716)
			(layers "F.Cu" "F.Mask" "F.Paste")
			(net "PU_RST_SMB_U181_N")
		)
		(pad "4" smd rect
			(at -2.925064 -1.625092)
			(size 0.4064 1.3716)
			(layers "F.Cu" "F.Mask" "F.Paste")
			(net "RST_USB_HUB_N")
		)
		(pad "5" smd rect
			(at -2.925064 -0.975106)
			(size 0.4064 1.3716)
			(layers "F.Cu" "F.Mask" "F.Paste")
			(net "RST_SWB_BIC_N")
		)
		(pad "6" smd rect
			(at -2.925064 -0.32512)
			(size 0.4064 1.3716)
			(layers "F.Cu" "F.Mask" "F.Paste")
			(net "TP_TCA9539_0_P0_2")
		)
		(pad "7" smd rect
			(at -2.925064 0.32512)
			(size 0.4064 1.3716)
			(layers "F.Cu" "F.Mask" "F.Paste")
			(net "TP_TCA9539_0_P0_3")
		)
		(pad "8" smd rect
			(at -2.925064 0.975106)
			(size 0.4064 1.3716)
			(layers "F.Cu" "F.Mask" "F.Paste")
			(net "PRSNT_SWB_ISO_R1_N")
		)
		(pad "9" smd rect
			(at -2.925064 1.625092)
			(size 0.4064 1.3716)
			(layers "F.Cu" "F.Mask" "F.Paste")
			(net "GPU_PRSNT_N_ISO_R1")
		)
		(pad "10" smd rect
			(at -2.925064 2.275078)
			(size 0.4064 1.3716)
			(layers "F.Cu" "F.Mask" "F.Paste")
			(net "PRSNT_CABLE_GPU_B3_ISO_R1_N")
		)
		(pad "11" smd rect
			(at -2.925064 2.925064)
			(size 0.4064 1.3716)
			(layers "F.Cu" "F.Mask" "F.Paste")
			(net "PRSNT_CABLE_SWB_B2_ISO_R_N")
		)
		(pad "12" smd rect
			(at -2.925064 3.674872)
			(size 0.6096 1.3716)
			(layers "F.Cu" "F.Mask" "F.Paste")
			(net "GND")
		)
		(pad "13" smd rect
			(at 2.925064 3.674872)
			(size 0.6096 1.3716)
			(layers "F.Cu" "F.Mask" "F.Paste")
			(net "PRSNT_CABLE_GPU_A2_ISO_R1_N")
		)
		(pad "14" smd rect
			(at 2.925064 2.925064)
			(size 0.4064 1.3716)
			(layers "F.Cu" "F.Mask" "F.Paste")
			(net "PRSNT_CABLE_SWB_B1_ISO_R_N")
		)
		(pad "15" smd rect
			(at 2.925064 2.275078)
			(size 0.4064 1.3716)
			(layers "F.Cu" "F.Mask" "F.Paste")
			(net "GPU_BASE_ID0_R")
		)
		(pad "16" smd rect
			(at 2.925064 1.625092)
			(size 0.4064 1.3716)
			(layers "F.Cu" "F.Mask" "F.Paste")
			(net "GPU_BASE_ID1_R")
		)
		(pad "17" smd rect
			(at 2.925064 0.975106)
			(size 0.4064 1.3716)
			(layers "F.Cu" "F.Mask" "F.Paste")
			(net "GPU_PEX_STRAP0_R")
		)
		(pad "18" smd rect
			(at 2.925064 0.32512)
			(size 0.4064 1.3716)
			(layers "F.Cu" "F.Mask" "F.Paste")
			(net "GPU_PEX_STRAP1_R")
		)
		(pad "19" smd rect
			(at 2.925064 -0.32512)
			(size 0.4064 1.3716)
			(layers "F.Cu" "F.Mask" "F.Paste")
			(net "PRSNT_CABLE_GPU_A1_ISO_R1_N")
		)
		(pad "20" smd rect
			(at 2.925064 -0.975106)
			(size 0.4064 1.3716)
			(layers "F.Cu" "F.Mask" "F.Paste")
			(net "PRSNT_CABLE_GPU_A3_ISO_R_N")
		)
		(pad "21" smd rect
			(at 2.925064 -1.625092)
			(size 0.4064 1.3716)
			(layers "F.Cu" "F.Mask" "F.Paste")
			(net "TCA9539_0_ADD0")
		)
		(pad "22" smd rect
			(at 2.925064 -2.275078)
			(size 0.4064 1.3716)
			(layers "F.Cu" "F.Mask" "F.Paste")
			(net "SMB_IOEXP_3V3AUX_SCL_R1")
		)
		(pad "23" smd rect
			(at 2.925064 -2.925064)
			(size 0.4064 1.3716)
			(layers "F.Cu" "F.Mask" "F.Paste")
			(net "SMB_IOEXP_3V3AUX_SDA_R1")
		)
		(pad "24" smd rect
			(at 2.925064 -3.674872)
			(size 0.6096 1.3716)
			(layers "F.Cu" "F.Mask" "F.Paste")
			(net "P3V3_AUX")
		)
	)
	(footprint ""
		(layer "F.Cu")
		(at 21.176996 -97.083626 180)
		(property "Reference" "R3663"
			(at 0 0 180)
			(layer "F.SilkS")
			(hide yes)
			(effects
				(font
					(size 1.27 1.27)
				)
			)
		)
		(property "Value" ""
			(at 0 0 180)
			(layer "F.Fab")
			(effects
				(font
					(size 1.27 1.27)
				)
			)
		)
		(duplicate_pad_numbers_are_jumpers no)
		(fp_line
			(start 0.7874 0.4064)
			(end -0.7874 0.4064)
			(stroke
				(width 0.1524)
				(type default)
			)
			(layer "F.SilkS")
		)
		(fp_line
			(start 0.7874 -0.4064)
			(end 0.7874 0.4064)
			(stroke
				(width 0.1524)
				(type default)
			)
			(layer "F.SilkS")
		)
		(fp_line
			(start -0.7874 0.4064)
			(end -0.7874 -0.4064)
			(stroke
				(width 0.1524)
				(type default)
			)
			(layer "F.SilkS")
		)
		(fp_line
			(start -0.7874 -0.4064)
			(end 0.7874 -0.4064)
			(stroke
				(width 0.1524)
				(type default)
			)
			(layer "F.SilkS")
		)
		(fp_line
			(start 0.67945 0.3048)
			(end 0.120396 0.3048)
			(stroke
				(width 0.1)
				(type default)
			)
			(layer "F.Fab")
		)
		(fp_line
			(start 0.67945 -0.3048)
			(end 0.67945 0.3048)
			(stroke
				(width 0.1)
				(type default)
			)
			(layer "F.Fab")
		)
		(fp_line
			(start 0.12065 -0.2794)
			(end 0.12065 -0.3048)
			(stroke
				(width 0.1)
				(type default)
			)
			(layer "F.Fab")
		)
		(fp_line
			(start 0.12065 -0.3048)
			(end 0.67945 -0.3048)
			(stroke
				(width 0.1)
				(type default)
			)
			(layer "F.Fab")
		)
		(fp_line
			(start 0.120396 0.3048)
			(end 0.120396 0.2794)
			(stroke
				(width 0.1)
				(type default)
			)
			(layer "F.Fab")
		)
		(fp_line
			(start 0.120396 0.2794)
			(end -0.12065 0.2794)
			(stroke
				(width 0.1)
				(type default)
			)
			(layer "F.Fab")
		)
		(fp_line
			(start -0.12065 0.3048)
			(end -0.67945 0.3048)
			(stroke
				(width 0.1)
				(type default)
			)
			(layer "F.Fab")
		)
		(fp_line
			(start -0.12065 0.2794)
			(end -0.12065 0.3048)
			(stroke
				(width 0.1)
				(type default)
			)
			(layer "F.Fab")
		)
		(fp_line
			(start -0.12065 -0.2794)
			(end 0.12065 -0.2794)
			(stroke
				(width 0.1)
				(type default)
			)
			(layer "F.Fab")
		)
		(fp_line
			(start -0.12065 -0.305054)
			(end -0.12065 -0.2794)
			(stroke
				(width 0.1)
				(type default)
			)
			(layer "F.Fab")
		)
		(fp_line
			(start -0.67945 0.3048)
			(end -0.67945 -0.305054)
			(stroke
				(width 0.1)
				(type default)
			)
			(layer "F.Fab")
		)
		(fp_line
			(start -0.67945 -0.305054)
			(end -0.12065 -0.305054)
			(stroke
				(width 0.1)
				(type default)
			)
			(layer "F.Fab")
		)
		(pad "1" smd circle
			(at -0.40005 0 180)
			(size 0 0)
			(layers "F.Cu" "F.Mask" "F.Paste")
			(net "P3V3_AUX")
		)
		(pad "2" smd circle
			(at 0.40005 0 180)
			(size 0 0)
			(layers "F.Cu" "F.Mask" "F.Paste")
			(net "USB_HUB_PSELF")
		)
	)
	(footprint ""
		(layer "F.Cu")
		(at 433.180236 -17.612614 90)
		(property "Reference" "C868"
			(at 0 0 90)
			(layer "F.SilkS")
			(hide yes)
			(effects
				(font
					(size 1.27 1.27)
				)
			)
		)
		(property "Value" ""
			(at 0 0 90)
			(layer "F.Fab")
			(effects
				(font
					(size 1.27 1.27)
				)
			)
		)
		(duplicate_pad_numbers_are_jumpers no)
		(fp_line
			(start 0.299974 -0.150114)
			(end 0.299974 0.150114)
			(stroke
				(width 0.1)
				(type default)
			)
			(layer "F.Fab")
		)
		(fp_line
			(start -0.299974 -0.150114)
			(end 0.299974 -0.150114)
			(stroke
				(width 0.1)
				(type default)
			)
			(layer "F.Fab")
		)
		(fp_line
			(start 0.299974 0.150114)
			(end -0.299974 0.150114)
			(stroke
				(width 0.1)
				(type default)
			)
			(layer "F.Fab")
		)
		(fp_line
			(start -0.299974 0.150114)
			(end -0.299974 -0.150114)
			(stroke
				(width 0.1)
				(type default)
			)
			(layer "F.Fab")
		)
		(pad "1" smd rect
			(at -0.2667 0 90)
			(size 0.3048 0.381)
			(layers "F.Cu" "F.Mask" "F.Paste")
			(net "P5E_CPU0_PE1_TX_C_DN<0>")
		)
		(pad "2" smd rect
			(at 0.2667 0 90)
			(size 0.3048 0.381)
			(layers "F.Cu" "F.Mask" "F.Paste")
			(net "P5E_CPU0_PE1_TX_DN<0>")
		)
	)
	(footprint ""
		(layer "F.Cu")
		(at 212.442806 -134.065518)
		(property "Reference" "U117"
			(at 1.884934 -1.66624 0)
			(unlocked yes)
			(layer "F.SilkS")
			(effects
				(font
					(size 0.7874 0.5842)
					(thickness 0.1524)
				)
			)
		)
		(property "Value" ""
			(at 0 0 0)
			(layer "F.Fab")
			(effects
				(font
					(size 1.27 1.27)
				)
			)
		)
		(duplicate_pad_numbers_are_jumpers no)
		(fp_line
			(start -0.779018 -0.800862)
			(end -0.779018 0.800862)
			(stroke
				(width 0.1524)
				(type default)
			)
			(layer "F.SilkS")
		)
		(fp_line
			(start -0.779018 0.800862)
			(end 0.779018 0.800862)
			(stroke
				(width 0.1524)
				(type default)
			)
			(layer "F.SilkS")
		)
		(fp_line
			(start 0.779018 -0.800862)
			(end -0.779018 -0.800862)
			(stroke
				(width 0.1524)
				(type default)
			)
			(layer "F.SilkS")
		)
		(fp_line
			(start 0.779018 0.800862)
			(end 0.779018 -0.800862)
			(stroke
				(width 0.1524)
				(type default)
			)
			(layer "F.SilkS")
		)
		(fp_poly
			(pts
				(xy -0.462534 -1.245108) (xy -0.677164 -1.634998) (xy -0.248158 -1.634998)
			)
			(stroke
				(width 0)
				(type default)
			)
			(fill yes)
			(layer "F.SilkS")
		)
		(fp_line
			(start -0.525018 -0.750062)
			(end 0.525018 -0.750062)
			(stroke
				(width 0.1)
				(type default)
			)
			(layer "F.Fab")
		)
		(fp_line
			(start -0.525018 0.750062)
			(end -0.525018 -0.750062)
			(stroke
				(width 0.1)
				(type default)
			)
			(layer "F.Fab")
		)
		(fp_line
			(start 0.525018 -0.750062)
			(end 0.525018 0.750062)
			(stroke
				(width 0.1)
				(type default)
			)
			(layer "F.Fab")
		)
		(fp_line
			(start 0.525018 0.750062)
			(end -0.525018 0.750062)
			(stroke
				(width 0.1)
				(type default)
			)
			(layer "F.Fab")
		)
		(fp_poly
			(pts
				(xy -0.923544 -0.500126) (xy -1.313434 -0.714502) (xy -1.313434 -0.285496)
			)
			(stroke
				(width 0)
				(type default)
			)
			(fill yes)
			(layer "F.Fab")
		)
		(pad "1" smd rect
			(at -0.377444 -0.500126 270)
			(size 0.3048 0.5334)
			(layers "F.Cu" "F.Mask" "F.Paste")
			(net "FM_COMP_P3V3_AUX_ENIN")
		)
		(pad "2" smd rect
			(at -0.372618 0 270)
			(size 0.2794 0.508)
			(layers "F.Cu" "F.Mask" "F.Paste")
			(net "GND")
		)
		(pad "3" smd rect
			(at -0.372618 0.499872 270)
			(size 0.2794 0.508)
			(layers "F.Cu" "F.Mask" "F.Paste")
			(net "FM_COMP_P3V3_AUX_VIN")
		)
		(pad "4" smd rect
			(at 0.377444 0.499872 270)
			(size 0.2794 0.508)
			(layers "F.Cu" "F.Mask" "F.Paste")
			(net "PWRGD_DSW_PWROK_R1")
		)
		(pad "5" smd rect
			(at 0.377444 0 270)
			(size 0.2794 0.508)
			(layers "F.Cu" "F.Mask" "F.Paste")
			(net "FM_COMP_P3V3_STBY_CEXT")
		)
		(pad "6" smd rect
			(at 0.377444 -0.500126 270)
			(size 0.2794 0.508)
			(layers "F.Cu" "F.Mask" "F.Paste")
			(net "P3V3_AUX")
		)
	)
	(footprint ""
		(layer "F.Cu")
		(at 421.927528 -157.990286 -90)
		(property "Reference" "PC635"
			(at 0 0 270)
			(layer "F.SilkS")
			(hide yes)
			(effects
				(font
					(size 1.27 1.27)
				)
			)
		)
		(property "Value" ""
			(at 0 0 270)
			(layer "F.Fab")
			(effects
				(font
					(size 1.27 1.27)
				)
			)
		)
		(duplicate_pad_numbers_are_jumpers no)
		(fp_line
			(start -0.7874 0.4064)
			(end -0.7874 -0.4064)
			(stroke
				(width 0.1524)
				(type default)
			)
			(layer "F.SilkS")
		)
		(fp_line
			(start 0.7874 0.4064)
			(end -0.7874 0.4064)
			(stroke
				(width 0.1524)
				(type default)
			)
			(layer "F.SilkS")
		)
		(fp_line
			(start -0.7874 -0.4064)
			(end 0.7874 -0.4064)
			(stroke
				(width 0.1524)
				(type default)
			)
			(layer "F.SilkS")
		)
		(fp_line
			(start 0.7874 -0.4064)
			(end 0.7874 0.4064)
			(stroke
				(width 0.1524)
				(type default)
			)
			(layer "F.SilkS")
		)
		(fp_line
			(start -0.67945 0.3048)
			(end -0.67945 -0.305054)
			(stroke
				(width 0.1)
				(type default)
			)
			(layer "F.Fab")
		)
		(fp_line
			(start -0.12065 0.3048)
			(end -0.67945 0.3048)
			(stroke
				(width 0.1)
				(type default)
			)
			(layer "F.Fab")
		)
		(fp_line
			(start 0.120396 0.3048)
			(end 0.120396 0.2794)
			(stroke
				(width 0.1)
				(type default)
			)
			(layer "F.Fab")
		)
		(fp_line
			(start 0.67945 0.3048)
			(end 0.120396 0.3048)
			(stroke
				(width 0.1)
				(type default)
			)
			(layer "F.Fab")
		)
		(fp_line
			(start -0.12065 0.2794)
			(end -0.12065 0.3048)
			(stroke
				(width 0.1)
				(type default)
			)
			(layer "F.Fab")
		)
		(fp_line
			(start 0.120396 0.2794)
			(end -0.12065 0.2794)
			(stroke
				(width 0.1)
				(type default)
			)
			(layer "F.Fab")
		)
		(fp_line
			(start -0.12065 -0.2794)
			(end 0.12065 -0.2794)
			(stroke
				(width 0.1)
				(type default)
			)
			(layer "F.Fab")
		)
		(fp_line
			(start 0.12065 -0.2794)
			(end 0.12065 -0.3048)
			(stroke
				(width 0.1)
				(type default)
			)
			(layer "F.Fab")
		)
		(fp_line
			(start 0.12065 -0.3048)
			(end 0.67945 -0.3048)
			(stroke
				(width 0.1)
				(type default)
			)
			(layer "F.Fab")
		)
		(fp_line
			(start 0.67945 -0.3048)
			(end 0.67945 0.3048)
			(stroke
				(width 0.1)
				(type default)
			)
			(layer "F.Fab")
		)
		(fp_line
			(start -0.67945 -0.305054)
			(end -0.12065 -0.305054)
			(stroke
				(width 0.1)
				(type default)
			)
			(layer "F.Fab")
		)
		(fp_line
			(start -0.12065 -0.305054)
			(end -0.12065 -0.2794)
			(stroke
				(width 0.1)
				(type default)
			)
			(layer "F.Fab")
		)
		(pad "1" smd circle
			(at -0.40005 0 270)
			(size 0 0)
			(layers "F.Cu" "F.Mask" "F.Paste")
			(net "SW_P12V_PVCCINFAON_CPU0_FLT")
		)
		(pad "2" smd circle
			(at 0.40005 0 270)
			(size 0 0)
			(layers "F.Cu" "F.Mask" "F.Paste")
			(net "GND")
		)
	)
	(footprint ""
		(layer "F.Cu")
		(at 216.1286 -120.142 180)
		(property "Reference" "C2369"
			(at 0 0 180)
			(layer "F.SilkS")
			(hide yes)
			(effects
				(font
					(size 1.27 1.27)
				)
			)
		)
		(property "Value" ""
			(at 0 0 180)
			(layer "F.Fab")
			(effects
				(font
					(size 1.27 1.27)
				)
			)
		)
		(duplicate_pad_numbers_are_jumpers no)
		(fp_line
			(start 0.7874 0.4064)
			(end -0.7874 0.4064)
			(stroke
				(width 0.1524)
				(type default)
			)
			(layer "F.SilkS")
		)
		(fp_line
			(start 0.7874 -0.4064)
			(end 0.7874 0.4064)
			(stroke
				(width 0.1524)
				(type default)
			)
			(layer "F.SilkS")
		)
		(fp_line
			(start -0.7874 0.4064)
			(end -0.7874 -0.4064)
			(stroke
				(width 0.1524)
				(type default)
			)
			(layer "F.SilkS")
		)
		(fp_line
			(start -0.7874 -0.4064)
			(end 0.7874 -0.4064)
			(stroke
				(width 0.1524)
				(type default)
			)
			(layer "F.SilkS")
		)
		(fp_line
			(start 0.67945 0.3048)
			(end 0.120396 0.3048)
			(stroke
				(width 0.1)
				(type default)
			)
			(layer "F.Fab")
		)
		(fp_line
			(start 0.67945 -0.3048)
			(end 0.67945 0.3048)
			(stroke
				(width 0.1)
				(type default)
			)
			(layer "F.Fab")
		)
		(fp_line
			(start 0.12065 -0.2794)
			(end 0.12065 -0.3048)
			(stroke
				(width 0.1)
				(type default)
			)
			(layer "F.Fab")
		)
		(fp_line
			(start 0.12065 -0.3048)
			(end 0.67945 -0.3048)
			(stroke
				(width 0.1)
				(type default)
			)
			(layer "F.Fab")
		)
		(fp_line
			(start 0.120396 0.3048)
			(end 0.120396 0.2794)
			(stroke
				(width 0.1)
				(type default)
			)
			(layer "F.Fab")
		)
		(fp_line
			(start 0.120396 0.2794)
			(end -0.12065 0.2794)
			(stroke
				(width 0.1)
				(type default)
			)
			(layer "F.Fab")
		)
		(fp_line
			(start -0.12065 0.3048)
			(end -0.67945 0.3048)
			(stroke
				(width 0.1)
				(type default)
			)
			(layer "F.Fab")
		)
		(fp_line
			(start -0.12065 0.2794)
			(end -0.12065 0.3048)
			(stroke
				(width 0.1)
				(type default)
			)
			(layer "F.Fab")
		)
		(fp_line
			(start -0.12065 -0.2794)
			(end 0.12065 -0.2794)
			(stroke
				(width 0.1)
				(type default)
			)
			(layer "F.Fab")
		)
		(fp_line
			(start -0.12065 -0.305054)
			(end -0.12065 -0.2794)
			(stroke
				(width 0.1)
				(type default)
			)
			(layer "F.Fab")
		)
		(fp_line
			(start -0.67945 0.3048)
			(end -0.67945 -0.305054)
			(stroke
				(width 0.1)
				(type default)
			)
			(layer "F.Fab")
		)
		(fp_line
			(start -0.67945 -0.305054)
			(end -0.12065 -0.305054)
			(stroke
				(width 0.1)
				(type default)
			)
			(layer "F.Fab")
		)
		(pad "1" smd circle
			(at -0.40005 0 180)
			(size 0 0)
			(layers "F.Cu" "F.Mask" "F.Paste")
			(net "FM_AC_PWR_BTN_R_N")
		)
		(pad "2" smd circle
			(at 0.40005 0 180)
			(size 0 0)
			(layers "F.Cu" "F.Mask" "F.Paste")
			(net "GND")
		)
	)
	(footprint ""
		(layer "F.Cu")
		(at 230.248206 -251.189236 180)
		(property "Reference" "R3336"
			(at 0 0 180)
			(layer "F.SilkS")
			(hide yes)
			(effects
				(font
					(size 1.27 1.27)
				)
			)
		)
		(property "Value" ""
			(at 0 0 180)
			(layer "F.Fab")
			(effects
				(font
					(size 1.27 1.27)
				)
			)
		)
		(duplicate_pad_numbers_are_jumpers no)
		(fp_line
			(start 0.7874 0.4064)
			(end -0.7874 0.4064)
			(stroke
				(width 0.1524)
				(type default)
			)
			(layer "F.SilkS")
		)
		(fp_line
			(start 0.7874 -0.4064)
			(end 0.7874 0.4064)
			(stroke
				(width 0.1524)
				(type default)
			)
			(layer "F.SilkS")
		)
		(fp_line
			(start -0.7874 0.4064)
			(end -0.7874 -0.4064)
			(stroke
				(width 0.1524)
				(type default)
			)
			(layer "F.SilkS")
		)
		(fp_line
			(start -0.7874 -0.4064)
			(end 0.7874 -0.4064)
			(stroke
				(width 0.1524)
				(type default)
			)
			(layer "F.SilkS")
		)
		(fp_line
			(start 0.67945 0.3048)
			(end 0.120396 0.3048)
			(stroke
				(width 0.1)
				(type default)
			)
			(layer "F.Fab")
		)
		(fp_line
			(start 0.67945 -0.3048)
			(end 0.67945 0.3048)
			(stroke
				(width 0.1)
				(type default)
			)
			(layer "F.Fab")
		)
		(fp_line
			(start 0.12065 -0.2794)
			(end 0.12065 -0.3048)
			(stroke
				(width 0.1)
				(type default)
			)
			(layer "F.Fab")
		)
		(fp_line
			(start 0.12065 -0.3048)
			(end 0.67945 -0.3048)
			(stroke
				(width 0.1)
				(type default)
			)
			(layer "F.Fab")
		)
		(fp_line
			(start 0.120396 0.3048)
			(end 0.120396 0.2794)
			(stroke
				(width 0.1)
				(type default)
			)
			(layer "F.Fab")
		)
		(fp_line
			(start 0.120396 0.2794)
			(end -0.12065 0.2794)
			(stroke
				(width 0.1)
				(type default)
			)
			(layer "F.Fab")
		)
		(fp_line
			(start -0.12065 0.3048)
			(end -0.67945 0.3048)
			(stroke
				(width 0.1)
				(type default)
			)
			(layer "F.Fab")
		)
		(fp_line
			(start -0.12065 0.2794)
			(end -0.12065 0.3048)
			(stroke
				(width 0.1)
				(type default)
			)
			(layer "F.Fab")
		)
		(fp_line
			(start -0.12065 -0.2794)
			(end 0.12065 -0.2794)
			(stroke
				(width 0.1)
				(type default)
			)
			(layer "F.Fab")
		)
		(fp_line
			(start -0.12065 -0.305054)
			(end -0.12065 -0.2794)
			(stroke
				(width 0.1)
				(type default)
			)
			(layer "F.Fab")
		)
		(fp_line
			(start -0.67945 0.3048)
			(end -0.67945 -0.305054)
			(stroke
				(width 0.1)
				(type default)
			)
			(layer "F.Fab")
		)
		(fp_line
			(start -0.67945 -0.305054)
			(end -0.12065 -0.305054)
			(stroke
				(width 0.1)
				(type default)
			)
			(layer "F.Fab")
		)
		(pad "1" smd circle
			(at -0.40005 0 180)
			(size 0 0)
			(layers "F.Cu" "F.Mask" "F.Paste")
			(net "CLK_100M_BMC_RC_DN_R")
		)
		(pad "2" smd circle
			(at 0.40005 0 180)
			(size 0 0)
			(layers "F.Cu" "F.Mask" "F.Paste")
			(net "CLK_100M_BMC_RC_DN")
		)
	)
	(footprint ""
		(layer "F.Cu")
		(at 365.46663 -249.320304 -90)
		(property "Reference" "C973"
			(at 0 0 270)
			(layer "F.SilkS")
			(hide yes)
			(effects
				(font
					(size 1.27 1.27)
				)
			)
		)
		(property "Value" ""
			(at 0 0 270)
			(layer "F.Fab")
			(effects
				(font
					(size 1.27 1.27)
				)
			)
		)
		(duplicate_pad_numbers_are_jumpers no)
		(fp_line
			(start -0.7874 0.4064)
			(end -0.7874 -0.4064)
			(stroke
				(width 0.1524)
				(type default)
			)
			(layer "F.SilkS")
		)
		(fp_line
			(start 0.7874 0.4064)
			(end -0.7874 0.4064)
			(stroke
				(width 0.1524)
				(type default)
			)
			(layer "F.SilkS")
		)
		(fp_line
			(start -0.7874 -0.4064)
			(end 0.7874 -0.4064)
			(stroke
				(width 0.1524)
				(type default)
			)
			(layer "F.SilkS")
		)
		(fp_line
			(start 0.7874 -0.4064)
			(end 0.7874 0.4064)
			(stroke
				(width 0.1524)
				(type default)
			)
			(layer "F.SilkS")
		)
		(fp_line
			(start -0.67945 0.3048)
			(end -0.67945 -0.305054)
			(stroke
				(width 0.1)
				(type default)
			)
			(layer "F.Fab")
		)
		(fp_line
			(start -0.12065 0.3048)
			(end -0.67945 0.3048)
			(stroke
				(width 0.1)
				(type default)
			)
			(layer "F.Fab")
		)
		(fp_line
			(start 0.120396 0.3048)
			(end 0.120396 0.2794)
			(stroke
				(width 0.1)
				(type default)
			)
			(layer "F.Fab")
		)
		(fp_line
			(start 0.67945 0.3048)
			(end 0.120396 0.3048)
			(stroke
				(width 0.1)
				(type default)
			)
			(layer "F.Fab")
		)
		(fp_line
			(start -0.12065 0.2794)
			(end -0.12065 0.3048)
			(stroke
				(width 0.1)
				(type default)
			)
			(layer "F.Fab")
		)
		(fp_line
			(start 0.120396 0.2794)
			(end -0.12065 0.2794)
			(stroke
				(width 0.1)
				(type default)
			)
			(layer "F.Fab")
		)
		(fp_line
			(start -0.12065 -0.2794)
			(end 0.12065 -0.2794)
			(stroke
				(width 0.1)
				(type default)
			)
			(layer "F.Fab")
		)
		(fp_line
			(start 0.12065 -0.2794)
			(end 0.12065 -0.3048)
			(stroke
				(width 0.1)
				(type default)
			)
			(layer "F.Fab")
		)
		(fp_line
			(start 0.12065 -0.3048)
			(end 0.67945 -0.3048)
			(stroke
				(width 0.1)
				(type default)
			)
			(layer "F.Fab")
		)
		(fp_line
			(start 0.67945 -0.3048)
			(end 0.67945 0.3048)
			(stroke
				(width 0.1)
				(type default)
			)
			(layer "F.Fab")
		)
		(fp_line
			(start -0.67945 -0.305054)
			(end -0.12065 -0.305054)
			(stroke
				(width 0.1)
				(type default)
			)
			(layer "F.Fab")
		)
		(fp_line
			(start -0.12065 -0.305054)
			(end -0.12065 -0.2794)
			(stroke
				(width 0.1)
				(type default)
			)
			(layer "F.Fab")
		)
		(pad "1" smd circle
			(at -0.40005 0 270)
			(size 0 0)
			(layers "F.Cu" "F.Mask" "F.Paste")
			(net "PVCCIN_CPU0")
		)
		(pad "2" smd circle
			(at 0.40005 0 270)
			(size 0 0)
			(layers "F.Cu" "F.Mask" "F.Paste")
			(net "GND")
		)
	)
	(footprint ""
		(layer "F.Cu")
		(at 396.822168 -165.363906 180)
		(property "Reference" "PR4237"
			(at 0 0 180)
			(layer "F.SilkS")
			(hide yes)
			(effects
				(font
					(size 1.27 1.27)
				)
			)
		)
		(property "Value" ""
			(at 0 0 180)
			(layer "F.Fab")
			(effects
				(font
					(size 1.27 1.27)
				)
			)
		)
		(duplicate_pad_numbers_are_jumpers no)
		(fp_line
			(start 0.7874 0.4064)
			(end -0.7874 0.4064)
			(stroke
				(width 0.1524)
				(type default)
			)
			(layer "F.SilkS")
		)
		(fp_line
			(start 0.7874 -0.4064)
			(end 0.7874 0.4064)
			(stroke
				(width 0.1524)
				(type default)
			)
			(layer "F.SilkS")
		)
		(fp_line
			(start -0.7874 0.4064)
			(end -0.7874 -0.4064)
			(stroke
				(width 0.1524)
				(type default)
			)
			(layer "F.SilkS")
		)
		(fp_line
			(start -0.7874 -0.4064)
			(end 0.7874 -0.4064)
			(stroke
				(width 0.1524)
				(type default)
			)
			(layer "F.SilkS")
		)
		(fp_line
			(start 0.67945 0.3048)
			(end 0.120396 0.3048)
			(stroke
				(width 0.1)
				(type default)
			)
			(layer "F.Fab")
		)
		(fp_line
			(start 0.67945 -0.3048)
			(end 0.67945 0.3048)
			(stroke
				(width 0.1)
				(type default)
			)
			(layer "F.Fab")
		)
		(fp_line
			(start 0.12065 -0.2794)
			(end 0.12065 -0.3048)
			(stroke
				(width 0.1)
				(type default)
			)
			(layer "F.Fab")
		)
		(fp_line
			(start 0.12065 -0.3048)
			(end 0.67945 -0.3048)
			(stroke
				(width 0.1)
				(type default)
			)
			(layer "F.Fab")
		)
		(fp_line
			(start 0.120396 0.3048)
			(end 0.120396 0.2794)
			(stroke
				(width 0.1)
				(type default)
			)
			(layer "F.Fab")
		)
		(fp_line
			(start 0.120396 0.2794)
			(end -0.12065 0.2794)
			(stroke
				(width 0.1)
				(type default)
			)
			(layer "F.Fab")
		)
		(fp_line
			(start -0.12065 0.3048)
			(end -0.67945 0.3048)
			(stroke
				(width 0.1)
				(type default)
			)
			(layer "F.Fab")
		)
		(fp_line
			(start -0.12065 0.2794)
			(end -0.12065 0.3048)
			(stroke
				(width 0.1)
				(type default)
			)
			(layer "F.Fab")
		)
		(fp_line
			(start -0.12065 -0.2794)
			(end 0.12065 -0.2794)
			(stroke
				(width 0.1)
				(type default)
			)
			(layer "F.Fab")
		)
		(fp_line
			(start -0.12065 -0.305054)
			(end -0.12065 -0.2794)
			(stroke
				(width 0.1)
				(type default)
			)
			(layer "F.Fab")
		)
		(fp_line
			(start -0.67945 0.3048)
			(end -0.67945 -0.305054)
			(stroke
				(width 0.1)
				(type default)
			)
			(layer "F.Fab")
		)
		(fp_line
			(start -0.67945 -0.305054)
			(end -0.12065 -0.305054)
			(stroke
				(width 0.1)
				(type default)
			)
			(layer "F.Fab")
		)
		(pad "1" smd circle
			(at -0.40005 0 180)
			(size 0 0)
			(layers "F.Cu" "F.Mask" "F.Paste")
			(net "PVCCD_HV_CPU0")
		)
		(pad "2" smd circle
			(at 0.40005 0 180)
			(size 0 0)
			(layers "F.Cu" "F.Mask" "F.Paste")
			(net "GND")
		)
	)
	(footprint ""
		(layer "F.Cu")
		(at 354.264214 -251.375418 90)
		(property "Reference" "C1022"
			(at 0 0 90)
			(layer "F.SilkS")
			(hide yes)
			(effects
				(font
					(size 1.27 1.27)
				)
			)
		)
		(property "Value" ""
			(at 0 0 90)
			(layer "F.Fab")
			(effects
				(font
					(size 1.27 1.27)
				)
			)
		)
		(duplicate_pad_numbers_are_jumpers no)
		(fp_line
			(start 0.7874 -0.4064)
			(end 0.7874 0.4064)
			(stroke
				(width 0.1524)
				(type default)
			)
			(layer "F.SilkS")
		)
		(fp_line
			(start -0.7874 -0.4064)
			(end 0.7874 -0.4064)
			(stroke
				(width 0.1524)
				(type default)
			)
			(layer "F.SilkS")
		)
		(fp_line
			(start 0.7874 0.4064)
			(end -0.7874 0.4064)
			(stroke
				(width 0.1524)
				(type default)
			)
			(layer "F.SilkS")
		)
		(fp_line
			(start -0.7874 0.4064)
			(end -0.7874 -0.4064)
			(stroke
				(width 0.1524)
				(type default)
			)
			(layer "F.SilkS")
		)
		(fp_line
			(start -0.12065 -0.305054)
			(end -0.12065 -0.2794)
			(stroke
				(width 0.1)
				(type default)
			)
			(layer "F.Fab")
		)
		(fp_line
			(start -0.67945 -0.305054)
			(end -0.12065 -0.305054)
			(stroke
				(width 0.1)
				(type default)
			)
			(layer "F.Fab")
		)
		(fp_line
			(start 0.67945 -0.3048)
			(end 0.67945 0.3048)
			(stroke
				(width 0.1)
				(type default)
			)
			(layer "F.Fab")
		)
		(fp_line
			(start 0.12065 -0.3048)
			(end 0.67945 -0.3048)
			(stroke
				(width 0.1)
				(type default)
			)
			(layer "F.Fab")
		)
		(fp_line
			(start 0.12065 -0.2794)
			(end 0.12065 -0.3048)
			(stroke
				(width 0.1)
				(type default)
			)
			(layer "F.Fab")
		)
		(fp_line
			(start -0.12065 -0.2794)
			(end 0.12065 -0.2794)
			(stroke
				(width 0.1)
				(type default)
			)
			(layer "F.Fab")
		)
		(fp_line
			(start 0.120396 0.2794)
			(end -0.12065 0.2794)
			(stroke
				(width 0.1)
				(type default)
			)
			(layer "F.Fab")
		)
		(fp_line
			(start -0.12065 0.2794)
			(end -0.12065 0.3048)
			(stroke
				(width 0.1)
				(type default)
			)
			(layer "F.Fab")
		)
		(fp_line
			(start 0.67945 0.3048)
			(end 0.120396 0.3048)
			(stroke
				(width 0.1)
				(type default)
			)
			(layer "F.Fab")
		)
		(fp_line
			(start 0.120396 0.3048)
			(end 0.120396 0.2794)
			(stroke
				(width 0.1)
				(type default)
			)
			(layer "F.Fab")
		)
		(fp_line
			(start -0.12065 0.3048)
			(end -0.67945 0.3048)
			(stroke
				(width 0.1)
				(type default)
			)
			(layer "F.Fab")
		)
		(fp_line
			(start -0.67945 0.3048)
			(end -0.67945 -0.305054)
			(stroke
				(width 0.1)
				(type default)
			)
			(layer "F.Fab")
		)
		(pad "1" smd circle
			(at -0.40005 0 90)
			(size 0 0)
			(layers "F.Cu" "F.Mask" "F.Paste")
			(net "PVCCIN_CPU0")
		)
		(pad "2" smd circle
			(at 0.40005 0 90)
			(size 0 0)
			(layers "F.Cu" "F.Mask" "F.Paste")
			(net "GND")
		)
	)
	(footprint ""
		(layer "F.Cu")
		(at 131.78155 -42.784522 180)
		(property "Reference" "R491"
			(at 0 0 180)
			(layer "F.SilkS")
			(hide yes)
			(effects
				(font
					(size 1.27 1.27)
				)
			)
		)
		(property "Value" ""
			(at 0 0 180)
			(layer "F.Fab")
			(effects
				(font
					(size 1.27 1.27)
				)
			)
		)
		(duplicate_pad_numbers_are_jumpers no)
		(fp_line
			(start 0.7874 0.4064)
			(end -0.7874 0.4064)
			(stroke
				(width 0.1524)
				(type default)
			)
			(layer "F.SilkS")
		)
		(fp_line
			(start 0.7874 -0.4064)
			(end 0.7874 0.4064)
			(stroke
				(width 0.1524)
				(type default)
			)
			(layer "F.SilkS")
		)
		(fp_line
			(start -0.7874 0.4064)
			(end -0.7874 -0.4064)
			(stroke
				(width 0.1524)
				(type default)
			)
			(layer "F.SilkS")
		)
		(fp_line
			(start -0.7874 -0.4064)
			(end 0.7874 -0.4064)
			(stroke
				(width 0.1524)
				(type default)
			)
			(layer "F.SilkS")
		)
		(fp_line
			(start 0.67945 0.3048)
			(end 0.120396 0.3048)
			(stroke
				(width 0.1)
				(type default)
			)
			(layer "F.Fab")
		)
		(fp_line
			(start 0.67945 -0.3048)
			(end 0.67945 0.3048)
			(stroke
				(width 0.1)
				(type default)
			)
			(layer "F.Fab")
		)
		(fp_line
			(start 0.12065 -0.2794)
			(end 0.12065 -0.3048)
			(stroke
				(width 0.1)
				(type default)
			)
			(layer "F.Fab")
		)
		(fp_line
			(start 0.12065 -0.3048)
			(end 0.67945 -0.3048)
			(stroke
				(width 0.1)
				(type default)
			)
			(layer "F.Fab")
		)
		(fp_line
			(start 0.120396 0.3048)
			(end 0.120396 0.2794)
			(stroke
				(width 0.1)
				(type default)
			)
			(layer "F.Fab")
		)
		(fp_line
			(start 0.120396 0.2794)
			(end -0.12065 0.2794)
			(stroke
				(width 0.1)
				(type default)
			)
			(layer "F.Fab")
		)
		(fp_line
			(start -0.12065 0.3048)
			(end -0.67945 0.3048)
			(stroke
				(width 0.1)
				(type default)
			)
			(layer "F.Fab")
		)
		(fp_line
			(start -0.12065 0.2794)
			(end -0.12065 0.3048)
			(stroke
				(width 0.1)
				(type default)
			)
			(layer "F.Fab")
		)
		(fp_line
			(start -0.12065 -0.2794)
			(end 0.12065 -0.2794)
			(stroke
				(width 0.1)
				(type default)
			)
			(layer "F.Fab")
		)
		(fp_line
			(start -0.12065 -0.305054)
			(end -0.12065 -0.2794)
			(stroke
				(width 0.1)
				(type default)
			)
			(layer "F.Fab")
		)
		(fp_line
			(start -0.67945 0.3048)
			(end -0.67945 -0.305054)
			(stroke
				(width 0.1)
				(type default)
			)
			(layer "F.Fab")
		)
		(fp_line
			(start -0.67945 -0.305054)
			(end -0.12065 -0.305054)
			(stroke
				(width 0.1)
				(type default)
			)
			(layer "F.Fab")
		)
		(pad "1" smd circle
			(at -0.40005 0 180)
			(size 0 0)
			(layers "F.Cu" "F.Mask" "F.Paste")
			(net "M2_SSD0_CLKREQ_EN_N")
		)
		(pad "2" smd circle
			(at 0.40005 0 180)
			(size 0 0)
			(layers "F.Cu" "F.Mask" "F.Paste")
			(net "GND")
		)
	)
	(footprint ""
		(layer "F.Cu")
		(at 118.09222 -296.05478 180)
		(property "Reference" "C245"
			(at 0 0 180)
			(layer "F.SilkS")
			(hide yes)
			(effects
				(font
					(size 1.27 1.27)
				)
			)
		)
		(property "Value" ""
			(at 0 0 180)
			(layer "F.Fab")
			(effects
				(font
					(size 1.27 1.27)
				)
			)
		)
		(duplicate_pad_numbers_are_jumpers no)
		(fp_line
			(start 1.524 0.762)
			(end -1.524 0.762)
			(stroke
				(width 0.1524)
				(type default)
			)
			(layer "F.SilkS")
		)
		(fp_line
			(start 1.524 -0.762)
			(end 1.524 0.762)
			(stroke
				(width 0.1524)
				(type default)
			)
			(layer "F.SilkS")
		)
		(fp_line
			(start -1.524 0.762)
			(end -1.524 -0.762)
			(stroke
				(width 0.1524)
				(type default)
			)
			(layer "F.SilkS")
		)
		(fp_line
			(start -1.524 -0.762)
			(end 1.524 -0.762)
			(stroke
				(width 0.1524)
				(type default)
			)
			(layer "F.SilkS")
		)
		(fp_line
			(start 1.1049 0.724916)
			(end 1.1049 -0.724916)
			(stroke
				(width 0.1)
				(type default)
			)
			(layer "F.Fab")
		)
		(fp_line
			(start 1.1049 -0.724916)
			(end -1.1049 -0.724916)
			(stroke
				(width 0.1)
				(type default)
			)
			(layer "F.Fab")
		)
		(fp_line
			(start -1.1049 0.724916)
			(end 1.1049 0.724916)
			(stroke
				(width 0.1)
				(type default)
			)
			(layer "F.Fab")
		)
		(fp_line
			(start -1.1049 -0.724916)
			(end -1.1049 0.724916)
			(stroke
				(width 0.1)
				(type default)
			)
			(layer "F.Fab")
		)
		(pad "1" smd rect
			(at -0.889 0)
			(size 1.016 1.27)
			(layers "F.Cu" "F.Mask" "F.Paste")
			(net "PVCCIN_CPU1")
		)
		(pad "2" smd rect
			(at 0.889 0)
			(size 1.016 1.27)
			(layers "F.Cu" "F.Mask" "F.Paste")
			(net "GND")
		)
	)
	(footprint ""
		(layer "F.Cu")
		(at 128.401572 -134.066026)
		(property "Reference" "R3580"
			(at 0 0 0)
			(layer "F.SilkS")
			(hide yes)
			(effects
				(font
					(size 1.27 1.27)
				)
			)
		)
		(property "Value" ""
			(at 0 0 0)
			(layer "F.Fab")
			(effects
				(font
					(size 1.27 1.27)
				)
			)
		)
		(duplicate_pad_numbers_are_jumpers no)
		(fp_line
			(start -0.7874 -0.4064)
			(end 0.7874 -0.4064)
			(stroke
				(width 0.1524)
				(type default)
			)
			(layer "F.SilkS")
		)
		(fp_line
			(start -0.7874 0.4064)
			(end -0.7874 -0.4064)
			(stroke
				(width 0.1524)
				(type default)
			)
			(layer "F.SilkS")
		)
		(fp_line
			(start 0.7874 -0.4064)
			(end 0.7874 0.4064)
			(stroke
				(width 0.1524)
				(type default)
			)
			(layer "F.SilkS")
		)
		(fp_line
			(start 0.7874 0.4064)
			(end -0.7874 0.4064)
			(stroke
				(width 0.1524)
				(type default)
			)
			(layer "F.SilkS")
		)
		(fp_line
			(start -0.67945 -0.305054)
			(end -0.12065 -0.305054)
			(stroke
				(width 0.1)
				(type default)
			)
			(layer "F.Fab")
		)
		(fp_line
			(start -0.67945 0.3048)
			(end -0.67945 -0.305054)
			(stroke
				(width 0.1)
				(type default)
			)
			(layer "F.Fab")
		)
		(fp_line
			(start -0.12065 -0.305054)
			(end -0.12065 -0.2794)
			(stroke
				(width 0.1)
				(type default)
			)
			(layer "F.Fab")
		)
		(fp_line
			(start -0.12065 -0.2794)
			(end 0.12065 -0.2794)
			(stroke
				(width 0.1)
				(type default)
			)
			(layer "F.Fab")
		)
		(fp_line
			(start -0.12065 0.2794)
			(end -0.12065 0.3048)
			(stroke
				(width 0.1)
				(type default)
			)
			(layer "F.Fab")
		)
		(fp_line
			(start -0.12065 0.3048)
			(end -0.67945 0.3048)
			(stroke
				(width 0.1)
				(type default)
			)
			(layer "F.Fab")
		)
		(fp_line
			(start 0.120396 0.2794)
			(end -0.12065 0.2794)
			(stroke
				(width 0.1)
				(type default)
			)
			(layer "F.Fab")
		)
		(fp_line
			(start 0.120396 0.3048)
			(end 0.120396 0.2794)
			(stroke
				(width 0.1)
				(type default)
			)
			(layer "F.Fab")
		)
		(fp_line
			(start 0.12065 -0.3048)
			(end 0.67945 -0.3048)
			(stroke
				(width 0.1)
				(type default)
			)
			(layer "F.Fab")
		)
		(fp_line
			(start 0.12065 -0.2794)
			(end 0.12065 -0.3048)
			(stroke
				(width 0.1)
				(type default)
			)
			(layer "F.Fab")
		)
		(fp_line
			(start 0.67945 -0.3048)
			(end 0.67945 0.3048)
			(stroke
				(width 0.1)
				(type default)
			)
			(layer "F.Fab")
		)
		(fp_line
			(start 0.67945 0.3048)
			(end 0.120396 0.3048)
			(stroke
				(width 0.1)
				(type default)
			)
			(layer "F.Fab")
		)
		(pad "1" smd circle
			(at -0.40005 0)
			(size 0 0)
			(layers "F.Cu" "F.Mask" "F.Paste")
			(net "SMB_INA230_3V3AUX_SCL_R")
		)
		(pad "2" smd circle
			(at 0.40005 0)
			(size 0 0)
			(layers "F.Cu" "F.Mask" "F.Paste")
			(net "SMB_INA230_3V3AUX_SCL")
		)
	)
	(footprint ""
		(layer "F.Cu")
		(at 180.528468 -44.091098 180)
		(property "Reference" "C1099"
			(at 0 0 180)
			(layer "F.SilkS")
			(hide yes)
			(effects
				(font
					(size 1.27 1.27)
				)
			)
		)
		(property "Value" ""
			(at 0 0 180)
			(layer "F.Fab")
			(effects
				(font
					(size 1.27 1.27)
				)
			)
		)
		(duplicate_pad_numbers_are_jumpers no)
		(fp_line
			(start 0.299974 0.150114)
			(end -0.299974 0.150114)
			(stroke
				(width 0.1)
				(type default)
			)
			(layer "F.Fab")
		)
		(fp_line
			(start 0.299974 -0.150114)
			(end 0.299974 0.150114)
			(stroke
				(width 0.1)
				(type default)
			)
			(layer "F.Fab")
		)
		(fp_line
			(start -0.299974 0.150114)
			(end -0.299974 -0.150114)
			(stroke
				(width 0.1)
				(type default)
			)
			(layer "F.Fab")
		)
		(fp_line
			(start -0.299974 -0.150114)
			(end 0.299974 -0.150114)
			(stroke
				(width 0.1)
				(type default)
			)
			(layer "F.Fab")
		)
		(pad "1" smd rect
			(at -0.2667 0 180)
			(size 0.3048 0.381)
			(layers "F.Cu" "F.Mask" "F.Paste")
			(net "P3E_PCH_M2_TX_DN<3>")
		)
		(pad "2" smd rect
			(at 0.2667 0 180)
			(size 0.3048 0.381)
			(layers "F.Cu" "F.Mask" "F.Paste")
			(net "P3E_PCH_M2_TX_C_DN<3>")
		)
		(zone
			(layer "In1.Cu")
			(hatch none 0.5)
			(connect_pads
				(clearance 0)
			)
			(min_thickness 0.25)
			(keepout
				(tracks not_allowed)
				(vias allowed)
				(pads allowed)
				(copperpour not_allowed)
				(footprints allowed)
			)
			(placement
				(enabled no)
				(sheetname "")
			)
			(fill
				(thermal_gap 0.5)
				(thermal_bridge_width 0.5)
				(island_removal_mode 0)
			)
			(polygon
				(pts
					(arc
						(start 180.388768 -44.332398)
						(mid 180.44265 -44.31008)
						(end 180.464968 -44.256198)
					)
					(arc
						(start 180.464968 -43.925998)
						(mid 180.44265 -43.872116)
						(end 180.388768 -43.849798)
					)
					(arc
						(start 180.134768 -43.849798)
						(mid 180.080886 -43.872116)
						(end 180.058568 -43.925998)
					)
					(arc
						(start 180.058568 -44.256198)
						(mid 180.080886 -44.31008)
						(end 180.134768 -44.332398)
					)
				)
			)
		)
		(zone
			(layer "In1.Cu")
			(hatch none 0.5)
			(connect_pads
				(clearance 0)
			)
			(min_thickness 0.25)
			(keepout
				(tracks not_allowed)
				(vias allowed)
				(pads allowed)
				(copperpour not_allowed)
				(footprints allowed)
			)
			(placement
				(enabled no)
				(sheetname "")
			)
			(fill
				(thermal_gap 0.5)
				(thermal_bridge_width 0.5)
				(island_removal_mode 0)
			)
			(polygon
				(pts
					(arc
						(start 180.922168 -44.332398)
						(mid 180.97605 -44.31008)
						(end 180.998368 -44.256198)
					)
					(arc
						(start 180.998368 -43.925998)
						(mid 180.97605 -43.872116)
						(end 180.922168 -43.849798)
					)
					(arc
						(start 180.668168 -43.849798)
						(mid 180.614286 -43.872116)
						(end 180.591968 -43.925998)
					)
					(arc
						(start 180.591968 -44.256198)
						(mid 180.614286 -44.31008)
						(end 180.668168 -44.332398)
					)
				)
			)
		)
	)
	(footprint ""
		(layer "F.Cu")
		(at 309.030624 -62.375542 90)
		(property "Reference" "R3064"
			(at 0 0 90)
			(layer "F.SilkS")
			(hide yes)
			(effects
				(font
					(size 1.27 1.27)
				)
			)
		)
		(property "Value" ""
			(at 0 0 90)
			(layer "F.Fab")
			(effects
				(font
					(size 1.27 1.27)
				)
			)
		)
		(duplicate_pad_numbers_are_jumpers no)
		(fp_line
			(start 0.7874 -0.4064)
			(end 0.7874 0.4064)
			(stroke
				(width 0.1524)
				(type default)
			)
			(layer "F.SilkS")
		)
		(fp_line
			(start -0.7874 -0.4064)
			(end 0.7874 -0.4064)
			(stroke
				(width 0.1524)
				(type default)
			)
			(layer "F.SilkS")
		)
		(fp_line
			(start 0.7874 0.4064)
			(end -0.7874 0.4064)
			(stroke
				(width 0.1524)
				(type default)
			)
			(layer "F.SilkS")
		)
		(fp_line
			(start -0.7874 0.4064)
			(end -0.7874 -0.4064)
			(stroke
				(width 0.1524)
				(type default)
			)
			(layer "F.SilkS")
		)
		(fp_line
			(start -0.12065 -0.305054)
			(end -0.12065 -0.2794)
			(stroke
				(width 0.1)
				(type default)
			)
			(layer "F.Fab")
		)
		(fp_line
			(start -0.67945 -0.305054)
			(end -0.12065 -0.305054)
			(stroke
				(width 0.1)
				(type default)
			)
			(layer "F.Fab")
		)
		(fp_line
			(start 0.67945 -0.3048)
			(end 0.67945 0.3048)
			(stroke
				(width 0.1)
				(type default)
			)
			(layer "F.Fab")
		)
		(fp_line
			(start 0.12065 -0.3048)
			(end 0.67945 -0.3048)
			(stroke
				(width 0.1)
				(type default)
			)
			(layer "F.Fab")
		)
		(fp_line
			(start 0.12065 -0.2794)
			(end 0.12065 -0.3048)
			(stroke
				(width 0.1)
				(type default)
			)
			(layer "F.Fab")
		)
		(fp_line
			(start -0.12065 -0.2794)
			(end 0.12065 -0.2794)
			(stroke
				(width 0.1)
				(type default)
			)
			(layer "F.Fab")
		)
		(fp_line
			(start 0.120396 0.2794)
			(end -0.12065 0.2794)
			(stroke
				(width 0.1)
				(type default)
			)
			(layer "F.Fab")
		)
		(fp_line
			(start -0.12065 0.2794)
			(end -0.12065 0.3048)
			(stroke
				(width 0.1)
				(type default)
			)
			(layer "F.Fab")
		)
		(fp_line
			(start 0.67945 0.3048)
			(end 0.120396 0.3048)
			(stroke
				(width 0.1)
				(type default)
			)
			(layer "F.Fab")
		)
		(fp_line
			(start 0.120396 0.3048)
			(end 0.120396 0.2794)
			(stroke
				(width 0.1)
				(type default)
			)
			(layer "F.Fab")
		)
		(fp_line
			(start -0.12065 0.3048)
			(end -0.67945 0.3048)
			(stroke
				(width 0.1)
				(type default)
			)
			(layer "F.Fab")
		)
		(fp_line
			(start -0.67945 0.3048)
			(end -0.67945 -0.305054)
			(stroke
				(width 0.1)
				(type default)
			)
			(layer "F.Fab")
		)
		(pad "1" smd circle
			(at -0.40005 0 90)
			(size 0 0)
			(layers "F.Cu" "F.Mask" "F.Paste")
			(net "PECI_CPU_GTL")
		)
		(pad "2" smd circle
			(at 0.40005 0 90)
			(size 0 0)
			(layers "F.Cu" "F.Mask" "F.Paste")
			(net "PECI_BMC_ME")
		)
	)
	(footprint ""
		(layer "F.Cu")
		(at 111.332772 -130.869182)
		(property "Reference" "R1090"
			(at 0 0 0)
			(layer "F.SilkS")
			(hide yes)
			(effects
				(font
					(size 1.27 1.27)
				)
			)
		)
		(property "Value" ""
			(at 0 0 0)
			(layer "F.Fab")
			(effects
				(font
					(size 1.27 1.27)
				)
			)
		)
		(duplicate_pad_numbers_are_jumpers no)
		(fp_line
			(start -0.7874 -0.4064)
			(end 0.7874 -0.4064)
			(stroke
				(width 0.1524)
				(type default)
			)
			(layer "F.SilkS")
		)
		(fp_line
			(start -0.7874 0.4064)
			(end -0.7874 -0.4064)
			(stroke
				(width 0.1524)
				(type default)
			)
			(layer "F.SilkS")
		)
		(fp_line
			(start 0.7874 -0.4064)
			(end 0.7874 0.4064)
			(stroke
				(width 0.1524)
				(type default)
			)
			(layer "F.SilkS")
		)
		(fp_line
			(start 0.7874 0.4064)
			(end -0.7874 0.4064)
			(stroke
				(width 0.1524)
				(type default)
			)
			(layer "F.SilkS")
		)
		(fp_line
			(start -0.67945 -0.305054)
			(end -0.12065 -0.305054)
			(stroke
				(width 0.1)
				(type default)
			)
			(layer "F.Fab")
		)
		(fp_line
			(start -0.67945 0.3048)
			(end -0.67945 -0.305054)
			(stroke
				(width 0.1)
				(type default)
			)
			(layer "F.Fab")
		)
		(fp_line
			(start -0.12065 -0.305054)
			(end -0.12065 -0.2794)
			(stroke
				(width 0.1)
				(type default)
			)
			(layer "F.Fab")
		)
		(fp_line
			(start -0.12065 -0.2794)
			(end 0.12065 -0.2794)
			(stroke
				(width 0.1)
				(type default)
			)
			(layer "F.Fab")
		)
		(fp_line
			(start -0.12065 0.2794)
			(end -0.12065 0.3048)
			(stroke
				(width 0.1)
				(type default)
			)
			(layer "F.Fab")
		)
		(fp_line
			(start -0.12065 0.3048)
			(end -0.67945 0.3048)
			(stroke
				(width 0.1)
				(type default)
			)
			(layer "F.Fab")
		)
		(fp_line
			(start 0.120396 0.2794)
			(end -0.12065 0.2794)
			(stroke
				(width 0.1)
				(type default)
			)
			(layer "F.Fab")
		)
		(fp_line
			(start 0.120396 0.3048)
			(end 0.120396 0.2794)
			(stroke
				(width 0.1)
				(type default)
			)
			(layer "F.Fab")
		)
		(fp_line
			(start 0.12065 -0.3048)
			(end 0.67945 -0.3048)
			(stroke
				(width 0.1)
				(type default)
			)
			(layer "F.Fab")
		)
		(fp_line
			(start 0.12065 -0.2794)
			(end 0.12065 -0.3048)
			(stroke
				(width 0.1)
				(type default)
			)
			(layer "F.Fab")
		)
		(fp_line
			(start 0.67945 -0.3048)
			(end 0.67945 0.3048)
			(stroke
				(width 0.1)
				(type default)
			)
			(layer "F.Fab")
		)
		(fp_line
			(start 0.67945 0.3048)
			(end 0.120396 0.3048)
			(stroke
				(width 0.1)
				(type default)
			)
			(layer "F.Fab")
		)
		(pad "1" smd circle
			(at -0.40005 0)
			(size 0 0)
			(layers "F.Cu" "F.Mask" "F.Paste")
			(net "P3V3_AUX")
		)
		(pad "2" smd circle
			(at 0.40005 0)
			(size 0 0)
			(layers "F.Cu" "F.Mask" "F.Paste")
			(net "SMB_SENSOR_M2_P0_3V3AUX_SDA")
		)
	)
	(footprint ""
		(layer "F.Cu")
		(at 461.720946 -102.41915)
		(property "Reference" "R1147"
			(at 0 0 0)
			(layer "F.SilkS")
			(hide yes)
			(effects
				(font
					(size 1.27 1.27)
				)
			)
		)
		(property "Value" ""
			(at 0 0 0)
			(layer "F.Fab")
			(effects
				(font
					(size 1.27 1.27)
				)
			)
		)
		(duplicate_pad_numbers_are_jumpers no)
		(fp_line
			(start -0.7874 -0.4064)
			(end 0.7874 -0.4064)
			(stroke
				(width 0.1524)
				(type default)
			)
			(layer "F.SilkS")
		)
		(fp_line
			(start -0.7874 0.4064)
			(end -0.7874 -0.4064)
			(stroke
				(width 0.1524)
				(type default)
			)
			(layer "F.SilkS")
		)
		(fp_line
			(start 0.7874 -0.4064)
			(end 0.7874 0.4064)
			(stroke
				(width 0.1524)
				(type default)
			)
			(layer "F.SilkS")
		)
		(fp_line
			(start 0.7874 0.4064)
			(end -0.7874 0.4064)
			(stroke
				(width 0.1524)
				(type default)
			)
			(layer "F.SilkS")
		)
		(fp_line
			(start -0.67945 -0.305054)
			(end -0.12065 -0.305054)
			(stroke
				(width 0.1)
				(type default)
			)
			(layer "F.Fab")
		)
		(fp_line
			(start -0.67945 0.3048)
			(end -0.67945 -0.305054)
			(stroke
				(width 0.1)
				(type default)
			)
			(layer "F.Fab")
		)
		(fp_line
			(start -0.12065 -0.305054)
			(end -0.12065 -0.2794)
			(stroke
				(width 0.1)
				(type default)
			)
			(layer "F.Fab")
		)
		(fp_line
			(start -0.12065 -0.2794)
			(end 0.12065 -0.2794)
			(stroke
				(width 0.1)
				(type default)
			)
			(layer "F.Fab")
		)
		(fp_line
			(start -0.12065 0.2794)
			(end -0.12065 0.3048)
			(stroke
				(width 0.1)
				(type default)
			)
			(layer "F.Fab")
		)
		(fp_line
			(start -0.12065 0.3048)
			(end -0.67945 0.3048)
			(stroke
				(width 0.1)
				(type default)
			)
			(layer "F.Fab")
		)
		(fp_line
			(start 0.120396 0.2794)
			(end -0.12065 0.2794)
			(stroke
				(width 0.1)
				(type default)
			)
			(layer "F.Fab")
		)
		(fp_line
			(start 0.120396 0.3048)
			(end 0.120396 0.2794)
			(stroke
				(width 0.1)
				(type default)
			)
			(layer "F.Fab")
		)
		(fp_line
			(start 0.12065 -0.3048)
			(end 0.67945 -0.3048)
			(stroke
				(width 0.1)
				(type default)
			)
			(layer "F.Fab")
		)
		(fp_line
			(start 0.12065 -0.2794)
			(end 0.12065 -0.3048)
			(stroke
				(width 0.1)
				(type default)
			)
			(layer "F.Fab")
		)
		(fp_line
			(start 0.67945 -0.3048)
			(end 0.67945 0.3048)
			(stroke
				(width 0.1)
				(type default)
			)
			(layer "F.Fab")
		)
		(fp_line
			(start 0.67945 0.3048)
			(end 0.120396 0.3048)
			(stroke
				(width 0.1)
				(type default)
			)
			(layer "F.Fab")
		)
		(pad "1" smd circle
			(at -0.40005 0)
			(size 0 0)
			(layers "F.Cu" "F.Mask" "F.Paste")
			(net "HP_LVC3_OCP_V3_1_PRSNT2_N_R")
		)
		(pad "2" smd circle
			(at 0.40005 0)
			(size 0 0)
			(layers "F.Cu" "F.Mask" "F.Paste")
			(net "HP_LVC3_OCP_V3_1_ATTN_OUT_SW_N")
		)
	)
	(footprint ""
		(layer "F.Cu")
		(at 461.459834 -347.699838)
		(property "Reference" "H98"
			(at -6.703314 -4.139692 0)
			(unlocked yes)
			(layer "F.SilkS")
			(effects
				(font
					(size 0.7874 0.5842)
					(thickness 0.1524)
				)
				(justify left)
			)
		)
		(property "Value" ""
			(at 0 0 0)
			(layer "F.Fab")
			(effects
				(font
					(size 1.27 1.27)
				)
			)
		)
		(duplicate_pad_numbers_are_jumpers no)
		(pad "1" thru_hole circle
			(at 0 0)
			(size 10.0076 10.0076)
			(drill 5.6134)
			(layers "*.Cu" "*.Mask")
			(remove_unused_layers no)
			(net "GND")
			(clearance -1.9431)
		)
	)
	(footprint ""
		(layer "F.Cu")
		(at 18.302478 -17.623536 90)
		(property "Reference" "C808"
			(at 0 0 90)
			(layer "F.SilkS")
			(hide yes)
			(effects
				(font
					(size 1.27 1.27)
				)
			)
		)
		(property "Value" ""
			(at 0 0 90)
			(layer "F.Fab")
			(effects
				(font
					(size 1.27 1.27)
				)
			)
		)
		(duplicate_pad_numbers_are_jumpers no)
		(fp_line
			(start 0.299974 -0.150114)
			(end 0.299974 0.150114)
			(stroke
				(width 0.1)
				(type default)
			)
			(layer "F.Fab")
		)
		(fp_line
			(start -0.299974 -0.150114)
			(end 0.299974 -0.150114)
			(stroke
				(width 0.1)
				(type default)
			)
			(layer "F.Fab")
		)
		(fp_line
			(start 0.299974 0.150114)
			(end -0.299974 0.150114)
			(stroke
				(width 0.1)
				(type default)
			)
			(layer "F.Fab")
		)
		(fp_line
			(start -0.299974 0.150114)
			(end -0.299974 -0.150114)
			(stroke
				(width 0.1)
				(type default)
			)
			(layer "F.Fab")
		)
		(pad "1" smd rect
			(at -0.2667 0 90)
			(size 0.3048 0.381)
			(layers "F.Cu" "F.Mask" "F.Paste")
			(net "P5E_CPU1_PE1_TX_C_DN<14>")
		)
		(pad "2" smd rect
			(at 0.2667 0 90)
			(size 0.3048 0.381)
			(layers "F.Cu" "F.Mask" "F.Paste")
			(net "P5E_CPU1_PE1_TX_DN<14>")
		)
	)
	(footprint ""
		(layer "F.Cu")
		(at 125.750066 -440.489848)
		(property "Reference" "J110"
			(at -3.723386 20.59559 0)
			(unlocked yes)
			(layer "F.SilkS")
			(effects
				(font
					(size 0.7874 0.5842)
					(thickness 0.1524)
				)
				(justify left)
			)
		)
		(property "Value" ""
			(at 0 0 0)
			(layer "F.Fab")
			(effects
				(font
					(size 1.27 1.27)
				)
			)
		)
		(duplicate_pad_numbers_are_jumpers no)
		(fp_line
			(start -4.249928 -11.999976)
			(end 18.64995 -11.999976)
			(stroke
				(width 0.1524)
				(type default)
			)
			(layer "F.SilkS")
		)
		(fp_line
			(start -4.249928 22.400006)
			(end -4.249928 -11.999976)
			(stroke
				(width 0.1524)
				(type default)
			)
			(layer "F.SilkS")
		)
		(fp_line
			(start -1.249934 -8.999982)
			(end -1.249934 19.400012)
			(stroke
				(width 0.1524)
				(type default)
			)
			(layer "F.SilkS")
		)
		(fp_line
			(start -1.249934 -1.500124)
			(end 15.649956 -1.500124)
			(stroke
				(width 0.1524)
				(type default)
			)
			(layer "F.SilkS")
		)
		(fp_line
			(start -1.249934 19.400012)
			(end 15.649956 19.400012)
			(stroke
				(width 0.1524)
				(type default)
			)
			(layer "F.SilkS")
		)
		(fp_line
			(start 0.0254 -0.9144)
			(end 1.0414 -0.9144)
			(stroke
				(width 0.1524)
				(type default)
			)
			(layer "F.SilkS")
		)
		(fp_line
			(start 0.5334 -1.4224)
			(end 0.0254 -0.9144)
			(stroke
				(width 0.1524)
				(type default)
			)
			(layer "F.SilkS")
		)
		(fp_line
			(start 0.5334 -1.4224)
			(end 0.5334 -0.5588)
			(stroke
				(width 0.1524)
				(type default)
			)
			(layer "F.SilkS")
		)
		(fp_line
			(start 0.5334 -0.5588)
			(end 1.8034 -0.5588)
			(stroke
				(width 0.1524)
				(type default)
			)
			(layer "F.SilkS")
		)
		(fp_line
			(start 1.0414 -0.9144)
			(end 0.5334 -1.4224)
			(stroke
				(width 0.1524)
				(type default)
			)
			(layer "F.SilkS")
		)
		(fp_line
			(start 1.8034 -0.5588)
			(end 2.032 -0.7874)
			(stroke
				(width 0.1524)
				(type default)
			)
			(layer "F.SilkS")
		)
		(fp_line
			(start 15.649956 -8.999982)
			(end -1.249934 -8.999982)
			(stroke
				(width 0.1524)
				(type default)
			)
			(layer "F.SilkS")
		)
		(fp_line
			(start 15.649956 19.400012)
			(end 15.649956 -8.999982)
			(stroke
				(width 0.1524)
				(type default)
			)
			(layer "F.SilkS")
		)
		(fp_line
			(start 18.64995 -11.999976)
			(end 18.64995 -1.231392)
			(stroke
				(width 0.1524)
				(type default)
			)
			(layer "F.SilkS")
		)
		(fp_line
			(start 18.64995 16.784828)
			(end 18.64995 22.400006)
			(stroke
				(width 0.1524)
				(type default)
			)
			(layer "F.SilkS")
		)
		(fp_line
			(start 18.64995 22.400006)
			(end -4.249928 22.400006)
			(stroke
				(width 0.1524)
				(type default)
			)
			(layer "F.SilkS")
		)
		(fp_poly
			(pts
				(xy -2.586228 -0.38354) (xy -1.570228 0.12446) (xy -2.586228 0.63246)
			)
			(stroke
				(width 0)
				(type default)
			)
			(fill yes)
			(layer "F.SilkS")
		)
		(fp_line
			(start -4.249928 -11.999976)
			(end 18.64995 -11.999976)
			(stroke
				(width 0.1524)
				(type default)
			)
			(layer "B.SilkS")
		)
		(fp_line
			(start -4.249928 17.49552)
			(end -4.249928 -11.999976)
			(stroke
				(width 0.1524)
				(type default)
			)
			(layer "B.SilkS")
		)
		(fp_line
			(start -4.249928 22.400006)
			(end -4.249928 19.69516)
			(stroke
				(width 0.1524)
				(type default)
			)
			(layer "B.SilkS")
		)
		(fp_line
			(start 18.64995 -11.999976)
			(end 18.64995 -1.086612)
			(stroke
				(width 0.1524)
				(type default)
			)
			(layer "B.SilkS")
		)
		(fp_line
			(start 18.64995 17.943068)
			(end 18.64995 22.400006)
			(stroke
				(width 0.1524)
				(type default)
			)
			(layer "B.SilkS")
		)
		(fp_line
			(start 18.64995 22.400006)
			(end -4.249928 22.400006)
			(stroke
				(width 0.1524)
				(type default)
			)
			(layer "B.SilkS")
		)
		(fp_line
			(start -4.249928 -11.999976)
			(end 18.64995 -11.999976)
			(stroke
				(width 0.1)
				(type default)
			)
			(layer "B.Fab")
		)
		(fp_line
			(start -4.249928 22.400006)
			(end -4.249928 -11.999976)
			(stroke
				(width 0.1)
				(type default)
			)
			(layer "B.Fab")
		)
		(fp_line
			(start 18.64995 -11.999976)
			(end 18.64995 22.400006)
			(stroke
				(width 0.1)
				(type default)
			)
			(layer "B.Fab")
		)
		(fp_line
			(start 18.64995 22.400006)
			(end -4.249928 22.400006)
			(stroke
				(width 0.1)
				(type default)
			)
			(layer "B.Fab")
		)
		(fp_line
			(start -1.249934 -8.999982)
			(end -1.249934 19.400012)
			(stroke
				(width 0.1)
				(type default)
			)
			(layer "F.Fab")
		)
		(fp_line
			(start -1.249934 19.400012)
			(end 15.649956 19.400012)
			(stroke
				(width 0.1)
				(type default)
			)
			(layer "F.Fab")
		)
		(fp_line
			(start 15.649956 -8.999982)
			(end -1.249934 -8.999982)
			(stroke
				(width 0.1)
				(type default)
			)
			(layer "F.Fab")
		)
		(fp_line
			(start 15.649956 19.400012)
			(end 15.649956 -8.999982)
			(stroke
				(width 0.1)
				(type default)
			)
			(layer "F.Fab")
		)
		(fp_poly
			(pts
				(xy -2.670048 -0.508) (xy -2.670048 0.508) (xy -1.654048 0)
			)
			(stroke
				(width 0)
				(type default)
			)
			(fill yes)
			(layer "F.Fab")
		)
		(fp_text user "B"
			(at -2.232152 1.549146 0)
			(unlocked yes)
			(layer "F.SilkS")
			(effects
				(font
					(size 0.7874 0.5842)
					(thickness 0.1524)
				)
			)
		)
		(fp_text user "C"
			(at -2.232152 2.749296 0)
			(unlocked yes)
			(layer "F.SilkS")
			(effects
				(font
					(size 0.7874 0.5842)
					(thickness 0.1524)
				)
			)
		)
		(fp_text user "D"
			(at -2.232152 3.949192 0)
			(unlocked yes)
			(layer "F.SilkS")
			(effects
				(font
					(size 0.7874 0.5842)
					(thickness 0.1524)
				)
			)
		)
		(fp_text user "E"
			(at -2.232152 5.149342 0)
			(unlocked yes)
			(layer "F.SilkS")
			(effects
				(font
					(size 0.7874 0.5842)
					(thickness 0.1524)
				)
			)
		)
		(fp_text user "F"
			(at -2.232152 6.349238 0)
			(unlocked yes)
			(layer "F.SilkS")
			(effects
				(font
					(size 0.7874 0.5842)
					(thickness 0.1524)
				)
			)
		)
		(fp_text user "G"
			(at -2.232152 7.549134 0)
			(unlocked yes)
			(layer "F.SilkS")
			(effects
				(font
					(size 0.7874 0.5842)
					(thickness 0.1524)
				)
			)
		)
		(fp_text user "H"
			(at -2.232152 8.749284 0)
			(unlocked yes)
			(layer "F.SilkS")
			(effects
				(font
					(size 0.7874 0.5842)
					(thickness 0.1524)
				)
			)
		)
		(fp_text user "I"
			(at -2.232152 9.94918 0)
			(unlocked yes)
			(layer "F.SilkS")
			(effects
				(font
					(size 0.7874 0.5842)
					(thickness 0.1524)
				)
			)
		)
		(fp_text user "J"
			(at -2.232152 11.14933 0)
			(unlocked yes)
			(layer "F.SilkS")
			(effects
				(font
					(size 0.7874 0.5842)
					(thickness 0.1524)
				)
			)
		)
		(fp_text user "K"
			(at -2.232152 12.349226 0)
			(unlocked yes)
			(layer "F.SilkS")
			(effects
				(font
					(size 0.7874 0.5842)
					(thickness 0.1524)
				)
			)
		)
		(fp_text user "L"
			(at -2.232152 13.549376 0)
			(unlocked yes)
			(layer "F.SilkS")
			(effects
				(font
					(size 0.7874 0.5842)
					(thickness 0.1524)
				)
			)
		)
		(fp_text user "M"
			(at -2.232152 14.749272 0)
			(unlocked yes)
			(layer "F.SilkS")
			(effects
				(font
					(size 0.7874 0.5842)
					(thickness 0.1524)
				)
			)
		)
		(fp_text user "N"
			(at -2.232152 15.949168 0)
			(unlocked yes)
			(layer "F.SilkS")
			(effects
				(font
					(size 0.7874 0.5842)
					(thickness 0.1524)
				)
			)
		)
		(fp_text user "PRESS-FIT"
			(at -0.477266 23.92553 0)
			(unlocked yes)
			(layer "F.SilkS")
			(effects
				(font
					(size 1.905 1.4224)
					(thickness 0.1524)
				)
				(justify left)
			)
		)
		(fp_text user "1"
			(at 0.305562 20.15363 0)
			(unlocked yes)
			(layer "F.SilkS")
			(effects
				(font
					(size 0.7874 0.5842)
					(thickness 0.1524)
				)
			)
		)
		(fp_text user "EDGE OF DAUGHTER CARD"
			(at 2.2479 -0.899668 0)
			(unlocked yes)
			(layer "F.SilkS")
			(effects
				(font
					(size 0.635 0.4064)
					(thickness 0.1524)
				)
				(justify left)
			)
		)
		(fp_text user "2"
			(at 2.305558 20.15363 0)
			(unlocked yes)
			(layer "F.SilkS")
			(effects
				(font
					(size 0.7874 0.5842)
					(thickness 0.1524)
				)
			)
		)
		(fp_text user "3"
			(at 4.305554 20.15363 0)
			(unlocked yes)
			(layer "F.SilkS")
			(effects
				(font
					(size 0.7874 0.5842)
					(thickness 0.1524)
				)
			)
		)
		(fp_text user "4"
			(at 6.30555 20.15363 0)
			(unlocked yes)
			(layer "F.SilkS")
			(effects
				(font
					(size 0.7874 0.5842)
					(thickness 0.1524)
				)
			)
		)
		(fp_text user "5"
			(at 8.305546 20.15363 0)
			(unlocked yes)
			(layer "F.SilkS")
			(effects
				(font
					(size 0.7874 0.5842)
					(thickness 0.1524)
				)
			)
		)
		(fp_text user "6"
			(at 10.305542 20.15363 0)
			(unlocked yes)
			(layer "F.SilkS")
			(effects
				(font
					(size 0.7874 0.5842)
					(thickness 0.1524)
				)
			)
		)
		(fp_text user "7"
			(at 11.112754 20.18919 0)
			(unlocked yes)
			(layer "F.SilkS")
			(effects
				(font
					(size 0.7874 0.5842)
					(thickness 0.1524)
				)
			)
		)
		(fp_text user "8"
			(at 11.900154 20.14601 0)
			(unlocked yes)
			(layer "F.SilkS")
			(effects
				(font
					(size 0.7874 0.5842)
					(thickness 0.1524)
				)
			)
		)
		(fp_text user "A"
			(at -1.342644 0.21971 0)
			(unlocked yes)
			(layer "B.SilkS")
			(effects
				(font
					(size 0.7874 0.5842)
					(thickness 0.1524)
				)
				(justify mirror)
			)
		)
		(fp_text user "G"
			(at -1.317244 7.63651 0)
			(unlocked yes)
			(layer "B.SilkS")
			(effects
				(font
					(size 0.7874 0.5842)
					(thickness 0.1524)
				)
				(justify mirror)
			)
		)
		(fp_text user "H"
			(at -1.291844 8.85571 0)
			(unlocked yes)
			(layer "B.SilkS")
			(effects
				(font
					(size 0.7874 0.5842)
					(thickness 0.1524)
				)
				(justify mirror)
			)
		)
		(fp_text user "B"
			(at -1.29032 1.546606 0)
			(unlocked yes)
			(layer "B.SilkS")
			(effects
				(font
					(size 0.7874 0.5842)
					(thickness 0.1524)
				)
				(justify mirror)
			)
		)
		(fp_text user "C"
			(at -1.29032 2.746756 0)
			(unlocked yes)
			(layer "B.SilkS")
			(effects
				(font
					(size 0.7874 0.5842)
					(thickness 0.1524)
				)
				(justify mirror)
			)
		)
		(fp_text user "D"
			(at -1.29032 3.946652 0)
			(unlocked yes)
			(layer "B.SilkS")
			(effects
				(font
					(size 0.7874 0.5842)
					(thickness 0.1524)
				)
				(justify mirror)
			)
		)
		(fp_text user "E"
			(at -1.29032 5.146802 0)
			(unlocked yes)
			(layer "B.SilkS")
			(effects
				(font
					(size 0.7874 0.5842)
					(thickness 0.1524)
				)
				(justify mirror)
			)
		)
		(fp_text user "F"
			(at -1.29032 6.346698 0)
			(unlocked yes)
			(layer "B.SilkS")
			(effects
				(font
					(size 0.7874 0.5842)
					(thickness 0.1524)
				)
				(justify mirror)
			)
		)
		(fp_text user "I"
			(at -1.29032 9.94664 0)
			(unlocked yes)
			(layer "B.SilkS")
			(effects
				(font
					(size 0.7874 0.5842)
					(thickness 0.1524)
				)
				(justify mirror)
			)
		)
		(fp_text user "J"
			(at -1.29032 11.14679 0)
			(unlocked yes)
			(layer "B.SilkS")
			(effects
				(font
					(size 0.7874 0.5842)
					(thickness 0.1524)
				)
				(justify mirror)
			)
		)
		(fp_text user "K"
			(at -1.29032 12.346686 0)
			(unlocked yes)
			(layer "B.SilkS")
			(effects
				(font
					(size 0.7874 0.5842)
					(thickness 0.1524)
				)
				(justify mirror)
			)
		)
		(fp_text user "L"
			(at -1.29032 13.546836 0)
			(unlocked yes)
			(layer "B.SilkS")
			(effects
				(font
					(size 0.7874 0.5842)
					(thickness 0.1524)
				)
				(justify mirror)
			)
		)
		(fp_text user "M"
			(at -1.29032 14.746732 0)
			(unlocked yes)
			(layer "B.SilkS")
			(effects
				(font
					(size 0.7874 0.5842)
					(thickness 0.1524)
				)
				(justify mirror)
			)
		)
		(fp_text user "N"
			(at -1.29032 15.946628 0)
			(unlocked yes)
			(layer "B.SilkS")
			(effects
				(font
					(size 0.7874 0.5842)
					(thickness 0.1524)
				)
				(justify mirror)
			)
		)
		(fp_text user "1"
			(at 0.031242 16.98371 0)
			(unlocked yes)
			(layer "B.SilkS")
			(effects
				(font
					(size 0.7874 0.5842)
					(thickness 0.1524)
				)
				(justify mirror)
			)
		)
		(fp_text user "2"
			(at 2.031238 16.98371 0)
			(unlocked yes)
			(layer "B.SilkS")
			(effects
				(font
					(size 0.7874 0.5842)
					(thickness 0.1524)
				)
				(justify mirror)
			)
		)
		(fp_text user "3"
			(at 4.031234 16.98371 0)
			(unlocked yes)
			(layer "B.SilkS")
			(effects
				(font
					(size 0.7874 0.5842)
					(thickness 0.1524)
				)
				(justify mirror)
			)
		)
		(fp_text user "4"
			(at 6.03123 16.98371 0)
			(unlocked yes)
			(layer "B.SilkS")
			(effects
				(font
					(size 0.7874 0.5842)
					(thickness 0.1524)
				)
				(justify mirror)
			)
		)
		(fp_text user "5"
			(at 8.031226 16.98371 0)
			(unlocked yes)
			(layer "B.SilkS")
			(effects
				(font
					(size 0.7874 0.5842)
					(thickness 0.1524)
				)
				(justify mirror)
			)
		)
		(fp_text user "6"
			(at 10.031222 16.98371 0)
			(unlocked yes)
			(layer "B.SilkS")
			(effects
				(font
					(size 0.7874 0.5842)
					(thickness 0.1524)
				)
				(justify mirror)
			)
		)
		(fp_text user "7"
			(at 12.031218 16.98371 0)
			(unlocked yes)
			(layer "B.SilkS")
			(effects
				(font
					(size 0.7874 0.5842)
					(thickness 0.1524)
				)
				(justify mirror)
			)
		)
		(fp_text user "PRESS-FIT"
			(at 12.667234 19.31543 0)
			(unlocked yes)
			(layer "B.SilkS")
			(effects
				(font
					(size 1.905 1.4224)
					(thickness 0.1524)
				)
				(justify left mirror)
			)
		)
		(fp_text user "8"
			(at 14.031214 16.98371 0)
			(unlocked yes)
			(layer "B.SilkS")
			(effects
				(font
					(size 0.7874 0.5842)
					(thickness 0.1524)
				)
				(justify mirror)
			)
		)
		(fp_text user "A"
			(at -1.199134 0 90)
			(unlocked yes)
			(layer "B.Fab")
			(effects
				(font
					(size 0.7874 0.5842)
					(thickness 0.1524)
				)
				(justify mirror)
			)
		)
		(fp_text user "G"
			(at -1.173734 7.4168 90)
			(unlocked yes)
			(layer "B.Fab")
			(effects
				(font
					(size 0.7874 0.5842)
					(thickness 0.1524)
				)
				(justify mirror)
			)
		)
		(fp_text user "H"
			(at -1.148334 8.636 90)
			(unlocked yes)
			(layer "B.Fab")
			(effects
				(font
					(size 0.7874 0.5842)
					(thickness 0.1524)
				)
				(justify mirror)
			)
		)
		(fp_text user "B"
			(at -1.14681 1.326896 90)
			(unlocked yes)
			(layer "B.Fab")
			(effects
				(font
					(size 0.7874 0.5842)
					(thickness 0.1524)
				)
				(justify mirror)
			)
		)
		(fp_text user "C"
			(at -1.14681 2.527046 90)
			(unlocked yes)
			(layer "B.Fab")
			(effects
				(font
					(size 0.7874 0.5842)
					(thickness 0.1524)
				)
				(justify mirror)
			)
		)
		(fp_text user "D"
			(at -1.14681 3.726942 90)
			(unlocked yes)
			(layer "B.Fab")
			(effects
				(font
					(size 0.7874 0.5842)
					(thickness 0.1524)
				)
				(justify mirror)
			)
		)
		(fp_text user "E"
			(at -1.14681 4.927092 90)
			(unlocked yes)
			(layer "B.Fab")
			(effects
				(font
					(size 0.7874 0.5842)
					(thickness 0.1524)
				)
				(justify mirror)
			)
		)
		(fp_text user "F"
			(at -1.14681 6.126988 90)
			(unlocked yes)
			(layer "B.Fab")
			(effects
				(font
					(size 0.7874 0.5842)
					(thickness 0.1524)
				)
				(justify mirror)
			)
		)
		(fp_text user "I"
			(at -1.14681 9.72693 90)
			(unlocked yes)
			(layer "B.Fab")
			(effects
				(font
					(size 0.7874 0.5842)
					(thickness 0.1524)
				)
				(justify mirror)
			)
		)
		(fp_text user "J"
			(at -1.14681 10.92708 90)
			(unlocked yes)
			(layer "B.Fab")
			(effects
				(font
					(size 0.7874 0.5842)
					(thickness 0.1524)
				)
				(justify mirror)
			)
		)
		(fp_text user "K"
			(at -1.14681 12.126976 90)
			(unlocked yes)
			(layer "B.Fab")
			(effects
				(font
					(size 0.7874 0.5842)
					(thickness 0.1524)
				)
				(justify mirror)
			)
		)
		(fp_text user "L"
			(at -1.14681 13.327126 90)
			(unlocked yes)
			(layer "B.Fab")
			(effects
				(font
					(size 0.7874 0.5842)
					(thickness 0.1524)
				)
				(justify mirror)
			)
		)
		(fp_text user "M"
			(at -1.14681 14.527022 90)
			(unlocked yes)
			(layer "B.Fab")
			(effects
				(font
					(size 0.7874 0.5842)
					(thickness 0.1524)
				)
				(justify mirror)
			)
		)
		(fp_text user "N"
			(at -1.14681 15.726918 90)
			(unlocked yes)
			(layer "B.Fab")
			(effects
				(font
					(size 0.7874 0.5842)
					(thickness 0.1524)
				)
				(justify mirror)
			)
		)
		(fp_text user "1"
			(at 0.060452 16.764 90)
			(unlocked yes)
			(layer "B.Fab")
			(effects
				(font
					(size 0.7874 0.5842)
					(thickness 0.1524)
				)
				(justify mirror)
			)
		)
		(fp_text user "2"
			(at 2.060448 16.764 90)
			(unlocked yes)
			(layer "B.Fab")
			(effects
				(font
					(size 0.7874 0.5842)
					(thickness 0.1524)
				)
				(justify mirror)
			)
		)
		(fp_text user "3"
			(at 4.060444 16.764 90)
			(unlocked yes)
			(layer "B.Fab")
			(effects
				(font
					(size 0.7874 0.5842)
					(thickness 0.1524)
				)
				(justify mirror)
			)
		)
		(fp_text user "4"
			(at 6.06044 16.764 90)
			(unlocked yes)
			(layer "B.Fab")
			(effects
				(font
					(size 0.7874 0.5842)
					(thickness 0.1524)
				)
				(justify mirror)
			)
		)
		(fp_text user "5"
			(at 8.060436 16.764 90)
			(unlocked yes)
			(layer "B.Fab")
			(effects
				(font
					(size 0.7874 0.5842)
					(thickness 0.1524)
				)
				(justify mirror)
			)
		)
		(fp_text user "6"
			(at 10.060432 16.764 90)
			(unlocked yes)
			(layer "B.Fab")
			(effects
				(font
					(size 0.7874 0.5842)
					(thickness 0.1524)
				)
				(justify mirror)
			)
		)
		(fp_text user "7"
			(at 12.060428 16.764 90)
			(unlocked yes)
			(layer "B.Fab")
			(effects
				(font
					(size 0.7874 0.5842)
					(thickness 0.1524)
				)
				(justify mirror)
			)
		)
		(fp_text user "8"
			(at 14.060424 16.764 90)
			(unlocked yes)
			(layer "B.Fab")
			(effects
				(font
					(size 0.7874 0.5842)
					(thickness 0.1524)
				)
				(justify mirror)
			)
		)
		(fp_text user "PRESS-FIT"
			(at 17.23771 -0.0762 90)
			(unlocked yes)
			(layer "B.Fab")
			(effects
				(font
					(size 1.905 1.4224)
					(thickness 0.1524)
				)
				(justify left mirror)
			)
		)
		(fp_text user "B"
			(at -2.253742 1.199896 90)
			(unlocked yes)
			(layer "F.Fab")
			(effects
				(font
					(size 0.7874 0.5842)
					(thickness 0.1524)
				)
			)
		)
		(fp_text user "C"
			(at -2.253742 2.400046 90)
			(unlocked yes)
			(layer "F.Fab")
			(effects
				(font
					(size 0.7874 0.5842)
					(thickness 0.1524)
				)
			)
		)
		(fp_text user "D"
			(at -2.253742 3.599942 90)
			(unlocked yes)
			(layer "F.Fab")
			(effects
				(font
					(size 0.7874 0.5842)
					(thickness 0.1524)
				)
			)
		)
		(fp_text user "E"
			(at -2.253742 4.800092 90)
			(unlocked yes)
			(layer "F.Fab")
			(effects
				(font
					(size 0.7874 0.5842)
					(thickness 0.1524)
				)
			)
		)
		(fp_text user "F"
			(at -2.253742 5.999988 90)
			(unlocked yes)
			(layer "F.Fab")
			(effects
				(font
					(size 0.7874 0.5842)
					(thickness 0.1524)
				)
			)
		)
		(fp_text user "G"
			(at -2.253742 7.199884 90)
			(unlocked yes)
			(layer "F.Fab")
			(effects
				(font
					(size 0.7874 0.5842)
					(thickness 0.1524)
				)
			)
		)
		(fp_text user "H"
			(at -2.253742 8.400034 90)
			(unlocked yes)
			(layer "F.Fab")
			(effects
				(font
					(size 0.7874 0.5842)
					(thickness 0.1524)
				)
			)
		)
		(fp_text user "I"
			(at -2.253742 9.59993 90)
			(unlocked yes)
			(layer "F.Fab")
			(effects
				(font
					(size 0.7874 0.5842)
					(thickness 0.1524)
				)
			)
		)
		(fp_text user "J"
			(at -2.253742 10.80008 90)
			(unlocked yes)
			(layer "F.Fab")
			(effects
				(font
					(size 0.7874 0.5842)
					(thickness 0.1524)
				)
			)
		)
		(fp_text user "K"
			(at -2.253742 11.999976 90)
			(unlocked yes)
			(layer "F.Fab")
			(effects
				(font
					(size 0.7874 0.5842)
					(thickness 0.1524)
				)
			)
		)
		(fp_text user "L"
			(at -2.253742 13.200126 90)
			(unlocked yes)
			(layer "F.Fab")
			(effects
				(font
					(size 0.7874 0.5842)
					(thickness 0.1524)
				)
			)
		)
		(fp_text user "M"
			(at -2.253742 14.400022 90)
			(unlocked yes)
			(layer "F.Fab")
			(effects
				(font
					(size 0.7874 0.5842)
					(thickness 0.1524)
				)
			)
		)
		(fp_text user "N"
			(at -2.253742 15.599918 90)
			(unlocked yes)
			(layer "F.Fab")
			(effects
				(font
					(size 0.7874 0.5842)
					(thickness 0.1524)
				)
			)
		)
		(fp_text user "1"
			(at 0.111252 19.8628 90)
			(unlocked yes)
			(layer "F.Fab")
			(effects
				(font
					(size 0.7874 0.5842)
					(thickness 0.1524)
				)
			)
		)
		(fp_text user "2"
			(at 2.111248 19.8628 90)
			(unlocked yes)
			(layer "F.Fab")
			(effects
				(font
					(size 0.7874 0.5842)
					(thickness 0.1524)
				)
			)
		)
		(fp_text user "3"
			(at 4.111244 19.8628 90)
			(unlocked yes)
			(layer "F.Fab")
			(effects
				(font
					(size 0.7874 0.5842)
					(thickness 0.1524)
				)
			)
		)
		(fp_text user "4"
			(at 6.11124 19.8628 90)
			(unlocked yes)
			(layer "F.Fab")
			(effects
				(font
					(size 0.7874 0.5842)
					(thickness 0.1524)
				)
			)
		)
		(fp_text user "5"
			(at 8.111236 19.8628 90)
			(unlocked yes)
			(layer "F.Fab")
			(effects
				(font
					(size 0.7874 0.5842)
					(thickness 0.1524)
				)
			)
		)
		(fp_text user "6"
			(at 10.111232 19.8628 90)
			(unlocked yes)
			(layer "F.Fab")
			(effects
				(font
					(size 0.7874 0.5842)
					(thickness 0.1524)
				)
			)
		)
		(fp_text user "7"
			(at 12.111228 19.8628 90)
			(unlocked yes)
			(layer "F.Fab")
			(effects
				(font
					(size 0.7874 0.5842)
					(thickness 0.1524)
				)
			)
		)
		(fp_text user "8"
			(at 14.111224 19.8628 90)
			(unlocked yes)
			(layer "F.Fab")
			(effects
				(font
					(size 0.7874 0.5842)
					(thickness 0.1524)
				)
			)
		)
		(fp_text user "PRESS-FIT"
			(at 17.240758 16.521684 90)
			(unlocked yes)
			(layer "F.Fab")
			(effects
				(font
					(size 1.905 1.4224)
					(thickness 0.1524)
				)
				(justify left)
			)
		)
		(pad "A1" thru_hole rect
			(at 0 0 180)
			(size 0.766318 0.766318)
			(drill 0.359918)
			(layers "*.Cu" "*.Mask")
			(remove_unused_layers no)
			(net "GPU_FPGA_EROT_RECOV_BUF_N")
			(clearance 0.0508)
			(thermal_gap 0.0508)
			(padstack
				(mode front_inner_back)
				(layer "Inner"
					(shape circle)
					(size 0.766318 0.766318)
					(clearance 0.0508)
				)
				(layer "B.Cu"
					(shape rect)
					(size 0.766318 0.766318)
					(clearance 0.0508)
				)
			)
		)
		(pad "A2" thru_hole circle
			(at 1.999996 0.199898 180)
			(size 0.906272 0.906272)
			(drill 0.499872)
			(layers "*.Cu" "*.Mask")
			(remove_unused_layers no)
			(net "GND")
			(clearance 0.0508)
			(thermal_gap 0.0508)
		)
		(pad "A3" thru_hole circle
			(at 3.999992 0 180)
			(size 0.766318 0.766318)
			(drill 0.359918)
			(layers "*.Cu" "*.Mask")
			(remove_unused_layers no)
			(net "GPU_HMC_PRSNT_N")
			(clearance 0.0508)
			(thermal_gap 0.0508)
		)
		(pad "A4" thru_hole circle
			(at 5.999988 0.199898 180)
			(size 0.906272 0.906272)
			(drill 0.499872)
			(layers "*.Cu" "*.Mask")
			(remove_unused_layers no)
			(net "GND")
			(clearance 0.0508)
			(thermal_gap 0.0508)
		)
		(pad "A5" thru_hole circle
			(at 7.999984 0 180)
			(size 0.766318 0.766318)
			(drill 0.359918)
			(layers "*.Cu" "*.Mask")
			(remove_unused_layers no)
			(net "GPU_BASE_HMC_READY")
			(clearance 0.0508)
			(thermal_gap 0.0508)
		)
		(pad "A6" thru_hole circle
			(at 9.99998 0.199898 180)
			(size 0.906272 0.906272)
			(drill 0.499872)
			(layers "*.Cu" "*.Mask")
			(remove_unused_layers no)
			(net "GND")
			(clearance 0.0508)
			(thermal_gap 0.0508)
		)
		(pad "A7" thru_hole circle
			(at 11.999976 0 180)
			(size 0.766318 0.766318)
			(drill 0.359918)
			(layers "*.Cu" "*.Mask")
			(remove_unused_layers no)
			(net "GPU_BASE_STBY_EN_BUF")
			(clearance 0.0508)
			(thermal_gap 0.0508)
		)
		(pad "A8" thru_hole circle
			(at 13.999972 0.199898 180)
			(size 0.906272 0.906272)
			(drill 0.499872)
			(layers "*.Cu" "*.Mask")
			(remove_unused_layers no)
			(net "GND")
			(clearance 0.0508)
			(thermal_gap 0.0508)
		)
		(pad "B1" thru_hole circle
			(at 0 1.199896 180)
			(size 0.906272 0.906272)
			(drill 0.499872)
			(layers "*.Cu" "*.Mask")
			(remove_unused_layers no)
			(net "GND")
			(clearance 0.0508)
			(thermal_gap 0.0508)
		)
		(pad "B3" thru_hole circle
			(at 3.999992 1.199896 180)
			(size 0.906272 0.906272)
			(drill 0.499872)
			(layers "*.Cu" "*.Mask")
			(remove_unused_layers no)
			(net "GND")
			(clearance 0.0508)
			(thermal_gap 0.0508)
		)
		(pad "B5" thru_hole circle
			(at 7.999984 1.199896 180)
			(size 0.906272 0.906272)
			(drill 0.499872)
			(layers "*.Cu" "*.Mask")
			(remove_unused_layers no)
			(net "GND")
			(clearance 0.0508)
			(thermal_gap 0.0508)
		)
		(pad "B7" thru_hole circle
			(at 11.999976 1.199896 180)
			(size 0.906272 0.906272)
			(drill 0.499872)
			(layers "*.Cu" "*.Mask")
			(remove_unused_layers no)
			(net "GND")
			(clearance 0.0508)
			(thermal_gap 0.0508)
		)
		(pad "D2" thru_hole circle
			(at 1.999996 3.800094 180)
			(size 0.906272 0.906272)
			(drill 0.499872)
			(layers "*.Cu" "*.Mask")
			(remove_unused_layers no)
			(net "GND")
			(clearance 0.0508)
			(thermal_gap 0.0508)
		)
		(pad "D4" thru_hole circle
			(at 5.999988 3.800094 180)
			(size 0.906272 0.906272)
			(drill 0.499872)
			(layers "*.Cu" "*.Mask")
			(remove_unused_layers no)
			(net "GND")
			(clearance 0.0508)
			(thermal_gap 0.0508)
		)
		(pad "D6" thru_hole circle
			(at 9.99998 3.800094 180)
			(size 0.906272 0.906272)
			(drill 0.499872)
			(layers "*.Cu" "*.Mask")
			(remove_unused_layers no)
			(net "GND")
			(clearance 0.0508)
			(thermal_gap 0.0508)
		)
		(pad "D8" thru_hole circle
			(at 13.999972 3.800094 180)
			(size 0.906272 0.906272)
			(drill 0.499872)
			(layers "*.Cu" "*.Mask")
			(remove_unused_layers no)
			(net "GND")
			(clearance 0.0508)
			(thermal_gap 0.0508)
		)
		(pad "E1" thru_hole circle
			(at 0 4.800092 180)
			(size 0.906272 0.906272)
			(drill 0.499872)
			(layers "*.Cu" "*.Mask")
			(remove_unused_layers no)
			(net "GND")
			(clearance 0.0508)
			(thermal_gap 0.0508)
		)
		(pad "E3" thru_hole circle
			(at 3.999992 4.800092 180)
			(size 0.906272 0.906272)
			(drill 0.499872)
			(layers "*.Cu" "*.Mask")
			(remove_unused_layers no)
			(net "GND")
			(clearance 0.0508)
			(thermal_gap 0.0508)
		)
		(pad "E5" thru_hole circle
			(at 7.999984 4.800092 180)
			(size 0.906272 0.906272)
			(drill 0.499872)
			(layers "*.Cu" "*.Mask")
			(remove_unused_layers no)
			(net "GND")
			(clearance 0.0508)
			(thermal_gap 0.0508)
		)
		(pad "E7" thru_hole circle
			(at 11.999976 4.800092 180)
			(size 0.906272 0.906272)
			(drill 0.499872)
			(layers "*.Cu" "*.Mask")
			(remove_unused_layers no)
			(net "GND")
			(clearance 0.0508)
			(thermal_gap 0.0508)
		)
		(pad "G2" thru_hole circle
			(at 1.999996 7.400036 180)
			(size 0.906272 0.906272)
			(drill 0.499872)
			(layers "*.Cu" "*.Mask")
			(remove_unused_layers no)
			(net "GND")
			(clearance 0.0508)
			(thermal_gap 0.0508)
		)
		(pad "G4" thru_hole circle
			(at 5.999988 7.400036 180)
			(size 0.906272 0.906272)
			(drill 0.499872)
			(layers "*.Cu" "*.Mask")
			(remove_unused_layers no)
			(net "GND")
			(clearance 0.0508)
			(thermal_gap 0.0508)
		)
		(pad "G6" thru_hole circle
			(at 9.99998 7.400036 180)
			(size 0.906272 0.906272)
			(drill 0.499872)
			(layers "*.Cu" "*.Mask")
			(remove_unused_layers no)
			(net "GND")
			(clearance 0.0508)
			(thermal_gap 0.0508)
		)
		(pad "G8" thru_hole circle
			(at 13.999972 7.400036 180)
			(size 0.906272 0.906272)
			(drill 0.499872)
			(layers "*.Cu" "*.Mask")
			(remove_unused_layers no)
			(net "GND")
			(clearance 0.0508)
			(thermal_gap 0.0508)
		)
		(pad "H1" thru_hole circle
			(at 0 8.400034 180)
			(size 0.906272 0.906272)
			(drill 0.499872)
			(layers "*.Cu" "*.Mask")
			(remove_unused_layers no)
			(net "GND")
			(clearance 0.0508)
			(thermal_gap 0.0508)
		)
		(pad "H3" thru_hole circle
			(at 3.999992 8.400034 180)
			(size 0.906272 0.906272)
			(drill 0.499872)
			(layers "*.Cu" "*.Mask")
			(remove_unused_layers no)
			(net "GND")
			(clearance 0.0508)
			(thermal_gap 0.0508)
		)
		(pad "H5" thru_hole circle
			(at 7.999984 8.400034 180)
			(size 0.906272 0.906272)
			(drill 0.499872)
			(layers "*.Cu" "*.Mask")
			(remove_unused_layers no)
			(net "GND")
			(clearance 0.0508)
			(thermal_gap 0.0508)
		)
		(pad "H7" thru_hole circle
			(at 11.999976 8.400034 180)
			(size 0.906272 0.906272)
			(drill 0.499872)
			(layers "*.Cu" "*.Mask")
			(remove_unused_layers no)
			(net "GND")
			(clearance 0.0508)
			(thermal_gap 0.0508)
		)
		(pad "J2" thru_hole circle
			(at 1.999996 10.999978 180)
			(size 0.906272 0.906272)
			(drill 0.499872)
			(layers "*.Cu" "*.Mask")
			(remove_unused_layers no)
			(net "GND")
			(clearance 0.0508)
			(thermal_gap 0.0508)
		)
		(pad "J4" thru_hole circle
			(at 5.999988 10.999978 180)
			(size 0.906272 0.906272)
			(drill 0.499872)
			(layers "*.Cu" "*.Mask")
			(remove_unused_layers no)
			(net "GND")
			(clearance 0.0508)
			(thermal_gap 0.0508)
		)
		(pad "J6" thru_hole circle
			(at 9.99998 10.999978 180)
			(size 0.906272 0.906272)
			(drill 0.499872)
			(layers "*.Cu" "*.Mask")
			(remove_unused_layers no)
			(net "GND")
			(clearance 0.0508)
			(thermal_gap 0.0508)
		)
		(pad "J8" thru_hole circle
			(at 13.999972 10.999978 180)
			(size 0.906272 0.906272)
			(drill 0.499872)
			(layers "*.Cu" "*.Mask")
			(remove_unused_layers no)
			(net "GND")
			(clearance 0.0508)
			(thermal_gap 0.0508)
		)
		(pad "K1" thru_hole circle
			(at 0 11.999976 180)
			(size 0.906272 0.906272)
			(drill 0.499872)
			(layers "*.Cu" "*.Mask")
			(remove_unused_layers no)
			(net "GND")
			(clearance 0.0508)
			(thermal_gap 0.0508)
		)
		(pad "K3" thru_hole circle
			(at 3.999992 11.999976 180)
			(size 0.906272 0.906272)
			(drill 0.499872)
			(layers "*.Cu" "*.Mask")
			(remove_unused_layers no)
			(net "GND")
			(clearance 0.0508)
			(thermal_gap 0.0508)
		)
		(pad "K5" thru_hole circle
			(at 7.999984 11.999976 180)
			(size 0.906272 0.906272)
			(drill 0.499872)
			(layers "*.Cu" "*.Mask")
			(remove_unused_layers no)
			(net "GND")
			(clearance 0.0508)
			(thermal_gap 0.0508)
		)
		(pad "K7" thru_hole circle
			(at 11.999976 11.999976 180)
			(size 0.906272 0.906272)
			(drill 0.499872)
			(layers "*.Cu" "*.Mask")
			(remove_unused_layers no)
			(net "GND")
			(clearance 0.0508)
			(thermal_gap 0.0508)
		)
		(pad "M2" thru_hole circle
			(at 1.999996 14.59992 180)
			(size 0.906272 0.906272)
			(drill 0.499872)
			(layers "*.Cu" "*.Mask")
			(remove_unused_layers no)
			(net "GND")
			(clearance 0.0508)
			(thermal_gap 0.0508)
		)
		(pad "M4" thru_hole circle
			(at 5.999988 14.59992 180)
			(size 0.906272 0.906272)
			(drill 0.499872)
			(layers "*.Cu" "*.Mask")
			(remove_unused_layers no)
			(net "GND")
			(clearance 0.0508)
			(thermal_gap 0.0508)
		)
		(pad "M6" thru_hole circle
			(at 9.99998 14.59992 180)
			(size 0.906272 0.906272)
			(drill 0.499872)
			(layers "*.Cu" "*.Mask")
			(remove_unused_layers no)
			(net "GND")
			(clearance 0.0508)
			(thermal_gap 0.0508)
		)
		(pad "M8" thru_hole circle
			(at 13.999972 14.59992 180)
			(size 0.906272 0.906272)
			(drill 0.499872)
			(layers "*.Cu" "*.Mask")
			(remove_unused_layers no)
			(net "GND")
			(clearance 0.0508)
			(thermal_gap 0.0508)
		)
		(pad "N1" thru_hole circle
			(at 0 15.599918 180)
			(size 0.906272 0.906272)
			(drill 0.499872)
			(layers "*.Cu" "*.Mask")
			(remove_unused_layers no)
			(net "GND")
			(clearance 0.0508)
			(thermal_gap 0.0508)
		)
		(pad "N2" thru_hole circle
			(at 1.999996 15.80007 180)
			(size 0.766318 0.766318)
			(drill 0.359918)
			(layers "*.Cu" "*.Mask")
			(remove_unused_layers no)
			(net "GPU_FPGA_BOOT_EN_BUF")
			(clearance 0.0508)
			(thermal_gap 0.0508)
		)
		(pad "N3" thru_hole circle
			(at 3.999992 15.599918 180)
			(size 0.906272 0.906272)
			(drill 0.499872)
			(layers "*.Cu" "*.Mask")
			(remove_unused_layers no)
			(net "GND")
			(clearance 0.0508)
			(thermal_gap 0.0508)
		)
		(pad "N4" thru_hole circle
			(at 5.999988 15.80007 180)
			(size 0.766318 0.766318)
			(drill 0.359918)
			(layers "*.Cu" "*.Mask")
			(remove_unused_layers no)
			(net "FM_SMB_1_ALERT_GPU_N")
			(clearance 0.0508)
			(thermal_gap 0.0508)
		)
		(pad "N5" thru_hole circle
			(at 7.999984 15.599918 180)
			(size 0.906272 0.906272)
			(drill 0.499872)
			(layers "*.Cu" "*.Mask")
			(remove_unused_layers no)
			(net "GND")
			(clearance 0.0508)
			(thermal_gap 0.0508)
		)
		(pad "N6" thru_hole circle
			(at 9.99998 15.80007 180)
			(size 0.766318 0.766318)
			(drill 0.359918)
			(layers "*.Cu" "*.Mask")
			(remove_unused_layers no)
			(net "FM_SMB_2_ALERT_GPU_N")
			(clearance 0.0508)
			(thermal_gap 0.0508)
		)
		(pad "N7" thru_hole circle
			(at 11.999976 15.599918 180)
			(size 0.906272 0.906272)
			(drill 0.499872)
			(layers "*.Cu" "*.Mask")
			(remove_unused_layers no)
			(net "GND")
			(clearance 0.0508)
			(thermal_gap 0.0508)
		)
		(pad "N8" thru_hole circle
			(at 13.999972 15.80007 180)
			(size 0.766318 0.766318)
			(drill 0.359918)
			(layers "*.Cu" "*.Mask")
			(remove_unused_layers no)
			(net "GPU_FPGA_EROT_RST_BUF_N")
			(clearance 0.0508)
			(thermal_gap 0.0508)
		)
	)
	(footprint ""
		(layer "F.Cu")
		(at 252.222 -37.667946 180)
		(property "Reference" "R3978"
			(at 0 0 180)
			(layer "F.SilkS")
			(hide yes)
			(effects
				(font
					(size 1.27 1.27)
				)
			)
		)
		(property "Value" ""
			(at 0 0 180)
			(layer "F.Fab")
			(effects
				(font
					(size 1.27 1.27)
				)
			)
		)
		(duplicate_pad_numbers_are_jumpers no)
		(fp_line
			(start 0.7874 0.4064)
			(end -0.7874 0.4064)
			(stroke
				(width 0.1524)
				(type default)
			)
			(layer "F.SilkS")
		)
		(fp_line
			(start 0.7874 -0.4064)
			(end 0.7874 0.4064)
			(stroke
				(width 0.1524)
				(type default)
			)
			(layer "F.SilkS")
		)
		(fp_line
			(start -0.7874 0.4064)
			(end -0.7874 -0.4064)
			(stroke
				(width 0.1524)
				(type default)
			)
			(layer "F.SilkS")
		)
		(fp_line
			(start -0.7874 -0.4064)
			(end 0.7874 -0.4064)
			(stroke
				(width 0.1524)
				(type default)
			)
			(layer "F.SilkS")
		)
		(fp_line
			(start 0.67945 0.3048)
			(end 0.120396 0.3048)
			(stroke
				(width 0.1)
				(type default)
			)
			(layer "F.Fab")
		)
		(fp_line
			(start 0.67945 -0.3048)
			(end 0.67945 0.3048)
			(stroke
				(width 0.1)
				(type default)
			)
			(layer "F.Fab")
		)
		(fp_line
			(start 0.12065 -0.2794)
			(end 0.12065 -0.3048)
			(stroke
				(width 0.1)
				(type default)
			)
			(layer "F.Fab")
		)
		(fp_line
			(start 0.12065 -0.3048)
			(end 0.67945 -0.3048)
			(stroke
				(width 0.1)
				(type default)
			)
			(layer "F.Fab")
		)
		(fp_line
			(start 0.120396 0.3048)
			(end 0.120396 0.2794)
			(stroke
				(width 0.1)
				(type default)
			)
			(layer "F.Fab")
		)
		(fp_line
			(start 0.120396 0.2794)
			(end -0.12065 0.2794)
			(stroke
				(width 0.1)
				(type default)
			)
			(layer "F.Fab")
		)
		(fp_line
			(start -0.12065 0.3048)
			(end -0.67945 0.3048)
			(stroke
				(width 0.1)
				(type default)
			)
			(layer "F.Fab")
		)
		(fp_line
			(start -0.12065 0.2794)
			(end -0.12065 0.3048)
			(stroke
				(width 0.1)
				(type default)
			)
			(layer "F.Fab")
		)
		(fp_line
			(start -0.12065 -0.2794)
			(end 0.12065 -0.2794)
			(stroke
				(width 0.1)
				(type default)
			)
			(layer "F.Fab")
		)
		(fp_line
			(start -0.12065 -0.305054)
			(end -0.12065 -0.2794)
			(stroke
				(width 0.1)
				(type default)
			)
			(layer "F.Fab")
		)
		(fp_line
			(start -0.67945 0.3048)
			(end -0.67945 -0.305054)
			(stroke
				(width 0.1)
				(type default)
			)
			(layer "F.Fab")
		)
		(fp_line
			(start -0.67945 -0.305054)
			(end -0.12065 -0.305054)
			(stroke
				(width 0.1)
				(type default)
			)
			(layer "F.Fab")
		)
		(pad "1" smd circle
			(at -0.40005 0 180)
			(size 0 0)
			(layers "F.Cu" "F.Mask" "F.Paste")
			(net "P3V3_AUX")
		)
		(pad "2" smd circle
			(at 0.40005 0 180)
			(size 0 0)
			(layers "F.Cu" "F.Mask" "F.Paste")
			(net "HP_LVC3_E1S_0_HSC_PWRGD")
		)
	)
	(footprint ""
		(layer "F.Cu")
		(at 86.94039 -53.875686 90)
		(property "Reference" "PC2149"
			(at 0 0 90)
			(layer "F.SilkS")
			(hide yes)
			(effects
				(font
					(size 1.27 1.27)
				)
			)
		)
		(property "Value" ""
			(at 0 0 90)
			(layer "F.Fab")
			(effects
				(font
					(size 1.27 1.27)
				)
			)
		)
		(duplicate_pad_numbers_are_jumpers no)
		(fp_line
			(start 0.7874 -0.4064)
			(end 0.7874 0.4064)
			(stroke
				(width 0.1524)
				(type default)
			)
			(layer "F.SilkS")
		)
		(fp_line
			(start -0.7874 -0.4064)
			(end 0.7874 -0.4064)
			(stroke
				(width 0.1524)
				(type default)
			)
			(layer "F.SilkS")
		)
		(fp_line
			(start 0.7874 0.4064)
			(end -0.7874 0.4064)
			(stroke
				(width 0.1524)
				(type default)
			)
			(layer "F.SilkS")
		)
		(fp_line
			(start -0.7874 0.4064)
			(end -0.7874 -0.4064)
			(stroke
				(width 0.1524)
				(type default)
			)
			(layer "F.SilkS")
		)
		(fp_line
			(start -0.12065 -0.305054)
			(end -0.12065 -0.2794)
			(stroke
				(width 0.1)
				(type default)
			)
			(layer "F.Fab")
		)
		(fp_line
			(start -0.67945 -0.305054)
			(end -0.12065 -0.305054)
			(stroke
				(width 0.1)
				(type default)
			)
			(layer "F.Fab")
		)
		(fp_line
			(start 0.67945 -0.3048)
			(end 0.67945 0.3048)
			(stroke
				(width 0.1)
				(type default)
			)
			(layer "F.Fab")
		)
		(fp_line
			(start 0.12065 -0.3048)
			(end 0.67945 -0.3048)
			(stroke
				(width 0.1)
				(type default)
			)
			(layer "F.Fab")
		)
		(fp_line
			(start 0.12065 -0.2794)
			(end 0.12065 -0.3048)
			(stroke
				(width 0.1)
				(type default)
			)
			(layer "F.Fab")
		)
		(fp_line
			(start -0.12065 -0.2794)
			(end 0.12065 -0.2794)
			(stroke
				(width 0.1)
				(type default)
			)
			(layer "F.Fab")
		)
		(fp_line
			(start 0.120396 0.2794)
			(end -0.12065 0.2794)
			(stroke
				(width 0.1)
				(type default)
			)
			(layer "F.Fab")
		)
		(fp_line
			(start -0.12065 0.2794)
			(end -0.12065 0.3048)
			(stroke
				(width 0.1)
				(type default)
			)
			(layer "F.Fab")
		)
		(fp_line
			(start 0.67945 0.3048)
			(end 0.120396 0.3048)
			(stroke
				(width 0.1)
				(type default)
			)
			(layer "F.Fab")
		)
		(fp_line
			(start 0.120396 0.3048)
			(end 0.120396 0.2794)
			(stroke
				(width 0.1)
				(type default)
			)
			(layer "F.Fab")
		)
		(fp_line
			(start -0.12065 0.3048)
			(end -0.67945 0.3048)
			(stroke
				(width 0.1)
				(type default)
			)
			(layer "F.Fab")
		)
		(fp_line
			(start -0.67945 0.3048)
			(end -0.67945 -0.305054)
			(stroke
				(width 0.1)
				(type default)
			)
			(layer "F.Fab")
		)
		(pad "1" smd circle
			(at -0.40005 0 90)
			(size 0 0)
			(layers "F.Cu" "F.Mask" "F.Paste")
			(net "P3V3_OCP_V3_2_R")
		)
		(pad "2" smd circle
			(at 0.40005 0 90)
			(size 0 0)
			(layers "F.Cu" "F.Mask" "F.Paste")
			(net "P3V3_OCP_GATE_2")
		)
	)
	(footprint ""
		(layer "F.Cu")
		(at 198.41464 -69.804788 180)
		(property "Reference" "R3946"
			(at 0 0 180)
			(layer "F.SilkS")
			(hide yes)
			(effects
				(font
					(size 1.27 1.27)
				)
			)
		)
		(property "Value" ""
			(at 0 0 180)
			(layer "F.Fab")
			(effects
				(font
					(size 1.27 1.27)
				)
			)
		)
		(duplicate_pad_numbers_are_jumpers no)
		(fp_line
			(start 0.7874 0.4064)
			(end -0.7874 0.4064)
			(stroke
				(width 0.1524)
				(type default)
			)
			(layer "F.SilkS")
		)
		(fp_line
			(start 0.7874 -0.4064)
			(end 0.7874 0.4064)
			(stroke
				(width 0.1524)
				(type default)
			)
			(layer "F.SilkS")
		)
		(fp_line
			(start -0.7874 0.4064)
			(end -0.7874 -0.4064)
			(stroke
				(width 0.1524)
				(type default)
			)
			(layer "F.SilkS")
		)
		(fp_line
			(start -0.7874 -0.4064)
			(end 0.7874 -0.4064)
			(stroke
				(width 0.1524)
				(type default)
			)
			(layer "F.SilkS")
		)
		(fp_line
			(start 0.67945 0.3048)
			(end 0.120396 0.3048)
			(stroke
				(width 0.1)
				(type default)
			)
			(layer "F.Fab")
		)
		(fp_line
			(start 0.67945 -0.3048)
			(end 0.67945 0.3048)
			(stroke
				(width 0.1)
				(type default)
			)
			(layer "F.Fab")
		)
		(fp_line
			(start 0.12065 -0.2794)
			(end 0.12065 -0.3048)
			(stroke
				(width 0.1)
				(type default)
			)
			(layer "F.Fab")
		)
		(fp_line
			(start 0.12065 -0.3048)
			(end 0.67945 -0.3048)
			(stroke
				(width 0.1)
				(type default)
			)
			(layer "F.Fab")
		)
		(fp_line
			(start 0.120396 0.3048)
			(end 0.120396 0.2794)
			(stroke
				(width 0.1)
				(type default)
			)
			(layer "F.Fab")
		)
		(fp_line
			(start 0.120396 0.2794)
			(end -0.12065 0.2794)
			(stroke
				(width 0.1)
				(type default)
			)
			(layer "F.Fab")
		)
		(fp_line
			(start -0.12065 0.3048)
			(end -0.67945 0.3048)
			(stroke
				(width 0.1)
				(type default)
			)
			(layer "F.Fab")
		)
		(fp_line
			(start -0.12065 0.2794)
			(end -0.12065 0.3048)
			(stroke
				(width 0.1)
				(type default)
			)
			(layer "F.Fab")
		)
		(fp_line
			(start -0.12065 -0.2794)
			(end 0.12065 -0.2794)
			(stroke
				(width 0.1)
				(type default)
			)
			(layer "F.Fab")
		)
		(fp_line
			(start -0.12065 -0.305054)
			(end -0.12065 -0.2794)
			(stroke
				(width 0.1)
				(type default)
			)
			(layer "F.Fab")
		)
		(fp_line
			(start -0.67945 0.3048)
			(end -0.67945 -0.305054)
			(stroke
				(width 0.1)
				(type default)
			)
			(layer "F.Fab")
		)
		(fp_line
			(start -0.67945 -0.305054)
			(end -0.12065 -0.305054)
			(stroke
				(width 0.1)
				(type default)
			)
			(layer "F.Fab")
		)
		(pad "1" smd circle
			(at -0.40005 0 180)
			(size 0 0)
			(layers "F.Cu" "F.Mask" "F.Paste")
			(net "E1S_0_EN")
		)
		(pad "2" smd circle
			(at 0.40005 0 180)
			(size 0 0)
			(layers "F.Cu" "F.Mask" "F.Paste")
			(net "P3V3_E1S_EN_0_R2")
		)
	)
	(footprint ""
		(layer "F.Cu")
		(at 51.251358 -344.77325 -90)
		(property "Reference" "PL19"
			(at -2.028698 4.869688 90)
			(unlocked yes)
			(layer "F.SilkS")
			(effects
				(font
					(size 0.7874 0.5842)
					(thickness 0.1524)
				)
				(justify left)
			)
		)
		(property "Value" ""
			(at 0 0 270)
			(layer "F.Fab")
			(effects
				(font
					(size 1.27 1.27)
				)
			)
		)
		(duplicate_pad_numbers_are_jumpers no)
		(fp_line
			(start -4.99999 3.750056)
			(end -4.99999 2.2479)
			(stroke
				(width 0.1524)
				(type default)
			)
			(layer "F.SilkS")
		)
		(fp_line
			(start 0 3.750056)
			(end -4.99999 3.750056)
			(stroke
				(width 0.1524)
				(type default)
			)
			(layer "F.SilkS")
		)
		(fp_line
			(start 4.99999 3.750056)
			(end 0 3.750056)
			(stroke
				(width 0.1524)
				(type default)
			)
			(layer "F.SilkS")
		)
		(fp_line
			(start 4.99999 2.2352)
			(end 4.99999 3.750056)
			(stroke
				(width 0.1524)
				(type default)
			)
			(layer "F.SilkS")
		)
		(fp_line
			(start -4.99999 -2.2479)
			(end -4.99999 -3.750056)
			(stroke
				(width 0.1524)
				(type default)
			)
			(layer "F.SilkS")
		)
		(fp_line
			(start -4.99999 -3.750056)
			(end 4.99999 -3.750056)
			(stroke
				(width 0.1524)
				(type default)
			)
			(layer "F.SilkS")
		)
		(fp_line
			(start 4.99999 -3.750056)
			(end 4.99999 -2.2479)
			(stroke
				(width 0.1524)
				(type default)
			)
			(layer "F.SilkS")
		)
		(fp_line
			(start -4.99999 3.750056)
			(end -4.99999 -3.750056)
			(stroke
				(width 0.1)
				(type default)
			)
			(layer "F.Fab")
		)
		(fp_line
			(start 0 3.750056)
			(end -4.99999 3.750056)
			(stroke
				(width 0.1)
				(type default)
			)
			(layer "F.Fab")
		)
		(fp_line
			(start 4.99999 3.750056)
			(end 0 3.750056)
			(stroke
				(width 0.1)
				(type default)
			)
			(layer "F.Fab")
		)
		(fp_line
			(start -4.99999 -3.750056)
			(end 4.99999 -3.750056)
			(stroke
				(width 0.1)
				(type default)
			)
			(layer "F.Fab")
		)
		(fp_line
			(start 4.99999 -3.750056)
			(end 4.99999 3.750056)
			(stroke
				(width 0.1)
				(type default)
			)
			(layer "F.Fab")
		)
		(pad "1" smd rect
			(at -3.299968 0 270)
			(size 3.302 4.2164)
			(layers "F.Cu" "F.Mask" "F.Paste")
			(net "SW_PVCCFA_EHV_FIVRA_CPU1_SW2")
		)
		(pad "2" smd rect
			(at 3.299968 0 270)
			(size 3.302 4.2164)
			(layers "F.Cu" "F.Mask" "F.Paste")
			(net "PVCCFA_EHV_FIVRA_CPU1")
		)
	)
	(footprint ""
		(layer "F.Cu")
		(at 412.367984 -16.088614 90)
		(property "Reference" "C855"
			(at 0 0 90)
			(layer "F.SilkS")
			(hide yes)
			(effects
				(font
					(size 1.27 1.27)
				)
			)
		)
		(property "Value" ""
			(at 0 0 90)
			(layer "F.Fab")
			(effects
				(font
					(size 1.27 1.27)
				)
			)
		)
		(duplicate_pad_numbers_are_jumpers no)
		(fp_line
			(start 0.299974 -0.150114)
			(end 0.299974 0.150114)
			(stroke
				(width 0.1)
				(type default)
			)
			(layer "F.Fab")
		)
		(fp_line
			(start -0.299974 -0.150114)
			(end 0.299974 -0.150114)
			(stroke
				(width 0.1)
				(type default)
			)
			(layer "F.Fab")
		)
		(fp_line
			(start 0.299974 0.150114)
			(end -0.299974 0.150114)
			(stroke
				(width 0.1)
				(type default)
			)
			(layer "F.Fab")
		)
		(fp_line
			(start -0.299974 0.150114)
			(end -0.299974 -0.150114)
			(stroke
				(width 0.1)
				(type default)
			)
			(layer "F.Fab")
		)
		(pad "1" smd rect
			(at -0.2667 0 90)
			(size 0.3048 0.381)
			(layers "F.Cu" "F.Mask" "F.Paste")
			(net "P5E_CPU0_PE1_TX_C_DP<7>")
		)
		(pad "2" smd rect
			(at 0.2667 0 90)
			(size 0.3048 0.381)
			(layers "F.Cu" "F.Mask" "F.Paste")
			(net "P5E_CPU0_PE1_TX_DP<7>")
		)
	)
	(footprint ""
		(layer "F.Cu")
		(at 111.332772 -126.678182)
		(property "Reference" "R3535"
			(at 0 0 0)
			(layer "F.SilkS")
			(hide yes)
			(effects
				(font
					(size 1.27 1.27)
				)
			)
		)
		(property "Value" ""
			(at 0 0 0)
			(layer "F.Fab")
			(effects
				(font
					(size 1.27 1.27)
				)
			)
		)
		(duplicate_pad_numbers_are_jumpers no)
		(fp_line
			(start -0.7874 -0.4064)
			(end 0.7874 -0.4064)
			(stroke
				(width 0.1524)
				(type default)
			)
			(layer "F.SilkS")
		)
		(fp_line
			(start -0.7874 0.4064)
			(end -0.7874 -0.4064)
			(stroke
				(width 0.1524)
				(type default)
			)
			(layer "F.SilkS")
		)
		(fp_line
			(start 0.7874 -0.4064)
			(end 0.7874 0.4064)
			(stroke
				(width 0.1524)
				(type default)
			)
			(layer "F.SilkS")
		)
		(fp_line
			(start 0.7874 0.4064)
			(end -0.7874 0.4064)
			(stroke
				(width 0.1524)
				(type default)
			)
			(layer "F.SilkS")
		)
		(fp_line
			(start -0.67945 -0.305054)
			(end -0.12065 -0.305054)
			(stroke
				(width 0.1)
				(type default)
			)
			(layer "F.Fab")
		)
		(fp_line
			(start -0.67945 0.3048)
			(end -0.67945 -0.305054)
			(stroke
				(width 0.1)
				(type default)
			)
			(layer "F.Fab")
		)
		(fp_line
			(start -0.12065 -0.305054)
			(end -0.12065 -0.2794)
			(stroke
				(width 0.1)
				(type default)
			)
			(layer "F.Fab")
		)
		(fp_line
			(start -0.12065 -0.2794)
			(end 0.12065 -0.2794)
			(stroke
				(width 0.1)
				(type default)
			)
			(layer "F.Fab")
		)
		(fp_line
			(start -0.12065 0.2794)
			(end -0.12065 0.3048)
			(stroke
				(width 0.1)
				(type default)
			)
			(layer "F.Fab")
		)
		(fp_line
			(start -0.12065 0.3048)
			(end -0.67945 0.3048)
			(stroke
				(width 0.1)
				(type default)
			)
			(layer "F.Fab")
		)
		(fp_line
			(start 0.120396 0.2794)
			(end -0.12065 0.2794)
			(stroke
				(width 0.1)
				(type default)
			)
			(layer "F.Fab")
		)
		(fp_line
			(start 0.120396 0.3048)
			(end 0.120396 0.2794)
			(stroke
				(width 0.1)
				(type default)
			)
			(layer "F.Fab")
		)
		(fp_line
			(start 0.12065 -0.3048)
			(end 0.67945 -0.3048)
			(stroke
				(width 0.1)
				(type default)
			)
			(layer "F.Fab")
		)
		(fp_line
			(start 0.12065 -0.2794)
			(end 0.12065 -0.3048)
			(stroke
				(width 0.1)
				(type default)
			)
			(layer "F.Fab")
		)
		(fp_line
			(start 0.67945 -0.3048)
			(end 0.67945 0.3048)
			(stroke
				(width 0.1)
				(type default)
			)
			(layer "F.Fab")
		)
		(fp_line
			(start 0.67945 0.3048)
			(end 0.120396 0.3048)
			(stroke
				(width 0.1)
				(type default)
			)
			(layer "F.Fab")
		)
		(pad "1" smd circle
			(at -0.40005 0)
			(size 0 0)
			(layers "F.Cu" "F.Mask" "F.Paste")
			(net "P3V3_AUX")
		)
		(pad "2" smd circle
			(at 0.40005 0)
			(size 0 0)
			(layers "F.Cu" "F.Mask" "F.Paste")
			(net "SMB_SENSOR_E1S_3V3AUX_SCL")
		)
	)
	(footprint ""
		(layer "F.Cu")
		(at 406.124664 -364.151926)
		(property "Reference" "R515"
			(at 0 0 0)
			(layer "F.SilkS")
			(hide yes)
			(effects
				(font
					(size 1.27 1.27)
				)
			)
		)
		(property "Value" ""
			(at 0 0 0)
			(layer "F.Fab")
			(effects
				(font
					(size 1.27 1.27)
				)
			)
		)
		(duplicate_pad_numbers_are_jumpers no)
		(fp_line
			(start -0.7874 -0.4064)
			(end 0.7874 -0.4064)
			(stroke
				(width 0.1524)
				(type default)
			)
			(layer "F.SilkS")
		)
		(fp_line
			(start -0.7874 0.4064)
			(end -0.7874 -0.4064)
			(stroke
				(width 0.1524)
				(type default)
			)
			(layer "F.SilkS")
		)
		(fp_line
			(start 0.7874 -0.4064)
			(end 0.7874 0.4064)
			(stroke
				(width 0.1524)
				(type default)
			)
			(layer "F.SilkS")
		)
		(fp_line
			(start 0.7874 0.4064)
			(end -0.7874 0.4064)
			(stroke
				(width 0.1524)
				(type default)
			)
			(layer "F.SilkS")
		)
		(fp_line
			(start -0.67945 -0.305054)
			(end -0.12065 -0.305054)
			(stroke
				(width 0.1)
				(type default)
			)
			(layer "F.Fab")
		)
		(fp_line
			(start -0.67945 0.3048)
			(end -0.67945 -0.305054)
			(stroke
				(width 0.1)
				(type default)
			)
			(layer "F.Fab")
		)
		(fp_line
			(start -0.12065 -0.305054)
			(end -0.12065 -0.2794)
			(stroke
				(width 0.1)
				(type default)
			)
			(layer "F.Fab")
		)
		(fp_line
			(start -0.12065 -0.2794)
			(end 0.12065 -0.2794)
			(stroke
				(width 0.1)
				(type default)
			)
			(layer "F.Fab")
		)
		(fp_line
			(start -0.12065 0.2794)
			(end -0.12065 0.3048)
			(stroke
				(width 0.1)
				(type default)
			)
			(layer "F.Fab")
		)
		(fp_line
			(start -0.12065 0.3048)
			(end -0.67945 0.3048)
			(stroke
				(width 0.1)
				(type default)
			)
			(layer "F.Fab")
		)
		(fp_line
			(start 0.120396 0.2794)
			(end -0.12065 0.2794)
			(stroke
				(width 0.1)
				(type default)
			)
			(layer "F.Fab")
		)
		(fp_line
			(start 0.120396 0.3048)
			(end 0.120396 0.2794)
			(stroke
				(width 0.1)
				(type default)
			)
			(layer "F.Fab")
		)
		(fp_line
			(start 0.12065 -0.3048)
			(end 0.67945 -0.3048)
			(stroke
				(width 0.1)
				(type default)
			)
			(layer "F.Fab")
		)
		(fp_line
			(start 0.12065 -0.2794)
			(end 0.12065 -0.3048)
			(stroke
				(width 0.1)
				(type default)
			)
			(layer "F.Fab")
		)
		(fp_line
			(start 0.67945 -0.3048)
			(end 0.67945 0.3048)
			(stroke
				(width 0.1)
				(type default)
			)
			(layer "F.Fab")
		)
		(fp_line
			(start 0.67945 0.3048)
			(end 0.120396 0.3048)
			(stroke
				(width 0.1)
				(type default)
			)
			(layer "F.Fab")
		)
		(pad "1" smd circle
			(at -0.40005 0)
			(size 0 0)
			(layers "F.Cu" "F.Mask" "F.Paste")
			(net "PD_PIROM_CPU0_ADDR0")
		)
		(pad "2" smd circle
			(at 0.40005 0)
			(size 0 0)
			(layers "F.Cu" "F.Mask" "F.Paste")
			(net "GND")
		)
	)
	(footprint ""
		(layer "F.Cu")
		(at 200.035414 -78.42377 180)
		(property "Reference" "R1293"
			(at 0 0 180)
			(layer "F.SilkS")
			(hide yes)
			(effects
				(font
					(size 1.27 1.27)
				)
			)
		)
		(property "Value" ""
			(at 0 0 180)
			(layer "F.Fab")
			(effects
				(font
					(size 1.27 1.27)
				)
			)
		)
		(duplicate_pad_numbers_are_jumpers no)
		(fp_line
			(start 0.7874 0.4064)
			(end -0.7874 0.4064)
			(stroke
				(width 0.1524)
				(type default)
			)
			(layer "F.SilkS")
		)
		(fp_line
			(start 0.7874 -0.4064)
			(end 0.7874 0.4064)
			(stroke
				(width 0.1524)
				(type default)
			)
			(layer "F.SilkS")
		)
		(fp_line
			(start -0.7874 0.4064)
			(end -0.7874 -0.4064)
			(stroke
				(width 0.1524)
				(type default)
			)
			(layer "F.SilkS")
		)
		(fp_line
			(start -0.7874 -0.4064)
			(end 0.7874 -0.4064)
			(stroke
				(width 0.1524)
				(type default)
			)
			(layer "F.SilkS")
		)
		(fp_line
			(start 0.67945 0.3048)
			(end 0.120396 0.3048)
			(stroke
				(width 0.1)
				(type default)
			)
			(layer "F.Fab")
		)
		(fp_line
			(start 0.67945 -0.3048)
			(end 0.67945 0.3048)
			(stroke
				(width 0.1)
				(type default)
			)
			(layer "F.Fab")
		)
		(fp_line
			(start 0.12065 -0.2794)
			(end 0.12065 -0.3048)
			(stroke
				(width 0.1)
				(type default)
			)
			(layer "F.Fab")
		)
		(fp_line
			(start 0.12065 -0.3048)
			(end 0.67945 -0.3048)
			(stroke
				(width 0.1)
				(type default)
			)
			(layer "F.Fab")
		)
		(fp_line
			(start 0.120396 0.3048)
			(end 0.120396 0.2794)
			(stroke
				(width 0.1)
				(type default)
			)
			(layer "F.Fab")
		)
		(fp_line
			(start 0.120396 0.2794)
			(end -0.12065 0.2794)
			(stroke
				(width 0.1)
				(type default)
			)
			(layer "F.Fab")
		)
		(fp_line
			(start -0.12065 0.3048)
			(end -0.67945 0.3048)
			(stroke
				(width 0.1)
				(type default)
			)
			(layer "F.Fab")
		)
		(fp_line
			(start -0.12065 0.2794)
			(end -0.12065 0.3048)
			(stroke
				(width 0.1)
				(type default)
			)
			(layer "F.Fab")
		)
		(fp_line
			(start -0.12065 -0.2794)
			(end 0.12065 -0.2794)
			(stroke
				(width 0.1)
				(type default)
			)
			(layer "F.Fab")
		)
		(fp_line
			(start -0.12065 -0.305054)
			(end -0.12065 -0.2794)
			(stroke
				(width 0.1)
				(type default)
			)
			(layer "F.Fab")
		)
		(fp_line
			(start -0.67945 0.3048)
			(end -0.67945 -0.305054)
			(stroke
				(width 0.1)
				(type default)
			)
			(layer "F.Fab")
		)
		(fp_line
			(start -0.67945 -0.305054)
			(end -0.12065 -0.305054)
			(stroke
				(width 0.1)
				(type default)
			)
			(layer "F.Fab")
		)
		(pad "1" smd circle
			(at -0.40005 0 180)
			(size 0 0)
			(layers "F.Cu" "F.Mask" "F.Paste")
			(net "NCSI_BMC_RXD1_R")
		)
		(pad "2" smd circle
			(at 0.40005 0 180)
			(size 0 0)
			(layers "F.Cu" "F.Mask" "F.Paste")
			(net "RMII_OCP_BMC_RXD_1")
		)
	)
	(footprint ""
		(layer "F.Cu")
		(at 20.785582 -423.629836 -90)
		(property "Reference" "R3516"
			(at 0 0 270)
			(layer "F.SilkS")
			(hide yes)
			(effects
				(font
					(size 1.27 1.27)
				)
			)
		)
		(property "Value" ""
			(at 0 0 270)
			(layer "F.Fab")
			(effects
				(font
					(size 1.27 1.27)
				)
			)
		)
		(duplicate_pad_numbers_are_jumpers no)
		(fp_line
			(start -0.7874 0.4064)
			(end -0.7874 -0.4064)
			(stroke
				(width 0.1524)
				(type default)
			)
			(layer "F.SilkS")
		)
		(fp_line
			(start 0.7874 0.4064)
			(end -0.7874 0.4064)
			(stroke
				(width 0.1524)
				(type default)
			)
			(layer "F.SilkS")
		)
		(fp_line
			(start -0.7874 -0.4064)
			(end 0.7874 -0.4064)
			(stroke
				(width 0.1524)
				(type default)
			)
			(layer "F.SilkS")
		)
		(fp_line
			(start 0.7874 -0.4064)
			(end 0.7874 0.4064)
			(stroke
				(width 0.1524)
				(type default)
			)
			(layer "F.SilkS")
		)
		(fp_line
			(start -0.67945 0.3048)
			(end -0.67945 -0.305054)
			(stroke
				(width 0.1)
				(type default)
			)
			(layer "F.Fab")
		)
		(fp_line
			(start -0.12065 0.3048)
			(end -0.67945 0.3048)
			(stroke
				(width 0.1)
				(type default)
			)
			(layer "F.Fab")
		)
		(fp_line
			(start 0.120396 0.3048)
			(end 0.120396 0.2794)
			(stroke
				(width 0.1)
				(type default)
			)
			(layer "F.Fab")
		)
		(fp_line
			(start 0.67945 0.3048)
			(end 0.120396 0.3048)
			(stroke
				(width 0.1)
				(type default)
			)
			(layer "F.Fab")
		)
		(fp_line
			(start -0.12065 0.2794)
			(end -0.12065 0.3048)
			(stroke
				(width 0.1)
				(type default)
			)
			(layer "F.Fab")
		)
		(fp_line
			(start 0.120396 0.2794)
			(end -0.12065 0.2794)
			(stroke
				(width 0.1)
				(type default)
			)
			(layer "F.Fab")
		)
		(fp_line
			(start -0.12065 -0.2794)
			(end 0.12065 -0.2794)
			(stroke
				(width 0.1)
				(type default)
			)
			(layer "F.Fab")
		)
		(fp_line
			(start 0.12065 -0.2794)
			(end 0.12065 -0.3048)
			(stroke
				(width 0.1)
				(type default)
			)
			(layer "F.Fab")
		)
		(fp_line
			(start 0.12065 -0.3048)
			(end 0.67945 -0.3048)
			(stroke
				(width 0.1)
				(type default)
			)
			(layer "F.Fab")
		)
		(fp_line
			(start 0.67945 -0.3048)
			(end 0.67945 0.3048)
			(stroke
				(width 0.1)
				(type default)
			)
			(layer "F.Fab")
		)
		(fp_line
			(start -0.67945 -0.305054)
			(end -0.12065 -0.305054)
			(stroke
				(width 0.1)
				(type default)
			)
			(layer "F.Fab")
		)
		(fp_line
			(start -0.12065 -0.305054)
			(end -0.12065 -0.2794)
			(stroke
				(width 0.1)
				(type default)
			)
			(layer "F.Fab")
		)
		(pad "1" smd circle
			(at -0.40005 0 270)
			(size 0 0)
			(layers "F.Cu" "F.Mask" "F.Paste")
			(net "GPU_BASE_ID0")
		)
		(pad "2" smd circle
			(at 0.40005 0 270)
			(size 0 0)
			(layers "F.Cu" "F.Mask" "F.Paste")
			(net "GPU_BASE_ID0_R")
		)
	)
	(footprint ""
		(layer "F.Cu")
		(at 49.139094 -169.708322 90)
		(property "Reference" "PC374"
			(at 0 0 90)
			(layer "F.SilkS")
			(hide yes)
			(effects
				(font
					(size 1.27 1.27)
				)
			)
		)
		(property "Value" ""
			(at 0 0 90)
			(layer "F.Fab")
			(effects
				(font
					(size 1.27 1.27)
				)
			)
		)
		(duplicate_pad_numbers_are_jumpers no)
		(fp_line
			(start 0.7874 -0.4064)
			(end 0.7874 0.4064)
			(stroke
				(width 0.1524)
				(type default)
			)
			(layer "F.SilkS")
		)
		(fp_line
			(start -0.7874 -0.4064)
			(end 0.7874 -0.4064)
			(stroke
				(width 0.1524)
				(type default)
			)
			(layer "F.SilkS")
		)
		(fp_line
			(start 0.7874 0.4064)
			(end -0.7874 0.4064)
			(stroke
				(width 0.1524)
				(type default)
			)
			(layer "F.SilkS")
		)
		(fp_line
			(start -0.7874 0.4064)
			(end -0.7874 -0.4064)
			(stroke
				(width 0.1524)
				(type default)
			)
			(layer "F.SilkS")
		)
		(fp_line
			(start -0.12065 -0.305054)
			(end -0.12065 -0.2794)
			(stroke
				(width 0.1)
				(type default)
			)
			(layer "F.Fab")
		)
		(fp_line
			(start -0.67945 -0.305054)
			(end -0.12065 -0.305054)
			(stroke
				(width 0.1)
				(type default)
			)
			(layer "F.Fab")
		)
		(fp_line
			(start 0.67945 -0.3048)
			(end 0.67945 0.3048)
			(stroke
				(width 0.1)
				(type default)
			)
			(layer "F.Fab")
		)
		(fp_line
			(start 0.12065 -0.3048)
			(end 0.67945 -0.3048)
			(stroke
				(width 0.1)
				(type default)
			)
			(layer "F.Fab")
		)
		(fp_line
			(start 0.12065 -0.2794)
			(end 0.12065 -0.3048)
			(stroke
				(width 0.1)
				(type default)
			)
			(layer "F.Fab")
		)
		(fp_line
			(start -0.12065 -0.2794)
			(end 0.12065 -0.2794)
			(stroke
				(width 0.1)
				(type default)
			)
			(layer "F.Fab")
		)
		(fp_line
			(start 0.120396 0.2794)
			(end -0.12065 0.2794)
			(stroke
				(width 0.1)
				(type default)
			)
			(layer "F.Fab")
		)
		(fp_line
			(start -0.12065 0.2794)
			(end -0.12065 0.3048)
			(stroke
				(width 0.1)
				(type default)
			)
			(layer "F.Fab")
		)
		(fp_line
			(start 0.67945 0.3048)
			(end 0.120396 0.3048)
			(stroke
				(width 0.1)
				(type default)
			)
			(layer "F.Fab")
		)
		(fp_line
			(start 0.120396 0.3048)
			(end 0.120396 0.2794)
			(stroke
				(width 0.1)
				(type default)
			)
			(layer "F.Fab")
		)
		(fp_line
			(start -0.12065 0.3048)
			(end -0.67945 0.3048)
			(stroke
				(width 0.1)
				(type default)
			)
			(layer "F.Fab")
		)
		(fp_line
			(start -0.67945 0.3048)
			(end -0.67945 -0.305054)
			(stroke
				(width 0.1)
				(type default)
			)
			(layer "F.Fab")
		)
		(pad "1" smd circle
			(at -0.40005 0 90)
			(size 0 0)
			(layers "F.Cu" "F.Mask" "F.Paste")
			(net "SW_P12V_PVCCINFAON_CPU1_FLT")
		)
		(pad "2" smd circle
			(at 0.40005 0 90)
			(size 0 0)
			(layers "F.Cu" "F.Mask" "F.Paste")
			(net "GND")
		)
	)
	(footprint ""
		(layer "F.Cu")
		(at 418.919914 -139.88669 90)
		(property "Reference" "PR435"
			(at 0 0 90)
			(layer "F.SilkS")
			(hide yes)
			(effects
				(font
					(size 1.27 1.27)
				)
			)
		)
		(property "Value" ""
			(at 0 0 90)
			(layer "F.Fab")
			(effects
				(font
					(size 1.27 1.27)
				)
			)
		)
		(duplicate_pad_numbers_are_jumpers no)
		(fp_line
			(start 0.7874 -0.4064)
			(end 0.7874 0.4064)
			(stroke
				(width 0.1524)
				(type default)
			)
			(layer "F.SilkS")
		)
		(fp_line
			(start -0.7874 -0.4064)
			(end 0.7874 -0.4064)
			(stroke
				(width 0.1524)
				(type default)
			)
			(layer "F.SilkS")
		)
		(fp_line
			(start 0.7874 0.4064)
			(end -0.7874 0.4064)
			(stroke
				(width 0.1524)
				(type default)
			)
			(layer "F.SilkS")
		)
		(fp_line
			(start -0.7874 0.4064)
			(end -0.7874 -0.4064)
			(stroke
				(width 0.1524)
				(type default)
			)
			(layer "F.SilkS")
		)
		(fp_line
			(start -0.12065 -0.305054)
			(end -0.12065 -0.2794)
			(stroke
				(width 0.1)
				(type default)
			)
			(layer "F.Fab")
		)
		(fp_line
			(start -0.67945 -0.305054)
			(end -0.12065 -0.305054)
			(stroke
				(width 0.1)
				(type default)
			)
			(layer "F.Fab")
		)
		(fp_line
			(start 0.67945 -0.3048)
			(end 0.67945 0.3048)
			(stroke
				(width 0.1)
				(type default)
			)
			(layer "F.Fab")
		)
		(fp_line
			(start 0.12065 -0.3048)
			(end 0.67945 -0.3048)
			(stroke
				(width 0.1)
				(type default)
			)
			(layer "F.Fab")
		)
		(fp_line
			(start 0.12065 -0.2794)
			(end 0.12065 -0.3048)
			(stroke
				(width 0.1)
				(type default)
			)
			(layer "F.Fab")
		)
		(fp_line
			(start -0.12065 -0.2794)
			(end 0.12065 -0.2794)
			(stroke
				(width 0.1)
				(type default)
			)
			(layer "F.Fab")
		)
		(fp_line
			(start 0.120396 0.2794)
			(end -0.12065 0.2794)
			(stroke
				(width 0.1)
				(type default)
			)
			(layer "F.Fab")
		)
		(fp_line
			(start -0.12065 0.2794)
			(end -0.12065 0.3048)
			(stroke
				(width 0.1)
				(type default)
			)
			(layer "F.Fab")
		)
		(fp_line
			(start 0.67945 0.3048)
			(end 0.120396 0.3048)
			(stroke
				(width 0.1)
				(type default)
			)
			(layer "F.Fab")
		)
		(fp_line
			(start 0.120396 0.3048)
			(end 0.120396 0.2794)
			(stroke
				(width 0.1)
				(type default)
			)
			(layer "F.Fab")
		)
		(fp_line
			(start -0.12065 0.3048)
			(end -0.67945 0.3048)
			(stroke
				(width 0.1)
				(type default)
			)
			(layer "F.Fab")
		)
		(fp_line
			(start -0.67945 0.3048)
			(end -0.67945 -0.305054)
			(stroke
				(width 0.1)
				(type default)
			)
			(layer "F.Fab")
		)
		(pad "1" smd circle
			(at -0.40005 0 90)
			(size 0 0)
			(layers "F.Cu" "F.Mask" "F.Paste")
			(net "PVCCINFAON_CPU0_ATSEN")
		)
		(pad "2" smd circle
			(at 0.40005 0 90)
			(size 0 0)
			(layers "F.Cu" "F.Mask" "F.Paste")
			(net "GND")
		)
	)
	(footprint ""
		(layer "F.Cu")
		(at 209.74558 -132.862828)
		(property "Reference" "R1690"
			(at 0 0 0)
			(layer "F.SilkS")
			(hide yes)
			(effects
				(font
					(size 1.27 1.27)
				)
			)
		)
		(property "Value" ""
			(at 0 0 0)
			(layer "F.Fab")
			(effects
				(font
					(size 1.27 1.27)
				)
			)
		)
		(duplicate_pad_numbers_are_jumpers no)
		(fp_line
			(start -0.7874 -0.4064)
			(end 0.7874 -0.4064)
			(stroke
				(width 0.1524)
				(type default)
			)
			(layer "F.SilkS")
		)
		(fp_line
			(start -0.7874 0.4064)
			(end -0.7874 -0.4064)
			(stroke
				(width 0.1524)
				(type default)
			)
			(layer "F.SilkS")
		)
		(fp_line
			(start 0.7874 -0.4064)
			(end 0.7874 0.4064)
			(stroke
				(width 0.1524)
				(type default)
			)
			(layer "F.SilkS")
		)
		(fp_line
			(start 0.7874 0.4064)
			(end -0.7874 0.4064)
			(stroke
				(width 0.1524)
				(type default)
			)
			(layer "F.SilkS")
		)
		(fp_line
			(start -0.67945 -0.305054)
			(end -0.12065 -0.305054)
			(stroke
				(width 0.1)
				(type default)
			)
			(layer "F.Fab")
		)
		(fp_line
			(start -0.67945 0.3048)
			(end -0.67945 -0.305054)
			(stroke
				(width 0.1)
				(type default)
			)
			(layer "F.Fab")
		)
		(fp_line
			(start -0.12065 -0.305054)
			(end -0.12065 -0.2794)
			(stroke
				(width 0.1)
				(type default)
			)
			(layer "F.Fab")
		)
		(fp_line
			(start -0.12065 -0.2794)
			(end 0.12065 -0.2794)
			(stroke
				(width 0.1)
				(type default)
			)
			(layer "F.Fab")
		)
		(fp_line
			(start -0.12065 0.2794)
			(end -0.12065 0.3048)
			(stroke
				(width 0.1)
				(type default)
			)
			(layer "F.Fab")
		)
		(fp_line
			(start -0.12065 0.3048)
			(end -0.67945 0.3048)
			(stroke
				(width 0.1)
				(type default)
			)
			(layer "F.Fab")
		)
		(fp_line
			(start 0.120396 0.2794)
			(end -0.12065 0.2794)
			(stroke
				(width 0.1)
				(type default)
			)
			(layer "F.Fab")
		)
		(fp_line
			(start 0.120396 0.3048)
			(end 0.120396 0.2794)
			(stroke
				(width 0.1)
				(type default)
			)
			(layer "F.Fab")
		)
		(fp_line
			(start 0.12065 -0.3048)
			(end 0.67945 -0.3048)
			(stroke
				(width 0.1)
				(type default)
			)
			(layer "F.Fab")
		)
		(fp_line
			(start 0.12065 -0.2794)
			(end 0.12065 -0.3048)
			(stroke
				(width 0.1)
				(type default)
			)
			(layer "F.Fab")
		)
		(fp_line
			(start 0.67945 -0.3048)
			(end 0.67945 0.3048)
			(stroke
				(width 0.1)
				(type default)
			)
			(layer "F.Fab")
		)
		(fp_line
			(start 0.67945 0.3048)
			(end 0.120396 0.3048)
			(stroke
				(width 0.1)
				(type default)
			)
			(layer "F.Fab")
		)
		(pad "1" smd circle
			(at -0.40005 0)
			(size 0 0)
			(layers "F.Cu" "F.Mask" "F.Paste")
			(net "P3V3_AUX")
		)
		(pad "2" smd circle
			(at 0.40005 0)
			(size 0 0)
			(layers "F.Cu" "F.Mask" "F.Paste")
			(net "FM_COMP_P3V3_AUX_ENIN")
		)
	)
	(footprint ""
		(layer "F.Cu")
		(at 52.480972 -436.376318)
		(property "Reference" "R2898"
			(at 0 0 0)
			(layer "F.SilkS")
			(hide yes)
			(effects
				(font
					(size 1.27 1.27)
				)
			)
		)
		(property "Value" ""
			(at 0 0 0)
			(layer "F.Fab")
			(effects
				(font
					(size 1.27 1.27)
				)
			)
		)
		(duplicate_pad_numbers_are_jumpers no)
		(fp_line
			(start -0.7874 -0.4064)
			(end 0.7874 -0.4064)
			(stroke
				(width 0.1524)
				(type default)
			)
			(layer "F.SilkS")
		)
		(fp_line
			(start -0.7874 0.4064)
			(end -0.7874 -0.4064)
			(stroke
				(width 0.1524)
				(type default)
			)
			(layer "F.SilkS")
		)
		(fp_line
			(start 0.7874 -0.4064)
			(end 0.7874 0.4064)
			(stroke
				(width 0.1524)
				(type default)
			)
			(layer "F.SilkS")
		)
		(fp_line
			(start 0.7874 0.4064)
			(end -0.7874 0.4064)
			(stroke
				(width 0.1524)
				(type default)
			)
			(layer "F.SilkS")
		)
		(fp_line
			(start -0.67945 -0.305054)
			(end -0.12065 -0.305054)
			(stroke
				(width 0.1)
				(type default)
			)
			(layer "F.Fab")
		)
		(fp_line
			(start -0.67945 0.3048)
			(end -0.67945 -0.305054)
			(stroke
				(width 0.1)
				(type default)
			)
			(layer "F.Fab")
		)
		(fp_line
			(start -0.12065 -0.305054)
			(end -0.12065 -0.2794)
			(stroke
				(width 0.1)
				(type default)
			)
			(layer "F.Fab")
		)
		(fp_line
			(start -0.12065 -0.2794)
			(end 0.12065 -0.2794)
			(stroke
				(width 0.1)
				(type default)
			)
			(layer "F.Fab")
		)
		(fp_line
			(start -0.12065 0.2794)
			(end -0.12065 0.3048)
			(stroke
				(width 0.1)
				(type default)
			)
			(layer "F.Fab")
		)
		(fp_line
			(start -0.12065 0.3048)
			(end -0.67945 0.3048)
			(stroke
				(width 0.1)
				(type default)
			)
			(layer "F.Fab")
		)
		(fp_line
			(start 0.120396 0.2794)
			(end -0.12065 0.2794)
			(stroke
				(width 0.1)
				(type default)
			)
			(layer "F.Fab")
		)
		(fp_line
			(start 0.120396 0.3048)
			(end 0.120396 0.2794)
			(stroke
				(width 0.1)
				(type default)
			)
			(layer "F.Fab")
		)
		(fp_line
			(start 0.12065 -0.3048)
			(end 0.67945 -0.3048)
			(stroke
				(width 0.1)
				(type default)
			)
			(layer "F.Fab")
		)
		(fp_line
			(start 0.12065 -0.2794)
			(end 0.12065 -0.3048)
			(stroke
				(width 0.1)
				(type default)
			)
			(layer "F.Fab")
		)
		(fp_line
			(start 0.67945 -0.3048)
			(end 0.67945 0.3048)
			(stroke
				(width 0.1)
				(type default)
			)
			(layer "F.Fab")
		)
		(fp_line
			(start 0.67945 0.3048)
			(end 0.120396 0.3048)
			(stroke
				(width 0.1)
				(type default)
			)
			(layer "F.Fab")
		)
		(pad "1" smd circle
			(at -0.40005 0)
			(size 0 0)
			(layers "F.Cu" "F.Mask" "F.Paste")
			(net "SMB_1_BMC_GPU_BUF_R_SDA")
		)
		(pad "2" smd circle
			(at 0.40005 0)
			(size 0 0)
			(layers "F.Cu" "F.Mask" "F.Paste")
			(net "SMB_1_BMC_GPU_BUF_SDA")
		)
	)
	(footprint ""
		(layer "F.Cu")
		(at 131.318 -156.398468 180)
		(property "Reference" "R1495"
			(at 0 0 180)
			(layer "F.SilkS")
			(hide yes)
			(effects
				(font
					(size 1.27 1.27)
				)
			)
		)
		(property "Value" ""
			(at 0 0 180)
			(layer "F.Fab")
			(effects
				(font
					(size 1.27 1.27)
				)
			)
		)
		(duplicate_pad_numbers_are_jumpers no)
		(fp_line
			(start 0.7874 0.4064)
			(end -0.7874 0.4064)
			(stroke
				(width 0.1524)
				(type default)
			)
			(layer "F.SilkS")
		)
		(fp_line
			(start 0.7874 -0.4064)
			(end 0.7874 0.4064)
			(stroke
				(width 0.1524)
				(type default)
			)
			(layer "F.SilkS")
		)
		(fp_line
			(start -0.7874 0.4064)
			(end -0.7874 -0.4064)
			(stroke
				(width 0.1524)
				(type default)
			)
			(layer "F.SilkS")
		)
		(fp_line
			(start -0.7874 -0.4064)
			(end 0.7874 -0.4064)
			(stroke
				(width 0.1524)
				(type default)
			)
			(layer "F.SilkS")
		)
		(fp_line
			(start 0.67945 0.3048)
			(end 0.120396 0.3048)
			(stroke
				(width 0.1)
				(type default)
			)
			(layer "F.Fab")
		)
		(fp_line
			(start 0.67945 -0.3048)
			(end 0.67945 0.3048)
			(stroke
				(width 0.1)
				(type default)
			)
			(layer "F.Fab")
		)
		(fp_line
			(start 0.12065 -0.2794)
			(end 0.12065 -0.3048)
			(stroke
				(width 0.1)
				(type default)
			)
			(layer "F.Fab")
		)
		(fp_line
			(start 0.12065 -0.3048)
			(end 0.67945 -0.3048)
			(stroke
				(width 0.1)
				(type default)
			)
			(layer "F.Fab")
		)
		(fp_line
			(start 0.120396 0.3048)
			(end 0.120396 0.2794)
			(stroke
				(width 0.1)
				(type default)
			)
			(layer "F.Fab")
		)
		(fp_line
			(start 0.120396 0.2794)
			(end -0.12065 0.2794)
			(stroke
				(width 0.1)
				(type default)
			)
			(layer "F.Fab")
		)
		(fp_line
			(start -0.12065 0.3048)
			(end -0.67945 0.3048)
			(stroke
				(width 0.1)
				(type default)
			)
			(layer "F.Fab")
		)
		(fp_line
			(start -0.12065 0.2794)
			(end -0.12065 0.3048)
			(stroke
				(width 0.1)
				(type default)
			)
			(layer "F.Fab")
		)
		(fp_line
			(start -0.12065 -0.2794)
			(end 0.12065 -0.2794)
			(stroke
				(width 0.1)
				(type default)
			)
			(layer "F.Fab")
		)
		(fp_line
			(start -0.12065 -0.305054)
			(end -0.12065 -0.2794)
			(stroke
				(width 0.1)
				(type default)
			)
			(layer "F.Fab")
		)
		(fp_line
			(start -0.67945 0.3048)
			(end -0.67945 -0.305054)
			(stroke
				(width 0.1)
				(type default)
			)
			(layer "F.Fab")
		)
		(fp_line
			(start -0.67945 -0.305054)
			(end -0.12065 -0.305054)
			(stroke
				(width 0.1)
				(type default)
			)
			(layer "F.Fab")
		)
		(pad "1" smd circle
			(at -0.40005 0 180)
			(size 0 0)
			(layers "F.Cu" "F.Mask" "F.Paste")
			(net "PD_FORCE_PWRON")
		)
		(pad "2" smd circle
			(at 0.40005 0 180)
			(size 0 0)
			(layers "F.Cu" "F.Mask" "F.Paste")
			(net "GND")
		)
	)
	(footprint ""
		(layer "F.Cu")
		(at 142.54988 -46.954948)
		(property "Reference" "R5377"
			(at 0 0 0)
			(layer "F.SilkS")
			(hide yes)
			(effects
				(font
					(size 1.27 1.27)
				)
			)
		)
		(property "Value" ""
			(at 0 0 0)
			(layer "F.Fab")
			(effects
				(font
					(size 1.27 1.27)
				)
			)
		)
		(duplicate_pad_numbers_are_jumpers no)
		(fp_line
			(start -0.7874 -0.4064)
			(end 0.7874 -0.4064)
			(stroke
				(width 0.1524)
				(type default)
			)
			(layer "F.SilkS")
		)
		(fp_line
			(start -0.7874 0.4064)
			(end -0.7874 -0.4064)
			(stroke
				(width 0.1524)
				(type default)
			)
			(layer "F.SilkS")
		)
		(fp_line
			(start 0.7874 -0.4064)
			(end 0.7874 0.4064)
			(stroke
				(width 0.1524)
				(type default)
			)
			(layer "F.SilkS")
		)
		(fp_line
			(start 0.7874 0.4064)
			(end -0.7874 0.4064)
			(stroke
				(width 0.1524)
				(type default)
			)
			(layer "F.SilkS")
		)
		(fp_line
			(start -0.67945 -0.305054)
			(end -0.12065 -0.305054)
			(stroke
				(width 0.1)
				(type default)
			)
			(layer "F.Fab")
		)
		(fp_line
			(start -0.67945 0.3048)
			(end -0.67945 -0.305054)
			(stroke
				(width 0.1)
				(type default)
			)
			(layer "F.Fab")
		)
		(fp_line
			(start -0.12065 -0.305054)
			(end -0.12065 -0.2794)
			(stroke
				(width 0.1)
				(type default)
			)
			(layer "F.Fab")
		)
		(fp_line
			(start -0.12065 -0.2794)
			(end 0.12065 -0.2794)
			(stroke
				(width 0.1)
				(type default)
			)
			(layer "F.Fab")
		)
		(fp_line
			(start -0.12065 0.2794)
			(end -0.12065 0.3048)
			(stroke
				(width 0.1)
				(type default)
			)
			(layer "F.Fab")
		)
		(fp_line
			(start -0.12065 0.3048)
			(end -0.67945 0.3048)
			(stroke
				(width 0.1)
				(type default)
			)
			(layer "F.Fab")
		)
		(fp_line
			(start 0.120396 0.2794)
			(end -0.12065 0.2794)
			(stroke
				(width 0.1)
				(type default)
			)
			(layer "F.Fab")
		)
		(fp_line
			(start 0.120396 0.3048)
			(end 0.120396 0.2794)
			(stroke
				(width 0.1)
				(type default)
			)
			(layer "F.Fab")
		)
		(fp_line
			(start 0.12065 -0.3048)
			(end 0.67945 -0.3048)
			(stroke
				(width 0.1)
				(type default)
			)
			(layer "F.Fab")
		)
		(fp_line
			(start 0.12065 -0.2794)
			(end 0.12065 -0.3048)
			(stroke
				(width 0.1)
				(type default)
			)
			(layer "F.Fab")
		)
		(fp_line
			(start 0.67945 -0.3048)
			(end 0.67945 0.3048)
			(stroke
				(width 0.1)
				(type default)
			)
			(layer "F.Fab")
		)
		(fp_line
			(start 0.67945 0.3048)
			(end 0.120396 0.3048)
			(stroke
				(width 0.1)
				(type default)
			)
			(layer "F.Fab")
		)
		(pad "1" smd circle
			(at -0.40005 0)
			(size 0 0)
			(layers "F.Cu" "F.Mask" "F.Paste")
			(net "HDD_ACTIVITY_BUF_N")
		)
		(pad "2" smd circle
			(at 0.40005 0)
			(size 0 0)
			(layers "F.Cu" "F.Mask" "F.Paste")
			(net "PU_BUFFER_HDD_ACTIVITY")
		)
	)
	(footprint ""
		(layer "F.Cu")
		(at 148.197824 -50.388012)
		(property "Reference" "R3621"
			(at 0 0 0)
			(layer "F.SilkS")
			(hide yes)
			(effects
				(font
					(size 1.27 1.27)
				)
			)
		)
		(property "Value" ""
			(at 0 0 0)
			(layer "F.Fab")
			(effects
				(font
					(size 1.27 1.27)
				)
			)
		)
		(duplicate_pad_numbers_are_jumpers no)
		(fp_line
			(start -0.7874 -0.4064)
			(end 0.7874 -0.4064)
			(stroke
				(width 0.1524)
				(type default)
			)
			(layer "F.SilkS")
		)
		(fp_line
			(start -0.7874 0.4064)
			(end -0.7874 -0.4064)
			(stroke
				(width 0.1524)
				(type default)
			)
			(layer "F.SilkS")
		)
		(fp_line
			(start 0.7874 -0.4064)
			(end 0.7874 0.4064)
			(stroke
				(width 0.1524)
				(type default)
			)
			(layer "F.SilkS")
		)
		(fp_line
			(start 0.7874 0.4064)
			(end -0.7874 0.4064)
			(stroke
				(width 0.1524)
				(type default)
			)
			(layer "F.SilkS")
		)
		(fp_line
			(start -0.67945 -0.305054)
			(end -0.12065 -0.305054)
			(stroke
				(width 0.1)
				(type default)
			)
			(layer "F.Fab")
		)
		(fp_line
			(start -0.67945 0.3048)
			(end -0.67945 -0.305054)
			(stroke
				(width 0.1)
				(type default)
			)
			(layer "F.Fab")
		)
		(fp_line
			(start -0.12065 -0.305054)
			(end -0.12065 -0.2794)
			(stroke
				(width 0.1)
				(type default)
			)
			(layer "F.Fab")
		)
		(fp_line
			(start -0.12065 -0.2794)
			(end 0.12065 -0.2794)
			(stroke
				(width 0.1)
				(type default)
			)
			(layer "F.Fab")
		)
		(fp_line
			(start -0.12065 0.2794)
			(end -0.12065 0.3048)
			(stroke
				(width 0.1)
				(type default)
			)
			(layer "F.Fab")
		)
		(fp_line
			(start -0.12065 0.3048)
			(end -0.67945 0.3048)
			(stroke
				(width 0.1)
				(type default)
			)
			(layer "F.Fab")
		)
		(fp_line
			(start 0.120396 0.2794)
			(end -0.12065 0.2794)
			(stroke
				(width 0.1)
				(type default)
			)
			(layer "F.Fab")
		)
		(fp_line
			(start 0.120396 0.3048)
			(end 0.120396 0.2794)
			(stroke
				(width 0.1)
				(type default)
			)
			(layer "F.Fab")
		)
		(fp_line
			(start 0.12065 -0.3048)
			(end 0.67945 -0.3048)
			(stroke
				(width 0.1)
				(type default)
			)
			(layer "F.Fab")
		)
		(fp_line
			(start 0.12065 -0.2794)
			(end 0.12065 -0.3048)
			(stroke
				(width 0.1)
				(type default)
			)
			(layer "F.Fab")
		)
		(fp_line
			(start 0.67945 -0.3048)
			(end 0.67945 0.3048)
			(stroke
				(width 0.1)
				(type default)
			)
			(layer "F.Fab")
		)
		(fp_line
			(start 0.67945 0.3048)
			(end 0.120396 0.3048)
			(stroke
				(width 0.1)
				(type default)
			)
			(layer "F.Fab")
		)
		(pad "1" smd circle
			(at -0.40005 0)
			(size 0 0)
			(layers "F.Cu" "F.Mask" "F.Paste")
			(net "P3V3_AUX")
		)
		(pad "2" smd circle
			(at 0.40005 0)
			(size 0 0)
			(layers "F.Cu" "F.Mask" "F.Paste")
			(net "INA230_4_A0")
		)
	)
	(footprint ""
		(layer "F.Cu")
		(at 224.16262 -378.176028)
		(property "Reference" "ME22"
			(at -0.1016 -6.949948 0)
			(unlocked yes)
			(layer "F.SilkS")
			(effects
				(font
					(size 0.7874 0.5842)
					(thickness 0.1524)
				)
				(justify left)
			)
		)
		(property "Value" ""
			(at 0 0 0)
			(layer "F.Fab")
			(effects
				(font
					(size 1.27 1.27)
				)
			)
		)
		(duplicate_pad_numbers_are_jumpers no)
		(fp_line
			(start 0 -5.999988)
			(end 0 -4.475988)
			(stroke
				(width 0.1524)
				(type default)
			)
			(layer "F.SilkS")
		)
		(fp_line
			(start 0 -1.524)
			(end 0 0)
			(stroke
				(width 0.1524)
				(type default)
			)
			(layer "F.SilkS")
		)
		(fp_line
			(start 0 0)
			(end 1.524 0)
			(stroke
				(width 0.1524)
				(type default)
			)
			(layer "F.SilkS")
		)
		(fp_line
			(start 1.524 -5.999988)
			(end 0 -5.999988)
			(stroke
				(width 0.1524)
				(type default)
			)
			(layer "F.SilkS")
		)
		(fp_line
			(start 25.475946 -5.999988)
			(end 26.999946 -5.999988)
			(stroke
				(width 0.1524)
				(type default)
			)
			(layer "F.SilkS")
		)
		(fp_line
			(start 26.999946 -5.999988)
			(end 26.999946 -4.475988)
			(stroke
				(width 0.1524)
				(type default)
			)
			(layer "F.SilkS")
		)
		(fp_line
			(start 26.999946 -1.524)
			(end 26.999946 0)
			(stroke
				(width 0.1524)
				(type default)
			)
			(layer "F.SilkS")
		)
		(fp_line
			(start 26.999946 0)
			(end 25.475946 0)
			(stroke
				(width 0.1524)
				(type default)
			)
			(layer "F.SilkS")
		)
		(fp_text user "S/N"
			(at 0.2032 -4.59105 0)
			(unlocked yes)
			(layer "F.SilkS")
			(effects
				(font
					(size 1.905 1.4224)
					(thickness 0.1524)
				)
				(justify left)
			)
		)
	)
	(footprint ""
		(layer "F.Cu")
		(at 397.403066 -167.491664)
		(property "Reference" "PR591"
			(at 0 0 0)
			(layer "F.SilkS")
			(hide yes)
			(effects
				(font
					(size 1.27 1.27)
				)
			)
		)
		(property "Value" ""
			(at 0 0 0)
			(layer "F.Fab")
			(effects
				(font
					(size 1.27 1.27)
				)
			)
		)
		(duplicate_pad_numbers_are_jumpers no)
		(fp_line
			(start -0.7874 -0.4064)
			(end 0.7874 -0.4064)
			(stroke
				(width 0.1524)
				(type default)
			)
			(layer "F.SilkS")
		)
		(fp_line
			(start -0.7874 0.4064)
			(end -0.7874 -0.4064)
			(stroke
				(width 0.1524)
				(type default)
			)
			(layer "F.SilkS")
		)
		(fp_line
			(start 0.7874 -0.4064)
			(end 0.7874 0.4064)
			(stroke
				(width 0.1524)
				(type default)
			)
			(layer "F.SilkS")
		)
		(fp_line
			(start 0.7874 0.4064)
			(end -0.7874 0.4064)
			(stroke
				(width 0.1524)
				(type default)
			)
			(layer "F.SilkS")
		)
		(fp_line
			(start -0.67945 -0.305054)
			(end -0.12065 -0.305054)
			(stroke
				(width 0.1)
				(type default)
			)
			(layer "F.Fab")
		)
		(fp_line
			(start -0.67945 0.3048)
			(end -0.67945 -0.305054)
			(stroke
				(width 0.1)
				(type default)
			)
			(layer "F.Fab")
		)
		(fp_line
			(start -0.12065 -0.305054)
			(end -0.12065 -0.2794)
			(stroke
				(width 0.1)
				(type default)
			)
			(layer "F.Fab")
		)
		(fp_line
			(start -0.12065 -0.2794)
			(end 0.12065 -0.2794)
			(stroke
				(width 0.1)
				(type default)
			)
			(layer "F.Fab")
		)
		(fp_line
			(start -0.12065 0.2794)
			(end -0.12065 0.3048)
			(stroke
				(width 0.1)
				(type default)
			)
			(layer "F.Fab")
		)
		(fp_line
			(start -0.12065 0.3048)
			(end -0.67945 0.3048)
			(stroke
				(width 0.1)
				(type default)
			)
			(layer "F.Fab")
		)
		(fp_line
			(start 0.120396 0.2794)
			(end -0.12065 0.2794)
			(stroke
				(width 0.1)
				(type default)
			)
			(layer "F.Fab")
		)
		(fp_line
			(start 0.120396 0.3048)
			(end 0.120396 0.2794)
			(stroke
				(width 0.1)
				(type default)
			)
			(layer "F.Fab")
		)
		(fp_line
			(start 0.12065 -0.3048)
			(end 0.67945 -0.3048)
			(stroke
				(width 0.1)
				(type default)
			)
			(layer "F.Fab")
		)
		(fp_line
			(start 0.12065 -0.2794)
			(end 0.12065 -0.3048)
			(stroke
				(width 0.1)
				(type default)
			)
			(layer "F.Fab")
		)
		(fp_line
			(start 0.67945 -0.3048)
			(end 0.67945 0.3048)
			(stroke
				(width 0.1)
				(type default)
			)
			(layer "F.Fab")
		)
		(fp_line
			(start 0.67945 0.3048)
			(end 0.120396 0.3048)
			(stroke
				(width 0.1)
				(type default)
			)
			(layer "F.Fab")
		)
		(pad "1" smd circle
			(at -0.40005 0)
			(size 0 0)
			(layers "F.Cu" "F.Mask" "F.Paste")
			(net "VSENSE_PVCCD_HV_CPU0_DN")
		)
		(pad "2" smd circle
			(at 0.40005 0)
			(size 0 0)
			(layers "F.Cu" "F.Mask" "F.Paste")
			(net "GND")
		)
	)
	(footprint ""
		(layer "F.Cu")
		(at 326.323198 -32.688022 -45)
		(property "Reference" "C1507"
			(at 0 0 315)
			(layer "F.SilkS")
			(hide yes)
			(effects
				(font
					(size 1.27 1.27)
				)
			)
		)
		(property "Value" ""
			(at 0 0 315)
			(layer "F.Fab")
			(effects
				(font
					(size 1.27 1.27)
				)
			)
		)
		(duplicate_pad_numbers_are_jumpers no)
		(fp_line
			(start -0.787389 0.406267)
			(end -0.787389 -0.406267)
			(stroke
				(width 0.1524)
				(type default)
			)
			(layer "F.SilkS")
		)
		(fp_line
			(start -0.787389 -0.406267)
			(end 0.787389 -0.406267)
			(stroke
				(width 0.1524)
				(type default)
			)
			(layer "F.SilkS")
		)
		(fp_line
			(start 0.787389 0.406267)
			(end -0.787389 0.406267)
			(stroke
				(width 0.1524)
				(type default)
			)
			(layer "F.SilkS")
		)
		(fp_line
			(start 0.787389 -0.406267)
			(end 0.787389 0.406267)
			(stroke
				(width 0.1524)
				(type default)
			)
			(layer "F.SilkS")
		)
		(fp_line
			(start -0.679446 0.30479)
			(end -0.679446 -0.305149)
			(stroke
				(width 0.1)
				(type default)
			)
			(layer "F.Fab")
		)
		(fp_line
			(start -0.120515 0.30479)
			(end -0.679446 0.30479)
			(stroke
				(width 0.1)
				(type default)
			)
			(layer "F.Fab")
		)
		(fp_line
			(start -0.120695 0.279466)
			(end -0.120515 0.30479)
			(stroke
				(width 0.1)
				(type default)
			)
			(layer "F.Fab")
		)
		(fp_line
			(start -0.679446 -0.305149)
			(end -0.120695 -0.304969)
			(stroke
				(width 0.1)
				(type default)
			)
			(layer "F.Fab")
		)
		(fp_line
			(start 0.120515 0.30479)
			(end 0.120335 0.279466)
			(stroke
				(width 0.1)
				(type default)
			)
			(layer "F.Fab")
		)
		(fp_line
			(start 0.120335 0.279466)
			(end -0.120695 0.279466)
			(stroke
				(width 0.1)
				(type default)
			)
			(layer "F.Fab")
		)
		(fp_line
			(start -0.120695 -0.279466)
			(end 0.120695 -0.279466)
			(stroke
				(width 0.1)
				(type default)
			)
			(layer "F.Fab")
		)
		(fp_line
			(start -0.120695 -0.304969)
			(end -0.120695 -0.279466)
			(stroke
				(width 0.1)
				(type default)
			)
			(layer "F.Fab")
		)
		(fp_line
			(start 0.679446 0.30479)
			(end 0.120515 0.30479)
			(stroke
				(width 0.1)
				(type default)
			)
			(layer "F.Fab")
		)
		(fp_line
			(start 0.120695 -0.279466)
			(end 0.120515 -0.30479)
			(stroke
				(width 0.1)
				(type default)
			)
			(layer "F.Fab")
		)
		(fp_line
			(start 0.120515 -0.30479)
			(end 0.679446 -0.30479)
			(stroke
				(width 0.1)
				(type default)
			)
			(layer "F.Fab")
		)
		(fp_line
			(start 0.679446 -0.30479)
			(end 0.679446 0.30479)
			(stroke
				(width 0.1)
				(type default)
			)
			(layer "F.Fab")
		)
		(pad "1" smd circle
			(at -0.40005 0 315)
			(size 0 0)
			(layers "F.Cu" "F.Mask" "F.Paste")
			(net "XTAL_PCH_RTC2_R")
		)
		(pad "2" smd circle
			(at 0.40005 0 315)
			(size 0 0)
			(layers "F.Cu" "F.Mask" "F.Paste")
			(net "GND")
		)
	)
	(footprint ""
		(layer "F.Cu")
		(at 114.81308 -393.048998 180)
		(property "Reference" "R3034"
			(at 0 0 180)
			(layer "F.SilkS")
			(hide yes)
			(effects
				(font
					(size 1.27 1.27)
				)
			)
		)
		(property "Value" ""
			(at 0 0 180)
			(layer "F.Fab")
			(effects
				(font
					(size 1.27 1.27)
				)
			)
		)
		(duplicate_pad_numbers_are_jumpers no)
		(fp_line
			(start 0.7874 0.4064)
			(end -0.7874 0.4064)
			(stroke
				(width 0.1524)
				(type default)
			)
			(layer "F.SilkS")
		)
		(fp_line
			(start 0.7874 -0.4064)
			(end 0.7874 0.4064)
			(stroke
				(width 0.1524)
				(type default)
			)
			(layer "F.SilkS")
		)
		(fp_line
			(start -0.7874 0.4064)
			(end -0.7874 -0.4064)
			(stroke
				(width 0.1524)
				(type default)
			)
			(layer "F.SilkS")
		)
		(fp_line
			(start -0.7874 -0.4064)
			(end 0.7874 -0.4064)
			(stroke
				(width 0.1524)
				(type default)
			)
			(layer "F.SilkS")
		)
		(fp_line
			(start 0.67945 0.3048)
			(end 0.120396 0.3048)
			(stroke
				(width 0.1)
				(type default)
			)
			(layer "F.Fab")
		)
		(fp_line
			(start 0.67945 -0.3048)
			(end 0.67945 0.3048)
			(stroke
				(width 0.1)
				(type default)
			)
			(layer "F.Fab")
		)
		(fp_line
			(start 0.12065 -0.2794)
			(end 0.12065 -0.3048)
			(stroke
				(width 0.1)
				(type default)
			)
			(layer "F.Fab")
		)
		(fp_line
			(start 0.12065 -0.3048)
			(end 0.67945 -0.3048)
			(stroke
				(width 0.1)
				(type default)
			)
			(layer "F.Fab")
		)
		(fp_line
			(start 0.120396 0.3048)
			(end 0.120396 0.2794)
			(stroke
				(width 0.1)
				(type default)
			)
			(layer "F.Fab")
		)
		(fp_line
			(start 0.120396 0.2794)
			(end -0.12065 0.2794)
			(stroke
				(width 0.1)
				(type default)
			)
			(layer "F.Fab")
		)
		(fp_line
			(start -0.12065 0.3048)
			(end -0.67945 0.3048)
			(stroke
				(width 0.1)
				(type default)
			)
			(layer "F.Fab")
		)
		(fp_line
			(start -0.12065 0.2794)
			(end -0.12065 0.3048)
			(stroke
				(width 0.1)
				(type default)
			)
			(layer "F.Fab")
		)
		(fp_line
			(start -0.12065 -0.2794)
			(end 0.12065 -0.2794)
			(stroke
				(width 0.1)
				(type default)
			)
			(layer "F.Fab")
		)
		(fp_line
			(start -0.12065 -0.305054)
			(end -0.12065 -0.2794)
			(stroke
				(width 0.1)
				(type default)
			)
			(layer "F.Fab")
		)
		(fp_line
			(start -0.67945 0.3048)
			(end -0.67945 -0.305054)
			(stroke
				(width 0.1)
				(type default)
			)
			(layer "F.Fab")
		)
		(fp_line
			(start -0.67945 -0.305054)
			(end -0.12065 -0.305054)
			(stroke
				(width 0.1)
				(type default)
			)
			(layer "F.Fab")
		)
		(pad "1" smd circle
			(at -0.40005 0 180)
			(size 0 0)
			(layers "F.Cu" "F.Mask" "F.Paste")
			(net "P3V3_AUX")
		)
		(pad "2" smd circle
			(at 0.40005 0 180)
			(size 0 0)
			(layers "F.Cu" "F.Mask" "F.Paste")
			(net "FM_SMB_2_ALERT_GPU")
		)
	)
	(footprint ""
		(layer "F.Cu")
		(at 170.965622 -337.477608)
		(property "Reference" "PC1203"
			(at 0 0 0)
			(layer "F.SilkS")
			(hide yes)
			(effects
				(font
					(size 1.27 1.27)
				)
			)
		)
		(property "Value" ""
			(at 0 0 0)
			(layer "F.Fab")
			(effects
				(font
					(size 1.27 1.27)
				)
			)
		)
		(duplicate_pad_numbers_are_jumpers no)
		(fp_line
			(start 2.750058 0.999998)
			(end -2.750058 0.999998)
			(stroke
				(width 0.1524)
				(type default)
			)
			(layer "F.SilkS")
		)
		(fp_circle
			(center 0 0.999998)
			(end 2.750058 0.999998)
			(stroke
				(width 0.1524)
				(type default)
			)
			(fill no)
			(layer "F.SilkS")
		)
		(fp_poly
			(pts
				(arc
					(start 2.750058 0.999998)
					(mid 0 3.750056)
					(end -2.750058 0.999998)
				)
			)
			(stroke
				(width 0)
				(type default)
			)
			(fill yes)
			(layer "F.SilkS")
		)
		(fp_circle
			(center 0 0.999998)
			(end 2.750058 0.999998)
			(stroke
				(width 0.1)
				(type default)
			)
			(fill no)
			(layer "F.Fab")
		)
		(pad "1" thru_hole rect
			(at 0 0)
			(size 1.5748 1.5748)
			(drill 1.0668)
			(layers "*.Cu" "*.Mask")
			(remove_unused_layers no)
			(net "PVCCFA_EHV_FIVRA_CPU1")
			(clearance 0)
			(padstack
				(mode front_inner_back)
				(layer "Inner"
					(shape circle)
					(size 1.5748 1.5748)
					(clearance 0)
				)
				(layer "B.Cu"
					(shape rect)
					(size 1.5748 1.5748)
					(clearance 0)
				)
			)
		)
		(pad "2" thru_hole circle
			(at 0 1.999996)
			(size 1.5748 1.5748)
			(drill 1.0668)
			(layers "*.Cu" "*.Mask")
			(remove_unused_layers no)
			(net "GND")
			(clearance 0)
		)
	)
	(footprint ""
		(layer "F.Cu")
		(at 428.912782 -107.872276 180)
		(property "Reference" "PR3790"
			(at 0 0 180)
			(layer "F.SilkS")
			(hide yes)
			(effects
				(font
					(size 1.27 1.27)
				)
			)
		)
		(property "Value" ""
			(at 0 0 180)
			(layer "F.Fab")
			(effects
				(font
					(size 1.27 1.27)
				)
			)
		)
		(duplicate_pad_numbers_are_jumpers no)
		(fp_line
			(start 0.7874 0.4064)
			(end -0.7874 0.4064)
			(stroke
				(width 0.1524)
				(type default)
			)
			(layer "F.SilkS")
		)
		(fp_line
			(start 0.7874 -0.4064)
			(end 0.7874 0.4064)
			(stroke
				(width 0.1524)
				(type default)
			)
			(layer "F.SilkS")
		)
		(fp_line
			(start -0.7874 0.4064)
			(end -0.7874 -0.4064)
			(stroke
				(width 0.1524)
				(type default)
			)
			(layer "F.SilkS")
		)
		(fp_line
			(start -0.7874 -0.4064)
			(end 0.7874 -0.4064)
			(stroke
				(width 0.1524)
				(type default)
			)
			(layer "F.SilkS")
		)
		(fp_line
			(start 0.67945 0.3048)
			(end 0.120396 0.3048)
			(stroke
				(width 0.1)
				(type default)
			)
			(layer "F.Fab")
		)
		(fp_line
			(start 0.67945 -0.3048)
			(end 0.67945 0.3048)
			(stroke
				(width 0.1)
				(type default)
			)
			(layer "F.Fab")
		)
		(fp_line
			(start 0.12065 -0.2794)
			(end 0.12065 -0.3048)
			(stroke
				(width 0.1)
				(type default)
			)
			(layer "F.Fab")
		)
		(fp_line
			(start 0.12065 -0.3048)
			(end 0.67945 -0.3048)
			(stroke
				(width 0.1)
				(type default)
			)
			(layer "F.Fab")
		)
		(fp_line
			(start 0.120396 0.3048)
			(end 0.120396 0.2794)
			(stroke
				(width 0.1)
				(type default)
			)
			(layer "F.Fab")
		)
		(fp_line
			(start 0.120396 0.2794)
			(end -0.12065 0.2794)
			(stroke
				(width 0.1)
				(type default)
			)
			(layer "F.Fab")
		)
		(fp_line
			(start -0.12065 0.3048)
			(end -0.67945 0.3048)
			(stroke
				(width 0.1)
				(type default)
			)
			(layer "F.Fab")
		)
		(fp_line
			(start -0.12065 0.2794)
			(end -0.12065 0.3048)
			(stroke
				(width 0.1)
				(type default)
			)
			(layer "F.Fab")
		)
		(fp_line
			(start -0.12065 -0.2794)
			(end 0.12065 -0.2794)
			(stroke
				(width 0.1)
				(type default)
			)
			(layer "F.Fab")
		)
		(fp_line
			(start -0.12065 -0.305054)
			(end -0.12065 -0.2794)
			(stroke
				(width 0.1)
				(type default)
			)
			(layer "F.Fab")
		)
		(fp_line
			(start -0.67945 0.3048)
			(end -0.67945 -0.305054)
			(stroke
				(width 0.1)
				(type default)
			)
			(layer "F.Fab")
		)
		(fp_line
			(start -0.67945 -0.305054)
			(end -0.12065 -0.305054)
			(stroke
				(width 0.1)
				(type default)
			)
			(layer "F.Fab")
		)
		(pad "1" smd circle
			(at -0.40005 0 180)
			(size 0 0)
			(layers "F.Cu" "F.Mask" "F.Paste")
			(net "P3V3_OCP_UV_1")
		)
		(pad "2" smd circle
			(at 0.40005 0 180)
			(size 0 0)
			(layers "F.Cu" "F.Mask" "F.Paste")
			(net "P3V3_OCP_OV_1")
		)
	)
	(footprint ""
		(layer "F.Cu")
		(at 461.720946 -103.614728)
		(property "Reference" "C593"
			(at 0 0 0)
			(layer "F.SilkS")
			(hide yes)
			(effects
				(font
					(size 1.27 1.27)
				)
			)
		)
		(property "Value" ""
			(at 0 0 0)
			(layer "F.Fab")
			(effects
				(font
					(size 1.27 1.27)
				)
			)
		)
		(duplicate_pad_numbers_are_jumpers no)
		(fp_line
			(start -0.7874 -0.4064)
			(end 0.7874 -0.4064)
			(stroke
				(width 0.1524)
				(type default)
			)
			(layer "F.SilkS")
		)
		(fp_line
			(start -0.7874 0.4064)
			(end -0.7874 -0.4064)
			(stroke
				(width 0.1524)
				(type default)
			)
			(layer "F.SilkS")
		)
		(fp_line
			(start 0.7874 -0.4064)
			(end 0.7874 0.4064)
			(stroke
				(width 0.1524)
				(type default)
			)
			(layer "F.SilkS")
		)
		(fp_line
			(start 0.7874 0.4064)
			(end -0.7874 0.4064)
			(stroke
				(width 0.1524)
				(type default)
			)
			(layer "F.SilkS")
		)
		(fp_line
			(start -0.67945 -0.305054)
			(end -0.12065 -0.305054)
			(stroke
				(width 0.1)
				(type default)
			)
			(layer "F.Fab")
		)
		(fp_line
			(start -0.67945 0.3048)
			(end -0.67945 -0.305054)
			(stroke
				(width 0.1)
				(type default)
			)
			(layer "F.Fab")
		)
		(fp_line
			(start -0.12065 -0.305054)
			(end -0.12065 -0.2794)
			(stroke
				(width 0.1)
				(type default)
			)
			(layer "F.Fab")
		)
		(fp_line
			(start -0.12065 -0.2794)
			(end 0.12065 -0.2794)
			(stroke
				(width 0.1)
				(type default)
			)
			(layer "F.Fab")
		)
		(fp_line
			(start -0.12065 0.2794)
			(end -0.12065 0.3048)
			(stroke
				(width 0.1)
				(type default)
			)
			(layer "F.Fab")
		)
		(fp_line
			(start -0.12065 0.3048)
			(end -0.67945 0.3048)
			(stroke
				(width 0.1)
				(type default)
			)
			(layer "F.Fab")
		)
		(fp_line
			(start 0.120396 0.2794)
			(end -0.12065 0.2794)
			(stroke
				(width 0.1)
				(type default)
			)
			(layer "F.Fab")
		)
		(fp_line
			(start 0.120396 0.3048)
			(end 0.120396 0.2794)
			(stroke
				(width 0.1)
				(type default)
			)
			(layer "F.Fab")
		)
		(fp_line
			(start 0.12065 -0.3048)
			(end 0.67945 -0.3048)
			(stroke
				(width 0.1)
				(type default)
			)
			(layer "F.Fab")
		)
		(fp_line
			(start 0.12065 -0.2794)
			(end 0.12065 -0.3048)
			(stroke
				(width 0.1)
				(type default)
			)
			(layer "F.Fab")
		)
		(fp_line
			(start 0.67945 -0.3048)
			(end 0.67945 0.3048)
			(stroke
				(width 0.1)
				(type default)
			)
			(layer "F.Fab")
		)
		(fp_line
			(start 0.67945 0.3048)
			(end 0.120396 0.3048)
			(stroke
				(width 0.1)
				(type default)
			)
			(layer "F.Fab")
		)
		(pad "1" smd circle
			(at -0.40005 0)
			(size 0 0)
			(layers "F.Cu" "F.Mask" "F.Paste")
			(net "P3V3_AUX")
		)
		(pad "2" smd circle
			(at 0.40005 0)
			(size 0 0)
			(layers "F.Cu" "F.Mask" "F.Paste")
			(net "GND")
		)
	)
	(footprint ""
		(layer "F.Cu")
		(at 194.08902 -29.12872 -90)
		(property "Reference" "R4708"
			(at 0 0 270)
			(layer "F.SilkS")
			(hide yes)
			(effects
				(font
					(size 1.27 1.27)
				)
			)
		)
		(property "Value" ""
			(at 0 0 270)
			(layer "F.Fab")
			(effects
				(font
					(size 1.27 1.27)
				)
			)
		)
		(duplicate_pad_numbers_are_jumpers no)
		(fp_line
			(start -0.7874 0.4064)
			(end -0.7874 -0.4064)
			(stroke
				(width 0.1524)
				(type default)
			)
			(layer "F.SilkS")
		)
		(fp_line
			(start 0.7874 0.4064)
			(end -0.7874 0.4064)
			(stroke
				(width 0.1524)
				(type default)
			)
			(layer "F.SilkS")
		)
		(fp_line
			(start -0.7874 -0.4064)
			(end 0.7874 -0.4064)
			(stroke
				(width 0.1524)
				(type default)
			)
			(layer "F.SilkS")
		)
		(fp_line
			(start 0.7874 -0.4064)
			(end 0.7874 0.4064)
			(stroke
				(width 0.1524)
				(type default)
			)
			(layer "F.SilkS")
		)
		(fp_line
			(start -0.67945 0.3048)
			(end -0.67945 -0.305054)
			(stroke
				(width 0.1)
				(type default)
			)
			(layer "F.Fab")
		)
		(fp_line
			(start -0.12065 0.3048)
			(end -0.67945 0.3048)
			(stroke
				(width 0.1)
				(type default)
			)
			(layer "F.Fab")
		)
		(fp_line
			(start 0.120396 0.3048)
			(end 0.120396 0.2794)
			(stroke
				(width 0.1)
				(type default)
			)
			(layer "F.Fab")
		)
		(fp_line
			(start 0.67945 0.3048)
			(end 0.120396 0.3048)
			(stroke
				(width 0.1)
				(type default)
			)
			(layer "F.Fab")
		)
		(fp_line
			(start -0.12065 0.2794)
			(end -0.12065 0.3048)
			(stroke
				(width 0.1)
				(type default)
			)
			(layer "F.Fab")
		)
		(fp_line
			(start 0.120396 0.2794)
			(end -0.12065 0.2794)
			(stroke
				(width 0.1)
				(type default)
			)
			(layer "F.Fab")
		)
		(fp_line
			(start -0.12065 -0.2794)
			(end 0.12065 -0.2794)
			(stroke
				(width 0.1)
				(type default)
			)
			(layer "F.Fab")
		)
		(fp_line
			(start 0.12065 -0.2794)
			(end 0.12065 -0.3048)
			(stroke
				(width 0.1)
				(type default)
			)
			(layer "F.Fab")
		)
		(fp_line
			(start 0.12065 -0.3048)
			(end 0.67945 -0.3048)
			(stroke
				(width 0.1)
				(type default)
			)
			(layer "F.Fab")
		)
		(fp_line
			(start 0.67945 -0.3048)
			(end 0.67945 0.3048)
			(stroke
				(width 0.1)
				(type default)
			)
			(layer "F.Fab")
		)
		(fp_line
			(start -0.67945 -0.305054)
			(end -0.12065 -0.305054)
			(stroke
				(width 0.1)
				(type default)
			)
			(layer "F.Fab")
		)
		(fp_line
			(start -0.12065 -0.305054)
			(end -0.12065 -0.2794)
			(stroke
				(width 0.1)
				(type default)
			)
			(layer "F.Fab")
		)
		(pad "1" smd circle
			(at -0.40005 0 270)
			(size 0 0)
			(layers "F.Cu" "F.Mask" "F.Paste")
			(net "P12V_SCM_FAULT_N")
		)
		(pad "2" smd circle
			(at 0.40005 0 270)
			(size 0 0)
			(layers "F.Cu" "F.Mask" "F.Paste")
			(net "P12V_SCM_FAULT_R_N")
		)
	)
	(footprint ""
		(layer "F.Cu")
		(at 253.97841 -44.849542 90)
		(property "Reference" "PR3970"
			(at 0 0 90)
			(layer "F.SilkS")
			(hide yes)
			(effects
				(font
					(size 1.27 1.27)
				)
			)
		)
		(property "Value" ""
			(at 0 0 90)
			(layer "F.Fab")
			(effects
				(font
					(size 1.27 1.27)
				)
			)
		)
		(duplicate_pad_numbers_are_jumpers no)
		(fp_line
			(start 0.7874 -0.4064)
			(end 0.7874 0.4064)
			(stroke
				(width 0.1524)
				(type default)
			)
			(layer "F.SilkS")
		)
		(fp_line
			(start -0.7874 -0.4064)
			(end 0.7874 -0.4064)
			(stroke
				(width 0.1524)
				(type default)
			)
			(layer "F.SilkS")
		)
		(fp_line
			(start 0.7874 0.4064)
			(end -0.7874 0.4064)
			(stroke
				(width 0.1524)
				(type default)
			)
			(layer "F.SilkS")
		)
		(fp_line
			(start -0.7874 0.4064)
			(end -0.7874 -0.4064)
			(stroke
				(width 0.1524)
				(type default)
			)
			(layer "F.SilkS")
		)
		(fp_line
			(start -0.12065 -0.305054)
			(end -0.12065 -0.2794)
			(stroke
				(width 0.1)
				(type default)
			)
			(layer "F.Fab")
		)
		(fp_line
			(start -0.67945 -0.305054)
			(end -0.12065 -0.305054)
			(stroke
				(width 0.1)
				(type default)
			)
			(layer "F.Fab")
		)
		(fp_line
			(start 0.67945 -0.3048)
			(end 0.67945 0.3048)
			(stroke
				(width 0.1)
				(type default)
			)
			(layer "F.Fab")
		)
		(fp_line
			(start 0.12065 -0.3048)
			(end 0.67945 -0.3048)
			(stroke
				(width 0.1)
				(type default)
			)
			(layer "F.Fab")
		)
		(fp_line
			(start 0.12065 -0.2794)
			(end 0.12065 -0.3048)
			(stroke
				(width 0.1)
				(type default)
			)
			(layer "F.Fab")
		)
		(fp_line
			(start -0.12065 -0.2794)
			(end 0.12065 -0.2794)
			(stroke
				(width 0.1)
				(type default)
			)
			(layer "F.Fab")
		)
		(fp_line
			(start 0.120396 0.2794)
			(end -0.12065 0.2794)
			(stroke
				(width 0.1)
				(type default)
			)
			(layer "F.Fab")
		)
		(fp_line
			(start -0.12065 0.2794)
			(end -0.12065 0.3048)
			(stroke
				(width 0.1)
				(type default)
			)
			(layer "F.Fab")
		)
		(fp_line
			(start 0.67945 0.3048)
			(end 0.120396 0.3048)
			(stroke
				(width 0.1)
				(type default)
			)
			(layer "F.Fab")
		)
		(fp_line
			(start 0.120396 0.3048)
			(end 0.120396 0.2794)
			(stroke
				(width 0.1)
				(type default)
			)
			(layer "F.Fab")
		)
		(fp_line
			(start -0.12065 0.3048)
			(end -0.67945 0.3048)
			(stroke
				(width 0.1)
				(type default)
			)
			(layer "F.Fab")
		)
		(fp_line
			(start -0.67945 0.3048)
			(end -0.67945 -0.305054)
			(stroke
				(width 0.1)
				(type default)
			)
			(layer "F.Fab")
		)
		(pad "1" smd circle
			(at -0.40005 0 90)
			(size 0 0)
			(layers "F.Cu" "F.Mask" "F.Paste")
			(net "P12V_E1S_SENSE_0")
		)
		(pad "2" smd circle
			(at 0.40005 0 90)
			(size 0 0)
			(layers "F.Cu" "F.Mask" "F.Paste")
			(net "GND")
		)
	)
	(footprint ""
		(layer "F.Cu")
		(at 315.110622 -53.203348 180)
		(property "Reference" "R372"
			(at 0 0 180)
			(layer "F.SilkS")
			(hide yes)
			(effects
				(font
					(size 1.27 1.27)
				)
			)
		)
		(property "Value" ""
			(at 0 0 180)
			(layer "F.Fab")
			(effects
				(font
					(size 1.27 1.27)
				)
			)
		)
		(duplicate_pad_numbers_are_jumpers no)
		(fp_line
			(start 0.7874 0.4064)
			(end -0.7874 0.4064)
			(stroke
				(width 0.1524)
				(type default)
			)
			(layer "F.SilkS")
		)
		(fp_line
			(start 0.7874 -0.4064)
			(end 0.7874 0.4064)
			(stroke
				(width 0.1524)
				(type default)
			)
			(layer "F.SilkS")
		)
		(fp_line
			(start -0.7874 0.4064)
			(end -0.7874 -0.4064)
			(stroke
				(width 0.1524)
				(type default)
			)
			(layer "F.SilkS")
		)
		(fp_line
			(start -0.7874 -0.4064)
			(end 0.7874 -0.4064)
			(stroke
				(width 0.1524)
				(type default)
			)
			(layer "F.SilkS")
		)
		(fp_line
			(start 0.67945 0.3048)
			(end 0.120396 0.3048)
			(stroke
				(width 0.1)
				(type default)
			)
			(layer "F.Fab")
		)
		(fp_line
			(start 0.67945 -0.3048)
			(end 0.67945 0.3048)
			(stroke
				(width 0.1)
				(type default)
			)
			(layer "F.Fab")
		)
		(fp_line
			(start 0.12065 -0.2794)
			(end 0.12065 -0.3048)
			(stroke
				(width 0.1)
				(type default)
			)
			(layer "F.Fab")
		)
		(fp_line
			(start 0.12065 -0.3048)
			(end 0.67945 -0.3048)
			(stroke
				(width 0.1)
				(type default)
			)
			(layer "F.Fab")
		)
		(fp_line
			(start 0.120396 0.3048)
			(end 0.120396 0.2794)
			(stroke
				(width 0.1)
				(type default)
			)
			(layer "F.Fab")
		)
		(fp_line
			(start 0.120396 0.2794)
			(end -0.12065 0.2794)
			(stroke
				(width 0.1)
				(type default)
			)
			(layer "F.Fab")
		)
		(fp_line
			(start -0.12065 0.3048)
			(end -0.67945 0.3048)
			(stroke
				(width 0.1)
				(type default)
			)
			(layer "F.Fab")
		)
		(fp_line
			(start -0.12065 0.2794)
			(end -0.12065 0.3048)
			(stroke
				(width 0.1)
				(type default)
			)
			(layer "F.Fab")
		)
		(fp_line
			(start -0.12065 -0.2794)
			(end 0.12065 -0.2794)
			(stroke
				(width 0.1)
				(type default)
			)
			(layer "F.Fab")
		)
		(fp_line
			(start -0.12065 -0.305054)
			(end -0.12065 -0.2794)
			(stroke
				(width 0.1)
				(type default)
			)
			(layer "F.Fab")
		)
		(fp_line
			(start -0.67945 0.3048)
			(end -0.67945 -0.305054)
			(stroke
				(width 0.1)
				(type default)
			)
			(layer "F.Fab")
		)
		(fp_line
			(start -0.67945 -0.305054)
			(end -0.12065 -0.305054)
			(stroke
				(width 0.1)
				(type default)
			)
			(layer "F.Fab")
		)
		(pad "1" smd circle
			(at -0.40005 0 180)
			(size 0 0)
			(layers "F.Cu" "F.Mask" "F.Paste")
			(net "FM_PCH_BOOT_BIOS_STRAP")
		)
		(pad "2" smd circle
			(at 0.40005 0 180)
			(size 0 0)
			(layers "F.Cu" "F.Mask" "F.Paste")
			(net "GND")
		)
	)
	(footprint ""
		(layer "F.Cu")
		(at 221.67088 -43.525948 180)
		(property "Reference" "R3530"
			(at 0 0 180)
			(layer "F.SilkS")
			(hide yes)
			(effects
				(font
					(size 1.27 1.27)
				)
			)
		)
		(property "Value" ""
			(at 0 0 180)
			(layer "F.Fab")
			(effects
				(font
					(size 1.27 1.27)
				)
			)
		)
		(duplicate_pad_numbers_are_jumpers no)
		(fp_line
			(start 0.7874 0.4064)
			(end -0.7874 0.4064)
			(stroke
				(width 0.1524)
				(type default)
			)
			(layer "F.SilkS")
		)
		(fp_line
			(start 0.7874 -0.4064)
			(end 0.7874 0.4064)
			(stroke
				(width 0.1524)
				(type default)
			)
			(layer "F.SilkS")
		)
		(fp_line
			(start -0.7874 0.4064)
			(end -0.7874 -0.4064)
			(stroke
				(width 0.1524)
				(type default)
			)
			(layer "F.SilkS")
		)
		(fp_line
			(start -0.7874 -0.4064)
			(end 0.7874 -0.4064)
			(stroke
				(width 0.1524)
				(type default)
			)
			(layer "F.SilkS")
		)
		(fp_line
			(start 0.67945 0.3048)
			(end 0.120396 0.3048)
			(stroke
				(width 0.1)
				(type default)
			)
			(layer "F.Fab")
		)
		(fp_line
			(start 0.67945 -0.3048)
			(end 0.67945 0.3048)
			(stroke
				(width 0.1)
				(type default)
			)
			(layer "F.Fab")
		)
		(fp_line
			(start 0.12065 -0.2794)
			(end 0.12065 -0.3048)
			(stroke
				(width 0.1)
				(type default)
			)
			(layer "F.Fab")
		)
		(fp_line
			(start 0.12065 -0.3048)
			(end 0.67945 -0.3048)
			(stroke
				(width 0.1)
				(type default)
			)
			(layer "F.Fab")
		)
		(fp_line
			(start 0.120396 0.3048)
			(end 0.120396 0.2794)
			(stroke
				(width 0.1)
				(type default)
			)
			(layer "F.Fab")
		)
		(fp_line
			(start 0.120396 0.2794)
			(end -0.12065 0.2794)
			(stroke
				(width 0.1)
				(type default)
			)
			(layer "F.Fab")
		)
		(fp_line
			(start -0.12065 0.3048)
			(end -0.67945 0.3048)
			(stroke
				(width 0.1)
				(type default)
			)
			(layer "F.Fab")
		)
		(fp_line
			(start -0.12065 0.2794)
			(end -0.12065 0.3048)
			(stroke
				(width 0.1)
				(type default)
			)
			(layer "F.Fab")
		)
		(fp_line
			(start -0.12065 -0.2794)
			(end 0.12065 -0.2794)
			(stroke
				(width 0.1)
				(type default)
			)
			(layer "F.Fab")
		)
		(fp_line
			(start -0.12065 -0.305054)
			(end -0.12065 -0.2794)
			(stroke
				(width 0.1)
				(type default)
			)
			(layer "F.Fab")
		)
		(fp_line
			(start -0.67945 0.3048)
			(end -0.67945 -0.305054)
			(stroke
				(width 0.1)
				(type default)
			)
			(layer "F.Fab")
		)
		(fp_line
			(start -0.67945 -0.305054)
			(end -0.12065 -0.305054)
			(stroke
				(width 0.1)
				(type default)
			)
			(layer "F.Fab")
		)
		(pad "1" smd circle
			(at -0.40005 0 180)
			(size 0 0)
			(layers "F.Cu" "F.Mask" "F.Paste")
			(net "P3V3_E1S_0")
		)
		(pad "2" smd circle
			(at 0.40005 0 180)
			(size 0 0)
			(layers "F.Cu" "F.Mask" "F.Paste")
			(net "SMB_E1S_3V3AUX_ISO_SCL_R")
		)
	)
	(footprint ""
		(layer "F.Cu")
		(at 120.37822 -419.415468)
		(property "Reference" "R3315"
			(at 0 0 0)
			(layer "F.SilkS")
			(hide yes)
			(effects
				(font
					(size 1.27 1.27)
				)
			)
		)
		(property "Value" ""
			(at 0 0 0)
			(layer "F.Fab")
			(effects
				(font
					(size 1.27 1.27)
				)
			)
		)
		(duplicate_pad_numbers_are_jumpers no)
		(fp_line
			(start -0.7874 -0.4064)
			(end 0.7874 -0.4064)
			(stroke
				(width 0.1524)
				(type default)
			)
			(layer "F.SilkS")
		)
		(fp_line
			(start -0.7874 0.4064)
			(end -0.7874 -0.4064)
			(stroke
				(width 0.1524)
				(type default)
			)
			(layer "F.SilkS")
		)
		(fp_line
			(start 0.7874 -0.4064)
			(end 0.7874 0.4064)
			(stroke
				(width 0.1524)
				(type default)
			)
			(layer "F.SilkS")
		)
		(fp_line
			(start 0.7874 0.4064)
			(end -0.7874 0.4064)
			(stroke
				(width 0.1524)
				(type default)
			)
			(layer "F.SilkS")
		)
		(fp_line
			(start -0.67945 -0.305054)
			(end -0.12065 -0.305054)
			(stroke
				(width 0.1)
				(type default)
			)
			(layer "F.Fab")
		)
		(fp_line
			(start -0.67945 0.3048)
			(end -0.67945 -0.305054)
			(stroke
				(width 0.1)
				(type default)
			)
			(layer "F.Fab")
		)
		(fp_line
			(start -0.12065 -0.305054)
			(end -0.12065 -0.2794)
			(stroke
				(width 0.1)
				(type default)
			)
			(layer "F.Fab")
		)
		(fp_line
			(start -0.12065 -0.2794)
			(end 0.12065 -0.2794)
			(stroke
				(width 0.1)
				(type default)
			)
			(layer "F.Fab")
		)
		(fp_line
			(start -0.12065 0.2794)
			(end -0.12065 0.3048)
			(stroke
				(width 0.1)
				(type default)
			)
			(layer "F.Fab")
		)
		(fp_line
			(start -0.12065 0.3048)
			(end -0.67945 0.3048)
			(stroke
				(width 0.1)
				(type default)
			)
			(layer "F.Fab")
		)
		(fp_line
			(start 0.120396 0.2794)
			(end -0.12065 0.2794)
			(stroke
				(width 0.1)
				(type default)
			)
			(layer "F.Fab")
		)
		(fp_line
			(start 0.120396 0.3048)
			(end 0.120396 0.2794)
			(stroke
				(width 0.1)
				(type default)
			)
			(layer "F.Fab")
		)
		(fp_line
			(start 0.12065 -0.3048)
			(end 0.67945 -0.3048)
			(stroke
				(width 0.1)
				(type default)
			)
			(layer "F.Fab")
		)
		(fp_line
			(start 0.12065 -0.2794)
			(end 0.12065 -0.3048)
			(stroke
				(width 0.1)
				(type default)
			)
			(layer "F.Fab")
		)
		(fp_line
			(start 0.67945 -0.3048)
			(end 0.67945 0.3048)
			(stroke
				(width 0.1)
				(type default)
			)
			(layer "F.Fab")
		)
		(fp_line
			(start 0.67945 0.3048)
			(end 0.120396 0.3048)
			(stroke
				(width 0.1)
				(type default)
			)
			(layer "F.Fab")
		)
		(pad "1" smd circle
			(at -0.40005 0)
			(size 0 0)
			(layers "F.Cu" "F.Mask" "F.Paste")
			(net "GPU_FPGA_RST_R1_BUF_N")
		)
		(pad "2" smd circle
			(at 0.40005 0)
			(size 0 0)
			(layers "F.Cu" "F.Mask" "F.Paste")
			(net "GPU_FPGA_RST_R_BUF_N")
		)
	)
	(footprint ""
		(layer "F.Cu")
		(at 124.107194 -402.371052 -90)
		(property "Reference" "C744"
			(at 0 0 270)
			(layer "F.SilkS")
			(hide yes)
			(effects
				(font
					(size 1.27 1.27)
				)
			)
		)
		(property "Value" ""
			(at 0 0 270)
			(layer "F.Fab")
			(effects
				(font
					(size 1.27 1.27)
				)
			)
		)
		(duplicate_pad_numbers_are_jumpers no)
		(fp_line
			(start -0.299974 0.150114)
			(end -0.299974 -0.150114)
			(stroke
				(width 0.1)
				(type default)
			)
			(layer "F.Fab")
		)
		(fp_line
			(start 0.299974 0.150114)
			(end -0.299974 0.150114)
			(stroke
				(width 0.1)
				(type default)
			)
			(layer "F.Fab")
		)
		(fp_line
			(start -0.299974 -0.150114)
			(end 0.299974 -0.150114)
			(stroke
				(width 0.1)
				(type default)
			)
			(layer "F.Fab")
		)
		(fp_line
			(start 0.299974 -0.150114)
			(end 0.299974 0.150114)
			(stroke
				(width 0.1)
				(type default)
			)
			(layer "F.Fab")
		)
		(pad "1" smd rect
			(at -0.2667 0 270)
			(size 0.3048 0.381)
			(layers "F.Cu" "F.Mask" "F.Paste")
			(net "P5E_CPU1_PE2_TX_C_DN<14>")
		)
		(pad "2" smd rect
			(at 0.2667 0 270)
			(size 0.3048 0.381)
			(layers "F.Cu" "F.Mask" "F.Paste")
			(net "P5E_CPU1_PE2_TX_DN<14>")
		)
	)
	(footprint ""
		(layer "F.Cu")
		(at 215.87714 -47.196248)
		(property "Reference" "R3586"
			(at 0 0 0)
			(layer "F.SilkS")
			(hide yes)
			(effects
				(font
					(size 1.27 1.27)
				)
			)
		)
		(property "Value" ""
			(at 0 0 0)
			(layer "F.Fab")
			(effects
				(font
					(size 1.27 1.27)
				)
			)
		)
		(duplicate_pad_numbers_are_jumpers no)
		(fp_line
			(start -0.7874 -0.4064)
			(end 0.7874 -0.4064)
			(stroke
				(width 0.1524)
				(type default)
			)
			(layer "F.SilkS")
		)
		(fp_line
			(start -0.7874 0.4064)
			(end -0.7874 -0.4064)
			(stroke
				(width 0.1524)
				(type default)
			)
			(layer "F.SilkS")
		)
		(fp_line
			(start 0.7874 -0.4064)
			(end 0.7874 0.4064)
			(stroke
				(width 0.1524)
				(type default)
			)
			(layer "F.SilkS")
		)
		(fp_line
			(start 0.7874 0.4064)
			(end -0.7874 0.4064)
			(stroke
				(width 0.1524)
				(type default)
			)
			(layer "F.SilkS")
		)
		(fp_line
			(start -0.67945 -0.305054)
			(end -0.12065 -0.305054)
			(stroke
				(width 0.1)
				(type default)
			)
			(layer "F.Fab")
		)
		(fp_line
			(start -0.67945 0.3048)
			(end -0.67945 -0.305054)
			(stroke
				(width 0.1)
				(type default)
			)
			(layer "F.Fab")
		)
		(fp_line
			(start -0.12065 -0.305054)
			(end -0.12065 -0.2794)
			(stroke
				(width 0.1)
				(type default)
			)
			(layer "F.Fab")
		)
		(fp_line
			(start -0.12065 -0.2794)
			(end 0.12065 -0.2794)
			(stroke
				(width 0.1)
				(type default)
			)
			(layer "F.Fab")
		)
		(fp_line
			(start -0.12065 0.2794)
			(end -0.12065 0.3048)
			(stroke
				(width 0.1)
				(type default)
			)
			(layer "F.Fab")
		)
		(fp_line
			(start -0.12065 0.3048)
			(end -0.67945 0.3048)
			(stroke
				(width 0.1)
				(type default)
			)
			(layer "F.Fab")
		)
		(fp_line
			(start 0.120396 0.2794)
			(end -0.12065 0.2794)
			(stroke
				(width 0.1)
				(type default)
			)
			(layer "F.Fab")
		)
		(fp_line
			(start 0.120396 0.3048)
			(end 0.120396 0.2794)
			(stroke
				(width 0.1)
				(type default)
			)
			(layer "F.Fab")
		)
		(fp_line
			(start 0.12065 -0.3048)
			(end 0.67945 -0.3048)
			(stroke
				(width 0.1)
				(type default)
			)
			(layer "F.Fab")
		)
		(fp_line
			(start 0.12065 -0.2794)
			(end 0.12065 -0.3048)
			(stroke
				(width 0.1)
				(type default)
			)
			(layer "F.Fab")
		)
		(fp_line
			(start 0.67945 -0.3048)
			(end 0.67945 0.3048)
			(stroke
				(width 0.1)
				(type default)
			)
			(layer "F.Fab")
		)
		(fp_line
			(start 0.67945 0.3048)
			(end 0.120396 0.3048)
			(stroke
				(width 0.1)
				(type default)
			)
			(layer "F.Fab")
		)
		(pad "1" smd circle
			(at -0.40005 0)
			(size 0 0)
			(layers "F.Cu" "F.Mask" "F.Paste")
			(net "SMB_INA230_3V3AUX_SCL")
		)
		(pad "2" smd circle
			(at 0.40005 0)
			(size 0 0)
			(layers "F.Cu" "F.Mask" "F.Paste")
			(net "SMB_INA230_1_3V3AUX_SCL_R")
		)
	)
	(footprint ""
		(layer "F.Cu")
		(at 166.01694 -30.584648)
		(property "Reference" "R4177"
			(at 0 0 0)
			(layer "F.SilkS")
			(hide yes)
			(effects
				(font
					(size 1.27 1.27)
				)
			)
		)
		(property "Value" ""
			(at 0 0 0)
			(layer "F.Fab")
			(effects
				(font
					(size 1.27 1.27)
				)
			)
		)
		(duplicate_pad_numbers_are_jumpers no)
		(fp_line
			(start -0.7874 -0.4064)
			(end 0.7874 -0.4064)
			(stroke
				(width 0.1524)
				(type default)
			)
			(layer "F.SilkS")
		)
		(fp_line
			(start -0.7874 0.4064)
			(end -0.7874 -0.4064)
			(stroke
				(width 0.1524)
				(type default)
			)
			(layer "F.SilkS")
		)
		(fp_line
			(start 0.7874 -0.4064)
			(end 0.7874 0.4064)
			(stroke
				(width 0.1524)
				(type default)
			)
			(layer "F.SilkS")
		)
		(fp_line
			(start 0.7874 0.4064)
			(end -0.7874 0.4064)
			(stroke
				(width 0.1524)
				(type default)
			)
			(layer "F.SilkS")
		)
		(fp_line
			(start -0.67945 -0.305054)
			(end -0.12065 -0.305054)
			(stroke
				(width 0.1)
				(type default)
			)
			(layer "F.Fab")
		)
		(fp_line
			(start -0.67945 0.3048)
			(end -0.67945 -0.305054)
			(stroke
				(width 0.1)
				(type default)
			)
			(layer "F.Fab")
		)
		(fp_line
			(start -0.12065 -0.305054)
			(end -0.12065 -0.2794)
			(stroke
				(width 0.1)
				(type default)
			)
			(layer "F.Fab")
		)
		(fp_line
			(start -0.12065 -0.2794)
			(end 0.12065 -0.2794)
			(stroke
				(width 0.1)
				(type default)
			)
			(layer "F.Fab")
		)
		(fp_line
			(start -0.12065 0.2794)
			(end -0.12065 0.3048)
			(stroke
				(width 0.1)
				(type default)
			)
			(layer "F.Fab")
		)
		(fp_line
			(start -0.12065 0.3048)
			(end -0.67945 0.3048)
			(stroke
				(width 0.1)
				(type default)
			)
			(layer "F.Fab")
		)
		(fp_line
			(start 0.120396 0.2794)
			(end -0.12065 0.2794)
			(stroke
				(width 0.1)
				(type default)
			)
			(layer "F.Fab")
		)
		(fp_line
			(start 0.120396 0.3048)
			(end 0.120396 0.2794)
			(stroke
				(width 0.1)
				(type default)
			)
			(layer "F.Fab")
		)
		(fp_line
			(start 0.12065 -0.3048)
			(end 0.67945 -0.3048)
			(stroke
				(width 0.1)
				(type default)
			)
			(layer "F.Fab")
		)
		(fp_line
			(start 0.12065 -0.2794)
			(end 0.12065 -0.3048)
			(stroke
				(width 0.1)
				(type default)
			)
			(layer "F.Fab")
		)
		(fp_line
			(start 0.67945 -0.3048)
			(end 0.67945 0.3048)
			(stroke
				(width 0.1)
				(type default)
			)
			(layer "F.Fab")
		)
		(fp_line
			(start 0.67945 0.3048)
			(end 0.120396 0.3048)
			(stroke
				(width 0.1)
				(type default)
			)
			(layer "F.Fab")
		)
		(pad "1" smd circle
			(at -0.40005 0)
			(size 0 0)
			(layers "F.Cu" "F.Mask" "F.Paste")
			(net "FM_ESPI_PLD_R_EN_BUF_R")
		)
		(pad "2" smd circle
			(at 0.40005 0)
			(size 0 0)
			(layers "F.Cu" "F.Mask" "F.Paste")
			(net "FM_ESPI_PLD_R_EN_BUF")
		)
	)
	(footprint ""
		(layer "F.Cu")
		(at 112.40008 -122.132598 90)
		(property "Reference" "R934"
			(at 0 0 90)
			(layer "F.SilkS")
			(hide yes)
			(effects
				(font
					(size 1.27 1.27)
				)
			)
		)
		(property "Value" ""
			(at 0 0 90)
			(layer "F.Fab")
			(effects
				(font
					(size 1.27 1.27)
				)
			)
		)
		(duplicate_pad_numbers_are_jumpers no)
		(fp_line
			(start 0.7874 -0.4064)
			(end 0.7874 0.4064)
			(stroke
				(width 0.1524)
				(type default)
			)
			(layer "F.SilkS")
		)
		(fp_line
			(start -0.7874 -0.4064)
			(end 0.7874 -0.4064)
			(stroke
				(width 0.1524)
				(type default)
			)
			(layer "F.SilkS")
		)
		(fp_line
			(start 0.7874 0.4064)
			(end -0.7874 0.4064)
			(stroke
				(width 0.1524)
				(type default)
			)
			(layer "F.SilkS")
		)
		(fp_line
			(start -0.7874 0.4064)
			(end -0.7874 -0.4064)
			(stroke
				(width 0.1524)
				(type default)
			)
			(layer "F.SilkS")
		)
		(fp_line
			(start -0.12065 -0.305054)
			(end -0.12065 -0.2794)
			(stroke
				(width 0.1)
				(type default)
			)
			(layer "F.Fab")
		)
		(fp_line
			(start -0.67945 -0.305054)
			(end -0.12065 -0.305054)
			(stroke
				(width 0.1)
				(type default)
			)
			(layer "F.Fab")
		)
		(fp_line
			(start 0.67945 -0.3048)
			(end 0.67945 0.3048)
			(stroke
				(width 0.1)
				(type default)
			)
			(layer "F.Fab")
		)
		(fp_line
			(start 0.12065 -0.3048)
			(end 0.67945 -0.3048)
			(stroke
				(width 0.1)
				(type default)
			)
			(layer "F.Fab")
		)
		(fp_line
			(start 0.12065 -0.2794)
			(end 0.12065 -0.3048)
			(stroke
				(width 0.1)
				(type default)
			)
			(layer "F.Fab")
		)
		(fp_line
			(start -0.12065 -0.2794)
			(end 0.12065 -0.2794)
			(stroke
				(width 0.1)
				(type default)
			)
			(layer "F.Fab")
		)
		(fp_line
			(start 0.120396 0.2794)
			(end -0.12065 0.2794)
			(stroke
				(width 0.1)
				(type default)
			)
			(layer "F.Fab")
		)
		(fp_line
			(start -0.12065 0.2794)
			(end -0.12065 0.3048)
			(stroke
				(width 0.1)
				(type default)
			)
			(layer "F.Fab")
		)
		(fp_line
			(start 0.67945 0.3048)
			(end 0.120396 0.3048)
			(stroke
				(width 0.1)
				(type default)
			)
			(layer "F.Fab")
		)
		(fp_line
			(start 0.120396 0.3048)
			(end 0.120396 0.2794)
			(stroke
				(width 0.1)
				(type default)
			)
			(layer "F.Fab")
		)
		(fp_line
			(start -0.12065 0.3048)
			(end -0.67945 0.3048)
			(stroke
				(width 0.1)
				(type default)
			)
			(layer "F.Fab")
		)
		(fp_line
			(start -0.67945 0.3048)
			(end -0.67945 -0.305054)
			(stroke
				(width 0.1)
				(type default)
			)
			(layer "F.Fab")
		)
		(pad "1" smd circle
			(at -0.40005 0 90)
			(size 0 0)
			(layers "F.Cu" "F.Mask" "F.Paste")
			(net "RST_CPU0_DRAM_CD_N")
		)
		(pad "2" smd circle
			(at 0.40005 0 90)
			(size 0 0)
			(layers "F.Cu" "F.Mask" "F.Paste")
			(net "GND")
		)
	)
	(footprint ""
		(layer "F.Cu")
		(at 22.364192 -399.532094 90)
		(property "Reference" "R3274"
			(at 0 0 90)
			(layer "F.SilkS")
			(hide yes)
			(effects
				(font
					(size 1.27 1.27)
				)
			)
		)
		(property "Value" ""
			(at 0 0 90)
			(layer "F.Fab")
			(effects
				(font
					(size 1.27 1.27)
				)
			)
		)
		(duplicate_pad_numbers_are_jumpers no)
		(fp_line
			(start 0.7874 -0.4064)
			(end 0.7874 0.4064)
			(stroke
				(width 0.1524)
				(type default)
			)
			(layer "F.SilkS")
		)
		(fp_line
			(start -0.7874 -0.4064)
			(end 0.7874 -0.4064)
			(stroke
				(width 0.1524)
				(type default)
			)
			(layer "F.SilkS")
		)
		(fp_line
			(start 0.7874 0.4064)
			(end -0.7874 0.4064)
			(stroke
				(width 0.1524)
				(type default)
			)
			(layer "F.SilkS")
		)
		(fp_line
			(start -0.7874 0.4064)
			(end -0.7874 -0.4064)
			(stroke
				(width 0.1524)
				(type default)
			)
			(layer "F.SilkS")
		)
		(fp_line
			(start -0.12065 -0.305054)
			(end -0.12065 -0.2794)
			(stroke
				(width 0.1)
				(type default)
			)
			(layer "F.Fab")
		)
		(fp_line
			(start -0.67945 -0.305054)
			(end -0.12065 -0.305054)
			(stroke
				(width 0.1)
				(type default)
			)
			(layer "F.Fab")
		)
		(fp_line
			(start 0.67945 -0.3048)
			(end 0.67945 0.3048)
			(stroke
				(width 0.1)
				(type default)
			)
			(layer "F.Fab")
		)
		(fp_line
			(start 0.12065 -0.3048)
			(end 0.67945 -0.3048)
			(stroke
				(width 0.1)
				(type default)
			)
			(layer "F.Fab")
		)
		(fp_line
			(start 0.12065 -0.2794)
			(end 0.12065 -0.3048)
			(stroke
				(width 0.1)
				(type default)
			)
			(layer "F.Fab")
		)
		(fp_line
			(start -0.12065 -0.2794)
			(end 0.12065 -0.2794)
			(stroke
				(width 0.1)
				(type default)
			)
			(layer "F.Fab")
		)
		(fp_line
			(start 0.120396 0.2794)
			(end -0.12065 0.2794)
			(stroke
				(width 0.1)
				(type default)
			)
			(layer "F.Fab")
		)
		(fp_line
			(start -0.12065 0.2794)
			(end -0.12065 0.3048)
			(stroke
				(width 0.1)
				(type default)
			)
			(layer "F.Fab")
		)
		(fp_line
			(start 0.67945 0.3048)
			(end 0.120396 0.3048)
			(stroke
				(width 0.1)
				(type default)
			)
			(layer "F.Fab")
		)
		(fp_line
			(start 0.120396 0.3048)
			(end 0.120396 0.2794)
			(stroke
				(width 0.1)
				(type default)
			)
			(layer "F.Fab")
		)
		(fp_line
			(start -0.12065 0.3048)
			(end -0.67945 0.3048)
			(stroke
				(width 0.1)
				(type default)
			)
			(layer "F.Fab")
		)
		(fp_line
			(start -0.67945 0.3048)
			(end -0.67945 -0.305054)
			(stroke
				(width 0.1)
				(type default)
			)
			(layer "F.Fab")
		)
		(pad "1" smd circle
			(at -0.40005 0 90)
			(size 0 0)
			(layers "F.Cu" "F.Mask" "F.Paste")
			(net "FM_P2E_EQA0")
		)
		(pad "2" smd circle
			(at 0.40005 0 90)
			(size 0 0)
			(layers "F.Cu" "F.Mask" "F.Paste")
			(net "GND")
		)
	)
	(footprint ""
		(layer "F.Cu")
		(at 46.697138 -337.477608)
		(property "Reference" "PC415"
			(at 0 0 0)
			(layer "F.SilkS")
			(hide yes)
			(effects
				(font
					(size 1.27 1.27)
				)
			)
		)
		(property "Value" ""
			(at 0 0 0)
			(layer "F.Fab")
			(effects
				(font
					(size 1.27 1.27)
				)
			)
		)
		(duplicate_pad_numbers_are_jumpers no)
		(fp_line
			(start 2.750058 0.999998)
			(end -2.750058 0.999998)
			(stroke
				(width 0.1524)
				(type default)
			)
			(layer "F.SilkS")
		)
		(fp_circle
			(center 0 0.999998)
			(end 2.750058 0.999998)
			(stroke
				(width 0.1524)
				(type default)
			)
			(fill no)
			(layer "F.SilkS")
		)
		(fp_poly
			(pts
				(arc
					(start 2.750058 0.999998)
					(mid 0 3.750056)
					(end -2.750058 0.999998)
				)
			)
			(stroke
				(width 0)
				(type default)
			)
			(fill yes)
			(layer "F.SilkS")
		)
		(fp_circle
			(center 0 0.999998)
			(end 2.750058 0.999998)
			(stroke
				(width 0.1)
				(type default)
			)
			(fill no)
			(layer "F.Fab")
		)
		(pad "1" thru_hole rect
			(at 0 0)
			(size 1.5748 1.5748)
			(drill 1.0668)
			(layers "*.Cu" "*.Mask")
			(remove_unused_layers no)
			(net "PVCCFA_EHV_FIVRA_CPU1")
			(clearance 0)
			(padstack
				(mode front_inner_back)
				(layer "Inner"
					(shape circle)
					(size 1.5748 1.5748)
					(clearance 0)
				)
				(layer "B.Cu"
					(shape rect)
					(size 1.5748 1.5748)
					(clearance 0)
				)
			)
		)
		(pad "2" thru_hole circle
			(at 0 1.999996)
			(size 1.5748 1.5748)
			(drill 1.0668)
			(layers "*.Cu" "*.Mask")
			(remove_unused_layers no)
			(net "GND")
			(clearance 0)
		)
	)
	(footprint ""
		(layer "F.Cu")
		(at 171.50588 -133.695948 -90)
		(property "Reference" "R3048"
			(at 0 0 270)
			(layer "F.SilkS")
			(hide yes)
			(effects
				(font
					(size 1.27 1.27)
				)
			)
		)
		(property "Value" ""
			(at 0 0 270)
			(layer "F.Fab")
			(effects
				(font
					(size 1.27 1.27)
				)
			)
		)
		(duplicate_pad_numbers_are_jumpers no)
		(fp_line
			(start -0.7874 0.4064)
			(end -0.7874 -0.4064)
			(stroke
				(width 0.1524)
				(type default)
			)
			(layer "F.SilkS")
		)
		(fp_line
			(start 0.7874 0.4064)
			(end -0.7874 0.4064)
			(stroke
				(width 0.1524)
				(type default)
			)
			(layer "F.SilkS")
		)
		(fp_line
			(start -0.7874 -0.4064)
			(end 0.7874 -0.4064)
			(stroke
				(width 0.1524)
				(type default)
			)
			(layer "F.SilkS")
		)
		(fp_line
			(start 0.7874 -0.4064)
			(end 0.7874 0.4064)
			(stroke
				(width 0.1524)
				(type default)
			)
			(layer "F.SilkS")
		)
		(fp_line
			(start -0.67945 0.3048)
			(end -0.67945 -0.305054)
			(stroke
				(width 0.1)
				(type default)
			)
			(layer "F.Fab")
		)
		(fp_line
			(start -0.12065 0.3048)
			(end -0.67945 0.3048)
			(stroke
				(width 0.1)
				(type default)
			)
			(layer "F.Fab")
		)
		(fp_line
			(start 0.120396 0.3048)
			(end 0.120396 0.2794)
			(stroke
				(width 0.1)
				(type default)
			)
			(layer "F.Fab")
		)
		(fp_line
			(start 0.67945 0.3048)
			(end 0.120396 0.3048)
			(stroke
				(width 0.1)
				(type default)
			)
			(layer "F.Fab")
		)
		(fp_line
			(start -0.12065 0.2794)
			(end -0.12065 0.3048)
			(stroke
				(width 0.1)
				(type default)
			)
			(layer "F.Fab")
		)
		(fp_line
			(start 0.120396 0.2794)
			(end -0.12065 0.2794)
			(stroke
				(width 0.1)
				(type default)
			)
			(layer "F.Fab")
		)
		(fp_line
			(start -0.12065 -0.2794)
			(end 0.12065 -0.2794)
			(stroke
				(width 0.1)
				(type default)
			)
			(layer "F.Fab")
		)
		(fp_line
			(start 0.12065 -0.2794)
			(end 0.12065 -0.3048)
			(stroke
				(width 0.1)
				(type default)
			)
			(layer "F.Fab")
		)
		(fp_line
			(start 0.12065 -0.3048)
			(end 0.67945 -0.3048)
			(stroke
				(width 0.1)
				(type default)
			)
			(layer "F.Fab")
		)
		(fp_line
			(start 0.67945 -0.3048)
			(end 0.67945 0.3048)
			(stroke
				(width 0.1)
				(type default)
			)
			(layer "F.Fab")
		)
		(fp_line
			(start -0.67945 -0.305054)
			(end -0.12065 -0.305054)
			(stroke
				(width 0.1)
				(type default)
			)
			(layer "F.Fab")
		)
		(fp_line
			(start -0.12065 -0.305054)
			(end -0.12065 -0.2794)
			(stroke
				(width 0.1)
				(type default)
			)
			(layer "F.Fab")
		)
		(pad "1" smd circle
			(at -0.40005 0 270)
			(size 0 0)
			(layers "F.Cu" "F.Mask" "F.Paste")
			(net "MB0_P12V_STBY_PWRGD")
		)
		(pad "2" smd circle
			(at 0.40005 0 270)
			(size 0 0)
			(layers "F.Cu" "F.Mask" "F.Paste")
			(net "PWRGD_PS_PWROK")
		)
	)
	(footprint ""
		(layer "F.Cu")
		(at 148.98243 -75.350878)
		(property "Reference" "R2312"
			(at 0 0 0)
			(layer "F.SilkS")
			(hide yes)
			(effects
				(font
					(size 1.27 1.27)
				)
			)
		)
		(property "Value" ""
			(at 0 0 0)
			(layer "F.Fab")
			(effects
				(font
					(size 1.27 1.27)
				)
			)
		)
		(duplicate_pad_numbers_are_jumpers no)
		(fp_line
			(start -0.7874 -0.4064)
			(end 0.7874 -0.4064)
			(stroke
				(width 0.1524)
				(type default)
			)
			(layer "F.SilkS")
		)
		(fp_line
			(start -0.7874 0.4064)
			(end -0.7874 -0.4064)
			(stroke
				(width 0.1524)
				(type default)
			)
			(layer "F.SilkS")
		)
		(fp_line
			(start 0.7874 -0.4064)
			(end 0.7874 0.4064)
			(stroke
				(width 0.1524)
				(type default)
			)
			(layer "F.SilkS")
		)
		(fp_line
			(start 0.7874 0.4064)
			(end -0.7874 0.4064)
			(stroke
				(width 0.1524)
				(type default)
			)
			(layer "F.SilkS")
		)
		(fp_line
			(start -0.67945 -0.305054)
			(end -0.12065 -0.305054)
			(stroke
				(width 0.1)
				(type default)
			)
			(layer "F.Fab")
		)
		(fp_line
			(start -0.67945 0.3048)
			(end -0.67945 -0.305054)
			(stroke
				(width 0.1)
				(type default)
			)
			(layer "F.Fab")
		)
		(fp_line
			(start -0.12065 -0.305054)
			(end -0.12065 -0.2794)
			(stroke
				(width 0.1)
				(type default)
			)
			(layer "F.Fab")
		)
		(fp_line
			(start -0.12065 -0.2794)
			(end 0.12065 -0.2794)
			(stroke
				(width 0.1)
				(type default)
			)
			(layer "F.Fab")
		)
		(fp_line
			(start -0.12065 0.2794)
			(end -0.12065 0.3048)
			(stroke
				(width 0.1)
				(type default)
			)
			(layer "F.Fab")
		)
		(fp_line
			(start -0.12065 0.3048)
			(end -0.67945 0.3048)
			(stroke
				(width 0.1)
				(type default)
			)
			(layer "F.Fab")
		)
		(fp_line
			(start 0.120396 0.2794)
			(end -0.12065 0.2794)
			(stroke
				(width 0.1)
				(type default)
			)
			(layer "F.Fab")
		)
		(fp_line
			(start 0.120396 0.3048)
			(end 0.120396 0.2794)
			(stroke
				(width 0.1)
				(type default)
			)
			(layer "F.Fab")
		)
		(fp_line
			(start 0.12065 -0.3048)
			(end 0.67945 -0.3048)
			(stroke
				(width 0.1)
				(type default)
			)
			(layer "F.Fab")
		)
		(fp_line
			(start 0.12065 -0.2794)
			(end 0.12065 -0.3048)
			(stroke
				(width 0.1)
				(type default)
			)
			(layer "F.Fab")
		)
		(fp_line
			(start 0.67945 -0.3048)
			(end 0.67945 0.3048)
			(stroke
				(width 0.1)
				(type default)
			)
			(layer "F.Fab")
		)
		(fp_line
			(start 0.67945 0.3048)
			(end 0.120396 0.3048)
			(stroke
				(width 0.1)
				(type default)
			)
			(layer "F.Fab")
		)
		(pad "1" smd circle
			(at -0.40005 0)
			(size 0 0)
			(layers "F.Cu" "F.Mask" "F.Paste")
			(net "P3V3_AUX")
		)
		(pad "2" smd circle
			(at 0.40005 0)
			(size 0 0)
			(layers "F.Cu" "F.Mask" "F.Paste")
			(net "PCA9545_S3M_INT_N")
		)
	)
	(footprint ""
		(layer "F.Cu")
		(at 334.729074 -16.2052 -90)
		(property "Reference" "R1750"
			(at 0 0 270)
			(layer "F.SilkS")
			(hide yes)
			(effects
				(font
					(size 1.27 1.27)
				)
			)
		)
		(property "Value" ""
			(at 0 0 270)
			(layer "F.Fab")
			(effects
				(font
					(size 1.27 1.27)
				)
			)
		)
		(duplicate_pad_numbers_are_jumpers no)
		(fp_line
			(start -0.7874 0.4064)
			(end -0.7874 -0.4064)
			(stroke
				(width 0.1524)
				(type default)
			)
			(layer "F.SilkS")
		)
		(fp_line
			(start 0.7874 0.4064)
			(end -0.7874 0.4064)
			(stroke
				(width 0.1524)
				(type default)
			)
			(layer "F.SilkS")
		)
		(fp_line
			(start -0.7874 -0.4064)
			(end 0.7874 -0.4064)
			(stroke
				(width 0.1524)
				(type default)
			)
			(layer "F.SilkS")
		)
		(fp_line
			(start 0.7874 -0.4064)
			(end 0.7874 0.4064)
			(stroke
				(width 0.1524)
				(type default)
			)
			(layer "F.SilkS")
		)
		(fp_line
			(start -0.67945 0.3048)
			(end -0.67945 -0.305054)
			(stroke
				(width 0.1)
				(type default)
			)
			(layer "F.Fab")
		)
		(fp_line
			(start -0.12065 0.3048)
			(end -0.67945 0.3048)
			(stroke
				(width 0.1)
				(type default)
			)
			(layer "F.Fab")
		)
		(fp_line
			(start 0.120396 0.3048)
			(end 0.120396 0.2794)
			(stroke
				(width 0.1)
				(type default)
			)
			(layer "F.Fab")
		)
		(fp_line
			(start 0.67945 0.3048)
			(end 0.120396 0.3048)
			(stroke
				(width 0.1)
				(type default)
			)
			(layer "F.Fab")
		)
		(fp_line
			(start -0.12065 0.2794)
			(end -0.12065 0.3048)
			(stroke
				(width 0.1)
				(type default)
			)
			(layer "F.Fab")
		)
		(fp_line
			(start 0.120396 0.2794)
			(end -0.12065 0.2794)
			(stroke
				(width 0.1)
				(type default)
			)
			(layer "F.Fab")
		)
		(fp_line
			(start -0.12065 -0.2794)
			(end 0.12065 -0.2794)
			(stroke
				(width 0.1)
				(type default)
			)
			(layer "F.Fab")
		)
		(fp_line
			(start 0.12065 -0.2794)
			(end 0.12065 -0.3048)
			(stroke
				(width 0.1)
				(type default)
			)
			(layer "F.Fab")
		)
		(fp_line
			(start 0.12065 -0.3048)
			(end 0.67945 -0.3048)
			(stroke
				(width 0.1)
				(type default)
			)
			(layer "F.Fab")
		)
		(fp_line
			(start 0.67945 -0.3048)
			(end 0.67945 0.3048)
			(stroke
				(width 0.1)
				(type default)
			)
			(layer "F.Fab")
		)
		(fp_line
			(start -0.67945 -0.305054)
			(end -0.12065 -0.305054)
			(stroke
				(width 0.1)
				(type default)
			)
			(layer "F.Fab")
		)
		(fp_line
			(start -0.12065 -0.305054)
			(end -0.12065 -0.2794)
			(stroke
				(width 0.1)
				(type default)
			)
			(layer "F.Fab")
		)
		(pad "1" smd circle
			(at -0.40005 0 270)
			(size 0 0)
			(layers "F.Cu" "F.Mask" "F.Paste")
			(net "PGPPA_AUX")
		)
		(pad "2" smd circle
			(at 0.40005 0 270)
			(size 0 0)
			(layers "F.Cu" "F.Mask" "F.Paste")
			(net "FM_ESPI_PLD_R_EN_BUF")
		)
	)
	(footprint ""
		(layer "F.Cu")
		(at 392.719814 -36.318698 90)
		(property "Reference" "U210"
			(at 0.01016 2.864866 0)
			(unlocked yes)
			(layer "F.SilkS")
			(effects
				(font
					(size 0.7874 0.5842)
					(thickness 0.1524)
				)
				(justify left)
			)
		)
		(property "Value" ""
			(at 0 0 90)
			(layer "F.Fab")
			(effects
				(font
					(size 1.27 1.27)
				)
			)
		)
		(duplicate_pad_numbers_are_jumpers no)
		(fp_line
			(start 1.733296 -1.549908)
			(end 0.660908 -1.549908)
			(stroke
				(width 0.1524)
				(type default)
			)
			(layer "F.SilkS")
		)
		(fp_line
			(start 0.660908 -1.549908)
			(end 0 -0.889)
			(stroke
				(width 0.1524)
				(type default)
			)
			(layer "F.SilkS")
		)
		(fp_line
			(start -0.660908 -1.549908)
			(end -1.733296 -1.549908)
			(stroke
				(width 0.1524)
				(type default)
			)
			(layer "F.SilkS")
		)
		(fp_line
			(start -1.733296 -1.549908)
			(end -1.733296 1.549908)
			(stroke
				(width 0.1524)
				(type default)
			)
			(layer "F.SilkS")
		)
		(fp_line
			(start 0 -0.889)
			(end -0.660908 -1.549908)
			(stroke
				(width 0.1524)
				(type default)
			)
			(layer "F.SilkS")
		)
		(fp_line
			(start 1.733296 1.549908)
			(end 1.733296 -1.549908)
			(stroke
				(width 0.1524)
				(type default)
			)
			(layer "F.SilkS")
		)
		(fp_line
			(start -1.733296 1.549908)
			(end 1.733296 1.549908)
			(stroke
				(width 0.1524)
				(type default)
			)
			(layer "F.SilkS")
		)
		(fp_poly
			(pts
				(xy -1.9304 -0.94996) (xy -2.4384 -0.69596) (xy -2.4384 -1.20396)
			)
			(stroke
				(width 0)
				(type default)
			)
			(fill yes)
			(layer "F.SilkS")
		)
		(fp_line
			(start 0.849884 -1.549908)
			(end -0.849884 -1.549908)
			(stroke
				(width 0.1)
				(type default)
			)
			(layer "F.Fab")
		)
		(fp_line
			(start -0.849884 -1.549908)
			(end -0.849884 1.549908)
			(stroke
				(width 0.1)
				(type default)
			)
			(layer "F.Fab")
		)
		(fp_line
			(start 0.849884 1.549908)
			(end 0.849884 -1.549908)
			(stroke
				(width 0.1)
				(type default)
			)
			(layer "F.Fab")
		)
		(fp_line
			(start -0.849884 1.549908)
			(end 0.849884 1.549908)
			(stroke
				(width 0.1)
				(type default)
			)
			(layer "F.Fab")
		)
		(fp_poly
			(pts
				(xy -2.4384 -1.20396) (xy -2.4384 -0.69596) (xy -1.9304 -0.94996)
			)
			(stroke
				(width 0)
				(type default)
			)
			(fill yes)
			(layer "F.Fab")
		)
		(pad "1" smd rect
			(at -1.199896 -0.94996)
			(size 0.5588 0.8128)
			(layers "F.Cu" "F.Mask" "F.Paste")
			(net "HP_LVC3_OCP_V3_1_PWRGD_R")
		)
		(pad "2" smd rect
			(at -1.199896 0)
			(size 0.5588 0.8128)
			(layers "F.Cu" "F.Mask" "F.Paste")
			(net "RST_OCP_V3_1_N")
		)
		(pad "3" smd rect
			(at -1.199896 0.94996)
			(size 0.5588 0.8128)
			(layers "F.Cu" "F.Mask" "F.Paste")
			(net "GND")
		)
		(pad "4" smd rect
			(at 1.199896 0.94996)
			(size 0.5588 0.8128)
			(layers "F.Cu" "F.Mask" "F.Paste")
			(net "RST_HP_OCP_V3_1_N")
		)
		(pad "5" smd rect
			(at 1.199896 -0.94996)
			(size 0.5588 0.8128)
			(layers "F.Cu" "F.Mask" "F.Paste")
			(net "P3V3_AUX")
		)
	)
	(footprint ""
		(layer "F.Cu")
		(at 68.594478 -408.517344 -90)
		(property "Reference" "C697"
			(at 0 0 270)
			(layer "F.SilkS")
			(hide yes)
			(effects
				(font
					(size 1.27 1.27)
				)
			)
		)
		(property "Value" ""
			(at 0 0 270)
			(layer "F.Fab")
			(effects
				(font
					(size 1.27 1.27)
				)
			)
		)
		(duplicate_pad_numbers_are_jumpers no)
		(fp_line
			(start -0.299974 0.150114)
			(end -0.299974 -0.150114)
			(stroke
				(width 0.1)
				(type default)
			)
			(layer "F.Fab")
		)
		(fp_line
			(start 0.299974 0.150114)
			(end -0.299974 0.150114)
			(stroke
				(width 0.1)
				(type default)
			)
			(layer "F.Fab")
		)
		(fp_line
			(start -0.299974 -0.150114)
			(end 0.299974 -0.150114)
			(stroke
				(width 0.1)
				(type default)
			)
			(layer "F.Fab")
		)
		(fp_line
			(start 0.299974 -0.150114)
			(end 0.299974 0.150114)
			(stroke
				(width 0.1)
				(type default)
			)
			(layer "F.Fab")
		)
		(pad "1" smd rect
			(at -0.2667 0 270)
			(size 0.3048 0.381)
			(layers "F.Cu" "F.Mask" "F.Paste")
			(net "P5E_CPU1_PE4_TX_C_DP<6>")
		)
		(pad "2" smd rect
			(at 0.2667 0 270)
			(size 0.3048 0.381)
			(layers "F.Cu" "F.Mask" "F.Paste")
			(net "P5E_CPU1_PE4_TX_DP<6>")
		)
	)
	(footprint ""
		(layer "F.Cu")
		(at 310.995568 -402.371052 -90)
		(property "Reference" "C1575"
			(at 0 0 270)
			(layer "F.SilkS")
			(hide yes)
			(effects
				(font
					(size 1.27 1.27)
				)
			)
		)
		(property "Value" ""
			(at 0 0 270)
			(layer "F.Fab")
			(effects
				(font
					(size 1.27 1.27)
				)
			)
		)
		(duplicate_pad_numbers_are_jumpers no)
		(fp_line
			(start -0.299974 0.150114)
			(end -0.299974 -0.150114)
			(stroke
				(width 0.1)
				(type default)
			)
			(layer "F.Fab")
		)
		(fp_line
			(start 0.299974 0.150114)
			(end -0.299974 0.150114)
			(stroke
				(width 0.1)
				(type default)
			)
			(layer "F.Fab")
		)
		(fp_line
			(start -0.299974 -0.150114)
			(end 0.299974 -0.150114)
			(stroke
				(width 0.1)
				(type default)
			)
			(layer "F.Fab")
		)
		(fp_line
			(start 0.299974 -0.150114)
			(end 0.299974 0.150114)
			(stroke
				(width 0.1)
				(type default)
			)
			(layer "F.Fab")
		)
		(pad "1" smd rect
			(at -0.2667 0 270)
			(size 0.3048 0.381)
			(layers "F.Cu" "F.Mask" "F.Paste")
			(net "P5E_CPU0_PE4_TX_C_DP<2>")
		)
		(pad "2" smd rect
			(at 0.2667 0 270)
			(size 0.3048 0.381)
			(layers "F.Cu" "F.Mask" "F.Paste")
			(net "P5E_CPU0_PE4_TX_DP<2>")
		)
	)
	(footprint ""
		(layer "F.Cu")
		(at 62.35446 -147.84197)
		(property "Reference" "PL22"
			(at -3.52044 -4.364228 0)
			(unlocked yes)
			(layer "F.SilkS")
			(effects
				(font
					(size 0.7874 0.5842)
					(thickness 0.1524)
				)
				(justify left)
			)
		)
		(property "Value" ""
			(at 0 0 0)
			(layer "F.Fab")
			(effects
				(font
					(size 1.27 1.27)
				)
			)
		)
		(duplicate_pad_numbers_are_jumpers no)
		(fp_line
			(start -3.24993 -3.24993)
			(end 3.24993 -3.24993)
			(stroke
				(width 0.1524)
				(type default)
			)
			(layer "F.SilkS")
		)
		(fp_line
			(start -3.24993 -2.2352)
			(end -3.24993 -3.24993)
			(stroke
				(width 0.1524)
				(type default)
			)
			(layer "F.SilkS")
		)
		(fp_line
			(start -3.24993 3.24993)
			(end -3.24993 2.2352)
			(stroke
				(width 0.1524)
				(type default)
			)
			(layer "F.SilkS")
		)
		(fp_line
			(start 3.24993 -3.24993)
			(end 3.24993 -2.2352)
			(stroke
				(width 0.1524)
				(type default)
			)
			(layer "F.SilkS")
		)
		(fp_line
			(start 3.24993 2.2352)
			(end 3.24993 3.24993)
			(stroke
				(width 0.1524)
				(type default)
			)
			(layer "F.SilkS")
		)
		(fp_line
			(start 3.24993 3.24993)
			(end -3.24993 3.24993)
			(stroke
				(width 0.1524)
				(type default)
			)
			(layer "F.SilkS")
		)
		(fp_line
			(start -3.24993 -3.24993)
			(end 3.24993 -3.24993)
			(stroke
				(width 0.1)
				(type default)
			)
			(layer "F.Fab")
		)
		(fp_line
			(start -3.24993 3.24993)
			(end -3.24993 -3.24993)
			(stroke
				(width 0.1)
				(type default)
			)
			(layer "F.Fab")
		)
		(fp_line
			(start 3.24993 -3.24993)
			(end 3.24993 3.24993)
			(stroke
				(width 0.1)
				(type default)
			)
			(layer "F.Fab")
		)
		(fp_line
			(start 3.24993 3.24993)
			(end -3.24993 3.24993)
			(stroke
				(width 0.1)
				(type default)
			)
			(layer "F.Fab")
		)
		(pad "1" smd rect
			(at -2.29997 0)
			(size 2.0066 4.2164)
			(layers "F.Cu" "F.Mask" "F.Paste")
			(net "SW_PVCCINFAON_CPU1_SW2")
		)
		(pad "2" smd rect
			(at 2.29997 0)
			(size 2.0066 4.2164)
			(layers "F.Cu" "F.Mask" "F.Paste")
			(net "PVCCINFAON_CPU1")
		)
	)
	(footprint ""
		(layer "F.Cu")
		(at 205.397608 -408.887422)
		(property "Reference" "PR3917"
			(at 0 0 0)
			(layer "F.SilkS")
			(hide yes)
			(effects
				(font
					(size 1.27 1.27)
				)
			)
		)
		(property "Value" ""
			(at 0 0 0)
			(layer "F.Fab")
			(effects
				(font
					(size 1.27 1.27)
				)
			)
		)
		(duplicate_pad_numbers_are_jumpers no)
		(fp_line
			(start -0.7874 -0.4064)
			(end 0.7874 -0.4064)
			(stroke
				(width 0.1524)
				(type default)
			)
			(layer "F.SilkS")
		)
		(fp_line
			(start -0.7874 0.4064)
			(end -0.7874 -0.4064)
			(stroke
				(width 0.1524)
				(type default)
			)
			(layer "F.SilkS")
		)
		(fp_line
			(start 0.7874 -0.4064)
			(end 0.7874 0.4064)
			(stroke
				(width 0.1524)
				(type default)
			)
			(layer "F.SilkS")
		)
		(fp_line
			(start 0.7874 0.4064)
			(end -0.7874 0.4064)
			(stroke
				(width 0.1524)
				(type default)
			)
			(layer "F.SilkS")
		)
		(fp_line
			(start -0.67945 -0.305054)
			(end -0.12065 -0.305054)
			(stroke
				(width 0.1)
				(type default)
			)
			(layer "F.Fab")
		)
		(fp_line
			(start -0.67945 0.3048)
			(end -0.67945 -0.305054)
			(stroke
				(width 0.1)
				(type default)
			)
			(layer "F.Fab")
		)
		(fp_line
			(start -0.12065 -0.305054)
			(end -0.12065 -0.2794)
			(stroke
				(width 0.1)
				(type default)
			)
			(layer "F.Fab")
		)
		(fp_line
			(start -0.12065 -0.2794)
			(end 0.12065 -0.2794)
			(stroke
				(width 0.1)
				(type default)
			)
			(layer "F.Fab")
		)
		(fp_line
			(start -0.12065 0.2794)
			(end -0.12065 0.3048)
			(stroke
				(width 0.1)
				(type default)
			)
			(layer "F.Fab")
		)
		(fp_line
			(start -0.12065 0.3048)
			(end -0.67945 0.3048)
			(stroke
				(width 0.1)
				(type default)
			)
			(layer "F.Fab")
		)
		(fp_line
			(start 0.120396 0.2794)
			(end -0.12065 0.2794)
			(stroke
				(width 0.1)
				(type default)
			)
			(layer "F.Fab")
		)
		(fp_line
			(start 0.120396 0.3048)
			(end 0.120396 0.2794)
			(stroke
				(width 0.1)
				(type default)
			)
			(layer "F.Fab")
		)
		(fp_line
			(start 0.12065 -0.3048)
			(end 0.67945 -0.3048)
			(stroke
				(width 0.1)
				(type default)
			)
			(layer "F.Fab")
		)
		(fp_line
			(start 0.12065 -0.2794)
			(end 0.12065 -0.3048)
			(stroke
				(width 0.1)
				(type default)
			)
			(layer "F.Fab")
		)
		(fp_line
			(start 0.67945 -0.3048)
			(end 0.67945 0.3048)
			(stroke
				(width 0.1)
				(type default)
			)
			(layer "F.Fab")
		)
		(fp_line
			(start 0.67945 0.3048)
			(end 0.120396 0.3048)
			(stroke
				(width 0.1)
				(type default)
			)
			(layer "F.Fab")
		)
		(pad "1" smd circle
			(at -0.40005 0)
			(size 0 0)
			(layers "F.Cu" "F.Mask" "F.Paste")
			(net "HSC_SCREF")
		)
		(pad "2" smd circle
			(at 0.40005 0)
			(size 0 0)
			(layers "F.Cu" "F.Mask" "F.Paste")
			(net "HSC_SCREF_2")
		)
	)
	(footprint ""
		(layer "F.Cu")
		(at 183.69788 -126.964948 -90)
		(property "Reference" "R285"
			(at 0 0 270)
			(layer "F.SilkS")
			(hide yes)
			(effects
				(font
					(size 1.27 1.27)
				)
			)
		)
		(property "Value" ""
			(at 0 0 270)
			(layer "F.Fab")
			(effects
				(font
					(size 1.27 1.27)
				)
			)
		)
		(duplicate_pad_numbers_are_jumpers no)
		(fp_line
			(start -0.7874 0.4064)
			(end -0.7874 -0.4064)
			(stroke
				(width 0.1524)
				(type default)
			)
			(layer "F.SilkS")
		)
		(fp_line
			(start 0.7874 0.4064)
			(end -0.7874 0.4064)
			(stroke
				(width 0.1524)
				(type default)
			)
			(layer "F.SilkS")
		)
		(fp_line
			(start -0.7874 -0.4064)
			(end 0.7874 -0.4064)
			(stroke
				(width 0.1524)
				(type default)
			)
			(layer "F.SilkS")
		)
		(fp_line
			(start 0.7874 -0.4064)
			(end 0.7874 0.4064)
			(stroke
				(width 0.1524)
				(type default)
			)
			(layer "F.SilkS")
		)
		(fp_line
			(start -0.67945 0.3048)
			(end -0.67945 -0.305054)
			(stroke
				(width 0.1)
				(type default)
			)
			(layer "F.Fab")
		)
		(fp_line
			(start -0.12065 0.3048)
			(end -0.67945 0.3048)
			(stroke
				(width 0.1)
				(type default)
			)
			(layer "F.Fab")
		)
		(fp_line
			(start 0.120396 0.3048)
			(end 0.120396 0.2794)
			(stroke
				(width 0.1)
				(type default)
			)
			(layer "F.Fab")
		)
		(fp_line
			(start 0.67945 0.3048)
			(end 0.120396 0.3048)
			(stroke
				(width 0.1)
				(type default)
			)
			(layer "F.Fab")
		)
		(fp_line
			(start -0.12065 0.2794)
			(end -0.12065 0.3048)
			(stroke
				(width 0.1)
				(type default)
			)
			(layer "F.Fab")
		)
		(fp_line
			(start 0.120396 0.2794)
			(end -0.12065 0.2794)
			(stroke
				(width 0.1)
				(type default)
			)
			(layer "F.Fab")
		)
		(fp_line
			(start -0.12065 -0.2794)
			(end 0.12065 -0.2794)
			(stroke
				(width 0.1)
				(type default)
			)
			(layer "F.Fab")
		)
		(fp_line
			(start 0.12065 -0.2794)
			(end 0.12065 -0.3048)
			(stroke
				(width 0.1)
				(type default)
			)
			(layer "F.Fab")
		)
		(fp_line
			(start 0.12065 -0.3048)
			(end 0.67945 -0.3048)
			(stroke
				(width 0.1)
				(type default)
			)
			(layer "F.Fab")
		)
		(fp_line
			(start 0.67945 -0.3048)
			(end 0.67945 0.3048)
			(stroke
				(width 0.1)
				(type default)
			)
			(layer "F.Fab")
		)
		(fp_line
			(start -0.67945 -0.305054)
			(end -0.12065 -0.305054)
			(stroke
				(width 0.1)
				(type default)
			)
			(layer "F.Fab")
		)
		(fp_line
			(start -0.12065 -0.305054)
			(end -0.12065 -0.2794)
			(stroke
				(width 0.1)
				(type default)
			)
			(layer "F.Fab")
		)
		(pad "1" smd circle
			(at -0.40005 0 270)
			(size 0 0)
			(layers "F.Cu" "F.Mask" "F.Paste")
			(net "P3V3_AUX")
		)
		(pad "2" smd circle
			(at 0.40005 0 270)
			(size 0 0)
			(layers "F.Cu" "F.Mask" "F.Paste")
			(net "FM_CPU0_PKGID2")
		)
	)
	(footprint ""
		(layer "F.Cu")
		(at 458.298804 -76.588112 90)
		(property "Reference" "PC2260"
			(at 0 0 90)
			(layer "F.SilkS")
			(hide yes)
			(effects
				(font
					(size 1.27 1.27)
				)
			)
		)
		(property "Value" ""
			(at 0 0 90)
			(layer "F.Fab")
			(effects
				(font
					(size 1.27 1.27)
				)
			)
		)
		(duplicate_pad_numbers_are_jumpers no)
		(fp_line
			(start 1.524 -0.762)
			(end 1.524 0.762)
			(stroke
				(width 0.1524)
				(type default)
			)
			(layer "F.SilkS")
		)
		(fp_line
			(start -1.524 -0.762)
			(end 1.524 -0.762)
			(stroke
				(width 0.1524)
				(type default)
			)
			(layer "F.SilkS")
		)
		(fp_line
			(start 1.524 0.762)
			(end -1.524 0.762)
			(stroke
				(width 0.1524)
				(type default)
			)
			(layer "F.SilkS")
		)
		(fp_line
			(start -1.524 0.762)
			(end -1.524 -0.762)
			(stroke
				(width 0.1524)
				(type default)
			)
			(layer "F.SilkS")
		)
		(fp_line
			(start 1.1049 -0.724916)
			(end -1.1049 -0.724916)
			(stroke
				(width 0.1)
				(type default)
			)
			(layer "F.Fab")
		)
		(fp_line
			(start -1.1049 -0.724916)
			(end -1.1049 0.724916)
			(stroke
				(width 0.1)
				(type default)
			)
			(layer "F.Fab")
		)
		(fp_line
			(start 1.1049 0.724916)
			(end 1.1049 -0.724916)
			(stroke
				(width 0.1)
				(type default)
			)
			(layer "F.Fab")
		)
		(fp_line
			(start -1.1049 0.724916)
			(end 1.1049 0.724916)
			(stroke
				(width 0.1)
				(type default)
			)
			(layer "F.Fab")
		)
		(pad "1" smd rect
			(at -0.889 0 270)
			(size 1.016 1.27)
			(layers "F.Cu" "F.Mask" "F.Paste")
			(net "SW_P3V3_AUX_FLT")
		)
		(pad "2" smd rect
			(at 0.889 0 270)
			(size 1.016 1.27)
			(layers "F.Cu" "F.Mask" "F.Paste")
			(net "GND")
		)
	)
	(footprint ""
		(layer "F.Cu")
		(at 220.087444 -100.23348)
		(property "Reference" "C1561"
			(at 0 0 0)
			(layer "F.SilkS")
			(hide yes)
			(effects
				(font
					(size 1.27 1.27)
				)
			)
		)
		(property "Value" ""
			(at 0 0 0)
			(layer "F.Fab")
			(effects
				(font
					(size 1.27 1.27)
				)
			)
		)
		(duplicate_pad_numbers_are_jumpers no)
		(fp_line
			(start -0.7874 -0.4064)
			(end 0.7874 -0.4064)
			(stroke
				(width 0.1524)
				(type default)
			)
			(layer "F.SilkS")
		)
		(fp_line
			(start -0.7874 0.4064)
			(end -0.7874 -0.4064)
			(stroke
				(width 0.1524)
				(type default)
			)
			(layer "F.SilkS")
		)
		(fp_line
			(start 0.7874 -0.4064)
			(end 0.7874 0.4064)
			(stroke
				(width 0.1524)
				(type default)
			)
			(layer "F.SilkS")
		)
		(fp_line
			(start 0.7874 0.4064)
			(end -0.7874 0.4064)
			(stroke
				(width 0.1524)
				(type default)
			)
			(layer "F.SilkS")
		)
		(fp_line
			(start -0.67945 -0.305054)
			(end -0.12065 -0.305054)
			(stroke
				(width 0.1)
				(type default)
			)
			(layer "F.Fab")
		)
		(fp_line
			(start -0.67945 0.3048)
			(end -0.67945 -0.305054)
			(stroke
				(width 0.1)
				(type default)
			)
			(layer "F.Fab")
		)
		(fp_line
			(start -0.12065 -0.305054)
			(end -0.12065 -0.2794)
			(stroke
				(width 0.1)
				(type default)
			)
			(layer "F.Fab")
		)
		(fp_line
			(start -0.12065 -0.2794)
			(end 0.12065 -0.2794)
			(stroke
				(width 0.1)
				(type default)
			)
			(layer "F.Fab")
		)
		(fp_line
			(start -0.12065 0.2794)
			(end -0.12065 0.3048)
			(stroke
				(width 0.1)
				(type default)
			)
			(layer "F.Fab")
		)
		(fp_line
			(start -0.12065 0.3048)
			(end -0.67945 0.3048)
			(stroke
				(width 0.1)
				(type default)
			)
			(layer "F.Fab")
		)
		(fp_line
			(start 0.120396 0.2794)
			(end -0.12065 0.2794)
			(stroke
				(width 0.1)
				(type default)
			)
			(layer "F.Fab")
		)
		(fp_line
			(start 0.120396 0.3048)
			(end 0.120396 0.2794)
			(stroke
				(width 0.1)
				(type default)
			)
			(layer "F.Fab")
		)
		(fp_line
			(start 0.12065 -0.3048)
			(end 0.67945 -0.3048)
			(stroke
				(width 0.1)
				(type default)
			)
			(layer "F.Fab")
		)
		(fp_line
			(start 0.12065 -0.2794)
			(end 0.12065 -0.3048)
			(stroke
				(width 0.1)
				(type default)
			)
			(layer "F.Fab")
		)
		(fp_line
			(start 0.67945 -0.3048)
			(end 0.67945 0.3048)
			(stroke
				(width 0.1)
				(type default)
			)
			(layer "F.Fab")
		)
		(fp_line
			(start 0.67945 0.3048)
			(end 0.120396 0.3048)
			(stroke
				(width 0.1)
				(type default)
			)
			(layer "F.Fab")
		)
		(pad "1" smd circle
			(at -0.40005 0)
			(size 0 0)
			(layers "F.Cu" "F.Mask" "F.Paste")
			(net "U206_VDD")
		)
		(pad "2" smd circle
			(at 0.40005 0)
			(size 0 0)
			(layers "F.Cu" "F.Mask" "F.Paste")
			(net "GND")
		)
	)
	(footprint ""
		(layer "F.Cu")
		(at 354.261928 -258.726686 90)
		(property "Reference" "C966"
			(at 0 0 90)
			(layer "F.SilkS")
			(hide yes)
			(effects
				(font
					(size 1.27 1.27)
				)
			)
		)
		(property "Value" ""
			(at 0 0 90)
			(layer "F.Fab")
			(effects
				(font
					(size 1.27 1.27)
				)
			)
		)
		(duplicate_pad_numbers_are_jumpers no)
		(fp_line
			(start 0.7874 -0.4064)
			(end 0.7874 0.4064)
			(stroke
				(width 0.1524)
				(type default)
			)
			(layer "F.SilkS")
		)
		(fp_line
			(start -0.7874 -0.4064)
			(end 0.7874 -0.4064)
			(stroke
				(width 0.1524)
				(type default)
			)
			(layer "F.SilkS")
		)
		(fp_line
			(start 0.7874 0.4064)
			(end -0.7874 0.4064)
			(stroke
				(width 0.1524)
				(type default)
			)
			(layer "F.SilkS")
		)
		(fp_line
			(start -0.7874 0.4064)
			(end -0.7874 -0.4064)
			(stroke
				(width 0.1524)
				(type default)
			)
			(layer "F.SilkS")
		)
		(fp_line
			(start -0.12065 -0.305054)
			(end -0.12065 -0.2794)
			(stroke
				(width 0.1)
				(type default)
			)
			(layer "F.Fab")
		)
		(fp_line
			(start -0.67945 -0.305054)
			(end -0.12065 -0.305054)
			(stroke
				(width 0.1)
				(type default)
			)
			(layer "F.Fab")
		)
		(fp_line
			(start 0.67945 -0.3048)
			(end 0.67945 0.3048)
			(stroke
				(width 0.1)
				(type default)
			)
			(layer "F.Fab")
		)
		(fp_line
			(start 0.12065 -0.3048)
			(end 0.67945 -0.3048)
			(stroke
				(width 0.1)
				(type default)
			)
			(layer "F.Fab")
		)
		(fp_line
			(start 0.12065 -0.2794)
			(end 0.12065 -0.3048)
			(stroke
				(width 0.1)
				(type default)
			)
			(layer "F.Fab")
		)
		(fp_line
			(start -0.12065 -0.2794)
			(end 0.12065 -0.2794)
			(stroke
				(width 0.1)
				(type default)
			)
			(layer "F.Fab")
		)
		(fp_line
			(start 0.120396 0.2794)
			(end -0.12065 0.2794)
			(stroke
				(width 0.1)
				(type default)
			)
			(layer "F.Fab")
		)
		(fp_line
			(start -0.12065 0.2794)
			(end -0.12065 0.3048)
			(stroke
				(width 0.1)
				(type default)
			)
			(layer "F.Fab")
		)
		(fp_line
			(start 0.67945 0.3048)
			(end 0.120396 0.3048)
			(stroke
				(width 0.1)
				(type default)
			)
			(layer "F.Fab")
		)
		(fp_line
			(start 0.120396 0.3048)
			(end 0.120396 0.2794)
			(stroke
				(width 0.1)
				(type default)
			)
			(layer "F.Fab")
		)
		(fp_line
			(start -0.12065 0.3048)
			(end -0.67945 0.3048)
			(stroke
				(width 0.1)
				(type default)
			)
			(layer "F.Fab")
		)
		(fp_line
			(start -0.67945 0.3048)
			(end -0.67945 -0.305054)
			(stroke
				(width 0.1)
				(type default)
			)
			(layer "F.Fab")
		)
		(pad "1" smd circle
			(at -0.40005 0 90)
			(size 0 0)
			(layers "F.Cu" "F.Mask" "F.Paste")
			(net "PVCCIN_CPU0")
		)
		(pad "2" smd circle
			(at 0.40005 0 90)
			(size 0 0)
			(layers "F.Cu" "F.Mask" "F.Paste")
			(net "GND")
		)
	)
	(footprint ""
		(layer "F.Cu")
		(at 302.85436 -433.04587 90)
		(property "Reference" "R4131"
			(at 0 0 90)
			(layer "F.SilkS")
			(hide yes)
			(effects
				(font
					(size 1.27 1.27)
				)
			)
		)
		(property "Value" ""
			(at 0 0 90)
			(layer "F.Fab")
			(effects
				(font
					(size 1.27 1.27)
				)
			)
		)
		(duplicate_pad_numbers_are_jumpers no)
		(fp_line
			(start 0.7874 -0.4064)
			(end 0.7874 0.4064)
			(stroke
				(width 0.1524)
				(type default)
			)
			(layer "F.SilkS")
		)
		(fp_line
			(start -0.7874 -0.4064)
			(end 0.7874 -0.4064)
			(stroke
				(width 0.1524)
				(type default)
			)
			(layer "F.SilkS")
		)
		(fp_line
			(start 0.7874 0.4064)
			(end -0.7874 0.4064)
			(stroke
				(width 0.1524)
				(type default)
			)
			(layer "F.SilkS")
		)
		(fp_line
			(start -0.7874 0.4064)
			(end -0.7874 -0.4064)
			(stroke
				(width 0.1524)
				(type default)
			)
			(layer "F.SilkS")
		)
		(fp_line
			(start -0.12065 -0.305054)
			(end -0.12065 -0.2794)
			(stroke
				(width 0.1)
				(type default)
			)
			(layer "F.Fab")
		)
		(fp_line
			(start -0.67945 -0.305054)
			(end -0.12065 -0.305054)
			(stroke
				(width 0.1)
				(type default)
			)
			(layer "F.Fab")
		)
		(fp_line
			(start 0.67945 -0.3048)
			(end 0.67945 0.3048)
			(stroke
				(width 0.1)
				(type default)
			)
			(layer "F.Fab")
		)
		(fp_line
			(start 0.12065 -0.3048)
			(end 0.67945 -0.3048)
			(stroke
				(width 0.1)
				(type default)
			)
			(layer "F.Fab")
		)
		(fp_line
			(start 0.12065 -0.2794)
			(end 0.12065 -0.3048)
			(stroke
				(width 0.1)
				(type default)
			)
			(layer "F.Fab")
		)
		(fp_line
			(start -0.12065 -0.2794)
			(end 0.12065 -0.2794)
			(stroke
				(width 0.1)
				(type default)
			)
			(layer "F.Fab")
		)
		(fp_line
			(start 0.120396 0.2794)
			(end -0.12065 0.2794)
			(stroke
				(width 0.1)
				(type default)
			)
			(layer "F.Fab")
		)
		(fp_line
			(start -0.12065 0.2794)
			(end -0.12065 0.3048)
			(stroke
				(width 0.1)
				(type default)
			)
			(layer "F.Fab")
		)
		(fp_line
			(start 0.67945 0.3048)
			(end 0.120396 0.3048)
			(stroke
				(width 0.1)
				(type default)
			)
			(layer "F.Fab")
		)
		(fp_line
			(start 0.120396 0.3048)
			(end 0.120396 0.2794)
			(stroke
				(width 0.1)
				(type default)
			)
			(layer "F.Fab")
		)
		(fp_line
			(start -0.12065 0.3048)
			(end -0.67945 0.3048)
			(stroke
				(width 0.1)
				(type default)
			)
			(layer "F.Fab")
		)
		(fp_line
			(start -0.67945 0.3048)
			(end -0.67945 -0.305054)
			(stroke
				(width 0.1)
				(type default)
			)
			(layer "F.Fab")
		)
		(pad "1" smd circle
			(at -0.40005 0 90)
			(size 0 0)
			(layers "F.Cu" "F.Mask" "F.Paste")
			(net "P3V3_AUX")
		)
		(pad "2" smd circle
			(at 0.40005 0 90)
			(size 0 0)
			(layers "F.Cu" "F.Mask" "F.Paste")
			(net "GPU_3V3IO_RSVD3_FFU")
		)
	)
	(footprint ""
		(layer "F.Cu")
		(at 145.981674 -408.517344 -90)
		(property "Reference" "C1532"
			(at 0 0 270)
			(layer "F.SilkS")
			(hide yes)
			(effects
				(font
					(size 1.27 1.27)
				)
			)
		)
		(property "Value" ""
			(at 0 0 270)
			(layer "F.Fab")
			(effects
				(font
					(size 1.27 1.27)
				)
			)
		)
		(duplicate_pad_numbers_are_jumpers no)
		(fp_line
			(start -0.299974 0.150114)
			(end -0.299974 -0.150114)
			(stroke
				(width 0.1)
				(type default)
			)
			(layer "F.Fab")
		)
		(fp_line
			(start 0.299974 0.150114)
			(end -0.299974 0.150114)
			(stroke
				(width 0.1)
				(type default)
			)
			(layer "F.Fab")
		)
		(fp_line
			(start -0.299974 -0.150114)
			(end 0.299974 -0.150114)
			(stroke
				(width 0.1)
				(type default)
			)
			(layer "F.Fab")
		)
		(fp_line
			(start 0.299974 -0.150114)
			(end 0.299974 0.150114)
			(stroke
				(width 0.1)
				(type default)
			)
			(layer "F.Fab")
		)
		(pad "1" smd rect
			(at -0.2667 0 270)
			(size 0.3048 0.381)
			(layers "F.Cu" "F.Mask" "F.Paste")
			(net "P5E_CPU1_PE3_TX_C_DN<7>")
		)
		(pad "2" smd rect
			(at 0.2667 0 270)
			(size 0.3048 0.381)
			(layers "F.Cu" "F.Mask" "F.Paste")
			(net "P5E_CPU1_PE3_TX_DN<7>")
		)
	)
	(footprint ""
		(layer "F.Cu")
		(at 435.157118 -44.44238)
		(property "Reference" "R2134"
			(at 0 0 0)
			(layer "F.SilkS")
			(hide yes)
			(effects
				(font
					(size 1.27 1.27)
				)
			)
		)
		(property "Value" ""
			(at 0 0 0)
			(layer "F.Fab")
			(effects
				(font
					(size 1.27 1.27)
				)
			)
		)
		(duplicate_pad_numbers_are_jumpers no)
		(fp_line
			(start -0.7874 -0.4064)
			(end 0.7874 -0.4064)
			(stroke
				(width 0.1524)
				(type default)
			)
			(layer "F.SilkS")
		)
		(fp_line
			(start -0.7874 0.4064)
			(end -0.7874 -0.4064)
			(stroke
				(width 0.1524)
				(type default)
			)
			(layer "F.SilkS")
		)
		(fp_line
			(start 0.7874 -0.4064)
			(end 0.7874 0.4064)
			(stroke
				(width 0.1524)
				(type default)
			)
			(layer "F.SilkS")
		)
		(fp_line
			(start 0.7874 0.4064)
			(end -0.7874 0.4064)
			(stroke
				(width 0.1524)
				(type default)
			)
			(layer "F.SilkS")
		)
		(fp_line
			(start -0.67945 -0.305054)
			(end -0.12065 -0.305054)
			(stroke
				(width 0.1)
				(type default)
			)
			(layer "F.Fab")
		)
		(fp_line
			(start -0.67945 0.3048)
			(end -0.67945 -0.305054)
			(stroke
				(width 0.1)
				(type default)
			)
			(layer "F.Fab")
		)
		(fp_line
			(start -0.12065 -0.305054)
			(end -0.12065 -0.2794)
			(stroke
				(width 0.1)
				(type default)
			)
			(layer "F.Fab")
		)
		(fp_line
			(start -0.12065 -0.2794)
			(end 0.12065 -0.2794)
			(stroke
				(width 0.1)
				(type default)
			)
			(layer "F.Fab")
		)
		(fp_line
			(start -0.12065 0.2794)
			(end -0.12065 0.3048)
			(stroke
				(width 0.1)
				(type default)
			)
			(layer "F.Fab")
		)
		(fp_line
			(start -0.12065 0.3048)
			(end -0.67945 0.3048)
			(stroke
				(width 0.1)
				(type default)
			)
			(layer "F.Fab")
		)
		(fp_line
			(start 0.120396 0.2794)
			(end -0.12065 0.2794)
			(stroke
				(width 0.1)
				(type default)
			)
			(layer "F.Fab")
		)
		(fp_line
			(start 0.120396 0.3048)
			(end 0.120396 0.2794)
			(stroke
				(width 0.1)
				(type default)
			)
			(layer "F.Fab")
		)
		(fp_line
			(start 0.12065 -0.3048)
			(end 0.67945 -0.3048)
			(stroke
				(width 0.1)
				(type default)
			)
			(layer "F.Fab")
		)
		(fp_line
			(start 0.12065 -0.2794)
			(end 0.12065 -0.3048)
			(stroke
				(width 0.1)
				(type default)
			)
			(layer "F.Fab")
		)
		(fp_line
			(start 0.67945 -0.3048)
			(end 0.67945 0.3048)
			(stroke
				(width 0.1)
				(type default)
			)
			(layer "F.Fab")
		)
		(fp_line
			(start 0.67945 0.3048)
			(end 0.120396 0.3048)
			(stroke
				(width 0.1)
				(type default)
			)
			(layer "F.Fab")
		)
		(pad "1" smd circle
			(at -0.40005 0)
			(size 0 0)
			(layers "F.Cu" "F.Mask" "F.Paste")
			(net "JTAG_TRC_PCH_PTI<6>")
		)
		(pad "2" smd circle
			(at 0.40005 0)
			(size 0 0)
			(layers "F.Cu" "F.Mask" "F.Paste")
			(net "GND")
		)
	)
	(footprint ""
		(layer "F.Cu")
		(at 309.523638 -36.806886 180)
		(property "Reference" "R4102"
			(at 0 0 180)
			(layer "F.SilkS")
			(hide yes)
			(effects
				(font
					(size 1.27 1.27)
				)
			)
		)
		(property "Value" ""
			(at 0 0 180)
			(layer "F.Fab")
			(effects
				(font
					(size 1.27 1.27)
				)
			)
		)
		(duplicate_pad_numbers_are_jumpers no)
		(fp_line
			(start 0.7874 0.4064)
			(end -0.7874 0.4064)
			(stroke
				(width 0.1524)
				(type default)
			)
			(layer "F.SilkS")
		)
		(fp_line
			(start 0.7874 -0.4064)
			(end 0.7874 0.4064)
			(stroke
				(width 0.1524)
				(type default)
			)
			(layer "F.SilkS")
		)
		(fp_line
			(start -0.7874 0.4064)
			(end -0.7874 -0.4064)
			(stroke
				(width 0.1524)
				(type default)
			)
			(layer "F.SilkS")
		)
		(fp_line
			(start -0.7874 -0.4064)
			(end 0.7874 -0.4064)
			(stroke
				(width 0.1524)
				(type default)
			)
			(layer "F.SilkS")
		)
		(fp_line
			(start 0.67945 0.3048)
			(end 0.120396 0.3048)
			(stroke
				(width 0.1)
				(type default)
			)
			(layer "F.Fab")
		)
		(fp_line
			(start 0.67945 -0.3048)
			(end 0.67945 0.3048)
			(stroke
				(width 0.1)
				(type default)
			)
			(layer "F.Fab")
		)
		(fp_line
			(start 0.12065 -0.2794)
			(end 0.12065 -0.3048)
			(stroke
				(width 0.1)
				(type default)
			)
			(layer "F.Fab")
		)
		(fp_line
			(start 0.12065 -0.3048)
			(end 0.67945 -0.3048)
			(stroke
				(width 0.1)
				(type default)
			)
			(layer "F.Fab")
		)
		(fp_line
			(start 0.120396 0.3048)
			(end 0.120396 0.2794)
			(stroke
				(width 0.1)
				(type default)
			)
			(layer "F.Fab")
		)
		(fp_line
			(start 0.120396 0.2794)
			(end -0.12065 0.2794)
			(stroke
				(width 0.1)
				(type default)
			)
			(layer "F.Fab")
		)
		(fp_line
			(start -0.12065 0.3048)
			(end -0.67945 0.3048)
			(stroke
				(width 0.1)
				(type default)
			)
			(layer "F.Fab")
		)
		(fp_line
			(start -0.12065 0.2794)
			(end -0.12065 0.3048)
			(stroke
				(width 0.1)
				(type default)
			)
			(layer "F.Fab")
		)
		(fp_line
			(start -0.12065 -0.2794)
			(end 0.12065 -0.2794)
			(stroke
				(width 0.1)
				(type default)
			)
			(layer "F.Fab")
		)
		(fp_line
			(start -0.12065 -0.305054)
			(end -0.12065 -0.2794)
			(stroke
				(width 0.1)
				(type default)
			)
			(layer "F.Fab")
		)
		(fp_line
			(start -0.67945 0.3048)
			(end -0.67945 -0.305054)
			(stroke
				(width 0.1)
				(type default)
			)
			(layer "F.Fab")
		)
		(fp_line
			(start -0.67945 -0.305054)
			(end -0.12065 -0.305054)
			(stroke
				(width 0.1)
				(type default)
			)
			(layer "F.Fab")
		)
		(pad "1" smd circle
			(at -0.40005 0 180)
			(size 0 0)
			(layers "F.Cu" "F.Mask" "F.Paste")
			(net "PD_PCH_GPPC_C5")
		)
		(pad "2" smd circle
			(at 0.40005 0 180)
			(size 0 0)
			(layers "F.Cu" "F.Mask" "F.Paste")
			(net "GND")
		)
	)
	(footprint ""
		(layer "F.Cu")
		(at 483.262432 -251.033788)
		(property "Reference" "DB10"
			(at 2.310384 2.86004 90)
			(unlocked yes)
			(layer "F.SilkS")
			(effects
				(font
					(size 0.7874 0.5842)
					(thickness 0.1524)
				)
				(justify left)
			)
		)
		(property "Value" ""
			(at 0 0 0)
			(layer "F.Fab")
			(effects
				(font
					(size 1.27 1.27)
				)
			)
		)
		(duplicate_pad_numbers_are_jumpers no)
		(fp_line
			(start -3.330702 -4.771136)
			(end 3.330702 -4.771136)
			(stroke
				(width 0.1524)
				(type default)
			)
			(layer "F.SilkS")
		)
		(fp_line
			(start 0 4.011168)
			(end -3.330702 -4.771136)
			(stroke
				(width 0.1524)
				(type default)
			)
			(layer "F.SilkS")
		)
		(fp_line
			(start 3.330702 -4.771136)
			(end 0 4.011168)
			(stroke
				(width 0.1524)
				(type default)
			)
			(layer "F.SilkS")
		)
		(fp_line
			(start -3.330702 -4.771136)
			(end 3.330702 -4.771136)
			(stroke
				(width 0.1)
				(type default)
			)
			(layer "F.Fab")
		)
		(fp_line
			(start 0 4.011168)
			(end -3.330702 -4.771136)
			(stroke
				(width 0.1)
				(type default)
			)
			(layer "F.Fab")
		)
		(fp_line
			(start 3.330702 -4.771136)
			(end 0 4.011168)
			(stroke
				(width 0.1)
				(type default)
			)
			(layer "F.Fab")
		)
		(pad "1" thru_hole circle
			(at 0 0)
			(size 2.159 2.159)
			(drill 1.7018)
			(layers "*.Cu" "*.Mask")
			(remove_unused_layers no)
			(net "T1_GND")
			(clearance 0.0254)
			(thermal_gap 0.0254)
		)
		(pad "2" thru_hole circle
			(at -1.27 -3.348736)
			(size 2.159 2.159)
			(drill 1.7018)
			(layers "*.Cu" "*.Mask")
			(remove_unused_layers no)
			(net "TDR_SE_50_OHM_IN3")
			(clearance 0.0254)
			(thermal_gap 0.0254)
		)
		(pad "3" thru_hole circle
			(at 1.27 -3.348736)
			(size 2.159 2.159)
			(drill 1.7018)
			(layers "*.Cu" "*.Mask")
			(remove_unused_layers no)
			(net "TDR_SE_50_OHM_IN3")
			(clearance 0.0254)
			(thermal_gap 0.0254)
		)
	)
	(footprint ""
		(layer "F.Cu")
		(at 417.730178 -375.08053)
		(property "Reference" "PC1654"
			(at 0 0 0)
			(layer "F.SilkS")
			(hide yes)
			(effects
				(font
					(size 1.27 1.27)
				)
			)
		)
		(property "Value" ""
			(at 0 0 0)
			(layer "F.Fab")
			(effects
				(font
					(size 1.27 1.27)
				)
			)
		)
		(duplicate_pad_numbers_are_jumpers no)
		(fp_line
			(start -0.7874 -0.4064)
			(end 0.7874 -0.4064)
			(stroke
				(width 0.1524)
				(type default)
			)
			(layer "F.SilkS")
		)
		(fp_line
			(start -0.7874 0.4064)
			(end -0.7874 -0.4064)
			(stroke
				(width 0.1524)
				(type default)
			)
			(layer "F.SilkS")
		)
		(fp_line
			(start 0.7874 -0.4064)
			(end 0.7874 0.4064)
			(stroke
				(width 0.1524)
				(type default)
			)
			(layer "F.SilkS")
		)
		(fp_line
			(start 0.7874 0.4064)
			(end -0.7874 0.4064)
			(stroke
				(width 0.1524)
				(type default)
			)
			(layer "F.SilkS")
		)
		(fp_line
			(start -0.67945 -0.305054)
			(end -0.12065 -0.305054)
			(stroke
				(width 0.1)
				(type default)
			)
			(layer "F.Fab")
		)
		(fp_line
			(start -0.67945 0.3048)
			(end -0.67945 -0.305054)
			(stroke
				(width 0.1)
				(type default)
			)
			(layer "F.Fab")
		)
		(fp_line
			(start -0.12065 -0.305054)
			(end -0.12065 -0.2794)
			(stroke
				(width 0.1)
				(type default)
			)
			(layer "F.Fab")
		)
		(fp_line
			(start -0.12065 -0.2794)
			(end 0.12065 -0.2794)
			(stroke
				(width 0.1)
				(type default)
			)
			(layer "F.Fab")
		)
		(fp_line
			(start -0.12065 0.2794)
			(end -0.12065 0.3048)
			(stroke
				(width 0.1)
				(type default)
			)
			(layer "F.Fab")
		)
		(fp_line
			(start -0.12065 0.3048)
			(end -0.67945 0.3048)
			(stroke
				(width 0.1)
				(type default)
			)
			(layer "F.Fab")
		)
		(fp_line
			(start 0.120396 0.2794)
			(end -0.12065 0.2794)
			(stroke
				(width 0.1)
				(type default)
			)
			(layer "F.Fab")
		)
		(fp_line
			(start 0.120396 0.3048)
			(end 0.120396 0.2794)
			(stroke
				(width 0.1)
				(type default)
			)
			(layer "F.Fab")
		)
		(fp_line
			(start 0.12065 -0.3048)
			(end 0.67945 -0.3048)
			(stroke
				(width 0.1)
				(type default)
			)
			(layer "F.Fab")
		)
		(fp_line
			(start 0.12065 -0.2794)
			(end 0.12065 -0.3048)
			(stroke
				(width 0.1)
				(type default)
			)
			(layer "F.Fab")
		)
		(fp_line
			(start 0.67945 -0.3048)
			(end 0.67945 0.3048)
			(stroke
				(width 0.1)
				(type default)
			)
			(layer "F.Fab")
		)
		(fp_line
			(start 0.67945 0.3048)
			(end 0.120396 0.3048)
			(stroke
				(width 0.1)
				(type default)
			)
			(layer "F.Fab")
		)
		(pad "1" smd circle
			(at -0.40005 0)
			(size 0 0)
			(layers "F.Cu" "F.Mask" "F.Paste")
			(net "P12V_AUX")
		)
		(pad "2" smd circle
			(at 0.40005 0)
			(size 0 0)
			(layers "F.Cu" "F.Mask" "F.Paste")
			(net "GND")
		)
	)
	(footprint ""
		(layer "F.Cu")
		(at 61.90488 -19.268948 180)
		(property "Reference" "R3164"
			(at 0 0 180)
			(layer "F.SilkS")
			(hide yes)
			(effects
				(font
					(size 1.27 1.27)
				)
			)
		)
		(property "Value" ""
			(at 0 0 180)
			(layer "F.Fab")
			(effects
				(font
					(size 1.27 1.27)
				)
			)
		)
		(duplicate_pad_numbers_are_jumpers no)
		(fp_line
			(start 0.7874 0.4064)
			(end -0.7874 0.4064)
			(stroke
				(width 0.1524)
				(type default)
			)
			(layer "F.SilkS")
		)
		(fp_line
			(start 0.7874 -0.4064)
			(end 0.7874 0.4064)
			(stroke
				(width 0.1524)
				(type default)
			)
			(layer "F.SilkS")
		)
		(fp_line
			(start -0.7874 0.4064)
			(end -0.7874 -0.4064)
			(stroke
				(width 0.1524)
				(type default)
			)
			(layer "F.SilkS")
		)
		(fp_line
			(start -0.7874 -0.4064)
			(end 0.7874 -0.4064)
			(stroke
				(width 0.1524)
				(type default)
			)
			(layer "F.SilkS")
		)
		(fp_line
			(start 0.67945 0.3048)
			(end 0.120396 0.3048)
			(stroke
				(width 0.1)
				(type default)
			)
			(layer "F.Fab")
		)
		(fp_line
			(start 0.67945 -0.3048)
			(end 0.67945 0.3048)
			(stroke
				(width 0.1)
				(type default)
			)
			(layer "F.Fab")
		)
		(fp_line
			(start 0.12065 -0.2794)
			(end 0.12065 -0.3048)
			(stroke
				(width 0.1)
				(type default)
			)
			(layer "F.Fab")
		)
		(fp_line
			(start 0.12065 -0.3048)
			(end 0.67945 -0.3048)
			(stroke
				(width 0.1)
				(type default)
			)
			(layer "F.Fab")
		)
		(fp_line
			(start 0.120396 0.3048)
			(end 0.120396 0.2794)
			(stroke
				(width 0.1)
				(type default)
			)
			(layer "F.Fab")
		)
		(fp_line
			(start 0.120396 0.2794)
			(end -0.12065 0.2794)
			(stroke
				(width 0.1)
				(type default)
			)
			(layer "F.Fab")
		)
		(fp_line
			(start -0.12065 0.3048)
			(end -0.67945 0.3048)
			(stroke
				(width 0.1)
				(type default)
			)
			(layer "F.Fab")
		)
		(fp_line
			(start -0.12065 0.2794)
			(end -0.12065 0.3048)
			(stroke
				(width 0.1)
				(type default)
			)
			(layer "F.Fab")
		)
		(fp_line
			(start -0.12065 -0.2794)
			(end 0.12065 -0.2794)
			(stroke
				(width 0.1)
				(type default)
			)
			(layer "F.Fab")
		)
		(fp_line
			(start -0.12065 -0.305054)
			(end -0.12065 -0.2794)
			(stroke
				(width 0.1)
				(type default)
			)
			(layer "F.Fab")
		)
		(fp_line
			(start -0.67945 0.3048)
			(end -0.67945 -0.305054)
			(stroke
				(width 0.1)
				(type default)
			)
			(layer "F.Fab")
		)
		(fp_line
			(start -0.67945 -0.305054)
			(end -0.12065 -0.305054)
			(stroke
				(width 0.1)
				(type default)
			)
			(layer "F.Fab")
		)
		(pad "1" smd circle
			(at -0.40005 0 180)
			(size 0 0)
			(layers "F.Cu" "F.Mask" "F.Paste")
			(net "GND")
		)
		(pad "2" smd circle
			(at 0.40005 0 180)
			(size 0 0)
			(layers "F.Cu" "F.Mask" "F.Paste")
			(net "OCP_V3_2_AUX_PWR_EN")
		)
	)
	(footprint ""
		(layer "F.Cu")
		(at 159.655256 -63.297308)
		(property "Reference" "R2114"
			(at 0 0 0)
			(layer "F.SilkS")
			(hide yes)
			(effects
				(font
					(size 1.27 1.27)
				)
			)
		)
		(property "Value" ""
			(at 0 0 0)
			(layer "F.Fab")
			(effects
				(font
					(size 1.27 1.27)
				)
			)
		)
		(duplicate_pad_numbers_are_jumpers no)
		(fp_line
			(start -0.7874 -0.4064)
			(end 0.7874 -0.4064)
			(stroke
				(width 0.1524)
				(type default)
			)
			(layer "F.SilkS")
		)
		(fp_line
			(start -0.7874 0.4064)
			(end -0.7874 -0.4064)
			(stroke
				(width 0.1524)
				(type default)
			)
			(layer "F.SilkS")
		)
		(fp_line
			(start 0.7874 -0.4064)
			(end 0.7874 0.4064)
			(stroke
				(width 0.1524)
				(type default)
			)
			(layer "F.SilkS")
		)
		(fp_line
			(start 0.7874 0.4064)
			(end -0.7874 0.4064)
			(stroke
				(width 0.1524)
				(type default)
			)
			(layer "F.SilkS")
		)
		(fp_line
			(start -0.67945 -0.305054)
			(end -0.12065 -0.305054)
			(stroke
				(width 0.1)
				(type default)
			)
			(layer "F.Fab")
		)
		(fp_line
			(start -0.67945 0.3048)
			(end -0.67945 -0.305054)
			(stroke
				(width 0.1)
				(type default)
			)
			(layer "F.Fab")
		)
		(fp_line
			(start -0.12065 -0.305054)
			(end -0.12065 -0.2794)
			(stroke
				(width 0.1)
				(type default)
			)
			(layer "F.Fab")
		)
		(fp_line
			(start -0.12065 -0.2794)
			(end 0.12065 -0.2794)
			(stroke
				(width 0.1)
				(type default)
			)
			(layer "F.Fab")
		)
		(fp_line
			(start -0.12065 0.2794)
			(end -0.12065 0.3048)
			(stroke
				(width 0.1)
				(type default)
			)
			(layer "F.Fab")
		)
		(fp_line
			(start -0.12065 0.3048)
			(end -0.67945 0.3048)
			(stroke
				(width 0.1)
				(type default)
			)
			(layer "F.Fab")
		)
		(fp_line
			(start 0.120396 0.2794)
			(end -0.12065 0.2794)
			(stroke
				(width 0.1)
				(type default)
			)
			(layer "F.Fab")
		)
		(fp_line
			(start 0.120396 0.3048)
			(end 0.120396 0.2794)
			(stroke
				(width 0.1)
				(type default)
			)
			(layer "F.Fab")
		)
		(fp_line
			(start 0.12065 -0.3048)
			(end 0.67945 -0.3048)
			(stroke
				(width 0.1)
				(type default)
			)
			(layer "F.Fab")
		)
		(fp_line
			(start 0.12065 -0.2794)
			(end 0.12065 -0.3048)
			(stroke
				(width 0.1)
				(type default)
			)
			(layer "F.Fab")
		)
		(fp_line
			(start 0.67945 -0.3048)
			(end 0.67945 0.3048)
			(stroke
				(width 0.1)
				(type default)
			)
			(layer "F.Fab")
		)
		(fp_line
			(start 0.67945 0.3048)
			(end 0.120396 0.3048)
			(stroke
				(width 0.1)
				(type default)
			)
			(layer "F.Fab")
		)
		(pad "1" smd circle
			(at -0.40005 0)
			(size 0 0)
			(layers "F.Cu" "F.Mask" "F.Paste")
			(net "SMB_PCIE_E1S_ISO_EN_R2")
		)
		(pad "2" smd circle
			(at 0.40005 0)
			(size 0 0)
			(layers "F.Cu" "F.Mask" "F.Paste")
			(net "SMB_PCIE_E1S_ISO_EN")
		)
	)
	(footprint ""
		(layer "F.Cu")
		(at 26.97988 -430.875948)
		(property "Reference" "U256"
			(at -1.9558 -1.97739 0)
			(unlocked yes)
			(layer "F.SilkS")
			(effects
				(font
					(size 0.7874 0.5842)
					(thickness 0.1524)
				)
				(justify left)
			)
		)
		(property "Value" ""
			(at 0 0 0)
			(layer "F.Fab")
			(effects
				(font
					(size 1.27 1.27)
				)
			)
		)
		(duplicate_pad_numbers_are_jumpers no)
		(fp_line
			(start -1.3462 -1.100074)
			(end -0.670052 -1.100074)
			(stroke
				(width 0.1524)
				(type default)
			)
			(layer "F.SilkS")
		)
		(fp_line
			(start -1.3462 1.100074)
			(end -1.3462 -1.100074)
			(stroke
				(width 0.1524)
				(type default)
			)
			(layer "F.SilkS")
		)
		(fp_line
			(start -0.670052 -1.100074)
			(end 0 -0.381)
			(stroke
				(width 0.1524)
				(type default)
			)
			(layer "F.SilkS")
		)
		(fp_line
			(start 0 -0.381)
			(end 0.670052 -1.100074)
			(stroke
				(width 0.1524)
				(type default)
			)
			(layer "F.SilkS")
		)
		(fp_line
			(start 0.670052 -1.100074)
			(end 1.3462 -1.100074)
			(stroke
				(width 0.1524)
				(type default)
			)
			(layer "F.SilkS")
		)
		(fp_line
			(start 1.3462 -1.100074)
			(end 1.3462 1.100074)
			(stroke
				(width 0.1524)
				(type default)
			)
			(layer "F.SilkS")
		)
		(fp_line
			(start 1.3462 1.100074)
			(end -1.3462 1.100074)
			(stroke
				(width 0.1524)
				(type default)
			)
			(layer "F.SilkS")
		)
		(fp_poly
			(pts
				(xy -2.01676 -0.685546) (xy -2.77876 -0.304546) (xy -2.77876 -1.066546)
			)
			(stroke
				(width 0)
				(type default)
			)
			(fill yes)
			(layer "F.SilkS")
		)
		(fp_line
			(start -1.100074 -0.8001)
			(end -0.670052 -0.8001)
			(stroke
				(width 0.1)
				(type default)
			)
			(layer "F.Fab")
		)
		(fp_line
			(start -1.100074 0.8001)
			(end -1.100074 -0.8001)
			(stroke
				(width 0.1)
				(type default)
			)
			(layer "F.Fab")
		)
		(fp_line
			(start -0.670052 -1.100074)
			(end 0.670052 -1.100074)
			(stroke
				(width 0.1)
				(type default)
			)
			(layer "F.Fab")
		)
		(fp_line
			(start -0.670052 -0.8001)
			(end -0.670052 -1.100074)
			(stroke
				(width 0.1)
				(type default)
			)
			(layer "F.Fab")
		)
		(fp_line
			(start -0.670052 0.8001)
			(end -1.100074 0.8001)
			(stroke
				(width 0.1)
				(type default)
			)
			(layer "F.Fab")
		)
		(fp_line
			(start -0.670052 0.8001)
			(end -0.670052 -0.8001)
			(stroke
				(width 0.1)
				(type default)
			)
			(layer "F.Fab")
		)
		(fp_line
			(start -0.670052 1.100074)
			(end -0.670052 0.8001)
			(stroke
				(width 0.1)
				(type default)
			)
			(layer "F.Fab")
		)
		(fp_line
			(start 0.670052 -1.100074)
			(end 0.670052 -0.8001)
			(stroke
				(width 0.1)
				(type default)
			)
			(layer "F.Fab")
		)
		(fp_line
			(start 0.670052 -0.8001)
			(end 0.670052 0.8001)
			(stroke
				(width 0.1)
				(type default)
			)
			(layer "F.Fab")
		)
		(fp_line
			(start 0.670052 -0.8001)
			(end 1.100074 -0.8001)
			(stroke
				(width 0.1)
				(type default)
			)
			(layer "F.Fab")
		)
		(fp_line
			(start 0.670052 0.8001)
			(end 0.670052 1.100074)
			(stroke
				(width 0.1)
				(type default)
			)
			(layer "F.Fab")
		)
		(fp_line
			(start 0.670052 1.100074)
			(end -0.670052 1.100074)
			(stroke
				(width 0.1)
				(type default)
			)
			(layer "F.Fab")
		)
		(fp_line
			(start 1.100074 -0.8001)
			(end 1.100074 0.8001)
			(stroke
				(width 0.1)
				(type default)
			)
			(layer "F.Fab")
		)
		(fp_line
			(start 1.100074 0.8001)
			(end 0.670052 0.8001)
			(stroke
				(width 0.1)
				(type default)
			)
			(layer "F.Fab")
		)
		(fp_poly
			(pts
				(xy -1.524 -0.649986) (xy -2.286 -1.030986) (xy -2.286 -0.268986)
			)
			(stroke
				(width 0)
				(type default)
			)
			(fill yes)
			(layer "F.Fab")
		)
		(pad "1" smd rect
			(at -0.94996 -0.649986 270)
			(size 0.4064 0.508)
			(layers "F.Cu" "F.Mask" "F.Paste")
			(net "RST_PERST_SWB_R_N")
		)
		(pad "2" smd rect
			(at -0.94996 0 270)
			(size 0.4064 0.508)
			(layers "F.Cu" "F.Mask" "F.Paste")
			(net "GND")
		)
		(pad "3" smd rect
			(at -0.94996 0.649986 270)
			(size 0.4064 0.508)
			(layers "F.Cu" "F.Mask" "F.Paste")
			(net "FM_SWB_PWR_EN_R")
		)
		(pad "4" smd rect
			(at 0.94996 0.649986 270)
			(size 0.4064 0.508)
			(layers "F.Cu" "F.Mask" "F.Paste")
			(net "FM_SWB_PWR_EN_R1_BUF")
		)
		(pad "5" smd rect
			(at 0.94996 0 270)
			(size 0.4064 0.508)
			(layers "F.Cu" "F.Mask" "F.Paste")
			(net "P3V3_AUX")
		)
		(pad "6" smd rect
			(at 0.94996 -0.649986 270)
			(size 0.4064 0.508)
			(layers "F.Cu" "F.Mask" "F.Paste")
			(net "RST_PERST_2_SWB_BUF_R_N")
		)
	)
	(footprint ""
		(layer "F.Cu")
		(at 167.064944 -354.6602)
		(property "Reference" "PR701"
			(at 0 0 0)
			(layer "F.SilkS")
			(hide yes)
			(effects
				(font
					(size 1.27 1.27)
				)
			)
		)
		(property "Value" ""
			(at 0 0 0)
			(layer "F.Fab")
			(effects
				(font
					(size 1.27 1.27)
				)
			)
		)
		(duplicate_pad_numbers_are_jumpers no)
		(fp_line
			(start -0.7874 -0.4064)
			(end 0.7874 -0.4064)
			(stroke
				(width 0.1524)
				(type default)
			)
			(layer "F.SilkS")
		)
		(fp_line
			(start -0.7874 0.4064)
			(end -0.7874 -0.4064)
			(stroke
				(width 0.1524)
				(type default)
			)
			(layer "F.SilkS")
		)
		(fp_line
			(start 0.7874 -0.4064)
			(end 0.7874 0.4064)
			(stroke
				(width 0.1524)
				(type default)
			)
			(layer "F.SilkS")
		)
		(fp_line
			(start 0.7874 0.4064)
			(end -0.7874 0.4064)
			(stroke
				(width 0.1524)
				(type default)
			)
			(layer "F.SilkS")
		)
		(fp_line
			(start -0.67945 -0.305054)
			(end -0.12065 -0.305054)
			(stroke
				(width 0.1)
				(type default)
			)
			(layer "F.Fab")
		)
		(fp_line
			(start -0.67945 0.3048)
			(end -0.67945 -0.305054)
			(stroke
				(width 0.1)
				(type default)
			)
			(layer "F.Fab")
		)
		(fp_line
			(start -0.12065 -0.305054)
			(end -0.12065 -0.2794)
			(stroke
				(width 0.1)
				(type default)
			)
			(layer "F.Fab")
		)
		(fp_line
			(start -0.12065 -0.2794)
			(end 0.12065 -0.2794)
			(stroke
				(width 0.1)
				(type default)
			)
			(layer "F.Fab")
		)
		(fp_line
			(start -0.12065 0.2794)
			(end -0.12065 0.3048)
			(stroke
				(width 0.1)
				(type default)
			)
			(layer "F.Fab")
		)
		(fp_line
			(start -0.12065 0.3048)
			(end -0.67945 0.3048)
			(stroke
				(width 0.1)
				(type default)
			)
			(layer "F.Fab")
		)
		(fp_line
			(start 0.120396 0.2794)
			(end -0.12065 0.2794)
			(stroke
				(width 0.1)
				(type default)
			)
			(layer "F.Fab")
		)
		(fp_line
			(start 0.120396 0.3048)
			(end 0.120396 0.2794)
			(stroke
				(width 0.1)
				(type default)
			)
			(layer "F.Fab")
		)
		(fp_line
			(start 0.12065 -0.3048)
			(end 0.67945 -0.3048)
			(stroke
				(width 0.1)
				(type default)
			)
			(layer "F.Fab")
		)
		(fp_line
			(start 0.12065 -0.2794)
			(end 0.12065 -0.3048)
			(stroke
				(width 0.1)
				(type default)
			)
			(layer "F.Fab")
		)
		(fp_line
			(start 0.67945 -0.3048)
			(end 0.67945 0.3048)
			(stroke
				(width 0.1)
				(type default)
			)
			(layer "F.Fab")
		)
		(fp_line
			(start 0.67945 0.3048)
			(end 0.120396 0.3048)
			(stroke
				(width 0.1)
				(type default)
			)
			(layer "F.Fab")
		)
		(pad "1" smd circle
			(at -0.40005 0)
			(size 0 0)
			(layers "F.Cu" "F.Mask" "F.Paste")
			(net "P5V")
		)
		(pad "2" smd circle
			(at 0.40005 0)
			(size 0 0)
			(layers "F.Cu" "F.Mask" "F.Paste")
			(net "PVCCFA_EHV_FIVRA_CPU1_PVCC1")
		)
	)
	(footprint ""
		(layer "F.Cu")
		(at 145.17116 -40.114728 180)
		(property "Reference" "C1877"
			(at 0 0 180)
			(layer "F.SilkS")
			(hide yes)
			(effects
				(font
					(size 1.27 1.27)
				)
			)
		)
		(property "Value" ""
			(at 0 0 180)
			(layer "F.Fab")
			(effects
				(font
					(size 1.27 1.27)
				)
			)
		)
		(duplicate_pad_numbers_are_jumpers no)
		(fp_line
			(start 0.7874 0.4064)
			(end -0.7874 0.4064)
			(stroke
				(width 0.1524)
				(type default)
			)
			(layer "F.SilkS")
		)
		(fp_line
			(start 0.7874 -0.4064)
			(end 0.7874 0.4064)
			(stroke
				(width 0.1524)
				(type default)
			)
			(layer "F.SilkS")
		)
		(fp_line
			(start -0.7874 0.4064)
			(end -0.7874 -0.4064)
			(stroke
				(width 0.1524)
				(type default)
			)
			(layer "F.SilkS")
		)
		(fp_line
			(start -0.7874 -0.4064)
			(end 0.7874 -0.4064)
			(stroke
				(width 0.1524)
				(type default)
			)
			(layer "F.SilkS")
		)
		(fp_line
			(start 0.67945 0.3048)
			(end 0.120396 0.3048)
			(stroke
				(width 0.1)
				(type default)
			)
			(layer "F.Fab")
		)
		(fp_line
			(start 0.67945 -0.3048)
			(end 0.67945 0.3048)
			(stroke
				(width 0.1)
				(type default)
			)
			(layer "F.Fab")
		)
		(fp_line
			(start 0.12065 -0.2794)
			(end 0.12065 -0.3048)
			(stroke
				(width 0.1)
				(type default)
			)
			(layer "F.Fab")
		)
		(fp_line
			(start 0.12065 -0.3048)
			(end 0.67945 -0.3048)
			(stroke
				(width 0.1)
				(type default)
			)
			(layer "F.Fab")
		)
		(fp_line
			(start 0.120396 0.3048)
			(end 0.120396 0.2794)
			(stroke
				(width 0.1)
				(type default)
			)
			(layer "F.Fab")
		)
		(fp_line
			(start 0.120396 0.2794)
			(end -0.12065 0.2794)
			(stroke
				(width 0.1)
				(type default)
			)
			(layer "F.Fab")
		)
		(fp_line
			(start -0.12065 0.3048)
			(end -0.67945 0.3048)
			(stroke
				(width 0.1)
				(type default)
			)
			(layer "F.Fab")
		)
		(fp_line
			(start -0.12065 0.2794)
			(end -0.12065 0.3048)
			(stroke
				(width 0.1)
				(type default)
			)
			(layer "F.Fab")
		)
		(fp_line
			(start -0.12065 -0.2794)
			(end 0.12065 -0.2794)
			(stroke
				(width 0.1)
				(type default)
			)
			(layer "F.Fab")
		)
		(fp_line
			(start -0.12065 -0.305054)
			(end -0.12065 -0.2794)
			(stroke
				(width 0.1)
				(type default)
			)
			(layer "F.Fab")
		)
		(fp_line
			(start -0.67945 0.3048)
			(end -0.67945 -0.305054)
			(stroke
				(width 0.1)
				(type default)
			)
			(layer "F.Fab")
		)
		(fp_line
			(start -0.67945 -0.305054)
			(end -0.12065 -0.305054)
			(stroke
				(width 0.1)
				(type default)
			)
			(layer "F.Fab")
		)
		(pad "1" smd circle
			(at -0.40005 0 180)
			(size 0 0)
			(layers "F.Cu" "F.Mask" "F.Paste")
			(net "P3V3_AUX")
		)
		(pad "2" smd circle
			(at 0.40005 0 180)
			(size 0 0)
			(layers "F.Cu" "F.Mask" "F.Paste")
			(net "GND")
		)
	)
	(footprint ""
		(layer "F.Cu")
		(at 68.093336 -111.65967 180)
		(property "Reference" "R3703"
			(at 0 0 180)
			(layer "F.SilkS")
			(hide yes)
			(effects
				(font
					(size 1.27 1.27)
				)
			)
		)
		(property "Value" ""
			(at 0 0 180)
			(layer "F.Fab")
			(effects
				(font
					(size 1.27 1.27)
				)
			)
		)
		(duplicate_pad_numbers_are_jumpers no)
		(fp_line
			(start 0.7874 0.4064)
			(end -0.7874 0.4064)
			(stroke
				(width 0.1524)
				(type default)
			)
			(layer "F.SilkS")
		)
		(fp_line
			(start 0.7874 -0.4064)
			(end 0.7874 0.4064)
			(stroke
				(width 0.1524)
				(type default)
			)
			(layer "F.SilkS")
		)
		(fp_line
			(start -0.7874 0.4064)
			(end -0.7874 -0.4064)
			(stroke
				(width 0.1524)
				(type default)
			)
			(layer "F.SilkS")
		)
		(fp_line
			(start -0.7874 -0.4064)
			(end 0.7874 -0.4064)
			(stroke
				(width 0.1524)
				(type default)
			)
			(layer "F.SilkS")
		)
		(fp_line
			(start 0.67945 0.3048)
			(end 0.120396 0.3048)
			(stroke
				(width 0.1)
				(type default)
			)
			(layer "F.Fab")
		)
		(fp_line
			(start 0.67945 -0.3048)
			(end 0.67945 0.3048)
			(stroke
				(width 0.1)
				(type default)
			)
			(layer "F.Fab")
		)
		(fp_line
			(start 0.12065 -0.2794)
			(end 0.12065 -0.3048)
			(stroke
				(width 0.1)
				(type default)
			)
			(layer "F.Fab")
		)
		(fp_line
			(start 0.12065 -0.3048)
			(end 0.67945 -0.3048)
			(stroke
				(width 0.1)
				(type default)
			)
			(layer "F.Fab")
		)
		(fp_line
			(start 0.120396 0.3048)
			(end 0.120396 0.2794)
			(stroke
				(width 0.1)
				(type default)
			)
			(layer "F.Fab")
		)
		(fp_line
			(start 0.120396 0.2794)
			(end -0.12065 0.2794)
			(stroke
				(width 0.1)
				(type default)
			)
			(layer "F.Fab")
		)
		(fp_line
			(start -0.12065 0.3048)
			(end -0.67945 0.3048)
			(stroke
				(width 0.1)
				(type default)
			)
			(layer "F.Fab")
		)
		(fp_line
			(start -0.12065 0.2794)
			(end -0.12065 0.3048)
			(stroke
				(width 0.1)
				(type default)
			)
			(layer "F.Fab")
		)
		(fp_line
			(start -0.12065 -0.2794)
			(end 0.12065 -0.2794)
			(stroke
				(width 0.1)
				(type default)
			)
			(layer "F.Fab")
		)
		(fp_line
			(start -0.12065 -0.305054)
			(end -0.12065 -0.2794)
			(stroke
				(width 0.1)
				(type default)
			)
			(layer "F.Fab")
		)
		(fp_line
			(start -0.67945 0.3048)
			(end -0.67945 -0.305054)
			(stroke
				(width 0.1)
				(type default)
			)
			(layer "F.Fab")
		)
		(fp_line
			(start -0.67945 -0.305054)
			(end -0.12065 -0.305054)
			(stroke
				(width 0.1)
				(type default)
			)
			(layer "F.Fab")
		)
		(pad "1" smd circle
			(at -0.40005 0 180)
			(size 0 0)
			(layers "F.Cu" "F.Mask" "F.Paste")
			(net "P3V3_AUX")
		)
		(pad "2" smd circle
			(at 0.40005 0 180)
			(size 0 0)
			(layers "F.Cu" "F.Mask" "F.Paste")
			(net "PCA9548_PCIE0_ADDR2")
		)
	)
	(footprint ""
		(layer "F.Cu")
		(at 10.3124 -401.523708)
		(property "Reference" ""
			(at 0 0 0)
			(layer "F.SilkS")
			(hide yes)
			(effects
				(font
					(size 1.27 1.27)
				)
			)
		)
		(property "Value" ""
			(at 0 0 0)
			(layer "F.Fab")
			(effects
				(font
					(size 1.27 1.27)
				)
			)
		)
		(duplicate_pad_numbers_are_jumpers no)
		(pad "1" smd circle
			(at 0 0)
			(size 0.9906 0.9906)
			(layers "F.Cu" "F.Mask" "F.Paste")
			(net "Net_286")
		)
		(zone
			(layer "F.Cu")
			(hatch none 0.5)
			(connect_pads
				(clearance 0)
			)
			(min_thickness 0.25)
			(keepout
				(tracks not_allowed)
				(vias allowed)
				(pads allowed)
				(copperpour not_allowed)
				(footprints allowed)
			)
			(placement
				(enabled no)
				(sheetname "")
			)
			(fill
				(thermal_gap 0.5)
				(thermal_bridge_width 0.5)
				(island_removal_mode 0)
			)
			(polygon
				(pts
					(arc
						(start 11.938 -401.523708)
						(mid 8.6868 -401.523708)
						(end 11.938 -401.523708)
					)
				)
			)
		)
	)
	(footprint ""
		(layer "F.Cu")
		(at 209.74558 -133.878828 180)
		(property "Reference" "R1745"
			(at 0 0 180)
			(layer "F.SilkS")
			(hide yes)
			(effects
				(font
					(size 1.27 1.27)
				)
			)
		)
		(property "Value" ""
			(at 0 0 180)
			(layer "F.Fab")
			(effects
				(font
					(size 1.27 1.27)
				)
			)
		)
		(duplicate_pad_numbers_are_jumpers no)
		(fp_line
			(start 0.7874 0.4064)
			(end -0.7874 0.4064)
			(stroke
				(width 0.1524)
				(type default)
			)
			(layer "F.SilkS")
		)
		(fp_line
			(start 0.7874 -0.4064)
			(end 0.7874 0.4064)
			(stroke
				(width 0.1524)
				(type default)
			)
			(layer "F.SilkS")
		)
		(fp_line
			(start -0.7874 0.4064)
			(end -0.7874 -0.4064)
			(stroke
				(width 0.1524)
				(type default)
			)
			(layer "F.SilkS")
		)
		(fp_line
			(start -0.7874 -0.4064)
			(end 0.7874 -0.4064)
			(stroke
				(width 0.1524)
				(type default)
			)
			(layer "F.SilkS")
		)
		(fp_line
			(start 0.67945 0.3048)
			(end 0.120396 0.3048)
			(stroke
				(width 0.1)
				(type default)
			)
			(layer "F.Fab")
		)
		(fp_line
			(start 0.67945 -0.3048)
			(end 0.67945 0.3048)
			(stroke
				(width 0.1)
				(type default)
			)
			(layer "F.Fab")
		)
		(fp_line
			(start 0.12065 -0.2794)
			(end 0.12065 -0.3048)
			(stroke
				(width 0.1)
				(type default)
			)
			(layer "F.Fab")
		)
		(fp_line
			(start 0.12065 -0.3048)
			(end 0.67945 -0.3048)
			(stroke
				(width 0.1)
				(type default)
			)
			(layer "F.Fab")
		)
		(fp_line
			(start 0.120396 0.3048)
			(end 0.120396 0.2794)
			(stroke
				(width 0.1)
				(type default)
			)
			(layer "F.Fab")
		)
		(fp_line
			(start 0.120396 0.2794)
			(end -0.12065 0.2794)
			(stroke
				(width 0.1)
				(type default)
			)
			(layer "F.Fab")
		)
		(fp_line
			(start -0.12065 0.3048)
			(end -0.67945 0.3048)
			(stroke
				(width 0.1)
				(type default)
			)
			(layer "F.Fab")
		)
		(fp_line
			(start -0.12065 0.2794)
			(end -0.12065 0.3048)
			(stroke
				(width 0.1)
				(type default)
			)
			(layer "F.Fab")
		)
		(fp_line
			(start -0.12065 -0.2794)
			(end 0.12065 -0.2794)
			(stroke
				(width 0.1)
				(type default)
			)
			(layer "F.Fab")
		)
		(fp_line
			(start -0.12065 -0.305054)
			(end -0.12065 -0.2794)
			(stroke
				(width 0.1)
				(type default)
			)
			(layer "F.Fab")
		)
		(fp_line
			(start -0.67945 0.3048)
			(end -0.67945 -0.305054)
			(stroke
				(width 0.1)
				(type default)
			)
			(layer "F.Fab")
		)
		(fp_line
			(start -0.67945 -0.305054)
			(end -0.12065 -0.305054)
			(stroke
				(width 0.1)
				(type default)
			)
			(layer "F.Fab")
		)
		(pad "1" smd circle
			(at -0.40005 0 180)
			(size 0 0)
			(layers "F.Cu" "F.Mask" "F.Paste")
			(net "FM_COMP_P3V3_AUX_ENIN")
		)
		(pad "2" smd circle
			(at 0.40005 0 180)
			(size 0 0)
			(layers "F.Cu" "F.Mask" "F.Paste")
			(net "FM_PFR_DSW_PWROK_N")
		)
	)
	(footprint ""
		(layer "F.Cu")
		(at 414.869122 -367.231676)
		(property "Reference" "PR354"
			(at 0 0 0)
			(layer "F.SilkS")
			(hide yes)
			(effects
				(font
					(size 1.27 1.27)
				)
			)
		)
		(property "Value" ""
			(at 0 0 0)
			(layer "F.Fab")
			(effects
				(font
					(size 1.27 1.27)
				)
			)
		)
		(duplicate_pad_numbers_are_jumpers no)
		(fp_line
			(start -0.7874 -0.4064)
			(end 0.7874 -0.4064)
			(stroke
				(width 0.1524)
				(type default)
			)
			(layer "F.SilkS")
		)
		(fp_line
			(start -0.7874 0.4064)
			(end -0.7874 -0.4064)
			(stroke
				(width 0.1524)
				(type default)
			)
			(layer "F.SilkS")
		)
		(fp_line
			(start 0.7874 -0.4064)
			(end 0.7874 0.4064)
			(stroke
				(width 0.1524)
				(type default)
			)
			(layer "F.SilkS")
		)
		(fp_line
			(start 0.7874 0.4064)
			(end -0.7874 0.4064)
			(stroke
				(width 0.1524)
				(type default)
			)
			(layer "F.SilkS")
		)
		(fp_line
			(start -0.67945 -0.305054)
			(end -0.12065 -0.305054)
			(stroke
				(width 0.1)
				(type default)
			)
			(layer "F.Fab")
		)
		(fp_line
			(start -0.67945 0.3048)
			(end -0.67945 -0.305054)
			(stroke
				(width 0.1)
				(type default)
			)
			(layer "F.Fab")
		)
		(fp_line
			(start -0.12065 -0.305054)
			(end -0.12065 -0.2794)
			(stroke
				(width 0.1)
				(type default)
			)
			(layer "F.Fab")
		)
		(fp_line
			(start -0.12065 -0.2794)
			(end 0.12065 -0.2794)
			(stroke
				(width 0.1)
				(type default)
			)
			(layer "F.Fab")
		)
		(fp_line
			(start -0.12065 0.2794)
			(end -0.12065 0.3048)
			(stroke
				(width 0.1)
				(type default)
			)
			(layer "F.Fab")
		)
		(fp_line
			(start -0.12065 0.3048)
			(end -0.67945 0.3048)
			(stroke
				(width 0.1)
				(type default)
			)
			(layer "F.Fab")
		)
		(fp_line
			(start 0.120396 0.2794)
			(end -0.12065 0.2794)
			(stroke
				(width 0.1)
				(type default)
			)
			(layer "F.Fab")
		)
		(fp_line
			(start 0.120396 0.3048)
			(end 0.120396 0.2794)
			(stroke
				(width 0.1)
				(type default)
			)
			(layer "F.Fab")
		)
		(fp_line
			(start 0.12065 -0.3048)
			(end 0.67945 -0.3048)
			(stroke
				(width 0.1)
				(type default)
			)
			(layer "F.Fab")
		)
		(fp_line
			(start 0.12065 -0.2794)
			(end 0.12065 -0.3048)
			(stroke
				(width 0.1)
				(type default)
			)
			(layer "F.Fab")
		)
		(fp_line
			(start 0.67945 -0.3048)
			(end 0.67945 0.3048)
			(stroke
				(width 0.1)
				(type default)
			)
			(layer "F.Fab")
		)
		(fp_line
			(start 0.67945 0.3048)
			(end 0.120396 0.3048)
			(stroke
				(width 0.1)
				(type default)
			)
			(layer "F.Fab")
		)
		(pad "1" smd circle
			(at -0.40005 0)
			(size 0 0)
			(layers "F.Cu" "F.Mask" "F.Paste")
			(net "PVCCFA_EHV_FIVRA_CPU0_LSET1")
		)
		(pad "2" smd circle
			(at 0.40005 0)
			(size 0 0)
			(layers "F.Cu" "F.Mask" "F.Paste")
			(net "GND")
		)
	)
	(footprint ""
		(layer "F.Cu")
		(at 157.00121 -70.26402 -90)
		(property "Reference" "R2311"
			(at 0 0 270)
			(layer "F.SilkS")
			(hide yes)
			(effects
				(font
					(size 1.27 1.27)
				)
			)
		)
		(property "Value" ""
			(at 0 0 270)
			(layer "F.Fab")
			(effects
				(font
					(size 1.27 1.27)
				)
			)
		)
		(duplicate_pad_numbers_are_jumpers no)
		(fp_line
			(start -0.7874 0.4064)
			(end -0.7874 -0.4064)
			(stroke
				(width 0.1524)
				(type default)
			)
			(layer "F.SilkS")
		)
		(fp_line
			(start 0.7874 0.4064)
			(end -0.7874 0.4064)
			(stroke
				(width 0.1524)
				(type default)
			)
			(layer "F.SilkS")
		)
		(fp_line
			(start -0.7874 -0.4064)
			(end 0.7874 -0.4064)
			(stroke
				(width 0.1524)
				(type default)
			)
			(layer "F.SilkS")
		)
		(fp_line
			(start 0.7874 -0.4064)
			(end 0.7874 0.4064)
			(stroke
				(width 0.1524)
				(type default)
			)
			(layer "F.SilkS")
		)
		(fp_line
			(start -0.67945 0.3048)
			(end -0.67945 -0.305054)
			(stroke
				(width 0.1)
				(type default)
			)
			(layer "F.Fab")
		)
		(fp_line
			(start -0.12065 0.3048)
			(end -0.67945 0.3048)
			(stroke
				(width 0.1)
				(type default)
			)
			(layer "F.Fab")
		)
		(fp_line
			(start 0.120396 0.3048)
			(end 0.120396 0.2794)
			(stroke
				(width 0.1)
				(type default)
			)
			(layer "F.Fab")
		)
		(fp_line
			(start 0.67945 0.3048)
			(end 0.120396 0.3048)
			(stroke
				(width 0.1)
				(type default)
			)
			(layer "F.Fab")
		)
		(fp_line
			(start -0.12065 0.2794)
			(end -0.12065 0.3048)
			(stroke
				(width 0.1)
				(type default)
			)
			(layer "F.Fab")
		)
		(fp_line
			(start 0.120396 0.2794)
			(end -0.12065 0.2794)
			(stroke
				(width 0.1)
				(type default)
			)
			(layer "F.Fab")
		)
		(fp_line
			(start -0.12065 -0.2794)
			(end 0.12065 -0.2794)
			(stroke
				(width 0.1)
				(type default)
			)
			(layer "F.Fab")
		)
		(fp_line
			(start 0.12065 -0.2794)
			(end 0.12065 -0.3048)
			(stroke
				(width 0.1)
				(type default)
			)
			(layer "F.Fab")
		)
		(fp_line
			(start 0.12065 -0.3048)
			(end 0.67945 -0.3048)
			(stroke
				(width 0.1)
				(type default)
			)
			(layer "F.Fab")
		)
		(fp_line
			(start 0.67945 -0.3048)
			(end 0.67945 0.3048)
			(stroke
				(width 0.1)
				(type default)
			)
			(layer "F.Fab")
		)
		(fp_line
			(start -0.67945 -0.305054)
			(end -0.12065 -0.305054)
			(stroke
				(width 0.1)
				(type default)
			)
			(layer "F.Fab")
		)
		(fp_line
			(start -0.12065 -0.305054)
			(end -0.12065 -0.2794)
			(stroke
				(width 0.1)
				(type default)
			)
			(layer "F.Fab")
		)
		(pad "1" smd circle
			(at -0.40005 0 270)
			(size 0 0)
			(layers "F.Cu" "F.Mask" "F.Paste")
			(net "PCA9543_S3M_ADDR0")
		)
		(pad "2" smd circle
			(at 0.40005 0 270)
			(size 0 0)
			(layers "F.Cu" "F.Mask" "F.Paste")
			(net "GND")
		)
	)
	(footprint ""
		(layer "F.Cu")
		(at 125.65888 -92.674948 90)
		(property "Reference" "R238"
			(at 0 0 90)
			(layer "F.SilkS")
			(hide yes)
			(effects
				(font
					(size 1.27 1.27)
				)
			)
		)
		(property "Value" ""
			(at 0 0 90)
			(layer "F.Fab")
			(effects
				(font
					(size 1.27 1.27)
				)
			)
		)
		(duplicate_pad_numbers_are_jumpers no)
		(fp_line
			(start 0.7874 -0.4064)
			(end 0.7874 0.4064)
			(stroke
				(width 0.1524)
				(type default)
			)
			(layer "F.SilkS")
		)
		(fp_line
			(start -0.7874 -0.4064)
			(end 0.7874 -0.4064)
			(stroke
				(width 0.1524)
				(type default)
			)
			(layer "F.SilkS")
		)
		(fp_line
			(start 0.7874 0.4064)
			(end -0.7874 0.4064)
			(stroke
				(width 0.1524)
				(type default)
			)
			(layer "F.SilkS")
		)
		(fp_line
			(start -0.7874 0.4064)
			(end -0.7874 -0.4064)
			(stroke
				(width 0.1524)
				(type default)
			)
			(layer "F.SilkS")
		)
		(fp_line
			(start -0.12065 -0.305054)
			(end -0.12065 -0.2794)
			(stroke
				(width 0.1)
				(type default)
			)
			(layer "F.Fab")
		)
		(fp_line
			(start -0.67945 -0.305054)
			(end -0.12065 -0.305054)
			(stroke
				(width 0.1)
				(type default)
			)
			(layer "F.Fab")
		)
		(fp_line
			(start 0.67945 -0.3048)
			(end 0.67945 0.3048)
			(stroke
				(width 0.1)
				(type default)
			)
			(layer "F.Fab")
		)
		(fp_line
			(start 0.12065 -0.3048)
			(end 0.67945 -0.3048)
			(stroke
				(width 0.1)
				(type default)
			)
			(layer "F.Fab")
		)
		(fp_line
			(start 0.12065 -0.2794)
			(end 0.12065 -0.3048)
			(stroke
				(width 0.1)
				(type default)
			)
			(layer "F.Fab")
		)
		(fp_line
			(start -0.12065 -0.2794)
			(end 0.12065 -0.2794)
			(stroke
				(width 0.1)
				(type default)
			)
			(layer "F.Fab")
		)
		(fp_line
			(start 0.120396 0.2794)
			(end -0.12065 0.2794)
			(stroke
				(width 0.1)
				(type default)
			)
			(layer "F.Fab")
		)
		(fp_line
			(start -0.12065 0.2794)
			(end -0.12065 0.3048)
			(stroke
				(width 0.1)
				(type default)
			)
			(layer "F.Fab")
		)
		(fp_line
			(start 0.67945 0.3048)
			(end 0.120396 0.3048)
			(stroke
				(width 0.1)
				(type default)
			)
			(layer "F.Fab")
		)
		(fp_line
			(start 0.120396 0.3048)
			(end 0.120396 0.2794)
			(stroke
				(width 0.1)
				(type default)
			)
			(layer "F.Fab")
		)
		(fp_line
			(start -0.12065 0.3048)
			(end -0.67945 0.3048)
			(stroke
				(width 0.1)
				(type default)
			)
			(layer "F.Fab")
		)
		(fp_line
			(start -0.67945 0.3048)
			(end -0.67945 -0.305054)
			(stroke
				(width 0.1)
				(type default)
			)
			(layer "F.Fab")
		)
		(pad "1" smd circle
			(at -0.40005 0 90)
			(size 0 0)
			(layers "F.Cu" "F.Mask" "F.Paste")
			(net "H_CPU1_THERMTRIP_LVC1_R_N")
		)
		(pad "2" smd circle
			(at 0.40005 0 90)
			(size 0 0)
			(layers "F.Cu" "F.Mask" "F.Paste")
			(net "H_CPU1_THERMTRIP_VT_R_N")
		)
	)
	(footprint ""
		(layer "F.Cu")
		(at 202.59802 -128.516888 180)
		(property "Reference" "U158"
			(at 1.68402 -2.72161 0)
			(unlocked yes)
			(layer "F.SilkS")
			(effects
				(font
					(size 0.7874 0.5842)
					(thickness 0.1524)
				)
				(justify left)
			)
		)
		(property "Value" ""
			(at 0 0 180)
			(layer "F.Fab")
			(effects
				(font
					(size 1.27 1.27)
				)
			)
		)
		(duplicate_pad_numbers_are_jumpers no)
		(fp_line
			(start 1.603248 1.500124)
			(end -1.603248 1.500124)
			(stroke
				(width 0.1524)
				(type default)
			)
			(layer "F.SilkS")
		)
		(fp_line
			(start 1.603248 -1.500124)
			(end 1.603248 1.500124)
			(stroke
				(width 0.1524)
				(type default)
			)
			(layer "F.SilkS")
		)
		(fp_line
			(start -1.603248 1.500124)
			(end -1.603248 -1.500124)
			(stroke
				(width 0.1524)
				(type default)
			)
			(layer "F.SilkS")
		)
		(fp_line
			(start -1.603248 -1.500124)
			(end 1.603248 -1.500124)
			(stroke
				(width 0.1524)
				(type default)
			)
			(layer "F.SilkS")
		)
		(fp_line
			(start 1.249934 0.219964)
			(end 1.249934 -0.219964)
			(stroke
				(width 0.1)
				(type default)
			)
			(layer "F.Fab")
		)
		(fp_line
			(start 1.249934 -0.219964)
			(end 0.700024 -0.219964)
			(stroke
				(width 0.1)
				(type default)
			)
			(layer "F.Fab")
		)
		(fp_line
			(start 0.700024 1.500124)
			(end 0.700024 0.219964)
			(stroke
				(width 0.1)
				(type default)
			)
			(layer "F.Fab")
		)
		(fp_line
			(start 0.700024 0.219964)
			(end 1.249934 0.219964)
			(stroke
				(width 0.1)
				(type default)
			)
			(layer "F.Fab")
		)
		(fp_line
			(start 0.700024 -0.219964)
			(end 0.700024 -1.500124)
			(stroke
				(width 0.1)
				(type default)
			)
			(layer "F.Fab")
		)
		(fp_line
			(start 0.700024 -1.500124)
			(end -0.700024 -1.500124)
			(stroke
				(width 0.1)
				(type default)
			)
			(layer "F.Fab")
		)
		(fp_line
			(start -0.6985 0.729996)
			(end -1.249934 0.729996)
			(stroke
				(width 0.1)
				(type default)
			)
			(layer "F.Fab")
		)
		(fp_line
			(start -0.6985 -0.729996)
			(end -0.6985 0.729996)
			(stroke
				(width 0.1)
				(type default)
			)
			(layer "F.Fab")
		)
		(fp_line
			(start -0.700024 1.500124)
			(end 0.700024 1.500124)
			(stroke
				(width 0.1)
				(type default)
			)
			(layer "F.Fab")
		)
		(fp_line
			(start -0.700024 1.169924)
			(end -0.700024 1.500124)
			(stroke
				(width 0.1)
				(type default)
			)
			(layer "F.Fab")
		)
		(fp_line
			(start -0.700024 -1.169924)
			(end -1.249934 -1.169924)
			(stroke
				(width 0.1)
				(type default)
			)
			(layer "F.Fab")
		)
		(fp_line
			(start -0.700024 -1.500124)
			(end -0.700024 -1.169924)
			(stroke
				(width 0.1)
				(type default)
			)
			(layer "F.Fab")
		)
		(fp_line
			(start -1.249934 1.169924)
			(end -0.700024 1.169924)
			(stroke
				(width 0.1)
				(type default)
			)
			(layer "F.Fab")
		)
		(fp_line
			(start -1.249934 0.729996)
			(end -1.249934 1.169924)
			(stroke
				(width 0.1)
				(type default)
			)
			(layer "F.Fab")
		)
		(fp_line
			(start -1.249934 -0.729996)
			(end -0.6985 -0.729996)
			(stroke
				(width 0.1)
				(type default)
			)
			(layer "F.Fab")
		)
		(fp_line
			(start -1.249934 -1.169924)
			(end -1.249934 -0.729996)
			(stroke
				(width 0.1)
				(type default)
			)
			(layer "F.Fab")
		)
		(fp_rect
			(start -0.700024 -1.500124)
			(end 0.700024 1.500124)
			(stroke
				(width 0)
				(type default)
			)
			(fill no)
			(layer "F.Fab")
		)
		(pad "D" smd rect
			(at 0.999998 0 90)
			(size 0.8128 0.9144)
			(layers "F.Cu" "F.Mask" "F.Paste")
			(net "FM_P12V_HSC_EN_N")
		)
		(pad "G" smd rect
			(at -0.999998 -0.94996 90)
			(size 0.8128 0.9144)
			(layers "F.Cu" "F.Mask" "F.Paste")
			(net "FM_P12V_HSC_EN_R")
		)
		(pad "S" smd rect
			(at -0.999998 0.94996 90)
			(size 0.8128 0.9144)
			(layers "F.Cu" "F.Mask" "F.Paste")
			(net "GND")
		)
	)
	(footprint ""
		(layer "F.Cu")
		(at 358.648 -402.844)
		(property "Reference" "Q152"
			(at 0.23876 1.764792 0)
			(unlocked yes)
			(layer "F.SilkS")
			(effects
				(font
					(size 0.7874 0.5842)
					(thickness 0.1524)
				)
				(justify left)
			)
		)
		(property "Value" ""
			(at 0 0 0)
			(layer "F.Fab")
			(effects
				(font
					(size 1.27 1.27)
				)
			)
		)
		(duplicate_pad_numbers_are_jumpers no)
		(fp_line
			(start -1.332738 -1.100074)
			(end -0.4826 -1.100074)
			(stroke
				(width 0.1524)
				(type default)
			)
			(layer "F.SilkS")
		)
		(fp_line
			(start -1.332738 1.100074)
			(end -1.332738 -1.100074)
			(stroke
				(width 0.1524)
				(type default)
			)
			(layer "F.SilkS")
		)
		(fp_line
			(start -0.4826 -1.100074)
			(end 0 -0.541274)
			(stroke
				(width 0.1524)
				(type default)
			)
			(layer "F.SilkS")
		)
		(fp_line
			(start 0 -0.541274)
			(end 0.4826 -1.100074)
			(stroke
				(width 0.1524)
				(type default)
			)
			(layer "F.SilkS")
		)
		(fp_line
			(start 0.4826 -1.100074)
			(end 1.332738 -1.100074)
			(stroke
				(width 0.1524)
				(type default)
			)
			(layer "F.SilkS")
		)
		(fp_line
			(start 1.332738 -1.100074)
			(end 1.332738 1.100074)
			(stroke
				(width 0.1524)
				(type default)
			)
			(layer "F.SilkS")
		)
		(fp_line
			(start 1.332738 1.100074)
			(end -1.332738 1.100074)
			(stroke
				(width 0.1524)
				(type default)
			)
			(layer "F.SilkS")
		)
		(fp_poly
			(pts
				(xy -1.921764 -1.517396) (xy -1.425194 -2.013966) (xy -1.177036 -1.269238)
			)
			(stroke
				(width 0)
				(type default)
			)
			(fill yes)
			(layer "F.SilkS")
		)
		(fp_line
			(start -0.674878 -1.100074)
			(end 0.674878 -1.100074)
			(stroke
				(width 0.1)
				(type default)
			)
			(layer "F.Fab")
		)
		(fp_line
			(start -0.674878 1.100074)
			(end -0.674878 -1.100074)
			(stroke
				(width 0.1)
				(type default)
			)
			(layer "F.Fab")
		)
		(fp_line
			(start 0.674878 -1.100074)
			(end 0.674878 1.100074)
			(stroke
				(width 0.1)
				(type default)
			)
			(layer "F.Fab")
		)
		(fp_line
			(start 0.674878 1.100074)
			(end -0.674878 1.100074)
			(stroke
				(width 0.1)
				(type default)
			)
			(layer "F.Fab")
		)
		(fp_poly
			(pts
				(xy -2.2352 -0.298958) (xy -2.2352 -1.001014) (xy -1.533144 -0.649986)
			)
			(stroke
				(width 0)
				(type default)
			)
			(fill yes)
			(layer "F.Fab")
		)
		(pad "1" smd rect
			(at -0.94996 -0.649986 90)
			(size 0.4318 0.508)
			(layers "F.Cu" "F.Mask" "F.Paste")
			(net "GND")
		)
		(pad "2" smd rect
			(at -0.94996 0 90)
			(size 0.4318 0.508)
			(layers "F.Cu" "F.Mask" "F.Paste")
			(net "PRSNT_CABLE_SWB_B2_N")
		)
		(pad "3" smd rect
			(at -0.94996 0.649986 90)
			(size 0.4318 0.508)
			(layers "F.Cu" "F.Mask" "F.Paste")
			(net "PRSNT_CABLE_SWB_B2_ISO_N")
		)
		(pad "4" smd rect
			(at 0.94996 0.649986 90)
			(size 0.4318 0.508)
			(layers "F.Cu" "F.Mask" "F.Paste")
			(net "GND")
		)
		(pad "5" smd rect
			(at 0.94996 0 90)
			(size 0.4318 0.508)
			(layers "F.Cu" "F.Mask" "F.Paste")
			(net "PRSNT_CABLE_SWB_B2")
		)
		(pad "6" smd rect
			(at 0.94996 -0.649986 90)
			(size 0.4318 0.508)
			(layers "F.Cu" "F.Mask" "F.Paste")
			(net "PRSNT_CABLE_SWB_B2")
		)
	)
	(footprint ""
		(layer "F.Cu")
		(at 435.431692 -181.13121 90)
		(property "Reference" "PC1275"
			(at 0 0 90)
			(layer "F.SilkS")
			(hide yes)
			(effects
				(font
					(size 1.27 1.27)
				)
			)
		)
		(property "Value" ""
			(at 0 0 90)
			(layer "F.Fab")
			(effects
				(font
					(size 1.27 1.27)
				)
			)
		)
		(duplicate_pad_numbers_are_jumpers no)
		(fp_line
			(start 0.7874 -0.4064)
			(end 0.7874 0.4064)
			(stroke
				(width 0.1524)
				(type default)
			)
			(layer "F.SilkS")
		)
		(fp_line
			(start -0.7874 -0.4064)
			(end 0.7874 -0.4064)
			(stroke
				(width 0.1524)
				(type default)
			)
			(layer "F.SilkS")
		)
		(fp_line
			(start 0.7874 0.4064)
			(end -0.7874 0.4064)
			(stroke
				(width 0.1524)
				(type default)
			)
			(layer "F.SilkS")
		)
		(fp_line
			(start -0.7874 0.4064)
			(end -0.7874 -0.4064)
			(stroke
				(width 0.1524)
				(type default)
			)
			(layer "F.SilkS")
		)
		(fp_line
			(start -0.12065 -0.305054)
			(end -0.12065 -0.2794)
			(stroke
				(width 0.1)
				(type default)
			)
			(layer "F.Fab")
		)
		(fp_line
			(start -0.67945 -0.305054)
			(end -0.12065 -0.305054)
			(stroke
				(width 0.1)
				(type default)
			)
			(layer "F.Fab")
		)
		(fp_line
			(start 0.67945 -0.3048)
			(end 0.67945 0.3048)
			(stroke
				(width 0.1)
				(type default)
			)
			(layer "F.Fab")
		)
		(fp_line
			(start 0.12065 -0.3048)
			(end 0.67945 -0.3048)
			(stroke
				(width 0.1)
				(type default)
			)
			(layer "F.Fab")
		)
		(fp_line
			(start 0.12065 -0.2794)
			(end 0.12065 -0.3048)
			(stroke
				(width 0.1)
				(type default)
			)
			(layer "F.Fab")
		)
		(fp_line
			(start -0.12065 -0.2794)
			(end 0.12065 -0.2794)
			(stroke
				(width 0.1)
				(type default)
			)
			(layer "F.Fab")
		)
		(fp_line
			(start 0.120396 0.2794)
			(end -0.12065 0.2794)
			(stroke
				(width 0.1)
				(type default)
			)
			(layer "F.Fab")
		)
		(fp_line
			(start -0.12065 0.2794)
			(end -0.12065 0.3048)
			(stroke
				(width 0.1)
				(type default)
			)
			(layer "F.Fab")
		)
		(fp_line
			(start 0.67945 0.3048)
			(end 0.120396 0.3048)
			(stroke
				(width 0.1)
				(type default)
			)
			(layer "F.Fab")
		)
		(fp_line
			(start 0.120396 0.3048)
			(end 0.120396 0.2794)
			(stroke
				(width 0.1)
				(type default)
			)
			(layer "F.Fab")
		)
		(fp_line
			(start -0.12065 0.3048)
			(end -0.67945 0.3048)
			(stroke
				(width 0.1)
				(type default)
			)
			(layer "F.Fab")
		)
		(fp_line
			(start -0.67945 0.3048)
			(end -0.67945 -0.305054)
			(stroke
				(width 0.1)
				(type default)
			)
			(layer "F.Fab")
		)
		(pad "1" smd circle
			(at -0.40005 0 90)
			(size 0 0)
			(layers "F.Cu" "F.Mask" "F.Paste")
			(net "SW_PVNN_MAIN_CPU0_BST_R")
		)
		(pad "2" smd circle
			(at 0.40005 0 90)
			(size 0 0)
			(layers "F.Cu" "F.Mask" "F.Paste")
			(net "SW_PVNN_MAIN_CPU0_SW")
		)
	)
	(footprint ""
		(layer "F.Cu")
		(at 155.27909 -46.751748 180)
		(property "Reference" "R4486"
			(at 0 0 180)
			(layer "F.SilkS")
			(hide yes)
			(effects
				(font
					(size 1.27 1.27)
				)
			)
		)
		(property "Value" ""
			(at 0 0 180)
			(layer "F.Fab")
			(effects
				(font
					(size 1.27 1.27)
				)
			)
		)
		(duplicate_pad_numbers_are_jumpers no)
		(fp_line
			(start 0.7874 0.4064)
			(end -0.08763 0.4064)
			(stroke
				(width 0.1524)
				(type default)
			)
			(layer "F.SilkS")
		)
		(fp_line
			(start 0.7874 -0.4064)
			(end 0.7874 0.4064)
			(stroke
				(width 0.1524)
				(type default)
			)
			(layer "F.SilkS")
		)
		(fp_line
			(start 0.05715 -0.4064)
			(end 0.7874 -0.4064)
			(stroke
				(width 0.1524)
				(type default)
			)
			(layer "F.SilkS")
		)
		(fp_line
			(start 0.67945 0.3048)
			(end 0.120396 0.3048)
			(stroke
				(width 0.1)
				(type default)
			)
			(layer "F.Fab")
		)
		(fp_line
			(start 0.67945 -0.3048)
			(end 0.67945 0.3048)
			(stroke
				(width 0.1)
				(type default)
			)
			(layer "F.Fab")
		)
		(fp_line
			(start 0.12065 -0.2794)
			(end 0.12065 -0.3048)
			(stroke
				(width 0.1)
				(type default)
			)
			(layer "F.Fab")
		)
		(fp_line
			(start 0.12065 -0.3048)
			(end 0.67945 -0.3048)
			(stroke
				(width 0.1)
				(type default)
			)
			(layer "F.Fab")
		)
		(fp_line
			(start 0.120396 0.3048)
			(end 0.120396 0.2794)
			(stroke
				(width 0.1)
				(type default)
			)
			(layer "F.Fab")
		)
		(fp_line
			(start 0.120396 0.2794)
			(end -0.12065 0.2794)
			(stroke
				(width 0.1)
				(type default)
			)
			(layer "F.Fab")
		)
		(fp_line
			(start -0.12065 0.3048)
			(end -0.67945 0.3048)
			(stroke
				(width 0.1)
				(type default)
			)
			(layer "F.Fab")
		)
		(fp_line
			(start -0.12065 0.2794)
			(end -0.12065 0.3048)
			(stroke
				(width 0.1)
				(type default)
			)
			(layer "F.Fab")
		)
		(fp_line
			(start -0.12065 -0.2794)
			(end 0.12065 -0.2794)
			(stroke
				(width 0.1)
				(type default)
			)
			(layer "F.Fab")
		)
		(fp_line
			(start -0.12065 -0.305054)
			(end -0.12065 -0.2794)
			(stroke
				(width 0.1)
				(type default)
			)
			(layer "F.Fab")
		)
		(fp_line
			(start -0.67945 0.3048)
			(end -0.67945 -0.305054)
			(stroke
				(width 0.1)
				(type default)
			)
			(layer "F.Fab")
		)
		(fp_line
			(start -0.67945 -0.305054)
			(end -0.12065 -0.305054)
			(stroke
				(width 0.1)
				(type default)
			)
			(layer "F.Fab")
		)
		(pad "1" smd circle
			(at -0.40005 0 180)
			(size 0 0)
			(layers "F.Cu" "F.Mask" "F.Paste")
			(net "USB2_HOST_PCH_0_DP")
		)
		(pad "2" smd circle
			(at 0.40005 0 180)
			(size 0 0)
			(layers "F.Cu" "F.Mask" "F.Paste")
			(net "GND")
		)
	)
	(footprint ""
		(layer "F.Cu")
		(at 465.821014 -118.699534 180)
		(property "Reference" "R1131"
			(at 0 0 180)
			(layer "F.SilkS")
			(hide yes)
			(effects
				(font
					(size 1.27 1.27)
				)
			)
		)
		(property "Value" ""
			(at 0 0 180)
			(layer "F.Fab")
			(effects
				(font
					(size 1.27 1.27)
				)
			)
		)
		(duplicate_pad_numbers_are_jumpers no)
		(fp_line
			(start 0.7874 0.4064)
			(end -0.7874 0.4064)
			(stroke
				(width 0.1524)
				(type default)
			)
			(layer "F.SilkS")
		)
		(fp_line
			(start 0.7874 -0.4064)
			(end 0.7874 0.4064)
			(stroke
				(width 0.1524)
				(type default)
			)
			(layer "F.SilkS")
		)
		(fp_line
			(start -0.7874 0.4064)
			(end -0.7874 -0.4064)
			(stroke
				(width 0.1524)
				(type default)
			)
			(layer "F.SilkS")
		)
		(fp_line
			(start -0.7874 -0.4064)
			(end 0.7874 -0.4064)
			(stroke
				(width 0.1524)
				(type default)
			)
			(layer "F.SilkS")
		)
		(fp_line
			(start 0.67945 0.3048)
			(end 0.120396 0.3048)
			(stroke
				(width 0.1)
				(type default)
			)
			(layer "F.Fab")
		)
		(fp_line
			(start 0.67945 -0.3048)
			(end 0.67945 0.3048)
			(stroke
				(width 0.1)
				(type default)
			)
			(layer "F.Fab")
		)
		(fp_line
			(start 0.12065 -0.2794)
			(end 0.12065 -0.3048)
			(stroke
				(width 0.1)
				(type default)
			)
			(layer "F.Fab")
		)
		(fp_line
			(start 0.12065 -0.3048)
			(end 0.67945 -0.3048)
			(stroke
				(width 0.1)
				(type default)
			)
			(layer "F.Fab")
		)
		(fp_line
			(start 0.120396 0.3048)
			(end 0.120396 0.2794)
			(stroke
				(width 0.1)
				(type default)
			)
			(layer "F.Fab")
		)
		(fp_line
			(start 0.120396 0.2794)
			(end -0.12065 0.2794)
			(stroke
				(width 0.1)
				(type default)
			)
			(layer "F.Fab")
		)
		(fp_line
			(start -0.12065 0.3048)
			(end -0.67945 0.3048)
			(stroke
				(width 0.1)
				(type default)
			)
			(layer "F.Fab")
		)
		(fp_line
			(start -0.12065 0.2794)
			(end -0.12065 0.3048)
			(stroke
				(width 0.1)
				(type default)
			)
			(layer "F.Fab")
		)
		(fp_line
			(start -0.12065 -0.2794)
			(end 0.12065 -0.2794)
			(stroke
				(width 0.1)
				(type default)
			)
			(layer "F.Fab")
		)
		(fp_line
			(start -0.12065 -0.305054)
			(end -0.12065 -0.2794)
			(stroke
				(width 0.1)
				(type default)
			)
			(layer "F.Fab")
		)
		(fp_line
			(start -0.67945 0.3048)
			(end -0.67945 -0.305054)
			(stroke
				(width 0.1)
				(type default)
			)
			(layer "F.Fab")
		)
		(fp_line
			(start -0.67945 -0.305054)
			(end -0.12065 -0.305054)
			(stroke
				(width 0.1)
				(type default)
			)
			(layer "F.Fab")
		)
		(pad "1" smd circle
			(at -0.40005 0 180)
			(size 0 0)
			(layers "F.Cu" "F.Mask" "F.Paste")
			(net "SMB_PEHPCPU0_LVC3_SDA")
		)
		(pad "2" smd circle
			(at 0.40005 0 180)
			(size 0 0)
			(layers "F.Cu" "F.Mask" "F.Paste")
			(net "SMB_PEHPCPU0_LVC3_R_SDA")
		)
	)
	(footprint ""
		(layer "F.Cu")
		(at 220.087444 -97.13341)
		(property "Reference" "R2222"
			(at 0 0 0)
			(layer "F.SilkS")
			(hide yes)
			(effects
				(font
					(size 1.27 1.27)
				)
			)
		)
		(property "Value" ""
			(at 0 0 0)
			(layer "F.Fab")
			(effects
				(font
					(size 1.27 1.27)
				)
			)
		)
		(duplicate_pad_numbers_are_jumpers no)
		(fp_line
			(start -0.7874 -0.4064)
			(end 0.7874 -0.4064)
			(stroke
				(width 0.1524)
				(type default)
			)
			(layer "F.SilkS")
		)
		(fp_line
			(start -0.7874 0.4064)
			(end -0.7874 -0.4064)
			(stroke
				(width 0.1524)
				(type default)
			)
			(layer "F.SilkS")
		)
		(fp_line
			(start 0.7874 -0.4064)
			(end 0.7874 0.4064)
			(stroke
				(width 0.1524)
				(type default)
			)
			(layer "F.SilkS")
		)
		(fp_line
			(start 0.7874 0.4064)
			(end -0.7874 0.4064)
			(stroke
				(width 0.1524)
				(type default)
			)
			(layer "F.SilkS")
		)
		(fp_line
			(start -0.67945 -0.305054)
			(end -0.12065 -0.305054)
			(stroke
				(width 0.1)
				(type default)
			)
			(layer "F.Fab")
		)
		(fp_line
			(start -0.67945 0.3048)
			(end -0.67945 -0.305054)
			(stroke
				(width 0.1)
				(type default)
			)
			(layer "F.Fab")
		)
		(fp_line
			(start -0.12065 -0.305054)
			(end -0.12065 -0.2794)
			(stroke
				(width 0.1)
				(type default)
			)
			(layer "F.Fab")
		)
		(fp_line
			(start -0.12065 -0.2794)
			(end 0.12065 -0.2794)
			(stroke
				(width 0.1)
				(type default)
			)
			(layer "F.Fab")
		)
		(fp_line
			(start -0.12065 0.2794)
			(end -0.12065 0.3048)
			(stroke
				(width 0.1)
				(type default)
			)
			(layer "F.Fab")
		)
		(fp_line
			(start -0.12065 0.3048)
			(end -0.67945 0.3048)
			(stroke
				(width 0.1)
				(type default)
			)
			(layer "F.Fab")
		)
		(fp_line
			(start 0.120396 0.2794)
			(end -0.12065 0.2794)
			(stroke
				(width 0.1)
				(type default)
			)
			(layer "F.Fab")
		)
		(fp_line
			(start 0.120396 0.3048)
			(end 0.120396 0.2794)
			(stroke
				(width 0.1)
				(type default)
			)
			(layer "F.Fab")
		)
		(fp_line
			(start 0.12065 -0.3048)
			(end 0.67945 -0.3048)
			(stroke
				(width 0.1)
				(type default)
			)
			(layer "F.Fab")
		)
		(fp_line
			(start 0.12065 -0.2794)
			(end 0.12065 -0.3048)
			(stroke
				(width 0.1)
				(type default)
			)
			(layer "F.Fab")
		)
		(fp_line
			(start 0.67945 -0.3048)
			(end 0.67945 0.3048)
			(stroke
				(width 0.1)
				(type default)
			)
			(layer "F.Fab")
		)
		(fp_line
			(start 0.67945 0.3048)
			(end 0.120396 0.3048)
			(stroke
				(width 0.1)
				(type default)
			)
			(layer "F.Fab")
		)
		(pad "1" smd circle
			(at -0.40005 0)
			(size 0 0)
			(layers "F.Cu" "F.Mask" "F.Paste")
			(net "A_P12V_STBY_FP_TRIGGER")
		)
		(pad "2" smd circle
			(at 0.40005 0)
			(size 0 0)
			(layers "F.Cu" "F.Mask" "F.Paste")
			(net "GND")
		)
	)
	(footprint ""
		(layer "F.Cu")
		(at 54.88686 -353.643946 -90)
		(property "Reference" "PC400_P1_2"
			(at 0 0 270)
			(layer "F.SilkS")
			(hide yes)
			(effects
				(font
					(size 1.27 1.27)
				)
			)
		)
		(property "Value" ""
			(at 0 0 270)
			(layer "F.Fab")
			(effects
				(font
					(size 1.27 1.27)
				)
			)
		)
		(duplicate_pad_numbers_are_jumpers no)
		(fp_line
			(start -0.7874 0.4064)
			(end -0.7874 -0.4064)
			(stroke
				(width 0.1524)
				(type default)
			)
			(layer "F.SilkS")
		)
		(fp_line
			(start 0.7874 0.4064)
			(end -0.7874 0.4064)
			(stroke
				(width 0.1524)
				(type default)
			)
			(layer "F.SilkS")
		)
		(fp_line
			(start -0.7874 -0.4064)
			(end 0.7874 -0.4064)
			(stroke
				(width 0.1524)
				(type default)
			)
			(layer "F.SilkS")
		)
		(fp_line
			(start 0.7874 -0.4064)
			(end 0.7874 0.4064)
			(stroke
				(width 0.1524)
				(type default)
			)
			(layer "F.SilkS")
		)
		(fp_line
			(start -0.67945 0.3048)
			(end -0.67945 -0.305054)
			(stroke
				(width 0.1)
				(type default)
			)
			(layer "F.Fab")
		)
		(fp_line
			(start -0.12065 0.3048)
			(end -0.67945 0.3048)
			(stroke
				(width 0.1)
				(type default)
			)
			(layer "F.Fab")
		)
		(fp_line
			(start 0.120396 0.3048)
			(end 0.120396 0.2794)
			(stroke
				(width 0.1)
				(type default)
			)
			(layer "F.Fab")
		)
		(fp_line
			(start 0.67945 0.3048)
			(end 0.120396 0.3048)
			(stroke
				(width 0.1)
				(type default)
			)
			(layer "F.Fab")
		)
		(fp_line
			(start -0.12065 0.2794)
			(end -0.12065 0.3048)
			(stroke
				(width 0.1)
				(type default)
			)
			(layer "F.Fab")
		)
		(fp_line
			(start 0.120396 0.2794)
			(end -0.12065 0.2794)
			(stroke
				(width 0.1)
				(type default)
			)
			(layer "F.Fab")
		)
		(fp_line
			(start -0.12065 -0.2794)
			(end 0.12065 -0.2794)
			(stroke
				(width 0.1)
				(type default)
			)
			(layer "F.Fab")
		)
		(fp_line
			(start 0.12065 -0.2794)
			(end 0.12065 -0.3048)
			(stroke
				(width 0.1)
				(type default)
			)
			(layer "F.Fab")
		)
		(fp_line
			(start 0.12065 -0.3048)
			(end 0.67945 -0.3048)
			(stroke
				(width 0.1)
				(type default)
			)
			(layer "F.Fab")
		)
		(fp_line
			(start 0.67945 -0.3048)
			(end 0.67945 0.3048)
			(stroke
				(width 0.1)
				(type default)
			)
			(layer "F.Fab")
		)
		(fp_line
			(start -0.67945 -0.305054)
			(end -0.12065 -0.305054)
			(stroke
				(width 0.1)
				(type default)
			)
			(layer "F.Fab")
		)
		(fp_line
			(start -0.12065 -0.305054)
			(end -0.12065 -0.2794)
			(stroke
				(width 0.1)
				(type default)
			)
			(layer "F.Fab")
		)
		(pad "1" smd circle
			(at -0.40005 0 270)
			(size 0 0)
			(layers "F.Cu" "F.Mask" "F.Paste")
			(net "SW_P12V_PVCCFA_EHV_FIVRA_CPU1_L")
		)
		(pad "2" smd circle
			(at 0.40005 0 270)
			(size 0 0)
			(layers "F.Cu" "F.Mask" "F.Paste")
			(net "GND")
		)
	)
	(footprint ""
		(layer "F.Cu")
		(at 169.422572 -419.495478)
		(property "Reference" "R3438"
			(at 0 0 0)
			(layer "F.SilkS")
			(hide yes)
			(effects
				(font
					(size 1.27 1.27)
				)
			)
		)
		(property "Value" ""
			(at 0 0 0)
			(layer "F.Fab")
			(effects
				(font
					(size 1.27 1.27)
				)
			)
		)
		(duplicate_pad_numbers_are_jumpers no)
		(fp_line
			(start -0.7874 -0.4064)
			(end 0.7874 -0.4064)
			(stroke
				(width 0.1524)
				(type default)
			)
			(layer "F.SilkS")
		)
		(fp_line
			(start -0.7874 0.4064)
			(end -0.7874 -0.4064)
			(stroke
				(width 0.1524)
				(type default)
			)
			(layer "F.SilkS")
		)
		(fp_line
			(start 0.7874 -0.4064)
			(end 0.7874 0.4064)
			(stroke
				(width 0.1524)
				(type default)
			)
			(layer "F.SilkS")
		)
		(fp_line
			(start 0.7874 0.4064)
			(end -0.7874 0.4064)
			(stroke
				(width 0.1524)
				(type default)
			)
			(layer "F.SilkS")
		)
		(fp_line
			(start -0.67945 -0.305054)
			(end -0.12065 -0.305054)
			(stroke
				(width 0.1)
				(type default)
			)
			(layer "F.Fab")
		)
		(fp_line
			(start -0.67945 0.3048)
			(end -0.67945 -0.305054)
			(stroke
				(width 0.1)
				(type default)
			)
			(layer "F.Fab")
		)
		(fp_line
			(start -0.12065 -0.305054)
			(end -0.12065 -0.2794)
			(stroke
				(width 0.1)
				(type default)
			)
			(layer "F.Fab")
		)
		(fp_line
			(start -0.12065 -0.2794)
			(end 0.12065 -0.2794)
			(stroke
				(width 0.1)
				(type default)
			)
			(layer "F.Fab")
		)
		(fp_line
			(start -0.12065 0.2794)
			(end -0.12065 0.3048)
			(stroke
				(width 0.1)
				(type default)
			)
			(layer "F.Fab")
		)
		(fp_line
			(start -0.12065 0.3048)
			(end -0.67945 0.3048)
			(stroke
				(width 0.1)
				(type default)
			)
			(layer "F.Fab")
		)
		(fp_line
			(start 0.120396 0.2794)
			(end -0.12065 0.2794)
			(stroke
				(width 0.1)
				(type default)
			)
			(layer "F.Fab")
		)
		(fp_line
			(start 0.120396 0.3048)
			(end 0.120396 0.2794)
			(stroke
				(width 0.1)
				(type default)
			)
			(layer "F.Fab")
		)
		(fp_line
			(start 0.12065 -0.3048)
			(end 0.67945 -0.3048)
			(stroke
				(width 0.1)
				(type default)
			)
			(layer "F.Fab")
		)
		(fp_line
			(start 0.12065 -0.2794)
			(end 0.12065 -0.3048)
			(stroke
				(width 0.1)
				(type default)
			)
			(layer "F.Fab")
		)
		(fp_line
			(start 0.67945 -0.3048)
			(end 0.67945 0.3048)
			(stroke
				(width 0.1)
				(type default)
			)
			(layer "F.Fab")
		)
		(fp_line
			(start 0.67945 0.3048)
			(end 0.120396 0.3048)
			(stroke
				(width 0.1)
				(type default)
			)
			(layer "F.Fab")
		)
		(pad "1" smd circle
			(at -0.40005 0)
			(size 0 0)
			(layers "F.Cu" "F.Mask" "F.Paste")
			(net "P3V3_AUX")
		)
		(pad "2" smd circle
			(at 0.40005 0)
			(size 0 0)
			(layers "F.Cu" "F.Mask" "F.Paste")
			(net "GPU_BASE_HMC_READY_ISO")
		)
	)
	(footprint ""
		(layer "F.Cu")
		(at 237.205266 -297.147996)
		(property "Reference" "ME10"
			(at -9.7155 10.690352 0)
			(unlocked yes)
			(layer "F.SilkS")
			(effects
				(font
					(size 0.7874 0.5842)
					(thickness 0.1524)
				)
				(justify left)
			)
		)
		(property "Value" ""
			(at 0 0 0)
			(layer "F.Fab")
			(effects
				(font
					(size 1.27 1.27)
				)
			)
		)
		(duplicate_pad_numbers_are_jumpers no)
	)
	(footprint ""
		(layer "F.Cu")
		(at 149.81428 -32.929068)
		(property "Reference" "C1878"
			(at 0 0 0)
			(layer "F.SilkS")
			(hide yes)
			(effects
				(font
					(size 1.27 1.27)
				)
			)
		)
		(property "Value" ""
			(at 0 0 0)
			(layer "F.Fab")
			(effects
				(font
					(size 1.27 1.27)
				)
			)
		)
		(duplicate_pad_numbers_are_jumpers no)
		(fp_line
			(start -0.7874 -0.4064)
			(end 0.7874 -0.4064)
			(stroke
				(width 0.1524)
				(type default)
			)
			(layer "F.SilkS")
		)
		(fp_line
			(start -0.7874 0.4064)
			(end -0.7874 -0.4064)
			(stroke
				(width 0.1524)
				(type default)
			)
			(layer "F.SilkS")
		)
		(fp_line
			(start 0.7874 -0.4064)
			(end 0.7874 0.4064)
			(stroke
				(width 0.1524)
				(type default)
			)
			(layer "F.SilkS")
		)
		(fp_line
			(start 0.7874 0.4064)
			(end -0.7874 0.4064)
			(stroke
				(width 0.1524)
				(type default)
			)
			(layer "F.SilkS")
		)
		(fp_line
			(start -0.67945 -0.305054)
			(end -0.12065 -0.305054)
			(stroke
				(width 0.1)
				(type default)
			)
			(layer "F.Fab")
		)
		(fp_line
			(start -0.67945 0.3048)
			(end -0.67945 -0.305054)
			(stroke
				(width 0.1)
				(type default)
			)
			(layer "F.Fab")
		)
		(fp_line
			(start -0.12065 -0.305054)
			(end -0.12065 -0.2794)
			(stroke
				(width 0.1)
				(type default)
			)
			(layer "F.Fab")
		)
		(fp_line
			(start -0.12065 -0.2794)
			(end 0.12065 -0.2794)
			(stroke
				(width 0.1)
				(type default)
			)
			(layer "F.Fab")
		)
		(fp_line
			(start -0.12065 0.2794)
			(end -0.12065 0.3048)
			(stroke
				(width 0.1)
				(type default)
			)
			(layer "F.Fab")
		)
		(fp_line
			(start -0.12065 0.3048)
			(end -0.67945 0.3048)
			(stroke
				(width 0.1)
				(type default)
			)
			(layer "F.Fab")
		)
		(fp_line
			(start 0.120396 0.2794)
			(end -0.12065 0.2794)
			(stroke
				(width 0.1)
				(type default)
			)
			(layer "F.Fab")
		)
		(fp_line
			(start 0.120396 0.3048)
			(end 0.120396 0.2794)
			(stroke
				(width 0.1)
				(type default)
			)
			(layer "F.Fab")
		)
		(fp_line
			(start 0.12065 -0.3048)
			(end 0.67945 -0.3048)
			(stroke
				(width 0.1)
				(type default)
			)
			(layer "F.Fab")
		)
		(fp_line
			(start 0.12065 -0.2794)
			(end 0.12065 -0.3048)
			(stroke
				(width 0.1)
				(type default)
			)
			(layer "F.Fab")
		)
		(fp_line
			(start 0.67945 -0.3048)
			(end 0.67945 0.3048)
			(stroke
				(width 0.1)
				(type default)
			)
			(layer "F.Fab")
		)
		(fp_line
			(start 0.67945 0.3048)
			(end 0.120396 0.3048)
			(stroke
				(width 0.1)
				(type default)
			)
			(layer "F.Fab")
		)
		(pad "1" smd circle
			(at -0.40005 0)
			(size 0 0)
			(layers "F.Cu" "F.Mask" "F.Paste")
			(net "P3V3_AUX")
		)
		(pad "2" smd circle
			(at 0.40005 0)
			(size 0 0)
			(layers "F.Cu" "F.Mask" "F.Paste")
			(net "GND")
		)
	)
	(footprint ""
		(layer "F.Cu")
		(at 174.04588 -126.964948 -90)
		(property "Reference" "R1444"
			(at 0 0 270)
			(layer "F.SilkS")
			(hide yes)
			(effects
				(font
					(size 1.27 1.27)
				)
			)
		)
		(property "Value" ""
			(at 0 0 270)
			(layer "F.Fab")
			(effects
				(font
					(size 1.27 1.27)
				)
			)
		)
		(duplicate_pad_numbers_are_jumpers no)
		(fp_line
			(start -0.7874 0.4064)
			(end -0.7874 -0.4064)
			(stroke
				(width 0.1524)
				(type default)
			)
			(layer "F.SilkS")
		)
		(fp_line
			(start 0.7874 0.4064)
			(end -0.7874 0.4064)
			(stroke
				(width 0.1524)
				(type default)
			)
			(layer "F.SilkS")
		)
		(fp_line
			(start -0.7874 -0.4064)
			(end 0.7874 -0.4064)
			(stroke
				(width 0.1524)
				(type default)
			)
			(layer "F.SilkS")
		)
		(fp_line
			(start 0.7874 -0.4064)
			(end 0.7874 0.4064)
			(stroke
				(width 0.1524)
				(type default)
			)
			(layer "F.SilkS")
		)
		(fp_line
			(start -0.67945 0.3048)
			(end -0.67945 -0.305054)
			(stroke
				(width 0.1)
				(type default)
			)
			(layer "F.Fab")
		)
		(fp_line
			(start -0.12065 0.3048)
			(end -0.67945 0.3048)
			(stroke
				(width 0.1)
				(type default)
			)
			(layer "F.Fab")
		)
		(fp_line
			(start 0.120396 0.3048)
			(end 0.120396 0.2794)
			(stroke
				(width 0.1)
				(type default)
			)
			(layer "F.Fab")
		)
		(fp_line
			(start 0.67945 0.3048)
			(end 0.120396 0.3048)
			(stroke
				(width 0.1)
				(type default)
			)
			(layer "F.Fab")
		)
		(fp_line
			(start -0.12065 0.2794)
			(end -0.12065 0.3048)
			(stroke
				(width 0.1)
				(type default)
			)
			(layer "F.Fab")
		)
		(fp_line
			(start 0.120396 0.2794)
			(end -0.12065 0.2794)
			(stroke
				(width 0.1)
				(type default)
			)
			(layer "F.Fab")
		)
		(fp_line
			(start -0.12065 -0.2794)
			(end 0.12065 -0.2794)
			(stroke
				(width 0.1)
				(type default)
			)
			(layer "F.Fab")
		)
		(fp_line
			(start 0.12065 -0.2794)
			(end 0.12065 -0.3048)
			(stroke
				(width 0.1)
				(type default)
			)
			(layer "F.Fab")
		)
		(fp_line
			(start 0.12065 -0.3048)
			(end 0.67945 -0.3048)
			(stroke
				(width 0.1)
				(type default)
			)
			(layer "F.Fab")
		)
		(fp_line
			(start 0.67945 -0.3048)
			(end 0.67945 0.3048)
			(stroke
				(width 0.1)
				(type default)
			)
			(layer "F.Fab")
		)
		(fp_line
			(start -0.67945 -0.305054)
			(end -0.12065 -0.305054)
			(stroke
				(width 0.1)
				(type default)
			)
			(layer "F.Fab")
		)
		(fp_line
			(start -0.12065 -0.305054)
			(end -0.12065 -0.2794)
			(stroke
				(width 0.1)
				(type default)
			)
			(layer "F.Fab")
		)
		(pad "1" smd circle
			(at -0.40005 0 270)
			(size 0 0)
			(layers "F.Cu" "F.Mask" "F.Paste")
			(net "PWRGD_P1V8_PCH_AUX")
		)
		(pad "2" smd circle
			(at 0.40005 0 270)
			(size 0 0)
			(layers "F.Cu" "F.Mask" "F.Paste")
			(net "PWRGD_P1V8_PCH_AUX_PLD")
		)
	)
	(footprint ""
		(layer "F.Cu")
		(at 366.48263 -258.726686 90)
		(property "Reference" "C976"
			(at 0 0 90)
			(layer "F.SilkS")
			(hide yes)
			(effects
				(font
					(size 1.27 1.27)
				)
			)
		)
		(property "Value" ""
			(at 0 0 90)
			(layer "F.Fab")
			(effects
				(font
					(size 1.27 1.27)
				)
			)
		)
		(duplicate_pad_numbers_are_jumpers no)
		(fp_line
			(start 0.7874 -0.4064)
			(end 0.7874 0.4064)
			(stroke
				(width 0.1524)
				(type default)
			)
			(layer "F.SilkS")
		)
		(fp_line
			(start -0.7874 -0.4064)
			(end 0.7874 -0.4064)
			(stroke
				(width 0.1524)
				(type default)
			)
			(layer "F.SilkS")
		)
		(fp_line
			(start 0.7874 0.4064)
			(end -0.7874 0.4064)
			(stroke
				(width 0.1524)
				(type default)
			)
			(layer "F.SilkS")
		)
		(fp_line
			(start -0.7874 0.4064)
			(end -0.7874 -0.4064)
			(stroke
				(width 0.1524)
				(type default)
			)
			(layer "F.SilkS")
		)
		(fp_line
			(start -0.12065 -0.305054)
			(end -0.12065 -0.2794)
			(stroke
				(width 0.1)
				(type default)
			)
			(layer "F.Fab")
		)
		(fp_line
			(start -0.67945 -0.305054)
			(end -0.12065 -0.305054)
			(stroke
				(width 0.1)
				(type default)
			)
			(layer "F.Fab")
		)
		(fp_line
			(start 0.67945 -0.3048)
			(end 0.67945 0.3048)
			(stroke
				(width 0.1)
				(type default)
			)
			(layer "F.Fab")
		)
		(fp_line
			(start 0.12065 -0.3048)
			(end 0.67945 -0.3048)
			(stroke
				(width 0.1)
				(type default)
			)
			(layer "F.Fab")
		)
		(fp_line
			(start 0.12065 -0.2794)
			(end 0.12065 -0.3048)
			(stroke
				(width 0.1)
				(type default)
			)
			(layer "F.Fab")
		)
		(fp_line
			(start -0.12065 -0.2794)
			(end 0.12065 -0.2794)
			(stroke
				(width 0.1)
				(type default)
			)
			(layer "F.Fab")
		)
		(fp_line
			(start 0.120396 0.2794)
			(end -0.12065 0.2794)
			(stroke
				(width 0.1)
				(type default)
			)
			(layer "F.Fab")
		)
		(fp_line
			(start -0.12065 0.2794)
			(end -0.12065 0.3048)
			(stroke
				(width 0.1)
				(type default)
			)
			(layer "F.Fab")
		)
		(fp_line
			(start 0.67945 0.3048)
			(end 0.120396 0.3048)
			(stroke
				(width 0.1)
				(type default)
			)
			(layer "F.Fab")
		)
		(fp_line
			(start 0.120396 0.3048)
			(end 0.120396 0.2794)
			(stroke
				(width 0.1)
				(type default)
			)
			(layer "F.Fab")
		)
		(fp_line
			(start -0.12065 0.3048)
			(end -0.67945 0.3048)
			(stroke
				(width 0.1)
				(type default)
			)
			(layer "F.Fab")
		)
		(fp_line
			(start -0.67945 0.3048)
			(end -0.67945 -0.305054)
			(stroke
				(width 0.1)
				(type default)
			)
			(layer "F.Fab")
		)
		(pad "1" smd circle
			(at -0.40005 0 90)
			(size 0 0)
			(layers "F.Cu" "F.Mask" "F.Paste")
			(net "PVCCIN_CPU0")
		)
		(pad "2" smd circle
			(at 0.40005 0 90)
			(size 0 0)
			(layers "F.Cu" "F.Mask" "F.Paste")
			(net "GND")
		)
	)
	(footprint ""
		(layer "F.Cu")
		(at 27.6352 -409.0416 -90)
		(property "Reference" "C1978"
			(at 0 0 270)
			(layer "F.SilkS")
			(hide yes)
			(effects
				(font
					(size 1.27 1.27)
				)
			)
		)
		(property "Value" ""
			(at 0 0 270)
			(layer "F.Fab")
			(effects
				(font
					(size 1.27 1.27)
				)
			)
		)
		(duplicate_pad_numbers_are_jumpers no)
		(fp_line
			(start -0.7874 0.4064)
			(end -0.7874 -0.4064)
			(stroke
				(width 0.1524)
				(type default)
			)
			(layer "F.SilkS")
		)
		(fp_line
			(start 0.7874 0.4064)
			(end -0.7874 0.4064)
			(stroke
				(width 0.1524)
				(type default)
			)
			(layer "F.SilkS")
		)
		(fp_line
			(start -0.7874 -0.4064)
			(end 0.7874 -0.4064)
			(stroke
				(width 0.1524)
				(type default)
			)
			(layer "F.SilkS")
		)
		(fp_line
			(start 0.7874 -0.4064)
			(end 0.7874 0.4064)
			(stroke
				(width 0.1524)
				(type default)
			)
			(layer "F.SilkS")
		)
		(fp_line
			(start -0.67945 0.3048)
			(end -0.67945 -0.305054)
			(stroke
				(width 0.1)
				(type default)
			)
			(layer "F.Fab")
		)
		(fp_line
			(start -0.12065 0.3048)
			(end -0.67945 0.3048)
			(stroke
				(width 0.1)
				(type default)
			)
			(layer "F.Fab")
		)
		(fp_line
			(start 0.120396 0.3048)
			(end 0.120396 0.2794)
			(stroke
				(width 0.1)
				(type default)
			)
			(layer "F.Fab")
		)
		(fp_line
			(start 0.67945 0.3048)
			(end 0.120396 0.3048)
			(stroke
				(width 0.1)
				(type default)
			)
			(layer "F.Fab")
		)
		(fp_line
			(start -0.12065 0.2794)
			(end -0.12065 0.3048)
			(stroke
				(width 0.1)
				(type default)
			)
			(layer "F.Fab")
		)
		(fp_line
			(start 0.120396 0.2794)
			(end -0.12065 0.2794)
			(stroke
				(width 0.1)
				(type default)
			)
			(layer "F.Fab")
		)
		(fp_line
			(start -0.12065 -0.2794)
			(end 0.12065 -0.2794)
			(stroke
				(width 0.1)
				(type default)
			)
			(layer "F.Fab")
		)
		(fp_line
			(start 0.12065 -0.2794)
			(end 0.12065 -0.3048)
			(stroke
				(width 0.1)
				(type default)
			)
			(layer "F.Fab")
		)
		(fp_line
			(start 0.12065 -0.3048)
			(end 0.67945 -0.3048)
			(stroke
				(width 0.1)
				(type default)
			)
			(layer "F.Fab")
		)
		(fp_line
			(start 0.67945 -0.3048)
			(end 0.67945 0.3048)
			(stroke
				(width 0.1)
				(type default)
			)
			(layer "F.Fab")
		)
		(fp_line
			(start -0.67945 -0.305054)
			(end -0.12065 -0.305054)
			(stroke
				(width 0.1)
				(type default)
			)
			(layer "F.Fab")
		)
		(fp_line
			(start -0.12065 -0.305054)
			(end -0.12065 -0.2794)
			(stroke
				(width 0.1)
				(type default)
			)
			(layer "F.Fab")
		)
		(pad "1" smd circle
			(at -0.40005 0 270)
			(size 0 0)
			(layers "F.Cu" "F.Mask" "F.Paste")
			(net "GPU_PRSNT_N_ISO")
		)
		(pad "2" smd circle
			(at 0.40005 0 270)
			(size 0 0)
			(layers "F.Cu" "F.Mask" "F.Paste")
			(net "GND")
		)
	)
	(footprint ""
		(layer "F.Cu")
		(at 443.7507 -51.059588 -90)
		(property "Reference" "C1333"
			(at 0 0 270)
			(layer "F.SilkS")
			(hide yes)
			(effects
				(font
					(size 1.27 1.27)
				)
			)
		)
		(property "Value" ""
			(at 0 0 270)
			(layer "F.Fab")
			(effects
				(font
					(size 1.27 1.27)
				)
			)
		)
		(duplicate_pad_numbers_are_jumpers no)
		(fp_line
			(start -1.524 0.762)
			(end -1.524 -0.762)
			(stroke
				(width 0.1524)
				(type default)
			)
			(layer "F.SilkS")
		)
		(fp_line
			(start 1.524 0.762)
			(end -1.524 0.762)
			(stroke
				(width 0.1524)
				(type default)
			)
			(layer "F.SilkS")
		)
		(fp_line
			(start -1.524 -0.762)
			(end 1.524 -0.762)
			(stroke
				(width 0.1524)
				(type default)
			)
			(layer "F.SilkS")
		)
		(fp_line
			(start 1.524 -0.762)
			(end 1.524 0.762)
			(stroke
				(width 0.1524)
				(type default)
			)
			(layer "F.SilkS")
		)
		(fp_line
			(start -1.1049 0.724916)
			(end 1.1049 0.724916)
			(stroke
				(width 0.1)
				(type default)
			)
			(layer "F.Fab")
		)
		(fp_line
			(start 1.1049 0.724916)
			(end 1.1049 -0.724916)
			(stroke
				(width 0.1)
				(type default)
			)
			(layer "F.Fab")
		)
		(fp_line
			(start -1.1049 -0.724916)
			(end -1.1049 0.724916)
			(stroke
				(width 0.1)
				(type default)
			)
			(layer "F.Fab")
		)
		(fp_line
			(start 1.1049 -0.724916)
			(end -1.1049 -0.724916)
			(stroke
				(width 0.1)
				(type default)
			)
			(layer "F.Fab")
		)
		(pad "1" smd rect
			(at -0.889 0 90)
			(size 1.016 1.27)
			(layers "F.Cu" "F.Mask" "F.Paste")
			(net "P3V3_AUX")
		)
		(pad "2" smd rect
			(at 0.889 0 90)
			(size 1.016 1.27)
			(layers "F.Cu" "F.Mask" "F.Paste")
			(net "GND")
		)
	)
	(footprint ""
		(layer "F.Cu")
		(at 259.021326 -131.502912)
		(property "Reference" "R4499"
			(at 0 0 0)
			(layer "F.SilkS")
			(hide yes)
			(effects
				(font
					(size 1.27 1.27)
				)
			)
		)
		(property "Value" ""
			(at 0 0 0)
			(layer "F.Fab")
			(effects
				(font
					(size 1.27 1.27)
				)
			)
		)
		(duplicate_pad_numbers_are_jumpers no)
		(fp_line
			(start -0.7874 -0.4064)
			(end 0.7874 -0.4064)
			(stroke
				(width 0.1524)
				(type default)
			)
			(layer "F.SilkS")
		)
		(fp_line
			(start -0.7874 0.4064)
			(end -0.7874 -0.4064)
			(stroke
				(width 0.1524)
				(type default)
			)
			(layer "F.SilkS")
		)
		(fp_line
			(start 0.7874 -0.4064)
			(end 0.7874 0.4064)
			(stroke
				(width 0.1524)
				(type default)
			)
			(layer "F.SilkS")
		)
		(fp_line
			(start 0.7874 0.4064)
			(end -0.7874 0.4064)
			(stroke
				(width 0.1524)
				(type default)
			)
			(layer "F.SilkS")
		)
		(fp_line
			(start -0.67945 -0.305054)
			(end -0.12065 -0.305054)
			(stroke
				(width 0.1)
				(type default)
			)
			(layer "F.Fab")
		)
		(fp_line
			(start -0.67945 0.3048)
			(end -0.67945 -0.305054)
			(stroke
				(width 0.1)
				(type default)
			)
			(layer "F.Fab")
		)
		(fp_line
			(start -0.12065 -0.305054)
			(end -0.12065 -0.2794)
			(stroke
				(width 0.1)
				(type default)
			)
			(layer "F.Fab")
		)
		(fp_line
			(start -0.12065 -0.2794)
			(end 0.12065 -0.2794)
			(stroke
				(width 0.1)
				(type default)
			)
			(layer "F.Fab")
		)
		(fp_line
			(start -0.12065 0.2794)
			(end -0.12065 0.3048)
			(stroke
				(width 0.1)
				(type default)
			)
			(layer "F.Fab")
		)
		(fp_line
			(start -0.12065 0.3048)
			(end -0.67945 0.3048)
			(stroke
				(width 0.1)
				(type default)
			)
			(layer "F.Fab")
		)
		(fp_line
			(start 0.120396 0.2794)
			(end -0.12065 0.2794)
			(stroke
				(width 0.1)
				(type default)
			)
			(layer "F.Fab")
		)
		(fp_line
			(start 0.120396 0.3048)
			(end 0.120396 0.2794)
			(stroke
				(width 0.1)
				(type default)
			)
			(layer "F.Fab")
		)
		(fp_line
			(start 0.12065 -0.3048)
			(end 0.67945 -0.3048)
			(stroke
				(width 0.1)
				(type default)
			)
			(layer "F.Fab")
		)
		(fp_line
			(start 0.12065 -0.2794)
			(end 0.12065 -0.3048)
			(stroke
				(width 0.1)
				(type default)
			)
			(layer "F.Fab")
		)
		(fp_line
			(start 0.67945 -0.3048)
			(end 0.67945 0.3048)
			(stroke
				(width 0.1)
				(type default)
			)
			(layer "F.Fab")
		)
		(fp_line
			(start 0.67945 0.3048)
			(end 0.120396 0.3048)
			(stroke
				(width 0.1)
				(type default)
			)
			(layer "F.Fab")
		)
		(pad "1" smd circle
			(at -0.40005 0)
			(size 0 0)
			(layers "F.Cu" "F.Mask" "F.Paste")
			(net "P3V3")
		)
		(pad "2" smd circle
			(at 0.40005 0)
			(size 0 0)
			(layers "F.Cu" "F.Mask" "F.Paste")
			(net "SMB_HOST_CLK_BUF_ISO_3V3AUX_S_2")
		)
	)
	(footprint ""
		(layer "F.Cu")
		(at 116.561616 -258.72694 90)
		(property "Reference" "C308"
			(at 0 0 90)
			(layer "F.SilkS")
			(hide yes)
			(effects
				(font
					(size 1.27 1.27)
				)
			)
		)
		(property "Value" ""
			(at 0 0 90)
			(layer "F.Fab")
			(effects
				(font
					(size 1.27 1.27)
				)
			)
		)
		(duplicate_pad_numbers_are_jumpers no)
		(fp_line
			(start 0.7874 -0.4064)
			(end 0.7874 0.4064)
			(stroke
				(width 0.1524)
				(type default)
			)
			(layer "F.SilkS")
		)
		(fp_line
			(start -0.7874 -0.4064)
			(end 0.7874 -0.4064)
			(stroke
				(width 0.1524)
				(type default)
			)
			(layer "F.SilkS")
		)
		(fp_line
			(start 0.7874 0.4064)
			(end -0.7874 0.4064)
			(stroke
				(width 0.1524)
				(type default)
			)
			(layer "F.SilkS")
		)
		(fp_line
			(start -0.7874 0.4064)
			(end -0.7874 -0.4064)
			(stroke
				(width 0.1524)
				(type default)
			)
			(layer "F.SilkS")
		)
		(fp_line
			(start -0.12065 -0.305054)
			(end -0.12065 -0.2794)
			(stroke
				(width 0.1)
				(type default)
			)
			(layer "F.Fab")
		)
		(fp_line
			(start -0.67945 -0.305054)
			(end -0.12065 -0.305054)
			(stroke
				(width 0.1)
				(type default)
			)
			(layer "F.Fab")
		)
		(fp_line
			(start 0.67945 -0.3048)
			(end 0.67945 0.3048)
			(stroke
				(width 0.1)
				(type default)
			)
			(layer "F.Fab")
		)
		(fp_line
			(start 0.12065 -0.3048)
			(end 0.67945 -0.3048)
			(stroke
				(width 0.1)
				(type default)
			)
			(layer "F.Fab")
		)
		(fp_line
			(start 0.12065 -0.2794)
			(end 0.12065 -0.3048)
			(stroke
				(width 0.1)
				(type default)
			)
			(layer "F.Fab")
		)
		(fp_line
			(start -0.12065 -0.2794)
			(end 0.12065 -0.2794)
			(stroke
				(width 0.1)
				(type default)
			)
			(layer "F.Fab")
		)
		(fp_line
			(start 0.120396 0.2794)
			(end -0.12065 0.2794)
			(stroke
				(width 0.1)
				(type default)
			)
			(layer "F.Fab")
		)
		(fp_line
			(start -0.12065 0.2794)
			(end -0.12065 0.3048)
			(stroke
				(width 0.1)
				(type default)
			)
			(layer "F.Fab")
		)
		(fp_line
			(start 0.67945 0.3048)
			(end 0.120396 0.3048)
			(stroke
				(width 0.1)
				(type default)
			)
			(layer "F.Fab")
		)
		(fp_line
			(start 0.120396 0.3048)
			(end 0.120396 0.2794)
			(stroke
				(width 0.1)
				(type default)
			)
			(layer "F.Fab")
		)
		(fp_line
			(start -0.12065 0.3048)
			(end -0.67945 0.3048)
			(stroke
				(width 0.1)
				(type default)
			)
			(layer "F.Fab")
		)
		(fp_line
			(start -0.67945 0.3048)
			(end -0.67945 -0.305054)
			(stroke
				(width 0.1)
				(type default)
			)
			(layer "F.Fab")
		)
		(pad "1" smd circle
			(at -0.40005 0 90)
			(size 0 0)
			(layers "F.Cu" "F.Mask" "F.Paste")
			(net "PVCCIN_CPU1")
		)
		(pad "2" smd circle
			(at 0.40005 0 90)
			(size 0 0)
			(layers "F.Cu" "F.Mask" "F.Paste")
			(net "GND")
		)
	)
	(footprint ""
		(layer "F.Cu")
		(at 448.787012 -62.020196 -90)
		(property "Reference" "PL66"
			(at -3.292602 -7.236968 0)
			(unlocked yes)
			(layer "F.SilkS")
			(effects
				(font
					(size 0.7874 0.5842)
					(thickness 0.1524)
				)
				(justify left)
			)
		)
		(property "Value" ""
			(at 0 0 270)
			(layer "F.Fab")
			(effects
				(font
					(size 1.27 1.27)
				)
			)
		)
		(duplicate_pad_numbers_are_jumpers no)
		(fp_line
			(start -7.1501 6.450076)
			(end -7.1501 2.6416)
			(stroke
				(width 0.1524)
				(type default)
			)
			(layer "F.SilkS")
		)
		(fp_line
			(start 7.1501 6.450076)
			(end -7.1501 6.450076)
			(stroke
				(width 0.1524)
				(type default)
			)
			(layer "F.SilkS")
		)
		(fp_line
			(start 7.1501 2.6416)
			(end 7.1501 6.450076)
			(stroke
				(width 0.1524)
				(type default)
			)
			(layer "F.SilkS")
		)
		(fp_line
			(start 7.1501 -2.6416)
			(end 7.1501 -6.450076)
			(stroke
				(width 0.1524)
				(type default)
			)
			(layer "F.SilkS")
		)
		(fp_line
			(start -7.1501 -6.450076)
			(end -7.1501 -2.6416)
			(stroke
				(width 0.1524)
				(type default)
			)
			(layer "F.SilkS")
		)
		(fp_line
			(start 7.1501 -6.450076)
			(end -7.1501 -6.450076)
			(stroke
				(width 0.1524)
				(type default)
			)
			(layer "F.SilkS")
		)
		(fp_line
			(start -7.1501 6.450076)
			(end 7.1501 6.450076)
			(stroke
				(width 0.1)
				(type default)
			)
			(layer "F.Fab")
		)
		(fp_line
			(start 7.1501 6.450076)
			(end 7.1501 -6.450076)
			(stroke
				(width 0.1)
				(type default)
			)
			(layer "F.Fab")
		)
		(fp_line
			(start -7.1501 -6.450076)
			(end -7.1501 6.450076)
			(stroke
				(width 0.1)
				(type default)
			)
			(layer "F.Fab")
		)
		(fp_line
			(start 7.1501 -6.450076)
			(end -7.1501 -6.450076)
			(stroke
				(width 0.1)
				(type default)
			)
			(layer "F.Fab")
		)
		(pad "1" smd rect
			(at -5.625084 0 270)
			(size 3.2512 5.0038)
			(layers "F.Cu" "F.Mask" "F.Paste")
			(net "SW_P3V3_AUX_SW")
		)
		(pad "2" smd rect
			(at 5.625084 0 270)
			(size 3.2512 5.0038)
			(layers "F.Cu" "F.Mask" "F.Paste")
			(net "P3V3_AUX")
		)
	)
	(footprint ""
		(layer "F.Cu")
		(at 452.486522 -76.007722)
		(property "Reference" "PR836"
			(at 0 0 0)
			(layer "F.SilkS")
			(hide yes)
			(effects
				(font
					(size 1.27 1.27)
				)
			)
		)
		(property "Value" ""
			(at 0 0 0)
			(layer "F.Fab")
			(effects
				(font
					(size 1.27 1.27)
				)
			)
		)
		(duplicate_pad_numbers_are_jumpers no)
		(fp_line
			(start -0.7874 -0.4064)
			(end 0.7874 -0.4064)
			(stroke
				(width 0.1524)
				(type default)
			)
			(layer "F.SilkS")
		)
		(fp_line
			(start -0.7874 0.4064)
			(end -0.7874 -0.4064)
			(stroke
				(width 0.1524)
				(type default)
			)
			(layer "F.SilkS")
		)
		(fp_line
			(start 0.7874 -0.4064)
			(end 0.7874 0.4064)
			(stroke
				(width 0.1524)
				(type default)
			)
			(layer "F.SilkS")
		)
		(fp_line
			(start 0.7874 0.4064)
			(end -0.7874 0.4064)
			(stroke
				(width 0.1524)
				(type default)
			)
			(layer "F.SilkS")
		)
		(fp_line
			(start -0.67945 -0.305054)
			(end -0.12065 -0.305054)
			(stroke
				(width 0.1)
				(type default)
			)
			(layer "F.Fab")
		)
		(fp_line
			(start -0.67945 0.3048)
			(end -0.67945 -0.305054)
			(stroke
				(width 0.1)
				(type default)
			)
			(layer "F.Fab")
		)
		(fp_line
			(start -0.12065 -0.305054)
			(end -0.12065 -0.2794)
			(stroke
				(width 0.1)
				(type default)
			)
			(layer "F.Fab")
		)
		(fp_line
			(start -0.12065 -0.2794)
			(end 0.12065 -0.2794)
			(stroke
				(width 0.1)
				(type default)
			)
			(layer "F.Fab")
		)
		(fp_line
			(start -0.12065 0.2794)
			(end -0.12065 0.3048)
			(stroke
				(width 0.1)
				(type default)
			)
			(layer "F.Fab")
		)
		(fp_line
			(start -0.12065 0.3048)
			(end -0.67945 0.3048)
			(stroke
				(width 0.1)
				(type default)
			)
			(layer "F.Fab")
		)
		(fp_line
			(start 0.120396 0.2794)
			(end -0.12065 0.2794)
			(stroke
				(width 0.1)
				(type default)
			)
			(layer "F.Fab")
		)
		(fp_line
			(start 0.120396 0.3048)
			(end 0.120396 0.2794)
			(stroke
				(width 0.1)
				(type default)
			)
			(layer "F.Fab")
		)
		(fp_line
			(start 0.12065 -0.3048)
			(end 0.67945 -0.3048)
			(stroke
				(width 0.1)
				(type default)
			)
			(layer "F.Fab")
		)
		(fp_line
			(start 0.12065 -0.2794)
			(end 0.12065 -0.3048)
			(stroke
				(width 0.1)
				(type default)
			)
			(layer "F.Fab")
		)
		(fp_line
			(start 0.67945 -0.3048)
			(end 0.67945 0.3048)
			(stroke
				(width 0.1)
				(type default)
			)
			(layer "F.Fab")
		)
		(fp_line
			(start 0.67945 0.3048)
			(end 0.120396 0.3048)
			(stroke
				(width 0.1)
				(type default)
			)
			(layer "F.Fab")
		)
		(pad "1" smd circle
			(at -0.40005 0)
			(size 0 0)
			(layers "F.Cu" "F.Mask" "F.Paste")
			(net "P3V3_AUX_VOS")
		)
		(pad "2" smd circle
			(at 0.40005 0)
			(size 0 0)
			(layers "F.Cu" "F.Mask" "F.Paste")
			(net "P3V3_AUX")
		)
	)
	(footprint ""
		(layer "F.Cu")
		(at 130.10388 -21.554948 90)
		(property "Reference" "R3302"
			(at 0 0 90)
			(layer "F.SilkS")
			(hide yes)
			(effects
				(font
					(size 1.27 1.27)
				)
			)
		)
		(property "Value" ""
			(at 0 0 90)
			(layer "F.Fab")
			(effects
				(font
					(size 1.27 1.27)
				)
			)
		)
		(duplicate_pad_numbers_are_jumpers no)
		(fp_line
			(start 0.7874 -0.4064)
			(end 0.7874 0.4064)
			(stroke
				(width 0.1524)
				(type default)
			)
			(layer "F.SilkS")
		)
		(fp_line
			(start -0.7874 -0.4064)
			(end 0.7874 -0.4064)
			(stroke
				(width 0.1524)
				(type default)
			)
			(layer "F.SilkS")
		)
		(fp_line
			(start 0.7874 0.4064)
			(end -0.7874 0.4064)
			(stroke
				(width 0.1524)
				(type default)
			)
			(layer "F.SilkS")
		)
		(fp_line
			(start -0.7874 0.4064)
			(end -0.7874 -0.4064)
			(stroke
				(width 0.1524)
				(type default)
			)
			(layer "F.SilkS")
		)
		(fp_line
			(start -0.12065 -0.305054)
			(end -0.12065 -0.2794)
			(stroke
				(width 0.1)
				(type default)
			)
			(layer "F.Fab")
		)
		(fp_line
			(start -0.67945 -0.305054)
			(end -0.12065 -0.305054)
			(stroke
				(width 0.1)
				(type default)
			)
			(layer "F.Fab")
		)
		(fp_line
			(start 0.67945 -0.3048)
			(end 0.67945 0.3048)
			(stroke
				(width 0.1)
				(type default)
			)
			(layer "F.Fab")
		)
		(fp_line
			(start 0.12065 -0.3048)
			(end 0.67945 -0.3048)
			(stroke
				(width 0.1)
				(type default)
			)
			(layer "F.Fab")
		)
		(fp_line
			(start 0.12065 -0.2794)
			(end 0.12065 -0.3048)
			(stroke
				(width 0.1)
				(type default)
			)
			(layer "F.Fab")
		)
		(fp_line
			(start -0.12065 -0.2794)
			(end 0.12065 -0.2794)
			(stroke
				(width 0.1)
				(type default)
			)
			(layer "F.Fab")
		)
		(fp_line
			(start 0.120396 0.2794)
			(end -0.12065 0.2794)
			(stroke
				(width 0.1)
				(type default)
			)
			(layer "F.Fab")
		)
		(fp_line
			(start -0.12065 0.2794)
			(end -0.12065 0.3048)
			(stroke
				(width 0.1)
				(type default)
			)
			(layer "F.Fab")
		)
		(fp_line
			(start 0.67945 0.3048)
			(end 0.120396 0.3048)
			(stroke
				(width 0.1)
				(type default)
			)
			(layer "F.Fab")
		)
		(fp_line
			(start 0.120396 0.3048)
			(end 0.120396 0.2794)
			(stroke
				(width 0.1)
				(type default)
			)
			(layer "F.Fab")
		)
		(fp_line
			(start -0.12065 0.3048)
			(end -0.67945 0.3048)
			(stroke
				(width 0.1)
				(type default)
			)
			(layer "F.Fab")
		)
		(fp_line
			(start -0.67945 0.3048)
			(end -0.67945 -0.305054)
			(stroke
				(width 0.1)
				(type default)
			)
			(layer "F.Fab")
		)
		(pad "1" smd circle
			(at -0.40005 0 90)
			(size 0 0)
			(layers "F.Cu" "F.Mask" "F.Paste")
			(net "TP_PCIE_HPM_TXN<3>")
		)
		(pad "2" smd circle
			(at 0.40005 0 90)
			(size 0 0)
			(layers "F.Cu" "F.Mask" "F.Paste")
			(net "FM_PCH_SPKR")
		)
	)
	(footprint ""
		(layer "F.Cu")
		(at 437.58358 -55.26532)
		(property "Reference" "Q56"
			(at -0.813308 3.743452 0)
			(unlocked yes)
			(layer "F.SilkS")
			(effects
				(font
					(size 0.7874 0.5842)
					(thickness 0.1524)
				)
			)
		)
		(property "Value" ""
			(at 0 0 0)
			(layer "F.Fab")
			(effects
				(font
					(size 1.27 1.27)
				)
			)
		)
		(duplicate_pad_numbers_are_jumpers no)
		(fp_line
			(start -2.350008 -2.649982)
			(end 2.350008 -2.649982)
			(stroke
				(width 0.1524)
				(type default)
			)
			(layer "F.SilkS")
		)
		(fp_line
			(start -2.350008 -2.4384)
			(end -2.350008 -2.649982)
			(stroke
				(width 0.1524)
				(type default)
			)
			(layer "F.SilkS")
		)
		(fp_line
			(start -2.350008 2.649982)
			(end -2.350008 2.413)
			(stroke
				(width 0.1524)
				(type default)
			)
			(layer "F.SilkS")
		)
		(fp_line
			(start 2.350008 -2.649982)
			(end 2.350008 -2.4892)
			(stroke
				(width 0.1524)
				(type default)
			)
			(layer "F.SilkS")
		)
		(fp_line
			(start 2.350008 2.4892)
			(end 2.350008 2.649982)
			(stroke
				(width 0.1524)
				(type default)
			)
			(layer "F.SilkS")
		)
		(fp_line
			(start 2.350008 2.649982)
			(end -2.350008 2.649982)
			(stroke
				(width 0.1524)
				(type default)
			)
			(layer "F.SilkS")
		)
		(fp_poly
			(pts
				(xy -3.00609 -2.66827) (xy -3.38709 -3.70967) (xy -2.58699 -3.70967)
			)
			(stroke
				(width 0)
				(type default)
			)
			(fill yes)
			(layer "F.SilkS")
		)
		(fp_line
			(start -2.350008 -2.649982)
			(end 2.350008 -2.649982)
			(stroke
				(width 0.1)
				(type default)
			)
			(layer "F.Fab")
		)
		(fp_line
			(start -2.350008 2.649982)
			(end -2.350008 -2.649982)
			(stroke
				(width 0.1)
				(type default)
			)
			(layer "F.Fab")
		)
		(fp_line
			(start 2.350008 -2.649982)
			(end 2.350008 2.649982)
			(stroke
				(width 0.1)
				(type default)
			)
			(layer "F.Fab")
		)
		(fp_line
			(start 2.350008 2.649982)
			(end -2.350008 2.649982)
			(stroke
				(width 0.1)
				(type default)
			)
			(layer "F.Fab")
		)
		(fp_poly
			(pts
				(xy -3.717544 -1.905) (xy -4.758944 -2.3241) (xy -4.758944 -1.524)
			)
			(stroke
				(width 0)
				(type default)
			)
			(fill yes)
			(layer "F.Fab")
		)
		(pad "1" smd rect
			(at -2.999994 -1.905 270)
			(size 0.7112 1.1684)
			(layers "F.Cu" "F.Mask" "F.Paste")
			(net "P3V3")
		)
		(pad "2" smd rect
			(at -2.999994 -0.635 270)
			(size 0.7112 1.1684)
			(layers "F.Cu" "F.Mask" "F.Paste")
			(net "P3V3")
		)
		(pad "3" smd rect
			(at -2.999994 0.635 270)
			(size 0.7112 1.1684)
			(layers "F.Cu" "F.Mask" "F.Paste")
			(net "P3V3")
		)
		(pad "4" smd rect
			(at -2.999994 1.905 270)
			(size 0.7112 1.1684)
			(layers "F.Cu" "F.Mask" "F.Paste")
			(net "PWRGD_P5V_ISO_R")
		)
		(pad "5" smd circle
			(at 0.925068 0 270)
			(size 0 0)
			(layers "F.Cu" "F.Mask" "F.Paste")
			(net "P3V3_AUX")
		)
		(zone
			(layer "F.Cu")
			(hatch none 0.5)
			(connect_pads
				(clearance 0)
			)
			(min_thickness 0.25)
			(keepout
				(tracks not_allowed)
				(vias allowed)
				(pads allowed)
				(copperpour not_allowed)
				(footprints allowed)
			)
			(placement
				(enabled no)
				(sheetname "")
			)
			(fill
				(thermal_gap 0.5)
				(thermal_bridge_width 0.5)
				(island_removal_mode 0)
			)
			(polygon
				(pts
					(xy 436.13578 -57.42432) (xy 436.13578 -53.10632) (xy 436.13578 -52.62372) (xy 435.23408 -52.62372)
					(xy 435.23408 -57.90692) (xy 435.873652 -57.90692) (xy 436.13578 -57.644792)
				)
			)
		)
	)
	(footprint ""
		(layer "F.Cu")
		(at 190.41364 -67.391788 180)
		(property "Reference" "PR3945"
			(at 0 0 180)
			(layer "F.SilkS")
			(hide yes)
			(effects
				(font
					(size 1.27 1.27)
				)
			)
		)
		(property "Value" ""
			(at 0 0 180)
			(layer "F.Fab")
			(effects
				(font
					(size 1.27 1.27)
				)
			)
		)
		(duplicate_pad_numbers_are_jumpers no)
		(fp_line
			(start 0.7874 0.4064)
			(end -0.7874 0.4064)
			(stroke
				(width 0.1524)
				(type default)
			)
			(layer "F.SilkS")
		)
		(fp_line
			(start 0.7874 -0.4064)
			(end 0.7874 0.4064)
			(stroke
				(width 0.1524)
				(type default)
			)
			(layer "F.SilkS")
		)
		(fp_line
			(start -0.7874 0.4064)
			(end -0.7874 -0.4064)
			(stroke
				(width 0.1524)
				(type default)
			)
			(layer "F.SilkS")
		)
		(fp_line
			(start -0.7874 -0.4064)
			(end 0.7874 -0.4064)
			(stroke
				(width 0.1524)
				(type default)
			)
			(layer "F.SilkS")
		)
		(fp_line
			(start 0.67945 0.3048)
			(end 0.120396 0.3048)
			(stroke
				(width 0.1)
				(type default)
			)
			(layer "F.Fab")
		)
		(fp_line
			(start 0.67945 -0.3048)
			(end 0.67945 0.3048)
			(stroke
				(width 0.1)
				(type default)
			)
			(layer "F.Fab")
		)
		(fp_line
			(start 0.12065 -0.2794)
			(end 0.12065 -0.3048)
			(stroke
				(width 0.1)
				(type default)
			)
			(layer "F.Fab")
		)
		(fp_line
			(start 0.12065 -0.3048)
			(end 0.67945 -0.3048)
			(stroke
				(width 0.1)
				(type default)
			)
			(layer "F.Fab")
		)
		(fp_line
			(start 0.120396 0.3048)
			(end 0.120396 0.2794)
			(stroke
				(width 0.1)
				(type default)
			)
			(layer "F.Fab")
		)
		(fp_line
			(start 0.120396 0.2794)
			(end -0.12065 0.2794)
			(stroke
				(width 0.1)
				(type default)
			)
			(layer "F.Fab")
		)
		(fp_line
			(start -0.12065 0.3048)
			(end -0.67945 0.3048)
			(stroke
				(width 0.1)
				(type default)
			)
			(layer "F.Fab")
		)
		(fp_line
			(start -0.12065 0.2794)
			(end -0.12065 0.3048)
			(stroke
				(width 0.1)
				(type default)
			)
			(layer "F.Fab")
		)
		(fp_line
			(start -0.12065 -0.2794)
			(end 0.12065 -0.2794)
			(stroke
				(width 0.1)
				(type default)
			)
			(layer "F.Fab")
		)
		(fp_line
			(start -0.12065 -0.305054)
			(end -0.12065 -0.2794)
			(stroke
				(width 0.1)
				(type default)
			)
			(layer "F.Fab")
		)
		(fp_line
			(start -0.67945 0.3048)
			(end -0.67945 -0.305054)
			(stroke
				(width 0.1)
				(type default)
			)
			(layer "F.Fab")
		)
		(fp_line
			(start -0.67945 -0.305054)
			(end -0.12065 -0.305054)
			(stroke
				(width 0.1)
				(type default)
			)
			(layer "F.Fab")
		)
		(pad "1" smd circle
			(at -0.40005 0 180)
			(size 0 0)
			(layers "F.Cu" "F.Mask" "F.Paste")
			(net "P3V3_E1S_MODE_0")
		)
		(pad "2" smd circle
			(at 0.40005 0 180)
			(size 0 0)
			(layers "F.Cu" "F.Mask" "F.Paste")
			(net "GND")
		)
	)
	(footprint ""
		(layer "F.Cu")
		(at 43.754294 -16.099536 90)
		(property "Reference" "C827"
			(at 0 0 90)
			(layer "F.SilkS")
			(hide yes)
			(effects
				(font
					(size 1.27 1.27)
				)
			)
		)
		(property "Value" ""
			(at 0 0 90)
			(layer "F.Fab")
			(effects
				(font
					(size 1.27 1.27)
				)
			)
		)
		(duplicate_pad_numbers_are_jumpers no)
		(fp_line
			(start 0.299974 -0.150114)
			(end 0.299974 0.150114)
			(stroke
				(width 0.1)
				(type default)
			)
			(layer "F.Fab")
		)
		(fp_line
			(start -0.299974 -0.150114)
			(end 0.299974 -0.150114)
			(stroke
				(width 0.1)
				(type default)
			)
			(layer "F.Fab")
		)
		(fp_line
			(start 0.299974 0.150114)
			(end -0.299974 0.150114)
			(stroke
				(width 0.1)
				(type default)
			)
			(layer "F.Fab")
		)
		(fp_line
			(start -0.299974 0.150114)
			(end -0.299974 -0.150114)
			(stroke
				(width 0.1)
				(type default)
			)
			(layer "F.Fab")
		)
		(pad "1" smd rect
			(at -0.2667 0 90)
			(size 0.3048 0.381)
			(layers "F.Cu" "F.Mask" "F.Paste")
			(net "P5E_CPU1_PE1_TX_C_DP<5>")
		)
		(pad "2" smd rect
			(at 0.2667 0 90)
			(size 0.3048 0.381)
			(layers "F.Cu" "F.Mask" "F.Paste")
			(net "P5E_CPU1_PE1_TX_DP<5>")
		)
	)
	(footprint ""
		(layer "F.Cu")
		(at 118.542816 -245.634256 -90)
		(property "Reference" "C264"
			(at 0 0 270)
			(layer "F.SilkS")
			(hide yes)
			(effects
				(font
					(size 1.27 1.27)
				)
			)
		)
		(property "Value" ""
			(at 0 0 270)
			(layer "F.Fab")
			(effects
				(font
					(size 1.27 1.27)
				)
			)
		)
		(duplicate_pad_numbers_are_jumpers no)
		(fp_line
			(start -0.7874 0.4064)
			(end -0.7874 -0.4064)
			(stroke
				(width 0.1524)
				(type default)
			)
			(layer "F.SilkS")
		)
		(fp_line
			(start 0.7874 0.4064)
			(end -0.7874 0.4064)
			(stroke
				(width 0.1524)
				(type default)
			)
			(layer "F.SilkS")
		)
		(fp_line
			(start -0.7874 -0.4064)
			(end 0.7874 -0.4064)
			(stroke
				(width 0.1524)
				(type default)
			)
			(layer "F.SilkS")
		)
		(fp_line
			(start 0.7874 -0.4064)
			(end 0.7874 0.4064)
			(stroke
				(width 0.1524)
				(type default)
			)
			(layer "F.SilkS")
		)
		(fp_line
			(start -0.67945 0.3048)
			(end -0.67945 -0.305054)
			(stroke
				(width 0.1)
				(type default)
			)
			(layer "F.Fab")
		)
		(fp_line
			(start -0.12065 0.3048)
			(end -0.67945 0.3048)
			(stroke
				(width 0.1)
				(type default)
			)
			(layer "F.Fab")
		)
		(fp_line
			(start 0.120396 0.3048)
			(end 0.120396 0.2794)
			(stroke
				(width 0.1)
				(type default)
			)
			(layer "F.Fab")
		)
		(fp_line
			(start 0.67945 0.3048)
			(end 0.120396 0.3048)
			(stroke
				(width 0.1)
				(type default)
			)
			(layer "F.Fab")
		)
		(fp_line
			(start -0.12065 0.2794)
			(end -0.12065 0.3048)
			(stroke
				(width 0.1)
				(type default)
			)
			(layer "F.Fab")
		)
		(fp_line
			(start 0.120396 0.2794)
			(end -0.12065 0.2794)
			(stroke
				(width 0.1)
				(type default)
			)
			(layer "F.Fab")
		)
		(fp_line
			(start -0.12065 -0.2794)
			(end 0.12065 -0.2794)
			(stroke
				(width 0.1)
				(type default)
			)
			(layer "F.Fab")
		)
		(fp_line
			(start 0.12065 -0.2794)
			(end 0.12065 -0.3048)
			(stroke
				(width 0.1)
				(type default)
			)
			(layer "F.Fab")
		)
		(fp_line
			(start 0.12065 -0.3048)
			(end 0.67945 -0.3048)
			(stroke
				(width 0.1)
				(type default)
			)
			(layer "F.Fab")
		)
		(fp_line
			(start 0.67945 -0.3048)
			(end 0.67945 0.3048)
			(stroke
				(width 0.1)
				(type default)
			)
			(layer "F.Fab")
		)
		(fp_line
			(start -0.67945 -0.305054)
			(end -0.12065 -0.305054)
			(stroke
				(width 0.1)
				(type default)
			)
			(layer "F.Fab")
		)
		(fp_line
			(start -0.12065 -0.305054)
			(end -0.12065 -0.2794)
			(stroke
				(width 0.1)
				(type default)
			)
			(layer "F.Fab")
		)
		(pad "1" smd circle
			(at -0.40005 0 270)
			(size 0 0)
			(layers "F.Cu" "F.Mask" "F.Paste")
			(net "PVCCIN_CPU1")
		)
		(pad "2" smd circle
			(at 0.40005 0 270)
			(size 0 0)
			(layers "F.Cu" "F.Mask" "F.Paste")
			(net "GND")
		)
	)
	(footprint ""
		(layer "F.Cu")
		(at 216.065608 -404.823422)
		(property "Reference" "PC2183"
			(at 0 0 0)
			(layer "F.SilkS")
			(hide yes)
			(effects
				(font
					(size 1.27 1.27)
				)
			)
		)
		(property "Value" ""
			(at 0 0 0)
			(layer "F.Fab")
			(effects
				(font
					(size 1.27 1.27)
				)
			)
		)
		(duplicate_pad_numbers_are_jumpers no)
		(fp_line
			(start -0.7874 -0.4064)
			(end 0.7874 -0.4064)
			(stroke
				(width 0.1524)
				(type default)
			)
			(layer "F.SilkS")
		)
		(fp_line
			(start -0.7874 0.4064)
			(end -0.7874 -0.4064)
			(stroke
				(width 0.1524)
				(type default)
			)
			(layer "F.SilkS")
		)
		(fp_line
			(start 0.7874 -0.4064)
			(end 0.7874 0.4064)
			(stroke
				(width 0.1524)
				(type default)
			)
			(layer "F.SilkS")
		)
		(fp_line
			(start 0.7874 0.4064)
			(end -0.7874 0.4064)
			(stroke
				(width 0.1524)
				(type default)
			)
			(layer "F.SilkS")
		)
		(fp_line
			(start -0.67945 -0.305054)
			(end -0.12065 -0.305054)
			(stroke
				(width 0.1)
				(type default)
			)
			(layer "F.Fab")
		)
		(fp_line
			(start -0.67945 0.3048)
			(end -0.67945 -0.305054)
			(stroke
				(width 0.1)
				(type default)
			)
			(layer "F.Fab")
		)
		(fp_line
			(start -0.12065 -0.305054)
			(end -0.12065 -0.2794)
			(stroke
				(width 0.1)
				(type default)
			)
			(layer "F.Fab")
		)
		(fp_line
			(start -0.12065 -0.2794)
			(end 0.12065 -0.2794)
			(stroke
				(width 0.1)
				(type default)
			)
			(layer "F.Fab")
		)
		(fp_line
			(start -0.12065 0.2794)
			(end -0.12065 0.3048)
			(stroke
				(width 0.1)
				(type default)
			)
			(layer "F.Fab")
		)
		(fp_line
			(start -0.12065 0.3048)
			(end -0.67945 0.3048)
			(stroke
				(width 0.1)
				(type default)
			)
			(layer "F.Fab")
		)
		(fp_line
			(start 0.120396 0.2794)
			(end -0.12065 0.2794)
			(stroke
				(width 0.1)
				(type default)
			)
			(layer "F.Fab")
		)
		(fp_line
			(start 0.120396 0.3048)
			(end 0.120396 0.2794)
			(stroke
				(width 0.1)
				(type default)
			)
			(layer "F.Fab")
		)
		(fp_line
			(start 0.12065 -0.3048)
			(end 0.67945 -0.3048)
			(stroke
				(width 0.1)
				(type default)
			)
			(layer "F.Fab")
		)
		(fp_line
			(start 0.12065 -0.2794)
			(end 0.12065 -0.3048)
			(stroke
				(width 0.1)
				(type default)
			)
			(layer "F.Fab")
		)
		(fp_line
			(start 0.67945 -0.3048)
			(end 0.67945 0.3048)
			(stroke
				(width 0.1)
				(type default)
			)
			(layer "F.Fab")
		)
		(fp_line
			(start 0.67945 0.3048)
			(end 0.120396 0.3048)
			(stroke
				(width 0.1)
				(type default)
			)
			(layer "F.Fab")
		)
		(pad "1" smd circle
			(at -0.40005 0)
			(size 0 0)
			(layers "F.Cu" "F.Mask" "F.Paste")
			(net "HSC_ON")
		)
		(pad "2" smd circle
			(at 0.40005 0)
			(size 0 0)
			(layers "F.Cu" "F.Mask" "F.Paste")
			(net "AGND_HSC")
		)
	)
	(footprint ""
		(layer "F.Cu")
		(at 17.190974 -92.687648 90)
		(property "Reference" "R3662"
			(at 0 0 90)
			(layer "F.SilkS")
			(hide yes)
			(effects
				(font
					(size 1.27 1.27)
				)
			)
		)
		(property "Value" ""
			(at 0 0 90)
			(layer "F.Fab")
			(effects
				(font
					(size 1.27 1.27)
				)
			)
		)
		(duplicate_pad_numbers_are_jumpers no)
		(fp_line
			(start 0.7874 -0.4064)
			(end 0.7874 0.4064)
			(stroke
				(width 0.1524)
				(type default)
			)
			(layer "F.SilkS")
		)
		(fp_line
			(start -0.7874 -0.4064)
			(end 0.7874 -0.4064)
			(stroke
				(width 0.1524)
				(type default)
			)
			(layer "F.SilkS")
		)
		(fp_line
			(start 0.7874 0.4064)
			(end -0.7874 0.4064)
			(stroke
				(width 0.1524)
				(type default)
			)
			(layer "F.SilkS")
		)
		(fp_line
			(start -0.7874 0.4064)
			(end -0.7874 -0.4064)
			(stroke
				(width 0.1524)
				(type default)
			)
			(layer "F.SilkS")
		)
		(fp_line
			(start -0.12065 -0.305054)
			(end -0.12065 -0.2794)
			(stroke
				(width 0.1)
				(type default)
			)
			(layer "F.Fab")
		)
		(fp_line
			(start -0.67945 -0.305054)
			(end -0.12065 -0.305054)
			(stroke
				(width 0.1)
				(type default)
			)
			(layer "F.Fab")
		)
		(fp_line
			(start 0.67945 -0.3048)
			(end 0.67945 0.3048)
			(stroke
				(width 0.1)
				(type default)
			)
			(layer "F.Fab")
		)
		(fp_line
			(start 0.12065 -0.3048)
			(end 0.67945 -0.3048)
			(stroke
				(width 0.1)
				(type default)
			)
			(layer "F.Fab")
		)
		(fp_line
			(start 0.12065 -0.2794)
			(end 0.12065 -0.3048)
			(stroke
				(width 0.1)
				(type default)
			)
			(layer "F.Fab")
		)
		(fp_line
			(start -0.12065 -0.2794)
			(end 0.12065 -0.2794)
			(stroke
				(width 0.1)
				(type default)
			)
			(layer "F.Fab")
		)
		(fp_line
			(start 0.120396 0.2794)
			(end -0.12065 0.2794)
			(stroke
				(width 0.1)
				(type default)
			)
			(layer "F.Fab")
		)
		(fp_line
			(start -0.12065 0.2794)
			(end -0.12065 0.3048)
			(stroke
				(width 0.1)
				(type default)
			)
			(layer "F.Fab")
		)
		(fp_line
			(start 0.67945 0.3048)
			(end 0.120396 0.3048)
			(stroke
				(width 0.1)
				(type default)
			)
			(layer "F.Fab")
		)
		(fp_line
			(start 0.120396 0.3048)
			(end 0.120396 0.2794)
			(stroke
				(width 0.1)
				(type default)
			)
			(layer "F.Fab")
		)
		(fp_line
			(start -0.12065 0.3048)
			(end -0.67945 0.3048)
			(stroke
				(width 0.1)
				(type default)
			)
			(layer "F.Fab")
		)
		(fp_line
			(start -0.67945 0.3048)
			(end -0.67945 -0.305054)
			(stroke
				(width 0.1)
				(type default)
			)
			(layer "F.Fab")
		)
		(pad "1" smd circle
			(at -0.40005 0 90)
			(size 0 0)
			(layers "F.Cu" "F.Mask" "F.Paste")
			(net "P3V3_AUX_USB_HUB")
		)
		(pad "2" smd circle
			(at 0.40005 0 90)
			(size 0 0)
			(layers "F.Cu" "F.Mask" "F.Paste")
			(net "USB_HUB_DVDD")
		)
	)
	(footprint ""
		(layer "F.Cu")
		(at 128.02616 -96.495108 90)
		(property "Reference" "R4403"
			(at 0 0 90)
			(layer "F.SilkS")
			(hide yes)
			(effects
				(font
					(size 1.27 1.27)
				)
			)
		)
		(property "Value" ""
			(at 0 0 90)
			(layer "F.Fab")
			(effects
				(font
					(size 1.27 1.27)
				)
			)
		)
		(duplicate_pad_numbers_are_jumpers no)
		(fp_line
			(start 0.7874 -0.4064)
			(end 0.7874 0.4064)
			(stroke
				(width 0.1524)
				(type default)
			)
			(layer "F.SilkS")
		)
		(fp_line
			(start -0.7874 -0.4064)
			(end 0.7874 -0.4064)
			(stroke
				(width 0.1524)
				(type default)
			)
			(layer "F.SilkS")
		)
		(fp_line
			(start 0.7874 0.4064)
			(end -0.7874 0.4064)
			(stroke
				(width 0.1524)
				(type default)
			)
			(layer "F.SilkS")
		)
		(fp_line
			(start -0.7874 0.4064)
			(end -0.7874 -0.4064)
			(stroke
				(width 0.1524)
				(type default)
			)
			(layer "F.SilkS")
		)
		(fp_line
			(start -0.12065 -0.305054)
			(end -0.12065 -0.2794)
			(stroke
				(width 0.1)
				(type default)
			)
			(layer "F.Fab")
		)
		(fp_line
			(start -0.67945 -0.305054)
			(end -0.12065 -0.305054)
			(stroke
				(width 0.1)
				(type default)
			)
			(layer "F.Fab")
		)
		(fp_line
			(start 0.67945 -0.3048)
			(end 0.67945 0.3048)
			(stroke
				(width 0.1)
				(type default)
			)
			(layer "F.Fab")
		)
		(fp_line
			(start 0.12065 -0.3048)
			(end 0.67945 -0.3048)
			(stroke
				(width 0.1)
				(type default)
			)
			(layer "F.Fab")
		)
		(fp_line
			(start 0.12065 -0.2794)
			(end 0.12065 -0.3048)
			(stroke
				(width 0.1)
				(type default)
			)
			(layer "F.Fab")
		)
		(fp_line
			(start -0.12065 -0.2794)
			(end 0.12065 -0.2794)
			(stroke
				(width 0.1)
				(type default)
			)
			(layer "F.Fab")
		)
		(fp_line
			(start 0.120396 0.2794)
			(end -0.12065 0.2794)
			(stroke
				(width 0.1)
				(type default)
			)
			(layer "F.Fab")
		)
		(fp_line
			(start -0.12065 0.2794)
			(end -0.12065 0.3048)
			(stroke
				(width 0.1)
				(type default)
			)
			(layer "F.Fab")
		)
		(fp_line
			(start 0.67945 0.3048)
			(end 0.120396 0.3048)
			(stroke
				(width 0.1)
				(type default)
			)
			(layer "F.Fab")
		)
		(fp_line
			(start 0.120396 0.3048)
			(end 0.120396 0.2794)
			(stroke
				(width 0.1)
				(type default)
			)
			(layer "F.Fab")
		)
		(fp_line
			(start -0.12065 0.3048)
			(end -0.67945 0.3048)
			(stroke
				(width 0.1)
				(type default)
			)
			(layer "F.Fab")
		)
		(fp_line
			(start -0.67945 0.3048)
			(end -0.67945 -0.305054)
			(stroke
				(width 0.1)
				(type default)
			)
			(layer "F.Fab")
		)
		(pad "1" smd circle
			(at -0.40005 0 90)
			(size 0 0)
			(layers "F.Cu" "F.Mask" "F.Paste")
			(net "H_CPU0_MEMHOT_OUT")
		)
		(pad "2" smd circle
			(at 0.40005 0 90)
			(size 0 0)
			(layers "F.Cu" "F.Mask" "F.Paste")
			(net "H_CPU0_MEMHOT_OUT_R")
		)
	)
	(footprint ""
		(layer "F.Cu")
		(at 234.11688 -256.123948 -90)
		(property "Reference" "R4075"
			(at 0 0 270)
			(layer "F.SilkS")
			(hide yes)
			(effects
				(font
					(size 1.27 1.27)
				)
			)
		)
		(property "Value" ""
			(at 0 0 270)
			(layer "F.Fab")
			(effects
				(font
					(size 1.27 1.27)
				)
			)
		)
		(duplicate_pad_numbers_are_jumpers no)
		(fp_line
			(start -0.7874 0.4064)
			(end -0.7874 -0.4064)
			(stroke
				(width 0.1524)
				(type default)
			)
			(layer "F.SilkS")
		)
		(fp_line
			(start 0.7874 0.4064)
			(end -0.7874 0.4064)
			(stroke
				(width 0.1524)
				(type default)
			)
			(layer "F.SilkS")
		)
		(fp_line
			(start -0.7874 -0.4064)
			(end 0.7874 -0.4064)
			(stroke
				(width 0.1524)
				(type default)
			)
			(layer "F.SilkS")
		)
		(fp_line
			(start 0.7874 -0.4064)
			(end 0.7874 0.4064)
			(stroke
				(width 0.1524)
				(type default)
			)
			(layer "F.SilkS")
		)
		(fp_line
			(start -0.67945 0.3048)
			(end -0.67945 -0.305054)
			(stroke
				(width 0.1)
				(type default)
			)
			(layer "F.Fab")
		)
		(fp_line
			(start -0.12065 0.3048)
			(end -0.67945 0.3048)
			(stroke
				(width 0.1)
				(type default)
			)
			(layer "F.Fab")
		)
		(fp_line
			(start 0.120396 0.3048)
			(end 0.120396 0.2794)
			(stroke
				(width 0.1)
				(type default)
			)
			(layer "F.Fab")
		)
		(fp_line
			(start 0.67945 0.3048)
			(end 0.120396 0.3048)
			(stroke
				(width 0.1)
				(type default)
			)
			(layer "F.Fab")
		)
		(fp_line
			(start -0.12065 0.2794)
			(end -0.12065 0.3048)
			(stroke
				(width 0.1)
				(type default)
			)
			(layer "F.Fab")
		)
		(fp_line
			(start 0.120396 0.2794)
			(end -0.12065 0.2794)
			(stroke
				(width 0.1)
				(type default)
			)
			(layer "F.Fab")
		)
		(fp_line
			(start -0.12065 -0.2794)
			(end 0.12065 -0.2794)
			(stroke
				(width 0.1)
				(type default)
			)
			(layer "F.Fab")
		)
		(fp_line
			(start 0.12065 -0.2794)
			(end 0.12065 -0.3048)
			(stroke
				(width 0.1)
				(type default)
			)
			(layer "F.Fab")
		)
		(fp_line
			(start 0.12065 -0.3048)
			(end 0.67945 -0.3048)
			(stroke
				(width 0.1)
				(type default)
			)
			(layer "F.Fab")
		)
		(fp_line
			(start 0.67945 -0.3048)
			(end 0.67945 0.3048)
			(stroke
				(width 0.1)
				(type default)
			)
			(layer "F.Fab")
		)
		(fp_line
			(start -0.67945 -0.305054)
			(end -0.12065 -0.305054)
			(stroke
				(width 0.1)
				(type default)
			)
			(layer "F.Fab")
		)
		(fp_line
			(start -0.12065 -0.305054)
			(end -0.12065 -0.2794)
			(stroke
				(width 0.1)
				(type default)
			)
			(layer "F.Fab")
		)
		(pad "1" smd circle
			(at -0.40005 0 270)
			(size 0 0)
			(layers "F.Cu" "F.Mask" "F.Paste")
			(net "CLK_GEN2_BMC_RC_OE_N")
		)
		(pad "2" smd circle
			(at 0.40005 0 270)
			(size 0 0)
			(layers "F.Cu" "F.Mask" "F.Paste")
			(net "CLK_GEN2_BMC_RC_OE_R3_N")
		)
	)
	(footprint ""
		(layer "F.Cu")
		(at 263.65962 -130.602228 180)
		(property "Reference" "R4540"
			(at 0 0 180)
			(layer "F.SilkS")
			(hide yes)
			(effects
				(font
					(size 1.27 1.27)
				)
			)
		)
		(property "Value" ""
			(at 0 0 180)
			(layer "F.Fab")
			(effects
				(font
					(size 1.27 1.27)
				)
			)
		)
		(duplicate_pad_numbers_are_jumpers no)
		(fp_line
			(start 0.7874 0.4064)
			(end -0.7874 0.4064)
			(stroke
				(width 0.1524)
				(type default)
			)
			(layer "F.SilkS")
		)
		(fp_line
			(start 0.7874 -0.4064)
			(end 0.7874 0.4064)
			(stroke
				(width 0.1524)
				(type default)
			)
			(layer "F.SilkS")
		)
		(fp_line
			(start -0.7874 0.4064)
			(end -0.7874 -0.4064)
			(stroke
				(width 0.1524)
				(type default)
			)
			(layer "F.SilkS")
		)
		(fp_line
			(start -0.7874 -0.4064)
			(end 0.7874 -0.4064)
			(stroke
				(width 0.1524)
				(type default)
			)
			(layer "F.SilkS")
		)
		(fp_line
			(start 0.67945 0.3048)
			(end 0.120396 0.3048)
			(stroke
				(width 0.1)
				(type default)
			)
			(layer "F.Fab")
		)
		(fp_line
			(start 0.67945 -0.3048)
			(end 0.67945 0.3048)
			(stroke
				(width 0.1)
				(type default)
			)
			(layer "F.Fab")
		)
		(fp_line
			(start 0.12065 -0.2794)
			(end 0.12065 -0.3048)
			(stroke
				(width 0.1)
				(type default)
			)
			(layer "F.Fab")
		)
		(fp_line
			(start 0.12065 -0.3048)
			(end 0.67945 -0.3048)
			(stroke
				(width 0.1)
				(type default)
			)
			(layer "F.Fab")
		)
		(fp_line
			(start 0.120396 0.3048)
			(end 0.120396 0.2794)
			(stroke
				(width 0.1)
				(type default)
			)
			(layer "F.Fab")
		)
		(fp_line
			(start 0.120396 0.2794)
			(end -0.12065 0.2794)
			(stroke
				(width 0.1)
				(type default)
			)
			(layer "F.Fab")
		)
		(fp_line
			(start -0.12065 0.3048)
			(end -0.67945 0.3048)
			(stroke
				(width 0.1)
				(type default)
			)
			(layer "F.Fab")
		)
		(fp_line
			(start -0.12065 0.2794)
			(end -0.12065 0.3048)
			(stroke
				(width 0.1)
				(type default)
			)
			(layer "F.Fab")
		)
		(fp_line
			(start -0.12065 -0.2794)
			(end 0.12065 -0.2794)
			(stroke
				(width 0.1)
				(type default)
			)
			(layer "F.Fab")
		)
		(fp_line
			(start -0.12065 -0.305054)
			(end -0.12065 -0.2794)
			(stroke
				(width 0.1)
				(type default)
			)
			(layer "F.Fab")
		)
		(fp_line
			(start -0.67945 0.3048)
			(end -0.67945 -0.305054)
			(stroke
				(width 0.1)
				(type default)
			)
			(layer "F.Fab")
		)
		(fp_line
			(start -0.67945 -0.305054)
			(end -0.12065 -0.305054)
			(stroke
				(width 0.1)
				(type default)
			)
			(layer "F.Fab")
		)
		(pad "1" smd circle
			(at -0.40005 0 180)
			(size 0 0)
			(layers "F.Cu" "F.Mask" "F.Paste")
			(net "SMB_HOST_CLK_BUF_ISO_3V3AUX_S_1")
		)
		(pad "2" smd circle
			(at 0.40005 0 180)
			(size 0 0)
			(layers "F.Cu" "F.Mask" "F.Paste")
			(net "SMB_HOST_CLK_BUF_ISO_3V3AUX_SCL")
		)
	)
	(footprint ""
		(layer "F.Cu")
		(at 150.622 -133.314948)
		(property "Reference" "R4605"
			(at 0 0 0)
			(layer "F.SilkS")
			(hide yes)
			(effects
				(font
					(size 1.27 1.27)
				)
			)
		)
		(property "Value" ""
			(at 0 0 0)
			(layer "F.Fab")
			(effects
				(font
					(size 1.27 1.27)
				)
			)
		)
		(duplicate_pad_numbers_are_jumpers no)
		(fp_line
			(start -0.7874 -0.4064)
			(end 0.7874 -0.4064)
			(stroke
				(width 0.1524)
				(type default)
			)
			(layer "F.SilkS")
		)
		(fp_line
			(start -0.7874 0.4064)
			(end -0.7874 -0.4064)
			(stroke
				(width 0.1524)
				(type default)
			)
			(layer "F.SilkS")
		)
		(fp_line
			(start 0.7874 -0.4064)
			(end 0.7874 0.4064)
			(stroke
				(width 0.1524)
				(type default)
			)
			(layer "F.SilkS")
		)
		(fp_line
			(start 0.7874 0.4064)
			(end -0.7874 0.4064)
			(stroke
				(width 0.1524)
				(type default)
			)
			(layer "F.SilkS")
		)
		(fp_line
			(start -0.67945 -0.305054)
			(end -0.12065 -0.305054)
			(stroke
				(width 0.1)
				(type default)
			)
			(layer "F.Fab")
		)
		(fp_line
			(start -0.67945 0.3048)
			(end -0.67945 -0.305054)
			(stroke
				(width 0.1)
				(type default)
			)
			(layer "F.Fab")
		)
		(fp_line
			(start -0.12065 -0.305054)
			(end -0.12065 -0.2794)
			(stroke
				(width 0.1)
				(type default)
			)
			(layer "F.Fab")
		)
		(fp_line
			(start -0.12065 -0.2794)
			(end 0.12065 -0.2794)
			(stroke
				(width 0.1)
				(type default)
			)
			(layer "F.Fab")
		)
		(fp_line
			(start -0.12065 0.2794)
			(end -0.12065 0.3048)
			(stroke
				(width 0.1)
				(type default)
			)
			(layer "F.Fab")
		)
		(fp_line
			(start -0.12065 0.3048)
			(end -0.67945 0.3048)
			(stroke
				(width 0.1)
				(type default)
			)
			(layer "F.Fab")
		)
		(fp_line
			(start 0.120396 0.2794)
			(end -0.12065 0.2794)
			(stroke
				(width 0.1)
				(type default)
			)
			(layer "F.Fab")
		)
		(fp_line
			(start 0.120396 0.3048)
			(end 0.120396 0.2794)
			(stroke
				(width 0.1)
				(type default)
			)
			(layer "F.Fab")
		)
		(fp_line
			(start 0.12065 -0.3048)
			(end 0.67945 -0.3048)
			(stroke
				(width 0.1)
				(type default)
			)
			(layer "F.Fab")
		)
		(fp_line
			(start 0.12065 -0.2794)
			(end 0.12065 -0.3048)
			(stroke
				(width 0.1)
				(type default)
			)
			(layer "F.Fab")
		)
		(fp_line
			(start 0.67945 -0.3048)
			(end 0.67945 0.3048)
			(stroke
				(width 0.1)
				(type default)
			)
			(layer "F.Fab")
		)
		(fp_line
			(start 0.67945 0.3048)
			(end 0.120396 0.3048)
			(stroke
				(width 0.1)
				(type default)
			)
			(layer "F.Fab")
		)
		(pad "1" smd circle
			(at -0.40005 0)
			(size 0 0)
			(layers "F.Cu" "F.Mask" "F.Paste")
			(net "P3V3_AUX")
		)
		(pad "2" smd circle
			(at 0.40005 0)
			(size 0 0)
			(layers "F.Cu" "F.Mask" "F.Paste")
			(net "PWRGD_PS_PWROK_PLD_ISO")
		)
	)
	(footprint ""
		(layer "F.Cu")
		(at 111.764826 -402.145246 90)
		(property "Reference" "U257"
			(at 1.622552 -4.533646 0)
			(unlocked yes)
			(layer "F.SilkS")
			(effects
				(font
					(size 0.7874 0.5842)
					(thickness 0.1524)
				)
				(justify left)
			)
		)
		(property "Value" ""
			(at 0 0 90)
			(layer "F.Fab")
			(effects
				(font
					(size 1.27 1.27)
				)
			)
		)
		(duplicate_pad_numbers_are_jumpers no)
		(fp_line
			(start 1.38176 -1.100074)
			(end 0.592074 -1.100074)
			(stroke
				(width 0.1524)
				(type default)
			)
			(layer "F.SilkS")
		)
		(fp_line
			(start 0.592074 -1.100074)
			(end 0 -0.508)
			(stroke
				(width 0.1524)
				(type default)
			)
			(layer "F.SilkS")
		)
		(fp_line
			(start -0.592074 -1.100074)
			(end -1.38176 -1.100074)
			(stroke
				(width 0.1524)
				(type default)
			)
			(layer "F.SilkS")
		)
		(fp_line
			(start -1.38176 -1.100074)
			(end -1.38176 1.100074)
			(stroke
				(width 0.1524)
				(type default)
			)
			(layer "F.SilkS")
		)
		(fp_line
			(start 0 -0.508)
			(end -0.592074 -1.100074)
			(stroke
				(width 0.1524)
				(type default)
			)
			(layer "F.SilkS")
		)
		(fp_line
			(start 1.38176 1.100074)
			(end 1.38176 -1.100074)
			(stroke
				(width 0.1524)
				(type default)
			)
			(layer "F.SilkS")
		)
		(fp_line
			(start -1.38176 1.100074)
			(end 1.38176 1.100074)
			(stroke
				(width 0.1524)
				(type default)
			)
			(layer "F.SilkS")
		)
		(fp_poly
			(pts
				(xy -1.50241 -0.649986) (xy -1.9431 -0.429768) (xy -1.9431 -0.870204)
			)
			(stroke
				(width 0)
				(type default)
			)
			(fill yes)
			(layer "F.SilkS")
		)
		(fp_line
			(start 0.674878 -1.100074)
			(end -0.674878 -1.100074)
			(stroke
				(width 0.1)
				(type default)
			)
			(layer "F.Fab")
		)
		(fp_line
			(start -0.674878 -1.100074)
			(end -0.674878 1.100074)
			(stroke
				(width 0.1)
				(type default)
			)
			(layer "F.Fab")
		)
		(fp_line
			(start 0.674878 1.100074)
			(end 0.674878 -1.100074)
			(stroke
				(width 0.1)
				(type default)
			)
			(layer "F.Fab")
		)
		(fp_line
			(start -0.674878 1.100074)
			(end 0.674878 1.100074)
			(stroke
				(width 0.1)
				(type default)
			)
			(layer "F.Fab")
		)
		(fp_poly
			(pts
				(xy -1.9431 -0.870204) (xy -1.50241 -0.649986) (xy -1.9431 -0.429768)
			)
			(stroke
				(width 0)
				(type default)
			)
			(fill yes)
			(layer "F.Fab")
		)
		(pad "1" smd rect
			(at -0.94996 -0.649986)
			(size 0.4318 0.6096)
			(layers "F.Cu" "F.Mask" "F.Paste")
			(net "GPU_FPGA_EROT_RECOV_N")
		)
		(pad "2" smd rect
			(at -0.94996 0)
			(size 0.4318 0.6096)
			(layers "F.Cu" "F.Mask" "F.Paste")
			(net "GND")
		)
		(pad "3" smd rect
			(at -0.94996 0.649986)
			(size 0.4318 0.6096)
			(layers "F.Cu" "F.Mask" "F.Paste")
			(net "GND")
		)
		(pad "4" smd rect
			(at 0.94996 0.649986)
			(size 0.4318 0.6096)
			(layers "F.Cu" "F.Mask" "F.Paste")
			(net "NC_U257_2Y")
		)
		(pad "5" smd rect
			(at 0.94996 0)
			(size 0.4318 0.6096)
			(layers "F.Cu" "F.Mask" "F.Paste")
			(net "P3V3_AUX")
		)
		(pad "6" smd rect
			(at 0.94996 -0.649986)
			(size 0.4318 0.6096)
			(layers "F.Cu" "F.Mask" "F.Paste")
			(net "GPU_FPGA_EROT_RECOV_BUF_R_N")
		)
	)
	(footprint ""
		(layer "F.Cu")
		(at 331.224636 -16.401288)
		(property "Reference" "R2452"
			(at 0 0 0)
			(layer "F.SilkS")
			(hide yes)
			(effects
				(font
					(size 1.27 1.27)
				)
			)
		)
		(property "Value" ""
			(at 0 0 0)
			(layer "F.Fab")
			(effects
				(font
					(size 1.27 1.27)
				)
			)
		)
		(duplicate_pad_numbers_are_jumpers no)
		(fp_line
			(start -0.7874 -0.4064)
			(end 0.7874 -0.4064)
			(stroke
				(width 0.1524)
				(type default)
			)
			(layer "F.SilkS")
		)
		(fp_line
			(start -0.7874 0.4064)
			(end -0.7874 -0.4064)
			(stroke
				(width 0.1524)
				(type default)
			)
			(layer "F.SilkS")
		)
		(fp_line
			(start 0.7874 -0.4064)
			(end 0.7874 0.4064)
			(stroke
				(width 0.1524)
				(type default)
			)
			(layer "F.SilkS")
		)
		(fp_line
			(start 0.7874 0.4064)
			(end -0.7874 0.4064)
			(stroke
				(width 0.1524)
				(type default)
			)
			(layer "F.SilkS")
		)
		(fp_line
			(start -0.67945 -0.305054)
			(end -0.12065 -0.305054)
			(stroke
				(width 0.1)
				(type default)
			)
			(layer "F.Fab")
		)
		(fp_line
			(start -0.67945 0.3048)
			(end -0.67945 -0.305054)
			(stroke
				(width 0.1)
				(type default)
			)
			(layer "F.Fab")
		)
		(fp_line
			(start -0.12065 -0.305054)
			(end -0.12065 -0.2794)
			(stroke
				(width 0.1)
				(type default)
			)
			(layer "F.Fab")
		)
		(fp_line
			(start -0.12065 -0.2794)
			(end 0.12065 -0.2794)
			(stroke
				(width 0.1)
				(type default)
			)
			(layer "F.Fab")
		)
		(fp_line
			(start -0.12065 0.2794)
			(end -0.12065 0.3048)
			(stroke
				(width 0.1)
				(type default)
			)
			(layer "F.Fab")
		)
		(fp_line
			(start -0.12065 0.3048)
			(end -0.67945 0.3048)
			(stroke
				(width 0.1)
				(type default)
			)
			(layer "F.Fab")
		)
		(fp_line
			(start 0.120396 0.2794)
			(end -0.12065 0.2794)
			(stroke
				(width 0.1)
				(type default)
			)
			(layer "F.Fab")
		)
		(fp_line
			(start 0.120396 0.3048)
			(end 0.120396 0.2794)
			(stroke
				(width 0.1)
				(type default)
			)
			(layer "F.Fab")
		)
		(fp_line
			(start 0.12065 -0.3048)
			(end 0.67945 -0.3048)
			(stroke
				(width 0.1)
				(type default)
			)
			(layer "F.Fab")
		)
		(fp_line
			(start 0.12065 -0.2794)
			(end 0.12065 -0.3048)
			(stroke
				(width 0.1)
				(type default)
			)
			(layer "F.Fab")
		)
		(fp_line
			(start 0.67945 -0.3048)
			(end 0.67945 0.3048)
			(stroke
				(width 0.1)
				(type default)
			)
			(layer "F.Fab")
		)
		(fp_line
			(start 0.67945 0.3048)
			(end 0.120396 0.3048)
			(stroke
				(width 0.1)
				(type default)
			)
			(layer "F.Fab")
		)
		(pad "1" smd circle
			(at -0.40005 0)
			(size 0 0)
			(layers "F.Cu" "F.Mask" "F.Paste")
			(net "FM_ESPI_PLD_R_EN")
		)
		(pad "2" smd circle
			(at 0.40005 0)
			(size 0 0)
			(layers "F.Cu" "F.Mask" "F.Paste")
			(net "FM_ESPI_PLD_R1_EN")
		)
	)
	(footprint ""
		(layer "F.Cu")
		(at 27.79395 -58.960512 180)
		(property "Reference" "R3103"
			(at 0 0 180)
			(layer "F.SilkS")
			(hide yes)
			(effects
				(font
					(size 1.27 1.27)
				)
			)
		)
		(property "Value" ""
			(at 0 0 180)
			(layer "F.Fab")
			(effects
				(font
					(size 1.27 1.27)
				)
			)
		)
		(duplicate_pad_numbers_are_jumpers no)
		(fp_line
			(start 0.7874 0.4064)
			(end -0.7874 0.4064)
			(stroke
				(width 0.1524)
				(type default)
			)
			(layer "F.SilkS")
		)
		(fp_line
			(start 0.7874 -0.4064)
			(end 0.7874 0.4064)
			(stroke
				(width 0.1524)
				(type default)
			)
			(layer "F.SilkS")
		)
		(fp_line
			(start -0.7874 0.4064)
			(end -0.7874 -0.4064)
			(stroke
				(width 0.1524)
				(type default)
			)
			(layer "F.SilkS")
		)
		(fp_line
			(start -0.7874 -0.4064)
			(end 0.7874 -0.4064)
			(stroke
				(width 0.1524)
				(type default)
			)
			(layer "F.SilkS")
		)
		(fp_line
			(start 0.67945 0.3048)
			(end 0.120396 0.3048)
			(stroke
				(width 0.1)
				(type default)
			)
			(layer "F.Fab")
		)
		(fp_line
			(start 0.67945 -0.3048)
			(end 0.67945 0.3048)
			(stroke
				(width 0.1)
				(type default)
			)
			(layer "F.Fab")
		)
		(fp_line
			(start 0.12065 -0.2794)
			(end 0.12065 -0.3048)
			(stroke
				(width 0.1)
				(type default)
			)
			(layer "F.Fab")
		)
		(fp_line
			(start 0.12065 -0.3048)
			(end 0.67945 -0.3048)
			(stroke
				(width 0.1)
				(type default)
			)
			(layer "F.Fab")
		)
		(fp_line
			(start 0.120396 0.3048)
			(end 0.120396 0.2794)
			(stroke
				(width 0.1)
				(type default)
			)
			(layer "F.Fab")
		)
		(fp_line
			(start 0.120396 0.2794)
			(end -0.12065 0.2794)
			(stroke
				(width 0.1)
				(type default)
			)
			(layer "F.Fab")
		)
		(fp_line
			(start -0.12065 0.3048)
			(end -0.67945 0.3048)
			(stroke
				(width 0.1)
				(type default)
			)
			(layer "F.Fab")
		)
		(fp_line
			(start -0.12065 0.2794)
			(end -0.12065 0.3048)
			(stroke
				(width 0.1)
				(type default)
			)
			(layer "F.Fab")
		)
		(fp_line
			(start -0.12065 -0.2794)
			(end 0.12065 -0.2794)
			(stroke
				(width 0.1)
				(type default)
			)
			(layer "F.Fab")
		)
		(fp_line
			(start -0.12065 -0.305054)
			(end -0.12065 -0.2794)
			(stroke
				(width 0.1)
				(type default)
			)
			(layer "F.Fab")
		)
		(fp_line
			(start -0.67945 0.3048)
			(end -0.67945 -0.305054)
			(stroke
				(width 0.1)
				(type default)
			)
			(layer "F.Fab")
		)
		(fp_line
			(start -0.67945 -0.305054)
			(end -0.12065 -0.305054)
			(stroke
				(width 0.1)
				(type default)
			)
			(layer "F.Fab")
		)
		(pad "1" smd circle
			(at -0.40005 0 180)
			(size 0 0)
			(layers "F.Cu" "F.Mask" "F.Paste")
			(net "IRQ_SML0_ALERT_R_N")
		)
		(pad "2" smd circle
			(at 0.40005 0 180)
			(size 0 0)
			(layers "F.Cu" "F.Mask" "F.Paste")
			(net "IRQ_SML0_ALERT_R1_N")
		)
	)
	(footprint ""
		(layer "F.Cu")
		(at 73.506076 -174.903638 180)
		(property "Reference" "PR567"
			(at 0 0 180)
			(layer "F.SilkS")
			(hide yes)
			(effects
				(font
					(size 1.27 1.27)
				)
			)
		)
		(property "Value" ""
			(at 0 0 180)
			(layer "F.Fab")
			(effects
				(font
					(size 1.27 1.27)
				)
			)
		)
		(duplicate_pad_numbers_are_jumpers no)
		(fp_line
			(start 0.7874 0.4064)
			(end -0.7874 0.4064)
			(stroke
				(width 0.1524)
				(type default)
			)
			(layer "F.SilkS")
		)
		(fp_line
			(start 0.7874 -0.4064)
			(end 0.7874 0.4064)
			(stroke
				(width 0.1524)
				(type default)
			)
			(layer "F.SilkS")
		)
		(fp_line
			(start -0.7874 0.4064)
			(end -0.7874 -0.4064)
			(stroke
				(width 0.1524)
				(type default)
			)
			(layer "F.SilkS")
		)
		(fp_line
			(start -0.7874 -0.4064)
			(end 0.7874 -0.4064)
			(stroke
				(width 0.1524)
				(type default)
			)
			(layer "F.SilkS")
		)
		(fp_line
			(start 0.67945 0.3048)
			(end 0.120396 0.3048)
			(stroke
				(width 0.1)
				(type default)
			)
			(layer "F.Fab")
		)
		(fp_line
			(start 0.67945 -0.3048)
			(end 0.67945 0.3048)
			(stroke
				(width 0.1)
				(type default)
			)
			(layer "F.Fab")
		)
		(fp_line
			(start 0.12065 -0.2794)
			(end 0.12065 -0.3048)
			(stroke
				(width 0.1)
				(type default)
			)
			(layer "F.Fab")
		)
		(fp_line
			(start 0.12065 -0.3048)
			(end 0.67945 -0.3048)
			(stroke
				(width 0.1)
				(type default)
			)
			(layer "F.Fab")
		)
		(fp_line
			(start 0.120396 0.3048)
			(end 0.120396 0.2794)
			(stroke
				(width 0.1)
				(type default)
			)
			(layer "F.Fab")
		)
		(fp_line
			(start 0.120396 0.2794)
			(end -0.12065 0.2794)
			(stroke
				(width 0.1)
				(type default)
			)
			(layer "F.Fab")
		)
		(fp_line
			(start -0.12065 0.3048)
			(end -0.67945 0.3048)
			(stroke
				(width 0.1)
				(type default)
			)
			(layer "F.Fab")
		)
		(fp_line
			(start -0.12065 0.2794)
			(end -0.12065 0.3048)
			(stroke
				(width 0.1)
				(type default)
			)
			(layer "F.Fab")
		)
		(fp_line
			(start -0.12065 -0.2794)
			(end 0.12065 -0.2794)
			(stroke
				(width 0.1)
				(type default)
			)
			(layer "F.Fab")
		)
		(fp_line
			(start -0.12065 -0.305054)
			(end -0.12065 -0.2794)
			(stroke
				(width 0.1)
				(type default)
			)
			(layer "F.Fab")
		)
		(fp_line
			(start -0.67945 0.3048)
			(end -0.67945 -0.305054)
			(stroke
				(width 0.1)
				(type default)
			)
			(layer "F.Fab")
		)
		(fp_line
			(start -0.67945 -0.305054)
			(end -0.12065 -0.305054)
			(stroke
				(width 0.1)
				(type default)
			)
			(layer "F.Fab")
		)
		(pad "1" smd circle
			(at -0.40005 0 180)
			(size 0 0)
			(layers "F.Cu" "F.Mask" "F.Paste")
			(net "VSENSE_PVCCFA_EHV_CPU1_DN")
		)
		(pad "2" smd circle
			(at 0.40005 0 180)
			(size 0 0)
			(layers "F.Cu" "F.Mask" "F.Paste")
			(net "GND")
		)
	)
	(footprint ""
		(layer "F.Cu")
		(at 126.065026 -336.935572 -90)
		(property "Reference" "PC504_P1_5"
			(at 0 0 270)
			(layer "F.SilkS")
			(hide yes)
			(effects
				(font
					(size 1.27 1.27)
				)
			)
		)
		(property "Value" ""
			(at 0 0 270)
			(layer "F.Fab")
			(effects
				(font
					(size 1.27 1.27)
				)
			)
		)
		(duplicate_pad_numbers_are_jumpers no)
		(fp_line
			(start -0.7874 0.4064)
			(end -0.7874 -0.4064)
			(stroke
				(width 0.1524)
				(type default)
			)
			(layer "F.SilkS")
		)
		(fp_line
			(start 0.7874 0.4064)
			(end -0.7874 0.4064)
			(stroke
				(width 0.1524)
				(type default)
			)
			(layer "F.SilkS")
		)
		(fp_line
			(start -0.7874 -0.4064)
			(end 0.7874 -0.4064)
			(stroke
				(width 0.1524)
				(type default)
			)
			(layer "F.SilkS")
		)
		(fp_line
			(start 0.7874 -0.4064)
			(end 0.7874 0.4064)
			(stroke
				(width 0.1524)
				(type default)
			)
			(layer "F.SilkS")
		)
		(fp_line
			(start -0.67945 0.3048)
			(end -0.67945 -0.305054)
			(stroke
				(width 0.1)
				(type default)
			)
			(layer "F.Fab")
		)
		(fp_line
			(start -0.12065 0.3048)
			(end -0.67945 0.3048)
			(stroke
				(width 0.1)
				(type default)
			)
			(layer "F.Fab")
		)
		(fp_line
			(start 0.120396 0.3048)
			(end 0.120396 0.2794)
			(stroke
				(width 0.1)
				(type default)
			)
			(layer "F.Fab")
		)
		(fp_line
			(start 0.67945 0.3048)
			(end 0.120396 0.3048)
			(stroke
				(width 0.1)
				(type default)
			)
			(layer "F.Fab")
		)
		(fp_line
			(start -0.12065 0.2794)
			(end -0.12065 0.3048)
			(stroke
				(width 0.1)
				(type default)
			)
			(layer "F.Fab")
		)
		(fp_line
			(start 0.120396 0.2794)
			(end -0.12065 0.2794)
			(stroke
				(width 0.1)
				(type default)
			)
			(layer "F.Fab")
		)
		(fp_line
			(start -0.12065 -0.2794)
			(end 0.12065 -0.2794)
			(stroke
				(width 0.1)
				(type default)
			)
			(layer "F.Fab")
		)
		(fp_line
			(start 0.12065 -0.2794)
			(end 0.12065 -0.3048)
			(stroke
				(width 0.1)
				(type default)
			)
			(layer "F.Fab")
		)
		(fp_line
			(start 0.12065 -0.3048)
			(end 0.67945 -0.3048)
			(stroke
				(width 0.1)
				(type default)
			)
			(layer "F.Fab")
		)
		(fp_line
			(start 0.67945 -0.3048)
			(end 0.67945 0.3048)
			(stroke
				(width 0.1)
				(type default)
			)
			(layer "F.Fab")
		)
		(fp_line
			(start -0.67945 -0.305054)
			(end -0.12065 -0.305054)
			(stroke
				(width 0.1)
				(type default)
			)
			(layer "F.Fab")
		)
		(fp_line
			(start -0.12065 -0.305054)
			(end -0.12065 -0.2794)
			(stroke
				(width 0.1)
				(type default)
			)
			(layer "F.Fab")
		)
		(pad "1" smd circle
			(at -0.40005 0 270)
			(size 0 0)
			(layers "F.Cu" "F.Mask" "F.Paste")
			(net "PVCCIN_CPU1_PVCC")
		)
		(pad "2" smd circle
			(at 0.40005 0 270)
			(size 0 0)
			(layers "F.Cu" "F.Mask" "F.Paste")
			(net "GND")
		)
	)
	(footprint ""
		(layer "F.Cu")
		(at 371.791738 -413.90443 -90)
		(property "Reference" "R4207"
			(at 0 0 270)
			(layer "F.SilkS")
			(hide yes)
			(effects
				(font
					(size 1.27 1.27)
				)
			)
		)
		(property "Value" ""
			(at 0 0 270)
			(layer "F.Fab")
			(effects
				(font
					(size 1.27 1.27)
				)
			)
		)
		(duplicate_pad_numbers_are_jumpers no)
		(fp_line
			(start -0.7874 0.4064)
			(end -0.7874 -0.4064)
			(stroke
				(width 0.1524)
				(type default)
			)
			(layer "F.SilkS")
		)
		(fp_line
			(start 0.7874 0.4064)
			(end -0.7874 0.4064)
			(stroke
				(width 0.1524)
				(type default)
			)
			(layer "F.SilkS")
		)
		(fp_line
			(start -0.7874 -0.4064)
			(end 0.7874 -0.4064)
			(stroke
				(width 0.1524)
				(type default)
			)
			(layer "F.SilkS")
		)
		(fp_line
			(start 0.7874 -0.4064)
			(end 0.7874 0.4064)
			(stroke
				(width 0.1524)
				(type default)
			)
			(layer "F.SilkS")
		)
		(fp_line
			(start -0.67945 0.3048)
			(end -0.67945 -0.305054)
			(stroke
				(width 0.1)
				(type default)
			)
			(layer "F.Fab")
		)
		(fp_line
			(start -0.12065 0.3048)
			(end -0.67945 0.3048)
			(stroke
				(width 0.1)
				(type default)
			)
			(layer "F.Fab")
		)
		(fp_line
			(start 0.120396 0.3048)
			(end 0.120396 0.2794)
			(stroke
				(width 0.1)
				(type default)
			)
			(layer "F.Fab")
		)
		(fp_line
			(start 0.67945 0.3048)
			(end 0.120396 0.3048)
			(stroke
				(width 0.1)
				(type default)
			)
			(layer "F.Fab")
		)
		(fp_line
			(start -0.12065 0.2794)
			(end -0.12065 0.3048)
			(stroke
				(width 0.1)
				(type default)
			)
			(layer "F.Fab")
		)
		(fp_line
			(start 0.120396 0.2794)
			(end -0.12065 0.2794)
			(stroke
				(width 0.1)
				(type default)
			)
			(layer "F.Fab")
		)
		(fp_line
			(start -0.12065 -0.2794)
			(end 0.12065 -0.2794)
			(stroke
				(width 0.1)
				(type default)
			)
			(layer "F.Fab")
		)
		(fp_line
			(start 0.12065 -0.2794)
			(end 0.12065 -0.3048)
			(stroke
				(width 0.1)
				(type default)
			)
			(layer "F.Fab")
		)
		(fp_line
			(start 0.12065 -0.3048)
			(end 0.67945 -0.3048)
			(stroke
				(width 0.1)
				(type default)
			)
			(layer "F.Fab")
		)
		(fp_line
			(start 0.67945 -0.3048)
			(end 0.67945 0.3048)
			(stroke
				(width 0.1)
				(type default)
			)
			(layer "F.Fab")
		)
		(fp_line
			(start -0.67945 -0.305054)
			(end -0.12065 -0.305054)
			(stroke
				(width 0.1)
				(type default)
			)
			(layer "F.Fab")
		)
		(fp_line
			(start -0.12065 -0.305054)
			(end -0.12065 -0.2794)
			(stroke
				(width 0.1)
				(type default)
			)
			(layer "F.Fab")
		)
		(pad "1" smd circle
			(at -0.40005 0 270)
			(size 0 0)
			(layers "F.Cu" "F.Mask" "F.Paste")
			(net "U270_0_ADD0")
		)
		(pad "2" smd circle
			(at 0.40005 0 270)
			(size 0 0)
			(layers "F.Cu" "F.Mask" "F.Paste")
			(net "GND")
		)
	)
	(footprint ""
		(layer "F.Cu")
		(at 240.219738 -119.183658 -90)
		(property "Reference" "R3199"
			(at 0 0 270)
			(layer "F.SilkS")
			(hide yes)
			(effects
				(font
					(size 1.27 1.27)
				)
			)
		)
		(property "Value" ""
			(at 0 0 270)
			(layer "F.Fab")
			(effects
				(font
					(size 1.27 1.27)
				)
			)
		)
		(duplicate_pad_numbers_are_jumpers no)
		(fp_line
			(start 0.385318 0.4064)
			(end -0.254762 0.4064)
			(stroke
				(width 0.1524)
				(type default)
			)
			(layer "F.SilkS")
		)
		(fp_line
			(start -0.7874 0.044958)
			(end -0.7874 -0.4064)
			(stroke
				(width 0.1524)
				(type default)
			)
			(layer "F.SilkS")
		)
		(fp_line
			(start -0.7874 -0.4064)
			(end 0.7874 -0.4064)
			(stroke
				(width 0.1524)
				(type default)
			)
			(layer "F.SilkS")
		)
		(fp_line
			(start 0.7874 -0.4064)
			(end 0.7874 0.093218)
			(stroke
				(width 0.1524)
				(type default)
			)
			(layer "F.SilkS")
		)
		(fp_line
			(start -0.67945 0.3048)
			(end -0.67945 -0.305054)
			(stroke
				(width 0.1)
				(type default)
			)
			(layer "F.Fab")
		)
		(fp_line
			(start -0.12065 0.3048)
			(end -0.67945 0.3048)
			(stroke
				(width 0.1)
				(type default)
			)
			(layer "F.Fab")
		)
		(fp_line
			(start 0.120396 0.3048)
			(end 0.120396 0.2794)
			(stroke
				(width 0.1)
				(type default)
			)
			(layer "F.Fab")
		)
		(fp_line
			(start 0.67945 0.3048)
			(end 0.120396 0.3048)
			(stroke
				(width 0.1)
				(type default)
			)
			(layer "F.Fab")
		)
		(fp_line
			(start -0.12065 0.2794)
			(end -0.12065 0.3048)
			(stroke
				(width 0.1)
				(type default)
			)
			(layer "F.Fab")
		)
		(fp_line
			(start 0.120396 0.2794)
			(end -0.12065 0.2794)
			(stroke
				(width 0.1)
				(type default)
			)
			(layer "F.Fab")
		)
		(fp_line
			(start -0.12065 -0.2794)
			(end 0.12065 -0.2794)
			(stroke
				(width 0.1)
				(type default)
			)
			(layer "F.Fab")
		)
		(fp_line
			(start 0.12065 -0.2794)
			(end 0.12065 -0.3048)
			(stroke
				(width 0.1)
				(type default)
			)
			(layer "F.Fab")
		)
		(fp_line
			(start 0.12065 -0.3048)
			(end 0.67945 -0.3048)
			(stroke
				(width 0.1)
				(type default)
			)
			(layer "F.Fab")
		)
		(fp_line
			(start 0.67945 -0.3048)
			(end 0.67945 0.3048)
			(stroke
				(width 0.1)
				(type default)
			)
			(layer "F.Fab")
		)
		(fp_line
			(start -0.67945 -0.305054)
			(end -0.12065 -0.305054)
			(stroke
				(width 0.1)
				(type default)
			)
			(layer "F.Fab")
		)
		(fp_line
			(start -0.12065 -0.305054)
			(end -0.12065 -0.2794)
			(stroke
				(width 0.1)
				(type default)
			)
			(layer "F.Fab")
		)
		(pad "1" smd circle
			(at -0.40005 0 270)
			(size 0 0)
			(layers "F.Cu" "F.Mask" "F.Paste")
			(net "CLK_100M_OCP_V3_2_C_R_DN")
		)
		(pad "2" smd circle
			(at 0.40005 0 270)
			(size 0 0)
			(layers "F.Cu" "F.Mask" "F.Paste")
			(net "CLK_100M_OCP_V3_2_C_DN")
		)
	)
	(footprint ""
		(layer "F.Cu")
		(at 164.64788 -104.485948 180)
		(property "Reference" "R2662"
			(at 0 0 180)
			(layer "F.SilkS")
			(hide yes)
			(effects
				(font
					(size 1.27 1.27)
				)
			)
		)
		(property "Value" ""
			(at 0 0 180)
			(layer "F.Fab")
			(effects
				(font
					(size 1.27 1.27)
				)
			)
		)
		(duplicate_pad_numbers_are_jumpers no)
		(fp_line
			(start 0.7874 0.4064)
			(end -0.7874 0.4064)
			(stroke
				(width 0.1524)
				(type default)
			)
			(layer "F.SilkS")
		)
		(fp_line
			(start 0.7874 -0.4064)
			(end 0.7874 0.4064)
			(stroke
				(width 0.1524)
				(type default)
			)
			(layer "F.SilkS")
		)
		(fp_line
			(start -0.7874 0.4064)
			(end -0.7874 -0.4064)
			(stroke
				(width 0.1524)
				(type default)
			)
			(layer "F.SilkS")
		)
		(fp_line
			(start -0.7874 -0.4064)
			(end 0.7874 -0.4064)
			(stroke
				(width 0.1524)
				(type default)
			)
			(layer "F.SilkS")
		)
		(fp_line
			(start 0.67945 0.3048)
			(end 0.120396 0.3048)
			(stroke
				(width 0.1)
				(type default)
			)
			(layer "F.Fab")
		)
		(fp_line
			(start 0.67945 -0.3048)
			(end 0.67945 0.3048)
			(stroke
				(width 0.1)
				(type default)
			)
			(layer "F.Fab")
		)
		(fp_line
			(start 0.12065 -0.2794)
			(end 0.12065 -0.3048)
			(stroke
				(width 0.1)
				(type default)
			)
			(layer "F.Fab")
		)
		(fp_line
			(start 0.12065 -0.3048)
			(end 0.67945 -0.3048)
			(stroke
				(width 0.1)
				(type default)
			)
			(layer "F.Fab")
		)
		(fp_line
			(start 0.120396 0.3048)
			(end 0.120396 0.2794)
			(stroke
				(width 0.1)
				(type default)
			)
			(layer "F.Fab")
		)
		(fp_line
			(start 0.120396 0.2794)
			(end -0.12065 0.2794)
			(stroke
				(width 0.1)
				(type default)
			)
			(layer "F.Fab")
		)
		(fp_line
			(start -0.12065 0.3048)
			(end -0.67945 0.3048)
			(stroke
				(width 0.1)
				(type default)
			)
			(layer "F.Fab")
		)
		(fp_line
			(start -0.12065 0.2794)
			(end -0.12065 0.3048)
			(stroke
				(width 0.1)
				(type default)
			)
			(layer "F.Fab")
		)
		(fp_line
			(start -0.12065 -0.2794)
			(end 0.12065 -0.2794)
			(stroke
				(width 0.1)
				(type default)
			)
			(layer "F.Fab")
		)
		(fp_line
			(start -0.12065 -0.305054)
			(end -0.12065 -0.2794)
			(stroke
				(width 0.1)
				(type default)
			)
			(layer "F.Fab")
		)
		(fp_line
			(start -0.67945 0.3048)
			(end -0.67945 -0.305054)
			(stroke
				(width 0.1)
				(type default)
			)
			(layer "F.Fab")
		)
		(fp_line
			(start -0.67945 -0.305054)
			(end -0.12065 -0.305054)
			(stroke
				(width 0.1)
				(type default)
			)
			(layer "F.Fab")
		)
		(pad "1" smd circle
			(at -0.40005 0 180)
			(size 0 0)
			(layers "F.Cu" "F.Mask" "F.Paste")
			(net "FM_GPU_PWR_EN")
		)
		(pad "2" smd circle
			(at 0.40005 0 180)
			(size 0 0)
			(layers "F.Cu" "F.Mask" "F.Paste")
			(net "FM_GPU_PWR_EN_R")
		)
	)
	(footprint ""
		(layer "F.Cu")
		(at 21.73351 -168.183306 90)
		(property "Reference" "R223"
			(at 0 0 90)
			(layer "F.SilkS")
			(hide yes)
			(effects
				(font
					(size 1.27 1.27)
				)
			)
		)
		(property "Value" ""
			(at 0 0 90)
			(layer "F.Fab")
			(effects
				(font
					(size 1.27 1.27)
				)
			)
		)
		(duplicate_pad_numbers_are_jumpers no)
		(fp_line
			(start 0.7874 -0.4064)
			(end 0.7874 0.4064)
			(stroke
				(width 0.1524)
				(type default)
			)
			(layer "F.SilkS")
		)
		(fp_line
			(start -0.7874 -0.4064)
			(end 0.7874 -0.4064)
			(stroke
				(width 0.1524)
				(type default)
			)
			(layer "F.SilkS")
		)
		(fp_line
			(start 0.7874 0.4064)
			(end -0.7874 0.4064)
			(stroke
				(width 0.1524)
				(type default)
			)
			(layer "F.SilkS")
		)
		(fp_line
			(start -0.7874 0.4064)
			(end -0.7874 -0.4064)
			(stroke
				(width 0.1524)
				(type default)
			)
			(layer "F.SilkS")
		)
		(fp_line
			(start -0.12065 -0.305054)
			(end -0.12065 -0.2794)
			(stroke
				(width 0.1)
				(type default)
			)
			(layer "F.Fab")
		)
		(fp_line
			(start -0.67945 -0.305054)
			(end -0.12065 -0.305054)
			(stroke
				(width 0.1)
				(type default)
			)
			(layer "F.Fab")
		)
		(fp_line
			(start 0.67945 -0.3048)
			(end 0.67945 0.3048)
			(stroke
				(width 0.1)
				(type default)
			)
			(layer "F.Fab")
		)
		(fp_line
			(start 0.12065 -0.3048)
			(end 0.67945 -0.3048)
			(stroke
				(width 0.1)
				(type default)
			)
			(layer "F.Fab")
		)
		(fp_line
			(start 0.12065 -0.2794)
			(end 0.12065 -0.3048)
			(stroke
				(width 0.1)
				(type default)
			)
			(layer "F.Fab")
		)
		(fp_line
			(start -0.12065 -0.2794)
			(end 0.12065 -0.2794)
			(stroke
				(width 0.1)
				(type default)
			)
			(layer "F.Fab")
		)
		(fp_line
			(start 0.120396 0.2794)
			(end -0.12065 0.2794)
			(stroke
				(width 0.1)
				(type default)
			)
			(layer "F.Fab")
		)
		(fp_line
			(start -0.12065 0.2794)
			(end -0.12065 0.3048)
			(stroke
				(width 0.1)
				(type default)
			)
			(layer "F.Fab")
		)
		(fp_line
			(start 0.67945 0.3048)
			(end 0.120396 0.3048)
			(stroke
				(width 0.1)
				(type default)
			)
			(layer "F.Fab")
		)
		(fp_line
			(start 0.120396 0.3048)
			(end 0.120396 0.2794)
			(stroke
				(width 0.1)
				(type default)
			)
			(layer "F.Fab")
		)
		(fp_line
			(start -0.12065 0.3048)
			(end -0.67945 0.3048)
			(stroke
				(width 0.1)
				(type default)
			)
			(layer "F.Fab")
		)
		(fp_line
			(start -0.67945 0.3048)
			(end -0.67945 -0.305054)
			(stroke
				(width 0.1)
				(type default)
			)
			(layer "F.Fab")
		)
		(pad "1" smd circle
			(at -0.40005 0 90)
			(size 0 0)
			(layers "F.Cu" "F.Mask" "F.Paste")
			(net "P3V3_AUX")
		)
		(pad "2" smd circle
			(at 0.40005 0 90)
			(size 0 0)
			(layers "F.Cu" "F.Mask" "F.Paste")
			(net "IRQ_PVCCD_CPU1_VRHOT_LVC3_N")
		)
	)
	(footprint ""
		(layer "F.Cu")
		(at 437.425846 -380.05258 180)
		(property "Reference" "PC1852"
			(at 0 0 180)
			(layer "F.SilkS")
			(hide yes)
			(effects
				(font
					(size 1.27 1.27)
				)
			)
		)
		(property "Value" ""
			(at 0 0 180)
			(layer "F.Fab")
			(effects
				(font
					(size 1.27 1.27)
				)
			)
		)
		(duplicate_pad_numbers_are_jumpers no)
		(fp_line
			(start 0.7874 0.4064)
			(end -0.7874 0.4064)
			(stroke
				(width 0.1524)
				(type default)
			)
			(layer "F.SilkS")
		)
		(fp_line
			(start 0.7874 -0.4064)
			(end 0.7874 0.4064)
			(stroke
				(width 0.1524)
				(type default)
			)
			(layer "F.SilkS")
		)
		(fp_line
			(start -0.7874 0.4064)
			(end -0.7874 -0.4064)
			(stroke
				(width 0.1524)
				(type default)
			)
			(layer "F.SilkS")
		)
		(fp_line
			(start -0.7874 -0.4064)
			(end 0.7874 -0.4064)
			(stroke
				(width 0.1524)
				(type default)
			)
			(layer "F.SilkS")
		)
		(fp_line
			(start 0.67945 0.3048)
			(end 0.120396 0.3048)
			(stroke
				(width 0.1)
				(type default)
			)
			(layer "F.Fab")
		)
		(fp_line
			(start 0.67945 -0.3048)
			(end 0.67945 0.3048)
			(stroke
				(width 0.1)
				(type default)
			)
			(layer "F.Fab")
		)
		(fp_line
			(start 0.12065 -0.2794)
			(end 0.12065 -0.3048)
			(stroke
				(width 0.1)
				(type default)
			)
			(layer "F.Fab")
		)
		(fp_line
			(start 0.12065 -0.3048)
			(end 0.67945 -0.3048)
			(stroke
				(width 0.1)
				(type default)
			)
			(layer "F.Fab")
		)
		(fp_line
			(start 0.120396 0.3048)
			(end 0.120396 0.2794)
			(stroke
				(width 0.1)
				(type default)
			)
			(layer "F.Fab")
		)
		(fp_line
			(start 0.120396 0.2794)
			(end -0.12065 0.2794)
			(stroke
				(width 0.1)
				(type default)
			)
			(layer "F.Fab")
		)
		(fp_line
			(start -0.12065 0.3048)
			(end -0.67945 0.3048)
			(stroke
				(width 0.1)
				(type default)
			)
			(layer "F.Fab")
		)
		(fp_line
			(start -0.12065 0.2794)
			(end -0.12065 0.3048)
			(stroke
				(width 0.1)
				(type default)
			)
			(layer "F.Fab")
		)
		(fp_line
			(start -0.12065 -0.2794)
			(end 0.12065 -0.2794)
			(stroke
				(width 0.1)
				(type default)
			)
			(layer "F.Fab")
		)
		(fp_line
			(start -0.12065 -0.305054)
			(end -0.12065 -0.2794)
			(stroke
				(width 0.1)
				(type default)
			)
			(layer "F.Fab")
		)
		(fp_line
			(start -0.67945 0.3048)
			(end -0.67945 -0.305054)
			(stroke
				(width 0.1)
				(type default)
			)
			(layer "F.Fab")
		)
		(fp_line
			(start -0.67945 -0.305054)
			(end -0.12065 -0.305054)
			(stroke
				(width 0.1)
				(type default)
			)
			(layer "F.Fab")
		)
		(pad "1" smd circle
			(at -0.40005 0 180)
			(size 0 0)
			(layers "F.Cu" "F.Mask" "F.Paste")
			(net "P5V_AUX")
		)
		(pad "2" smd circle
			(at 0.40005 0 180)
			(size 0 0)
			(layers "F.Cu" "F.Mask" "F.Paste")
			(net "GND")
		)
	)
	(footprint ""
		(layer "F.Cu")
		(at 436.10911 -19.611086 -90)
		(property "Reference" "R417"
			(at 0 0 270)
			(layer "F.SilkS")
			(hide yes)
			(effects
				(font
					(size 1.27 1.27)
				)
			)
		)
		(property "Value" ""
			(at 0 0 270)
			(layer "F.Fab")
			(effects
				(font
					(size 1.27 1.27)
				)
			)
		)
		(duplicate_pad_numbers_are_jumpers no)
		(fp_line
			(start -0.7874 0.4064)
			(end -0.7874 -0.4064)
			(stroke
				(width 0.1524)
				(type default)
			)
			(layer "F.SilkS")
		)
		(fp_line
			(start 0.7874 0.4064)
			(end -0.7874 0.4064)
			(stroke
				(width 0.1524)
				(type default)
			)
			(layer "F.SilkS")
		)
		(fp_line
			(start -0.7874 -0.4064)
			(end 0.7874 -0.4064)
			(stroke
				(width 0.1524)
				(type default)
			)
			(layer "F.SilkS")
		)
		(fp_line
			(start 0.7874 -0.4064)
			(end 0.7874 0.4064)
			(stroke
				(width 0.1524)
				(type default)
			)
			(layer "F.SilkS")
		)
		(fp_line
			(start -0.67945 0.3048)
			(end -0.67945 -0.305054)
			(stroke
				(width 0.1)
				(type default)
			)
			(layer "F.Fab")
		)
		(fp_line
			(start -0.12065 0.3048)
			(end -0.67945 0.3048)
			(stroke
				(width 0.1)
				(type default)
			)
			(layer "F.Fab")
		)
		(fp_line
			(start 0.120396 0.3048)
			(end 0.120396 0.2794)
			(stroke
				(width 0.1)
				(type default)
			)
			(layer "F.Fab")
		)
		(fp_line
			(start 0.67945 0.3048)
			(end 0.120396 0.3048)
			(stroke
				(width 0.1)
				(type default)
			)
			(layer "F.Fab")
		)
		(fp_line
			(start -0.12065 0.2794)
			(end -0.12065 0.3048)
			(stroke
				(width 0.1)
				(type default)
			)
			(layer "F.Fab")
		)
		(fp_line
			(start 0.120396 0.2794)
			(end -0.12065 0.2794)
			(stroke
				(width 0.1)
				(type default)
			)
			(layer "F.Fab")
		)
		(fp_line
			(start -0.12065 -0.2794)
			(end 0.12065 -0.2794)
			(stroke
				(width 0.1)
				(type default)
			)
			(layer "F.Fab")
		)
		(fp_line
			(start 0.12065 -0.2794)
			(end 0.12065 -0.3048)
			(stroke
				(width 0.1)
				(type default)
			)
			(layer "F.Fab")
		)
		(fp_line
			(start 0.12065 -0.3048)
			(end 0.67945 -0.3048)
			(stroke
				(width 0.1)
				(type default)
			)
			(layer "F.Fab")
		)
		(fp_line
			(start 0.67945 -0.3048)
			(end 0.67945 0.3048)
			(stroke
				(width 0.1)
				(type default)
			)
			(layer "F.Fab")
		)
		(fp_line
			(start -0.67945 -0.305054)
			(end -0.12065 -0.305054)
			(stroke
				(width 0.1)
				(type default)
			)
			(layer "F.Fab")
		)
		(fp_line
			(start -0.12065 -0.305054)
			(end -0.12065 -0.2794)
			(stroke
				(width 0.1)
				(type default)
			)
			(layer "F.Fab")
		)
		(pad "1" smd circle
			(at -0.40005 0 270)
			(size 0 0)
			(layers "F.Cu" "F.Mask" "F.Paste")
			(net "OCP_SFF_ISO_BIF1_EN")
		)
		(pad "2" smd circle
			(at 0.40005 0 270)
			(size 0 0)
			(layers "F.Cu" "F.Mask" "F.Paste")
			(net "OCP_SFF_BIF1_R_N")
		)
	)
	(footprint ""
		(layer "F.Cu")
		(at 22.13356 -166.767256)
		(property "Reference" "PR215"
			(at 0 0 0)
			(layer "F.SilkS")
			(hide yes)
			(effects
				(font
					(size 1.27 1.27)
				)
			)
		)
		(property "Value" ""
			(at 0 0 0)
			(layer "F.Fab")
			(effects
				(font
					(size 1.27 1.27)
				)
			)
		)
		(duplicate_pad_numbers_are_jumpers no)
		(fp_line
			(start -0.7874 -0.4064)
			(end 0.7874 -0.4064)
			(stroke
				(width 0.1524)
				(type default)
			)
			(layer "F.SilkS")
		)
		(fp_line
			(start -0.7874 0.4064)
			(end -0.7874 -0.4064)
			(stroke
				(width 0.1524)
				(type default)
			)
			(layer "F.SilkS")
		)
		(fp_line
			(start 0.7874 -0.4064)
			(end 0.7874 0.4064)
			(stroke
				(width 0.1524)
				(type default)
			)
			(layer "F.SilkS")
		)
		(fp_line
			(start 0.7874 0.4064)
			(end -0.7874 0.4064)
			(stroke
				(width 0.1524)
				(type default)
			)
			(layer "F.SilkS")
		)
		(fp_line
			(start -0.67945 -0.305054)
			(end -0.12065 -0.305054)
			(stroke
				(width 0.1)
				(type default)
			)
			(layer "F.Fab")
		)
		(fp_line
			(start -0.67945 0.3048)
			(end -0.67945 -0.305054)
			(stroke
				(width 0.1)
				(type default)
			)
			(layer "F.Fab")
		)
		(fp_line
			(start -0.12065 -0.305054)
			(end -0.12065 -0.2794)
			(stroke
				(width 0.1)
				(type default)
			)
			(layer "F.Fab")
		)
		(fp_line
			(start -0.12065 -0.2794)
			(end 0.12065 -0.2794)
			(stroke
				(width 0.1)
				(type default)
			)
			(layer "F.Fab")
		)
		(fp_line
			(start -0.12065 0.2794)
			(end -0.12065 0.3048)
			(stroke
				(width 0.1)
				(type default)
			)
			(layer "F.Fab")
		)
		(fp_line
			(start -0.12065 0.3048)
			(end -0.67945 0.3048)
			(stroke
				(width 0.1)
				(type default)
			)
			(layer "F.Fab")
		)
		(fp_line
			(start 0.120396 0.2794)
			(end -0.12065 0.2794)
			(stroke
				(width 0.1)
				(type default)
			)
			(layer "F.Fab")
		)
		(fp_line
			(start 0.120396 0.3048)
			(end 0.120396 0.2794)
			(stroke
				(width 0.1)
				(type default)
			)
			(layer "F.Fab")
		)
		(fp_line
			(start 0.12065 -0.3048)
			(end 0.67945 -0.3048)
			(stroke
				(width 0.1)
				(type default)
			)
			(layer "F.Fab")
		)
		(fp_line
			(start 0.12065 -0.2794)
			(end 0.12065 -0.3048)
			(stroke
				(width 0.1)
				(type default)
			)
			(layer "F.Fab")
		)
		(fp_line
			(start 0.67945 -0.3048)
			(end 0.67945 0.3048)
			(stroke
				(width 0.1)
				(type default)
			)
			(layer "F.Fab")
		)
		(fp_line
			(start 0.67945 0.3048)
			(end 0.120396 0.3048)
			(stroke
				(width 0.1)
				(type default)
			)
			(layer "F.Fab")
		)
		(pad "1" smd circle
			(at -0.40005 0)
			(size 0 0)
			(layers "F.Cu" "F.Mask" "F.Paste")
			(net "P3V3_AUX")
		)
		(pad "2" smd circle
			(at 0.40005 0)
			(size 0 0)
			(layers "F.Cu" "F.Mask" "F.Paste")
			(net "PVCCD_HV_CPU1_PIN_ALT")
		)
	)
	(footprint ""
		(layer "F.Cu")
		(at 244.596666 -394.17117)
		(property "Reference" "PR2535"
			(at 0 0 0)
			(layer "F.SilkS")
			(hide yes)
			(effects
				(font
					(size 1.27 1.27)
				)
			)
		)
		(property "Value" ""
			(at 0 0 0)
			(layer "F.Fab")
			(effects
				(font
					(size 1.27 1.27)
				)
			)
		)
		(duplicate_pad_numbers_are_jumpers no)
		(fp_line
			(start -0.7874 -0.4064)
			(end 0.7874 -0.4064)
			(stroke
				(width 0.1524)
				(type default)
			)
			(layer "F.SilkS")
		)
		(fp_line
			(start -0.7874 0.4064)
			(end -0.7874 -0.4064)
			(stroke
				(width 0.1524)
				(type default)
			)
			(layer "F.SilkS")
		)
		(fp_line
			(start 0.7874 -0.4064)
			(end 0.7874 0.4064)
			(stroke
				(width 0.1524)
				(type default)
			)
			(layer "F.SilkS")
		)
		(fp_line
			(start 0.7874 0.4064)
			(end -0.7874 0.4064)
			(stroke
				(width 0.1524)
				(type default)
			)
			(layer "F.SilkS")
		)
		(fp_line
			(start -0.67945 -0.305054)
			(end -0.12065 -0.305054)
			(stroke
				(width 0.1)
				(type default)
			)
			(layer "F.Fab")
		)
		(fp_line
			(start -0.67945 0.3048)
			(end -0.67945 -0.305054)
			(stroke
				(width 0.1)
				(type default)
			)
			(layer "F.Fab")
		)
		(fp_line
			(start -0.12065 -0.305054)
			(end -0.12065 -0.2794)
			(stroke
				(width 0.1)
				(type default)
			)
			(layer "F.Fab")
		)
		(fp_line
			(start -0.12065 -0.2794)
			(end 0.12065 -0.2794)
			(stroke
				(width 0.1)
				(type default)
			)
			(layer "F.Fab")
		)
		(fp_line
			(start -0.12065 0.2794)
			(end -0.12065 0.3048)
			(stroke
				(width 0.1)
				(type default)
			)
			(layer "F.Fab")
		)
		(fp_line
			(start -0.12065 0.3048)
			(end -0.67945 0.3048)
			(stroke
				(width 0.1)
				(type default)
			)
			(layer "F.Fab")
		)
		(fp_line
			(start 0.120396 0.2794)
			(end -0.12065 0.2794)
			(stroke
				(width 0.1)
				(type default)
			)
			(layer "F.Fab")
		)
		(fp_line
			(start 0.120396 0.3048)
			(end 0.120396 0.2794)
			(stroke
				(width 0.1)
				(type default)
			)
			(layer "F.Fab")
		)
		(fp_line
			(start 0.12065 -0.3048)
			(end 0.67945 -0.3048)
			(stroke
				(width 0.1)
				(type default)
			)
			(layer "F.Fab")
		)
		(fp_line
			(start 0.12065 -0.2794)
			(end 0.12065 -0.3048)
			(stroke
				(width 0.1)
				(type default)
			)
			(layer "F.Fab")
		)
		(fp_line
			(start 0.67945 -0.3048)
			(end 0.67945 0.3048)
			(stroke
				(width 0.1)
				(type default)
			)
			(layer "F.Fab")
		)
		(fp_line
			(start 0.67945 0.3048)
			(end 0.120396 0.3048)
			(stroke
				(width 0.1)
				(type default)
			)
			(layer "F.Fab")
		)
		(pad "1" smd circle
			(at -0.40005 0)
			(size 0 0)
			(layers "F.Cu" "F.Mask" "F.Paste")
			(net "P12V_HSC_GATE_G5")
		)
		(pad "2" smd circle
			(at 0.40005 0)
			(size 0 0)
			(layers "F.Cu" "F.Mask" "F.Paste")
			(net "P12V_HSC_GATE2")
		)
	)
	(footprint ""
		(layer "F.Cu")
		(at 331.029056 -19.37766 90)
		(property "Reference" "R1254"
			(at 0 0 90)
			(layer "F.SilkS")
			(hide yes)
			(effects
				(font
					(size 1.27 1.27)
				)
			)
		)
		(property "Value" ""
			(at 0 0 90)
			(layer "F.Fab")
			(effects
				(font
					(size 1.27 1.27)
				)
			)
		)
		(duplicate_pad_numbers_are_jumpers no)
		(fp_line
			(start 0.7874 -0.4064)
			(end 0.7874 0.4064)
			(stroke
				(width 0.1524)
				(type default)
			)
			(layer "F.SilkS")
		)
		(fp_line
			(start -0.7874 -0.4064)
			(end 0.7874 -0.4064)
			(stroke
				(width 0.1524)
				(type default)
			)
			(layer "F.SilkS")
		)
		(fp_line
			(start 0.7874 0.4064)
			(end -0.7874 0.4064)
			(stroke
				(width 0.1524)
				(type default)
			)
			(layer "F.SilkS")
		)
		(fp_line
			(start -0.7874 0.4064)
			(end -0.7874 -0.4064)
			(stroke
				(width 0.1524)
				(type default)
			)
			(layer "F.SilkS")
		)
		(fp_line
			(start -0.12065 -0.305054)
			(end -0.12065 -0.2794)
			(stroke
				(width 0.1)
				(type default)
			)
			(layer "F.Fab")
		)
		(fp_line
			(start -0.67945 -0.305054)
			(end -0.12065 -0.305054)
			(stroke
				(width 0.1)
				(type default)
			)
			(layer "F.Fab")
		)
		(fp_line
			(start 0.67945 -0.3048)
			(end 0.67945 0.3048)
			(stroke
				(width 0.1)
				(type default)
			)
			(layer "F.Fab")
		)
		(fp_line
			(start 0.12065 -0.3048)
			(end 0.67945 -0.3048)
			(stroke
				(width 0.1)
				(type default)
			)
			(layer "F.Fab")
		)
		(fp_line
			(start 0.12065 -0.2794)
			(end 0.12065 -0.3048)
			(stroke
				(width 0.1)
				(type default)
			)
			(layer "F.Fab")
		)
		(fp_line
			(start -0.12065 -0.2794)
			(end 0.12065 -0.2794)
			(stroke
				(width 0.1)
				(type default)
			)
			(layer "F.Fab")
		)
		(fp_line
			(start 0.120396 0.2794)
			(end -0.12065 0.2794)
			(stroke
				(width 0.1)
				(type default)
			)
			(layer "F.Fab")
		)
		(fp_line
			(start -0.12065 0.2794)
			(end -0.12065 0.3048)
			(stroke
				(width 0.1)
				(type default)
			)
			(layer "F.Fab")
		)
		(fp_line
			(start 0.67945 0.3048)
			(end 0.120396 0.3048)
			(stroke
				(width 0.1)
				(type default)
			)
			(layer "F.Fab")
		)
		(fp_line
			(start 0.120396 0.3048)
			(end 0.120396 0.2794)
			(stroke
				(width 0.1)
				(type default)
			)
			(layer "F.Fab")
		)
		(fp_line
			(start -0.12065 0.3048)
			(end -0.67945 0.3048)
			(stroke
				(width 0.1)
				(type default)
			)
			(layer "F.Fab")
		)
		(fp_line
			(start -0.67945 0.3048)
			(end -0.67945 -0.305054)
			(stroke
				(width 0.1)
				(type default)
			)
			(layer "F.Fab")
		)
		(pad "1" smd circle
			(at -0.40005 0 90)
			(size 0 0)
			(layers "F.Cu" "F.Mask" "F.Paste")
			(net "PGPPA_AUX")
		)
		(pad "2" smd circle
			(at 0.40005 0 90)
			(size 0 0)
			(layers "F.Cu" "F.Mask" "F.Paste")
			(net "IRQ_LPC_SERIRQ_ESPI_CS1_N")
		)
	)
	(footprint ""
		(layer "F.Cu")
		(at 490.57433 2.370328 -90)
		(property "Reference" "X16"
			(at -1.342644 2.821178 90)
			(unlocked yes)
			(layer "F.SilkS")
			(effects
				(font
					(size 0.7874 0.5842)
					(thickness 0.1524)
				)
				(justify left)
			)
		)
		(property "Value" ""
			(at 0 0 270)
			(layer "F.Fab")
			(effects
				(font
					(size 1.27 1.27)
				)
			)
		)
		(property "Device Type" "TP_TDR_4P_FTS_TH-TP_TDR_4P_DIPA"
			(at 1.30175 1.27 0)
			(unlocked yes)
			(layer "F.Fab")
			(hide yes)
			(effects
				(font
					(size 0.635 0.4064)
					(thickness 0.1524)
				)
			)
		)
		(property "User Part Number" "N_A"
			(at 1.30175 1.27 0)
			(unlocked yes)
			(layer "Cmts.User")
			(hide yes)
			(effects
				(font
					(size 0.635 0.4064)
					(thickness 0.1524)
				)
			)
		)
		(duplicate_pad_numbers_are_jumpers no)
		(fp_line
			(start 0 3.81)
			(end 2.54 3.81)
			(stroke
				(width 0.1524)
				(type default)
			)
			(layer "F.SilkS")
		)
		(fp_line
			(start 2.54 3.81)
			(end 2.54 3.6703)
			(stroke
				(width 0.1524)
				(type default)
			)
			(layer "F.SilkS")
		)
		(fp_line
			(start 0 3.175)
			(end 0 3.81)
			(stroke
				(width 0.1524)
				(type default)
			)
			(layer "F.SilkS")
		)
		(fp_line
			(start 2.54 1.4097)
			(end 2.54 1.1303)
			(stroke
				(width 0.1524)
				(type default)
			)
			(layer "F.SilkS")
		)
		(fp_line
			(start 0 0.635)
			(end 0 1.905)
			(stroke
				(width 0.1524)
				(type default)
			)
			(layer "F.SilkS")
		)
		(fp_line
			(start 2.54 -1.1303)
			(end 2.54 -1.27)
			(stroke
				(width 0.1524)
				(type default)
			)
			(layer "F.SilkS")
		)
		(fp_line
			(start 0 -1.27)
			(end 0 -0.635)
			(stroke
				(width 0.1524)
				(type default)
			)
			(layer "F.SilkS")
		)
		(fp_line
			(start 2.54 -1.27)
			(end 0 -1.27)
			(stroke
				(width 0.1524)
				(type default)
			)
			(layer "F.SilkS")
		)
		(fp_poly
			(pts
				(xy -1.247648 0.03175) (xy -2.771648 0.79375) (xy -2.771648 -0.73025)
			)
			(stroke
				(width 0)
				(type default)
			)
			(fill yes)
			(layer "F.SilkS")
		)
		(fp_line
			(start 0 3.81)
			(end 2.54 3.81)
			(stroke
				(width 0.1)
				(type default)
			)
			(layer "F.Fab")
		)
		(fp_line
			(start 2.54 3.81)
			(end 2.54 -1.27)
			(stroke
				(width 0.1)
				(type default)
			)
			(layer "F.Fab")
		)
		(fp_line
			(start 0 -1.27)
			(end 0 3.81)
			(stroke
				(width 0.1)
				(type default)
			)
			(layer "F.Fab")
		)
		(fp_line
			(start 2.54 -1.27)
			(end 0 -1.27)
			(stroke
				(width 0.1)
				(type default)
			)
			(layer "F.Fab")
		)
		(fp_poly
			(pts
				(xy -0.761746 0) (xy -2.285746 -0.762) (xy -2.285746 0.762)
			)
			(stroke
				(width 0)
				(type default)
			)
			(fill yes)
			(layer "F.Fab")
		)
		(pad "1" thru_hole circle
			(at 0 0 270)
			(size 1.0033 1.0033)
			(drill 0.249936)
			(layers "*.Cu" "*.Mask")
			(remove_unused_layers no)
			(net "TDR_DIFF_100_IN3_DP")
			(clearance 0.10795)
			(thermal_gap 0.10795)
			(padstack
				(mode front_inner_back)
				(layer "Inner"
					(shape circle)
					(size 0.8001 0.8001)
					(clearance 0.1524)
				)
				(layer "B.Cu"
					(shape circle)
					(size 1.0033 1.0033)
					(clearance 0.10795)
				)
			)
		)
		(pad "2" thru_hole circle
			(at 2.54 0 270)
			(size 1.9939 1.9939)
			(drill 0.249936)
			(layers "*.Cu" "*.Mask")
			(remove_unused_layers no)
			(net "T1_GND")
			(clearance 0.10795)
			(thermal_gap 0.10795)
			(padstack
				(mode front_inner_back)
				(layer "Inner"
					(shape circle)
					(size 0.8001 0.8001)
					(clearance 0.1524)
				)
				(layer "B.Cu"
					(shape circle)
					(size 1.9939 1.9939)
					(clearance 0.10795)
				)
			)
		)
		(pad "3" thru_hole circle
			(at 2.54 2.54 270)
			(size 1.9939 1.9939)
			(drill 0.249936)
			(layers "*.Cu" "*.Mask")
			(remove_unused_layers no)
			(net "T1_GND")
			(clearance 0.10795)
			(thermal_gap 0.10795)
			(padstack
				(mode front_inner_back)
				(layer "Inner"
					(shape circle)
					(size 0.8001 0.8001)
					(clearance 0.1524)
				)
				(layer "B.Cu"
					(shape circle)
					(size 1.9939 1.9939)
					(clearance 0.10795)
				)
			)
		)
		(pad "4" thru_hole circle
			(at 0 2.54 270)
			(size 1.0033 1.0033)
			(drill 0.249936)
			(layers "*.Cu" "*.Mask")
			(remove_unused_layers no)
			(net "TDR_DIFF_100_IN3_DN")
			(clearance 0.10795)
			(thermal_gap 0.10795)
			(padstack
				(mode front_inner_back)
				(layer "Inner"
					(shape circle)
					(size 0.8001 0.8001)
					(clearance 0.1524)
				)
				(layer "B.Cu"
					(shape circle)
					(size 1.0033 1.0033)
					(clearance 0.10795)
				)
			)
		)
	)
	(footprint ""
		(layer "F.Cu")
		(at 73.475596 -74.901552 -90)
		(property "Reference" "R3088"
			(at 0 0 270)
			(layer "F.SilkS")
			(hide yes)
			(effects
				(font
					(size 1.27 1.27)
				)
			)
		)
		(property "Value" ""
			(at 0 0 270)
			(layer "F.Fab")
			(effects
				(font
					(size 1.27 1.27)
				)
			)
		)
		(duplicate_pad_numbers_are_jumpers no)
		(fp_line
			(start -0.7874 0.4064)
			(end -0.7874 -0.4064)
			(stroke
				(width 0.1524)
				(type default)
			)
			(layer "F.SilkS")
		)
		(fp_line
			(start 0.7874 0.4064)
			(end -0.7874 0.4064)
			(stroke
				(width 0.1524)
				(type default)
			)
			(layer "F.SilkS")
		)
		(fp_line
			(start -0.7874 -0.4064)
			(end 0.7874 -0.4064)
			(stroke
				(width 0.1524)
				(type default)
			)
			(layer "F.SilkS")
		)
		(fp_line
			(start 0.7874 -0.4064)
			(end 0.7874 0.4064)
			(stroke
				(width 0.1524)
				(type default)
			)
			(layer "F.SilkS")
		)
		(fp_line
			(start -0.67945 0.3048)
			(end -0.67945 -0.305054)
			(stroke
				(width 0.1)
				(type default)
			)
			(layer "F.Fab")
		)
		(fp_line
			(start -0.12065 0.3048)
			(end -0.67945 0.3048)
			(stroke
				(width 0.1)
				(type default)
			)
			(layer "F.Fab")
		)
		(fp_line
			(start 0.120396 0.3048)
			(end 0.120396 0.2794)
			(stroke
				(width 0.1)
				(type default)
			)
			(layer "F.Fab")
		)
		(fp_line
			(start 0.67945 0.3048)
			(end 0.120396 0.3048)
			(stroke
				(width 0.1)
				(type default)
			)
			(layer "F.Fab")
		)
		(fp_line
			(start -0.12065 0.2794)
			(end -0.12065 0.3048)
			(stroke
				(width 0.1)
				(type default)
			)
			(layer "F.Fab")
		)
		(fp_line
			(start 0.120396 0.2794)
			(end -0.12065 0.2794)
			(stroke
				(width 0.1)
				(type default)
			)
			(layer "F.Fab")
		)
		(fp_line
			(start -0.12065 -0.2794)
			(end 0.12065 -0.2794)
			(stroke
				(width 0.1)
				(type default)
			)
			(layer "F.Fab")
		)
		(fp_line
			(start 0.12065 -0.2794)
			(end 0.12065 -0.3048)
			(stroke
				(width 0.1)
				(type default)
			)
			(layer "F.Fab")
		)
		(fp_line
			(start 0.12065 -0.3048)
			(end 0.67945 -0.3048)
			(stroke
				(width 0.1)
				(type default)
			)
			(layer "F.Fab")
		)
		(fp_line
			(start 0.67945 -0.3048)
			(end 0.67945 0.3048)
			(stroke
				(width 0.1)
				(type default)
			)
			(layer "F.Fab")
		)
		(fp_line
			(start -0.67945 -0.305054)
			(end -0.12065 -0.305054)
			(stroke
				(width 0.1)
				(type default)
			)
			(layer "F.Fab")
		)
		(fp_line
			(start -0.12065 -0.305054)
			(end -0.12065 -0.2794)
			(stroke
				(width 0.1)
				(type default)
			)
			(layer "F.Fab")
		)
		(pad "1" smd circle
			(at -0.40005 0 270)
			(size 0 0)
			(layers "F.Cu" "F.Mask" "F.Paste")
			(net "LED_PWRGD_PVCCFA_EHV_FIVRA_CPU0")
		)
		(pad "2" smd circle
			(at 0.40005 0 270)
			(size 0 0)
			(layers "F.Cu" "F.Mask" "F.Paste")
			(net "P3V3_AUX")
		)
	)
	(footprint ""
		(layer "F.Cu")
		(at 51.593496 -106.74477)
		(property "Reference" "R3730"
			(at 0 0 0)
			(layer "F.SilkS")
			(hide yes)
			(effects
				(font
					(size 1.27 1.27)
				)
			)
		)
		(property "Value" ""
			(at 0 0 0)
			(layer "F.Fab")
			(effects
				(font
					(size 1.27 1.27)
				)
			)
		)
		(duplicate_pad_numbers_are_jumpers no)
		(fp_line
			(start -0.7874 -0.4064)
			(end 0.7874 -0.4064)
			(stroke
				(width 0.1524)
				(type default)
			)
			(layer "F.SilkS")
		)
		(fp_line
			(start -0.7874 0.4064)
			(end -0.7874 -0.4064)
			(stroke
				(width 0.1524)
				(type default)
			)
			(layer "F.SilkS")
		)
		(fp_line
			(start 0.7874 -0.4064)
			(end 0.7874 0.4064)
			(stroke
				(width 0.1524)
				(type default)
			)
			(layer "F.SilkS")
		)
		(fp_line
			(start 0.7874 0.4064)
			(end -0.7874 0.4064)
			(stroke
				(width 0.1524)
				(type default)
			)
			(layer "F.SilkS")
		)
		(fp_line
			(start -0.67945 -0.305054)
			(end -0.12065 -0.305054)
			(stroke
				(width 0.1)
				(type default)
			)
			(layer "F.Fab")
		)
		(fp_line
			(start -0.67945 0.3048)
			(end -0.67945 -0.305054)
			(stroke
				(width 0.1)
				(type default)
			)
			(layer "F.Fab")
		)
		(fp_line
			(start -0.12065 -0.305054)
			(end -0.12065 -0.2794)
			(stroke
				(width 0.1)
				(type default)
			)
			(layer "F.Fab")
		)
		(fp_line
			(start -0.12065 -0.2794)
			(end 0.12065 -0.2794)
			(stroke
				(width 0.1)
				(type default)
			)
			(layer "F.Fab")
		)
		(fp_line
			(start -0.12065 0.2794)
			(end -0.12065 0.3048)
			(stroke
				(width 0.1)
				(type default)
			)
			(layer "F.Fab")
		)
		(fp_line
			(start -0.12065 0.3048)
			(end -0.67945 0.3048)
			(stroke
				(width 0.1)
				(type default)
			)
			(layer "F.Fab")
		)
		(fp_line
			(start 0.120396 0.2794)
			(end -0.12065 0.2794)
			(stroke
				(width 0.1)
				(type default)
			)
			(layer "F.Fab")
		)
		(fp_line
			(start 0.120396 0.3048)
			(end 0.120396 0.2794)
			(stroke
				(width 0.1)
				(type default)
			)
			(layer "F.Fab")
		)
		(fp_line
			(start 0.12065 -0.3048)
			(end 0.67945 -0.3048)
			(stroke
				(width 0.1)
				(type default)
			)
			(layer "F.Fab")
		)
		(fp_line
			(start 0.12065 -0.2794)
			(end 0.12065 -0.3048)
			(stroke
				(width 0.1)
				(type default)
			)
			(layer "F.Fab")
		)
		(fp_line
			(start 0.67945 -0.3048)
			(end 0.67945 0.3048)
			(stroke
				(width 0.1)
				(type default)
			)
			(layer "F.Fab")
		)
		(fp_line
			(start 0.67945 0.3048)
			(end 0.120396 0.3048)
			(stroke
				(width 0.1)
				(type default)
			)
			(layer "F.Fab")
		)
		(pad "1" smd circle
			(at -0.40005 0)
			(size 0 0)
			(layers "F.Cu" "F.Mask" "F.Paste")
			(net "P3V3_AUX")
		)
		(pad "2" smd circle
			(at 0.40005 0)
			(size 0 0)
			(layers "F.Cu" "F.Mask" "F.Paste")
			(net "SMB_LM75_2_3V3AUX_SDA")
		)
	)
	(footprint ""
		(layer "F.Cu")
		(at 131.466844 -134.104126 180)
		(property "Reference" "R3395"
			(at 0 0 180)
			(layer "F.SilkS")
			(hide yes)
			(effects
				(font
					(size 1.27 1.27)
				)
			)
		)
		(property "Value" ""
			(at 0 0 180)
			(layer "F.Fab")
			(effects
				(font
					(size 1.27 1.27)
				)
			)
		)
		(duplicate_pad_numbers_are_jumpers no)
		(fp_line
			(start 0.7874 0.4064)
			(end -0.7874 0.4064)
			(stroke
				(width 0.1524)
				(type default)
			)
			(layer "F.SilkS")
		)
		(fp_line
			(start 0.7874 -0.4064)
			(end 0.7874 0.4064)
			(stroke
				(width 0.1524)
				(type default)
			)
			(layer "F.SilkS")
		)
		(fp_line
			(start -0.7874 0.4064)
			(end -0.7874 -0.4064)
			(stroke
				(width 0.1524)
				(type default)
			)
			(layer "F.SilkS")
		)
		(fp_line
			(start -0.7874 -0.4064)
			(end 0.7874 -0.4064)
			(stroke
				(width 0.1524)
				(type default)
			)
			(layer "F.SilkS")
		)
		(fp_line
			(start 0.67945 0.3048)
			(end 0.120396 0.3048)
			(stroke
				(width 0.1)
				(type default)
			)
			(layer "F.Fab")
		)
		(fp_line
			(start 0.67945 -0.3048)
			(end 0.67945 0.3048)
			(stroke
				(width 0.1)
				(type default)
			)
			(layer "F.Fab")
		)
		(fp_line
			(start 0.12065 -0.2794)
			(end 0.12065 -0.3048)
			(stroke
				(width 0.1)
				(type default)
			)
			(layer "F.Fab")
		)
		(fp_line
			(start 0.12065 -0.3048)
			(end 0.67945 -0.3048)
			(stroke
				(width 0.1)
				(type default)
			)
			(layer "F.Fab")
		)
		(fp_line
			(start 0.120396 0.3048)
			(end 0.120396 0.2794)
			(stroke
				(width 0.1)
				(type default)
			)
			(layer "F.Fab")
		)
		(fp_line
			(start 0.120396 0.2794)
			(end -0.12065 0.2794)
			(stroke
				(width 0.1)
				(type default)
			)
			(layer "F.Fab")
		)
		(fp_line
			(start -0.12065 0.3048)
			(end -0.67945 0.3048)
			(stroke
				(width 0.1)
				(type default)
			)
			(layer "F.Fab")
		)
		(fp_line
			(start -0.12065 0.2794)
			(end -0.12065 0.3048)
			(stroke
				(width 0.1)
				(type default)
			)
			(layer "F.Fab")
		)
		(fp_line
			(start -0.12065 -0.2794)
			(end 0.12065 -0.2794)
			(stroke
				(width 0.1)
				(type default)
			)
			(layer "F.Fab")
		)
		(fp_line
			(start -0.12065 -0.305054)
			(end -0.12065 -0.2794)
			(stroke
				(width 0.1)
				(type default)
			)
			(layer "F.Fab")
		)
		(fp_line
			(start -0.67945 0.3048)
			(end -0.67945 -0.305054)
			(stroke
				(width 0.1)
				(type default)
			)
			(layer "F.Fab")
		)
		(fp_line
			(start -0.67945 -0.305054)
			(end -0.12065 -0.305054)
			(stroke
				(width 0.1)
				(type default)
			)
			(layer "F.Fab")
		)
		(pad "1" smd circle
			(at -0.40005 0 180)
			(size 0 0)
			(layers "F.Cu" "F.Mask" "F.Paste")
			(net "P3V3_AUX")
		)
		(pad "2" smd circle
			(at 0.40005 0 180)
			(size 0 0)
			(layers "F.Cu" "F.Mask" "F.Paste")
			(net "SMB_INA230_3V3AUX_SCL")
		)
	)
	(footprint ""
		(layer "F.Cu")
		(at 446.694814 -110.038134)
		(property "Reference" "R1129"
			(at 0 0 0)
			(layer "F.SilkS")
			(hide yes)
			(effects
				(font
					(size 1.27 1.27)
				)
			)
		)
		(property "Value" ""
			(at 0 0 0)
			(layer "F.Fab")
			(effects
				(font
					(size 1.27 1.27)
				)
			)
		)
		(duplicate_pad_numbers_are_jumpers no)
		(fp_line
			(start -0.7874 -0.4064)
			(end 0.7874 -0.4064)
			(stroke
				(width 0.1524)
				(type default)
			)
			(layer "F.SilkS")
		)
		(fp_line
			(start -0.7874 0.4064)
			(end -0.7874 -0.4064)
			(stroke
				(width 0.1524)
				(type default)
			)
			(layer "F.SilkS")
		)
		(fp_line
			(start 0.7874 -0.4064)
			(end 0.7874 0.4064)
			(stroke
				(width 0.1524)
				(type default)
			)
			(layer "F.SilkS")
		)
		(fp_line
			(start 0.7874 0.4064)
			(end -0.7874 0.4064)
			(stroke
				(width 0.1524)
				(type default)
			)
			(layer "F.SilkS")
		)
		(fp_line
			(start -0.67945 -0.305054)
			(end -0.12065 -0.305054)
			(stroke
				(width 0.1)
				(type default)
			)
			(layer "F.Fab")
		)
		(fp_line
			(start -0.67945 0.3048)
			(end -0.67945 -0.305054)
			(stroke
				(width 0.1)
				(type default)
			)
			(layer "F.Fab")
		)
		(fp_line
			(start -0.12065 -0.305054)
			(end -0.12065 -0.2794)
			(stroke
				(width 0.1)
				(type default)
			)
			(layer "F.Fab")
		)
		(fp_line
			(start -0.12065 -0.2794)
			(end 0.12065 -0.2794)
			(stroke
				(width 0.1)
				(type default)
			)
			(layer "F.Fab")
		)
		(fp_line
			(start -0.12065 0.2794)
			(end -0.12065 0.3048)
			(stroke
				(width 0.1)
				(type default)
			)
			(layer "F.Fab")
		)
		(fp_line
			(start -0.12065 0.3048)
			(end -0.67945 0.3048)
			(stroke
				(width 0.1)
				(type default)
			)
			(layer "F.Fab")
		)
		(fp_line
			(start 0.120396 0.2794)
			(end -0.12065 0.2794)
			(stroke
				(width 0.1)
				(type default)
			)
			(layer "F.Fab")
		)
		(fp_line
			(start 0.120396 0.3048)
			(end 0.120396 0.2794)
			(stroke
				(width 0.1)
				(type default)
			)
			(layer "F.Fab")
		)
		(fp_line
			(start 0.12065 -0.3048)
			(end 0.67945 -0.3048)
			(stroke
				(width 0.1)
				(type default)
			)
			(layer "F.Fab")
		)
		(fp_line
			(start 0.12065 -0.2794)
			(end 0.12065 -0.3048)
			(stroke
				(width 0.1)
				(type default)
			)
			(layer "F.Fab")
		)
		(fp_line
			(start 0.67945 -0.3048)
			(end 0.67945 0.3048)
			(stroke
				(width 0.1)
				(type default)
			)
			(layer "F.Fab")
		)
		(fp_line
			(start 0.67945 0.3048)
			(end 0.120396 0.3048)
			(stroke
				(width 0.1)
				(type default)
			)
			(layer "F.Fab")
		)
		(pad "1" smd circle
			(at -0.40005 0)
			(size 0 0)
			(layers "F.Cu" "F.Mask" "F.Paste")
			(net "P3V3_AUX")
		)
		(pad "2" smd circle
			(at 0.40005 0)
			(size 0 0)
			(layers "F.Cu" "F.Mask" "F.Paste")
			(net "HP_LVC3_OCP_V3_1_PRSNT2")
		)
	)
	(footprint ""
		(layer "F.Cu")
		(at 193.93408 -353.761548)
		(property "Reference" "R630"
			(at 0 0 0)
			(layer "F.SilkS")
			(hide yes)
			(effects
				(font
					(size 1.27 1.27)
				)
			)
		)
		(property "Value" ""
			(at 0 0 0)
			(layer "F.Fab")
			(effects
				(font
					(size 1.27 1.27)
				)
			)
		)
		(duplicate_pad_numbers_are_jumpers no)
		(fp_line
			(start -0.7874 -0.4064)
			(end 0.7874 -0.4064)
			(stroke
				(width 0.1524)
				(type default)
			)
			(layer "F.SilkS")
		)
		(fp_line
			(start -0.7874 0.4064)
			(end -0.7874 -0.4064)
			(stroke
				(width 0.1524)
				(type default)
			)
			(layer "F.SilkS")
		)
		(fp_line
			(start 0.7874 -0.4064)
			(end 0.7874 0.4064)
			(stroke
				(width 0.1524)
				(type default)
			)
			(layer "F.SilkS")
		)
		(fp_line
			(start 0.7874 0.4064)
			(end -0.7874 0.4064)
			(stroke
				(width 0.1524)
				(type default)
			)
			(layer "F.SilkS")
		)
		(fp_line
			(start -0.67945 -0.305054)
			(end -0.12065 -0.305054)
			(stroke
				(width 0.1)
				(type default)
			)
			(layer "F.Fab")
		)
		(fp_line
			(start -0.67945 0.3048)
			(end -0.67945 -0.305054)
			(stroke
				(width 0.1)
				(type default)
			)
			(layer "F.Fab")
		)
		(fp_line
			(start -0.12065 -0.305054)
			(end -0.12065 -0.2794)
			(stroke
				(width 0.1)
				(type default)
			)
			(layer "F.Fab")
		)
		(fp_line
			(start -0.12065 -0.2794)
			(end 0.12065 -0.2794)
			(stroke
				(width 0.1)
				(type default)
			)
			(layer "F.Fab")
		)
		(fp_line
			(start -0.12065 0.2794)
			(end -0.12065 0.3048)
			(stroke
				(width 0.1)
				(type default)
			)
			(layer "F.Fab")
		)
		(fp_line
			(start -0.12065 0.3048)
			(end -0.67945 0.3048)
			(stroke
				(width 0.1)
				(type default)
			)
			(layer "F.Fab")
		)
		(fp_line
			(start 0.120396 0.2794)
			(end -0.12065 0.2794)
			(stroke
				(width 0.1)
				(type default)
			)
			(layer "F.Fab")
		)
		(fp_line
			(start 0.120396 0.3048)
			(end 0.120396 0.2794)
			(stroke
				(width 0.1)
				(type default)
			)
			(layer "F.Fab")
		)
		(fp_line
			(start 0.12065 -0.3048)
			(end 0.67945 -0.3048)
			(stroke
				(width 0.1)
				(type default)
			)
			(layer "F.Fab")
		)
		(fp_line
			(start 0.12065 -0.2794)
			(end 0.12065 -0.3048)
			(stroke
				(width 0.1)
				(type default)
			)
			(layer "F.Fab")
		)
		(fp_line
			(start 0.67945 -0.3048)
			(end 0.67945 0.3048)
			(stroke
				(width 0.1)
				(type default)
			)
			(layer "F.Fab")
		)
		(fp_line
			(start 0.67945 0.3048)
			(end 0.120396 0.3048)
			(stroke
				(width 0.1)
				(type default)
			)
			(layer "F.Fab")
		)
		(pad "1" smd circle
			(at -0.40005 0)
			(size 0 0)
			(layers "F.Cu" "F.Mask" "F.Paste")
			(net "PU_PIROM_CPU1_ADDR0")
		)
		(pad "2" smd circle
			(at 0.40005 0)
			(size 0 0)
			(layers "F.Cu" "F.Mask" "F.Paste")
			(net "GND")
		)
	)
	(footprint ""
		(layer "F.Cu")
		(at 67.248278 -402.371052 -90)
		(property "Reference" "C723"
			(at 0 0 270)
			(layer "F.SilkS")
			(hide yes)
			(effects
				(font
					(size 1.27 1.27)
				)
			)
		)
		(property "Value" ""
			(at 0 0 270)
			(layer "F.Fab")
			(effects
				(font
					(size 1.27 1.27)
				)
			)
		)
		(duplicate_pad_numbers_are_jumpers no)
		(fp_line
			(start -0.299974 0.150114)
			(end -0.299974 -0.150114)
			(stroke
				(width 0.1)
				(type default)
			)
			(layer "F.Fab")
		)
		(fp_line
			(start 0.299974 0.150114)
			(end -0.299974 0.150114)
			(stroke
				(width 0.1)
				(type default)
			)
			(layer "F.Fab")
		)
		(fp_line
			(start -0.299974 -0.150114)
			(end 0.299974 -0.150114)
			(stroke
				(width 0.1)
				(type default)
			)
			(layer "F.Fab")
		)
		(fp_line
			(start 0.299974 -0.150114)
			(end 0.299974 0.150114)
			(stroke
				(width 0.1)
				(type default)
			)
			(layer "F.Fab")
		)
		(pad "1" smd rect
			(at -0.2667 0 270)
			(size 0.3048 0.381)
			(layers "F.Cu" "F.Mask" "F.Paste")
			(net "P5E_CPU1_PE0_TX_C_DP<9>")
		)
		(pad "2" smd rect
			(at 0.2667 0 270)
			(size 0.3048 0.381)
			(layers "F.Cu" "F.Mask" "F.Paste")
			(net "P5E_CPU1_PE0_TX_DP<9>")
		)
	)
	(footprint ""
		(layer "F.Cu")
		(at 403.987 -50.637948 180)
		(property "Reference" "R4503"
			(at 0 0 180)
			(layer "F.SilkS")
			(hide yes)
			(effects
				(font
					(size 1.27 1.27)
				)
			)
		)
		(property "Value" ""
			(at 0 0 180)
			(layer "F.Fab")
			(effects
				(font
					(size 1.27 1.27)
				)
			)
		)
		(duplicate_pad_numbers_are_jumpers no)
		(fp_line
			(start 0.7874 0.4064)
			(end -0.7874 0.4064)
			(stroke
				(width 0.1524)
				(type default)
			)
			(layer "F.SilkS")
		)
		(fp_line
			(start 0.7874 -0.4064)
			(end 0.7874 0.4064)
			(stroke
				(width 0.1524)
				(type default)
			)
			(layer "F.SilkS")
		)
		(fp_line
			(start -0.7874 0.4064)
			(end -0.7874 -0.4064)
			(stroke
				(width 0.1524)
				(type default)
			)
			(layer "F.SilkS")
		)
		(fp_line
			(start -0.7874 -0.4064)
			(end 0.7874 -0.4064)
			(stroke
				(width 0.1524)
				(type default)
			)
			(layer "F.SilkS")
		)
		(fp_line
			(start 0.67945 0.3048)
			(end 0.120396 0.3048)
			(stroke
				(width 0.1)
				(type default)
			)
			(layer "F.Fab")
		)
		(fp_line
			(start 0.67945 -0.3048)
			(end 0.67945 0.3048)
			(stroke
				(width 0.1)
				(type default)
			)
			(layer "F.Fab")
		)
		(fp_line
			(start 0.12065 -0.2794)
			(end 0.12065 -0.3048)
			(stroke
				(width 0.1)
				(type default)
			)
			(layer "F.Fab")
		)
		(fp_line
			(start 0.12065 -0.3048)
			(end 0.67945 -0.3048)
			(stroke
				(width 0.1)
				(type default)
			)
			(layer "F.Fab")
		)
		(fp_line
			(start 0.120396 0.3048)
			(end 0.120396 0.2794)
			(stroke
				(width 0.1)
				(type default)
			)
			(layer "F.Fab")
		)
		(fp_line
			(start 0.120396 0.2794)
			(end -0.12065 0.2794)
			(stroke
				(width 0.1)
				(type default)
			)
			(layer "F.Fab")
		)
		(fp_line
			(start -0.12065 0.3048)
			(end -0.67945 0.3048)
			(stroke
				(width 0.1)
				(type default)
			)
			(layer "F.Fab")
		)
		(fp_line
			(start -0.12065 0.2794)
			(end -0.12065 0.3048)
			(stroke
				(width 0.1)
				(type default)
			)
			(layer "F.Fab")
		)
		(fp_line
			(start -0.12065 -0.2794)
			(end 0.12065 -0.2794)
			(stroke
				(width 0.1)
				(type default)
			)
			(layer "F.Fab")
		)
		(fp_line
			(start -0.12065 -0.305054)
			(end -0.12065 -0.2794)
			(stroke
				(width 0.1)
				(type default)
			)
			(layer "F.Fab")
		)
		(fp_line
			(start -0.67945 0.3048)
			(end -0.67945 -0.305054)
			(stroke
				(width 0.1)
				(type default)
			)
			(layer "F.Fab")
		)
		(fp_line
			(start -0.67945 -0.305054)
			(end -0.12065 -0.305054)
			(stroke
				(width 0.1)
				(type default)
			)
			(layer "F.Fab")
		)
		(pad "1" smd circle
			(at -0.40005 0 180)
			(size 0 0)
			(layers "F.Cu" "F.Mask" "F.Paste")
			(net "SMB_HOST_3V3AUX_SDA_R4")
		)
		(pad "2" smd circle
			(at 0.40005 0 180)
			(size 0 0)
			(layers "F.Cu" "F.Mask" "F.Paste")
			(net "SMB_HOST_3V3AUX_XDP_R_SDA")
		)
	)
	(footprint ""
		(layer "F.Cu")
		(at 54.96433 -16.099536 90)
		(property "Reference" "C835"
			(at 0 0 90)
			(layer "F.SilkS")
			(hide yes)
			(effects
				(font
					(size 1.27 1.27)
				)
			)
		)
		(property "Value" ""
			(at 0 0 90)
			(layer "F.Fab")
			(effects
				(font
					(size 1.27 1.27)
				)
			)
		)
		(duplicate_pad_numbers_are_jumpers no)
		(fp_line
			(start 0.299974 -0.150114)
			(end 0.299974 0.150114)
			(stroke
				(width 0.1)
				(type default)
			)
			(layer "F.Fab")
		)
		(fp_line
			(start -0.299974 -0.150114)
			(end 0.299974 -0.150114)
			(stroke
				(width 0.1)
				(type default)
			)
			(layer "F.Fab")
		)
		(fp_line
			(start 0.299974 0.150114)
			(end -0.299974 0.150114)
			(stroke
				(width 0.1)
				(type default)
			)
			(layer "F.Fab")
		)
		(fp_line
			(start -0.299974 0.150114)
			(end -0.299974 -0.150114)
			(stroke
				(width 0.1)
				(type default)
			)
			(layer "F.Fab")
		)
		(pad "1" smd rect
			(at -0.2667 0 90)
			(size 0.3048 0.381)
			(layers "F.Cu" "F.Mask" "F.Paste")
			(net "P5E_CPU1_PE1_TX_C_DP<1>")
		)
		(pad "2" smd rect
			(at 0.2667 0 90)
			(size 0.3048 0.381)
			(layers "F.Cu" "F.Mask" "F.Paste")
			(net "P5E_CPU1_PE1_TX_DP<1>")
		)
	)
	(footprint ""
		(layer "F.Cu")
		(at 47.90948 -258.091686)
		(property "Reference" "J20"
			(at -2.74066 -81.678272 0)
			(unlocked yes)
			(layer "F.SilkS")
			(effects
				(font
					(size 0.7874 0.5842)
					(thickness 0.1524)
				)
				(justify left)
			)
		)
		(property "Value" ""
			(at 0 0 0)
			(layer "F.Fab")
			(effects
				(font
					(size 1.27 1.27)
				)
			)
		)
		(duplicate_pad_numbers_are_jumpers no)
		(fp_line
			(start -3.24993 -81.000092)
			(end -3.24993 -80.683354)
			(stroke
				(width 0.1524)
				(type default)
			)
			(layer "F.SilkS")
		)
		(fp_line
			(start -3.24993 -76.040234)
			(end -3.24993 81.000092)
			(stroke
				(width 0.1524)
				(type default)
			)
			(layer "F.SilkS")
		)
		(fp_line
			(start -3.24993 81.000092)
			(end -1.80086 81.000092)
			(stroke
				(width 0.1524)
				(type default)
			)
			(layer "F.SilkS")
		)
		(fp_line
			(start -2.58318 -81.000092)
			(end -3.24993 -81.000092)
			(stroke
				(width 0.1524)
				(type default)
			)
			(layer "F.SilkS")
		)
		(fp_line
			(start 0.53594 81.000092)
			(end 3.24993 81.000092)
			(stroke
				(width 0.1524)
				(type default)
			)
			(layer "F.SilkS")
		)
		(fp_line
			(start 3.24993 -81.000092)
			(end 0.32258 -81.000092)
			(stroke
				(width 0.1524)
				(type default)
			)
			(layer "F.SilkS")
		)
		(fp_line
			(start 3.24993 -80.670654)
			(end 3.24993 -81.000092)
			(stroke
				(width 0.1524)
				(type default)
			)
			(layer "F.SilkS")
		)
		(fp_line
			(start 3.24993 -72.00011)
			(end -3.24993 -72.00011)
			(stroke
				(width 0.1524)
				(type default)
			)
			(layer "F.SilkS")
		)
		(fp_line
			(start 3.24993 72.00011)
			(end -3.24993 72.00011)
			(stroke
				(width 0.1524)
				(type default)
			)
			(layer "F.SilkS")
		)
		(fp_line
			(start 3.24993 81.000092)
			(end 3.24993 -75.577954)
			(stroke
				(width 0.1524)
				(type default)
			)
			(layer "F.SilkS")
		)
		(fp_poly
			(pts
				(xy -4.214114 -63.771526) (xy -3.320288 -63.324486) (xy -4.214114 -62.877446)
			)
			(stroke
				(width 0)
				(type default)
			)
			(fill yes)
			(layer "F.SilkS")
		)
		(fp_line
			(start -3.24993 -81.000092)
			(end -3.24993 81.000092)
			(stroke
				(width 0.1)
				(type default)
			)
			(layer "F.Fab")
		)
		(fp_line
			(start -3.24993 81.000092)
			(end 3.24993 81.000092)
			(stroke
				(width 0.1)
				(type default)
			)
			(layer "F.Fab")
		)
		(fp_line
			(start 3.24993 -81.000092)
			(end -3.24993 -81.000092)
			(stroke
				(width 0.1)
				(type default)
			)
			(layer "F.Fab")
		)
		(fp_line
			(start 3.24993 -72.00011)
			(end -3.24993 -72.00011)
			(stroke
				(width 0.1)
				(type default)
			)
			(layer "F.Fab")
		)
		(fp_line
			(start 3.24993 -71.000112)
			(end -3.24993 -71.000112)
			(stroke
				(width 0.1)
				(type default)
			)
			(layer "F.Fab")
		)
		(fp_line
			(start 3.24993 71.000112)
			(end -3.24993 71.000112)
			(stroke
				(width 0.1)
				(type default)
			)
			(layer "F.Fab")
		)
		(fp_line
			(start 3.24993 72.00011)
			(end -3.24993 72.00011)
			(stroke
				(width 0.1)
				(type default)
			)
			(layer "F.Fab")
		)
		(fp_line
			(start 3.24993 81.000092)
			(end 3.24993 -81.000092)
			(stroke
				(width 0.1)
				(type default)
			)
			(layer "F.Fab")
		)
		(fp_poly
			(pts
				(xy -4.445 -63.832994) (xy -4.445 -62.816994) (xy -3.429 -63.324994)
			)
			(stroke
				(width 0)
				(type default)
			)
			(fill yes)
			(layer "F.Fab")
		)
		(pad "1" smd rect
			(at -2.050034 -63.324994 270)
			(size 0.519938 1.4986)
			(layers "F.Cu" "F.Mask" "F.Paste")
			(net "P12V_S3_AUX_CPU1_NVDIMM")
		)
		(pad "2" smd rect
			(at -2.050034 -62.47511 270)
			(size 0.519938 1.4986)
			(layers "F.Cu" "F.Mask" "F.Paste")
			(net "TP_CHB_CPU1_DIMM2_FRU_0")
		)
		(pad "3" smd rect
			(at -2.050034 -61.624972 270)
			(size 0.519938 1.4986)
			(layers "F.Cu" "F.Mask" "F.Paste")
			(net "P3V3_AUX")
		)
		(pad "4" smd rect
			(at -2.050034 -60.775088 270)
			(size 0.519938 1.4986)
			(layers "F.Cu" "F.Mask" "F.Paste")
			(net "I3C_SPD_DDRABCD_CPU1_LVC1_SCL_3")
		)
		(pad "5" smd rect
			(at -2.050034 -59.92495 270)
			(size 0.519938 1.4986)
			(layers "F.Cu" "F.Mask" "F.Paste")
			(net "I3C_SPD_DDRABCD_CPU1_LVC1_SDA")
		)
		(pad "6" smd rect
			(at -2.050034 -59.075066 270)
			(size 0.519938 1.4986)
			(layers "F.Cu" "F.Mask" "F.Paste")
			(net "GND")
		)
		(pad "7" smd rect
			(at -2.050034 -58.224928 270)
			(size 0.519938 1.4986)
			(layers "F.Cu" "F.Mask" "F.Paste")
			(net "M_B_CPU1_SA_DQ<0>")
		)
		(pad "8" smd rect
			(at -2.050034 -57.375044 270)
			(size 0.519938 1.4986)
			(layers "F.Cu" "F.Mask" "F.Paste")
			(net "GND")
		)
		(pad "9" smd rect
			(at -2.050034 -56.524906 270)
			(size 0.519938 1.4986)
			(layers "F.Cu" "F.Mask" "F.Paste")
			(net "M_B_CPU1_SA_DQ<1>")
		)
		(pad "10" smd rect
			(at -2.050034 -55.675022 270)
			(size 0.519938 1.4986)
			(layers "F.Cu" "F.Mask" "F.Paste")
			(net "GND")
		)
		(pad "11" smd rect
			(at -2.050034 -54.824884 270)
			(size 0.519938 1.4986)
			(layers "F.Cu" "F.Mask" "F.Paste")
			(net "M_B_CPU1_SA_DQS_DP<0>")
		)
		(pad "12" smd rect
			(at -2.050034 -53.975 270)
			(size 0.519938 1.4986)
			(layers "F.Cu" "F.Mask" "F.Paste")
			(net "M_B_CPU1_SA_DQS_DN<0>")
		)
		(pad "13" smd rect
			(at -2.050034 -53.125116 270)
			(size 0.519938 1.4986)
			(layers "F.Cu" "F.Mask" "F.Paste")
			(net "GND")
		)
		(pad "14" smd rect
			(at -2.050034 -52.274978 270)
			(size 0.519938 1.4986)
			(layers "F.Cu" "F.Mask" "F.Paste")
			(net "M_B_CPU1_SA_DQ<4>")
		)
		(pad "15" smd rect
			(at -2.050034 -51.425094 270)
			(size 0.519938 1.4986)
			(layers "F.Cu" "F.Mask" "F.Paste")
			(net "GND")
		)
		(pad "16" smd rect
			(at -2.050034 -50.574956 270)
			(size 0.519938 1.4986)
			(layers "F.Cu" "F.Mask" "F.Paste")
			(net "M_B_CPU1_SA_DQ<5>")
		)
		(pad "17" smd rect
			(at -2.050034 -49.725072 270)
			(size 0.519938 1.4986)
			(layers "F.Cu" "F.Mask" "F.Paste")
			(net "GND")
		)
		(pad "18" smd rect
			(at -2.050034 -48.874934 270)
			(size 0.519938 1.4986)
			(layers "F.Cu" "F.Mask" "F.Paste")
			(net "M_B_CPU1_SA_DQ<8>")
		)
		(pad "19" smd rect
			(at -2.050034 -48.02505 270)
			(size 0.519938 1.4986)
			(layers "F.Cu" "F.Mask" "F.Paste")
			(net "GND")
		)
		(pad "20" smd rect
			(at -2.050034 -47.174912 270)
			(size 0.519938 1.4986)
			(layers "F.Cu" "F.Mask" "F.Paste")
			(net "M_B_CPU1_SA_DQ<9>")
		)
		(pad "21" smd rect
			(at -2.050034 -46.325028 270)
			(size 0.519938 1.4986)
			(layers "F.Cu" "F.Mask" "F.Paste")
			(net "GND")
		)
		(pad "22" smd rect
			(at -2.050034 -45.47489 270)
			(size 0.519938 1.4986)
			(layers "F.Cu" "F.Mask" "F.Paste")
			(net "M_B_CPU1_SA_DQS_DP<1>")
		)
		(pad "23" smd rect
			(at -2.050034 -44.625006 270)
			(size 0.519938 1.4986)
			(layers "F.Cu" "F.Mask" "F.Paste")
			(net "M_B_CPU1_SA_DQS_DN<1>")
		)
		(pad "24" smd rect
			(at -2.050034 -43.775122 270)
			(size 0.519938 1.4986)
			(layers "F.Cu" "F.Mask" "F.Paste")
			(net "GND")
		)
		(pad "25" smd rect
			(at -2.050034 -42.924984 270)
			(size 0.519938 1.4986)
			(layers "F.Cu" "F.Mask" "F.Paste")
			(net "M_B_CPU1_SA_DQ<12>")
		)
		(pad "26" smd rect
			(at -2.050034 -42.0751 270)
			(size 0.519938 1.4986)
			(layers "F.Cu" "F.Mask" "F.Paste")
			(net "GND")
		)
		(pad "27" smd rect
			(at -2.050034 -41.224962 270)
			(size 0.519938 1.4986)
			(layers "F.Cu" "F.Mask" "F.Paste")
			(net "M_B_CPU1_SA_DQ<13>")
		)
		(pad "28" smd rect
			(at -2.050034 -40.375078 270)
			(size 0.519938 1.4986)
			(layers "F.Cu" "F.Mask" "F.Paste")
			(net "GND")
		)
		(pad "29" smd rect
			(at -2.050034 -39.52494 270)
			(size 0.519938 1.4986)
			(layers "F.Cu" "F.Mask" "F.Paste")
			(net "M_B_CPU1_SA_DQ<16>")
		)
		(pad "30" smd rect
			(at -2.050034 -38.675056 270)
			(size 0.519938 1.4986)
			(layers "F.Cu" "F.Mask" "F.Paste")
			(net "GND")
		)
		(pad "31" smd rect
			(at -2.050034 -37.824918 270)
			(size 0.519938 1.4986)
			(layers "F.Cu" "F.Mask" "F.Paste")
			(net "M_B_CPU1_SA_DQ<17>")
		)
		(pad "32" smd rect
			(at -2.050034 -36.975034 270)
			(size 0.519938 1.4986)
			(layers "F.Cu" "F.Mask" "F.Paste")
			(net "GND")
		)
		(pad "33" smd rect
			(at -2.050034 -36.124896 270)
			(size 0.519938 1.4986)
			(layers "F.Cu" "F.Mask" "F.Paste")
			(net "M_B_CPU1_SA_DQS_DP<2>")
		)
		(pad "34" smd rect
			(at -2.050034 -35.275012 270)
			(size 0.519938 1.4986)
			(layers "F.Cu" "F.Mask" "F.Paste")
			(net "M_B_CPU1_SA_DQS_DN<2>")
		)
		(pad "35" smd rect
			(at -2.050034 -34.425128 270)
			(size 0.519938 1.4986)
			(layers "F.Cu" "F.Mask" "F.Paste")
			(net "GND")
		)
		(pad "36" smd rect
			(at -2.050034 -33.57499 270)
			(size 0.519938 1.4986)
			(layers "F.Cu" "F.Mask" "F.Paste")
			(net "M_B_CPU1_SA_DQ<20>")
		)
		(pad "37" smd rect
			(at -2.050034 -32.725106 270)
			(size 0.519938 1.4986)
			(layers "F.Cu" "F.Mask" "F.Paste")
			(net "GND")
		)
		(pad "38" smd rect
			(at -2.050034 -31.874968 270)
			(size 0.519938 1.4986)
			(layers "F.Cu" "F.Mask" "F.Paste")
			(net "M_B_CPU1_SA_DQ<21>")
		)
		(pad "39" smd rect
			(at -2.050034 -31.025084 270)
			(size 0.519938 1.4986)
			(layers "F.Cu" "F.Mask" "F.Paste")
			(net "GND")
		)
		(pad "40" smd rect
			(at -2.050034 -30.174946 270)
			(size 0.519938 1.4986)
			(layers "F.Cu" "F.Mask" "F.Paste")
			(net "M_B_CPU1_SA_DQ<24>")
		)
		(pad "41" smd rect
			(at -2.050034 -29.325062 270)
			(size 0.519938 1.4986)
			(layers "F.Cu" "F.Mask" "F.Paste")
			(net "GND")
		)
		(pad "42" smd rect
			(at -2.050034 -28.474924 270)
			(size 0.519938 1.4986)
			(layers "F.Cu" "F.Mask" "F.Paste")
			(net "M_B_CPU1_SA_DQ<25>")
		)
		(pad "43" smd rect
			(at -2.050034 -27.62504 270)
			(size 0.519938 1.4986)
			(layers "F.Cu" "F.Mask" "F.Paste")
			(net "GND")
		)
		(pad "44" smd rect
			(at -2.050034 -26.774902 270)
			(size 0.519938 1.4986)
			(layers "F.Cu" "F.Mask" "F.Paste")
			(net "M_B_CPU1_SA_DQS_DP<3>")
		)
		(pad "45" smd rect
			(at -2.050034 -25.925018 270)
			(size 0.519938 1.4986)
			(layers "F.Cu" "F.Mask" "F.Paste")
			(net "M_B_CPU1_SA_DQS_DN<3>")
		)
		(pad "46" smd rect
			(at -2.050034 -25.07488 270)
			(size 0.519938 1.4986)
			(layers "F.Cu" "F.Mask" "F.Paste")
			(net "GND")
		)
		(pad "47" smd rect
			(at -2.050034 -24.224996 270)
			(size 0.519938 1.4986)
			(layers "F.Cu" "F.Mask" "F.Paste")
			(net "M_B_CPU1_SA_DQ<28>")
		)
		(pad "48" smd rect
			(at -2.050034 -23.375112 270)
			(size 0.519938 1.4986)
			(layers "F.Cu" "F.Mask" "F.Paste")
			(net "GND")
		)
		(pad "49" smd rect
			(at -2.050034 -22.524974 270)
			(size 0.519938 1.4986)
			(layers "F.Cu" "F.Mask" "F.Paste")
			(net "M_B_CPU1_SA_DQ<29>")
		)
		(pad "50" smd rect
			(at -2.050034 -21.67509 270)
			(size 0.519938 1.4986)
			(layers "F.Cu" "F.Mask" "F.Paste")
			(net "GND")
		)
		(pad "51" smd rect
			(at -2.050034 -20.824952 270)
			(size 0.519938 1.4986)
			(layers "F.Cu" "F.Mask" "F.Paste")
			(net "M_B_CPU1_SA_CB<0>")
		)
		(pad "52" smd rect
			(at -2.050034 -19.975068 270)
			(size 0.519938 1.4986)
			(layers "F.Cu" "F.Mask" "F.Paste")
			(net "GND")
		)
		(pad "53" smd rect
			(at -2.050034 -19.12493 270)
			(size 0.519938 1.4986)
			(layers "F.Cu" "F.Mask" "F.Paste")
			(net "M_B_CPU1_SA_CB<1>")
		)
		(pad "54" smd rect
			(at -2.050034 -18.275046 270)
			(size 0.519938 1.4986)
			(layers "F.Cu" "F.Mask" "F.Paste")
			(net "GND")
		)
		(pad "55" smd rect
			(at -2.050034 -17.424908 270)
			(size 0.519938 1.4986)
			(layers "F.Cu" "F.Mask" "F.Paste")
			(net "M_B_CPU1_SA_DQS_DP<4>")
		)
		(pad "56" smd rect
			(at -2.050034 -16.575024 270)
			(size 0.519938 1.4986)
			(layers "F.Cu" "F.Mask" "F.Paste")
			(net "M_B_CPU1_SA_DQS_DN<4>")
		)
		(pad "57" smd rect
			(at -2.050034 -15.724886 270)
			(size 0.519938 1.4986)
			(layers "F.Cu" "F.Mask" "F.Paste")
			(net "GND")
		)
		(pad "58" smd rect
			(at -2.050034 -14.875002 270)
			(size 0.519938 1.4986)
			(layers "F.Cu" "F.Mask" "F.Paste")
			(net "M_B_CPU1_SA_CB<4>")
		)
		(pad "59" smd rect
			(at -2.050034 -14.025118 270)
			(size 0.519938 1.4986)
			(layers "F.Cu" "F.Mask" "F.Paste")
			(net "GND")
		)
		(pad "60" smd rect
			(at -2.050034 -13.17498 270)
			(size 0.519938 1.4986)
			(layers "F.Cu" "F.Mask" "F.Paste")
			(net "M_B_CPU1_SA_CB<5>")
		)
		(pad "61" smd rect
			(at -2.050034 -12.325096 270)
			(size 0.519938 1.4986)
			(layers "F.Cu" "F.Mask" "F.Paste")
			(net "GND")
		)
		(pad "62" smd rect
			(at -2.050034 -11.474958 270)
			(size 0.519938 1.4986)
			(layers "F.Cu" "F.Mask" "F.Paste")
			(net "M_B_CPU1_ALERT_N")
		)
		(pad "63" smd rect
			(at -2.050034 -10.625074 270)
			(size 0.519938 1.4986)
			(layers "F.Cu" "F.Mask" "F.Paste")
			(net "GND")
		)
		(pad "64" smd rect
			(at -2.050034 -9.774936 270)
			(size 0.519938 1.4986)
			(layers "F.Cu" "F.Mask" "F.Paste")
			(net "M_B_CPU1_SA_CS_N<2>")
		)
		(pad "65" smd rect
			(at -2.050034 -8.925052 270)
			(size 0.519938 1.4986)
			(layers "F.Cu" "F.Mask" "F.Paste")
			(net "GND")
		)
		(pad "66" smd rect
			(at -2.050034 -8.074914 270)
			(size 0.519938 1.4986)
			(layers "F.Cu" "F.Mask" "F.Paste")
			(net "M_B_CPU1_SA_CA<0>")
		)
		(pad "67" smd rect
			(at -2.050034 -7.22503 270)
			(size 0.519938 1.4986)
			(layers "F.Cu" "F.Mask" "F.Paste")
			(net "GND")
		)
		(pad "68" smd rect
			(at -2.050034 -6.374892 270)
			(size 0.519938 1.4986)
			(layers "F.Cu" "F.Mask" "F.Paste")
			(net "M_B_CPU1_SA_CA<2>")
		)
		(pad "69" smd rect
			(at -2.050034 -5.525008 270)
			(size 0.519938 1.4986)
			(layers "F.Cu" "F.Mask" "F.Paste")
			(net "GND")
		)
		(pad "70" smd rect
			(at -2.050034 -4.675124 270)
			(size 0.519938 1.4986)
			(layers "F.Cu" "F.Mask" "F.Paste")
			(net "M_B_CPU1_SA_CA<4>")
		)
		(pad "71" smd rect
			(at -2.050034 -3.824986 270)
			(size 0.519938 1.4986)
			(layers "F.Cu" "F.Mask" "F.Paste")
			(net "GND")
		)
		(pad "72" smd rect
			(at -2.050034 -2.975102 270)
			(size 0.519938 1.4986)
			(layers "F.Cu" "F.Mask" "F.Paste")
			(net "M_B_CPU1_SA_CA<6>")
		)
		(pad "73" smd rect
			(at -2.050034 -2.124964 270)
			(size 0.519938 1.4986)
			(layers "F.Cu" "F.Mask" "F.Paste")
			(net "GND")
		)
		(pad "74" smd rect
			(at -2.050034 -1.27508 270)
			(size 0.519938 1.4986)
			(layers "F.Cu" "F.Mask" "F.Paste")
			(net "M_B_CPU1_SA_PAR")
		)
		(pad "75" smd rect
			(at -2.050034 -0.424942 270)
			(size 0.519938 1.4986)
			(layers "F.Cu" "F.Mask" "F.Paste")
			(net "GND")
		)
		(pad "76" smd rect
			(at -2.050034 5.525008 270)
			(size 0.519938 1.4986)
			(layers "F.Cu" "F.Mask" "F.Paste")
			(net "M_B_CPU1_SB_CA<0>")
		)
		(pad "77" smd rect
			(at -2.050034 6.374892 270)
			(size 0.519938 1.4986)
			(layers "F.Cu" "F.Mask" "F.Paste")
			(net "GND")
		)
		(pad "78" smd rect
			(at -2.050034 7.22503 270)
			(size 0.519938 1.4986)
			(layers "F.Cu" "F.Mask" "F.Paste")
			(net "M_B_CPU1_SB_CA<2>")
		)
		(pad "79" smd rect
			(at -2.050034 8.074914 270)
			(size 0.519938 1.4986)
			(layers "F.Cu" "F.Mask" "F.Paste")
			(net "GND")
		)
		(pad "80" smd rect
			(at -2.050034 8.925052 270)
			(size 0.519938 1.4986)
			(layers "F.Cu" "F.Mask" "F.Paste")
			(net "M_B_CPU1_SB_CA<4>")
		)
		(pad "81" smd rect
			(at -2.050034 9.774936 270)
			(size 0.519938 1.4986)
			(layers "F.Cu" "F.Mask" "F.Paste")
			(net "GND")
		)
		(pad "82" smd rect
			(at -2.050034 10.625074 270)
			(size 0.519938 1.4986)
			(layers "F.Cu" "F.Mask" "F.Paste")
			(net "M_B_CPU1_SB_CA<6>")
		)
		(pad "83" smd rect
			(at -2.050034 11.474958 270)
			(size 0.519938 1.4986)
			(layers "F.Cu" "F.Mask" "F.Paste")
			(net "GND")
		)
		(pad "84" smd rect
			(at -2.050034 12.325096 270)
			(size 0.519938 1.4986)
			(layers "F.Cu" "F.Mask" "F.Paste")
			(net "M_B_CPU1_SB_CS_N<2>")
		)
		(pad "85" smd rect
			(at -2.050034 13.17498 270)
			(size 0.519938 1.4986)
			(layers "F.Cu" "F.Mask" "F.Paste")
			(net "GND")
		)
		(pad "86" smd rect
			(at -2.050034 14.025118 270)
			(size 0.519938 1.4986)
			(layers "F.Cu" "F.Mask" "F.Paste")
			(net "M_B_CPU1_SA_RSP<1>")
		)
		(pad "87" smd rect
			(at -2.050034 14.875002 270)
			(size 0.519938 1.4986)
			(layers "F.Cu" "F.Mask" "F.Paste")
			(net "M_B_CPU1_SB_RSP<1>")
		)
		(pad "88" smd rect
			(at -2.050034 15.724886 270)
			(size 0.519938 1.4986)
			(layers "F.Cu" "F.Mask" "F.Paste")
			(net "GND")
		)
		(pad "89" smd rect
			(at -2.050034 16.575024 270)
			(size 0.519938 1.4986)
			(layers "F.Cu" "F.Mask" "F.Paste")
			(net "M_B_CPU1_SB_CB<4>")
		)
		(pad "90" smd rect
			(at -2.050034 17.424908 270)
			(size 0.519938 1.4986)
			(layers "F.Cu" "F.Mask" "F.Paste")
			(net "GND")
		)
		(pad "91" smd rect
			(at -2.050034 18.275046 270)
			(size 0.519938 1.4986)
			(layers "F.Cu" "F.Mask" "F.Paste")
			(net "M_B_CPU1_SB_CB<5>")
		)
		(pad "92" smd rect
			(at -2.050034 19.12493 270)
			(size 0.519938 1.4986)
			(layers "F.Cu" "F.Mask" "F.Paste")
			(net "GND")
		)
		(pad "93" smd rect
			(at -2.050034 19.975068 270)
			(size 0.519938 1.4986)
			(layers "F.Cu" "F.Mask" "F.Paste")
			(net "M_B_CPU1_SB_DQS_DP<9>")
		)
		(pad "94" smd rect
			(at -2.050034 20.824952 270)
			(size 0.519938 1.4986)
			(layers "F.Cu" "F.Mask" "F.Paste")
			(net "M_B_CPU1_SB_DQS_DN<9>")
		)
		(pad "95" smd rect
			(at -2.050034 21.67509 270)
			(size 0.519938 1.4986)
			(layers "F.Cu" "F.Mask" "F.Paste")
			(net "GND")
		)
		(pad "96" smd rect
			(at -2.050034 22.524974 270)
			(size 0.519938 1.4986)
			(layers "F.Cu" "F.Mask" "F.Paste")
			(net "M_B_CPU1_SB_CB<0>")
		)
		(pad "97" smd rect
			(at -2.050034 23.375112 270)
			(size 0.519938 1.4986)
			(layers "F.Cu" "F.Mask" "F.Paste")
			(net "GND")
		)
		(pad "98" smd rect
			(at -2.050034 24.224996 270)
			(size 0.519938 1.4986)
			(layers "F.Cu" "F.Mask" "F.Paste")
			(net "M_B_CPU1_SB_CB<1>")
		)
		(pad "99" smd rect
			(at -2.050034 25.07488 270)
			(size 0.519938 1.4986)
			(layers "F.Cu" "F.Mask" "F.Paste")
			(net "GND")
		)
		(pad "100" smd rect
			(at -2.050034 25.925018 270)
			(size 0.519938 1.4986)
			(layers "F.Cu" "F.Mask" "F.Paste")
			(net "M_B_CPU1_SB_DQ<0>")
		)
		(pad "101" smd rect
			(at -2.050034 26.774902 270)
			(size 0.519938 1.4986)
			(layers "F.Cu" "F.Mask" "F.Paste")
			(net "GND")
		)
		(pad "102" smd rect
			(at -2.050034 27.62504 270)
			(size 0.519938 1.4986)
			(layers "F.Cu" "F.Mask" "F.Paste")
			(net "M_B_CPU1_SB_DQ<1>")
		)
		(pad "103" smd rect
			(at -2.050034 28.474924 270)
			(size 0.519938 1.4986)
			(layers "F.Cu" "F.Mask" "F.Paste")
			(net "GND")
		)
		(pad "104" smd rect
			(at -2.050034 29.325062 270)
			(size 0.519938 1.4986)
			(layers "F.Cu" "F.Mask" "F.Paste")
			(net "M_B_CPU1_SB_DQS_DP<0>")
		)
		(pad "105" smd rect
			(at -2.050034 30.174946 270)
			(size 0.519938 1.4986)
			(layers "F.Cu" "F.Mask" "F.Paste")
			(net "M_B_CPU1_SB_DQS_DN<0>")
		)
		(pad "106" smd rect
			(at -2.050034 31.025084 270)
			(size 0.519938 1.4986)
			(layers "F.Cu" "F.Mask" "F.Paste")
			(net "GND")
		)
		(pad "107" smd rect
			(at -2.050034 31.874968 270)
			(size 0.519938 1.4986)
			(layers "F.Cu" "F.Mask" "F.Paste")
			(net "M_B_CPU1_SB_DQ<4>")
		)
		(pad "108" smd rect
			(at -2.050034 32.725106 270)
			(size 0.519938 1.4986)
			(layers "F.Cu" "F.Mask" "F.Paste")
			(net "GND")
		)
		(pad "109" smd rect
			(at -2.050034 33.57499 270)
			(size 0.519938 1.4986)
			(layers "F.Cu" "F.Mask" "F.Paste")
			(net "M_B_CPU1_SB_DQ<5>")
		)
		(pad "110" smd rect
			(at -2.050034 34.425128 270)
			(size 0.519938 1.4986)
			(layers "F.Cu" "F.Mask" "F.Paste")
			(net "GND")
		)
		(pad "111" smd rect
			(at -2.050034 35.275012 270)
			(size 0.519938 1.4986)
			(layers "F.Cu" "F.Mask" "F.Paste")
			(net "M_B_CPU1_SB_DQ<8>")
		)
		(pad "112" smd rect
			(at -2.050034 36.124896 270)
			(size 0.519938 1.4986)
			(layers "F.Cu" "F.Mask" "F.Paste")
			(net "GND")
		)
		(pad "113" smd rect
			(at -2.050034 36.975034 270)
			(size 0.519938 1.4986)
			(layers "F.Cu" "F.Mask" "F.Paste")
			(net "M_B_CPU1_SB_DQ<9>")
		)
		(pad "114" smd rect
			(at -2.050034 37.824918 270)
			(size 0.519938 1.4986)
			(layers "F.Cu" "F.Mask" "F.Paste")
			(net "GND")
		)
		(pad "115" smd rect
			(at -2.050034 38.675056 270)
			(size 0.519938 1.4986)
			(layers "F.Cu" "F.Mask" "F.Paste")
			(net "M_B_CPU1_SB_DQS_DP<1>")
		)
		(pad "116" smd rect
			(at -2.050034 39.52494 270)
			(size 0.519938 1.4986)
			(layers "F.Cu" "F.Mask" "F.Paste")
			(net "M_B_CPU1_SB_DQS_DN<1>")
		)
		(pad "117" smd rect
			(at -2.050034 40.375078 270)
			(size 0.519938 1.4986)
			(layers "F.Cu" "F.Mask" "F.Paste")
			(net "GND")
		)
		(pad "118" smd rect
			(at -2.050034 41.224962 270)
			(size 0.519938 1.4986)
			(layers "F.Cu" "F.Mask" "F.Paste")
			(net "M_B_CPU1_SB_DQ<12>")
		)
		(pad "119" smd rect
			(at -2.050034 42.0751 270)
			(size 0.519938 1.4986)
			(layers "F.Cu" "F.Mask" "F.Paste")
			(net "GND")
		)
		(pad "120" smd rect
			(at -2.050034 42.924984 270)
			(size 0.519938 1.4986)
			(layers "F.Cu" "F.Mask" "F.Paste")
			(net "M_B_CPU1_SB_DQ<13>")
		)
		(pad "121" smd rect
			(at -2.050034 43.775122 270)
			(size 0.519938 1.4986)
			(layers "F.Cu" "F.Mask" "F.Paste")
			(net "GND")
		)
		(pad "122" smd rect
			(at -2.050034 44.625006 270)
			(size 0.519938 1.4986)
			(layers "F.Cu" "F.Mask" "F.Paste")
			(net "M_B_CPU1_SB_DQ<16>")
		)
		(pad "123" smd rect
			(at -2.050034 45.47489 270)
			(size 0.519938 1.4986)
			(layers "F.Cu" "F.Mask" "F.Paste")
			(net "GND")
		)
		(pad "124" smd rect
			(at -2.050034 46.325028 270)
			(size 0.519938 1.4986)
			(layers "F.Cu" "F.Mask" "F.Paste")
			(net "M_B_CPU1_SB_DQ<17>")
		)
		(pad "125" smd rect
			(at -2.050034 47.174912 270)
			(size 0.519938 1.4986)
			(layers "F.Cu" "F.Mask" "F.Paste")
			(net "GND")
		)
		(pad "126" smd rect
			(at -2.050034 48.02505 270)
			(size 0.519938 1.4986)
			(layers "F.Cu" "F.Mask" "F.Paste")
			(net "M_B_CPU1_SB_DQS_DP<2>")
		)
		(pad "127" smd rect
			(at -2.050034 48.874934 270)
			(size 0.519938 1.4986)
			(layers "F.Cu" "F.Mask" "F.Paste")
			(net "M_B_CPU1_SB_DQS_DN<2>")
		)
		(pad "128" smd rect
			(at -2.050034 49.725072 270)
			(size 0.519938 1.4986)
			(layers "F.Cu" "F.Mask" "F.Paste")
			(net "GND")
		)
		(pad "129" smd rect
			(at -2.050034 50.574956 270)
			(size 0.519938 1.4986)
			(layers "F.Cu" "F.Mask" "F.Paste")
			(net "M_B_CPU1_SB_DQ<20>")
		)
		(pad "130" smd rect
			(at -2.050034 51.425094 270)
			(size 0.519938 1.4986)
			(layers "F.Cu" "F.Mask" "F.Paste")
			(net "GND")
		)
		(pad "131" smd rect
			(at -2.050034 52.274978 270)
			(size 0.519938 1.4986)
			(layers "F.Cu" "F.Mask" "F.Paste")
			(net "M_B_CPU1_SB_DQ<21>")
		)
		(pad "132" smd rect
			(at -2.050034 53.125116 270)
			(size 0.519938 1.4986)
			(layers "F.Cu" "F.Mask" "F.Paste")
			(net "GND")
		)
		(pad "133" smd rect
			(at -2.050034 53.975 270)
			(size 0.519938 1.4986)
			(layers "F.Cu" "F.Mask" "F.Paste")
			(net "M_B_CPU1_SB_DQ<24>")
		)
		(pad "134" smd rect
			(at -2.050034 54.824884 270)
			(size 0.519938 1.4986)
			(layers "F.Cu" "F.Mask" "F.Paste")
			(net "GND")
		)
		(pad "135" smd rect
			(at -2.050034 55.675022 270)
			(size 0.519938 1.4986)
			(layers "F.Cu" "F.Mask" "F.Paste")
			(net "M_B_CPU1_SB_DQ<25>")
		)
		(pad "136" smd rect
			(at -2.050034 56.524906 270)
			(size 0.519938 1.4986)
			(layers "F.Cu" "F.Mask" "F.Paste")
			(net "GND")
		)
		(pad "137" smd rect
			(at -2.050034 57.375044 270)
			(size 0.519938 1.4986)
			(layers "F.Cu" "F.Mask" "F.Paste")
			(net "M_B_CPU1_SB_DQS_DP<3>")
		)
		(pad "138" smd rect
			(at -2.050034 58.224928 270)
			(size 0.519938 1.4986)
			(layers "F.Cu" "F.Mask" "F.Paste")
			(net "M_B_CPU1_SB_DQS_DN<3>")
		)
		(pad "139" smd rect
			(at -2.050034 59.075066 270)
			(size 0.519938 1.4986)
			(layers "F.Cu" "F.Mask" "F.Paste")
			(net "GND")
		)
		(pad "140" smd rect
			(at -2.050034 59.92495 270)
			(size 0.519938 1.4986)
			(layers "F.Cu" "F.Mask" "F.Paste")
			(net "M_B_CPU1_SB_DQ<28>")
		)
		(pad "141" smd rect
			(at -2.050034 60.775088 270)
			(size 0.519938 1.4986)
			(layers "F.Cu" "F.Mask" "F.Paste")
			(net "GND")
		)
		(pad "142" smd rect
			(at -2.050034 61.624972 270)
			(size 0.519938 1.4986)
			(layers "F.Cu" "F.Mask" "F.Paste")
			(net "M_B_CPU1_SB_DQ<29>")
		)
		(pad "143" smd rect
			(at -2.050034 62.47511 270)
			(size 0.519938 1.4986)
			(layers "F.Cu" "F.Mask" "F.Paste")
			(net "GND")
		)
		(pad "144" smd rect
			(at -2.050034 63.324994 270)
			(size 0.519938 1.4986)
			(layers "F.Cu" "F.Mask" "F.Paste")
			(net "TP_CHB_CPU1_DIMM2_FRU_1")
		)
		(pad "145" smd rect
			(at 2.050034 -63.324994 270)
			(size 0.519938 1.4986)
			(layers "F.Cu" "F.Mask" "F.Paste")
			(net "P12V_S3_AUX_CPU1_NVDIMM")
		)
		(pad "146" smd rect
			(at 2.050034 -62.47511 270)
			(size 0.519938 1.4986)
			(layers "F.Cu" "F.Mask" "F.Paste")
			(net "P12V_S3_AUX_CPU1_NVDIMM")
		)
		(pad "147" smd rect
			(at 2.050034 -61.624972 270)
			(size 0.519938 1.4986)
			(layers "F.Cu" "F.Mask" "F.Paste")
			(net "PWRGD_CHB_CPU1_DIMM2")
		)
		(pad "148" smd rect
			(at 2.050034 -60.775088 270)
			(size 0.519938 1.4986)
			(layers "F.Cu" "F.Mask" "F.Paste")
			(net "PD_CHB_CPU1_DIMM2_SAA")
		)
		(pad "149" smd rect
			(at 2.050034 -59.92495 270)
			(size 0.519938 1.4986)
			(layers "F.Cu" "F.Mask" "F.Paste")
			(net "TP_CHB_CPU1_DIMM2_FRU_2")
		)
		(pad "150" smd rect
			(at 2.050034 -59.075066 270)
			(size 0.519938 1.4986)
			(layers "F.Cu" "F.Mask" "F.Paste")
			(net "TP_CHB_CPU1_DIMM2_FRU_3")
		)
		(pad "151" smd rect
			(at 2.050034 -58.224928 270)
			(size 0.519938 1.4986)
			(layers "F.Cu" "F.Mask" "F.Paste")
			(net "GND")
		)
		(pad "152" smd rect
			(at 2.050034 -57.375044 270)
			(size 0.519938 1.4986)
			(layers "F.Cu" "F.Mask" "F.Paste")
			(net "M_B_CPU1_SA_DQ<2>")
		)
		(pad "153" smd rect
			(at 2.050034 -56.524906 270)
			(size 0.519938 1.4986)
			(layers "F.Cu" "F.Mask" "F.Paste")
			(net "GND")
		)
		(pad "154" smd rect
			(at 2.050034 -55.675022 270)
			(size 0.519938 1.4986)
			(layers "F.Cu" "F.Mask" "F.Paste")
			(net "M_B_CPU1_SA_DQ<3>")
		)
		(pad "155" smd rect
			(at 2.050034 -54.824884 270)
			(size 0.519938 1.4986)
			(layers "F.Cu" "F.Mask" "F.Paste")
			(net "GND")
		)
		(pad "156" smd rect
			(at 2.050034 -53.975 270)
			(size 0.519938 1.4986)
			(layers "F.Cu" "F.Mask" "F.Paste")
			(net "M_B_CPU1_SA_DQS_DN<5>")
		)
		(pad "157" smd rect
			(at 2.050034 -53.125116 270)
			(size 0.519938 1.4986)
			(layers "F.Cu" "F.Mask" "F.Paste")
			(net "M_B_CPU1_SA_DQS_DP<5>")
		)
		(pad "158" smd rect
			(at 2.050034 -52.274978 270)
			(size 0.519938 1.4986)
			(layers "F.Cu" "F.Mask" "F.Paste")
			(net "GND")
		)
		(pad "159" smd rect
			(at 2.050034 -51.425094 270)
			(size 0.519938 1.4986)
			(layers "F.Cu" "F.Mask" "F.Paste")
			(net "M_B_CPU1_SA_DQ<6>")
		)
		(pad "160" smd rect
			(at 2.050034 -50.574956 270)
			(size 0.519938 1.4986)
			(layers "F.Cu" "F.Mask" "F.Paste")
			(net "GND")
		)
		(pad "161" smd rect
			(at 2.050034 -49.725072 270)
			(size 0.519938 1.4986)
			(layers "F.Cu" "F.Mask" "F.Paste")
			(net "M_B_CPU1_SA_DQ<7>")
		)
		(pad "162" smd rect
			(at 2.050034 -48.874934 270)
			(size 0.519938 1.4986)
			(layers "F.Cu" "F.Mask" "F.Paste")
			(net "GND")
		)
		(pad "163" smd rect
			(at 2.050034 -48.02505 270)
			(size 0.519938 1.4986)
			(layers "F.Cu" "F.Mask" "F.Paste")
			(net "M_B_CPU1_SA_DQ<10>")
		)
		(pad "164" smd rect
			(at 2.050034 -47.174912 270)
			(size 0.519938 1.4986)
			(layers "F.Cu" "F.Mask" "F.Paste")
			(net "GND")
		)
		(pad "165" smd rect
			(at 2.050034 -46.325028 270)
			(size 0.519938 1.4986)
			(layers "F.Cu" "F.Mask" "F.Paste")
			(net "M_B_CPU1_SA_DQ<11>")
		)
		(pad "166" smd rect
			(at 2.050034 -45.47489 270)
			(size 0.519938 1.4986)
			(layers "F.Cu" "F.Mask" "F.Paste")
			(net "GND")
		)
		(pad "167" smd rect
			(at 2.050034 -44.625006 270)
			(size 0.519938 1.4986)
			(layers "F.Cu" "F.Mask" "F.Paste")
			(net "M_B_CPU1_SA_DQS_DN<6>")
		)
		(pad "168" smd rect
			(at 2.050034 -43.775122 270)
			(size 0.519938 1.4986)
			(layers "F.Cu" "F.Mask" "F.Paste")
			(net "M_B_CPU1_SA_DQS_DP<6>")
		)
		(pad "169" smd rect
			(at 2.050034 -42.924984 270)
			(size 0.519938 1.4986)
			(layers "F.Cu" "F.Mask" "F.Paste")
			(net "GND")
		)
		(pad "170" smd rect
			(at 2.050034 -42.0751 270)
			(size 0.519938 1.4986)
			(layers "F.Cu" "F.Mask" "F.Paste")
			(net "M_B_CPU1_SA_DQ<14>")
		)
		(pad "171" smd rect
			(at 2.050034 -41.224962 270)
			(size 0.519938 1.4986)
			(layers "F.Cu" "F.Mask" "F.Paste")
			(net "GND")
		)
		(pad "172" smd rect
			(at 2.050034 -40.375078 270)
			(size 0.519938 1.4986)
			(layers "F.Cu" "F.Mask" "F.Paste")
			(net "M_B_CPU1_SA_DQ<15>")
		)
		(pad "173" smd rect
			(at 2.050034 -39.52494 270)
			(size 0.519938 1.4986)
			(layers "F.Cu" "F.Mask" "F.Paste")
			(net "GND")
		)
		(pad "174" smd rect
			(at 2.050034 -38.675056 270)
			(size 0.519938 1.4986)
			(layers "F.Cu" "F.Mask" "F.Paste")
			(net "M_B_CPU1_SA_DQ<18>")
		)
		(pad "175" smd rect
			(at 2.050034 -37.824918 270)
			(size 0.519938 1.4986)
			(layers "F.Cu" "F.Mask" "F.Paste")
			(net "GND")
		)
		(pad "176" smd rect
			(at 2.050034 -36.975034 270)
			(size 0.519938 1.4986)
			(layers "F.Cu" "F.Mask" "F.Paste")
			(net "M_B_CPU1_SA_DQ<19>")
		)
		(pad "177" smd rect
			(at 2.050034 -36.124896 270)
			(size 0.519938 1.4986)
			(layers "F.Cu" "F.Mask" "F.Paste")
			(net "GND")
		)
		(pad "178" smd rect
			(at 2.050034 -35.275012 270)
			(size 0.519938 1.4986)
			(layers "F.Cu" "F.Mask" "F.Paste")
			(net "M_B_CPU1_SA_DQS_DN<7>")
		)
		(pad "179" smd rect
			(at 2.050034 -34.425128 270)
			(size 0.519938 1.4986)
			(layers "F.Cu" "F.Mask" "F.Paste")
			(net "M_B_CPU1_SA_DQS_DP<7>")
		)
		(pad "180" smd rect
			(at 2.050034 -33.57499 270)
			(size 0.519938 1.4986)
			(layers "F.Cu" "F.Mask" "F.Paste")
			(net "GND")
		)
		(pad "181" smd rect
			(at 2.050034 -32.725106 270)
			(size 0.519938 1.4986)
			(layers "F.Cu" "F.Mask" "F.Paste")
			(net "M_B_CPU1_SA_DQ<22>")
		)
		(pad "182" smd rect
			(at 2.050034 -31.874968 270)
			(size 0.519938 1.4986)
			(layers "F.Cu" "F.Mask" "F.Paste")
			(net "GND")
		)
		(pad "183" smd rect
			(at 2.050034 -31.025084 270)
			(size 0.519938 1.4986)
			(layers "F.Cu" "F.Mask" "F.Paste")
			(net "M_B_CPU1_SA_DQ<23>")
		)
		(pad "184" smd rect
			(at 2.050034 -30.174946 270)
			(size 0.519938 1.4986)
			(layers "F.Cu" "F.Mask" "F.Paste")
			(net "GND")
		)
		(pad "185" smd rect
			(at 2.050034 -29.325062 270)
			(size 0.519938 1.4986)
			(layers "F.Cu" "F.Mask" "F.Paste")
			(net "M_B_CPU1_SA_DQ<26>")
		)
		(pad "186" smd rect
			(at 2.050034 -28.474924 270)
			(size 0.519938 1.4986)
			(layers "F.Cu" "F.Mask" "F.Paste")
			(net "GND")
		)
		(pad "187" smd rect
			(at 2.050034 -27.62504 270)
			(size 0.519938 1.4986)
			(layers "F.Cu" "F.Mask" "F.Paste")
			(net "M_B_CPU1_SA_DQ<27>")
		)
		(pad "188" smd rect
			(at 2.050034 -26.774902 270)
			(size 0.519938 1.4986)
			(layers "F.Cu" "F.Mask" "F.Paste")
			(net "GND")
		)
		(pad "189" smd rect
			(at 2.050034 -25.925018 270)
			(size 0.519938 1.4986)
			(layers "F.Cu" "F.Mask" "F.Paste")
			(net "M_B_CPU1_SA_DQS_DN<8>")
		)
		(pad "190" smd rect
			(at 2.050034 -25.07488 270)
			(size 0.519938 1.4986)
			(layers "F.Cu" "F.Mask" "F.Paste")
			(net "M_B_CPU1_SA_DQS_DP<8>")
		)
		(pad "191" smd rect
			(at 2.050034 -24.224996 270)
			(size 0.519938 1.4986)
			(layers "F.Cu" "F.Mask" "F.Paste")
			(net "GND")
		)
		(pad "192" smd rect
			(at 2.050034 -23.375112 270)
			(size 0.519938 1.4986)
			(layers "F.Cu" "F.Mask" "F.Paste")
			(net "M_B_CPU1_SA_DQ<30>")
		)
		(pad "193" smd rect
			(at 2.050034 -22.524974 270)
			(size 0.519938 1.4986)
			(layers "F.Cu" "F.Mask" "F.Paste")
			(net "GND")
		)
		(pad "194" smd rect
			(at 2.050034 -21.67509 270)
			(size 0.519938 1.4986)
			(layers "F.Cu" "F.Mask" "F.Paste")
			(net "M_B_CPU1_SA_DQ<31>")
		)
		(pad "195" smd rect
			(at 2.050034 -20.824952 270)
			(size 0.519938 1.4986)
			(layers "F.Cu" "F.Mask" "F.Paste")
			(net "GND")
		)
		(pad "196" smd rect
			(at 2.050034 -19.975068 270)
			(size 0.519938 1.4986)
			(layers "F.Cu" "F.Mask" "F.Paste")
			(net "M_B_CPU1_SA_CB<2>")
		)
		(pad "197" smd rect
			(at 2.050034 -19.12493 270)
			(size 0.519938 1.4986)
			(layers "F.Cu" "F.Mask" "F.Paste")
			(net "GND")
		)
		(pad "198" smd rect
			(at 2.050034 -18.275046 270)
			(size 0.519938 1.4986)
			(layers "F.Cu" "F.Mask" "F.Paste")
			(net "M_B_CPU1_SA_CB<3>")
		)
		(pad "199" smd rect
			(at 2.050034 -17.424908 270)
			(size 0.519938 1.4986)
			(layers "F.Cu" "F.Mask" "F.Paste")
			(net "GND")
		)
		(pad "200" smd rect
			(at 2.050034 -16.575024 270)
			(size 0.519938 1.4986)
			(layers "F.Cu" "F.Mask" "F.Paste")
			(net "M_B_CPU1_SA_DQS_DN<9>")
		)
		(pad "201" smd rect
			(at 2.050034 -15.724886 270)
			(size 0.519938 1.4986)
			(layers "F.Cu" "F.Mask" "F.Paste")
			(net "M_B_CPU1_SA_DQS_DP<9>")
		)
		(pad "202" smd rect
			(at 2.050034 -14.875002 270)
			(size 0.519938 1.4986)
			(layers "F.Cu" "F.Mask" "F.Paste")
			(net "GND")
		)
		(pad "203" smd rect
			(at 2.050034 -14.025118 270)
			(size 0.519938 1.4986)
			(layers "F.Cu" "F.Mask" "F.Paste")
			(net "M_B_CPU1_SA_CB<6>")
		)
		(pad "204" smd rect
			(at 2.050034 -13.17498 270)
			(size 0.519938 1.4986)
			(layers "F.Cu" "F.Mask" "F.Paste")
			(net "GND")
		)
		(pad "205" smd rect
			(at 2.050034 -12.325096 270)
			(size 0.519938 1.4986)
			(layers "F.Cu" "F.Mask" "F.Paste")
			(net "M_B_CPU1_SA_CB<7>")
		)
		(pad "206" smd rect
			(at 2.050034 -11.474958 270)
			(size 0.519938 1.4986)
			(layers "F.Cu" "F.Mask" "F.Paste")
			(net "GND")
		)
		(pad "207" smd rect
			(at 2.050034 -10.625074 270)
			(size 0.519938 1.4986)
			(layers "F.Cu" "F.Mask" "F.Paste")
			(net "RST_M_AB_CPU1_FPGA_N")
		)
		(pad "208" smd rect
			(at 2.050034 -9.774936 270)
			(size 0.519938 1.4986)
			(layers "F.Cu" "F.Mask" "F.Paste")
			(net "GND")
		)
		(pad "209" smd rect
			(at 2.050034 -8.925052 270)
			(size 0.519938 1.4986)
			(layers "F.Cu" "F.Mask" "F.Paste")
			(net "M_B_CPU1_SA_CS_N<3>")
		)
		(pad "210" smd rect
			(at 2.050034 -8.074914 270)
			(size 0.519938 1.4986)
			(layers "F.Cu" "F.Mask" "F.Paste")
			(net "GND")
		)
		(pad "211" smd rect
			(at 2.050034 -7.22503 270)
			(size 0.519938 1.4986)
			(layers "F.Cu" "F.Mask" "F.Paste")
			(net "M_B_CPU1_SA_CA<1>")
		)
		(pad "212" smd rect
			(at 2.050034 -6.374892 270)
			(size 0.519938 1.4986)
			(layers "F.Cu" "F.Mask" "F.Paste")
			(net "GND")
		)
		(pad "213" smd rect
			(at 2.050034 -5.525008 270)
			(size 0.519938 1.4986)
			(layers "F.Cu" "F.Mask" "F.Paste")
			(net "M_B_CPU1_SA_CA<3>")
		)
		(pad "214" smd rect
			(at 2.050034 -4.675124 270)
			(size 0.519938 1.4986)
			(layers "F.Cu" "F.Mask" "F.Paste")
			(net "GND")
		)
		(pad "215" smd rect
			(at 2.050034 -3.824986 270)
			(size 0.519938 1.4986)
			(layers "F.Cu" "F.Mask" "F.Paste")
			(net "M_B_CPU1_SA_CA<5>")
		)
		(pad "216" smd rect
			(at 2.050034 -2.975102 270)
			(size 0.519938 1.4986)
			(layers "F.Cu" "F.Mask" "F.Paste")
			(net "GND")
		)
		(pad "217" smd rect
			(at 2.050034 -2.124964 270)
			(size 0.519938 1.4986)
			(layers "F.Cu" "F.Mask" "F.Paste")
			(net "M_B_CPU1_CLK_DP<1>")
		)
		(pad "218" smd rect
			(at 2.050034 -1.27508 270)
			(size 0.519938 1.4986)
			(layers "F.Cu" "F.Mask" "F.Paste")
			(net "M_B_CPU1_CLK_DN<1>")
		)
		(pad "219" smd rect
			(at 2.050034 -0.424942 270)
			(size 0.519938 1.4986)
			(layers "F.Cu" "F.Mask" "F.Paste")
			(net "GND")
		)
		(pad "220" smd rect
			(at 2.050034 5.525008 270)
			(size 0.519938 1.4986)
			(layers "F.Cu" "F.Mask" "F.Paste")
			(net "TP_CHB_CPU1_DIMM2_FRU_4")
		)
		(pad "221" smd rect
			(at 2.050034 6.374892 270)
			(size 0.519938 1.4986)
			(layers "F.Cu" "F.Mask" "F.Paste")
			(net "M_B_CPU1_SB_CA<1>")
		)
		(pad "222" smd rect
			(at 2.050034 7.22503 270)
			(size 0.519938 1.4986)
			(layers "F.Cu" "F.Mask" "F.Paste")
			(net "GND")
		)
		(pad "223" smd rect
			(at 2.050034 8.074914 270)
			(size 0.519938 1.4986)
			(layers "F.Cu" "F.Mask" "F.Paste")
			(net "M_B_CPU1_SB_CA<3>")
		)
		(pad "224" smd rect
			(at 2.050034 8.925052 270)
			(size 0.519938 1.4986)
			(layers "F.Cu" "F.Mask" "F.Paste")
			(net "GND")
		)
		(pad "225" smd rect
			(at 2.050034 9.774936 270)
			(size 0.519938 1.4986)
			(layers "F.Cu" "F.Mask" "F.Paste")
			(net "M_B_CPU1_SB_CA<5>")
		)
		(pad "226" smd rect
			(at 2.050034 10.625074 270)
			(size 0.519938 1.4986)
			(layers "F.Cu" "F.Mask" "F.Paste")
			(net "GND")
		)
		(pad "227" smd rect
			(at 2.050034 11.474958 270)
			(size 0.519938 1.4986)
			(layers "F.Cu" "F.Mask" "F.Paste")
			(net "M_B_CPU1_SB_PAR")
		)
		(pad "228" smd rect
			(at 2.050034 12.325096 270)
			(size 0.519938 1.4986)
			(layers "F.Cu" "F.Mask" "F.Paste")
			(net "GND")
		)
		(pad "229" smd rect
			(at 2.050034 13.17498 270)
			(size 0.519938 1.4986)
			(layers "F.Cu" "F.Mask" "F.Paste")
			(net "M_B_CPU1_SB_CS_N<3>")
		)
		(pad "230" smd rect
			(at 2.050034 14.025118 270)
			(size 0.519938 1.4986)
			(layers "F.Cu" "F.Mask" "F.Paste")
			(net "GND")
		)
		(pad "231" smd rect
			(at 2.050034 14.875002 270)
			(size 0.519938 1.4986)
			(layers "F.Cu" "F.Mask" "F.Paste")
			(net "TP_CHB_CPU1_DIMM2_FRU_5")
		)
		(pad "232" smd rect
			(at 2.050034 15.724886 270)
			(size 0.519938 1.4986)
			(layers "F.Cu" "F.Mask" "F.Paste")
			(net "TP_CHB_CPU1_DIMM2_FRU_6")
		)
		(pad "233" smd rect
			(at 2.050034 16.575024 270)
			(size 0.519938 1.4986)
			(layers "F.Cu" "F.Mask" "F.Paste")
			(net "GND")
		)
		(pad "234" smd rect
			(at 2.050034 17.424908 270)
			(size 0.519938 1.4986)
			(layers "F.Cu" "F.Mask" "F.Paste")
			(net "M_B_CPU1_SB_CB<6>")
		)
		(pad "235" smd rect
			(at 2.050034 18.275046 270)
			(size 0.519938 1.4986)
			(layers "F.Cu" "F.Mask" "F.Paste")
			(net "GND")
		)
		(pad "236" smd rect
			(at 2.050034 19.12493 270)
			(size 0.519938 1.4986)
			(layers "F.Cu" "F.Mask" "F.Paste")
			(net "M_B_CPU1_SB_CB<7>")
		)
		(pad "237" smd rect
			(at 2.050034 19.975068 270)
			(size 0.519938 1.4986)
			(layers "F.Cu" "F.Mask" "F.Paste")
			(net "GND")
		)
		(pad "238" smd rect
			(at 2.050034 20.824952 270)
			(size 0.519938 1.4986)
			(layers "F.Cu" "F.Mask" "F.Paste")
			(net "M_B_CPU1_SB_DQS_DN<4>")
		)
		(pad "239" smd rect
			(at 2.050034 21.67509 270)
			(size 0.519938 1.4986)
			(layers "F.Cu" "F.Mask" "F.Paste")
			(net "M_B_CPU1_SB_DQS_DP<4>")
		)
		(pad "240" smd rect
			(at 2.050034 22.524974 270)
			(size 0.519938 1.4986)
			(layers "F.Cu" "F.Mask" "F.Paste")
			(net "GND")
		)
		(pad "241" smd rect
			(at 2.050034 23.375112 270)
			(size 0.519938 1.4986)
			(layers "F.Cu" "F.Mask" "F.Paste")
			(net "M_B_CPU1_SB_CB<2>")
		)
		(pad "242" smd rect
			(at 2.050034 24.224996 270)
			(size 0.519938 1.4986)
			(layers "F.Cu" "F.Mask" "F.Paste")
			(net "GND")
		)
		(pad "243" smd rect
			(at 2.050034 25.07488 270)
			(size 0.519938 1.4986)
			(layers "F.Cu" "F.Mask" "F.Paste")
			(net "M_B_CPU1_SB_CB<3>")
		)
		(pad "244" smd rect
			(at 2.050034 25.925018 270)
			(size 0.519938 1.4986)
			(layers "F.Cu" "F.Mask" "F.Paste")
			(net "GND")
		)
		(pad "245" smd rect
			(at 2.050034 26.774902 270)
			(size 0.519938 1.4986)
			(layers "F.Cu" "F.Mask" "F.Paste")
			(net "M_B_CPU1_SB_DQ<2>")
		)
		(pad "246" smd rect
			(at 2.050034 27.62504 270)
			(size 0.519938 1.4986)
			(layers "F.Cu" "F.Mask" "F.Paste")
			(net "GND")
		)
		(pad "247" smd rect
			(at 2.050034 28.474924 270)
			(size 0.519938 1.4986)
			(layers "F.Cu" "F.Mask" "F.Paste")
			(net "M_B_CPU1_SB_DQ<3>")
		)
		(pad "248" smd rect
			(at 2.050034 29.325062 270)
			(size 0.519938 1.4986)
			(layers "F.Cu" "F.Mask" "F.Paste")
			(net "GND")
		)
		(pad "249" smd rect
			(at 2.050034 30.174946 270)
			(size 0.519938 1.4986)
			(layers "F.Cu" "F.Mask" "F.Paste")
			(net "M_B_CPU1_SB_DQS_DN<5>")
		)
		(pad "250" smd rect
			(at 2.050034 31.025084 270)
			(size 0.519938 1.4986)
			(layers "F.Cu" "F.Mask" "F.Paste")
			(net "M_B_CPU1_SB_DQS_DP<5>")
		)
		(pad "251" smd rect
			(at 2.050034 31.874968 270)
			(size 0.519938 1.4986)
			(layers "F.Cu" "F.Mask" "F.Paste")
			(net "GND")
		)
		(pad "252" smd rect
			(at 2.050034 32.725106 270)
			(size 0.519938 1.4986)
			(layers "F.Cu" "F.Mask" "F.Paste")
			(net "M_B_CPU1_SB_DQ<6>")
		)
		(pad "253" smd rect
			(at 2.050034 33.57499 270)
			(size 0.519938 1.4986)
			(layers "F.Cu" "F.Mask" "F.Paste")
			(net "GND")
		)
		(pad "254" smd rect
			(at 2.050034 34.425128 270)
			(size 0.519938 1.4986)
			(layers "F.Cu" "F.Mask" "F.Paste")
			(net "M_B_CPU1_SB_DQ<7>")
		)
		(pad "255" smd rect
			(at 2.050034 35.275012 270)
			(size 0.519938 1.4986)
			(layers "F.Cu" "F.Mask" "F.Paste")
			(net "GND")
		)
		(pad "256" smd rect
			(at 2.050034 36.124896 270)
			(size 0.519938 1.4986)
			(layers "F.Cu" "F.Mask" "F.Paste")
			(net "M_B_CPU1_SB_DQ<10>")
		)
		(pad "257" smd rect
			(at 2.050034 36.975034 270)
			(size 0.519938 1.4986)
			(layers "F.Cu" "F.Mask" "F.Paste")
			(net "GND")
		)
		(pad "258" smd rect
			(at 2.050034 37.824918 270)
			(size 0.519938 1.4986)
			(layers "F.Cu" "F.Mask" "F.Paste")
			(net "M_B_CPU1_SB_DQ<11>")
		)
		(pad "259" smd rect
			(at 2.050034 38.675056 270)
			(size 0.519938 1.4986)
			(layers "F.Cu" "F.Mask" "F.Paste")
			(net "GND")
		)
		(pad "260" smd rect
			(at 2.050034 39.52494 270)
			(size 0.519938 1.4986)
			(layers "F.Cu" "F.Mask" "F.Paste")
			(net "M_B_CPU1_SB_DQS_DN<6>")
		)
		(pad "261" smd rect
			(at 2.050034 40.375078 270)
			(size 0.519938 1.4986)
			(layers "F.Cu" "F.Mask" "F.Paste")
			(net "M_B_CPU1_SB_DQS_DP<6>")
		)
		(pad "262" smd rect
			(at 2.050034 41.224962 270)
			(size 0.519938 1.4986)
			(layers "F.Cu" "F.Mask" "F.Paste")
			(net "GND")
		)
		(pad "263" smd rect
			(at 2.050034 42.0751 270)
			(size 0.519938 1.4986)
			(layers "F.Cu" "F.Mask" "F.Paste")
			(net "M_B_CPU1_SB_DQ<14>")
		)
		(pad "264" smd rect
			(at 2.050034 42.924984 270)
			(size 0.519938 1.4986)
			(layers "F.Cu" "F.Mask" "F.Paste")
			(net "GND")
		)
		(pad "265" smd rect
			(at 2.050034 43.775122 270)
			(size 0.519938 1.4986)
			(layers "F.Cu" "F.Mask" "F.Paste")
			(net "M_B_CPU1_SB_DQ<15>")
		)
		(pad "266" smd rect
			(at 2.050034 44.625006 270)
			(size 0.519938 1.4986)
			(layers "F.Cu" "F.Mask" "F.Paste")
			(net "GND")
		)
		(pad "267" smd rect
			(at 2.050034 45.47489 270)
			(size 0.519938 1.4986)
			(layers "F.Cu" "F.Mask" "F.Paste")
			(net "M_B_CPU1_SB_DQ<18>")
		)
		(pad "268" smd rect
			(at 2.050034 46.325028 270)
			(size 0.519938 1.4986)
			(layers "F.Cu" "F.Mask" "F.Paste")
			(net "GND")
		)
		(pad "269" smd rect
			(at 2.050034 47.174912 270)
			(size 0.519938 1.4986)
			(layers "F.Cu" "F.Mask" "F.Paste")
			(net "M_B_CPU1_SB_DQ<19>")
		)
		(pad "270" smd rect
			(at 2.050034 48.02505 270)
			(size 0.519938 1.4986)
			(layers "F.Cu" "F.Mask" "F.Paste")
			(net "GND")
		)
		(pad "271" smd rect
			(at 2.050034 48.874934 270)
			(size 0.519938 1.4986)
			(layers "F.Cu" "F.Mask" "F.Paste")
			(net "M_B_CPU1_SB_DQS_DN<7>")
		)
		(pad "272" smd rect
			(at 2.050034 49.725072 270)
			(size 0.519938 1.4986)
			(layers "F.Cu" "F.Mask" "F.Paste")
			(net "M_B_CPU1_SB_DQS_DP<7>")
		)
		(pad "273" smd rect
			(at 2.050034 50.574956 270)
			(size 0.519938 1.4986)
			(layers "F.Cu" "F.Mask" "F.Paste")
			(net "GND")
		)
		(pad "274" smd rect
			(at 2.050034 51.425094 270)
			(size 0.519938 1.4986)
			(layers "F.Cu" "F.Mask" "F.Paste")
			(net "M_B_CPU1_SB_DQ<22>")
		)
		(pad "275" smd rect
			(at 2.050034 52.274978 270)
			(size 0.519938 1.4986)
			(layers "F.Cu" "F.Mask" "F.Paste")
			(net "GND")
		)
		(pad "276" smd rect
			(at 2.050034 53.125116 270)
			(size 0.519938 1.4986)
			(layers "F.Cu" "F.Mask" "F.Paste")
			(net "M_B_CPU1_SB_DQ<23>")
		)
		(pad "277" smd rect
			(at 2.050034 53.975 270)
			(size 0.519938 1.4986)
			(layers "F.Cu" "F.Mask" "F.Paste")
			(net "GND")
		)
		(pad "278" smd rect
			(at 2.050034 54.824884 270)
			(size 0.519938 1.4986)
			(layers "F.Cu" "F.Mask" "F.Paste")
			(net "M_B_CPU1_SB_DQ<26>")
		)
		(pad "279" smd rect
			(at 2.050034 55.675022 270)
			(size 0.519938 1.4986)
			(layers "F.Cu" "F.Mask" "F.Paste")
			(net "GND")
		)
		(pad "280" smd rect
			(at 2.050034 56.524906 270)
			(size 0.519938 1.4986)
			(layers "F.Cu" "F.Mask" "F.Paste")
			(net "M_B_CPU1_SB_DQ<27>")
		)
		(pad "281" smd rect
			(at 2.050034 57.375044 270)
			(size 0.519938 1.4986)
			(layers "F.Cu" "F.Mask" "F.Paste")
			(net "GND")
		)
		(pad "282" smd rect
			(at 2.050034 58.224928 270)
			(size 0.519938 1.4986)
			(layers "F.Cu" "F.Mask" "F.Paste")
			(net "M_B_CPU1_SB_DQS_DN<8>")
		)
		(pad "283" smd rect
			(at 2.050034 59.075066 270)
			(size 0.519938 1.4986)
			(layers "F.Cu" "F.Mask" "F.Paste")
			(net "M_B_CPU1_SB_DQS_DP<8>")
		)
		(pad "284" smd rect
			(at 2.050034 59.92495 270)
			(size 0.519938 1.4986)
			(layers "F.Cu" "F.Mask" "F.Paste")
			(net "GND")
		)
		(pad "285" smd rect
			(at 2.050034 60.775088 270)
			(size 0.519938 1.4986)
			(layers "F.Cu" "F.Mask" "F.Paste")
			(net "M_B_CPU1_SB_DQ<30>")
		)
		(pad "286" smd rect
			(at 2.050034 61.624972 270)
			(size 0.519938 1.4986)
			(layers "F.Cu" "F.Mask" "F.Paste")
			(net "GND")
		)
		(pad "287" smd rect
			(at 2.050034 62.47511 270)
			(size 0.519938 1.4986)
			(layers "F.Cu" "F.Mask" "F.Paste")
			(net "M_B_CPU1_SB_DQ<31>")
		)
		(pad "288" smd rect
			(at 2.050034 63.324994 270)
			(size 0.519938 1.4986)
			(layers "F.Cu" "F.Mask" "F.Paste")
			(net "GND")
		)
		(pad "G1" thru_hole oval
			(at 0 -68.97497)
			(size 2.8194 1.5748)
			(drill oval 2.4384 1.1938)
			(layers "*.Cu" "*.Mask")
			(remove_unused_layers no)
			(net "GND")
			(clearance 0.127)
			(thermal_gap 0.127)
		)
		(pad "G2" thru_hole oval
			(at 0 3.875024)
			(size 2.8194 1.5748)
			(drill oval 2.4384 1.1938)
			(layers "*.Cu" "*.Mask")
			(remove_unused_layers no)
			(net "GND")
			(clearance 0.127)
			(thermal_gap 0.127)
		)
		(pad "G3" thru_hole oval
			(at 0 68.97497)
			(size 2.8194 1.5748)
			(drill oval 2.4384 1.1938)
			(layers "*.Cu" "*.Mask")
			(remove_unused_layers no)
			(net "GND")
			(clearance 0.127)
			(thermal_gap 0.127)
		)
	)
	(footprint ""
		(layer "F.Cu")
		(at 240.854484 -56.527192 180)
		(property "Reference" "C1991"
			(at 0 0 180)
			(layer "F.SilkS")
			(hide yes)
			(effects
				(font
					(size 1.27 1.27)
				)
			)
		)
		(property "Value" ""
			(at 0 0 180)
			(layer "F.Fab")
			(effects
				(font
					(size 1.27 1.27)
				)
			)
		)
		(duplicate_pad_numbers_are_jumpers no)
		(fp_line
			(start 0.299974 0.150114)
			(end -0.299974 0.150114)
			(stroke
				(width 0.1)
				(type default)
			)
			(layer "F.Fab")
		)
		(fp_line
			(start 0.299974 -0.150114)
			(end 0.299974 0.150114)
			(stroke
				(width 0.1)
				(type default)
			)
			(layer "F.Fab")
		)
		(fp_line
			(start -0.299974 0.150114)
			(end -0.299974 -0.150114)
			(stroke
				(width 0.1)
				(type default)
			)
			(layer "F.Fab")
		)
		(fp_line
			(start -0.299974 -0.150114)
			(end 0.299974 -0.150114)
			(stroke
				(width 0.1)
				(type default)
			)
			(layer "F.Fab")
		)
		(pad "1" smd rect
			(at -0.2667 0 180)
			(size 0.3048 0.381)
			(layers "F.Cu" "F.Mask" "F.Paste")
			(net "P3E_PCH_E1S_TX_DP<2>")
		)
		(pad "2" smd rect
			(at 0.2667 0 180)
			(size 0.3048 0.381)
			(layers "F.Cu" "F.Mask" "F.Paste")
			(net "P3E_PCH_E1S_TX_C_DP<2>")
		)
		(zone
			(layer "In1.Cu")
			(hatch none 0.5)
			(connect_pads
				(clearance 0)
			)
			(min_thickness 0.25)
			(keepout
				(tracks not_allowed)
				(vias allowed)
				(pads allowed)
				(copperpour not_allowed)
				(footprints allowed)
			)
			(placement
				(enabled no)
				(sheetname "")
			)
			(fill
				(thermal_gap 0.5)
				(thermal_bridge_width 0.5)
				(island_removal_mode 0)
			)
			(polygon
				(pts
					(arc
						(start 240.714784 -56.767476)
						(mid 240.768666 -56.745158)
						(end 240.790984 -56.691276)
					)
					(arc
						(start 240.790984 -56.361076)
						(mid 240.768666 -56.307194)
						(end 240.714784 -56.284876)
					)
					(arc
						(start 240.460784 -56.284876)
						(mid 240.406902 -56.307194)
						(end 240.384584 -56.361076)
					)
					(arc
						(start 240.384584 -56.691276)
						(mid 240.406902 -56.745158)
						(end 240.460784 -56.767476)
					)
				)
			)
		)
		(zone
			(layer "In1.Cu")
			(hatch none 0.5)
			(connect_pads
				(clearance 0)
			)
			(min_thickness 0.25)
			(keepout
				(tracks not_allowed)
				(vias allowed)
				(pads allowed)
				(copperpour not_allowed)
				(footprints allowed)
			)
			(placement
				(enabled no)
				(sheetname "")
			)
			(fill
				(thermal_gap 0.5)
				(thermal_bridge_width 0.5)
				(island_removal_mode 0)
			)
			(polygon
				(pts
					(arc
						(start 241.248184 -56.767476)
						(mid 241.302066 -56.745158)
						(end 241.324384 -56.691276)
					)
					(arc
						(start 241.324384 -56.361076)
						(mid 241.302066 -56.307194)
						(end 241.248184 -56.284876)
					)
					(arc
						(start 240.994184 -56.284876)
						(mid 240.940302 -56.307194)
						(end 240.917984 -56.361076)
					)
					(arc
						(start 240.917984 -56.691276)
						(mid 240.940302 -56.745158)
						(end 240.994184 -56.767476)
					)
				)
			)
		)
	)
	(footprint ""
		(layer "F.Cu")
		(at 93.295724 -65.223644 -90)
		(property "Reference" "R3068"
			(at 0 0 270)
			(layer "F.SilkS")
			(hide yes)
			(effects
				(font
					(size 1.27 1.27)
				)
			)
		)
		(property "Value" ""
			(at 0 0 270)
			(layer "F.Fab")
			(effects
				(font
					(size 1.27 1.27)
				)
			)
		)
		(duplicate_pad_numbers_are_jumpers no)
		(fp_line
			(start -0.7874 0.4064)
			(end -0.7874 -0.4064)
			(stroke
				(width 0.1524)
				(type default)
			)
			(layer "F.SilkS")
		)
		(fp_line
			(start 0.7874 0.4064)
			(end -0.7874 0.4064)
			(stroke
				(width 0.1524)
				(type default)
			)
			(layer "F.SilkS")
		)
		(fp_line
			(start -0.7874 -0.4064)
			(end 0.7874 -0.4064)
			(stroke
				(width 0.1524)
				(type default)
			)
			(layer "F.SilkS")
		)
		(fp_line
			(start 0.7874 -0.4064)
			(end 0.7874 0.4064)
			(stroke
				(width 0.1524)
				(type default)
			)
			(layer "F.SilkS")
		)
		(fp_line
			(start -0.67945 0.3048)
			(end -0.67945 -0.305054)
			(stroke
				(width 0.1)
				(type default)
			)
			(layer "F.Fab")
		)
		(fp_line
			(start -0.12065 0.3048)
			(end -0.67945 0.3048)
			(stroke
				(width 0.1)
				(type default)
			)
			(layer "F.Fab")
		)
		(fp_line
			(start 0.120396 0.3048)
			(end 0.120396 0.2794)
			(stroke
				(width 0.1)
				(type default)
			)
			(layer "F.Fab")
		)
		(fp_line
			(start 0.67945 0.3048)
			(end 0.120396 0.3048)
			(stroke
				(width 0.1)
				(type default)
			)
			(layer "F.Fab")
		)
		(fp_line
			(start -0.12065 0.2794)
			(end -0.12065 0.3048)
			(stroke
				(width 0.1)
				(type default)
			)
			(layer "F.Fab")
		)
		(fp_line
			(start 0.120396 0.2794)
			(end -0.12065 0.2794)
			(stroke
				(width 0.1)
				(type default)
			)
			(layer "F.Fab")
		)
		(fp_line
			(start -0.12065 -0.2794)
			(end 0.12065 -0.2794)
			(stroke
				(width 0.1)
				(type default)
			)
			(layer "F.Fab")
		)
		(fp_line
			(start 0.12065 -0.2794)
			(end 0.12065 -0.3048)
			(stroke
				(width 0.1)
				(type default)
			)
			(layer "F.Fab")
		)
		(fp_line
			(start 0.12065 -0.3048)
			(end 0.67945 -0.3048)
			(stroke
				(width 0.1)
				(type default)
			)
			(layer "F.Fab")
		)
		(fp_line
			(start 0.67945 -0.3048)
			(end 0.67945 0.3048)
			(stroke
				(width 0.1)
				(type default)
			)
			(layer "F.Fab")
		)
		(fp_line
			(start -0.67945 -0.305054)
			(end -0.12065 -0.305054)
			(stroke
				(width 0.1)
				(type default)
			)
			(layer "F.Fab")
		)
		(fp_line
			(start -0.12065 -0.305054)
			(end -0.12065 -0.2794)
			(stroke
				(width 0.1)
				(type default)
			)
			(layer "F.Fab")
		)
		(pad "1" smd circle
			(at -0.40005 0 270)
			(size 0 0)
			(layers "F.Cu" "F.Mask" "F.Paste")
			(net "LED_PWRGD_PCH_PWROK_R")
		)
		(pad "2" smd circle
			(at 0.40005 0 270)
			(size 0 0)
			(layers "F.Cu" "F.Mask" "F.Paste")
			(net "P3V3_AUX")
		)
	)
	(footprint ""
		(layer "F.Cu")
		(at 404.006812 -55.759604)
		(property "Reference" "C552"
			(at 0 0 0)
			(layer "F.SilkS")
			(hide yes)
			(effects
				(font
					(size 1.27 1.27)
				)
			)
		)
		(property "Value" ""
			(at 0 0 0)
			(layer "F.Fab")
			(effects
				(font
					(size 1.27 1.27)
				)
			)
		)
		(duplicate_pad_numbers_are_jumpers no)
		(fp_line
			(start -0.7874 -0.4064)
			(end 0.7874 -0.4064)
			(stroke
				(width 0.1524)
				(type default)
			)
			(layer "F.SilkS")
		)
		(fp_line
			(start -0.7874 0.4064)
			(end -0.7874 -0.4064)
			(stroke
				(width 0.1524)
				(type default)
			)
			(layer "F.SilkS")
		)
		(fp_line
			(start 0.7874 -0.4064)
			(end 0.7874 0.4064)
			(stroke
				(width 0.1524)
				(type default)
			)
			(layer "F.SilkS")
		)
		(fp_line
			(start 0.7874 0.4064)
			(end -0.7874 0.4064)
			(stroke
				(width 0.1524)
				(type default)
			)
			(layer "F.SilkS")
		)
		(fp_line
			(start -0.67945 -0.305054)
			(end -0.12065 -0.305054)
			(stroke
				(width 0.1)
				(type default)
			)
			(layer "F.Fab")
		)
		(fp_line
			(start -0.67945 0.3048)
			(end -0.67945 -0.305054)
			(stroke
				(width 0.1)
				(type default)
			)
			(layer "F.Fab")
		)
		(fp_line
			(start -0.12065 -0.305054)
			(end -0.12065 -0.2794)
			(stroke
				(width 0.1)
				(type default)
			)
			(layer "F.Fab")
		)
		(fp_line
			(start -0.12065 -0.2794)
			(end 0.12065 -0.2794)
			(stroke
				(width 0.1)
				(type default)
			)
			(layer "F.Fab")
		)
		(fp_line
			(start -0.12065 0.2794)
			(end -0.12065 0.3048)
			(stroke
				(width 0.1)
				(type default)
			)
			(layer "F.Fab")
		)
		(fp_line
			(start -0.12065 0.3048)
			(end -0.67945 0.3048)
			(stroke
				(width 0.1)
				(type default)
			)
			(layer "F.Fab")
		)
		(fp_line
			(start 0.120396 0.2794)
			(end -0.12065 0.2794)
			(stroke
				(width 0.1)
				(type default)
			)
			(layer "F.Fab")
		)
		(fp_line
			(start 0.120396 0.3048)
			(end 0.120396 0.2794)
			(stroke
				(width 0.1)
				(type default)
			)
			(layer "F.Fab")
		)
		(fp_line
			(start 0.12065 -0.3048)
			(end 0.67945 -0.3048)
			(stroke
				(width 0.1)
				(type default)
			)
			(layer "F.Fab")
		)
		(fp_line
			(start 0.12065 -0.2794)
			(end 0.12065 -0.3048)
			(stroke
				(width 0.1)
				(type default)
			)
			(layer "F.Fab")
		)
		(fp_line
			(start 0.67945 -0.3048)
			(end 0.67945 0.3048)
			(stroke
				(width 0.1)
				(type default)
			)
			(layer "F.Fab")
		)
		(fp_line
			(start 0.67945 0.3048)
			(end 0.120396 0.3048)
			(stroke
				(width 0.1)
				(type default)
			)
			(layer "F.Fab")
		)
		(pad "1" smd circle
			(at -0.40005 0)
			(size 0 0)
			(layers "F.Cu" "F.Mask" "F.Paste")
			(net "FM_CPU_FBRK_DEBUG_N")
		)
		(pad "2" smd circle
			(at 0.40005 0)
			(size 0 0)
			(layers "F.Cu" "F.Mask" "F.Paste")
			(net "GND")
		)
	)
	(footprint ""
		(layer "F.Cu")
		(at 341.651082 -24.217122 -90)
		(property "Reference" "R727"
			(at 0 0 270)
			(layer "F.SilkS")
			(hide yes)
			(effects
				(font
					(size 1.27 1.27)
				)
			)
		)
		(property "Value" ""
			(at 0 0 270)
			(layer "F.Fab")
			(effects
				(font
					(size 1.27 1.27)
				)
			)
		)
		(duplicate_pad_numbers_are_jumpers no)
		(fp_line
			(start -0.7874 0.4064)
			(end -0.7874 -0.4064)
			(stroke
				(width 0.1524)
				(type default)
			)
			(layer "F.SilkS")
		)
		(fp_line
			(start 0.7874 0.4064)
			(end -0.7874 0.4064)
			(stroke
				(width 0.1524)
				(type default)
			)
			(layer "F.SilkS")
		)
		(fp_line
			(start -0.7874 -0.4064)
			(end 0.7874 -0.4064)
			(stroke
				(width 0.1524)
				(type default)
			)
			(layer "F.SilkS")
		)
		(fp_line
			(start 0.7874 -0.4064)
			(end 0.7874 0.4064)
			(stroke
				(width 0.1524)
				(type default)
			)
			(layer "F.SilkS")
		)
		(fp_line
			(start -0.67945 0.3048)
			(end -0.67945 -0.305054)
			(stroke
				(width 0.1)
				(type default)
			)
			(layer "F.Fab")
		)
		(fp_line
			(start -0.12065 0.3048)
			(end -0.67945 0.3048)
			(stroke
				(width 0.1)
				(type default)
			)
			(layer "F.Fab")
		)
		(fp_line
			(start 0.120396 0.3048)
			(end 0.120396 0.2794)
			(stroke
				(width 0.1)
				(type default)
			)
			(layer "F.Fab")
		)
		(fp_line
			(start 0.67945 0.3048)
			(end 0.120396 0.3048)
			(stroke
				(width 0.1)
				(type default)
			)
			(layer "F.Fab")
		)
		(fp_line
			(start -0.12065 0.2794)
			(end -0.12065 0.3048)
			(stroke
				(width 0.1)
				(type default)
			)
			(layer "F.Fab")
		)
		(fp_line
			(start 0.120396 0.2794)
			(end -0.12065 0.2794)
			(stroke
				(width 0.1)
				(type default)
			)
			(layer "F.Fab")
		)
		(fp_line
			(start -0.12065 -0.2794)
			(end 0.12065 -0.2794)
			(stroke
				(width 0.1)
				(type default)
			)
			(layer "F.Fab")
		)
		(fp_line
			(start 0.12065 -0.2794)
			(end 0.12065 -0.3048)
			(stroke
				(width 0.1)
				(type default)
			)
			(layer "F.Fab")
		)
		(fp_line
			(start 0.12065 -0.3048)
			(end 0.67945 -0.3048)
			(stroke
				(width 0.1)
				(type default)
			)
			(layer "F.Fab")
		)
		(fp_line
			(start 0.67945 -0.3048)
			(end 0.67945 0.3048)
			(stroke
				(width 0.1)
				(type default)
			)
			(layer "F.Fab")
		)
		(fp_line
			(start -0.67945 -0.305054)
			(end -0.12065 -0.305054)
			(stroke
				(width 0.1)
				(type default)
			)
			(layer "F.Fab")
		)
		(fp_line
			(start -0.12065 -0.305054)
			(end -0.12065 -0.2794)
			(stroke
				(width 0.1)
				(type default)
			)
			(layer "F.Fab")
		)
		(pad "1" smd circle
			(at -0.40005 0 270)
			(size 0 0)
			(layers "F.Cu" "F.Mask" "F.Paste")
			(net "PU_OC4_USB_N")
		)
		(pad "2" smd circle
			(at 0.40005 0 270)
			(size 0 0)
			(layers "F.Cu" "F.Mask" "F.Paste")
			(net "P3V3_AUX")
		)
	)
	(footprint ""
		(layer "F.Cu")
		(at 90.582496 -70.78599)
		(property "Reference" "D88"
			(at -46.009306 50.178462 90)
			(unlocked yes)
			(layer "F.SilkS")
			(effects
				(font
					(size 0.635 0.4064)
					(thickness 0.1524)
				)
				(justify left)
			)
		)
		(property "Value" ""
			(at 0 0 0)
			(layer "F.Fab")
			(effects
				(font
					(size 1.27 1.27)
				)
			)
		)
		(duplicate_pad_numbers_are_jumpers no)
		(fp_line
			(start -0.90678 0.4826)
			(end -0.90678 -0.4699)
			(stroke
				(width 0.1524)
				(type default)
			)
			(layer "F.SilkS")
		)
		(fp_line
			(start -0.89408 -0.4826)
			(end 0.90678 -0.4826)
			(stroke
				(width 0.1524)
				(type default)
			)
			(layer "F.SilkS")
		)
		(fp_line
			(start -0.79248 -0.4826)
			(end 1.03378 -0.4826)
			(stroke
				(width 0.1524)
				(type default)
			)
			(layer "F.SilkS")
		)
		(fp_line
			(start -0.64008 -0.4826)
			(end 1.16078 -0.4826)
			(stroke
				(width 0.1524)
				(type default)
			)
			(layer "F.SilkS")
		)
		(fp_line
			(start 0.90678 -0.4826)
			(end 0.90678 0.4826)
			(stroke
				(width 0.1524)
				(type default)
			)
			(layer "F.SilkS")
		)
		(fp_line
			(start 0.90678 0.4826)
			(end -0.90678 0.4826)
			(stroke
				(width 0.1524)
				(type default)
			)
			(layer "F.SilkS")
		)
		(fp_line
			(start 1.03378 -0.4826)
			(end 1.03378 0.4826)
			(stroke
				(width 0.1524)
				(type default)
			)
			(layer "F.SilkS")
		)
		(fp_line
			(start 1.03378 0.4826)
			(end -0.79248 0.4826)
			(stroke
				(width 0.1524)
				(type default)
			)
			(layer "F.SilkS")
		)
		(fp_line
			(start 1.16078 -0.4826)
			(end 1.16078 0.4826)
			(stroke
				(width 0.1524)
				(type default)
			)
			(layer "F.SilkS")
		)
		(fp_line
			(start 1.16078 0.4826)
			(end -0.64008 0.4826)
			(stroke
				(width 0.1524)
				(type default)
			)
			(layer "F.SilkS")
		)
		(fp_line
			(start -0.499872 -0.249936)
			(end 0.499872 -0.249936)
			(stroke
				(width 0.1)
				(type default)
			)
			(layer "F.Fab")
		)
		(fp_line
			(start -0.499872 0.249936)
			(end -0.499872 -0.249936)
			(stroke
				(width 0.1)
				(type default)
			)
			(layer "F.Fab")
		)
		(fp_line
			(start 0.499872 -0.249936)
			(end 0.499872 0.249936)
			(stroke
				(width 0.1)
				(type default)
			)
			(layer "F.Fab")
		)
		(fp_line
			(start 0.499872 0.249936)
			(end -0.499872 0.249936)
			(stroke
				(width 0.1)
				(type default)
			)
			(layer "F.Fab")
		)
		(pad "A" smd rect
			(at -0.47498 0)
			(size 0.6096 0.7112)
			(layers "F.Cu" "F.Mask" "F.Paste")
			(net "LED_PWRGD_SYS_PWROK_R")
		)
		(pad "C" smd rect
			(at 0.47498 0)
			(size 0.6096 0.7112)
			(layers "F.Cu" "F.Mask" "F.Paste")
			(net "LED_PWRGD_SYS_PWROK_R_D")
		)
	)
	(footprint ""
		(layer "F.Cu")
		(at 427.592236 -17.612614 90)
		(property "Reference" "C865"
			(at 0 0 90)
			(layer "F.SilkS")
			(hide yes)
			(effects
				(font
					(size 1.27 1.27)
				)
			)
		)
		(property "Value" ""
			(at 0 0 90)
			(layer "F.Fab")
			(effects
				(font
					(size 1.27 1.27)
				)
			)
		)
		(duplicate_pad_numbers_are_jumpers no)
		(fp_line
			(start 0.299974 -0.150114)
			(end 0.299974 0.150114)
			(stroke
				(width 0.1)
				(type default)
			)
			(layer "F.Fab")
		)
		(fp_line
			(start -0.299974 -0.150114)
			(end 0.299974 -0.150114)
			(stroke
				(width 0.1)
				(type default)
			)
			(layer "F.Fab")
		)
		(fp_line
			(start 0.299974 0.150114)
			(end -0.299974 0.150114)
			(stroke
				(width 0.1)
				(type default)
			)
			(layer "F.Fab")
		)
		(fp_line
			(start -0.299974 0.150114)
			(end -0.299974 -0.150114)
			(stroke
				(width 0.1)
				(type default)
			)
			(layer "F.Fab")
		)
		(pad "1" smd rect
			(at -0.2667 0 90)
			(size 0.3048 0.381)
			(layers "F.Cu" "F.Mask" "F.Paste")
			(net "P5E_CPU0_PE1_TX_C_DP<2>")
		)
		(pad "2" smd rect
			(at 0.2667 0 90)
			(size 0.3048 0.381)
			(layers "F.Cu" "F.Mask" "F.Paste")
			(net "P5E_CPU0_PE1_TX_DP<2>")
		)
	)
	(footprint ""
		(layer "F.Cu")
		(at 110.079282 -406.058116 90)
		(property "Reference" "R3495"
			(at 0 0 90)
			(layer "F.SilkS")
			(hide yes)
			(effects
				(font
					(size 1.27 1.27)
				)
			)
		)
		(property "Value" ""
			(at 0 0 90)
			(layer "F.Fab")
			(effects
				(font
					(size 1.27 1.27)
				)
			)
		)
		(duplicate_pad_numbers_are_jumpers no)
		(fp_line
			(start 0.7874 -0.4064)
			(end 0.7874 0.4064)
			(stroke
				(width 0.1524)
				(type default)
			)
			(layer "F.SilkS")
		)
		(fp_line
			(start -0.7874 -0.4064)
			(end 0.7874 -0.4064)
			(stroke
				(width 0.1524)
				(type default)
			)
			(layer "F.SilkS")
		)
		(fp_line
			(start 0.7874 0.4064)
			(end -0.7874 0.4064)
			(stroke
				(width 0.1524)
				(type default)
			)
			(layer "F.SilkS")
		)
		(fp_line
			(start -0.7874 0.4064)
			(end -0.7874 -0.4064)
			(stroke
				(width 0.1524)
				(type default)
			)
			(layer "F.SilkS")
		)
		(fp_line
			(start -0.12065 -0.305054)
			(end -0.12065 -0.2794)
			(stroke
				(width 0.1)
				(type default)
			)
			(layer "F.Fab")
		)
		(fp_line
			(start -0.67945 -0.305054)
			(end -0.12065 -0.305054)
			(stroke
				(width 0.1)
				(type default)
			)
			(layer "F.Fab")
		)
		(fp_line
			(start 0.67945 -0.3048)
			(end 0.67945 0.3048)
			(stroke
				(width 0.1)
				(type default)
			)
			(layer "F.Fab")
		)
		(fp_line
			(start 0.12065 -0.3048)
			(end 0.67945 -0.3048)
			(stroke
				(width 0.1)
				(type default)
			)
			(layer "F.Fab")
		)
		(fp_line
			(start 0.12065 -0.2794)
			(end 0.12065 -0.3048)
			(stroke
				(width 0.1)
				(type default)
			)
			(layer "F.Fab")
		)
		(fp_line
			(start -0.12065 -0.2794)
			(end 0.12065 -0.2794)
			(stroke
				(width 0.1)
				(type default)
			)
			(layer "F.Fab")
		)
		(fp_line
			(start 0.120396 0.2794)
			(end -0.12065 0.2794)
			(stroke
				(width 0.1)
				(type default)
			)
			(layer "F.Fab")
		)
		(fp_line
			(start -0.12065 0.2794)
			(end -0.12065 0.3048)
			(stroke
				(width 0.1)
				(type default)
			)
			(layer "F.Fab")
		)
		(fp_line
			(start 0.67945 0.3048)
			(end 0.120396 0.3048)
			(stroke
				(width 0.1)
				(type default)
			)
			(layer "F.Fab")
		)
		(fp_line
			(start 0.120396 0.3048)
			(end 0.120396 0.2794)
			(stroke
				(width 0.1)
				(type default)
			)
			(layer "F.Fab")
		)
		(fp_line
			(start -0.12065 0.3048)
			(end -0.67945 0.3048)
			(stroke
				(width 0.1)
				(type default)
			)
			(layer "F.Fab")
		)
		(fp_line
			(start -0.67945 0.3048)
			(end -0.67945 -0.305054)
			(stroke
				(width 0.1)
				(type default)
			)
			(layer "F.Fab")
		)
		(pad "1" smd circle
			(at -0.40005 0 90)
			(size 0 0)
			(layers "F.Cu" "F.Mask" "F.Paste")
			(net "GPU_FPGA_EROT_RECOV_BUF_R_N")
		)
		(pad "2" smd circle
			(at 0.40005 0 90)
			(size 0 0)
			(layers "F.Cu" "F.Mask" "F.Paste")
			(net "GND")
		)
	)
	(footprint ""
		(layer "F.Cu")
		(at 293.579042 -51.091338 90)
		(property "Reference" "Q127"
			(at 0.542036 -6.504432 0)
			(unlocked yes)
			(layer "F.SilkS")
			(effects
				(font
					(size 0.7874 0.5842)
					(thickness 0.1524)
				)
				(justify left)
			)
		)
		(property "Value" ""
			(at 0 0 90)
			(layer "F.Fab")
			(effects
				(font
					(size 1.27 1.27)
				)
			)
		)
		(duplicate_pad_numbers_are_jumpers no)
		(fp_line
			(start 1.332738 -1.100074)
			(end 1.332738 1.100074)
			(stroke
				(width 0.1524)
				(type default)
			)
			(layer "F.SilkS")
		)
		(fp_line
			(start 0.4826 -1.100074)
			(end 1.332738 -1.100074)
			(stroke
				(width 0.1524)
				(type default)
			)
			(layer "F.SilkS")
		)
		(fp_line
			(start -0.4826 -1.100074)
			(end 0 -0.541274)
			(stroke
				(width 0.1524)
				(type default)
			)
			(layer "F.SilkS")
		)
		(fp_line
			(start -1.332738 -1.100074)
			(end -0.4826 -1.100074)
			(stroke
				(width 0.1524)
				(type default)
			)
			(layer "F.SilkS")
		)
		(fp_line
			(start 0 -0.541274)
			(end 0.4826 -1.100074)
			(stroke
				(width 0.1524)
				(type default)
			)
			(layer "F.SilkS")
		)
		(fp_line
			(start 1.332738 1.100074)
			(end -1.332738 1.100074)
			(stroke
				(width 0.1524)
				(type default)
			)
			(layer "F.SilkS")
		)
		(fp_line
			(start -1.332738 1.100074)
			(end -1.332738 -1.100074)
			(stroke
				(width 0.1524)
				(type default)
			)
			(layer "F.SilkS")
		)
		(fp_poly
			(pts
				(xy -2.43332 -1.270254) (xy -1.731264 -0.919226) (xy -2.43332 -0.568198)
			)
			(stroke
				(width 0)
				(type default)
			)
			(fill yes)
			(layer "F.SilkS")
		)
		(fp_line
			(start 0.674878 -1.100074)
			(end 0.674878 1.100074)
			(stroke
				(width 0.1)
				(type default)
			)
			(layer "F.Fab")
		)
		(fp_line
			(start -0.674878 -1.100074)
			(end 0.674878 -1.100074)
			(stroke
				(width 0.1)
				(type default)
			)
			(layer "F.Fab")
		)
		(fp_line
			(start 0.674878 1.100074)
			(end -0.674878 1.100074)
			(stroke
				(width 0.1)
				(type default)
			)
			(layer "F.Fab")
		)
		(fp_line
			(start -0.674878 1.100074)
			(end -0.674878 -1.100074)
			(stroke
				(width 0.1)
				(type default)
			)
			(layer "F.Fab")
		)
		(fp_poly
			(pts
				(xy -2.2352 -0.298958) (xy -2.2352 -1.001014) (xy -1.533144 -0.649986)
			)
			(stroke
				(width 0)
				(type default)
			)
			(fill yes)
			(layer "F.Fab")
		)
		(pad "1" smd rect
			(at -0.94996 -0.649986 180)
			(size 0.4318 0.508)
			(layers "F.Cu" "F.Mask" "F.Paste")
			(net "GND")
		)
		(pad "2" smd rect
			(at -0.94996 0 180)
			(size 0.4318 0.508)
			(layers "F.Cu" "F.Mask" "F.Paste")
			(net "P12V_E1S_EN_0_R")
		)
		(pad "3" smd rect
			(at -0.94996 0.649986 180)
			(size 0.4318 0.508)
			(layers "F.Cu" "F.Mask" "F.Paste")
			(net "P12V_E1S_UV_0_R")
		)
		(pad "4" smd rect
			(at 0.94996 0.649986 180)
			(size 0.4318 0.508)
			(layers "F.Cu" "F.Mask" "F.Paste")
			(net "GND")
		)
		(pad "5" smd rect
			(at 0.94996 0 180)
			(size 0.4318 0.508)
			(layers "F.Cu" "F.Mask" "F.Paste")
			(net "P12V_E1S_0_EN_G")
		)
		(pad "6" smd rect
			(at 0.94996 -0.649986 180)
			(size 0.4318 0.508)
			(layers "F.Cu" "F.Mask" "F.Paste")
			(net "P12V_E1S_0_EN_G")
		)
	)
	(footprint ""
		(layer "F.Cu")
		(at 307.361336 -59.037728 90)
		(property "Reference" "U142"
			(at -0.091186 3.191764 0)
			(unlocked yes)
			(layer "F.SilkS")
			(effects
				(font
					(size 0.7874 0.5842)
					(thickness 0.1524)
				)
			)
		)
		(property "Value" ""
			(at 0 0 90)
			(layer "F.Fab")
			(effects
				(font
					(size 1.27 1.27)
				)
			)
		)
		(duplicate_pad_numbers_are_jumpers no)
		(fp_line
			(start 1.7272 -1.1176)
			(end 0.254 -1.1176)
			(stroke
				(width 0.1524)
				(type default)
			)
			(layer "F.SilkS")
		)
		(fp_line
			(start 1.7272 -1.1176)
			(end 1.7272 1.1176)
			(stroke
				(width 0.1524)
				(type default)
			)
			(layer "F.SilkS")
		)
		(fp_line
			(start 0.254 -1.1176)
			(end 0 -0.7366)
			(stroke
				(width 0.1524)
				(type default)
			)
			(layer "F.SilkS")
		)
		(fp_line
			(start -0.254 -1.1176)
			(end -1.7272 -1.1176)
			(stroke
				(width 0.1524)
				(type default)
			)
			(layer "F.SilkS")
		)
		(fp_line
			(start 0 -0.7366)
			(end -0.254 -1.1176)
			(stroke
				(width 0.1524)
				(type default)
			)
			(layer "F.SilkS")
		)
		(fp_line
			(start 1.7272 1.1176)
			(end -1.7272 1.1176)
			(stroke
				(width 0.1524)
				(type default)
			)
			(layer "F.SilkS")
		)
		(fp_line
			(start -1.7272 1.1176)
			(end -1.7272 -1.1176)
			(stroke
				(width 0.1524)
				(type default)
			)
			(layer "F.SilkS")
		)
		(fp_poly
			(pts
				(xy -1.31953 -1.375156) (xy -1.70053 -2.137156) (xy -0.93853 -2.137156)
			)
			(stroke
				(width 0)
				(type default)
			)
			(fill yes)
			(layer "F.SilkS")
		)
		(fp_line
			(start 1.5748 -1.1176)
			(end -1.5748 -1.1176)
			(stroke
				(width 0.1)
				(type default)
			)
			(layer "F.Fab")
		)
		(fp_line
			(start -1.5748 -1.1176)
			(end -1.5748 1.1176)
			(stroke
				(width 0.1)
				(type default)
			)
			(layer "F.Fab")
		)
		(fp_line
			(start 1.5748 1.1176)
			(end 1.5748 -1.1176)
			(stroke
				(width 0.1)
				(type default)
			)
			(layer "F.Fab")
		)
		(fp_line
			(start -1.5748 1.1176)
			(end 1.5748 1.1176)
			(stroke
				(width 0.1)
				(type default)
			)
			(layer "F.Fab")
		)
		(fp_poly
			(pts
				(xy -1.9558 -0.649986) (xy -2.7178 -0.268986) (xy -2.7178 -1.030986)
			)
			(stroke
				(width 0)
				(type default)
			)
			(fill yes)
			(layer "F.Fab")
		)
		(pad "1" smd rect
			(at -0.999998 -0.649986)
			(size 0.3556 1.1176)
			(layers "F.Cu" "F.Mask" "F.Paste")
			(net "PECI_BMC_B1")
		)
		(pad "2" smd rect
			(at -0.999998 0)
			(size 0.3556 1.1176)
			(layers "F.Cu" "F.Mask" "F.Paste")
			(net "GND")
		)
		(pad "3" smd rect
			(at -0.999998 0.649986)
			(size 0.3556 1.1176)
			(layers "F.Cu" "F.Mask" "F.Paste")
			(net "PECI_PCH_B1")
		)
		(pad "4" smd rect
			(at 0.999998 0.649986)
			(size 0.3556 1.1176)
			(layers "F.Cu" "F.Mask" "F.Paste")
			(net "PECI_CPU_GTL")
		)
		(pad "5" smd rect
			(at 0.999998 0)
			(size 0.3556 1.1176)
			(layers "F.Cu" "F.Mask" "F.Paste")
			(net "P3V3_AUX")
		)
		(pad "6" smd rect
			(at 0.999998 -0.649986)
			(size 0.3556 1.1176)
			(layers "F.Cu" "F.Mask" "F.Paste")
			(net "PECI_MUX_SEL_R")
		)
	)
	(footprint ""
		(layer "F.Cu")
		(at 376.658632 -71.489824)
		(property "Reference" "PC1236"
			(at 0 0 0)
			(layer "F.SilkS")
			(hide yes)
			(effects
				(font
					(size 1.27 1.27)
				)
			)
		)
		(property "Value" ""
			(at 0 0 0)
			(layer "F.Fab")
			(effects
				(font
					(size 1.27 1.27)
				)
			)
		)
		(duplicate_pad_numbers_are_jumpers no)
		(fp_line
			(start -0.7874 -0.4064)
			(end 0.7874 -0.4064)
			(stroke
				(width 0.1524)
				(type default)
			)
			(layer "F.SilkS")
		)
		(fp_line
			(start -0.7874 0.4064)
			(end -0.7874 -0.4064)
			(stroke
				(width 0.1524)
				(type default)
			)
			(layer "F.SilkS")
		)
		(fp_line
			(start 0.7874 -0.4064)
			(end 0.7874 0.4064)
			(stroke
				(width 0.1524)
				(type default)
			)
			(layer "F.SilkS")
		)
		(fp_line
			(start 0.7874 0.4064)
			(end -0.7874 0.4064)
			(stroke
				(width 0.1524)
				(type default)
			)
			(layer "F.SilkS")
		)
		(fp_line
			(start -0.67945 -0.305054)
			(end -0.12065 -0.305054)
			(stroke
				(width 0.1)
				(type default)
			)
			(layer "F.Fab")
		)
		(fp_line
			(start -0.67945 0.3048)
			(end -0.67945 -0.305054)
			(stroke
				(width 0.1)
				(type default)
			)
			(layer "F.Fab")
		)
		(fp_line
			(start -0.12065 -0.305054)
			(end -0.12065 -0.2794)
			(stroke
				(width 0.1)
				(type default)
			)
			(layer "F.Fab")
		)
		(fp_line
			(start -0.12065 -0.2794)
			(end 0.12065 -0.2794)
			(stroke
				(width 0.1)
				(type default)
			)
			(layer "F.Fab")
		)
		(fp_line
			(start -0.12065 0.2794)
			(end -0.12065 0.3048)
			(stroke
				(width 0.1)
				(type default)
			)
			(layer "F.Fab")
		)
		(fp_line
			(start -0.12065 0.3048)
			(end -0.67945 0.3048)
			(stroke
				(width 0.1)
				(type default)
			)
			(layer "F.Fab")
		)
		(fp_line
			(start 0.120396 0.2794)
			(end -0.12065 0.2794)
			(stroke
				(width 0.1)
				(type default)
			)
			(layer "F.Fab")
		)
		(fp_line
			(start 0.120396 0.3048)
			(end 0.120396 0.2794)
			(stroke
				(width 0.1)
				(type default)
			)
			(layer "F.Fab")
		)
		(fp_line
			(start 0.12065 -0.3048)
			(end 0.67945 -0.3048)
			(stroke
				(width 0.1)
				(type default)
			)
			(layer "F.Fab")
		)
		(fp_line
			(start 0.12065 -0.2794)
			(end 0.12065 -0.3048)
			(stroke
				(width 0.1)
				(type default)
			)
			(layer "F.Fab")
		)
		(fp_line
			(start 0.67945 -0.3048)
			(end 0.67945 0.3048)
			(stroke
				(width 0.1)
				(type default)
			)
			(layer "F.Fab")
		)
		(fp_line
			(start 0.67945 0.3048)
			(end 0.120396 0.3048)
			(stroke
				(width 0.1)
				(type default)
			)
			(layer "F.Fab")
		)
		(pad "1" smd circle
			(at -0.40005 0)
			(size 0 0)
			(layers "F.Cu" "F.Mask" "F.Paste")
			(net "P1V8_PCH_AUX")
		)
		(pad "2" smd circle
			(at 0.40005 0)
			(size 0 0)
			(layers "F.Cu" "F.Mask" "F.Paste")
			(net "GND")
		)
	)
	(footprint ""
		(layer "F.Cu")
		(at 295.86682 -419.02761 -90)
		(property "Reference" "C2270"
			(at 0 0 270)
			(layer "F.SilkS")
			(hide yes)
			(effects
				(font
					(size 1.27 1.27)
				)
			)
		)
		(property "Value" ""
			(at 0 0 270)
			(layer "F.Fab")
			(effects
				(font
					(size 1.27 1.27)
				)
			)
		)
		(duplicate_pad_numbers_are_jumpers no)
		(fp_line
			(start -0.7874 0.4064)
			(end -0.7874 -0.4064)
			(stroke
				(width 0.1524)
				(type default)
			)
			(layer "F.SilkS")
		)
		(fp_line
			(start 0.7874 0.4064)
			(end -0.7874 0.4064)
			(stroke
				(width 0.1524)
				(type default)
			)
			(layer "F.SilkS")
		)
		(fp_line
			(start -0.7874 -0.4064)
			(end 0.7874 -0.4064)
			(stroke
				(width 0.1524)
				(type default)
			)
			(layer "F.SilkS")
		)
		(fp_line
			(start 0.7874 -0.4064)
			(end 0.7874 0.4064)
			(stroke
				(width 0.1524)
				(type default)
			)
			(layer "F.SilkS")
		)
		(fp_line
			(start -0.67945 0.3048)
			(end -0.67945 -0.305054)
			(stroke
				(width 0.1)
				(type default)
			)
			(layer "F.Fab")
		)
		(fp_line
			(start -0.12065 0.3048)
			(end -0.67945 0.3048)
			(stroke
				(width 0.1)
				(type default)
			)
			(layer "F.Fab")
		)
		(fp_line
			(start 0.120396 0.3048)
			(end 0.120396 0.2794)
			(stroke
				(width 0.1)
				(type default)
			)
			(layer "F.Fab")
		)
		(fp_line
			(start 0.67945 0.3048)
			(end 0.120396 0.3048)
			(stroke
				(width 0.1)
				(type default)
			)
			(layer "F.Fab")
		)
		(fp_line
			(start -0.12065 0.2794)
			(end -0.12065 0.3048)
			(stroke
				(width 0.1)
				(type default)
			)
			(layer "F.Fab")
		)
		(fp_line
			(start 0.120396 0.2794)
			(end -0.12065 0.2794)
			(stroke
				(width 0.1)
				(type default)
			)
			(layer "F.Fab")
		)
		(fp_line
			(start -0.12065 -0.2794)
			(end 0.12065 -0.2794)
			(stroke
				(width 0.1)
				(type default)
			)
			(layer "F.Fab")
		)
		(fp_line
			(start 0.12065 -0.2794)
			(end 0.12065 -0.3048)
			(stroke
				(width 0.1)
				(type default)
			)
			(layer "F.Fab")
		)
		(fp_line
			(start 0.12065 -0.3048)
			(end 0.67945 -0.3048)
			(stroke
				(width 0.1)
				(type default)
			)
			(layer "F.Fab")
		)
		(fp_line
			(start 0.67945 -0.3048)
			(end 0.67945 0.3048)
			(stroke
				(width 0.1)
				(type default)
			)
			(layer "F.Fab")
		)
		(fp_line
			(start -0.67945 -0.305054)
			(end -0.12065 -0.305054)
			(stroke
				(width 0.1)
				(type default)
			)
			(layer "F.Fab")
		)
		(fp_line
			(start -0.12065 -0.305054)
			(end -0.12065 -0.2794)
			(stroke
				(width 0.1)
				(type default)
			)
			(layer "F.Fab")
		)
		(pad "1" smd circle
			(at -0.40005 0 270)
			(size 0 0)
			(layers "F.Cu" "F.Mask" "F.Paste")
			(net "PRSNT_CABLE_GPU_A1_ISO_N")
		)
		(pad "2" smd circle
			(at 0.40005 0 270)
			(size 0 0)
			(layers "F.Cu" "F.Mask" "F.Paste")
			(net "GND")
		)
	)
	(footprint ""
		(layer "F.Cu")
		(at 184.58688 -418.06876 90)
		(property "Reference" "R4794"
			(at 0 0 90)
			(layer "F.SilkS")
			(hide yes)
			(effects
				(font
					(size 1.27 1.27)
				)
			)
		)
		(property "Value" ""
			(at 0 0 90)
			(layer "F.Fab")
			(effects
				(font
					(size 1.27 1.27)
				)
			)
		)
		(duplicate_pad_numbers_are_jumpers no)
		(fp_line
			(start 0.7874 -0.4064)
			(end 0.7874 0.4064)
			(stroke
				(width 0.1524)
				(type default)
			)
			(layer "F.SilkS")
		)
		(fp_line
			(start -0.7874 -0.4064)
			(end 0.7874 -0.4064)
			(stroke
				(width 0.1524)
				(type default)
			)
			(layer "F.SilkS")
		)
		(fp_line
			(start 0.7874 0.4064)
			(end -0.7874 0.4064)
			(stroke
				(width 0.1524)
				(type default)
			)
			(layer "F.SilkS")
		)
		(fp_line
			(start -0.7874 0.4064)
			(end -0.7874 -0.4064)
			(stroke
				(width 0.1524)
				(type default)
			)
			(layer "F.SilkS")
		)
		(fp_line
			(start -0.12065 -0.305054)
			(end -0.12065 -0.2794)
			(stroke
				(width 0.1)
				(type default)
			)
			(layer "F.Fab")
		)
		(fp_line
			(start -0.67945 -0.305054)
			(end -0.12065 -0.305054)
			(stroke
				(width 0.1)
				(type default)
			)
			(layer "F.Fab")
		)
		(fp_line
			(start 0.67945 -0.3048)
			(end 0.67945 0.3048)
			(stroke
				(width 0.1)
				(type default)
			)
			(layer "F.Fab")
		)
		(fp_line
			(start 0.12065 -0.3048)
			(end 0.67945 -0.3048)
			(stroke
				(width 0.1)
				(type default)
			)
			(layer "F.Fab")
		)
		(fp_line
			(start 0.12065 -0.2794)
			(end 0.12065 -0.3048)
			(stroke
				(width 0.1)
				(type default)
			)
			(layer "F.Fab")
		)
		(fp_line
			(start -0.12065 -0.2794)
			(end 0.12065 -0.2794)
			(stroke
				(width 0.1)
				(type default)
			)
			(layer "F.Fab")
		)
		(fp_line
			(start 0.120396 0.2794)
			(end -0.12065 0.2794)
			(stroke
				(width 0.1)
				(type default)
			)
			(layer "F.Fab")
		)
		(fp_line
			(start -0.12065 0.2794)
			(end -0.12065 0.3048)
			(stroke
				(width 0.1)
				(type default)
			)
			(layer "F.Fab")
		)
		(fp_line
			(start 0.67945 0.3048)
			(end 0.120396 0.3048)
			(stroke
				(width 0.1)
				(type default)
			)
			(layer "F.Fab")
		)
		(fp_line
			(start 0.120396 0.3048)
			(end 0.120396 0.2794)
			(stroke
				(width 0.1)
				(type default)
			)
			(layer "F.Fab")
		)
		(fp_line
			(start -0.12065 0.3048)
			(end -0.67945 0.3048)
			(stroke
				(width 0.1)
				(type default)
			)
			(layer "F.Fab")
		)
		(fp_line
			(start -0.67945 0.3048)
			(end -0.67945 -0.305054)
			(stroke
				(width 0.1)
				(type default)
			)
			(layer "F.Fab")
		)
		(pad "1" smd circle
			(at -0.40005 0 90)
			(size 0 0)
			(layers "F.Cu" "F.Mask" "F.Paste")
			(net "HSC_D_OC_R2")
		)
		(pad "2" smd circle
			(at 0.40005 0 90)
			(size 0 0)
			(layers "F.Cu" "F.Mask" "F.Paste")
			(net "A_HSC_LOW_GATE")
		)
	)
	(footprint ""
		(layer "F.Cu")
		(at 113.494312 -136.520682)
		(property "Reference" "R2268"
			(at 0 0 0)
			(layer "F.SilkS")
			(hide yes)
			(effects
				(font
					(size 1.27 1.27)
				)
			)
		)
		(property "Value" ""
			(at 0 0 0)
			(layer "F.Fab")
			(effects
				(font
					(size 1.27 1.27)
				)
			)
		)
		(duplicate_pad_numbers_are_jumpers no)
		(fp_line
			(start -0.7874 -0.4064)
			(end 0.7874 -0.4064)
			(stroke
				(width 0.1524)
				(type default)
			)
			(layer "F.SilkS")
		)
		(fp_line
			(start -0.7874 0.4064)
			(end -0.7874 -0.4064)
			(stroke
				(width 0.1524)
				(type default)
			)
			(layer "F.SilkS")
		)
		(fp_line
			(start 0.7874 -0.4064)
			(end 0.7874 0.4064)
			(stroke
				(width 0.1524)
				(type default)
			)
			(layer "F.SilkS")
		)
		(fp_line
			(start 0.7874 0.4064)
			(end -0.7874 0.4064)
			(stroke
				(width 0.1524)
				(type default)
			)
			(layer "F.SilkS")
		)
		(fp_line
			(start -0.67945 -0.305054)
			(end -0.12065 -0.305054)
			(stroke
				(width 0.1)
				(type default)
			)
			(layer "F.Fab")
		)
		(fp_line
			(start -0.67945 0.3048)
			(end -0.67945 -0.305054)
			(stroke
				(width 0.1)
				(type default)
			)
			(layer "F.Fab")
		)
		(fp_line
			(start -0.12065 -0.305054)
			(end -0.12065 -0.2794)
			(stroke
				(width 0.1)
				(type default)
			)
			(layer "F.Fab")
		)
		(fp_line
			(start -0.12065 -0.2794)
			(end 0.12065 -0.2794)
			(stroke
				(width 0.1)
				(type default)
			)
			(layer "F.Fab")
		)
		(fp_line
			(start -0.12065 0.2794)
			(end -0.12065 0.3048)
			(stroke
				(width 0.1)
				(type default)
			)
			(layer "F.Fab")
		)
		(fp_line
			(start -0.12065 0.3048)
			(end -0.67945 0.3048)
			(stroke
				(width 0.1)
				(type default)
			)
			(layer "F.Fab")
		)
		(fp_line
			(start 0.120396 0.2794)
			(end -0.12065 0.2794)
			(stroke
				(width 0.1)
				(type default)
			)
			(layer "F.Fab")
		)
		(fp_line
			(start 0.120396 0.3048)
			(end 0.120396 0.2794)
			(stroke
				(width 0.1)
				(type default)
			)
			(layer "F.Fab")
		)
		(fp_line
			(start 0.12065 -0.3048)
			(end 0.67945 -0.3048)
			(stroke
				(width 0.1)
				(type default)
			)
			(layer "F.Fab")
		)
		(fp_line
			(start 0.12065 -0.2794)
			(end 0.12065 -0.3048)
			(stroke
				(width 0.1)
				(type default)
			)
			(layer "F.Fab")
		)
		(fp_line
			(start 0.67945 -0.3048)
			(end 0.67945 0.3048)
			(stroke
				(width 0.1)
				(type default)
			)
			(layer "F.Fab")
		)
		(fp_line
			(start 0.67945 0.3048)
			(end 0.120396 0.3048)
			(stroke
				(width 0.1)
				(type default)
			)
			(layer "F.Fab")
		)
		(pad "1" smd circle
			(at -0.40005 0)
			(size 0 0)
			(layers "F.Cu" "F.Mask" "F.Paste")
			(net "RST_SMB_SWITCH_N")
		)
		(pad "2" smd circle
			(at 0.40005 0)
			(size 0 0)
			(layers "F.Cu" "F.Mask" "F.Paste")
			(net "PU_RST_SMB_PCIE0_N")
		)
	)
	(footprint ""
		(layer "F.Cu")
		(at 69.923406 -160.499806)
		(property "Reference" "PC1595"
			(at 0 0 0)
			(layer "F.SilkS")
			(hide yes)
			(effects
				(font
					(size 1.27 1.27)
				)
			)
		)
		(property "Value" ""
			(at 0 0 0)
			(layer "F.Fab")
			(effects
				(font
					(size 1.27 1.27)
				)
			)
		)
		(duplicate_pad_numbers_are_jumpers no)
		(fp_line
			(start 2.750058 0.999998)
			(end -2.750058 0.999998)
			(stroke
				(width 0.1524)
				(type default)
			)
			(layer "F.SilkS")
		)
		(fp_circle
			(center 0 0.999998)
			(end 2.750058 0.999998)
			(stroke
				(width 0.1524)
				(type default)
			)
			(fill no)
			(layer "F.SilkS")
		)
		(fp_poly
			(pts
				(arc
					(start 2.750058 0.999998)
					(mid 0 3.750056)
					(end -2.750058 0.999998)
				)
			)
			(stroke
				(width 0)
				(type default)
			)
			(fill yes)
			(layer "F.SilkS")
		)
		(fp_circle
			(center 0 0.999998)
			(end 2.750058 0.999998)
			(stroke
				(width 0.1)
				(type default)
			)
			(fill no)
			(layer "F.Fab")
		)
		(pad "1" thru_hole rect
			(at 0 0)
			(size 1.5748 1.5748)
			(drill 1.0668)
			(layers "*.Cu" "*.Mask")
			(remove_unused_layers no)
			(net "PVCCINFAON_CPU1")
			(clearance 0)
			(padstack
				(mode front_inner_back)
				(layer "Inner"
					(shape circle)
					(size 1.5748 1.5748)
					(clearance 0)
				)
				(layer "B.Cu"
					(shape rect)
					(size 1.5748 1.5748)
					(clearance 0)
				)
			)
		)
		(pad "2" thru_hole circle
			(at 0 1.999996)
			(size 1.5748 1.5748)
			(drill 1.0668)
			(layers "*.Cu" "*.Mask")
			(remove_unused_layers no)
			(net "GND")
			(clearance 0)
		)
	)
	(footprint ""
		(layer "F.Cu")
		(at 108.016802 -96.317054)
		(property "Reference" "Q76"
			(at 2.043938 -1.909064 0)
			(unlocked yes)
			(layer "F.SilkS")
			(effects
				(font
					(size 0.7874 0.5842)
					(thickness 0.1524)
				)
				(justify left)
			)
		)
		(property "Value" ""
			(at 0 0 0)
			(layer "F.Fab")
			(effects
				(font
					(size 1.27 1.27)
				)
			)
		)
		(duplicate_pad_numbers_are_jumpers no)
		(fp_line
			(start -1.332738 -1.100074)
			(end -0.4826 -1.100074)
			(stroke
				(width 0.1524)
				(type default)
			)
			(layer "F.SilkS")
		)
		(fp_line
			(start -1.332738 1.100074)
			(end -1.332738 -1.100074)
			(stroke
				(width 0.1524)
				(type default)
			)
			(layer "F.SilkS")
		)
		(fp_line
			(start -0.4826 -1.100074)
			(end 0 -0.541274)
			(stroke
				(width 0.1524)
				(type default)
			)
			(layer "F.SilkS")
		)
		(fp_line
			(start 0 -0.541274)
			(end 0.4826 -1.100074)
			(stroke
				(width 0.1524)
				(type default)
			)
			(layer "F.SilkS")
		)
		(fp_line
			(start 0.4826 -1.100074)
			(end 1.332738 -1.100074)
			(stroke
				(width 0.1524)
				(type default)
			)
			(layer "F.SilkS")
		)
		(fp_line
			(start 1.332738 -1.100074)
			(end 1.332738 1.100074)
			(stroke
				(width 0.1524)
				(type default)
			)
			(layer "F.SilkS")
		)
		(fp_line
			(start 1.332738 1.100074)
			(end -1.332738 1.100074)
			(stroke
				(width 0.1524)
				(type default)
			)
			(layer "F.SilkS")
		)
		(fp_poly
			(pts
				(xy -0.673862 -2.001012) (xy -1.02489 -1.298956) (xy -1.375918 -2.001012)
			)
			(stroke
				(width 0)
				(type default)
			)
			(fill yes)
			(layer "F.SilkS")
		)
		(fp_line
			(start -0.674878 -1.100074)
			(end 0.674878 -1.100074)
			(stroke
				(width 0.1)
				(type default)
			)
			(layer "F.Fab")
		)
		(fp_line
			(start -0.674878 1.100074)
			(end -0.674878 -1.100074)
			(stroke
				(width 0.1)
				(type default)
			)
			(layer "F.Fab")
		)
		(fp_line
			(start 0.674878 -1.100074)
			(end 0.674878 1.100074)
			(stroke
				(width 0.1)
				(type default)
			)
			(layer "F.Fab")
		)
		(fp_line
			(start 0.674878 1.100074)
			(end -0.674878 1.100074)
			(stroke
				(width 0.1)
				(type default)
			)
			(layer "F.Fab")
		)
		(fp_poly
			(pts
				(xy -2.2352 -0.298958) (xy -2.2352 -1.001014) (xy -1.533144 -0.649986)
			)
			(stroke
				(width 0)
				(type default)
			)
			(fill yes)
			(layer "F.Fab")
		)
		(pad "1" smd rect
			(at -0.94996 -0.649986 90)
			(size 0.4318 0.508)
			(layers "F.Cu" "F.Mask" "F.Paste")
			(net "GND")
		)
		(pad "2" smd rect
			(at -0.94996 0 90)
			(size 0.4318 0.508)
			(layers "F.Cu" "F.Mask" "F.Paste")
			(net "PWRGD_P1V8_PCH_AUX")
		)
		(pad "3" smd rect
			(at -0.94996 0.649986 90)
			(size 0.4318 0.508)
			(layers "F.Cu" "F.Mask" "F.Paste")
			(net "LED_PWRGD_P1V05_PCH_AUX_D")
		)
		(pad "4" smd rect
			(at 0.94996 0.649986 90)
			(size 0.4318 0.508)
			(layers "F.Cu" "F.Mask" "F.Paste")
			(net "GND")
		)
		(pad "5" smd rect
			(at 0.94996 0 90)
			(size 0.4318 0.508)
			(layers "F.Cu" "F.Mask" "F.Paste")
			(net "PWRGD_P1V05_PCH_AUX")
		)
		(pad "6" smd rect
			(at 0.94996 -0.649986 90)
			(size 0.4318 0.508)
			(layers "F.Cu" "F.Mask" "F.Paste")
			(net "LED_PWRGD_P1V8_PCH_AUX_D")
		)
	)
	(footprint ""
		(layer "F.Cu")
		(at 128.016 -61.432948 180)
		(property "Reference" "R4634"
			(at 0 0 180)
			(layer "F.SilkS")
			(hide yes)
			(effects
				(font
					(size 1.27 1.27)
				)
			)
		)
		(property "Value" ""
			(at 0 0 180)
			(layer "F.Fab")
			(effects
				(font
					(size 1.27 1.27)
				)
			)
		)
		(duplicate_pad_numbers_are_jumpers no)
		(fp_line
			(start 0.7874 0.4064)
			(end -0.7874 0.4064)
			(stroke
				(width 0.1524)
				(type default)
			)
			(layer "F.SilkS")
		)
		(fp_line
			(start 0.7874 -0.4064)
			(end 0.7874 0.4064)
			(stroke
				(width 0.1524)
				(type default)
			)
			(layer "F.SilkS")
		)
		(fp_line
			(start -0.7874 0.4064)
			(end -0.7874 -0.4064)
			(stroke
				(width 0.1524)
				(type default)
			)
			(layer "F.SilkS")
		)
		(fp_line
			(start -0.7874 -0.4064)
			(end 0.7874 -0.4064)
			(stroke
				(width 0.1524)
				(type default)
			)
			(layer "F.SilkS")
		)
		(fp_line
			(start 0.67945 0.3048)
			(end 0.120396 0.3048)
			(stroke
				(width 0.1)
				(type default)
			)
			(layer "F.Fab")
		)
		(fp_line
			(start 0.67945 -0.3048)
			(end 0.67945 0.3048)
			(stroke
				(width 0.1)
				(type default)
			)
			(layer "F.Fab")
		)
		(fp_line
			(start 0.12065 -0.2794)
			(end 0.12065 -0.3048)
			(stroke
				(width 0.1)
				(type default)
			)
			(layer "F.Fab")
		)
		(fp_line
			(start 0.12065 -0.3048)
			(end 0.67945 -0.3048)
			(stroke
				(width 0.1)
				(type default)
			)
			(layer "F.Fab")
		)
		(fp_line
			(start 0.120396 0.3048)
			(end 0.120396 0.2794)
			(stroke
				(width 0.1)
				(type default)
			)
			(layer "F.Fab")
		)
		(fp_line
			(start 0.120396 0.2794)
			(end -0.12065 0.2794)
			(stroke
				(width 0.1)
				(type default)
			)
			(layer "F.Fab")
		)
		(fp_line
			(start -0.12065 0.3048)
			(end -0.67945 0.3048)
			(stroke
				(width 0.1)
				(type default)
			)
			(layer "F.Fab")
		)
		(fp_line
			(start -0.12065 0.2794)
			(end -0.12065 0.3048)
			(stroke
				(width 0.1)
				(type default)
			)
			(layer "F.Fab")
		)
		(fp_line
			(start -0.12065 -0.2794)
			(end 0.12065 -0.2794)
			(stroke
				(width 0.1)
				(type default)
			)
			(layer "F.Fab")
		)
		(fp_line
			(start -0.12065 -0.305054)
			(end -0.12065 -0.2794)
			(stroke
				(width 0.1)
				(type default)
			)
			(layer "F.Fab")
		)
		(fp_line
			(start -0.67945 0.3048)
			(end -0.67945 -0.305054)
			(stroke
				(width 0.1)
				(type default)
			)
			(layer "F.Fab")
		)
		(fp_line
			(start -0.67945 -0.305054)
			(end -0.12065 -0.305054)
			(stroke
				(width 0.1)
				(type default)
			)
			(layer "F.Fab")
		)
		(pad "1" smd circle
			(at -0.40005 0 180)
			(size 0 0)
			(layers "F.Cu" "F.Mask" "F.Paste")
			(net "P3V3_AUX")
		)
		(pad "2" smd circle
			(at 0.40005 0 180)
			(size 0 0)
			(layers "F.Cu" "F.Mask" "F.Paste")
			(net "JTAG_BMC_SW_OE")
		)
	)
	(footprint ""
		(layer "F.Cu")
		(at 27.03068 -125.368812 180)
		(property "Reference" "PC2367"
			(at 0 0 180)
			(layer "F.SilkS")
			(hide yes)
			(effects
				(font
					(size 1.27 1.27)
				)
			)
		)
		(property "Value" ""
			(at 0 0 180)
			(layer "F.Fab")
			(effects
				(font
					(size 1.27 1.27)
				)
			)
		)
		(duplicate_pad_numbers_are_jumpers no)
		(fp_line
			(start 0.7874 0.4064)
			(end -0.7874 0.4064)
			(stroke
				(width 0.1524)
				(type default)
			)
			(layer "F.SilkS")
		)
		(fp_line
			(start 0.7874 -0.4064)
			(end 0.7874 0.4064)
			(stroke
				(width 0.1524)
				(type default)
			)
			(layer "F.SilkS")
		)
		(fp_line
			(start -0.7874 0.4064)
			(end -0.7874 -0.4064)
			(stroke
				(width 0.1524)
				(type default)
			)
			(layer "F.SilkS")
		)
		(fp_line
			(start -0.7874 -0.4064)
			(end 0.7874 -0.4064)
			(stroke
				(width 0.1524)
				(type default)
			)
			(layer "F.SilkS")
		)
		(fp_line
			(start 0.67945 0.3048)
			(end 0.120396 0.3048)
			(stroke
				(width 0.1)
				(type default)
			)
			(layer "F.Fab")
		)
		(fp_line
			(start 0.67945 -0.3048)
			(end 0.67945 0.3048)
			(stroke
				(width 0.1)
				(type default)
			)
			(layer "F.Fab")
		)
		(fp_line
			(start 0.12065 -0.2794)
			(end 0.12065 -0.3048)
			(stroke
				(width 0.1)
				(type default)
			)
			(layer "F.Fab")
		)
		(fp_line
			(start 0.12065 -0.3048)
			(end 0.67945 -0.3048)
			(stroke
				(width 0.1)
				(type default)
			)
			(layer "F.Fab")
		)
		(fp_line
			(start 0.120396 0.3048)
			(end 0.120396 0.2794)
			(stroke
				(width 0.1)
				(type default)
			)
			(layer "F.Fab")
		)
		(fp_line
			(start 0.120396 0.2794)
			(end -0.12065 0.2794)
			(stroke
				(width 0.1)
				(type default)
			)
			(layer "F.Fab")
		)
		(fp_line
			(start -0.12065 0.3048)
			(end -0.67945 0.3048)
			(stroke
				(width 0.1)
				(type default)
			)
			(layer "F.Fab")
		)
		(fp_line
			(start -0.12065 0.2794)
			(end -0.12065 0.3048)
			(stroke
				(width 0.1)
				(type default)
			)
			(layer "F.Fab")
		)
		(fp_line
			(start -0.12065 -0.2794)
			(end 0.12065 -0.2794)
			(stroke
				(width 0.1)
				(type default)
			)
			(layer "F.Fab")
		)
		(fp_line
			(start -0.12065 -0.305054)
			(end -0.12065 -0.2794)
			(stroke
				(width 0.1)
				(type default)
			)
			(layer "F.Fab")
		)
		(fp_line
			(start -0.67945 0.3048)
			(end -0.67945 -0.305054)
			(stroke
				(width 0.1)
				(type default)
			)
			(layer "F.Fab")
		)
		(fp_line
			(start -0.67945 -0.305054)
			(end -0.12065 -0.305054)
			(stroke
				(width 0.1)
				(type default)
			)
			(layer "F.Fab")
		)
		(pad "1" smd circle
			(at -0.40005 0 180)
			(size 0 0)
			(layers "F.Cu" "F.Mask" "F.Paste")
			(net "PVCCINFAON_CPU1_VCC")
		)
		(pad "2" smd circle
			(at 0.40005 0 180)
			(size 0 0)
			(layers "F.Cu" "F.Mask" "F.Paste")
			(net "GND")
		)
	)
	(footprint ""
		(layer "F.Cu")
		(at 136.3853 -115.38458 180)
		(property "Reference" "R4757"
			(at 0 0 180)
			(layer "F.SilkS")
			(hide yes)
			(effects
				(font
					(size 1.27 1.27)
				)
			)
		)
		(property "Value" ""
			(at 0 0 180)
			(layer "F.Fab")
			(effects
				(font
					(size 1.27 1.27)
				)
			)
		)
		(duplicate_pad_numbers_are_jumpers no)
		(fp_line
			(start 0.7874 0.4064)
			(end -0.7874 0.4064)
			(stroke
				(width 0.1524)
				(type default)
			)
			(layer "F.SilkS")
		)
		(fp_line
			(start 0.7874 -0.4064)
			(end 0.7874 0.4064)
			(stroke
				(width 0.1524)
				(type default)
			)
			(layer "F.SilkS")
		)
		(fp_line
			(start -0.7874 0.4064)
			(end -0.7874 -0.4064)
			(stroke
				(width 0.1524)
				(type default)
			)
			(layer "F.SilkS")
		)
		(fp_line
			(start -0.7874 -0.4064)
			(end 0.7874 -0.4064)
			(stroke
				(width 0.1524)
				(type default)
			)
			(layer "F.SilkS")
		)
		(fp_line
			(start 0.67945 0.3048)
			(end 0.120396 0.3048)
			(stroke
				(width 0.1)
				(type default)
			)
			(layer "F.Fab")
		)
		(fp_line
			(start 0.67945 -0.3048)
			(end 0.67945 0.3048)
			(stroke
				(width 0.1)
				(type default)
			)
			(layer "F.Fab")
		)
		(fp_line
			(start 0.12065 -0.2794)
			(end 0.12065 -0.3048)
			(stroke
				(width 0.1)
				(type default)
			)
			(layer "F.Fab")
		)
		(fp_line
			(start 0.12065 -0.3048)
			(end 0.67945 -0.3048)
			(stroke
				(width 0.1)
				(type default)
			)
			(layer "F.Fab")
		)
		(fp_line
			(start 0.120396 0.3048)
			(end 0.120396 0.2794)
			(stroke
				(width 0.1)
				(type default)
			)
			(layer "F.Fab")
		)
		(fp_line
			(start 0.120396 0.2794)
			(end -0.12065 0.2794)
			(stroke
				(width 0.1)
				(type default)
			)
			(layer "F.Fab")
		)
		(fp_line
			(start -0.12065 0.3048)
			(end -0.67945 0.3048)
			(stroke
				(width 0.1)
				(type default)
			)
			(layer "F.Fab")
		)
		(fp_line
			(start -0.12065 0.2794)
			(end -0.12065 0.3048)
			(stroke
				(width 0.1)
				(type default)
			)
			(layer "F.Fab")
		)
		(fp_line
			(start -0.12065 -0.2794)
			(end 0.12065 -0.2794)
			(stroke
				(width 0.1)
				(type default)
			)
			(layer "F.Fab")
		)
		(fp_line
			(start -0.12065 -0.305054)
			(end -0.12065 -0.2794)
			(stroke
				(width 0.1)
				(type default)
			)
			(layer "F.Fab")
		)
		(fp_line
			(start -0.67945 0.3048)
			(end -0.67945 -0.305054)
			(stroke
				(width 0.1)
				(type default)
			)
			(layer "F.Fab")
		)
		(fp_line
			(start -0.67945 -0.305054)
			(end -0.12065 -0.305054)
			(stroke
				(width 0.1)
				(type default)
			)
			(layer "F.Fab")
		)
		(pad "1" smd circle
			(at -0.40005 0 180)
			(size 0 0)
			(layers "F.Cu" "F.Mask" "F.Paste")
			(net "HP_LVC3_OCP_V3_2_PWRGD_R2")
		)
		(pad "2" smd circle
			(at 0.40005 0 180)
			(size 0 0)
			(layers "F.Cu" "F.Mask" "F.Paste")
			(net "OCP_V3_2_AUX_PWR_EN_R2")
		)
	)
	(footprint ""
		(layer "F.Cu")
		(at 125.048518 -333.804514 -90)
		(property "Reference" "PC529_P1_4"
			(at 0 0 270)
			(layer "F.SilkS")
			(hide yes)
			(effects
				(font
					(size 1.27 1.27)
				)
			)
		)
		(property "Value" ""
			(at 0 0 270)
			(layer "F.Fab")
			(effects
				(font
					(size 1.27 1.27)
				)
			)
		)
		(duplicate_pad_numbers_are_jumpers no)
		(fp_line
			(start -0.7874 0.4064)
			(end -0.7874 -0.4064)
			(stroke
				(width 0.1524)
				(type default)
			)
			(layer "F.SilkS")
		)
		(fp_line
			(start 0.7874 0.4064)
			(end -0.7874 0.4064)
			(stroke
				(width 0.1524)
				(type default)
			)
			(layer "F.SilkS")
		)
		(fp_line
			(start -0.7874 -0.4064)
			(end 0.7874 -0.4064)
			(stroke
				(width 0.1524)
				(type default)
			)
			(layer "F.SilkS")
		)
		(fp_line
			(start 0.7874 -0.4064)
			(end 0.7874 0.4064)
			(stroke
				(width 0.1524)
				(type default)
			)
			(layer "F.SilkS")
		)
		(fp_line
			(start -0.67945 0.3048)
			(end -0.67945 -0.305054)
			(stroke
				(width 0.1)
				(type default)
			)
			(layer "F.Fab")
		)
		(fp_line
			(start -0.12065 0.3048)
			(end -0.67945 0.3048)
			(stroke
				(width 0.1)
				(type default)
			)
			(layer "F.Fab")
		)
		(fp_line
			(start 0.120396 0.3048)
			(end 0.120396 0.2794)
			(stroke
				(width 0.1)
				(type default)
			)
			(layer "F.Fab")
		)
		(fp_line
			(start 0.67945 0.3048)
			(end 0.120396 0.3048)
			(stroke
				(width 0.1)
				(type default)
			)
			(layer "F.Fab")
		)
		(fp_line
			(start -0.12065 0.2794)
			(end -0.12065 0.3048)
			(stroke
				(width 0.1)
				(type default)
			)
			(layer "F.Fab")
		)
		(fp_line
			(start 0.120396 0.2794)
			(end -0.12065 0.2794)
			(stroke
				(width 0.1)
				(type default)
			)
			(layer "F.Fab")
		)
		(fp_line
			(start -0.12065 -0.2794)
			(end 0.12065 -0.2794)
			(stroke
				(width 0.1)
				(type default)
			)
			(layer "F.Fab")
		)
		(fp_line
			(start 0.12065 -0.2794)
			(end 0.12065 -0.3048)
			(stroke
				(width 0.1)
				(type default)
			)
			(layer "F.Fab")
		)
		(fp_line
			(start 0.12065 -0.3048)
			(end 0.67945 -0.3048)
			(stroke
				(width 0.1)
				(type default)
			)
			(layer "F.Fab")
		)
		(fp_line
			(start 0.67945 -0.3048)
			(end 0.67945 0.3048)
			(stroke
				(width 0.1)
				(type default)
			)
			(layer "F.Fab")
		)
		(fp_line
			(start -0.67945 -0.305054)
			(end -0.12065 -0.305054)
			(stroke
				(width 0.1)
				(type default)
			)
			(layer "F.Fab")
		)
		(fp_line
			(start -0.12065 -0.305054)
			(end -0.12065 -0.2794)
			(stroke
				(width 0.1)
				(type default)
			)
			(layer "F.Fab")
		)
		(pad "1" smd circle
			(at -0.40005 0 270)
			(size 0 0)
			(layers "F.Cu" "F.Mask" "F.Paste")
			(net "SW_P12V_PVCCIN_CPU1_FLT")
		)
		(pad "2" smd circle
			(at 0.40005 0 270)
			(size 0 0)
			(layers "F.Cu" "F.Mask" "F.Paste")
			(net "GND")
		)
	)
	(footprint ""
		(layer "F.Cu")
		(at 347.754448 -402.371052 -90)
		(property "Reference" "C1792"
			(at 0 0 270)
			(layer "F.SilkS")
			(hide yes)
			(effects
				(font
					(size 1.27 1.27)
				)
			)
		)
		(property "Value" ""
			(at 0 0 270)
			(layer "F.Fab")
			(effects
				(font
					(size 1.27 1.27)
				)
			)
		)
		(duplicate_pad_numbers_are_jumpers no)
		(fp_line
			(start -0.299974 0.150114)
			(end -0.299974 -0.150114)
			(stroke
				(width 0.1)
				(type default)
			)
			(layer "F.Fab")
		)
		(fp_line
			(start 0.299974 0.150114)
			(end -0.299974 0.150114)
			(stroke
				(width 0.1)
				(type default)
			)
			(layer "F.Fab")
		)
		(fp_line
			(start -0.299974 -0.150114)
			(end 0.299974 -0.150114)
			(stroke
				(width 0.1)
				(type default)
			)
			(layer "F.Fab")
		)
		(fp_line
			(start 0.299974 -0.150114)
			(end 0.299974 0.150114)
			(stroke
				(width 0.1)
				(type default)
			)
			(layer "F.Fab")
		)
		(pad "1" smd rect
			(at -0.2667 0 270)
			(size 0.3048 0.381)
			(layers "F.Cu" "F.Mask" "F.Paste")
			(net "P5E_CPU0_PE4_TX_C_DP<14>")
		)
		(pad "2" smd rect
			(at 0.2667 0 270)
			(size 0.3048 0.381)
			(layers "F.Cu" "F.Mask" "F.Paste")
			(net "P5E_CPU0_PE4_TX_DP<14>")
		)
	)
	(footprint ""
		(layer "F.Cu")
		(at 304.058828 -364.929928)
		(property "Reference" "PC1669"
			(at 0 0 0)
			(layer "F.SilkS")
			(hide yes)
			(effects
				(font
					(size 1.27 1.27)
				)
			)
		)
		(property "Value" ""
			(at 0 0 0)
			(layer "F.Fab")
			(effects
				(font
					(size 1.27 1.27)
				)
			)
		)
		(duplicate_pad_numbers_are_jumpers no)
		(fp_line
			(start -1.524 -0.762)
			(end 1.524 -0.762)
			(stroke
				(width 0.1524)
				(type default)
			)
			(layer "F.SilkS")
		)
		(fp_line
			(start -1.524 0.762)
			(end -1.524 -0.762)
			(stroke
				(width 0.1524)
				(type default)
			)
			(layer "F.SilkS")
		)
		(fp_line
			(start 1.524 -0.762)
			(end 1.524 0.762)
			(stroke
				(width 0.1524)
				(type default)
			)
			(layer "F.SilkS")
		)
		(fp_line
			(start 1.524 0.762)
			(end -1.524 0.762)
			(stroke
				(width 0.1524)
				(type default)
			)
			(layer "F.SilkS")
		)
		(fp_line
			(start -1.1049 -0.724916)
			(end -1.1049 0.724916)
			(stroke
				(width 0.1)
				(type default)
			)
			(layer "F.Fab")
		)
		(fp_line
			(start -1.1049 0.724916)
			(end 1.1049 0.724916)
			(stroke
				(width 0.1)
				(type default)
			)
			(layer "F.Fab")
		)
		(fp_line
			(start 1.1049 -0.724916)
			(end -1.1049 -0.724916)
			(stroke
				(width 0.1)
				(type default)
			)
			(layer "F.Fab")
		)
		(fp_line
			(start 1.1049 0.724916)
			(end 1.1049 -0.724916)
			(stroke
				(width 0.1)
				(type default)
			)
			(layer "F.Fab")
		)
		(pad "1" smd rect
			(at -0.889 0 180)
			(size 1.016 1.27)
			(layers "F.Cu" "F.Mask" "F.Paste")
			(net "SW_P12V_PVCCFA_EHV_FIVRA_CPU0_L")
		)
		(pad "2" smd rect
			(at 0.889 0 180)
			(size 1.016 1.27)
			(layers "F.Cu" "F.Mask" "F.Paste")
			(net "GND")
		)
	)
	(footprint ""
		(layer "F.Cu")
		(at 78.160626 -151.210772)
		(property "Reference" "R665"
			(at 0 0 0)
			(layer "F.SilkS")
			(hide yes)
			(effects
				(font
					(size 1.27 1.27)
				)
			)
		)
		(property "Value" ""
			(at 0 0 0)
			(layer "F.Fab")
			(effects
				(font
					(size 1.27 1.27)
				)
			)
		)
		(duplicate_pad_numbers_are_jumpers no)
		(fp_line
			(start -0.7874 -0.4064)
			(end 0.7874 -0.4064)
			(stroke
				(width 0.1524)
				(type default)
			)
			(layer "F.SilkS")
		)
		(fp_line
			(start -0.7874 0.4064)
			(end -0.7874 -0.4064)
			(stroke
				(width 0.1524)
				(type default)
			)
			(layer "F.SilkS")
		)
		(fp_line
			(start 0.7874 -0.4064)
			(end 0.7874 0.4064)
			(stroke
				(width 0.1524)
				(type default)
			)
			(layer "F.SilkS")
		)
		(fp_line
			(start 0.7874 0.4064)
			(end -0.7874 0.4064)
			(stroke
				(width 0.1524)
				(type default)
			)
			(layer "F.SilkS")
		)
		(fp_line
			(start -0.67945 -0.305054)
			(end -0.12065 -0.305054)
			(stroke
				(width 0.1)
				(type default)
			)
			(layer "F.Fab")
		)
		(fp_line
			(start -0.67945 0.3048)
			(end -0.67945 -0.305054)
			(stroke
				(width 0.1)
				(type default)
			)
			(layer "F.Fab")
		)
		(fp_line
			(start -0.12065 -0.305054)
			(end -0.12065 -0.2794)
			(stroke
				(width 0.1)
				(type default)
			)
			(layer "F.Fab")
		)
		(fp_line
			(start -0.12065 -0.2794)
			(end 0.12065 -0.2794)
			(stroke
				(width 0.1)
				(type default)
			)
			(layer "F.Fab")
		)
		(fp_line
			(start -0.12065 0.2794)
			(end -0.12065 0.3048)
			(stroke
				(width 0.1)
				(type default)
			)
			(layer "F.Fab")
		)
		(fp_line
			(start -0.12065 0.3048)
			(end -0.67945 0.3048)
			(stroke
				(width 0.1)
				(type default)
			)
			(layer "F.Fab")
		)
		(fp_line
			(start 0.120396 0.2794)
			(end -0.12065 0.2794)
			(stroke
				(width 0.1)
				(type default)
			)
			(layer "F.Fab")
		)
		(fp_line
			(start 0.120396 0.3048)
			(end 0.120396 0.2794)
			(stroke
				(width 0.1)
				(type default)
			)
			(layer "F.Fab")
		)
		(fp_line
			(start 0.12065 -0.3048)
			(end 0.67945 -0.3048)
			(stroke
				(width 0.1)
				(type default)
			)
			(layer "F.Fab")
		)
		(fp_line
			(start 0.12065 -0.2794)
			(end 0.12065 -0.3048)
			(stroke
				(width 0.1)
				(type default)
			)
			(layer "F.Fab")
		)
		(fp_line
			(start 0.67945 -0.3048)
			(end 0.67945 0.3048)
			(stroke
				(width 0.1)
				(type default)
			)
			(layer "F.Fab")
		)
		(fp_line
			(start 0.67945 0.3048)
			(end 0.120396 0.3048)
			(stroke
				(width 0.1)
				(type default)
			)
			(layer "F.Fab")
		)
		(pad "1" smd circle
			(at -0.40005 0)
			(size 0 0)
			(layers "F.Cu" "F.Mask" "F.Paste")
			(net "I3C_SPD_DDRABCD_CPU1_R_SCL")
		)
		(pad "2" smd circle
			(at 0.40005 0)
			(size 0 0)
			(layers "F.Cu" "F.Mask" "F.Paste")
			(net "I3C_SPD_DDRABCD_CPU1_LVC1_R_SCL")
		)
	)
	(footprint ""
		(layer "F.Cu")
		(at 197.41388 -104.955848)
		(property "Reference" "R1206"
			(at 0 0 0)
			(layer "F.SilkS")
			(hide yes)
			(effects
				(font
					(size 1.27 1.27)
				)
			)
		)
		(property "Value" ""
			(at 0 0 0)
			(layer "F.Fab")
			(effects
				(font
					(size 1.27 1.27)
				)
			)
		)
		(duplicate_pad_numbers_are_jumpers no)
		(fp_line
			(start -0.7874 -0.4064)
			(end 0.7874 -0.4064)
			(stroke
				(width 0.1524)
				(type default)
			)
			(layer "F.SilkS")
		)
		(fp_line
			(start -0.7874 0.4064)
			(end -0.7874 -0.4064)
			(stroke
				(width 0.1524)
				(type default)
			)
			(layer "F.SilkS")
		)
		(fp_line
			(start 0.7874 -0.4064)
			(end 0.7874 0.4064)
			(stroke
				(width 0.1524)
				(type default)
			)
			(layer "F.SilkS")
		)
		(fp_line
			(start 0.7874 0.4064)
			(end -0.7874 0.4064)
			(stroke
				(width 0.1524)
				(type default)
			)
			(layer "F.SilkS")
		)
		(fp_line
			(start -0.67945 -0.305054)
			(end -0.12065 -0.305054)
			(stroke
				(width 0.1)
				(type default)
			)
			(layer "F.Fab")
		)
		(fp_line
			(start -0.67945 0.3048)
			(end -0.67945 -0.305054)
			(stroke
				(width 0.1)
				(type default)
			)
			(layer "F.Fab")
		)
		(fp_line
			(start -0.12065 -0.305054)
			(end -0.12065 -0.2794)
			(stroke
				(width 0.1)
				(type default)
			)
			(layer "F.Fab")
		)
		(fp_line
			(start -0.12065 -0.2794)
			(end 0.12065 -0.2794)
			(stroke
				(width 0.1)
				(type default)
			)
			(layer "F.Fab")
		)
		(fp_line
			(start -0.12065 0.2794)
			(end -0.12065 0.3048)
			(stroke
				(width 0.1)
				(type default)
			)
			(layer "F.Fab")
		)
		(fp_line
			(start -0.12065 0.3048)
			(end -0.67945 0.3048)
			(stroke
				(width 0.1)
				(type default)
			)
			(layer "F.Fab")
		)
		(fp_line
			(start 0.120396 0.2794)
			(end -0.12065 0.2794)
			(stroke
				(width 0.1)
				(type default)
			)
			(layer "F.Fab")
		)
		(fp_line
			(start 0.120396 0.3048)
			(end 0.120396 0.2794)
			(stroke
				(width 0.1)
				(type default)
			)
			(layer "F.Fab")
		)
		(fp_line
			(start 0.12065 -0.3048)
			(end 0.67945 -0.3048)
			(stroke
				(width 0.1)
				(type default)
			)
			(layer "F.Fab")
		)
		(fp_line
			(start 0.12065 -0.2794)
			(end 0.12065 -0.3048)
			(stroke
				(width 0.1)
				(type default)
			)
			(layer "F.Fab")
		)
		(fp_line
			(start 0.67945 -0.3048)
			(end 0.67945 0.3048)
			(stroke
				(width 0.1)
				(type default)
			)
			(layer "F.Fab")
		)
		(fp_line
			(start 0.67945 0.3048)
			(end 0.120396 0.3048)
			(stroke
				(width 0.1)
				(type default)
			)
			(layer "F.Fab")
		)
		(pad "1" smd circle
			(at -0.40005 0)
			(size 0 0)
			(layers "F.Cu" "F.Mask" "F.Paste")
			(net "RST_MB_STBY_R_N")
		)
		(pad "2" smd circle
			(at 0.40005 0)
			(size 0 0)
			(layers "F.Cu" "F.Mask" "F.Paste")
			(net "RST_MB_STBY_N")
		)
	)
	(footprint ""
		(layer "F.Cu")
		(at 172.77588 -126.964948 90)
		(property "Reference" "R1404"
			(at 0 0 90)
			(layer "F.SilkS")
			(hide yes)
			(effects
				(font
					(size 1.27 1.27)
				)
			)
		)
		(property "Value" ""
			(at 0 0 90)
			(layer "F.Fab")
			(effects
				(font
					(size 1.27 1.27)
				)
			)
		)
		(duplicate_pad_numbers_are_jumpers no)
		(fp_line
			(start 0.7874 -0.4064)
			(end 0.7874 0.4064)
			(stroke
				(width 0.1524)
				(type default)
			)
			(layer "F.SilkS")
		)
		(fp_line
			(start -0.7874 -0.4064)
			(end 0.7874 -0.4064)
			(stroke
				(width 0.1524)
				(type default)
			)
			(layer "F.SilkS")
		)
		(fp_line
			(start 0.7874 0.4064)
			(end -0.7874 0.4064)
			(stroke
				(width 0.1524)
				(type default)
			)
			(layer "F.SilkS")
		)
		(fp_line
			(start -0.7874 0.4064)
			(end -0.7874 -0.4064)
			(stroke
				(width 0.1524)
				(type default)
			)
			(layer "F.SilkS")
		)
		(fp_line
			(start -0.12065 -0.305054)
			(end -0.12065 -0.2794)
			(stroke
				(width 0.1)
				(type default)
			)
			(layer "F.Fab")
		)
		(fp_line
			(start -0.67945 -0.305054)
			(end -0.12065 -0.305054)
			(stroke
				(width 0.1)
				(type default)
			)
			(layer "F.Fab")
		)
		(fp_line
			(start 0.67945 -0.3048)
			(end 0.67945 0.3048)
			(stroke
				(width 0.1)
				(type default)
			)
			(layer "F.Fab")
		)
		(fp_line
			(start 0.12065 -0.3048)
			(end 0.67945 -0.3048)
			(stroke
				(width 0.1)
				(type default)
			)
			(layer "F.Fab")
		)
		(fp_line
			(start 0.12065 -0.2794)
			(end 0.12065 -0.3048)
			(stroke
				(width 0.1)
				(type default)
			)
			(layer "F.Fab")
		)
		(fp_line
			(start -0.12065 -0.2794)
			(end 0.12065 -0.2794)
			(stroke
				(width 0.1)
				(type default)
			)
			(layer "F.Fab")
		)
		(fp_line
			(start 0.120396 0.2794)
			(end -0.12065 0.2794)
			(stroke
				(width 0.1)
				(type default)
			)
			(layer "F.Fab")
		)
		(fp_line
			(start -0.12065 0.2794)
			(end -0.12065 0.3048)
			(stroke
				(width 0.1)
				(type default)
			)
			(layer "F.Fab")
		)
		(fp_line
			(start 0.67945 0.3048)
			(end 0.120396 0.3048)
			(stroke
				(width 0.1)
				(type default)
			)
			(layer "F.Fab")
		)
		(fp_line
			(start 0.120396 0.3048)
			(end 0.120396 0.2794)
			(stroke
				(width 0.1)
				(type default)
			)
			(layer "F.Fab")
		)
		(fp_line
			(start -0.12065 0.3048)
			(end -0.67945 0.3048)
			(stroke
				(width 0.1)
				(type default)
			)
			(layer "F.Fab")
		)
		(fp_line
			(start -0.67945 0.3048)
			(end -0.67945 -0.305054)
			(stroke
				(width 0.1)
				(type default)
			)
			(layer "F.Fab")
		)
		(pad "1" smd circle
			(at -0.40005 0 90)
			(size 0 0)
			(layers "F.Cu" "F.Mask" "F.Paste")
			(net "FM_PCH_P1V8_AUX_EN")
		)
		(pad "2" smd circle
			(at 0.40005 0 90)
			(size 0 0)
			(layers "F.Cu" "F.Mask" "F.Paste")
			(net "GND")
		)
	)
	(footprint ""
		(layer "F.Cu")
		(at 303.65573 -346.239084 180)
		(property "Reference" "PR587"
			(at 0 0 180)
			(layer "F.SilkS")
			(hide yes)
			(effects
				(font
					(size 1.27 1.27)
				)
			)
		)
		(property "Value" ""
			(at 0 0 180)
			(layer "F.Fab")
			(effects
				(font
					(size 1.27 1.27)
				)
			)
		)
		(duplicate_pad_numbers_are_jumpers no)
		(fp_line
			(start 0.7874 0.4064)
			(end -0.7874 0.4064)
			(stroke
				(width 0.1524)
				(type default)
			)
			(layer "F.SilkS")
		)
		(fp_line
			(start 0.7874 -0.4064)
			(end 0.7874 0.4064)
			(stroke
				(width 0.1524)
				(type default)
			)
			(layer "F.SilkS")
		)
		(fp_line
			(start -0.7874 0.4064)
			(end -0.7874 -0.4064)
			(stroke
				(width 0.1524)
				(type default)
			)
			(layer "F.SilkS")
		)
		(fp_line
			(start -0.7874 -0.4064)
			(end 0.7874 -0.4064)
			(stroke
				(width 0.1524)
				(type default)
			)
			(layer "F.SilkS")
		)
		(fp_line
			(start 0.67945 0.3048)
			(end 0.120396 0.3048)
			(stroke
				(width 0.1)
				(type default)
			)
			(layer "F.Fab")
		)
		(fp_line
			(start 0.67945 -0.3048)
			(end 0.67945 0.3048)
			(stroke
				(width 0.1)
				(type default)
			)
			(layer "F.Fab")
		)
		(fp_line
			(start 0.12065 -0.2794)
			(end 0.12065 -0.3048)
			(stroke
				(width 0.1)
				(type default)
			)
			(layer "F.Fab")
		)
		(fp_line
			(start 0.12065 -0.3048)
			(end 0.67945 -0.3048)
			(stroke
				(width 0.1)
				(type default)
			)
			(layer "F.Fab")
		)
		(fp_line
			(start 0.120396 0.3048)
			(end 0.120396 0.2794)
			(stroke
				(width 0.1)
				(type default)
			)
			(layer "F.Fab")
		)
		(fp_line
			(start 0.120396 0.2794)
			(end -0.12065 0.2794)
			(stroke
				(width 0.1)
				(type default)
			)
			(layer "F.Fab")
		)
		(fp_line
			(start -0.12065 0.3048)
			(end -0.67945 0.3048)
			(stroke
				(width 0.1)
				(type default)
			)
			(layer "F.Fab")
		)
		(fp_line
			(start -0.12065 0.2794)
			(end -0.12065 0.3048)
			(stroke
				(width 0.1)
				(type default)
			)
			(layer "F.Fab")
		)
		(fp_line
			(start -0.12065 -0.2794)
			(end 0.12065 -0.2794)
			(stroke
				(width 0.1)
				(type default)
			)
			(layer "F.Fab")
		)
		(fp_line
			(start -0.12065 -0.305054)
			(end -0.12065 -0.2794)
			(stroke
				(width 0.1)
				(type default)
			)
			(layer "F.Fab")
		)
		(fp_line
			(start -0.67945 0.3048)
			(end -0.67945 -0.305054)
			(stroke
				(width 0.1)
				(type default)
			)
			(layer "F.Fab")
		)
		(fp_line
			(start -0.67945 -0.305054)
			(end -0.12065 -0.305054)
			(stroke
				(width 0.1)
				(type default)
			)
			(layer "F.Fab")
		)
		(pad "1" smd circle
			(at -0.40005 0 180)
			(size 0 0)
			(layers "F.Cu" "F.Mask" "F.Paste")
			(net "VSENSE_PVCCFA_EHV_FIVRA_CPU0_DP")
		)
		(pad "2" smd circle
			(at 0.40005 0 180)
			(size 0 0)
			(layers "F.Cu" "F.Mask" "F.Paste")
			(net "PVCCFA_EHV_FIVRA_CPU0")
		)
	)
	(footprint ""
		(layer "F.Cu")
		(at 50.437542 -166.847266)
		(property "Reference" "PC376"
			(at 0 0 0)
			(layer "F.SilkS")
			(hide yes)
			(effects
				(font
					(size 1.27 1.27)
				)
			)
		)
		(property "Value" ""
			(at 0 0 0)
			(layer "F.Fab")
			(effects
				(font
					(size 1.27 1.27)
				)
			)
		)
		(duplicate_pad_numbers_are_jumpers no)
		(fp_line
			(start -0.7874 -0.4064)
			(end 0.7874 -0.4064)
			(stroke
				(width 0.1524)
				(type default)
			)
			(layer "F.SilkS")
		)
		(fp_line
			(start -0.7874 0.4064)
			(end -0.7874 -0.4064)
			(stroke
				(width 0.1524)
				(type default)
			)
			(layer "F.SilkS")
		)
		(fp_line
			(start 0.7874 -0.4064)
			(end 0.7874 0.4064)
			(stroke
				(width 0.1524)
				(type default)
			)
			(layer "F.SilkS")
		)
		(fp_line
			(start 0.7874 0.4064)
			(end -0.7874 0.4064)
			(stroke
				(width 0.1524)
				(type default)
			)
			(layer "F.SilkS")
		)
		(fp_line
			(start -0.67945 -0.305054)
			(end -0.12065 -0.305054)
			(stroke
				(width 0.1)
				(type default)
			)
			(layer "F.Fab")
		)
		(fp_line
			(start -0.67945 0.3048)
			(end -0.67945 -0.305054)
			(stroke
				(width 0.1)
				(type default)
			)
			(layer "F.Fab")
		)
		(fp_line
			(start -0.12065 -0.305054)
			(end -0.12065 -0.2794)
			(stroke
				(width 0.1)
				(type default)
			)
			(layer "F.Fab")
		)
		(fp_line
			(start -0.12065 -0.2794)
			(end 0.12065 -0.2794)
			(stroke
				(width 0.1)
				(type default)
			)
			(layer "F.Fab")
		)
		(fp_line
			(start -0.12065 0.2794)
			(end -0.12065 0.3048)
			(stroke
				(width 0.1)
				(type default)
			)
			(layer "F.Fab")
		)
		(fp_line
			(start -0.12065 0.3048)
			(end -0.67945 0.3048)
			(stroke
				(width 0.1)
				(type default)
			)
			(layer "F.Fab")
		)
		(fp_line
			(start 0.120396 0.2794)
			(end -0.12065 0.2794)
			(stroke
				(width 0.1)
				(type default)
			)
			(layer "F.Fab")
		)
		(fp_line
			(start 0.120396 0.3048)
			(end 0.120396 0.2794)
			(stroke
				(width 0.1)
				(type default)
			)
			(layer "F.Fab")
		)
		(fp_line
			(start 0.12065 -0.3048)
			(end 0.67945 -0.3048)
			(stroke
				(width 0.1)
				(type default)
			)
			(layer "F.Fab")
		)
		(fp_line
			(start 0.12065 -0.2794)
			(end 0.12065 -0.3048)
			(stroke
				(width 0.1)
				(type default)
			)
			(layer "F.Fab")
		)
		(fp_line
			(start 0.67945 -0.3048)
			(end 0.67945 0.3048)
			(stroke
				(width 0.1)
				(type default)
			)
			(layer "F.Fab")
		)
		(fp_line
			(start 0.67945 0.3048)
			(end 0.120396 0.3048)
			(stroke
				(width 0.1)
				(type default)
			)
			(layer "F.Fab")
		)
		(pad "1" smd circle
			(at -0.40005 0)
			(size 0 0)
			(layers "F.Cu" "F.Mask" "F.Paste")
			(net "SW_PVCCD_HV_CPU1_BOOT1_R")
		)
		(pad "2" smd circle
			(at 0.40005 0)
			(size 0 0)
			(layers "F.Cu" "F.Mask" "F.Paste")
			(net "SW_PVCCD_HV_CPU1_BOOTR1")
		)
	)
	(footprint ""
		(layer "F.Cu")
		(at 179.12588 -133.695948 -90)
		(property "Reference" "R1448"
			(at 0 0 270)
			(layer "F.SilkS")
			(hide yes)
			(effects
				(font
					(size 1.27 1.27)
				)
			)
		)
		(property "Value" ""
			(at 0 0 270)
			(layer "F.Fab")
			(effects
				(font
					(size 1.27 1.27)
				)
			)
		)
		(duplicate_pad_numbers_are_jumpers no)
		(fp_line
			(start -0.7874 0.4064)
			(end -0.7874 -0.4064)
			(stroke
				(width 0.1524)
				(type default)
			)
			(layer "F.SilkS")
		)
		(fp_line
			(start 0.7874 0.4064)
			(end -0.7874 0.4064)
			(stroke
				(width 0.1524)
				(type default)
			)
			(layer "F.SilkS")
		)
		(fp_line
			(start -0.7874 -0.4064)
			(end 0.7874 -0.4064)
			(stroke
				(width 0.1524)
				(type default)
			)
			(layer "F.SilkS")
		)
		(fp_line
			(start 0.7874 -0.4064)
			(end 0.7874 0.4064)
			(stroke
				(width 0.1524)
				(type default)
			)
			(layer "F.SilkS")
		)
		(fp_line
			(start -0.67945 0.3048)
			(end -0.67945 -0.305054)
			(stroke
				(width 0.1)
				(type default)
			)
			(layer "F.Fab")
		)
		(fp_line
			(start -0.12065 0.3048)
			(end -0.67945 0.3048)
			(stroke
				(width 0.1)
				(type default)
			)
			(layer "F.Fab")
		)
		(fp_line
			(start 0.120396 0.3048)
			(end 0.120396 0.2794)
			(stroke
				(width 0.1)
				(type default)
			)
			(layer "F.Fab")
		)
		(fp_line
			(start 0.67945 0.3048)
			(end 0.120396 0.3048)
			(stroke
				(width 0.1)
				(type default)
			)
			(layer "F.Fab")
		)
		(fp_line
			(start -0.12065 0.2794)
			(end -0.12065 0.3048)
			(stroke
				(width 0.1)
				(type default)
			)
			(layer "F.Fab")
		)
		(fp_line
			(start 0.120396 0.2794)
			(end -0.12065 0.2794)
			(stroke
				(width 0.1)
				(type default)
			)
			(layer "F.Fab")
		)
		(fp_line
			(start -0.12065 -0.2794)
			(end 0.12065 -0.2794)
			(stroke
				(width 0.1)
				(type default)
			)
			(layer "F.Fab")
		)
		(fp_line
			(start 0.12065 -0.2794)
			(end 0.12065 -0.3048)
			(stroke
				(width 0.1)
				(type default)
			)
			(layer "F.Fab")
		)
		(fp_line
			(start 0.12065 -0.3048)
			(end 0.67945 -0.3048)
			(stroke
				(width 0.1)
				(type default)
			)
			(layer "F.Fab")
		)
		(fp_line
			(start 0.67945 -0.3048)
			(end 0.67945 0.3048)
			(stroke
				(width 0.1)
				(type default)
			)
			(layer "F.Fab")
		)
		(fp_line
			(start -0.67945 -0.305054)
			(end -0.12065 -0.305054)
			(stroke
				(width 0.1)
				(type default)
			)
			(layer "F.Fab")
		)
		(fp_line
			(start -0.12065 -0.305054)
			(end -0.12065 -0.2794)
			(stroke
				(width 0.1)
				(type default)
			)
			(layer "F.Fab")
		)
		(pad "1" smd circle
			(at -0.40005 0 270)
			(size 0 0)
			(layers "F.Cu" "F.Mask" "F.Paste")
			(net "FM_CPU1_SKTOCC_LVT3_N")
		)
		(pad "2" smd circle
			(at 0.40005 0 270)
			(size 0 0)
			(layers "F.Cu" "F.Mask" "F.Paste")
			(net "FM_CPU1_SKTOCC_LVT3_PLD_N")
		)
	)
	(footprint ""
		(layer "F.Cu")
		(at 298.16552 -407.6954)
		(property "Reference" "R4684"
			(at 0 0 0)
			(layer "F.SilkS")
			(hide yes)
			(effects
				(font
					(size 1.27 1.27)
				)
			)
		)
		(property "Value" ""
			(at 0 0 0)
			(layer "F.Fab")
			(effects
				(font
					(size 1.27 1.27)
				)
			)
		)
		(duplicate_pad_numbers_are_jumpers no)
		(fp_line
			(start -0.7874 -0.4064)
			(end 0.7874 -0.4064)
			(stroke
				(width 0.1524)
				(type default)
			)
			(layer "F.SilkS")
		)
		(fp_line
			(start -0.7874 0.4064)
			(end -0.7874 -0.4064)
			(stroke
				(width 0.1524)
				(type default)
			)
			(layer "F.SilkS")
		)
		(fp_line
			(start 0.7874 -0.4064)
			(end 0.7874 0.4064)
			(stroke
				(width 0.1524)
				(type default)
			)
			(layer "F.SilkS")
		)
		(fp_line
			(start 0.7874 0.4064)
			(end -0.7874 0.4064)
			(stroke
				(width 0.1524)
				(type default)
			)
			(layer "F.SilkS")
		)
		(fp_line
			(start -0.67945 -0.305054)
			(end -0.12065 -0.305054)
			(stroke
				(width 0.1)
				(type default)
			)
			(layer "F.Fab")
		)
		(fp_line
			(start -0.67945 0.3048)
			(end -0.67945 -0.305054)
			(stroke
				(width 0.1)
				(type default)
			)
			(layer "F.Fab")
		)
		(fp_line
			(start -0.12065 -0.305054)
			(end -0.12065 -0.2794)
			(stroke
				(width 0.1)
				(type default)
			)
			(layer "F.Fab")
		)
		(fp_line
			(start -0.12065 -0.2794)
			(end 0.12065 -0.2794)
			(stroke
				(width 0.1)
				(type default)
			)
			(layer "F.Fab")
		)
		(fp_line
			(start -0.12065 0.2794)
			(end -0.12065 0.3048)
			(stroke
				(width 0.1)
				(type default)
			)
			(layer "F.Fab")
		)
		(fp_line
			(start -0.12065 0.3048)
			(end -0.67945 0.3048)
			(stroke
				(width 0.1)
				(type default)
			)
			(layer "F.Fab")
		)
		(fp_line
			(start 0.120396 0.2794)
			(end -0.12065 0.2794)
			(stroke
				(width 0.1)
				(type default)
			)
			(layer "F.Fab")
		)
		(fp_line
			(start 0.120396 0.3048)
			(end 0.120396 0.2794)
			(stroke
				(width 0.1)
				(type default)
			)
			(layer "F.Fab")
		)
		(fp_line
			(start 0.12065 -0.3048)
			(end 0.67945 -0.3048)
			(stroke
				(width 0.1)
				(type default)
			)
			(layer "F.Fab")
		)
		(fp_line
			(start 0.12065 -0.2794)
			(end 0.12065 -0.3048)
			(stroke
				(width 0.1)
				(type default)
			)
			(layer "F.Fab")
		)
		(fp_line
			(start 0.67945 -0.3048)
			(end 0.67945 0.3048)
			(stroke
				(width 0.1)
				(type default)
			)
			(layer "F.Fab")
		)
		(fp_line
			(start 0.67945 0.3048)
			(end 0.120396 0.3048)
			(stroke
				(width 0.1)
				(type default)
			)
			(layer "F.Fab")
		)
		(pad "1" smd circle
			(at -0.40005 0)
			(size 0 0)
			(layers "F.Cu" "F.Mask" "F.Paste")
			(net "P12V_HSC_TEMP_ALERT_N")
		)
		(pad "2" smd circle
			(at 0.40005 0)
			(size 0 0)
			(layers "F.Cu" "F.Mask" "F.Paste")
			(net "P12V_HSC_TEMP_ALERT_R_N")
		)
	)
	(footprint ""
		(layer "F.Cu")
		(at 118.542816 -241.97691 -90)
		(property "Reference" "C254"
			(at 0 0 270)
			(layer "F.SilkS")
			(hide yes)
			(effects
				(font
					(size 1.27 1.27)
				)
			)
		)
		(property "Value" ""
			(at 0 0 270)
			(layer "F.Fab")
			(effects
				(font
					(size 1.27 1.27)
				)
			)
		)
		(duplicate_pad_numbers_are_jumpers no)
		(fp_line
			(start -0.7874 0.4064)
			(end -0.7874 -0.4064)
			(stroke
				(width 0.1524)
				(type default)
			)
			(layer "F.SilkS")
		)
		(fp_line
			(start 0.7874 0.4064)
			(end -0.7874 0.4064)
			(stroke
				(width 0.1524)
				(type default)
			)
			(layer "F.SilkS")
		)
		(fp_line
			(start -0.7874 -0.4064)
			(end 0.7874 -0.4064)
			(stroke
				(width 0.1524)
				(type default)
			)
			(layer "F.SilkS")
		)
		(fp_line
			(start 0.7874 -0.4064)
			(end 0.7874 0.4064)
			(stroke
				(width 0.1524)
				(type default)
			)
			(layer "F.SilkS")
		)
		(fp_line
			(start -0.67945 0.3048)
			(end -0.67945 -0.305054)
			(stroke
				(width 0.1)
				(type default)
			)
			(layer "F.Fab")
		)
		(fp_line
			(start -0.12065 0.3048)
			(end -0.67945 0.3048)
			(stroke
				(width 0.1)
				(type default)
			)
			(layer "F.Fab")
		)
		(fp_line
			(start 0.120396 0.3048)
			(end 0.120396 0.2794)
			(stroke
				(width 0.1)
				(type default)
			)
			(layer "F.Fab")
		)
		(fp_line
			(start 0.67945 0.3048)
			(end 0.120396 0.3048)
			(stroke
				(width 0.1)
				(type default)
			)
			(layer "F.Fab")
		)
		(fp_line
			(start -0.12065 0.2794)
			(end -0.12065 0.3048)
			(stroke
				(width 0.1)
				(type default)
			)
			(layer "F.Fab")
		)
		(fp_line
			(start 0.120396 0.2794)
			(end -0.12065 0.2794)
			(stroke
				(width 0.1)
				(type default)
			)
			(layer "F.Fab")
		)
		(fp_line
			(start -0.12065 -0.2794)
			(end 0.12065 -0.2794)
			(stroke
				(width 0.1)
				(type default)
			)
			(layer "F.Fab")
		)
		(fp_line
			(start 0.12065 -0.2794)
			(end 0.12065 -0.3048)
			(stroke
				(width 0.1)
				(type default)
			)
			(layer "F.Fab")
		)
		(fp_line
			(start 0.12065 -0.3048)
			(end 0.67945 -0.3048)
			(stroke
				(width 0.1)
				(type default)
			)
			(layer "F.Fab")
		)
		(fp_line
			(start 0.67945 -0.3048)
			(end 0.67945 0.3048)
			(stroke
				(width 0.1)
				(type default)
			)
			(layer "F.Fab")
		)
		(fp_line
			(start -0.67945 -0.305054)
			(end -0.12065 -0.305054)
			(stroke
				(width 0.1)
				(type default)
			)
			(layer "F.Fab")
		)
		(fp_line
			(start -0.12065 -0.305054)
			(end -0.12065 -0.2794)
			(stroke
				(width 0.1)
				(type default)
			)
			(layer "F.Fab")
		)
		(pad "1" smd circle
			(at -0.40005 0 270)
			(size 0 0)
			(layers "F.Cu" "F.Mask" "F.Paste")
			(net "PVCCIN_CPU1")
		)
		(pad "2" smd circle
			(at 0.40005 0 270)
			(size 0 0)
			(layers "F.Cu" "F.Mask" "F.Paste")
			(net "GND")
		)
	)
	(footprint ""
		(layer "F.Cu")
		(at 420.124128 -166.499286 -90)
		(property "Reference" "PC191_P0_1"
			(at 0 0 270)
			(layer "F.SilkS")
			(hide yes)
			(effects
				(font
					(size 1.27 1.27)
				)
			)
		)
		(property "Value" ""
			(at 0 0 270)
			(layer "F.Fab")
			(effects
				(font
					(size 1.27 1.27)
				)
			)
		)
		(duplicate_pad_numbers_are_jumpers no)
		(fp_line
			(start -0.7874 0.4064)
			(end -0.7874 -0.4064)
			(stroke
				(width 0.1524)
				(type default)
			)
			(layer "F.SilkS")
		)
		(fp_line
			(start 0.7874 0.4064)
			(end -0.7874 0.4064)
			(stroke
				(width 0.1524)
				(type default)
			)
			(layer "F.SilkS")
		)
		(fp_line
			(start -0.7874 -0.4064)
			(end 0.7874 -0.4064)
			(stroke
				(width 0.1524)
				(type default)
			)
			(layer "F.SilkS")
		)
		(fp_line
			(start 0.7874 -0.4064)
			(end 0.7874 0.4064)
			(stroke
				(width 0.1524)
				(type default)
			)
			(layer "F.SilkS")
		)
		(fp_line
			(start -0.67945 0.3048)
			(end -0.67945 -0.305054)
			(stroke
				(width 0.1)
				(type default)
			)
			(layer "F.Fab")
		)
		(fp_line
			(start -0.12065 0.3048)
			(end -0.67945 0.3048)
			(stroke
				(width 0.1)
				(type default)
			)
			(layer "F.Fab")
		)
		(fp_line
			(start 0.120396 0.3048)
			(end 0.120396 0.2794)
			(stroke
				(width 0.1)
				(type default)
			)
			(layer "F.Fab")
		)
		(fp_line
			(start 0.67945 0.3048)
			(end 0.120396 0.3048)
			(stroke
				(width 0.1)
				(type default)
			)
			(layer "F.Fab")
		)
		(fp_line
			(start -0.12065 0.2794)
			(end -0.12065 0.3048)
			(stroke
				(width 0.1)
				(type default)
			)
			(layer "F.Fab")
		)
		(fp_line
			(start 0.120396 0.2794)
			(end -0.12065 0.2794)
			(stroke
				(width 0.1)
				(type default)
			)
			(layer "F.Fab")
		)
		(fp_line
			(start -0.12065 -0.2794)
			(end 0.12065 -0.2794)
			(stroke
				(width 0.1)
				(type default)
			)
			(layer "F.Fab")
		)
		(fp_line
			(start 0.12065 -0.2794)
			(end 0.12065 -0.3048)
			(stroke
				(width 0.1)
				(type default)
			)
			(layer "F.Fab")
		)
		(fp_line
			(start 0.12065 -0.3048)
			(end 0.67945 -0.3048)
			(stroke
				(width 0.1)
				(type default)
			)
			(layer "F.Fab")
		)
		(fp_line
			(start 0.67945 -0.3048)
			(end 0.67945 0.3048)
			(stroke
				(width 0.1)
				(type default)
			)
			(layer "F.Fab")
		)
		(fp_line
			(start -0.67945 -0.305054)
			(end -0.12065 -0.305054)
			(stroke
				(width 0.1)
				(type default)
			)
			(layer "F.Fab")
		)
		(fp_line
			(start -0.12065 -0.305054)
			(end -0.12065 -0.2794)
			(stroke
				(width 0.1)
				(type default)
			)
			(layer "F.Fab")
		)
		(pad "1" smd circle
			(at -0.40005 0 270)
			(size 0 0)
			(layers "F.Cu" "F.Mask" "F.Paste")
			(net "SW_P12V_PVCCINFAON_CPU0_FLT")
		)
		(pad "2" smd circle
			(at 0.40005 0 270)
			(size 0 0)
			(layers "F.Cu" "F.Mask" "F.Paste")
			(net "GND")
		)
	)
	(footprint ""
		(layer "F.Cu")
		(at 103.85552 -31.731458 180)
		(property "Reference" "U235"
			(at 1.59766 -2.717292 0)
			(unlocked yes)
			(layer "F.SilkS")
			(effects
				(font
					(size 0.7874 0.5842)
					(thickness 0.1524)
				)
				(justify left)
			)
		)
		(property "Value" ""
			(at 0 0 180)
			(layer "F.Fab")
			(effects
				(font
					(size 1.27 1.27)
				)
			)
		)
		(duplicate_pad_numbers_are_jumpers no)
		(fp_line
			(start 1.463548 1.549908)
			(end -1.463548 1.549908)
			(stroke
				(width 0.1524)
				(type default)
			)
			(layer "F.SilkS")
		)
		(fp_line
			(start 1.463548 -1.549908)
			(end 1.463548 1.549908)
			(stroke
				(width 0.1524)
				(type default)
			)
			(layer "F.SilkS")
		)
		(fp_line
			(start 0.762 -1.549908)
			(end 1.463548 -1.549908)
			(stroke
				(width 0.1524)
				(type default)
			)
			(layer "F.SilkS")
		)
		(fp_line
			(start 0 -0.762)
			(end 0.762 -1.549908)
			(stroke
				(width 0.1524)
				(type default)
			)
			(layer "F.SilkS")
		)
		(fp_line
			(start -0.787908 -1.549908)
			(end 0 -0.762)
			(stroke
				(width 0.1524)
				(type default)
			)
			(layer "F.SilkS")
		)
		(fp_line
			(start -1.463548 1.549908)
			(end -1.463548 -1.549908)
			(stroke
				(width 0.1524)
				(type default)
			)
			(layer "F.SilkS")
		)
		(fp_line
			(start -1.463548 -1.549908)
			(end -0.787908 -1.549908)
			(stroke
				(width 0.1524)
				(type default)
			)
			(layer "F.SilkS")
		)
		(fp_poly
			(pts
				(xy -2.84988 -1.050036) (xy -3.46964 -0.740156) (xy -3.46964 -1.359916)
			)
			(stroke
				(width 0)
				(type default)
			)
			(fill yes)
			(layer "F.SilkS")
		)
		(fp_line
			(start 1.549908 1.549908)
			(end -1.549908 1.549908)
			(stroke
				(width 0.1)
				(type default)
			)
			(layer "F.Fab")
		)
		(fp_line
			(start 1.549908 -1.549908)
			(end 1.549908 1.549908)
			(stroke
				(width 0.1)
				(type default)
			)
			(layer "F.Fab")
		)
		(fp_line
			(start -1.549908 1.549908)
			(end -1.549908 -1.549908)
			(stroke
				(width 0.1)
				(type default)
			)
			(layer "F.Fab")
		)
		(fp_line
			(start -1.549908 -1.549908)
			(end 1.549908 -1.549908)
			(stroke
				(width 0.1)
				(type default)
			)
			(layer "F.Fab")
		)
		(fp_poly
			(pts
				(xy -3.4798 -1.359916) (xy -2.86004 -1.050036) (xy -3.4798 -0.740156)
			)
			(stroke
				(width 0)
				(type default)
			)
			(fill yes)
			(layer "F.Fab")
		)
		(pad "1" smd rect
			(at -2.175002 -1.050036 270)
			(size 0.6096 1.1684)
			(layers "F.Cu" "F.Mask" "F.Paste")
			(net "P3V3_AUX")
		)
		(pad "2" smd rect
			(at -2.175002 -0.32512 270)
			(size 0.4318 1.1684)
			(layers "F.Cu" "F.Mask" "F.Paste")
			(net "SMB_OCP_V3_2_3V3AUX_SCL")
		)
		(pad "3" smd rect
			(at -2.175002 0.32512 270)
			(size 0.4318 1.1684)
			(layers "F.Cu" "F.Mask" "F.Paste")
			(net "SMB_OCP_V3_2_3V3AUX_SDA")
		)
		(pad "4" smd rect
			(at -2.175002 1.050036 270)
			(size 0.6096 1.1684)
			(layers "F.Cu" "F.Mask" "F.Paste")
			(net "GND")
		)
		(pad "5" smd rect
			(at 2.175002 1.050036 270)
			(size 0.6096 1.1684)
			(layers "F.Cu" "F.Mask" "F.Paste")
			(net "HP_LVC3_OCP_V3_2_R_EN")
		)
		(pad "6" smd rect
			(at 2.175002 0.32512 270)
			(size 0.4318 1.1684)
			(layers "F.Cu" "F.Mask" "F.Paste")
			(net "SMB_OCP_V3_2_3V3AUX_BUF_SDA")
		)
		(pad "7" smd rect
			(at 2.175002 -0.32512 270)
			(size 0.4318 1.1684)
			(layers "F.Cu" "F.Mask" "F.Paste")
			(net "SMB_OCP_V3_2_3V3AUX_BUF_SCL")
		)
		(pad "8" smd rect
			(at 2.175002 -1.050036 270)
			(size 0.6096 1.1684)
			(layers "F.Cu" "F.Mask" "F.Paste")
			(net "P3V3_OCP_V3_2")
		)
	)
	(footprint ""
		(layer "F.Cu")
		(at 160.261554 -31.341568 90)
		(property "Reference" "R4462"
			(at 0 0 90)
			(layer "F.SilkS")
			(hide yes)
			(effects
				(font
					(size 1.27 1.27)
				)
			)
		)
		(property "Value" ""
			(at 0 0 90)
			(layer "F.Fab")
			(effects
				(font
					(size 1.27 1.27)
				)
			)
		)
		(duplicate_pad_numbers_are_jumpers no)
		(fp_line
			(start 0.7874 -0.4064)
			(end 0.7874 0.4064)
			(stroke
				(width 0.1524)
				(type default)
			)
			(layer "F.SilkS")
		)
		(fp_line
			(start -0.7874 -0.4064)
			(end 0.7874 -0.4064)
			(stroke
				(width 0.1524)
				(type default)
			)
			(layer "F.SilkS")
		)
		(fp_line
			(start 0.7874 0.4064)
			(end -0.7874 0.4064)
			(stroke
				(width 0.1524)
				(type default)
			)
			(layer "F.SilkS")
		)
		(fp_line
			(start -0.7874 0.4064)
			(end -0.7874 -0.4064)
			(stroke
				(width 0.1524)
				(type default)
			)
			(layer "F.SilkS")
		)
		(fp_line
			(start -0.12065 -0.305054)
			(end -0.12065 -0.2794)
			(stroke
				(width 0.1)
				(type default)
			)
			(layer "F.Fab")
		)
		(fp_line
			(start -0.67945 -0.305054)
			(end -0.12065 -0.305054)
			(stroke
				(width 0.1)
				(type default)
			)
			(layer "F.Fab")
		)
		(fp_line
			(start 0.67945 -0.3048)
			(end 0.67945 0.3048)
			(stroke
				(width 0.1)
				(type default)
			)
			(layer "F.Fab")
		)
		(fp_line
			(start 0.12065 -0.3048)
			(end 0.67945 -0.3048)
			(stroke
				(width 0.1)
				(type default)
			)
			(layer "F.Fab")
		)
		(fp_line
			(start 0.12065 -0.2794)
			(end 0.12065 -0.3048)
			(stroke
				(width 0.1)
				(type default)
			)
			(layer "F.Fab")
		)
		(fp_line
			(start -0.12065 -0.2794)
			(end 0.12065 -0.2794)
			(stroke
				(width 0.1)
				(type default)
			)
			(layer "F.Fab")
		)
		(fp_line
			(start 0.120396 0.2794)
			(end -0.12065 0.2794)
			(stroke
				(width 0.1)
				(type default)
			)
			(layer "F.Fab")
		)
		(fp_line
			(start -0.12065 0.2794)
			(end -0.12065 0.3048)
			(stroke
				(width 0.1)
				(type default)
			)
			(layer "F.Fab")
		)
		(fp_line
			(start 0.67945 0.3048)
			(end 0.120396 0.3048)
			(stroke
				(width 0.1)
				(type default)
			)
			(layer "F.Fab")
		)
		(fp_line
			(start 0.120396 0.3048)
			(end 0.120396 0.2794)
			(stroke
				(width 0.1)
				(type default)
			)
			(layer "F.Fab")
		)
		(fp_line
			(start -0.12065 0.3048)
			(end -0.67945 0.3048)
			(stroke
				(width 0.1)
				(type default)
			)
			(layer "F.Fab")
		)
		(fp_line
			(start -0.67945 0.3048)
			(end -0.67945 -0.305054)
			(stroke
				(width 0.1)
				(type default)
			)
			(layer "F.Fab")
		)
		(pad "1" smd circle
			(at -0.40005 0 90)
			(size 0 0)
			(layers "F.Cu" "F.Mask" "F.Paste")
			(net "P3V3_AUX_USB_HUB_2")
		)
		(pad "2" smd circle
			(at 0.40005 0 90)
			(size 0 0)
			(layers "F.Cu" "F.Mask" "F.Paste")
			(net "USB_HUB_2_DVDD")
		)
	)
	(footprint ""
		(layer "F.Cu")
		(at 439.262266 -124.680726 180)
		(property "Reference" "R1735"
			(at 0 0 180)
			(layer "F.SilkS")
			(hide yes)
			(effects
				(font
					(size 1.27 1.27)
				)
			)
		)
		(property "Value" ""
			(at 0 0 180)
			(layer "F.Fab")
			(effects
				(font
					(size 1.27 1.27)
				)
			)
		)
		(duplicate_pad_numbers_are_jumpers no)
		(fp_line
			(start 0.7874 0.4064)
			(end -0.7874 0.4064)
			(stroke
				(width 0.1524)
				(type default)
			)
			(layer "F.SilkS")
		)
		(fp_line
			(start 0.7874 -0.4064)
			(end 0.7874 0.4064)
			(stroke
				(width 0.1524)
				(type default)
			)
			(layer "F.SilkS")
		)
		(fp_line
			(start -0.7874 0.4064)
			(end -0.7874 -0.4064)
			(stroke
				(width 0.1524)
				(type default)
			)
			(layer "F.SilkS")
		)
		(fp_line
			(start -0.7874 -0.4064)
			(end 0.7874 -0.4064)
			(stroke
				(width 0.1524)
				(type default)
			)
			(layer "F.SilkS")
		)
		(fp_line
			(start 0.67945 0.3048)
			(end 0.120396 0.3048)
			(stroke
				(width 0.1)
				(type default)
			)
			(layer "F.Fab")
		)
		(fp_line
			(start 0.67945 -0.3048)
			(end 0.67945 0.3048)
			(stroke
				(width 0.1)
				(type default)
			)
			(layer "F.Fab")
		)
		(fp_line
			(start 0.12065 -0.2794)
			(end 0.12065 -0.3048)
			(stroke
				(width 0.1)
				(type default)
			)
			(layer "F.Fab")
		)
		(fp_line
			(start 0.12065 -0.3048)
			(end 0.67945 -0.3048)
			(stroke
				(width 0.1)
				(type default)
			)
			(layer "F.Fab")
		)
		(fp_line
			(start 0.120396 0.3048)
			(end 0.120396 0.2794)
			(stroke
				(width 0.1)
				(type default)
			)
			(layer "F.Fab")
		)
		(fp_line
			(start 0.120396 0.2794)
			(end -0.12065 0.2794)
			(stroke
				(width 0.1)
				(type default)
			)
			(layer "F.Fab")
		)
		(fp_line
			(start -0.12065 0.3048)
			(end -0.67945 0.3048)
			(stroke
				(width 0.1)
				(type default)
			)
			(layer "F.Fab")
		)
		(fp_line
			(start -0.12065 0.2794)
			(end -0.12065 0.3048)
			(stroke
				(width 0.1)
				(type default)
			)
			(layer "F.Fab")
		)
		(fp_line
			(start -0.12065 -0.2794)
			(end 0.12065 -0.2794)
			(stroke
				(width 0.1)
				(type default)
			)
			(layer "F.Fab")
		)
		(fp_line
			(start -0.12065 -0.305054)
			(end -0.12065 -0.2794)
			(stroke
				(width 0.1)
				(type default)
			)
			(layer "F.Fab")
		)
		(fp_line
			(start -0.67945 0.3048)
			(end -0.67945 -0.305054)
			(stroke
				(width 0.1)
				(type default)
			)
			(layer "F.Fab")
		)
		(fp_line
			(start -0.67945 -0.305054)
			(end -0.12065 -0.305054)
			(stroke
				(width 0.1)
				(type default)
			)
			(layer "F.Fab")
		)
		(pad "1" smd circle
			(at -0.40005 0 180)
			(size 0 0)
			(layers "F.Cu" "F.Mask" "F.Paste")
			(net "PVNN_TERM_CPU0")
		)
		(pad "2" smd circle
			(at 0.40005 0 180)
			(size 0 0)
			(layers "F.Cu" "F.Mask" "F.Paste")
			(net "SVID_DIO1_CPU0_R")
		)
	)
	(footprint ""
		(layer "F.Cu")
		(at 468.49157 -44.887388)
		(property "Reference" "R1594"
			(at 0 0 0)
			(layer "F.SilkS")
			(hide yes)
			(effects
				(font
					(size 1.27 1.27)
				)
			)
		)
		(property "Value" ""
			(at 0 0 0)
			(layer "F.Fab")
			(effects
				(font
					(size 1.27 1.27)
				)
			)
		)
		(duplicate_pad_numbers_are_jumpers no)
		(fp_line
			(start -0.7874 -0.4064)
			(end 0.7874 -0.4064)
			(stroke
				(width 0.1524)
				(type default)
			)
			(layer "F.SilkS")
		)
		(fp_line
			(start -0.7874 0.4064)
			(end -0.7874 -0.4064)
			(stroke
				(width 0.1524)
				(type default)
			)
			(layer "F.SilkS")
		)
		(fp_line
			(start 0.7874 -0.4064)
			(end 0.7874 0.4064)
			(stroke
				(width 0.1524)
				(type default)
			)
			(layer "F.SilkS")
		)
		(fp_line
			(start 0.7874 0.4064)
			(end -0.7874 0.4064)
			(stroke
				(width 0.1524)
				(type default)
			)
			(layer "F.SilkS")
		)
		(fp_line
			(start -0.67945 -0.305054)
			(end -0.12065 -0.305054)
			(stroke
				(width 0.1)
				(type default)
			)
			(layer "F.Fab")
		)
		(fp_line
			(start -0.67945 0.3048)
			(end -0.67945 -0.305054)
			(stroke
				(width 0.1)
				(type default)
			)
			(layer "F.Fab")
		)
		(fp_line
			(start -0.12065 -0.305054)
			(end -0.12065 -0.2794)
			(stroke
				(width 0.1)
				(type default)
			)
			(layer "F.Fab")
		)
		(fp_line
			(start -0.12065 -0.2794)
			(end 0.12065 -0.2794)
			(stroke
				(width 0.1)
				(type default)
			)
			(layer "F.Fab")
		)
		(fp_line
			(start -0.12065 0.2794)
			(end -0.12065 0.3048)
			(stroke
				(width 0.1)
				(type default)
			)
			(layer "F.Fab")
		)
		(fp_line
			(start -0.12065 0.3048)
			(end -0.67945 0.3048)
			(stroke
				(width 0.1)
				(type default)
			)
			(layer "F.Fab")
		)
		(fp_line
			(start 0.120396 0.2794)
			(end -0.12065 0.2794)
			(stroke
				(width 0.1)
				(type default)
			)
			(layer "F.Fab")
		)
		(fp_line
			(start 0.120396 0.3048)
			(end 0.120396 0.2794)
			(stroke
				(width 0.1)
				(type default)
			)
			(layer "F.Fab")
		)
		(fp_line
			(start 0.12065 -0.3048)
			(end 0.67945 -0.3048)
			(stroke
				(width 0.1)
				(type default)
			)
			(layer "F.Fab")
		)
		(fp_line
			(start 0.12065 -0.2794)
			(end 0.12065 -0.3048)
			(stroke
				(width 0.1)
				(type default)
			)
			(layer "F.Fab")
		)
		(fp_line
			(start 0.67945 -0.3048)
			(end 0.67945 0.3048)
			(stroke
				(width 0.1)
				(type default)
			)
			(layer "F.Fab")
		)
		(fp_line
			(start 0.67945 0.3048)
			(end 0.120396 0.3048)
			(stroke
				(width 0.1)
				(type default)
			)
			(layer "F.Fab")
		)
		(pad "1" smd circle
			(at -0.40005 0)
			(size 0 0)
			(layers "F.Cu" "F.Mask" "F.Paste")
			(net "OCP_SFF_WAKE_BUFF_N")
		)
		(pad "2" smd circle
			(at 0.40005 0)
			(size 0 0)
			(layers "F.Cu" "F.Mask" "F.Paste")
			(net "OCP_SFF_WAKE_BUFF_R_N")
		)
	)
	(footprint ""
		(layer "F.Cu")
		(at 362.89742 -354.065586)
		(property "Reference" "PC594"
			(at 0 0 0)
			(layer "F.SilkS")
			(hide yes)
			(effects
				(font
					(size 1.27 1.27)
				)
			)
		)
		(property "Value" ""
			(at 0 0 0)
			(layer "F.Fab")
			(effects
				(font
					(size 1.27 1.27)
				)
			)
		)
		(duplicate_pad_numbers_are_jumpers no)
		(fp_line
			(start -0.7874 -0.4064)
			(end 0.7874 -0.4064)
			(stroke
				(width 0.1524)
				(type default)
			)
			(layer "F.SilkS")
		)
		(fp_line
			(start -0.7874 0.4064)
			(end -0.7874 -0.4064)
			(stroke
				(width 0.1524)
				(type default)
			)
			(layer "F.SilkS")
		)
		(fp_line
			(start 0.7874 -0.4064)
			(end 0.7874 0.4064)
			(stroke
				(width 0.1524)
				(type default)
			)
			(layer "F.SilkS")
		)
		(fp_line
			(start 0.7874 0.4064)
			(end -0.7874 0.4064)
			(stroke
				(width 0.1524)
				(type default)
			)
			(layer "F.SilkS")
		)
		(fp_line
			(start -0.67945 -0.305054)
			(end -0.12065 -0.305054)
			(stroke
				(width 0.1)
				(type default)
			)
			(layer "F.Fab")
		)
		(fp_line
			(start -0.67945 0.3048)
			(end -0.67945 -0.305054)
			(stroke
				(width 0.1)
				(type default)
			)
			(layer "F.Fab")
		)
		(fp_line
			(start -0.12065 -0.305054)
			(end -0.12065 -0.2794)
			(stroke
				(width 0.1)
				(type default)
			)
			(layer "F.Fab")
		)
		(fp_line
			(start -0.12065 -0.2794)
			(end 0.12065 -0.2794)
			(stroke
				(width 0.1)
				(type default)
			)
			(layer "F.Fab")
		)
		(fp_line
			(start -0.12065 0.2794)
			(end -0.12065 0.3048)
			(stroke
				(width 0.1)
				(type default)
			)
			(layer "F.Fab")
		)
		(fp_line
			(start -0.12065 0.3048)
			(end -0.67945 0.3048)
			(stroke
				(width 0.1)
				(type default)
			)
			(layer "F.Fab")
		)
		(fp_line
			(start 0.120396 0.2794)
			(end -0.12065 0.2794)
			(stroke
				(width 0.1)
				(type default)
			)
			(layer "F.Fab")
		)
		(fp_line
			(start 0.120396 0.3048)
			(end 0.120396 0.2794)
			(stroke
				(width 0.1)
				(type default)
			)
			(layer "F.Fab")
		)
		(fp_line
			(start 0.12065 -0.3048)
			(end 0.67945 -0.3048)
			(stroke
				(width 0.1)
				(type default)
			)
			(layer "F.Fab")
		)
		(fp_line
			(start 0.12065 -0.2794)
			(end 0.12065 -0.3048)
			(stroke
				(width 0.1)
				(type default)
			)
			(layer "F.Fab")
		)
		(fp_line
			(start 0.67945 -0.3048)
			(end 0.67945 0.3048)
			(stroke
				(width 0.1)
				(type default)
			)
			(layer "F.Fab")
		)
		(fp_line
			(start 0.67945 0.3048)
			(end 0.120396 0.3048)
			(stroke
				(width 0.1)
				(type default)
			)
			(layer "F.Fab")
		)
		(pad "1" smd circle
			(at -0.40005 0)
			(size 0 0)
			(layers "F.Cu" "F.Mask" "F.Paste")
			(net "SH_PVCCFA_EHV_FIVRA_CPU0_R")
		)
		(pad "2" smd circle
			(at 0.40005 0)
			(size 0 0)
			(layers "F.Cu" "F.Mask" "F.Paste")
			(net "VSENSE_PVCCFA_EHV_FIVRA_CPU0_DN")
		)
	)
	(footprint ""
		(layer "F.Cu")
		(at 218.130882 -57.399682 -90)
		(property "Reference" "C2071"
			(at 0 0 270)
			(layer "F.SilkS")
			(hide yes)
			(effects
				(font
					(size 1.27 1.27)
				)
			)
		)
		(property "Value" ""
			(at 0 0 270)
			(layer "F.Fab")
			(effects
				(font
					(size 1.27 1.27)
				)
			)
		)
		(duplicate_pad_numbers_are_jumpers no)
		(fp_line
			(start -0.7874 0.4064)
			(end -0.7874 -0.4064)
			(stroke
				(width 0.1524)
				(type default)
			)
			(layer "F.SilkS")
		)
		(fp_line
			(start 0.7874 0.4064)
			(end -0.7874 0.4064)
			(stroke
				(width 0.1524)
				(type default)
			)
			(layer "F.SilkS")
		)
		(fp_line
			(start -0.7874 -0.4064)
			(end 0.7874 -0.4064)
			(stroke
				(width 0.1524)
				(type default)
			)
			(layer "F.SilkS")
		)
		(fp_line
			(start 0.7874 -0.4064)
			(end 0.7874 0.4064)
			(stroke
				(width 0.1524)
				(type default)
			)
			(layer "F.SilkS")
		)
		(fp_line
			(start -0.67945 0.3048)
			(end -0.67945 -0.305054)
			(stroke
				(width 0.1)
				(type default)
			)
			(layer "F.Fab")
		)
		(fp_line
			(start -0.12065 0.3048)
			(end -0.67945 0.3048)
			(stroke
				(width 0.1)
				(type default)
			)
			(layer "F.Fab")
		)
		(fp_line
			(start 0.120396 0.3048)
			(end 0.120396 0.2794)
			(stroke
				(width 0.1)
				(type default)
			)
			(layer "F.Fab")
		)
		(fp_line
			(start 0.67945 0.3048)
			(end 0.120396 0.3048)
			(stroke
				(width 0.1)
				(type default)
			)
			(layer "F.Fab")
		)
		(fp_line
			(start -0.12065 0.2794)
			(end -0.12065 0.3048)
			(stroke
				(width 0.1)
				(type default)
			)
			(layer "F.Fab")
		)
		(fp_line
			(start 0.120396 0.2794)
			(end -0.12065 0.2794)
			(stroke
				(width 0.1)
				(type default)
			)
			(layer "F.Fab")
		)
		(fp_line
			(start -0.12065 -0.2794)
			(end 0.12065 -0.2794)
			(stroke
				(width 0.1)
				(type default)
			)
			(layer "F.Fab")
		)
		(fp_line
			(start 0.12065 -0.2794)
			(end 0.12065 -0.3048)
			(stroke
				(width 0.1)
				(type default)
			)
			(layer "F.Fab")
		)
		(fp_line
			(start 0.12065 -0.3048)
			(end 0.67945 -0.3048)
			(stroke
				(width 0.1)
				(type default)
			)
			(layer "F.Fab")
		)
		(fp_line
			(start 0.67945 -0.3048)
			(end 0.67945 0.3048)
			(stroke
				(width 0.1)
				(type default)
			)
			(layer "F.Fab")
		)
		(fp_line
			(start -0.67945 -0.305054)
			(end -0.12065 -0.305054)
			(stroke
				(width 0.1)
				(type default)
			)
			(layer "F.Fab")
		)
		(fp_line
			(start -0.12065 -0.305054)
			(end -0.12065 -0.2794)
			(stroke
				(width 0.1)
				(type default)
			)
			(layer "F.Fab")
		)
		(pad "1" smd circle
			(at -0.40005 0 270)
			(size 0 0)
			(layers "F.Cu" "F.Mask" "F.Paste")
			(net "VSENSE_P3V3_INA230_2_INP")
		)
		(pad "2" smd circle
			(at 0.40005 0 270)
			(size 0 0)
			(layers "F.Cu" "F.Mask" "F.Paste")
			(net "VSENSE_P3V3_INA230_2_INN")
		)
	)
	(footprint ""
		(layer "F.Cu")
		(at 93.400118 -333.525368 -90)
		(property "Reference" "PC559_P1_1"
			(at 0 0 270)
			(layer "F.SilkS")
			(hide yes)
			(effects
				(font
					(size 1.27 1.27)
				)
			)
		)
		(property "Value" ""
			(at 0 0 270)
			(layer "F.Fab")
			(effects
				(font
					(size 1.27 1.27)
				)
			)
		)
		(duplicate_pad_numbers_are_jumpers no)
		(fp_line
			(start -0.7874 0.4064)
			(end -0.7874 -0.4064)
			(stroke
				(width 0.1524)
				(type default)
			)
			(layer "F.SilkS")
		)
		(fp_line
			(start 0.7874 0.4064)
			(end -0.7874 0.4064)
			(stroke
				(width 0.1524)
				(type default)
			)
			(layer "F.SilkS")
		)
		(fp_line
			(start -0.7874 -0.4064)
			(end 0.7874 -0.4064)
			(stroke
				(width 0.1524)
				(type default)
			)
			(layer "F.SilkS")
		)
		(fp_line
			(start 0.7874 -0.4064)
			(end 0.7874 0.4064)
			(stroke
				(width 0.1524)
				(type default)
			)
			(layer "F.SilkS")
		)
		(fp_line
			(start -0.67945 0.3048)
			(end -0.67945 -0.305054)
			(stroke
				(width 0.1)
				(type default)
			)
			(layer "F.Fab")
		)
		(fp_line
			(start -0.12065 0.3048)
			(end -0.67945 0.3048)
			(stroke
				(width 0.1)
				(type default)
			)
			(layer "F.Fab")
		)
		(fp_line
			(start 0.120396 0.3048)
			(end 0.120396 0.2794)
			(stroke
				(width 0.1)
				(type default)
			)
			(layer "F.Fab")
		)
		(fp_line
			(start 0.67945 0.3048)
			(end 0.120396 0.3048)
			(stroke
				(width 0.1)
				(type default)
			)
			(layer "F.Fab")
		)
		(fp_line
			(start -0.12065 0.2794)
			(end -0.12065 0.3048)
			(stroke
				(width 0.1)
				(type default)
			)
			(layer "F.Fab")
		)
		(fp_line
			(start 0.120396 0.2794)
			(end -0.12065 0.2794)
			(stroke
				(width 0.1)
				(type default)
			)
			(layer "F.Fab")
		)
		(fp_line
			(start -0.12065 -0.2794)
			(end 0.12065 -0.2794)
			(stroke
				(width 0.1)
				(type default)
			)
			(layer "F.Fab")
		)
		(fp_line
			(start 0.12065 -0.2794)
			(end 0.12065 -0.3048)
			(stroke
				(width 0.1)
				(type default)
			)
			(layer "F.Fab")
		)
		(fp_line
			(start 0.12065 -0.3048)
			(end 0.67945 -0.3048)
			(stroke
				(width 0.1)
				(type default)
			)
			(layer "F.Fab")
		)
		(fp_line
			(start 0.67945 -0.3048)
			(end 0.67945 0.3048)
			(stroke
				(width 0.1)
				(type default)
			)
			(layer "F.Fab")
		)
		(fp_line
			(start -0.67945 -0.305054)
			(end -0.12065 -0.305054)
			(stroke
				(width 0.1)
				(type default)
			)
			(layer "F.Fab")
		)
		(fp_line
			(start -0.12065 -0.305054)
			(end -0.12065 -0.2794)
			(stroke
				(width 0.1)
				(type default)
			)
			(layer "F.Fab")
		)
		(pad "1" smd circle
			(at -0.40005 0 270)
			(size 0 0)
			(layers "F.Cu" "F.Mask" "F.Paste")
			(net "PVCCIN_CPU1_PVCC")
		)
		(pad "2" smd circle
			(at 0.40005 0 270)
			(size 0 0)
			(layers "F.Cu" "F.Mask" "F.Paste")
			(net "GND")
		)
	)
	(footprint ""
		(layer "F.Cu")
		(at 254.58674 -92.291408 180)
		(property "Reference" "R3643"
			(at 0 0 180)
			(layer "F.SilkS")
			(hide yes)
			(effects
				(font
					(size 1.27 1.27)
				)
			)
		)
		(property "Value" ""
			(at 0 0 180)
			(layer "F.Fab")
			(effects
				(font
					(size 1.27 1.27)
				)
			)
		)
		(duplicate_pad_numbers_are_jumpers no)
		(fp_line
			(start 0.7874 0.4064)
			(end -0.7874 0.4064)
			(stroke
				(width 0.1524)
				(type default)
			)
			(layer "F.SilkS")
		)
		(fp_line
			(start 0.7874 -0.4064)
			(end 0.7874 0.4064)
			(stroke
				(width 0.1524)
				(type default)
			)
			(layer "F.SilkS")
		)
		(fp_line
			(start -0.7874 0.4064)
			(end -0.7874 -0.4064)
			(stroke
				(width 0.1524)
				(type default)
			)
			(layer "F.SilkS")
		)
		(fp_line
			(start -0.7874 -0.4064)
			(end 0.7874 -0.4064)
			(stroke
				(width 0.1524)
				(type default)
			)
			(layer "F.SilkS")
		)
		(fp_line
			(start 0.67945 0.3048)
			(end 0.120396 0.3048)
			(stroke
				(width 0.1)
				(type default)
			)
			(layer "F.Fab")
		)
		(fp_line
			(start 0.67945 -0.3048)
			(end 0.67945 0.3048)
			(stroke
				(width 0.1)
				(type default)
			)
			(layer "F.Fab")
		)
		(fp_line
			(start 0.12065 -0.2794)
			(end 0.12065 -0.3048)
			(stroke
				(width 0.1)
				(type default)
			)
			(layer "F.Fab")
		)
		(fp_line
			(start 0.12065 -0.3048)
			(end 0.67945 -0.3048)
			(stroke
				(width 0.1)
				(type default)
			)
			(layer "F.Fab")
		)
		(fp_line
			(start 0.120396 0.3048)
			(end 0.120396 0.2794)
			(stroke
				(width 0.1)
				(type default)
			)
			(layer "F.Fab")
		)
		(fp_line
			(start 0.120396 0.2794)
			(end -0.12065 0.2794)
			(stroke
				(width 0.1)
				(type default)
			)
			(layer "F.Fab")
		)
		(fp_line
			(start -0.12065 0.3048)
			(end -0.67945 0.3048)
			(stroke
				(width 0.1)
				(type default)
			)
			(layer "F.Fab")
		)
		(fp_line
			(start -0.12065 0.2794)
			(end -0.12065 0.3048)
			(stroke
				(width 0.1)
				(type default)
			)
			(layer "F.Fab")
		)
		(fp_line
			(start -0.12065 -0.2794)
			(end 0.12065 -0.2794)
			(stroke
				(width 0.1)
				(type default)
			)
			(layer "F.Fab")
		)
		(fp_line
			(start -0.12065 -0.305054)
			(end -0.12065 -0.2794)
			(stroke
				(width 0.1)
				(type default)
			)
			(layer "F.Fab")
		)
		(fp_line
			(start -0.67945 0.3048)
			(end -0.67945 -0.305054)
			(stroke
				(width 0.1)
				(type default)
			)
			(layer "F.Fab")
		)
		(fp_line
			(start -0.67945 -0.305054)
			(end -0.12065 -0.305054)
			(stroke
				(width 0.1)
				(type default)
			)
			(layer "F.Fab")
		)
		(pad "1" smd circle
			(at -0.40005 0 180)
			(size 0 0)
			(layers "F.Cu" "F.Mask" "F.Paste")
			(net "P3V3_AUX")
		)
		(pad "2" smd circle
			(at 0.40005 0 180)
			(size 0 0)
			(layers "F.Cu" "F.Mask" "F.Paste")
			(net "CK440Q_OE_6")
		)
	)
	(footprint ""
		(layer "F.Cu")
		(at 46.350428 -99.840034)
		(property "Reference" "C2045"
			(at 0 0 0)
			(layer "F.SilkS")
			(hide yes)
			(effects
				(font
					(size 1.27 1.27)
				)
			)
		)
		(property "Value" ""
			(at 0 0 0)
			(layer "F.Fab")
			(effects
				(font
					(size 1.27 1.27)
				)
			)
		)
		(duplicate_pad_numbers_are_jumpers no)
		(fp_line
			(start -0.7874 -0.4064)
			(end 0.7874 -0.4064)
			(stroke
				(width 0.1524)
				(type default)
			)
			(layer "F.SilkS")
		)
		(fp_line
			(start -0.7874 0.4064)
			(end -0.7874 -0.4064)
			(stroke
				(width 0.1524)
				(type default)
			)
			(layer "F.SilkS")
		)
		(fp_line
			(start 0.7874 -0.4064)
			(end 0.7874 0.4064)
			(stroke
				(width 0.1524)
				(type default)
			)
			(layer "F.SilkS")
		)
		(fp_line
			(start 0.7874 0.4064)
			(end -0.7874 0.4064)
			(stroke
				(width 0.1524)
				(type default)
			)
			(layer "F.SilkS")
		)
		(fp_line
			(start -0.67945 -0.305054)
			(end -0.12065 -0.305054)
			(stroke
				(width 0.1)
				(type default)
			)
			(layer "F.Fab")
		)
		(fp_line
			(start -0.67945 0.3048)
			(end -0.67945 -0.305054)
			(stroke
				(width 0.1)
				(type default)
			)
			(layer "F.Fab")
		)
		(fp_line
			(start -0.12065 -0.305054)
			(end -0.12065 -0.2794)
			(stroke
				(width 0.1)
				(type default)
			)
			(layer "F.Fab")
		)
		(fp_line
			(start -0.12065 -0.2794)
			(end 0.12065 -0.2794)
			(stroke
				(width 0.1)
				(type default)
			)
			(layer "F.Fab")
		)
		(fp_line
			(start -0.12065 0.2794)
			(end -0.12065 0.3048)
			(stroke
				(width 0.1)
				(type default)
			)
			(layer "F.Fab")
		)
		(fp_line
			(start -0.12065 0.3048)
			(end -0.67945 0.3048)
			(stroke
				(width 0.1)
				(type default)
			)
			(layer "F.Fab")
		)
		(fp_line
			(start 0.120396 0.2794)
			(end -0.12065 0.2794)
			(stroke
				(width 0.1)
				(type default)
			)
			(layer "F.Fab")
		)
		(fp_line
			(start 0.120396 0.3048)
			(end 0.120396 0.2794)
			(stroke
				(width 0.1)
				(type default)
			)
			(layer "F.Fab")
		)
		(fp_line
			(start 0.12065 -0.3048)
			(end 0.67945 -0.3048)
			(stroke
				(width 0.1)
				(type default)
			)
			(layer "F.Fab")
		)
		(fp_line
			(start 0.12065 -0.2794)
			(end 0.12065 -0.3048)
			(stroke
				(width 0.1)
				(type default)
			)
			(layer "F.Fab")
		)
		(fp_line
			(start 0.67945 -0.3048)
			(end 0.67945 0.3048)
			(stroke
				(width 0.1)
				(type default)
			)
			(layer "F.Fab")
		)
		(fp_line
			(start 0.67945 0.3048)
			(end 0.120396 0.3048)
			(stroke
				(width 0.1)
				(type default)
			)
			(layer "F.Fab")
		)
		(pad "1" smd circle
			(at -0.40005 0)
			(size 0 0)
			(layers "F.Cu" "F.Mask" "F.Paste")
			(net "P3V3_PDB_AUX_ADC_MAM")
		)
		(pad "2" smd circle
			(at 0.40005 0)
			(size 0 0)
			(layers "F.Cu" "F.Mask" "F.Paste")
			(net "GND")
		)
	)
	(footprint ""
		(layer "F.Cu")
		(at 320.190622 -58.283348)
		(property "Reference" "R617"
			(at 0 0 0)
			(layer "F.SilkS")
			(hide yes)
			(effects
				(font
					(size 1.27 1.27)
				)
			)
		)
		(property "Value" ""
			(at 0 0 0)
			(layer "F.Fab")
			(effects
				(font
					(size 1.27 1.27)
				)
			)
		)
		(duplicate_pad_numbers_are_jumpers no)
		(fp_line
			(start -0.7874 -0.4064)
			(end 0.7874 -0.4064)
			(stroke
				(width 0.1524)
				(type default)
			)
			(layer "F.SilkS")
		)
		(fp_line
			(start -0.7874 0.4064)
			(end -0.7874 -0.4064)
			(stroke
				(width 0.1524)
				(type default)
			)
			(layer "F.SilkS")
		)
		(fp_line
			(start 0.7874 -0.4064)
			(end 0.7874 0.4064)
			(stroke
				(width 0.1524)
				(type default)
			)
			(layer "F.SilkS")
		)
		(fp_line
			(start 0.7874 0.4064)
			(end -0.7874 0.4064)
			(stroke
				(width 0.1524)
				(type default)
			)
			(layer "F.SilkS")
		)
		(fp_line
			(start -0.67945 -0.305054)
			(end -0.12065 -0.305054)
			(stroke
				(width 0.1)
				(type default)
			)
			(layer "F.Fab")
		)
		(fp_line
			(start -0.67945 0.3048)
			(end -0.67945 -0.305054)
			(stroke
				(width 0.1)
				(type default)
			)
			(layer "F.Fab")
		)
		(fp_line
			(start -0.12065 -0.305054)
			(end -0.12065 -0.2794)
			(stroke
				(width 0.1)
				(type default)
			)
			(layer "F.Fab")
		)
		(fp_line
			(start -0.12065 -0.2794)
			(end 0.12065 -0.2794)
			(stroke
				(width 0.1)
				(type default)
			)
			(layer "F.Fab")
		)
		(fp_line
			(start -0.12065 0.2794)
			(end -0.12065 0.3048)
			(stroke
				(width 0.1)
				(type default)
			)
			(layer "F.Fab")
		)
		(fp_line
			(start -0.12065 0.3048)
			(end -0.67945 0.3048)
			(stroke
				(width 0.1)
				(type default)
			)
			(layer "F.Fab")
		)
		(fp_line
			(start 0.120396 0.2794)
			(end -0.12065 0.2794)
			(stroke
				(width 0.1)
				(type default)
			)
			(layer "F.Fab")
		)
		(fp_line
			(start 0.120396 0.3048)
			(end 0.120396 0.2794)
			(stroke
				(width 0.1)
				(type default)
			)
			(layer "F.Fab")
		)
		(fp_line
			(start 0.12065 -0.3048)
			(end 0.67945 -0.3048)
			(stroke
				(width 0.1)
				(type default)
			)
			(layer "F.Fab")
		)
		(fp_line
			(start 0.12065 -0.2794)
			(end 0.12065 -0.3048)
			(stroke
				(width 0.1)
				(type default)
			)
			(layer "F.Fab")
		)
		(fp_line
			(start 0.67945 -0.3048)
			(end 0.67945 0.3048)
			(stroke
				(width 0.1)
				(type default)
			)
			(layer "F.Fab")
		)
		(fp_line
			(start 0.67945 0.3048)
			(end 0.120396 0.3048)
			(stroke
				(width 0.1)
				(type default)
			)
			(layer "F.Fab")
		)
		(pad "1" smd circle
			(at -0.40005 0)
			(size 0 0)
			(layers "F.Cu" "F.Mask" "F.Paste")
			(net "P3V3_AUX")
		)
		(pad "2" smd circle
			(at 0.40005 0)
			(size 0 0)
			(layers "F.Cu" "F.Mask" "F.Paste")
			(net "FM_PCH_IO_EXPANDER")
		)
	)
	(footprint ""
		(layer "F.Cu")
		(at 39.263574 -387.340856 -90)
		(property "Reference" "C2358"
			(at 0 0 270)
			(layer "F.SilkS")
			(hide yes)
			(effects
				(font
					(size 1.27 1.27)
				)
			)
		)
		(property "Value" ""
			(at 0 0 270)
			(layer "F.Fab")
			(effects
				(font
					(size 1.27 1.27)
				)
			)
		)
		(duplicate_pad_numbers_are_jumpers no)
		(fp_line
			(start -0.7874 0.4064)
			(end -0.7874 -0.4064)
			(stroke
				(width 0.1524)
				(type default)
			)
			(layer "F.SilkS")
		)
		(fp_line
			(start 0.7874 0.4064)
			(end -0.7874 0.4064)
			(stroke
				(width 0.1524)
				(type default)
			)
			(layer "F.SilkS")
		)
		(fp_line
			(start -0.7874 -0.4064)
			(end 0.7874 -0.4064)
			(stroke
				(width 0.1524)
				(type default)
			)
			(layer "F.SilkS")
		)
		(fp_line
			(start 0.7874 -0.4064)
			(end 0.7874 0.4064)
			(stroke
				(width 0.1524)
				(type default)
			)
			(layer "F.SilkS")
		)
		(fp_line
			(start -0.67945 0.3048)
			(end -0.67945 -0.305054)
			(stroke
				(width 0.1)
				(type default)
			)
			(layer "F.Fab")
		)
		(fp_line
			(start -0.12065 0.3048)
			(end -0.67945 0.3048)
			(stroke
				(width 0.1)
				(type default)
			)
			(layer "F.Fab")
		)
		(fp_line
			(start 0.120396 0.3048)
			(end 0.120396 0.2794)
			(stroke
				(width 0.1)
				(type default)
			)
			(layer "F.Fab")
		)
		(fp_line
			(start 0.67945 0.3048)
			(end 0.120396 0.3048)
			(stroke
				(width 0.1)
				(type default)
			)
			(layer "F.Fab")
		)
		(fp_line
			(start -0.12065 0.2794)
			(end -0.12065 0.3048)
			(stroke
				(width 0.1)
				(type default)
			)
			(layer "F.Fab")
		)
		(fp_line
			(start 0.120396 0.2794)
			(end -0.12065 0.2794)
			(stroke
				(width 0.1)
				(type default)
			)
			(layer "F.Fab")
		)
		(fp_line
			(start -0.12065 -0.2794)
			(end 0.12065 -0.2794)
			(stroke
				(width 0.1)
				(type default)
			)
			(layer "F.Fab")
		)
		(fp_line
			(start 0.12065 -0.2794)
			(end 0.12065 -0.3048)
			(stroke
				(width 0.1)
				(type default)
			)
			(layer "F.Fab")
		)
		(fp_line
			(start 0.12065 -0.3048)
			(end 0.67945 -0.3048)
			(stroke
				(width 0.1)
				(type default)
			)
			(layer "F.Fab")
		)
		(fp_line
			(start 0.67945 -0.3048)
			(end 0.67945 0.3048)
			(stroke
				(width 0.1)
				(type default)
			)
			(layer "F.Fab")
		)
		(fp_line
			(start -0.67945 -0.305054)
			(end -0.12065 -0.305054)
			(stroke
				(width 0.1)
				(type default)
			)
			(layer "F.Fab")
		)
		(fp_line
			(start -0.12065 -0.305054)
			(end -0.12065 -0.2794)
			(stroke
				(width 0.1)
				(type default)
			)
			(layer "F.Fab")
		)
		(pad "1" smd circle
			(at -0.40005 0 270)
			(size 0 0)
			(layers "F.Cu" "F.Mask" "F.Paste")
			(net "P2E_BUF2_VDD")
		)
		(pad "2" smd circle
			(at 0.40005 0 270)
			(size 0 0)
			(layers "F.Cu" "F.Mask" "F.Paste")
			(net "GND")
		)
	)
	(footprint ""
		(layer "F.Cu")
		(at 312.443622 -35.84194 180)
		(property "Reference" "R1582"
			(at 0 0 180)
			(layer "F.SilkS")
			(hide yes)
			(effects
				(font
					(size 1.27 1.27)
				)
			)
		)
		(property "Value" ""
			(at 0 0 180)
			(layer "F.Fab")
			(effects
				(font
					(size 1.27 1.27)
				)
			)
		)
		(duplicate_pad_numbers_are_jumpers no)
		(fp_line
			(start 0.7874 0.4064)
			(end -0.7874 0.4064)
			(stroke
				(width 0.1524)
				(type default)
			)
			(layer "F.SilkS")
		)
		(fp_line
			(start 0.7874 -0.4064)
			(end 0.7874 0.4064)
			(stroke
				(width 0.1524)
				(type default)
			)
			(layer "F.SilkS")
		)
		(fp_line
			(start -0.7874 0.4064)
			(end -0.7874 -0.4064)
			(stroke
				(width 0.1524)
				(type default)
			)
			(layer "F.SilkS")
		)
		(fp_line
			(start -0.7874 -0.4064)
			(end 0.7874 -0.4064)
			(stroke
				(width 0.1524)
				(type default)
			)
			(layer "F.SilkS")
		)
		(fp_line
			(start 0.67945 0.3048)
			(end 0.120396 0.3048)
			(stroke
				(width 0.1)
				(type default)
			)
			(layer "F.Fab")
		)
		(fp_line
			(start 0.67945 -0.3048)
			(end 0.67945 0.3048)
			(stroke
				(width 0.1)
				(type default)
			)
			(layer "F.Fab")
		)
		(fp_line
			(start 0.12065 -0.2794)
			(end 0.12065 -0.3048)
			(stroke
				(width 0.1)
				(type default)
			)
			(layer "F.Fab")
		)
		(fp_line
			(start 0.12065 -0.3048)
			(end 0.67945 -0.3048)
			(stroke
				(width 0.1)
				(type default)
			)
			(layer "F.Fab")
		)
		(fp_line
			(start 0.120396 0.3048)
			(end 0.120396 0.2794)
			(stroke
				(width 0.1)
				(type default)
			)
			(layer "F.Fab")
		)
		(fp_line
			(start 0.120396 0.2794)
			(end -0.12065 0.2794)
			(stroke
				(width 0.1)
				(type default)
			)
			(layer "F.Fab")
		)
		(fp_line
			(start -0.12065 0.3048)
			(end -0.67945 0.3048)
			(stroke
				(width 0.1)
				(type default)
			)
			(layer "F.Fab")
		)
		(fp_line
			(start -0.12065 0.2794)
			(end -0.12065 0.3048)
			(stroke
				(width 0.1)
				(type default)
			)
			(layer "F.Fab")
		)
		(fp_line
			(start -0.12065 -0.2794)
			(end 0.12065 -0.2794)
			(stroke
				(width 0.1)
				(type default)
			)
			(layer "F.Fab")
		)
		(fp_line
			(start -0.12065 -0.305054)
			(end -0.12065 -0.2794)
			(stroke
				(width 0.1)
				(type default)
			)
			(layer "F.Fab")
		)
		(fp_line
			(start -0.67945 0.3048)
			(end -0.67945 -0.305054)
			(stroke
				(width 0.1)
				(type default)
			)
			(layer "F.Fab")
		)
		(fp_line
			(start -0.67945 -0.305054)
			(end -0.12065 -0.305054)
			(stroke
				(width 0.1)
				(type default)
			)
			(layer "F.Fab")
		)
		(pad "1" smd circle
			(at -0.40005 0 180)
			(size 0 0)
			(layers "F.Cu" "F.Mask" "F.Paste")
			(net "PU_SMB_PCH_PLD_3V3AUX_SDA")
		)
		(pad "2" smd circle
			(at 0.40005 0 180)
			(size 0 0)
			(layers "F.Cu" "F.Mask" "F.Paste")
			(net "P3V3_AUX")
		)
	)
	(footprint ""
		(layer "F.Cu")
		(at 393.724384 -17.612614 90)
		(property "Reference" "C841"
			(at 0 0 90)
			(layer "F.SilkS")
			(hide yes)
			(effects
				(font
					(size 1.27 1.27)
				)
			)
		)
		(property "Value" ""
			(at 0 0 90)
			(layer "F.Fab")
			(effects
				(font
					(size 1.27 1.27)
				)
			)
		)
		(duplicate_pad_numbers_are_jumpers no)
		(fp_line
			(start 0.299974 -0.150114)
			(end 0.299974 0.150114)
			(stroke
				(width 0.1)
				(type default)
			)
			(layer "F.Fab")
		)
		(fp_line
			(start -0.299974 -0.150114)
			(end 0.299974 -0.150114)
			(stroke
				(width 0.1)
				(type default)
			)
			(layer "F.Fab")
		)
		(fp_line
			(start 0.299974 0.150114)
			(end -0.299974 0.150114)
			(stroke
				(width 0.1)
				(type default)
			)
			(layer "F.Fab")
		)
		(fp_line
			(start -0.299974 0.150114)
			(end -0.299974 -0.150114)
			(stroke
				(width 0.1)
				(type default)
			)
			(layer "F.Fab")
		)
		(pad "1" smd rect
			(at -0.2667 0 90)
			(size 0.3048 0.381)
			(layers "F.Cu" "F.Mask" "F.Paste")
			(net "P5E_CPU0_PE1_TX_C_DP<14>")
		)
		(pad "2" smd rect
			(at 0.2667 0 90)
			(size 0.3048 0.381)
			(layers "F.Cu" "F.Mask" "F.Paste")
			(net "P5E_CPU0_PE1_TX_DP<14>")
		)
	)
	(footprint ""
		(layer "F.Cu")
		(at 186.74588 -130.266948 -90)
		(property "Reference" "R287"
			(at 0 0 270)
			(layer "F.SilkS")
			(hide yes)
			(effects
				(font
					(size 1.27 1.27)
				)
			)
		)
		(property "Value" ""
			(at 0 0 270)
			(layer "F.Fab")
			(effects
				(font
					(size 1.27 1.27)
				)
			)
		)
		(duplicate_pad_numbers_are_jumpers no)
		(fp_line
			(start -0.7874 0.4064)
			(end -0.7874 -0.4064)
			(stroke
				(width 0.1524)
				(type default)
			)
			(layer "F.SilkS")
		)
		(fp_line
			(start 0.7874 0.4064)
			(end -0.7874 0.4064)
			(stroke
				(width 0.1524)
				(type default)
			)
			(layer "F.SilkS")
		)
		(fp_line
			(start -0.7874 -0.4064)
			(end 0.7874 -0.4064)
			(stroke
				(width 0.1524)
				(type default)
			)
			(layer "F.SilkS")
		)
		(fp_line
			(start 0.7874 -0.4064)
			(end 0.7874 0.4064)
			(stroke
				(width 0.1524)
				(type default)
			)
			(layer "F.SilkS")
		)
		(fp_line
			(start -0.67945 0.3048)
			(end -0.67945 -0.305054)
			(stroke
				(width 0.1)
				(type default)
			)
			(layer "F.Fab")
		)
		(fp_line
			(start -0.12065 0.3048)
			(end -0.67945 0.3048)
			(stroke
				(width 0.1)
				(type default)
			)
			(layer "F.Fab")
		)
		(fp_line
			(start 0.120396 0.3048)
			(end 0.120396 0.2794)
			(stroke
				(width 0.1)
				(type default)
			)
			(layer "F.Fab")
		)
		(fp_line
			(start 0.67945 0.3048)
			(end 0.120396 0.3048)
			(stroke
				(width 0.1)
				(type default)
			)
			(layer "F.Fab")
		)
		(fp_line
			(start -0.12065 0.2794)
			(end -0.12065 0.3048)
			(stroke
				(width 0.1)
				(type default)
			)
			(layer "F.Fab")
		)
		(fp_line
			(start 0.120396 0.2794)
			(end -0.12065 0.2794)
			(stroke
				(width 0.1)
				(type default)
			)
			(layer "F.Fab")
		)
		(fp_line
			(start -0.12065 -0.2794)
			(end 0.12065 -0.2794)
			(stroke
				(width 0.1)
				(type default)
			)
			(layer "F.Fab")
		)
		(fp_line
			(start 0.12065 -0.2794)
			(end 0.12065 -0.3048)
			(stroke
				(width 0.1)
				(type default)
			)
			(layer "F.Fab")
		)
		(fp_line
			(start 0.12065 -0.3048)
			(end 0.67945 -0.3048)
			(stroke
				(width 0.1)
				(type default)
			)
			(layer "F.Fab")
		)
		(fp_line
			(start 0.67945 -0.3048)
			(end 0.67945 0.3048)
			(stroke
				(width 0.1)
				(type default)
			)
			(layer "F.Fab")
		)
		(fp_line
			(start -0.67945 -0.305054)
			(end -0.12065 -0.305054)
			(stroke
				(width 0.1)
				(type default)
			)
			(layer "F.Fab")
		)
		(fp_line
			(start -0.12065 -0.305054)
			(end -0.12065 -0.2794)
			(stroke
				(width 0.1)
				(type default)
			)
			(layer "F.Fab")
		)
		(pad "1" smd circle
			(at -0.40005 0 270)
			(size 0 0)
			(layers "F.Cu" "F.Mask" "F.Paste")
			(net "P3V3_AUX")
		)
		(pad "2" smd circle
			(at 0.40005 0 270)
			(size 0 0)
			(layers "F.Cu" "F.Mask" "F.Paste")
			(net "FM_CPU0_PROC_ID1")
		)
	)
	(footprint ""
		(layer "F.Cu")
		(at 312.42 -23.9268)
		(property "Reference" "R4789"
			(at 0 0 0)
			(layer "F.SilkS")
			(hide yes)
			(effects
				(font
					(size 1.27 1.27)
				)
			)
		)
		(property "Value" ""
			(at 0 0 0)
			(layer "F.Fab")
			(effects
				(font
					(size 1.27 1.27)
				)
			)
		)
		(duplicate_pad_numbers_are_jumpers no)
		(fp_line
			(start -0.7874 -0.4064)
			(end 0.7874 -0.4064)
			(stroke
				(width 0.1524)
				(type default)
			)
			(layer "F.SilkS")
		)
		(fp_line
			(start -0.7874 0.4064)
			(end -0.7874 -0.4064)
			(stroke
				(width 0.1524)
				(type default)
			)
			(layer "F.SilkS")
		)
		(fp_line
			(start 0.7874 -0.4064)
			(end 0.7874 0.4064)
			(stroke
				(width 0.1524)
				(type default)
			)
			(layer "F.SilkS")
		)
		(fp_line
			(start 0.7874 0.4064)
			(end -0.7874 0.4064)
			(stroke
				(width 0.1524)
				(type default)
			)
			(layer "F.SilkS")
		)
		(fp_line
			(start -0.67945 -0.305054)
			(end -0.12065 -0.305054)
			(stroke
				(width 0.1)
				(type default)
			)
			(layer "F.Fab")
		)
		(fp_line
			(start -0.67945 0.3048)
			(end -0.67945 -0.305054)
			(stroke
				(width 0.1)
				(type default)
			)
			(layer "F.Fab")
		)
		(fp_line
			(start -0.12065 -0.305054)
			(end -0.12065 -0.2794)
			(stroke
				(width 0.1)
				(type default)
			)
			(layer "F.Fab")
		)
		(fp_line
			(start -0.12065 -0.2794)
			(end 0.12065 -0.2794)
			(stroke
				(width 0.1)
				(type default)
			)
			(layer "F.Fab")
		)
		(fp_line
			(start -0.12065 0.2794)
			(end -0.12065 0.3048)
			(stroke
				(width 0.1)
				(type default)
			)
			(layer "F.Fab")
		)
		(fp_line
			(start -0.12065 0.3048)
			(end -0.67945 0.3048)
			(stroke
				(width 0.1)
				(type default)
			)
			(layer "F.Fab")
		)
		(fp_line
			(start 0.120396 0.2794)
			(end -0.12065 0.2794)
			(stroke
				(width 0.1)
				(type default)
			)
			(layer "F.Fab")
		)
		(fp_line
			(start 0.120396 0.3048)
			(end 0.120396 0.2794)
			(stroke
				(width 0.1)
				(type default)
			)
			(layer "F.Fab")
		)
		(fp_line
			(start 0.12065 -0.3048)
			(end 0.67945 -0.3048)
			(stroke
				(width 0.1)
				(type default)
			)
			(layer "F.Fab")
		)
		(fp_line
			(start 0.12065 -0.2794)
			(end 0.12065 -0.3048)
			(stroke
				(width 0.1)
				(type default)
			)
			(layer "F.Fab")
		)
		(fp_line
			(start 0.67945 -0.3048)
			(end 0.67945 0.3048)
			(stroke
				(width 0.1)
				(type default)
			)
			(layer "F.Fab")
		)
		(fp_line
			(start 0.67945 0.3048)
			(end 0.120396 0.3048)
			(stroke
				(width 0.1)
				(type default)
			)
			(layer "F.Fab")
		)
		(pad "1" smd circle
			(at -0.40005 0)
			(size 0 0)
			(layers "F.Cu" "F.Mask" "F.Paste")
			(net "P3V3_AUX")
		)
		(pad "2" smd circle
			(at 0.40005 0)
			(size 0 0)
			(layers "F.Cu" "F.Mask" "F.Paste")
			(net "PWRGD_DSW_PWROK")
		)
	)
	(footprint ""
		(layer "F.Cu")
		(at 170.23588 -437.987948)
		(property "Reference" "R3390"
			(at 0 0 0)
			(layer "F.SilkS")
			(hide yes)
			(effects
				(font
					(size 1.27 1.27)
				)
			)
		)
		(property "Value" ""
			(at 0 0 0)
			(layer "F.Fab")
			(effects
				(font
					(size 1.27 1.27)
				)
			)
		)
		(duplicate_pad_numbers_are_jumpers no)
		(fp_line
			(start -0.7874 -0.4064)
			(end 0.7874 -0.4064)
			(stroke
				(width 0.1524)
				(type default)
			)
			(layer "F.SilkS")
		)
		(fp_line
			(start -0.7874 0.4064)
			(end -0.7874 -0.4064)
			(stroke
				(width 0.1524)
				(type default)
			)
			(layer "F.SilkS")
		)
		(fp_line
			(start 0.7874 -0.4064)
			(end 0.7874 0.4064)
			(stroke
				(width 0.1524)
				(type default)
			)
			(layer "F.SilkS")
		)
		(fp_line
			(start 0.7874 0.4064)
			(end -0.7874 0.4064)
			(stroke
				(width 0.1524)
				(type default)
			)
			(layer "F.SilkS")
		)
		(fp_line
			(start -0.67945 -0.305054)
			(end -0.12065 -0.305054)
			(stroke
				(width 0.1)
				(type default)
			)
			(layer "F.Fab")
		)
		(fp_line
			(start -0.67945 0.3048)
			(end -0.67945 -0.305054)
			(stroke
				(width 0.1)
				(type default)
			)
			(layer "F.Fab")
		)
		(fp_line
			(start -0.12065 -0.305054)
			(end -0.12065 -0.2794)
			(stroke
				(width 0.1)
				(type default)
			)
			(layer "F.Fab")
		)
		(fp_line
			(start -0.12065 -0.2794)
			(end 0.12065 -0.2794)
			(stroke
				(width 0.1)
				(type default)
			)
			(layer "F.Fab")
		)
		(fp_line
			(start -0.12065 0.2794)
			(end -0.12065 0.3048)
			(stroke
				(width 0.1)
				(type default)
			)
			(layer "F.Fab")
		)
		(fp_line
			(start -0.12065 0.3048)
			(end -0.67945 0.3048)
			(stroke
				(width 0.1)
				(type default)
			)
			(layer "F.Fab")
		)
		(fp_line
			(start 0.120396 0.2794)
			(end -0.12065 0.2794)
			(stroke
				(width 0.1)
				(type default)
			)
			(layer "F.Fab")
		)
		(fp_line
			(start 0.120396 0.3048)
			(end 0.120396 0.2794)
			(stroke
				(width 0.1)
				(type default)
			)
			(layer "F.Fab")
		)
		(fp_line
			(start 0.12065 -0.3048)
			(end 0.67945 -0.3048)
			(stroke
				(width 0.1)
				(type default)
			)
			(layer "F.Fab")
		)
		(fp_line
			(start 0.12065 -0.2794)
			(end 0.12065 -0.3048)
			(stroke
				(width 0.1)
				(type default)
			)
			(layer "F.Fab")
		)
		(fp_line
			(start 0.67945 -0.3048)
			(end 0.67945 0.3048)
			(stroke
				(width 0.1)
				(type default)
			)
			(layer "F.Fab")
		)
		(fp_line
			(start 0.67945 0.3048)
			(end 0.120396 0.3048)
			(stroke
				(width 0.1)
				(type default)
			)
			(layer "F.Fab")
		)
		(pad "1" smd circle
			(at -0.40005 0)
			(size 0 0)
			(layers "F.Cu" "F.Mask" "F.Paste")
			(net "GPU_FPGA_BOOT_EN_BUF_R")
		)
		(pad "2" smd circle
			(at 0.40005 0)
			(size 0 0)
			(layers "F.Cu" "F.Mask" "F.Paste")
			(net "GPU_FPGA_BOOT_EN_BUF")
		)
	)
	(footprint ""
		(layer "F.Cu")
		(at 374.032018 -16.34617 180)
		(property "Reference" "R4601"
			(at 0 0 180)
			(layer "F.SilkS")
			(hide yes)
			(effects
				(font
					(size 1.27 1.27)
				)
			)
		)
		(property "Value" ""
			(at 0 0 180)
			(layer "F.Fab")
			(effects
				(font
					(size 1.27 1.27)
				)
			)
		)
		(duplicate_pad_numbers_are_jumpers no)
		(fp_line
			(start 0.7874 0.4064)
			(end -0.7874 0.4064)
			(stroke
				(width 0.1524)
				(type default)
			)
			(layer "F.SilkS")
		)
		(fp_line
			(start 0.7874 -0.4064)
			(end 0.7874 0.4064)
			(stroke
				(width 0.1524)
				(type default)
			)
			(layer "F.SilkS")
		)
		(fp_line
			(start -0.7874 0.4064)
			(end -0.7874 -0.4064)
			(stroke
				(width 0.1524)
				(type default)
			)
			(layer "F.SilkS")
		)
		(fp_line
			(start -0.7874 -0.4064)
			(end 0.7874 -0.4064)
			(stroke
				(width 0.1524)
				(type default)
			)
			(layer "F.SilkS")
		)
		(fp_line
			(start 0.67945 0.3048)
			(end 0.120396 0.3048)
			(stroke
				(width 0.1)
				(type default)
			)
			(layer "F.Fab")
		)
		(fp_line
			(start 0.67945 -0.3048)
			(end 0.67945 0.3048)
			(stroke
				(width 0.1)
				(type default)
			)
			(layer "F.Fab")
		)
		(fp_line
			(start 0.12065 -0.2794)
			(end 0.12065 -0.3048)
			(stroke
				(width 0.1)
				(type default)
			)
			(layer "F.Fab")
		)
		(fp_line
			(start 0.12065 -0.3048)
			(end 0.67945 -0.3048)
			(stroke
				(width 0.1)
				(type default)
			)
			(layer "F.Fab")
		)
		(fp_line
			(start 0.120396 0.3048)
			(end 0.120396 0.2794)
			(stroke
				(width 0.1)
				(type default)
			)
			(layer "F.Fab")
		)
		(fp_line
			(start 0.120396 0.2794)
			(end -0.12065 0.2794)
			(stroke
				(width 0.1)
				(type default)
			)
			(layer "F.Fab")
		)
		(fp_line
			(start -0.12065 0.3048)
			(end -0.67945 0.3048)
			(stroke
				(width 0.1)
				(type default)
			)
			(layer "F.Fab")
		)
		(fp_line
			(start -0.12065 0.2794)
			(end -0.12065 0.3048)
			(stroke
				(width 0.1)
				(type default)
			)
			(layer "F.Fab")
		)
		(fp_line
			(start -0.12065 -0.2794)
			(end 0.12065 -0.2794)
			(stroke
				(width 0.1)
				(type default)
			)
			(layer "F.Fab")
		)
		(fp_line
			(start -0.12065 -0.305054)
			(end -0.12065 -0.2794)
			(stroke
				(width 0.1)
				(type default)
			)
			(layer "F.Fab")
		)
		(fp_line
			(start -0.67945 0.3048)
			(end -0.67945 -0.305054)
			(stroke
				(width 0.1)
				(type default)
			)
			(layer "F.Fab")
		)
		(fp_line
			(start -0.67945 -0.305054)
			(end -0.12065 -0.305054)
			(stroke
				(width 0.1)
				(type default)
			)
			(layer "F.Fab")
		)
		(pad "1" smd circle
			(at -0.40005 0 180)
			(size 0 0)
			(layers "F.Cu" "F.Mask" "F.Paste")
			(net "CLK_50M_NCSI_OCP_SFF_ISO")
		)
		(pad "2" smd circle
			(at 0.40005 0 180)
			(size 0 0)
			(layers "F.Cu" "F.Mask" "F.Paste")
			(net "CLK_50M_NCSI_OCP_SFF_ISO_R")
		)
	)
	(footprint ""
		(layer "F.Cu")
		(at 323.815456 -27.612848 90)
		(property "Reference" "R2966"
			(at 0 0 90)
			(layer "F.SilkS")
			(hide yes)
			(effects
				(font
					(size 1.27 1.27)
				)
			)
		)
		(property "Value" ""
			(at 0 0 90)
			(layer "F.Fab")
			(effects
				(font
					(size 1.27 1.27)
				)
			)
		)
		(duplicate_pad_numbers_are_jumpers no)
		(fp_line
			(start 0.7874 -0.4064)
			(end 0.7874 0.4064)
			(stroke
				(width 0.1524)
				(type default)
			)
			(layer "F.SilkS")
		)
		(fp_line
			(start -0.7874 -0.4064)
			(end 0.7874 -0.4064)
			(stroke
				(width 0.1524)
				(type default)
			)
			(layer "F.SilkS")
		)
		(fp_line
			(start 0.7874 0.4064)
			(end -0.7874 0.4064)
			(stroke
				(width 0.1524)
				(type default)
			)
			(layer "F.SilkS")
		)
		(fp_line
			(start -0.7874 0.4064)
			(end -0.7874 -0.4064)
			(stroke
				(width 0.1524)
				(type default)
			)
			(layer "F.SilkS")
		)
		(fp_line
			(start -0.12065 -0.305054)
			(end -0.12065 -0.2794)
			(stroke
				(width 0.1)
				(type default)
			)
			(layer "F.Fab")
		)
		(fp_line
			(start -0.67945 -0.305054)
			(end -0.12065 -0.305054)
			(stroke
				(width 0.1)
				(type default)
			)
			(layer "F.Fab")
		)
		(fp_line
			(start 0.67945 -0.3048)
			(end 0.67945 0.3048)
			(stroke
				(width 0.1)
				(type default)
			)
			(layer "F.Fab")
		)
		(fp_line
			(start 0.12065 -0.3048)
			(end 0.67945 -0.3048)
			(stroke
				(width 0.1)
				(type default)
			)
			(layer "F.Fab")
		)
		(fp_line
			(start 0.12065 -0.2794)
			(end 0.12065 -0.3048)
			(stroke
				(width 0.1)
				(type default)
			)
			(layer "F.Fab")
		)
		(fp_line
			(start -0.12065 -0.2794)
			(end 0.12065 -0.2794)
			(stroke
				(width 0.1)
				(type default)
			)
			(layer "F.Fab")
		)
		(fp_line
			(start 0.120396 0.2794)
			(end -0.12065 0.2794)
			(stroke
				(width 0.1)
				(type default)
			)
			(layer "F.Fab")
		)
		(fp_line
			(start -0.12065 0.2794)
			(end -0.12065 0.3048)
			(stroke
				(width 0.1)
				(type default)
			)
			(layer "F.Fab")
		)
		(fp_line
			(start 0.67945 0.3048)
			(end 0.120396 0.3048)
			(stroke
				(width 0.1)
				(type default)
			)
			(layer "F.Fab")
		)
		(fp_line
			(start 0.120396 0.3048)
			(end 0.120396 0.2794)
			(stroke
				(width 0.1)
				(type default)
			)
			(layer "F.Fab")
		)
		(fp_line
			(start -0.12065 0.3048)
			(end -0.67945 0.3048)
			(stroke
				(width 0.1)
				(type default)
			)
			(layer "F.Fab")
		)
		(fp_line
			(start -0.67945 0.3048)
			(end -0.67945 -0.305054)
			(stroke
				(width 0.1)
				(type default)
			)
			(layer "F.Fab")
		)
		(pad "1" smd circle
			(at -0.40005 0 90)
			(size 0 0)
			(layers "F.Cu" "F.Mask" "F.Paste")
			(net "P3V3_RTC_AUX")
		)
		(pad "2" smd circle
			(at 0.40005 0 90)
			(size 0 0)
			(layers "F.Cu" "F.Mask" "F.Paste")
			(net "FM_INTRUDER_HDR_PCH_N")
		)
	)
	(footprint ""
		(layer "F.Cu")
		(at 205.6384 -97.6884 -90)
		(property "Reference" "R4778"
			(at 0 0 270)
			(layer "F.SilkS")
			(hide yes)
			(effects
				(font
					(size 1.27 1.27)
				)
			)
		)
		(property "Value" ""
			(at 0 0 270)
			(layer "F.Fab")
			(effects
				(font
					(size 1.27 1.27)
				)
			)
		)
		(duplicate_pad_numbers_are_jumpers no)
		(fp_line
			(start -0.7874 0.4064)
			(end -0.7874 -0.4064)
			(stroke
				(width 0.1524)
				(type default)
			)
			(layer "F.SilkS")
		)
		(fp_line
			(start 0.7874 0.4064)
			(end -0.7874 0.4064)
			(stroke
				(width 0.1524)
				(type default)
			)
			(layer "F.SilkS")
		)
		(fp_line
			(start -0.7874 -0.4064)
			(end 0.7874 -0.4064)
			(stroke
				(width 0.1524)
				(type default)
			)
			(layer "F.SilkS")
		)
		(fp_line
			(start 0.7874 -0.4064)
			(end 0.7874 0.4064)
			(stroke
				(width 0.1524)
				(type default)
			)
			(layer "F.SilkS")
		)
		(fp_line
			(start -0.67945 0.3048)
			(end -0.67945 -0.305054)
			(stroke
				(width 0.1)
				(type default)
			)
			(layer "F.Fab")
		)
		(fp_line
			(start -0.12065 0.3048)
			(end -0.67945 0.3048)
			(stroke
				(width 0.1)
				(type default)
			)
			(layer "F.Fab")
		)
		(fp_line
			(start 0.120396 0.3048)
			(end 0.120396 0.2794)
			(stroke
				(width 0.1)
				(type default)
			)
			(layer "F.Fab")
		)
		(fp_line
			(start 0.67945 0.3048)
			(end 0.120396 0.3048)
			(stroke
				(width 0.1)
				(type default)
			)
			(layer "F.Fab")
		)
		(fp_line
			(start -0.12065 0.2794)
			(end -0.12065 0.3048)
			(stroke
				(width 0.1)
				(type default)
			)
			(layer "F.Fab")
		)
		(fp_line
			(start 0.120396 0.2794)
			(end -0.12065 0.2794)
			(stroke
				(width 0.1)
				(type default)
			)
			(layer "F.Fab")
		)
		(fp_line
			(start -0.12065 -0.2794)
			(end 0.12065 -0.2794)
			(stroke
				(width 0.1)
				(type default)
			)
			(layer "F.Fab")
		)
		(fp_line
			(start 0.12065 -0.2794)
			(end 0.12065 -0.3048)
			(stroke
				(width 0.1)
				(type default)
			)
			(layer "F.Fab")
		)
		(fp_line
			(start 0.12065 -0.3048)
			(end 0.67945 -0.3048)
			(stroke
				(width 0.1)
				(type default)
			)
			(layer "F.Fab")
		)
		(fp_line
			(start 0.67945 -0.3048)
			(end 0.67945 0.3048)
			(stroke
				(width 0.1)
				(type default)
			)
			(layer "F.Fab")
		)
		(fp_line
			(start -0.67945 -0.305054)
			(end -0.12065 -0.305054)
			(stroke
				(width 0.1)
				(type default)
			)
			(layer "F.Fab")
		)
		(fp_line
			(start -0.12065 -0.305054)
			(end -0.12065 -0.2794)
			(stroke
				(width 0.1)
				(type default)
			)
			(layer "F.Fab")
		)
		(pad "1" smd circle
			(at -0.40005 0 270)
			(size 0 0)
			(layers "F.Cu" "F.Mask" "F.Paste")
			(net "P12V_AUX_UV_ADR_TRIGGER")
		)
		(pad "2" smd circle
			(at 0.40005 0 270)
			(size 0 0)
			(layers "F.Cu" "F.Mask" "F.Paste")
			(net "FM_UV_ADR_TRIGGER_N_R2")
		)
	)
	(footprint ""
		(layer "F.Cu")
		(at 202.7936 -92.6338 90)
		(property "Reference" "R4772"
			(at 0 0 90)
			(layer "F.SilkS")
			(hide yes)
			(effects
				(font
					(size 1.27 1.27)
				)
			)
		)
		(property "Value" ""
			(at 0 0 90)
			(layer "F.Fab")
			(effects
				(font
					(size 1.27 1.27)
				)
			)
		)
		(duplicate_pad_numbers_are_jumpers no)
		(fp_line
			(start 0.7874 -0.4064)
			(end 0.7874 0.4064)
			(stroke
				(width 0.1524)
				(type default)
			)
			(layer "F.SilkS")
		)
		(fp_line
			(start -0.7874 -0.4064)
			(end 0.7874 -0.4064)
			(stroke
				(width 0.1524)
				(type default)
			)
			(layer "F.SilkS")
		)
		(fp_line
			(start 0.7874 0.4064)
			(end -0.7874 0.4064)
			(stroke
				(width 0.1524)
				(type default)
			)
			(layer "F.SilkS")
		)
		(fp_line
			(start -0.7874 0.4064)
			(end -0.7874 -0.4064)
			(stroke
				(width 0.1524)
				(type default)
			)
			(layer "F.SilkS")
		)
		(fp_line
			(start -0.12065 -0.305054)
			(end -0.12065 -0.2794)
			(stroke
				(width 0.1)
				(type default)
			)
			(layer "F.Fab")
		)
		(fp_line
			(start -0.67945 -0.305054)
			(end -0.12065 -0.305054)
			(stroke
				(width 0.1)
				(type default)
			)
			(layer "F.Fab")
		)
		(fp_line
			(start 0.67945 -0.3048)
			(end 0.67945 0.3048)
			(stroke
				(width 0.1)
				(type default)
			)
			(layer "F.Fab")
		)
		(fp_line
			(start 0.12065 -0.3048)
			(end 0.67945 -0.3048)
			(stroke
				(width 0.1)
				(type default)
			)
			(layer "F.Fab")
		)
		(fp_line
			(start 0.12065 -0.2794)
			(end 0.12065 -0.3048)
			(stroke
				(width 0.1)
				(type default)
			)
			(layer "F.Fab")
		)
		(fp_line
			(start -0.12065 -0.2794)
			(end 0.12065 -0.2794)
			(stroke
				(width 0.1)
				(type default)
			)
			(layer "F.Fab")
		)
		(fp_line
			(start 0.120396 0.2794)
			(end -0.12065 0.2794)
			(stroke
				(width 0.1)
				(type default)
			)
			(layer "F.Fab")
		)
		(fp_line
			(start -0.12065 0.2794)
			(end -0.12065 0.3048)
			(stroke
				(width 0.1)
				(type default)
			)
			(layer "F.Fab")
		)
		(fp_line
			(start 0.67945 0.3048)
			(end 0.120396 0.3048)
			(stroke
				(width 0.1)
				(type default)
			)
			(layer "F.Fab")
		)
		(fp_line
			(start 0.120396 0.3048)
			(end 0.120396 0.2794)
			(stroke
				(width 0.1)
				(type default)
			)
			(layer "F.Fab")
		)
		(fp_line
			(start -0.12065 0.3048)
			(end -0.67945 0.3048)
			(stroke
				(width 0.1)
				(type default)
			)
			(layer "F.Fab")
		)
		(fp_line
			(start -0.67945 0.3048)
			(end -0.67945 -0.305054)
			(stroke
				(width 0.1)
				(type default)
			)
			(layer "F.Fab")
		)
		(pad "1" smd circle
			(at -0.40005 0 90)
			(size 0 0)
			(layers "F.Cu" "F.Mask" "F.Paste")
			(net "P3V3_AUX")
		)
		(pad "2" smd circle
			(at 0.40005 0 90)
			(size 0 0)
			(layers "F.Cu" "F.Mask" "F.Paste")
			(net "UV_ADR_P2V5_COMP")
		)
	)
	(footprint ""
		(layer "F.Cu")
		(at 369.6208 -16.271748 180)
		(property "Reference" "U320"
			(at 1.64338 -2.461768 0)
			(unlocked yes)
			(layer "F.SilkS")
			(effects
				(font
					(size 0.7874 0.5842)
					(thickness 0.1524)
				)
				(justify left)
			)
		)
		(property "Value" ""
			(at 0 0 180)
			(layer "F.Fab")
			(effects
				(font
					(size 1.27 1.27)
				)
			)
		)
		(duplicate_pad_numbers_are_jumpers no)
		(fp_line
			(start 2.032 1.549908)
			(end -2.032 1.549908)
			(stroke
				(width 0.1524)
				(type default)
			)
			(layer "F.SilkS")
		)
		(fp_line
			(start 2.032 -1.549908)
			(end 2.032 1.549908)
			(stroke
				(width 0.1524)
				(type default)
			)
			(layer "F.SilkS")
		)
		(fp_line
			(start -2.032 1.549908)
			(end -2.032 -1.549908)
			(stroke
				(width 0.1524)
				(type default)
			)
			(layer "F.SilkS")
		)
		(fp_line
			(start -2.032 -1.549908)
			(end 2.032 -1.549908)
			(stroke
				(width 0.1524)
				(type default)
			)
			(layer "F.SilkS")
		)
		(fp_poly
			(pts
				(xy -2.629408 -2.512568) (xy -2.988564 -2.153412) (xy -2.270252 -1.794002)
			)
			(stroke
				(width 0)
				(type default)
			)
			(fill yes)
			(layer "F.SilkS")
		)
		(fp_line
			(start 0.849884 1.549908)
			(end 0.849884 -1.549908)
			(stroke
				(width 0.1)
				(type default)
			)
			(layer "F.Fab")
		)
		(fp_line
			(start 0.849884 -1.549908)
			(end -0.849884 -1.549908)
			(stroke
				(width 0.1)
				(type default)
			)
			(layer "F.Fab")
		)
		(fp_line
			(start -0.849884 1.549908)
			(end 0.849884 1.549908)
			(stroke
				(width 0.1)
				(type default)
			)
			(layer "F.Fab")
		)
		(fp_line
			(start -0.849884 -1.549908)
			(end -0.849884 1.549908)
			(stroke
				(width 0.1)
				(type default)
			)
			(layer "F.Fab")
		)
		(fp_poly
			(pts
				(xy -2.9464 -1.2192) (xy -2.9464 -0.7112) (xy -2.1844 -0.9652)
			)
			(stroke
				(width 0)
				(type default)
			)
			(fill yes)
			(layer "F.Fab")
		)
		(pad "1" smd rect
			(at -1.225042 -0.94996 90)
			(size 0.4572 1.3208)
			(layers "F.Cu" "F.Mask" "F.Paste")
			(net "CLK_50M_NCSI_OCP_SFF")
		)
		(pad "2" smd rect
			(at -1.225042 0 90)
			(size 0.4572 1.3208)
			(layers "F.Cu" "F.Mask" "F.Paste")
			(net "CLK_50M_NCSI_OCP_SFF_ISO_R")
		)
		(pad "3" smd rect
			(at -1.225042 0.94996 90)
			(size 0.4572 1.3208)
			(layers "F.Cu" "F.Mask" "F.Paste")
			(net "GND")
		)
		(pad "4" smd rect
			(at 1.225042 0.94996 90)
			(size 0.4572 1.3208)
			(layers "F.Cu" "F.Mask" "F.Paste")
			(net "FB_BMC_ISOLATE")
		)
		(pad "5" smd rect
			(at 1.225042 -0.94996 90)
			(size 0.4572 1.3208)
			(layers "F.Cu" "F.Mask" "F.Paste")
			(net "P3V3_AUX")
		)
	)
	(footprint ""
		(layer "F.Cu")
		(at 220.190822 -56.835802 180)
		(property "Reference" "R3760"
			(at 0 0 180)
			(layer "F.SilkS")
			(hide yes)
			(effects
				(font
					(size 1.27 1.27)
				)
			)
		)
		(property "Value" ""
			(at 0 0 180)
			(layer "F.Fab")
			(effects
				(font
					(size 1.27 1.27)
				)
			)
		)
		(duplicate_pad_numbers_are_jumpers no)
		(fp_line
			(start 0.7874 0.4064)
			(end -0.7874 0.4064)
			(stroke
				(width 0.1524)
				(type default)
			)
			(layer "F.SilkS")
		)
		(fp_line
			(start 0.7874 -0.4064)
			(end 0.7874 0.4064)
			(stroke
				(width 0.1524)
				(type default)
			)
			(layer "F.SilkS")
		)
		(fp_line
			(start -0.7874 0.4064)
			(end -0.7874 -0.4064)
			(stroke
				(width 0.1524)
				(type default)
			)
			(layer "F.SilkS")
		)
		(fp_line
			(start -0.7874 -0.4064)
			(end 0.7874 -0.4064)
			(stroke
				(width 0.1524)
				(type default)
			)
			(layer "F.SilkS")
		)
		(fp_line
			(start 0.67945 0.3048)
			(end 0.120396 0.3048)
			(stroke
				(width 0.1)
				(type default)
			)
			(layer "F.Fab")
		)
		(fp_line
			(start 0.67945 -0.3048)
			(end 0.67945 0.3048)
			(stroke
				(width 0.1)
				(type default)
			)
			(layer "F.Fab")
		)
		(fp_line
			(start 0.12065 -0.2794)
			(end 0.12065 -0.3048)
			(stroke
				(width 0.1)
				(type default)
			)
			(layer "F.Fab")
		)
		(fp_line
			(start 0.12065 -0.3048)
			(end 0.67945 -0.3048)
			(stroke
				(width 0.1)
				(type default)
			)
			(layer "F.Fab")
		)
		(fp_line
			(start 0.120396 0.3048)
			(end 0.120396 0.2794)
			(stroke
				(width 0.1)
				(type default)
			)
			(layer "F.Fab")
		)
		(fp_line
			(start 0.120396 0.2794)
			(end -0.12065 0.2794)
			(stroke
				(width 0.1)
				(type default)
			)
			(layer "F.Fab")
		)
		(fp_line
			(start -0.12065 0.3048)
			(end -0.67945 0.3048)
			(stroke
				(width 0.1)
				(type default)
			)
			(layer "F.Fab")
		)
		(fp_line
			(start -0.12065 0.2794)
			(end -0.12065 0.3048)
			(stroke
				(width 0.1)
				(type default)
			)
			(layer "F.Fab")
		)
		(fp_line
			(start -0.12065 -0.2794)
			(end 0.12065 -0.2794)
			(stroke
				(width 0.1)
				(type default)
			)
			(layer "F.Fab")
		)
		(fp_line
			(start -0.12065 -0.305054)
			(end -0.12065 -0.2794)
			(stroke
				(width 0.1)
				(type default)
			)
			(layer "F.Fab")
		)
		(fp_line
			(start -0.67945 0.3048)
			(end -0.67945 -0.305054)
			(stroke
				(width 0.1)
				(type default)
			)
			(layer "F.Fab")
		)
		(fp_line
			(start -0.67945 -0.305054)
			(end -0.12065 -0.305054)
			(stroke
				(width 0.1)
				(type default)
			)
			(layer "F.Fab")
		)
		(pad "1" smd circle
			(at -0.40005 0 180)
			(size 0 0)
			(layers "F.Cu" "F.Mask" "F.Paste")
			(net "P3V3_E1S_0")
		)
		(pad "2" smd circle
			(at 0.40005 0 180)
			(size 0 0)
			(layers "F.Cu" "F.Mask" "F.Paste")
			(net "VSENSE_P3V3_INA230_2_INN")
		)
	)
	(footprint ""
		(layer "F.Cu")
		(at 387.526022 -347.520514 -90)
		(property "Reference" "PC234"
			(at 0 0 270)
			(layer "F.SilkS")
			(hide yes)
			(effects
				(font
					(size 1.27 1.27)
				)
			)
		)
		(property "Value" ""
			(at 0 0 270)
			(layer "F.Fab")
			(effects
				(font
					(size 1.27 1.27)
				)
			)
		)
		(duplicate_pad_numbers_are_jumpers no)
		(fp_line
			(start -0.7874 0.4064)
			(end -0.7874 -0.4064)
			(stroke
				(width 0.1524)
				(type default)
			)
			(layer "F.SilkS")
		)
		(fp_line
			(start 0.7874 0.4064)
			(end -0.7874 0.4064)
			(stroke
				(width 0.1524)
				(type default)
			)
			(layer "F.SilkS")
		)
		(fp_line
			(start -0.7874 -0.4064)
			(end 0.7874 -0.4064)
			(stroke
				(width 0.1524)
				(type default)
			)
			(layer "F.SilkS")
		)
		(fp_line
			(start 0.7874 -0.4064)
			(end 0.7874 0.4064)
			(stroke
				(width 0.1524)
				(type default)
			)
			(layer "F.SilkS")
		)
		(fp_line
			(start -0.67945 0.3048)
			(end -0.67945 -0.305054)
			(stroke
				(width 0.1)
				(type default)
			)
			(layer "F.Fab")
		)
		(fp_line
			(start -0.12065 0.3048)
			(end -0.67945 0.3048)
			(stroke
				(width 0.1)
				(type default)
			)
			(layer "F.Fab")
		)
		(fp_line
			(start 0.120396 0.3048)
			(end 0.120396 0.2794)
			(stroke
				(width 0.1)
				(type default)
			)
			(layer "F.Fab")
		)
		(fp_line
			(start 0.67945 0.3048)
			(end 0.120396 0.3048)
			(stroke
				(width 0.1)
				(type default)
			)
			(layer "F.Fab")
		)
		(fp_line
			(start -0.12065 0.2794)
			(end -0.12065 0.3048)
			(stroke
				(width 0.1)
				(type default)
			)
			(layer "F.Fab")
		)
		(fp_line
			(start 0.120396 0.2794)
			(end -0.12065 0.2794)
			(stroke
				(width 0.1)
				(type default)
			)
			(layer "F.Fab")
		)
		(fp_line
			(start -0.12065 -0.2794)
			(end 0.12065 -0.2794)
			(stroke
				(width 0.1)
				(type default)
			)
			(layer "F.Fab")
		)
		(fp_line
			(start 0.12065 -0.2794)
			(end 0.12065 -0.3048)
			(stroke
				(width 0.1)
				(type default)
			)
			(layer "F.Fab")
		)
		(fp_line
			(start 0.12065 -0.3048)
			(end 0.67945 -0.3048)
			(stroke
				(width 0.1)
				(type default)
			)
			(layer "F.Fab")
		)
		(fp_line
			(start 0.67945 -0.3048)
			(end 0.67945 0.3048)
			(stroke
				(width 0.1)
				(type default)
			)
			(layer "F.Fab")
		)
		(fp_line
			(start -0.67945 -0.305054)
			(end -0.12065 -0.305054)
			(stroke
				(width 0.1)
				(type default)
			)
			(layer "F.Fab")
		)
		(fp_line
			(start -0.12065 -0.305054)
			(end -0.12065 -0.2794)
			(stroke
				(width 0.1)
				(type default)
			)
			(layer "F.Fab")
		)
		(pad "1" smd circle
			(at -0.40005 0 270)
			(size 0 0)
			(layers "F.Cu" "F.Mask" "F.Paste")
			(net "SW_PVCCIN_CPU0_BOOT8_R")
		)
		(pad "2" smd circle
			(at 0.40005 0 270)
			(size 0 0)
			(layers "F.Cu" "F.Mask" "F.Paste")
			(net "SW_PVCCIN_CPU0_BOOTR8")
		)
	)
	(footprint ""
		(layer "F.Cu")
		(at 164.247576 -38.067234 180)
		(property "Reference" "R4457"
			(at 0 0 180)
			(layer "F.SilkS")
			(hide yes)
			(effects
				(font
					(size 1.27 1.27)
				)
			)
		)
		(property "Value" ""
			(at 0 0 180)
			(layer "F.Fab")
			(effects
				(font
					(size 1.27 1.27)
				)
			)
		)
		(duplicate_pad_numbers_are_jumpers no)
		(fp_line
			(start 0.7874 0.4064)
			(end -0.7874 0.4064)
			(stroke
				(width 0.1524)
				(type default)
			)
			(layer "F.SilkS")
		)
		(fp_line
			(start 0.7874 -0.4064)
			(end 0.7874 0.4064)
			(stroke
				(width 0.1524)
				(type default)
			)
			(layer "F.SilkS")
		)
		(fp_line
			(start -0.7874 0.4064)
			(end -0.7874 -0.4064)
			(stroke
				(width 0.1524)
				(type default)
			)
			(layer "F.SilkS")
		)
		(fp_line
			(start -0.7874 -0.4064)
			(end 0.7874 -0.4064)
			(stroke
				(width 0.1524)
				(type default)
			)
			(layer "F.SilkS")
		)
		(fp_line
			(start 0.67945 0.3048)
			(end 0.120396 0.3048)
			(stroke
				(width 0.1)
				(type default)
			)
			(layer "F.Fab")
		)
		(fp_line
			(start 0.67945 -0.3048)
			(end 0.67945 0.3048)
			(stroke
				(width 0.1)
				(type default)
			)
			(layer "F.Fab")
		)
		(fp_line
			(start 0.12065 -0.2794)
			(end 0.12065 -0.3048)
			(stroke
				(width 0.1)
				(type default)
			)
			(layer "F.Fab")
		)
		(fp_line
			(start 0.12065 -0.3048)
			(end 0.67945 -0.3048)
			(stroke
				(width 0.1)
				(type default)
			)
			(layer "F.Fab")
		)
		(fp_line
			(start 0.120396 0.3048)
			(end 0.120396 0.2794)
			(stroke
				(width 0.1)
				(type default)
			)
			(layer "F.Fab")
		)
		(fp_line
			(start 0.120396 0.2794)
			(end -0.12065 0.2794)
			(stroke
				(width 0.1)
				(type default)
			)
			(layer "F.Fab")
		)
		(fp_line
			(start -0.12065 0.3048)
			(end -0.67945 0.3048)
			(stroke
				(width 0.1)
				(type default)
			)
			(layer "F.Fab")
		)
		(fp_line
			(start -0.12065 0.2794)
			(end -0.12065 0.3048)
			(stroke
				(width 0.1)
				(type default)
			)
			(layer "F.Fab")
		)
		(fp_line
			(start -0.12065 -0.2794)
			(end 0.12065 -0.2794)
			(stroke
				(width 0.1)
				(type default)
			)
			(layer "F.Fab")
		)
		(fp_line
			(start -0.12065 -0.305054)
			(end -0.12065 -0.2794)
			(stroke
				(width 0.1)
				(type default)
			)
			(layer "F.Fab")
		)
		(fp_line
			(start -0.67945 0.3048)
			(end -0.67945 -0.305054)
			(stroke
				(width 0.1)
				(type default)
			)
			(layer "F.Fab")
		)
		(fp_line
			(start -0.67945 -0.305054)
			(end -0.12065 -0.305054)
			(stroke
				(width 0.1)
				(type default)
			)
			(layer "F.Fab")
		)
		(pad "1" smd circle
			(at -0.40005 0 180)
			(size 0 0)
			(layers "F.Cu" "F.Mask" "F.Paste")
			(net "P3V3_AUX")
		)
		(pad "2" smd circle
			(at 0.40005 0 180)
			(size 0 0)
			(layers "F.Cu" "F.Mask" "F.Paste")
			(net "USB_HUB_2_OVCUR2")
		)
	)
	(footprint ""
		(layer "F.Cu")
		(at 277.894796 -153.76652)
		(property "Reference" "H122"
			(at -2.5527 -8.20293 0)
			(unlocked yes)
			(layer "F.SilkS")
			(effects
				(font
					(size 0.7874 0.5842)
					(thickness 0.1524)
				)
				(justify left)
			)
		)
		(property "Value" ""
			(at 0 0 0)
			(layer "F.Fab")
			(effects
				(font
					(size 1.27 1.27)
				)
			)
		)
		(duplicate_pad_numbers_are_jumpers no)
		(fp_circle
			(center 0 0)
			(end 5.8166 0)
			(stroke
				(width 0.1524)
				(type default)
			)
			(fill no)
			(layer "F.SilkS")
		)
		(fp_circle
			(center 0 0)
			(end 5.8166 0)
			(stroke
				(width 0.1524)
				(type default)
			)
			(fill no)
			(layer "B.SilkS")
		)
		(fp_circle
			(center 0 0)
			(end 5.8166 0)
			(stroke
				(width 0.1)
				(type default)
			)
			(fill no)
			(layer "B.Fab")
		)
		(fp_circle
			(center 0 0)
			(end 5.8166 0)
			(stroke
				(width 0.1)
				(type default)
			)
			(fill no)
			(layer "F.Fab")
		)
		(pad "" np_thru_hole circle
			(at 0 0)
			(size 10.0076 10.0076)
			(drill 10.0076)
			(layers "*.Cu" "*.Mask")
			(clearance 0.381)
			(thermal_gap 0.381)
		)
	)
	(footprint ""
		(layer "F.Cu")
		(at 333.986124 -25.956006 -90)
		(property "Reference" "R1868"
			(at 0 0 270)
			(layer "F.SilkS")
			(hide yes)
			(effects
				(font
					(size 1.27 1.27)
				)
			)
		)
		(property "Value" ""
			(at 0 0 270)
			(layer "F.Fab")
			(effects
				(font
					(size 1.27 1.27)
				)
			)
		)
		(duplicate_pad_numbers_are_jumpers no)
		(fp_line
			(start -0.7874 0.4064)
			(end -0.7874 -0.4064)
			(stroke
				(width 0.1524)
				(type default)
			)
			(layer "F.SilkS")
		)
		(fp_line
			(start 0.7874 0.4064)
			(end -0.7874 0.4064)
			(stroke
				(width 0.1524)
				(type default)
			)
			(layer "F.SilkS")
		)
		(fp_line
			(start -0.7874 -0.4064)
			(end 0.7874 -0.4064)
			(stroke
				(width 0.1524)
				(type default)
			)
			(layer "F.SilkS")
		)
		(fp_line
			(start 0.7874 -0.4064)
			(end 0.7874 0.4064)
			(stroke
				(width 0.1524)
				(type default)
			)
			(layer "F.SilkS")
		)
		(fp_line
			(start -0.67945 0.3048)
			(end -0.67945 -0.305054)
			(stroke
				(width 0.1)
				(type default)
			)
			(layer "F.Fab")
		)
		(fp_line
			(start -0.12065 0.3048)
			(end -0.67945 0.3048)
			(stroke
				(width 0.1)
				(type default)
			)
			(layer "F.Fab")
		)
		(fp_line
			(start 0.120396 0.3048)
			(end 0.120396 0.2794)
			(stroke
				(width 0.1)
				(type default)
			)
			(layer "F.Fab")
		)
		(fp_line
			(start 0.67945 0.3048)
			(end 0.120396 0.3048)
			(stroke
				(width 0.1)
				(type default)
			)
			(layer "F.Fab")
		)
		(fp_line
			(start -0.12065 0.2794)
			(end -0.12065 0.3048)
			(stroke
				(width 0.1)
				(type default)
			)
			(layer "F.Fab")
		)
		(fp_line
			(start 0.120396 0.2794)
			(end -0.12065 0.2794)
			(stroke
				(width 0.1)
				(type default)
			)
			(layer "F.Fab")
		)
		(fp_line
			(start -0.12065 -0.2794)
			(end 0.12065 -0.2794)
			(stroke
				(width 0.1)
				(type default)
			)
			(layer "F.Fab")
		)
		(fp_line
			(start 0.12065 -0.2794)
			(end 0.12065 -0.3048)
			(stroke
				(width 0.1)
				(type default)
			)
			(layer "F.Fab")
		)
		(fp_line
			(start 0.12065 -0.3048)
			(end 0.67945 -0.3048)
			(stroke
				(width 0.1)
				(type default)
			)
			(layer "F.Fab")
		)
		(fp_line
			(start 0.67945 -0.3048)
			(end 0.67945 0.3048)
			(stroke
				(width 0.1)
				(type default)
			)
			(layer "F.Fab")
		)
		(fp_line
			(start -0.67945 -0.305054)
			(end -0.12065 -0.305054)
			(stroke
				(width 0.1)
				(type default)
			)
			(layer "F.Fab")
		)
		(fp_line
			(start -0.12065 -0.305054)
			(end -0.12065 -0.2794)
			(stroke
				(width 0.1)
				(type default)
			)
			(layer "F.Fab")
		)
		(pad "1" smd circle
			(at -0.40005 0 270)
			(size 0 0)
			(layers "F.Cu" "F.Mask" "F.Paste")
			(net "ESPI_LAD0_DATA_IO3")
		)
		(pad "2" smd circle
			(at 0.40005 0 270)
			(size 0 0)
			(layers "F.Cu" "F.Mask" "F.Paste")
			(net "ESPI_LPC_LAD0_IO3")
		)
	)
	(footprint ""
		(layer "F.Cu")
		(at 69.16928 -53.548788 180)
		(property "Reference" "PC2168"
			(at 0 0 180)
			(layer "F.SilkS")
			(hide yes)
			(effects
				(font
					(size 1.27 1.27)
				)
			)
		)
		(property "Value" ""
			(at 0 0 180)
			(layer "F.Fab")
			(effects
				(font
					(size 1.27 1.27)
				)
			)
		)
		(duplicate_pad_numbers_are_jumpers no)
		(fp_line
			(start 0.7874 0.4064)
			(end -0.7874 0.4064)
			(stroke
				(width 0.1524)
				(type default)
			)
			(layer "F.SilkS")
		)
		(fp_line
			(start 0.7874 -0.4064)
			(end 0.7874 0.4064)
			(stroke
				(width 0.1524)
				(type default)
			)
			(layer "F.SilkS")
		)
		(fp_line
			(start -0.7874 0.4064)
			(end -0.7874 -0.4064)
			(stroke
				(width 0.1524)
				(type default)
			)
			(layer "F.SilkS")
		)
		(fp_line
			(start -0.7874 -0.4064)
			(end 0.7874 -0.4064)
			(stroke
				(width 0.1524)
				(type default)
			)
			(layer "F.SilkS")
		)
		(fp_line
			(start 0.67945 0.3048)
			(end 0.120396 0.3048)
			(stroke
				(width 0.1)
				(type default)
			)
			(layer "F.Fab")
		)
		(fp_line
			(start 0.67945 -0.3048)
			(end 0.67945 0.3048)
			(stroke
				(width 0.1)
				(type default)
			)
			(layer "F.Fab")
		)
		(fp_line
			(start 0.12065 -0.2794)
			(end 0.12065 -0.3048)
			(stroke
				(width 0.1)
				(type default)
			)
			(layer "F.Fab")
		)
		(fp_line
			(start 0.12065 -0.3048)
			(end 0.67945 -0.3048)
			(stroke
				(width 0.1)
				(type default)
			)
			(layer "F.Fab")
		)
		(fp_line
			(start 0.120396 0.3048)
			(end 0.120396 0.2794)
			(stroke
				(width 0.1)
				(type default)
			)
			(layer "F.Fab")
		)
		(fp_line
			(start 0.120396 0.2794)
			(end -0.12065 0.2794)
			(stroke
				(width 0.1)
				(type default)
			)
			(layer "F.Fab")
		)
		(fp_line
			(start -0.12065 0.3048)
			(end -0.67945 0.3048)
			(stroke
				(width 0.1)
				(type default)
			)
			(layer "F.Fab")
		)
		(fp_line
			(start -0.12065 0.2794)
			(end -0.12065 0.3048)
			(stroke
				(width 0.1)
				(type default)
			)
			(layer "F.Fab")
		)
		(fp_line
			(start -0.12065 -0.2794)
			(end 0.12065 -0.2794)
			(stroke
				(width 0.1)
				(type default)
			)
			(layer "F.Fab")
		)
		(fp_line
			(start -0.12065 -0.305054)
			(end -0.12065 -0.2794)
			(stroke
				(width 0.1)
				(type default)
			)
			(layer "F.Fab")
		)
		(fp_line
			(start -0.67945 0.3048)
			(end -0.67945 -0.305054)
			(stroke
				(width 0.1)
				(type default)
			)
			(layer "F.Fab")
		)
		(fp_line
			(start -0.67945 -0.305054)
			(end -0.12065 -0.305054)
			(stroke
				(width 0.1)
				(type default)
			)
			(layer "F.Fab")
		)
		(pad "1" smd circle
			(at -0.40005 0 180)
			(size 0 0)
			(layers "F.Cu" "F.Mask" "F.Paste")
			(net "P3V3_OCP_MODE_2")
		)
		(pad "2" smd circle
			(at 0.40005 0 180)
			(size 0 0)
			(layers "F.Cu" "F.Mask" "F.Paste")
			(net "GND")
		)
	)
	(footprint ""
		(layer "F.Cu")
		(at 72.4662 -34.788348 180)
		(property "Reference" "R3568"
			(at 0 0 180)
			(layer "F.SilkS")
			(hide yes)
			(effects
				(font
					(size 1.27 1.27)
				)
			)
		)
		(property "Value" ""
			(at 0 0 180)
			(layer "F.Fab")
			(effects
				(font
					(size 1.27 1.27)
				)
			)
		)
		(duplicate_pad_numbers_are_jumpers no)
		(fp_line
			(start 0.7874 0.4064)
			(end -0.7874 0.4064)
			(stroke
				(width 0.1524)
				(type default)
			)
			(layer "F.SilkS")
		)
		(fp_line
			(start 0.7874 -0.4064)
			(end 0.7874 0.4064)
			(stroke
				(width 0.1524)
				(type default)
			)
			(layer "F.SilkS")
		)
		(fp_line
			(start -0.7874 0.4064)
			(end -0.7874 -0.4064)
			(stroke
				(width 0.1524)
				(type default)
			)
			(layer "F.SilkS")
		)
		(fp_line
			(start -0.7874 -0.4064)
			(end 0.7874 -0.4064)
			(stroke
				(width 0.1524)
				(type default)
			)
			(layer "F.SilkS")
		)
		(fp_line
			(start 0.67945 0.3048)
			(end 0.120396 0.3048)
			(stroke
				(width 0.1)
				(type default)
			)
			(layer "F.Fab")
		)
		(fp_line
			(start 0.67945 -0.3048)
			(end 0.67945 0.3048)
			(stroke
				(width 0.1)
				(type default)
			)
			(layer "F.Fab")
		)
		(fp_line
			(start 0.12065 -0.2794)
			(end 0.12065 -0.3048)
			(stroke
				(width 0.1)
				(type default)
			)
			(layer "F.Fab")
		)
		(fp_line
			(start 0.12065 -0.3048)
			(end 0.67945 -0.3048)
			(stroke
				(width 0.1)
				(type default)
			)
			(layer "F.Fab")
		)
		(fp_line
			(start 0.120396 0.3048)
			(end 0.120396 0.2794)
			(stroke
				(width 0.1)
				(type default)
			)
			(layer "F.Fab")
		)
		(fp_line
			(start 0.120396 0.2794)
			(end -0.12065 0.2794)
			(stroke
				(width 0.1)
				(type default)
			)
			(layer "F.Fab")
		)
		(fp_line
			(start -0.12065 0.3048)
			(end -0.67945 0.3048)
			(stroke
				(width 0.1)
				(type default)
			)
			(layer "F.Fab")
		)
		(fp_line
			(start -0.12065 0.2794)
			(end -0.12065 0.3048)
			(stroke
				(width 0.1)
				(type default)
			)
			(layer "F.Fab")
		)
		(fp_line
			(start -0.12065 -0.2794)
			(end 0.12065 -0.2794)
			(stroke
				(width 0.1)
				(type default)
			)
			(layer "F.Fab")
		)
		(fp_line
			(start -0.12065 -0.305054)
			(end -0.12065 -0.2794)
			(stroke
				(width 0.1)
				(type default)
			)
			(layer "F.Fab")
		)
		(fp_line
			(start -0.67945 0.3048)
			(end -0.67945 -0.305054)
			(stroke
				(width 0.1)
				(type default)
			)
			(layer "F.Fab")
		)
		(fp_line
			(start -0.67945 -0.305054)
			(end -0.12065 -0.305054)
			(stroke
				(width 0.1)
				(type default)
			)
			(layer "F.Fab")
		)
		(pad "1" smd circle
			(at -0.40005 0 180)
			(size 0 0)
			(layers "F.Cu" "F.Mask" "F.Paste")
			(net "SMB_INA230_3_3V3AUX_SCL_R")
		)
		(pad "2" smd circle
			(at 0.40005 0 180)
			(size 0 0)
			(layers "F.Cu" "F.Mask" "F.Paste")
			(net "SMB_INA230_3_3V3AUX_SCL_R1")
		)
	)
	(footprint ""
		(layer "F.Cu")
		(at 226.733608 -401.775422 180)
		(property "Reference" "PR3987"
			(at 0 0 180)
			(layer "F.SilkS")
			(hide yes)
			(effects
				(font
					(size 1.27 1.27)
				)
			)
		)
		(property "Value" ""
			(at 0 0 180)
			(layer "F.Fab")
			(effects
				(font
					(size 1.27 1.27)
				)
			)
		)
		(duplicate_pad_numbers_are_jumpers no)
		(fp_line
			(start 0.7874 0.4064)
			(end -0.7874 0.4064)
			(stroke
				(width 0.1524)
				(type default)
			)
			(layer "F.SilkS")
		)
		(fp_line
			(start 0.7874 -0.4064)
			(end 0.7874 0.4064)
			(stroke
				(width 0.1524)
				(type default)
			)
			(layer "F.SilkS")
		)
		(fp_line
			(start -0.7874 0.4064)
			(end -0.7874 -0.4064)
			(stroke
				(width 0.1524)
				(type default)
			)
			(layer "F.SilkS")
		)
		(fp_line
			(start -0.7874 -0.4064)
			(end 0.7874 -0.4064)
			(stroke
				(width 0.1524)
				(type default)
			)
			(layer "F.SilkS")
		)
		(fp_line
			(start 0.67945 0.3048)
			(end 0.120396 0.3048)
			(stroke
				(width 0.1)
				(type default)
			)
			(layer "F.Fab")
		)
		(fp_line
			(start 0.67945 -0.3048)
			(end 0.67945 0.3048)
			(stroke
				(width 0.1)
				(type default)
			)
			(layer "F.Fab")
		)
		(fp_line
			(start 0.12065 -0.2794)
			(end 0.12065 -0.3048)
			(stroke
				(width 0.1)
				(type default)
			)
			(layer "F.Fab")
		)
		(fp_line
			(start 0.12065 -0.3048)
			(end 0.67945 -0.3048)
			(stroke
				(width 0.1)
				(type default)
			)
			(layer "F.Fab")
		)
		(fp_line
			(start 0.120396 0.3048)
			(end 0.120396 0.2794)
			(stroke
				(width 0.1)
				(type default)
			)
			(layer "F.Fab")
		)
		(fp_line
			(start 0.120396 0.2794)
			(end -0.12065 0.2794)
			(stroke
				(width 0.1)
				(type default)
			)
			(layer "F.Fab")
		)
		(fp_line
			(start -0.12065 0.3048)
			(end -0.67945 0.3048)
			(stroke
				(width 0.1)
				(type default)
			)
			(layer "F.Fab")
		)
		(fp_line
			(start -0.12065 0.2794)
			(end -0.12065 0.3048)
			(stroke
				(width 0.1)
				(type default)
			)
			(layer "F.Fab")
		)
		(fp_line
			(start -0.12065 -0.2794)
			(end 0.12065 -0.2794)
			(stroke
				(width 0.1)
				(type default)
			)
			(layer "F.Fab")
		)
		(fp_line
			(start -0.12065 -0.305054)
			(end -0.12065 -0.2794)
			(stroke
				(width 0.1)
				(type default)
			)
			(layer "F.Fab")
		)
		(fp_line
			(start -0.67945 0.3048)
			(end -0.67945 -0.305054)
			(stroke
				(width 0.1)
				(type default)
			)
			(layer "F.Fab")
		)
		(fp_line
			(start -0.67945 -0.305054)
			(end -0.12065 -0.305054)
			(stroke
				(width 0.1)
				(type default)
			)
			(layer "F.Fab")
		)
		(pad "1" smd circle
			(at -0.40005 0 180)
			(size 0 0)
			(layers "F.Cu" "F.Mask" "F.Paste")
			(net "HSC_CS_4")
		)
		(pad "2" smd circle
			(at 0.40005 0 180)
			(size 0 0)
			(layers "F.Cu" "F.Mask" "F.Paste")
			(net "AGND_HSC")
		)
	)
	(footprint ""
		(layer "F.Cu")
		(at 423.56278 -106.129328 90)
		(property "Reference" "PC2163"
			(at 0 0 90)
			(layer "F.SilkS")
			(hide yes)
			(effects
				(font
					(size 1.27 1.27)
				)
			)
		)
		(property "Value" ""
			(at 0 0 90)
			(layer "F.Fab")
			(effects
				(font
					(size 1.27 1.27)
				)
			)
		)
		(duplicate_pad_numbers_are_jumpers no)
		(fp_line
			(start 1.524 -0.762)
			(end 1.524 0.762)
			(stroke
				(width 0.1524)
				(type default)
			)
			(layer "F.SilkS")
		)
		(fp_line
			(start -1.524 -0.762)
			(end 1.524 -0.762)
			(stroke
				(width 0.1524)
				(type default)
			)
			(layer "F.SilkS")
		)
		(fp_line
			(start 1.524 0.762)
			(end -1.524 0.762)
			(stroke
				(width 0.1524)
				(type default)
			)
			(layer "F.SilkS")
		)
		(fp_line
			(start -1.524 0.762)
			(end -1.524 -0.762)
			(stroke
				(width 0.1524)
				(type default)
			)
			(layer "F.SilkS")
		)
		(fp_line
			(start 1.1049 -0.724916)
			(end -1.1049 -0.724916)
			(stroke
				(width 0.1)
				(type default)
			)
			(layer "F.Fab")
		)
		(fp_line
			(start -1.1049 -0.724916)
			(end -1.1049 0.724916)
			(stroke
				(width 0.1)
				(type default)
			)
			(layer "F.Fab")
		)
		(fp_line
			(start 1.1049 0.724916)
			(end 1.1049 -0.724916)
			(stroke
				(width 0.1)
				(type default)
			)
			(layer "F.Fab")
		)
		(fp_line
			(start -1.1049 0.724916)
			(end 1.1049 0.724916)
			(stroke
				(width 0.1)
				(type default)
			)
			(layer "F.Fab")
		)
		(pad "1" smd rect
			(at -0.889 0 270)
			(size 1.016 1.27)
			(layers "F.Cu" "F.Mask" "F.Paste")
			(net "P3V3_OCP_SFF_R")
		)
		(pad "2" smd rect
			(at 0.889 0 270)
			(size 1.016 1.27)
			(layers "F.Cu" "F.Mask" "F.Paste")
			(net "GND")
		)
	)
	(footprint ""
		(layer "F.Cu")
		(at 219.79128 -111.115348 180)
		(property "Reference" "D0"
			(at -2.3876 -0.581152 0)
			(unlocked yes)
			(layer "F.SilkS")
			(effects
				(font
					(size 0.7874 0.5842)
					(thickness 0.1524)
				)
				(justify left)
			)
		)
		(property "Value" ""
			(at 0 0 180)
			(layer "F.Fab")
			(effects
				(font
					(size 1.27 1.27)
				)
			)
		)
		(duplicate_pad_numbers_are_jumpers no)
		(fp_line
			(start 1.16078 0.4826)
			(end -0.64008 0.4826)
			(stroke
				(width 0.1524)
				(type default)
			)
			(layer "F.SilkS")
		)
		(fp_line
			(start 1.16078 -0.4826)
			(end 1.16078 0.4826)
			(stroke
				(width 0.1524)
				(type default)
			)
			(layer "F.SilkS")
		)
		(fp_line
			(start 1.03378 0.4826)
			(end -0.79248 0.4826)
			(stroke
				(width 0.1524)
				(type default)
			)
			(layer "F.SilkS")
		)
		(fp_line
			(start 1.03378 -0.4826)
			(end 1.03378 0.4826)
			(stroke
				(width 0.1524)
				(type default)
			)
			(layer "F.SilkS")
		)
		(fp_line
			(start 0.90678 0.4826)
			(end -0.90678 0.4826)
			(stroke
				(width 0.1524)
				(type default)
			)
			(layer "F.SilkS")
		)
		(fp_line
			(start 0.90678 -0.4826)
			(end 0.90678 0.4826)
			(stroke
				(width 0.1524)
				(type default)
			)
			(layer "F.SilkS")
		)
		(fp_line
			(start -0.64008 -0.4826)
			(end 1.16078 -0.4826)
			(stroke
				(width 0.1524)
				(type default)
			)
			(layer "F.SilkS")
		)
		(fp_line
			(start -0.79248 -0.4826)
			(end 1.03378 -0.4826)
			(stroke
				(width 0.1524)
				(type default)
			)
			(layer "F.SilkS")
		)
		(fp_line
			(start -0.89408 -0.4826)
			(end 0.90678 -0.4826)
			(stroke
				(width 0.1524)
				(type default)
			)
			(layer "F.SilkS")
		)
		(fp_line
			(start -0.90678 0.4826)
			(end -0.90678 -0.4699)
			(stroke
				(width 0.1524)
				(type default)
			)
			(layer "F.SilkS")
		)
		(fp_line
			(start 0.499872 0.249936)
			(end -0.499872 0.249936)
			(stroke
				(width 0.1)
				(type default)
			)
			(layer "F.Fab")
		)
		(fp_line
			(start 0.499872 -0.249936)
			(end 0.499872 0.249936)
			(stroke
				(width 0.1)
				(type default)
			)
			(layer "F.Fab")
		)
		(fp_line
			(start -0.499872 0.249936)
			(end -0.499872 -0.249936)
			(stroke
				(width 0.1)
				(type default)
			)
			(layer "F.Fab")
		)
		(fp_line
			(start -0.499872 -0.249936)
			(end 0.499872 -0.249936)
			(stroke
				(width 0.1)
				(type default)
			)
			(layer "F.Fab")
		)
		(pad "A" smd rect
			(at -0.47498 0 180)
			(size 0.6096 0.7112)
			(layers "F.Cu" "F.Mask" "F.Paste")
			(net "PU_PLD_HEARTBEAT_LVC3")
		)
		(pad "C" smd rect
			(at 0.47498 0 180)
			(size 0.6096 0.7112)
			(layers "F.Cu" "F.Mask" "F.Paste")
			(net "FM_PLD_HEARTBEAT_LVC3_D")
		)
	)
	(footprint ""
		(layer "F.Cu")
		(at 309.522622 -39.106348 180)
		(property "Reference" "R453"
			(at 0 0 180)
			(layer "F.SilkS")
			(hide yes)
			(effects
				(font
					(size 1.27 1.27)
				)
			)
		)
		(property "Value" ""
			(at 0 0 180)
			(layer "F.Fab")
			(effects
				(font
					(size 1.27 1.27)
				)
			)
		)
		(duplicate_pad_numbers_are_jumpers no)
		(fp_line
			(start 0.7874 0.4064)
			(end -0.7874 0.4064)
			(stroke
				(width 0.1524)
				(type default)
			)
			(layer "F.SilkS")
		)
		(fp_line
			(start 0.7874 -0.4064)
			(end 0.7874 0.4064)
			(stroke
				(width 0.1524)
				(type default)
			)
			(layer "F.SilkS")
		)
		(fp_line
			(start -0.7874 0.4064)
			(end -0.7874 -0.4064)
			(stroke
				(width 0.1524)
				(type default)
			)
			(layer "F.SilkS")
		)
		(fp_line
			(start -0.7874 -0.4064)
			(end 0.7874 -0.4064)
			(stroke
				(width 0.1524)
				(type default)
			)
			(layer "F.SilkS")
		)
		(fp_line
			(start 0.67945 0.3048)
			(end 0.120396 0.3048)
			(stroke
				(width 0.1)
				(type default)
			)
			(layer "F.Fab")
		)
		(fp_line
			(start 0.67945 -0.3048)
			(end 0.67945 0.3048)
			(stroke
				(width 0.1)
				(type default)
			)
			(layer "F.Fab")
		)
		(fp_line
			(start 0.12065 -0.2794)
			(end 0.12065 -0.3048)
			(stroke
				(width 0.1)
				(type default)
			)
			(layer "F.Fab")
		)
		(fp_line
			(start 0.12065 -0.3048)
			(end 0.67945 -0.3048)
			(stroke
				(width 0.1)
				(type default)
			)
			(layer "F.Fab")
		)
		(fp_line
			(start 0.120396 0.3048)
			(end 0.120396 0.2794)
			(stroke
				(width 0.1)
				(type default)
			)
			(layer "F.Fab")
		)
		(fp_line
			(start 0.120396 0.2794)
			(end -0.12065 0.2794)
			(stroke
				(width 0.1)
				(type default)
			)
			(layer "F.Fab")
		)
		(fp_line
			(start -0.12065 0.3048)
			(end -0.67945 0.3048)
			(stroke
				(width 0.1)
				(type default)
			)
			(layer "F.Fab")
		)
		(fp_line
			(start -0.12065 0.2794)
			(end -0.12065 0.3048)
			(stroke
				(width 0.1)
				(type default)
			)
			(layer "F.Fab")
		)
		(fp_line
			(start -0.12065 -0.2794)
			(end 0.12065 -0.2794)
			(stroke
				(width 0.1)
				(type default)
			)
			(layer "F.Fab")
		)
		(fp_line
			(start -0.12065 -0.305054)
			(end -0.12065 -0.2794)
			(stroke
				(width 0.1)
				(type default)
			)
			(layer "F.Fab")
		)
		(fp_line
			(start -0.67945 0.3048)
			(end -0.67945 -0.305054)
			(stroke
				(width 0.1)
				(type default)
			)
			(layer "F.Fab")
		)
		(fp_line
			(start -0.67945 -0.305054)
			(end -0.12065 -0.305054)
			(stroke
				(width 0.1)
				(type default)
			)
			(layer "F.Fab")
		)
		(pad "1" smd circle
			(at -0.40005 0 180)
			(size 0 0)
			(layers "F.Cu" "F.Mask" "F.Paste")
			(net "P3V3_AUX")
		)
		(pad "2" smd circle
			(at 0.40005 0 180)
			(size 0 0)
			(layers "F.Cu" "F.Mask" "F.Paste")
			(net "PU_LAN_WAKE_N")
		)
	)
	(footprint ""
		(layer "F.Cu")
		(at 434.805328 -19.614134 -90)
		(property "Reference" "R1929"
			(at 0 0 270)
			(layer "F.SilkS")
			(hide yes)
			(effects
				(font
					(size 1.27 1.27)
				)
			)
		)
		(property "Value" ""
			(at 0 0 270)
			(layer "F.Fab")
			(effects
				(font
					(size 1.27 1.27)
				)
			)
		)
		(duplicate_pad_numbers_are_jumpers no)
		(fp_line
			(start -0.7874 0.4064)
			(end -0.7874 -0.4064)
			(stroke
				(width 0.1524)
				(type default)
			)
			(layer "F.SilkS")
		)
		(fp_line
			(start 0.7874 0.4064)
			(end -0.7874 0.4064)
			(stroke
				(width 0.1524)
				(type default)
			)
			(layer "F.SilkS")
		)
		(fp_line
			(start -0.7874 -0.4064)
			(end 0.7874 -0.4064)
			(stroke
				(width 0.1524)
				(type default)
			)
			(layer "F.SilkS")
		)
		(fp_line
			(start 0.7874 -0.4064)
			(end 0.7874 0.4064)
			(stroke
				(width 0.1524)
				(type default)
			)
			(layer "F.SilkS")
		)
		(fp_line
			(start -0.67945 0.3048)
			(end -0.67945 -0.305054)
			(stroke
				(width 0.1)
				(type default)
			)
			(layer "F.Fab")
		)
		(fp_line
			(start -0.12065 0.3048)
			(end -0.67945 0.3048)
			(stroke
				(width 0.1)
				(type default)
			)
			(layer "F.Fab")
		)
		(fp_line
			(start 0.120396 0.3048)
			(end 0.120396 0.2794)
			(stroke
				(width 0.1)
				(type default)
			)
			(layer "F.Fab")
		)
		(fp_line
			(start 0.67945 0.3048)
			(end 0.120396 0.3048)
			(stroke
				(width 0.1)
				(type default)
			)
			(layer "F.Fab")
		)
		(fp_line
			(start -0.12065 0.2794)
			(end -0.12065 0.3048)
			(stroke
				(width 0.1)
				(type default)
			)
			(layer "F.Fab")
		)
		(fp_line
			(start 0.120396 0.2794)
			(end -0.12065 0.2794)
			(stroke
				(width 0.1)
				(type default)
			)
			(layer "F.Fab")
		)
		(fp_line
			(start -0.12065 -0.2794)
			(end 0.12065 -0.2794)
			(stroke
				(width 0.1)
				(type default)
			)
			(layer "F.Fab")
		)
		(fp_line
			(start 0.12065 -0.2794)
			(end 0.12065 -0.3048)
			(stroke
				(width 0.1)
				(type default)
			)
			(layer "F.Fab")
		)
		(fp_line
			(start 0.12065 -0.3048)
			(end 0.67945 -0.3048)
			(stroke
				(width 0.1)
				(type default)
			)
			(layer "F.Fab")
		)
		(fp_line
			(start 0.67945 -0.3048)
			(end 0.67945 0.3048)
			(stroke
				(width 0.1)
				(type default)
			)
			(layer "F.Fab")
		)
		(fp_line
			(start -0.67945 -0.305054)
			(end -0.12065 -0.305054)
			(stroke
				(width 0.1)
				(type default)
			)
			(layer "F.Fab")
		)
		(fp_line
			(start -0.12065 -0.305054)
			(end -0.12065 -0.2794)
			(stroke
				(width 0.1)
				(type default)
			)
			(layer "F.Fab")
		)
		(pad "1" smd circle
			(at -0.40005 0 270)
			(size 0 0)
			(layers "F.Cu" "F.Mask" "F.Paste")
			(net "GND")
		)
		(pad "2" smd circle
			(at 0.40005 0 270)
			(size 0 0)
			(layers "F.Cu" "F.Mask" "F.Paste")
			(net "OCP_SFF_AUX_PWR_EN")
		)
	)
	(footprint ""
		(layer "F.Cu")
		(at 309.523638 -37.822886 180)
		(property "Reference" "R4101"
			(at 0 0 180)
			(layer "F.SilkS")
			(hide yes)
			(effects
				(font
					(size 1.27 1.27)
				)
			)
		)
		(property "Value" ""
			(at 0 0 180)
			(layer "F.Fab")
			(effects
				(font
					(size 1.27 1.27)
				)
			)
		)
		(duplicate_pad_numbers_are_jumpers no)
		(fp_line
			(start 0.7874 0.4064)
			(end -0.7874 0.4064)
			(stroke
				(width 0.1524)
				(type default)
			)
			(layer "F.SilkS")
		)
		(fp_line
			(start 0.7874 -0.4064)
			(end 0.7874 0.4064)
			(stroke
				(width 0.1524)
				(type default)
			)
			(layer "F.SilkS")
		)
		(fp_line
			(start -0.7874 0.4064)
			(end -0.7874 -0.4064)
			(stroke
				(width 0.1524)
				(type default)
			)
			(layer "F.SilkS")
		)
		(fp_line
			(start -0.7874 -0.4064)
			(end 0.7874 -0.4064)
			(stroke
				(width 0.1524)
				(type default)
			)
			(layer "F.SilkS")
		)
		(fp_line
			(start 0.67945 0.3048)
			(end 0.120396 0.3048)
			(stroke
				(width 0.1)
				(type default)
			)
			(layer "F.Fab")
		)
		(fp_line
			(start 0.67945 -0.3048)
			(end 0.67945 0.3048)
			(stroke
				(width 0.1)
				(type default)
			)
			(layer "F.Fab")
		)
		(fp_line
			(start 0.12065 -0.2794)
			(end 0.12065 -0.3048)
			(stroke
				(width 0.1)
				(type default)
			)
			(layer "F.Fab")
		)
		(fp_line
			(start 0.12065 -0.3048)
			(end 0.67945 -0.3048)
			(stroke
				(width 0.1)
				(type default)
			)
			(layer "F.Fab")
		)
		(fp_line
			(start 0.120396 0.3048)
			(end 0.120396 0.2794)
			(stroke
				(width 0.1)
				(type default)
			)
			(layer "F.Fab")
		)
		(fp_line
			(start 0.120396 0.2794)
			(end -0.12065 0.2794)
			(stroke
				(width 0.1)
				(type default)
			)
			(layer "F.Fab")
		)
		(fp_line
			(start -0.12065 0.3048)
			(end -0.67945 0.3048)
			(stroke
				(width 0.1)
				(type default)
			)
			(layer "F.Fab")
		)
		(fp_line
			(start -0.12065 0.2794)
			(end -0.12065 0.3048)
			(stroke
				(width 0.1)
				(type default)
			)
			(layer "F.Fab")
		)
		(fp_line
			(start -0.12065 -0.2794)
			(end 0.12065 -0.2794)
			(stroke
				(width 0.1)
				(type default)
			)
			(layer "F.Fab")
		)
		(fp_line
			(start -0.12065 -0.305054)
			(end -0.12065 -0.2794)
			(stroke
				(width 0.1)
				(type default)
			)
			(layer "F.Fab")
		)
		(fp_line
			(start -0.67945 0.3048)
			(end -0.67945 -0.305054)
			(stroke
				(width 0.1)
				(type default)
			)
			(layer "F.Fab")
		)
		(fp_line
			(start -0.67945 -0.305054)
			(end -0.12065 -0.305054)
			(stroke
				(width 0.1)
				(type default)
			)
			(layer "F.Fab")
		)
		(pad "1" smd circle
			(at -0.40005 0 180)
			(size 0 0)
			(layers "F.Cu" "F.Mask" "F.Paste")
			(net "PD_PCH_GPPC_C9")
		)
		(pad "2" smd circle
			(at 0.40005 0 180)
			(size 0 0)
			(layers "F.Cu" "F.Mask" "F.Paste")
			(net "GND")
		)
	)
	(footprint ""
		(layer "F.Cu")
		(at 144.294606 -78.955138 180)
		(property "Reference" "R2355"
			(at 0 0 180)
			(layer "F.SilkS")
			(hide yes)
			(effects
				(font
					(size 1.27 1.27)
				)
			)
		)
		(property "Value" ""
			(at 0 0 180)
			(layer "F.Fab")
			(effects
				(font
					(size 1.27 1.27)
				)
			)
		)
		(duplicate_pad_numbers_are_jumpers no)
		(fp_line
			(start 0.7874 0.4064)
			(end -0.7874 0.4064)
			(stroke
				(width 0.1524)
				(type default)
			)
			(layer "F.SilkS")
		)
		(fp_line
			(start 0.7874 -0.4064)
			(end 0.7874 0.4064)
			(stroke
				(width 0.1524)
				(type default)
			)
			(layer "F.SilkS")
		)
		(fp_line
			(start -0.7874 0.4064)
			(end -0.7874 -0.4064)
			(stroke
				(width 0.1524)
				(type default)
			)
			(layer "F.SilkS")
		)
		(fp_line
			(start -0.7874 -0.4064)
			(end 0.7874 -0.4064)
			(stroke
				(width 0.1524)
				(type default)
			)
			(layer "F.SilkS")
		)
		(fp_line
			(start 0.67945 0.3048)
			(end 0.120396 0.3048)
			(stroke
				(width 0.1)
				(type default)
			)
			(layer "F.Fab")
		)
		(fp_line
			(start 0.67945 -0.3048)
			(end 0.67945 0.3048)
			(stroke
				(width 0.1)
				(type default)
			)
			(layer "F.Fab")
		)
		(fp_line
			(start 0.12065 -0.2794)
			(end 0.12065 -0.3048)
			(stroke
				(width 0.1)
				(type default)
			)
			(layer "F.Fab")
		)
		(fp_line
			(start 0.12065 -0.3048)
			(end 0.67945 -0.3048)
			(stroke
				(width 0.1)
				(type default)
			)
			(layer "F.Fab")
		)
		(fp_line
			(start 0.120396 0.3048)
			(end 0.120396 0.2794)
			(stroke
				(width 0.1)
				(type default)
			)
			(layer "F.Fab")
		)
		(fp_line
			(start 0.120396 0.2794)
			(end -0.12065 0.2794)
			(stroke
				(width 0.1)
				(type default)
			)
			(layer "F.Fab")
		)
		(fp_line
			(start -0.12065 0.3048)
			(end -0.67945 0.3048)
			(stroke
				(width 0.1)
				(type default)
			)
			(layer "F.Fab")
		)
		(fp_line
			(start -0.12065 0.2794)
			(end -0.12065 0.3048)
			(stroke
				(width 0.1)
				(type default)
			)
			(layer "F.Fab")
		)
		(fp_line
			(start -0.12065 -0.2794)
			(end 0.12065 -0.2794)
			(stroke
				(width 0.1)
				(type default)
			)
			(layer "F.Fab")
		)
		(fp_line
			(start -0.12065 -0.305054)
			(end -0.12065 -0.2794)
			(stroke
				(width 0.1)
				(type default)
			)
			(layer "F.Fab")
		)
		(fp_line
			(start -0.67945 0.3048)
			(end -0.67945 -0.305054)
			(stroke
				(width 0.1)
				(type default)
			)
			(layer "F.Fab")
		)
		(fp_line
			(start -0.67945 -0.305054)
			(end -0.12065 -0.305054)
			(stroke
				(width 0.1)
				(type default)
			)
			(layer "F.Fab")
		)
		(pad "1" smd circle
			(at -0.40005 0 180)
			(size 0 0)
			(layers "F.Cu" "F.Mask" "F.Paste")
			(net "P3V3_AUX")
		)
		(pad "2" smd circle
			(at 0.40005 0 180)
			(size 0 0)
			(layers "F.Cu" "F.Mask" "F.Paste")
			(net "FM_PS_EN_PLD_BUF1")
		)
	)
	(footprint ""
		(layer "F.Cu")
		(at 104.3432 -249.320558 -90)
		(property "Reference" "C232"
			(at 0 0 270)
			(layer "F.SilkS")
			(hide yes)
			(effects
				(font
					(size 1.27 1.27)
				)
			)
		)
		(property "Value" ""
			(at 0 0 270)
			(layer "F.Fab")
			(effects
				(font
					(size 1.27 1.27)
				)
			)
		)
		(duplicate_pad_numbers_are_jumpers no)
		(fp_line
			(start -0.7874 0.4064)
			(end -0.7874 -0.4064)
			(stroke
				(width 0.1524)
				(type default)
			)
			(layer "F.SilkS")
		)
		(fp_line
			(start 0.7874 0.4064)
			(end -0.7874 0.4064)
			(stroke
				(width 0.1524)
				(type default)
			)
			(layer "F.SilkS")
		)
		(fp_line
			(start -0.7874 -0.4064)
			(end 0.7874 -0.4064)
			(stroke
				(width 0.1524)
				(type default)
			)
			(layer "F.SilkS")
		)
		(fp_line
			(start 0.7874 -0.4064)
			(end 0.7874 0.4064)
			(stroke
				(width 0.1524)
				(type default)
			)
			(layer "F.SilkS")
		)
		(fp_line
			(start -0.67945 0.3048)
			(end -0.67945 -0.305054)
			(stroke
				(width 0.1)
				(type default)
			)
			(layer "F.Fab")
		)
		(fp_line
			(start -0.12065 0.3048)
			(end -0.67945 0.3048)
			(stroke
				(width 0.1)
				(type default)
			)
			(layer "F.Fab")
		)
		(fp_line
			(start 0.120396 0.3048)
			(end 0.120396 0.2794)
			(stroke
				(width 0.1)
				(type default)
			)
			(layer "F.Fab")
		)
		(fp_line
			(start 0.67945 0.3048)
			(end 0.120396 0.3048)
			(stroke
				(width 0.1)
				(type default)
			)
			(layer "F.Fab")
		)
		(fp_line
			(start -0.12065 0.2794)
			(end -0.12065 0.3048)
			(stroke
				(width 0.1)
				(type default)
			)
			(layer "F.Fab")
		)
		(fp_line
			(start 0.120396 0.2794)
			(end -0.12065 0.2794)
			(stroke
				(width 0.1)
				(type default)
			)
			(layer "F.Fab")
		)
		(fp_line
			(start -0.12065 -0.2794)
			(end 0.12065 -0.2794)
			(stroke
				(width 0.1)
				(type default)
			)
			(layer "F.Fab")
		)
		(fp_line
			(start 0.12065 -0.2794)
			(end 0.12065 -0.3048)
			(stroke
				(width 0.1)
				(type default)
			)
			(layer "F.Fab")
		)
		(fp_line
			(start 0.12065 -0.3048)
			(end 0.67945 -0.3048)
			(stroke
				(width 0.1)
				(type default)
			)
			(layer "F.Fab")
		)
		(fp_line
			(start 0.67945 -0.3048)
			(end 0.67945 0.3048)
			(stroke
				(width 0.1)
				(type default)
			)
			(layer "F.Fab")
		)
		(fp_line
			(start -0.67945 -0.305054)
			(end -0.12065 -0.305054)
			(stroke
				(width 0.1)
				(type default)
			)
			(layer "F.Fab")
		)
		(fp_line
			(start -0.12065 -0.305054)
			(end -0.12065 -0.2794)
			(stroke
				(width 0.1)
				(type default)
			)
			(layer "F.Fab")
		)
		(pad "1" smd circle
			(at -0.40005 0 270)
			(size 0 0)
			(layers "F.Cu" "F.Mask" "F.Paste")
			(net "PVCCIN_CPU1")
		)
		(pad "2" smd circle
			(at 0.40005 0 270)
			(size 0 0)
			(layers "F.Cu" "F.Mask" "F.Paste")
			(net "GND")
		)
	)
	(footprint ""
		(layer "F.Cu")
		(at 307.017928 -402.371052 -90)
		(property "Reference" "C1577"
			(at 0 0 270)
			(layer "F.SilkS")
			(hide yes)
			(effects
				(font
					(size 1.27 1.27)
				)
			)
		)
		(property "Value" ""
			(at 0 0 270)
			(layer "F.Fab")
			(effects
				(font
					(size 1.27 1.27)
				)
			)
		)
		(duplicate_pad_numbers_are_jumpers no)
		(fp_line
			(start -0.299974 0.150114)
			(end -0.299974 -0.150114)
			(stroke
				(width 0.1)
				(type default)
			)
			(layer "F.Fab")
		)
		(fp_line
			(start 0.299974 0.150114)
			(end -0.299974 0.150114)
			(stroke
				(width 0.1)
				(type default)
			)
			(layer "F.Fab")
		)
		(fp_line
			(start -0.299974 -0.150114)
			(end 0.299974 -0.150114)
			(stroke
				(width 0.1)
				(type default)
			)
			(layer "F.Fab")
		)
		(fp_line
			(start 0.299974 -0.150114)
			(end 0.299974 0.150114)
			(stroke
				(width 0.1)
				(type default)
			)
			(layer "F.Fab")
		)
		(pad "1" smd rect
			(at -0.2667 0 270)
			(size 0.3048 0.381)
			(layers "F.Cu" "F.Mask" "F.Paste")
			(net "P5E_CPU0_PE4_TX_C_DP<1>")
		)
		(pad "2" smd rect
			(at 0.2667 0 270)
			(size 0.3048 0.381)
			(layers "F.Cu" "F.Mask" "F.Paste")
			(net "P5E_CPU0_PE4_TX_DP<1>")
		)
	)
	(footprint ""
		(layer "F.Cu")
		(at 449.973954 -117.193822 180)
		(property "Reference" "R1124"
			(at 0 0 180)
			(layer "F.SilkS")
			(hide yes)
			(effects
				(font
					(size 1.27 1.27)
				)
			)
		)
		(property "Value" ""
			(at 0 0 180)
			(layer "F.Fab")
			(effects
				(font
					(size 1.27 1.27)
				)
			)
		)
		(duplicate_pad_numbers_are_jumpers no)
		(fp_line
			(start 0.7874 0.4064)
			(end -0.7874 0.4064)
			(stroke
				(width 0.1524)
				(type default)
			)
			(layer "F.SilkS")
		)
		(fp_line
			(start 0.7874 -0.4064)
			(end 0.7874 0.4064)
			(stroke
				(width 0.1524)
				(type default)
			)
			(layer "F.SilkS")
		)
		(fp_line
			(start -0.7874 0.4064)
			(end -0.7874 -0.4064)
			(stroke
				(width 0.1524)
				(type default)
			)
			(layer "F.SilkS")
		)
		(fp_line
			(start -0.7874 -0.4064)
			(end 0.7874 -0.4064)
			(stroke
				(width 0.1524)
				(type default)
			)
			(layer "F.SilkS")
		)
		(fp_line
			(start 0.67945 0.3048)
			(end 0.120396 0.3048)
			(stroke
				(width 0.1)
				(type default)
			)
			(layer "F.Fab")
		)
		(fp_line
			(start 0.67945 -0.3048)
			(end 0.67945 0.3048)
			(stroke
				(width 0.1)
				(type default)
			)
			(layer "F.Fab")
		)
		(fp_line
			(start 0.12065 -0.2794)
			(end 0.12065 -0.3048)
			(stroke
				(width 0.1)
				(type default)
			)
			(layer "F.Fab")
		)
		(fp_line
			(start 0.12065 -0.3048)
			(end 0.67945 -0.3048)
			(stroke
				(width 0.1)
				(type default)
			)
			(layer "F.Fab")
		)
		(fp_line
			(start 0.120396 0.3048)
			(end 0.120396 0.2794)
			(stroke
				(width 0.1)
				(type default)
			)
			(layer "F.Fab")
		)
		(fp_line
			(start 0.120396 0.2794)
			(end -0.12065 0.2794)
			(stroke
				(width 0.1)
				(type default)
			)
			(layer "F.Fab")
		)
		(fp_line
			(start -0.12065 0.3048)
			(end -0.67945 0.3048)
			(stroke
				(width 0.1)
				(type default)
			)
			(layer "F.Fab")
		)
		(fp_line
			(start -0.12065 0.2794)
			(end -0.12065 0.3048)
			(stroke
				(width 0.1)
				(type default)
			)
			(layer "F.Fab")
		)
		(fp_line
			(start -0.12065 -0.2794)
			(end 0.12065 -0.2794)
			(stroke
				(width 0.1)
				(type default)
			)
			(layer "F.Fab")
		)
		(fp_line
			(start -0.12065 -0.305054)
			(end -0.12065 -0.2794)
			(stroke
				(width 0.1)
				(type default)
			)
			(layer "F.Fab")
		)
		(fp_line
			(start -0.67945 0.3048)
			(end -0.67945 -0.305054)
			(stroke
				(width 0.1)
				(type default)
			)
			(layer "F.Fab")
		)
		(fp_line
			(start -0.67945 -0.305054)
			(end -0.12065 -0.305054)
			(stroke
				(width 0.1)
				(type default)
			)
			(layer "F.Fab")
		)
		(pad "1" smd circle
			(at -0.40005 0 180)
			(size 0 0)
			(layers "F.Cu" "F.Mask" "F.Paste")
			(net "PD_SMB_OCP1_HP_ADD2")
		)
		(pad "2" smd circle
			(at 0.40005 0 180)
			(size 0 0)
			(layers "F.Cu" "F.Mask" "F.Paste")
			(net "GND")
		)
	)
	(footprint ""
		(layer "F.Cu")
		(at 458.41666 -39.765478)
		(property "Reference" "C1173"
			(at 0 0 0)
			(layer "F.SilkS")
			(hide yes)
			(effects
				(font
					(size 1.27 1.27)
				)
			)
		)
		(property "Value" ""
			(at 0 0 0)
			(layer "F.Fab")
			(effects
				(font
					(size 1.27 1.27)
				)
			)
		)
		(duplicate_pad_numbers_are_jumpers no)
		(fp_line
			(start -0.7874 -0.4064)
			(end 0.7874 -0.4064)
			(stroke
				(width 0.1524)
				(type default)
			)
			(layer "F.SilkS")
		)
		(fp_line
			(start -0.7874 0.4064)
			(end -0.7874 -0.4064)
			(stroke
				(width 0.1524)
				(type default)
			)
			(layer "F.SilkS")
		)
		(fp_line
			(start 0.7874 -0.4064)
			(end 0.7874 0.4064)
			(stroke
				(width 0.1524)
				(type default)
			)
			(layer "F.SilkS")
		)
		(fp_line
			(start 0.7874 0.4064)
			(end -0.7874 0.4064)
			(stroke
				(width 0.1524)
				(type default)
			)
			(layer "F.SilkS")
		)
		(fp_line
			(start -0.67945 -0.305054)
			(end -0.12065 -0.305054)
			(stroke
				(width 0.1)
				(type default)
			)
			(layer "F.Fab")
		)
		(fp_line
			(start -0.67945 0.3048)
			(end -0.67945 -0.305054)
			(stroke
				(width 0.1)
				(type default)
			)
			(layer "F.Fab")
		)
		(fp_line
			(start -0.12065 -0.305054)
			(end -0.12065 -0.2794)
			(stroke
				(width 0.1)
				(type default)
			)
			(layer "F.Fab")
		)
		(fp_line
			(start -0.12065 -0.2794)
			(end 0.12065 -0.2794)
			(stroke
				(width 0.1)
				(type default)
			)
			(layer "F.Fab")
		)
		(fp_line
			(start -0.12065 0.2794)
			(end -0.12065 0.3048)
			(stroke
				(width 0.1)
				(type default)
			)
			(layer "F.Fab")
		)
		(fp_line
			(start -0.12065 0.3048)
			(end -0.67945 0.3048)
			(stroke
				(width 0.1)
				(type default)
			)
			(layer "F.Fab")
		)
		(fp_line
			(start 0.120396 0.2794)
			(end -0.12065 0.2794)
			(stroke
				(width 0.1)
				(type default)
			)
			(layer "F.Fab")
		)
		(fp_line
			(start 0.120396 0.3048)
			(end 0.120396 0.2794)
			(stroke
				(width 0.1)
				(type default)
			)
			(layer "F.Fab")
		)
		(fp_line
			(start 0.12065 -0.3048)
			(end 0.67945 -0.3048)
			(stroke
				(width 0.1)
				(type default)
			)
			(layer "F.Fab")
		)
		(fp_line
			(start 0.12065 -0.2794)
			(end 0.12065 -0.3048)
			(stroke
				(width 0.1)
				(type default)
			)
			(layer "F.Fab")
		)
		(fp_line
			(start 0.67945 -0.3048)
			(end 0.67945 0.3048)
			(stroke
				(width 0.1)
				(type default)
			)
			(layer "F.Fab")
		)
		(fp_line
			(start 0.67945 0.3048)
			(end 0.120396 0.3048)
			(stroke
				(width 0.1)
				(type default)
			)
			(layer "F.Fab")
		)
		(pad "1" smd circle
			(at -0.40005 0)
			(size 0 0)
			(layers "F.Cu" "F.Mask" "F.Paste")
			(net "P3V3_AUX")
		)
		(pad "2" smd circle
			(at 0.40005 0)
			(size 0 0)
			(layers "F.Cu" "F.Mask" "F.Paste")
			(net "GND")
		)
	)
	(footprint ""
		(layer "F.Cu")
		(at 17.36471 -180.522626 90)
		(property "Reference" "PC1280"
			(at 0 0 90)
			(layer "F.SilkS")
			(hide yes)
			(effects
				(font
					(size 1.27 1.27)
				)
			)
		)
		(property "Value" ""
			(at 0 0 90)
			(layer "F.Fab")
			(effects
				(font
					(size 1.27 1.27)
				)
			)
		)
		(duplicate_pad_numbers_are_jumpers no)
		(fp_line
			(start 1.524 -0.762)
			(end 1.524 0.762)
			(stroke
				(width 0.1524)
				(type default)
			)
			(layer "F.SilkS")
		)
		(fp_line
			(start -1.524 -0.762)
			(end 1.524 -0.762)
			(stroke
				(width 0.1524)
				(type default)
			)
			(layer "F.SilkS")
		)
		(fp_line
			(start 1.524 0.762)
			(end -1.524 0.762)
			(stroke
				(width 0.1524)
				(type default)
			)
			(layer "F.SilkS")
		)
		(fp_line
			(start -1.524 0.762)
			(end -1.524 -0.762)
			(stroke
				(width 0.1524)
				(type default)
			)
			(layer "F.SilkS")
		)
		(fp_line
			(start 1.1049 -0.724916)
			(end -1.1049 -0.724916)
			(stroke
				(width 0.1)
				(type default)
			)
			(layer "F.Fab")
		)
		(fp_line
			(start -1.1049 -0.724916)
			(end -1.1049 0.724916)
			(stroke
				(width 0.1)
				(type default)
			)
			(layer "F.Fab")
		)
		(fp_line
			(start 1.1049 0.724916)
			(end 1.1049 -0.724916)
			(stroke
				(width 0.1)
				(type default)
			)
			(layer "F.Fab")
		)
		(fp_line
			(start -1.1049 0.724916)
			(end 1.1049 0.724916)
			(stroke
				(width 0.1)
				(type default)
			)
			(layer "F.Fab")
		)
		(pad "1" smd rect
			(at -0.889 0 270)
			(size 1.016 1.27)
			(layers "F.Cu" "F.Mask" "F.Paste")
			(net "SW_P12V_PVCCINFAON_CPU1_FLT")
		)
		(pad "2" smd rect
			(at 0.889 0 270)
			(size 1.016 1.27)
			(layers "F.Cu" "F.Mask" "F.Paste")
			(net "GND")
		)
	)
	(footprint ""
		(layer "F.Cu")
		(at 453.719946 -104.249728)
		(property "Reference" "R1906"
			(at 0 0 0)
			(layer "F.SilkS")
			(hide yes)
			(effects
				(font
					(size 1.27 1.27)
				)
			)
		)
		(property "Value" ""
			(at 0 0 0)
			(layer "F.Fab")
			(effects
				(font
					(size 1.27 1.27)
				)
			)
		)
		(duplicate_pad_numbers_are_jumpers no)
		(fp_line
			(start -0.7874 -0.4064)
			(end 0.7874 -0.4064)
			(stroke
				(width 0.1524)
				(type default)
			)
			(layer "F.SilkS")
		)
		(fp_line
			(start -0.7874 0.4064)
			(end -0.7874 -0.4064)
			(stroke
				(width 0.1524)
				(type default)
			)
			(layer "F.SilkS")
		)
		(fp_line
			(start 0.7874 -0.4064)
			(end 0.7874 0.4064)
			(stroke
				(width 0.1524)
				(type default)
			)
			(layer "F.SilkS")
		)
		(fp_line
			(start 0.7874 0.4064)
			(end -0.7874 0.4064)
			(stroke
				(width 0.1524)
				(type default)
			)
			(layer "F.SilkS")
		)
		(fp_line
			(start -0.67945 -0.305054)
			(end -0.12065 -0.305054)
			(stroke
				(width 0.1)
				(type default)
			)
			(layer "F.Fab")
		)
		(fp_line
			(start -0.67945 0.3048)
			(end -0.67945 -0.305054)
			(stroke
				(width 0.1)
				(type default)
			)
			(layer "F.Fab")
		)
		(fp_line
			(start -0.12065 -0.305054)
			(end -0.12065 -0.2794)
			(stroke
				(width 0.1)
				(type default)
			)
			(layer "F.Fab")
		)
		(fp_line
			(start -0.12065 -0.2794)
			(end 0.12065 -0.2794)
			(stroke
				(width 0.1)
				(type default)
			)
			(layer "F.Fab")
		)
		(fp_line
			(start -0.12065 0.2794)
			(end -0.12065 0.3048)
			(stroke
				(width 0.1)
				(type default)
			)
			(layer "F.Fab")
		)
		(fp_line
			(start -0.12065 0.3048)
			(end -0.67945 0.3048)
			(stroke
				(width 0.1)
				(type default)
			)
			(layer "F.Fab")
		)
		(fp_line
			(start 0.120396 0.2794)
			(end -0.12065 0.2794)
			(stroke
				(width 0.1)
				(type default)
			)
			(layer "F.Fab")
		)
		(fp_line
			(start 0.120396 0.3048)
			(end 0.120396 0.2794)
			(stroke
				(width 0.1)
				(type default)
			)
			(layer "F.Fab")
		)
		(fp_line
			(start 0.12065 -0.3048)
			(end 0.67945 -0.3048)
			(stroke
				(width 0.1)
				(type default)
			)
			(layer "F.Fab")
		)
		(fp_line
			(start 0.12065 -0.2794)
			(end 0.12065 -0.3048)
			(stroke
				(width 0.1)
				(type default)
			)
			(layer "F.Fab")
		)
		(fp_line
			(start 0.67945 -0.3048)
			(end 0.67945 0.3048)
			(stroke
				(width 0.1)
				(type default)
			)
			(layer "F.Fab")
		)
		(fp_line
			(start 0.67945 0.3048)
			(end 0.120396 0.3048)
			(stroke
				(width 0.1)
				(type default)
			)
			(layer "F.Fab")
		)
		(pad "1" smd circle
			(at -0.40005 0)
			(size 0 0)
			(layers "F.Cu" "F.Mask" "F.Paste")
			(net "P3V3_AUX")
		)
		(pad "2" smd circle
			(at 0.40005 0)
			(size 0 0)
			(layers "F.Cu" "F.Mask" "F.Paste")
			(net "OCP_SFF_PRSNT2_R_N")
		)
	)
	(footprint ""
		(layer "F.Cu")
		(at 354.687632 -397.519398 180)
		(property "Reference" "R2674"
			(at 0 0 180)
			(layer "F.SilkS")
			(hide yes)
			(effects
				(font
					(size 1.27 1.27)
				)
			)
		)
		(property "Value" ""
			(at 0 0 180)
			(layer "F.Fab")
			(effects
				(font
					(size 1.27 1.27)
				)
			)
		)
		(duplicate_pad_numbers_are_jumpers no)
		(fp_line
			(start 0.7874 0.4064)
			(end -0.7874 0.4064)
			(stroke
				(width 0.1524)
				(type default)
			)
			(layer "F.SilkS")
		)
		(fp_line
			(start 0.7874 -0.4064)
			(end 0.7874 0.4064)
			(stroke
				(width 0.1524)
				(type default)
			)
			(layer "F.SilkS")
		)
		(fp_line
			(start -0.7874 0.4064)
			(end -0.7874 -0.4064)
			(stroke
				(width 0.1524)
				(type default)
			)
			(layer "F.SilkS")
		)
		(fp_line
			(start -0.7874 -0.4064)
			(end 0.7874 -0.4064)
			(stroke
				(width 0.1524)
				(type default)
			)
			(layer "F.SilkS")
		)
		(fp_line
			(start 0.67945 0.3048)
			(end 0.120396 0.3048)
			(stroke
				(width 0.1)
				(type default)
			)
			(layer "F.Fab")
		)
		(fp_line
			(start 0.67945 -0.3048)
			(end 0.67945 0.3048)
			(stroke
				(width 0.1)
				(type default)
			)
			(layer "F.Fab")
		)
		(fp_line
			(start 0.12065 -0.2794)
			(end 0.12065 -0.3048)
			(stroke
				(width 0.1)
				(type default)
			)
			(layer "F.Fab")
		)
		(fp_line
			(start 0.12065 -0.3048)
			(end 0.67945 -0.3048)
			(stroke
				(width 0.1)
				(type default)
			)
			(layer "F.Fab")
		)
		(fp_line
			(start 0.120396 0.3048)
			(end 0.120396 0.2794)
			(stroke
				(width 0.1)
				(type default)
			)
			(layer "F.Fab")
		)
		(fp_line
			(start 0.120396 0.2794)
			(end -0.12065 0.2794)
			(stroke
				(width 0.1)
				(type default)
			)
			(layer "F.Fab")
		)
		(fp_line
			(start -0.12065 0.3048)
			(end -0.67945 0.3048)
			(stroke
				(width 0.1)
				(type default)
			)
			(layer "F.Fab")
		)
		(fp_line
			(start -0.12065 0.2794)
			(end -0.12065 0.3048)
			(stroke
				(width 0.1)
				(type default)
			)
			(layer "F.Fab")
		)
		(fp_line
			(start -0.12065 -0.2794)
			(end 0.12065 -0.2794)
			(stroke
				(width 0.1)
				(type default)
			)
			(layer "F.Fab")
		)
		(fp_line
			(start -0.12065 -0.305054)
			(end -0.12065 -0.2794)
			(stroke
				(width 0.1)
				(type default)
			)
			(layer "F.Fab")
		)
		(fp_line
			(start -0.67945 0.3048)
			(end -0.67945 -0.305054)
			(stroke
				(width 0.1)
				(type default)
			)
			(layer "F.Fab")
		)
		(fp_line
			(start -0.67945 -0.305054)
			(end -0.12065 -0.305054)
			(stroke
				(width 0.1)
				(type default)
			)
			(layer "F.Fab")
		)
		(pad "1" smd circle
			(at -0.40005 0 180)
			(size 0 0)
			(layers "F.Cu" "F.Mask" "F.Paste")
			(net "I3C_BMC_SWB_BUF_R_SDA")
		)
		(pad "2" smd circle
			(at 0.40005 0 180)
			(size 0 0)
			(layers "F.Cu" "F.Mask" "F.Paste")
			(net "I3C_BMC_SWB_BUF_SDA")
		)
	)
	(footprint ""
		(layer "F.Cu")
		(at 459.267814 -380.572772)
		(property "Reference" "PR92"
			(at 0 0 0)
			(layer "F.SilkS")
			(hide yes)
			(effects
				(font
					(size 1.27 1.27)
				)
			)
		)
		(property "Value" ""
			(at 0 0 0)
			(layer "F.Fab")
			(effects
				(font
					(size 1.27 1.27)
				)
			)
		)
		(duplicate_pad_numbers_are_jumpers no)
		(fp_line
			(start -0.7874 -0.4064)
			(end 0.7874 -0.4064)
			(stroke
				(width 0.1524)
				(type default)
			)
			(layer "F.SilkS")
		)
		(fp_line
			(start -0.7874 0.4064)
			(end -0.7874 -0.4064)
			(stroke
				(width 0.1524)
				(type default)
			)
			(layer "F.SilkS")
		)
		(fp_line
			(start 0.7874 -0.4064)
			(end 0.7874 0.4064)
			(stroke
				(width 0.1524)
				(type default)
			)
			(layer "F.SilkS")
		)
		(fp_line
			(start 0.7874 0.4064)
			(end -0.7874 0.4064)
			(stroke
				(width 0.1524)
				(type default)
			)
			(layer "F.SilkS")
		)
		(fp_line
			(start -0.67945 -0.305054)
			(end -0.12065 -0.305054)
			(stroke
				(width 0.1)
				(type default)
			)
			(layer "F.Fab")
		)
		(fp_line
			(start -0.67945 0.3048)
			(end -0.67945 -0.305054)
			(stroke
				(width 0.1)
				(type default)
			)
			(layer "F.Fab")
		)
		(fp_line
			(start -0.12065 -0.305054)
			(end -0.12065 -0.2794)
			(stroke
				(width 0.1)
				(type default)
			)
			(layer "F.Fab")
		)
		(fp_line
			(start -0.12065 -0.2794)
			(end 0.12065 -0.2794)
			(stroke
				(width 0.1)
				(type default)
			)
			(layer "F.Fab")
		)
		(fp_line
			(start -0.12065 0.2794)
			(end -0.12065 0.3048)
			(stroke
				(width 0.1)
				(type default)
			)
			(layer "F.Fab")
		)
		(fp_line
			(start -0.12065 0.3048)
			(end -0.67945 0.3048)
			(stroke
				(width 0.1)
				(type default)
			)
			(layer "F.Fab")
		)
		(fp_line
			(start 0.120396 0.2794)
			(end -0.12065 0.2794)
			(stroke
				(width 0.1)
				(type default)
			)
			(layer "F.Fab")
		)
		(fp_line
			(start 0.120396 0.3048)
			(end 0.120396 0.2794)
			(stroke
				(width 0.1)
				(type default)
			)
			(layer "F.Fab")
		)
		(fp_line
			(start 0.12065 -0.3048)
			(end 0.67945 -0.3048)
			(stroke
				(width 0.1)
				(type default)
			)
			(layer "F.Fab")
		)
		(fp_line
			(start 0.12065 -0.2794)
			(end 0.12065 -0.3048)
			(stroke
				(width 0.1)
				(type default)
			)
			(layer "F.Fab")
		)
		(fp_line
			(start 0.67945 -0.3048)
			(end 0.67945 0.3048)
			(stroke
				(width 0.1)
				(type default)
			)
			(layer "F.Fab")
		)
		(fp_line
			(start 0.67945 0.3048)
			(end 0.120396 0.3048)
			(stroke
				(width 0.1)
				(type default)
			)
			(layer "F.Fab")
		)
		(pad "1" smd circle
			(at -0.40005 0)
			(size 0 0)
			(layers "F.Cu" "F.Mask" "F.Paste")
			(net "P5V_AUX_FB")
		)
		(pad "2" smd circle
			(at 0.40005 0)
			(size 0 0)
			(layers "F.Cu" "F.Mask" "F.Paste")
			(net "P5V_AUX")
		)
	)
	(footprint ""
		(layer "F.Cu")
		(at 420.4716 -160.452562 180)
		(property "Reference" "PC636"
			(at 0 0 180)
			(layer "F.SilkS")
			(hide yes)
			(effects
				(font
					(size 1.27 1.27)
				)
			)
		)
		(property "Value" ""
			(at 0 0 180)
			(layer "F.Fab")
			(effects
				(font
					(size 1.27 1.27)
				)
			)
		)
		(duplicate_pad_numbers_are_jumpers no)
		(fp_line
			(start 0.7874 0.4064)
			(end -0.7874 0.4064)
			(stroke
				(width 0.1524)
				(type default)
			)
			(layer "F.SilkS")
		)
		(fp_line
			(start 0.7874 -0.4064)
			(end 0.7874 0.4064)
			(stroke
				(width 0.1524)
				(type default)
			)
			(layer "F.SilkS")
		)
		(fp_line
			(start -0.7874 0.4064)
			(end -0.7874 -0.4064)
			(stroke
				(width 0.1524)
				(type default)
			)
			(layer "F.SilkS")
		)
		(fp_line
			(start -0.7874 -0.4064)
			(end 0.7874 -0.4064)
			(stroke
				(width 0.1524)
				(type default)
			)
			(layer "F.SilkS")
		)
		(fp_line
			(start 0.67945 0.3048)
			(end 0.120396 0.3048)
			(stroke
				(width 0.1)
				(type default)
			)
			(layer "F.Fab")
		)
		(fp_line
			(start 0.67945 -0.3048)
			(end 0.67945 0.3048)
			(stroke
				(width 0.1)
				(type default)
			)
			(layer "F.Fab")
		)
		(fp_line
			(start 0.12065 -0.2794)
			(end 0.12065 -0.3048)
			(stroke
				(width 0.1)
				(type default)
			)
			(layer "F.Fab")
		)
		(fp_line
			(start 0.12065 -0.3048)
			(end 0.67945 -0.3048)
			(stroke
				(width 0.1)
				(type default)
			)
			(layer "F.Fab")
		)
		(fp_line
			(start 0.120396 0.3048)
			(end 0.120396 0.2794)
			(stroke
				(width 0.1)
				(type default)
			)
			(layer "F.Fab")
		)
		(fp_line
			(start 0.120396 0.2794)
			(end -0.12065 0.2794)
			(stroke
				(width 0.1)
				(type default)
			)
			(layer "F.Fab")
		)
		(fp_line
			(start -0.12065 0.3048)
			(end -0.67945 0.3048)
			(stroke
				(width 0.1)
				(type default)
			)
			(layer "F.Fab")
		)
		(fp_line
			(start -0.12065 0.2794)
			(end -0.12065 0.3048)
			(stroke
				(width 0.1)
				(type default)
			)
			(layer "F.Fab")
		)
		(fp_line
			(start -0.12065 -0.2794)
			(end 0.12065 -0.2794)
			(stroke
				(width 0.1)
				(type default)
			)
			(layer "F.Fab")
		)
		(fp_line
			(start -0.12065 -0.305054)
			(end -0.12065 -0.2794)
			(stroke
				(width 0.1)
				(type default)
			)
			(layer "F.Fab")
		)
		(fp_line
			(start -0.67945 0.3048)
			(end -0.67945 -0.305054)
			(stroke
				(width 0.1)
				(type default)
			)
			(layer "F.Fab")
		)
		(fp_line
			(start -0.67945 -0.305054)
			(end -0.12065 -0.305054)
			(stroke
				(width 0.1)
				(type default)
			)
			(layer "F.Fab")
		)
		(pad "1" smd circle
			(at -0.40005 0 180)
			(size 0 0)
			(layers "F.Cu" "F.Mask" "F.Paste")
			(net "SW_PVCCD_HV_CPU0_BOOT1_R")
		)
		(pad "2" smd circle
			(at 0.40005 0 180)
			(size 0 0)
			(layers "F.Cu" "F.Mask" "F.Paste")
			(net "SW_PVCCD_HV_CPU0_BOOTR1")
		)
	)
	(footprint ""
		(layer "F.Cu")
		(at 219.347034 -75.02779 -90)
		(property "Reference" "PC2208"
			(at 0 0 270)
			(layer "F.SilkS")
			(hide yes)
			(effects
				(font
					(size 1.27 1.27)
				)
			)
		)
		(property "Value" ""
			(at 0 0 270)
			(layer "F.Fab")
			(effects
				(font
					(size 1.27 1.27)
				)
			)
		)
		(duplicate_pad_numbers_are_jumpers no)
		(fp_line
			(start -0.7874 0.4064)
			(end -0.7874 -0.4064)
			(stroke
				(width 0.1524)
				(type default)
			)
			(layer "F.SilkS")
		)
		(fp_line
			(start 0.7874 0.4064)
			(end -0.7874 0.4064)
			(stroke
				(width 0.1524)
				(type default)
			)
			(layer "F.SilkS")
		)
		(fp_line
			(start -0.7874 -0.4064)
			(end 0.7874 -0.4064)
			(stroke
				(width 0.1524)
				(type default)
			)
			(layer "F.SilkS")
		)
		(fp_line
			(start 0.7874 -0.4064)
			(end 0.7874 0.4064)
			(stroke
				(width 0.1524)
				(type default)
			)
			(layer "F.SilkS")
		)
		(fp_line
			(start -0.67945 0.3048)
			(end -0.67945 -0.305054)
			(stroke
				(width 0.1)
				(type default)
			)
			(layer "F.Fab")
		)
		(fp_line
			(start -0.12065 0.3048)
			(end -0.67945 0.3048)
			(stroke
				(width 0.1)
				(type default)
			)
			(layer "F.Fab")
		)
		(fp_line
			(start 0.120396 0.3048)
			(end 0.120396 0.2794)
			(stroke
				(width 0.1)
				(type default)
			)
			(layer "F.Fab")
		)
		(fp_line
			(start 0.67945 0.3048)
			(end 0.120396 0.3048)
			(stroke
				(width 0.1)
				(type default)
			)
			(layer "F.Fab")
		)
		(fp_line
			(start -0.12065 0.2794)
			(end -0.12065 0.3048)
			(stroke
				(width 0.1)
				(type default)
			)
			(layer "F.Fab")
		)
		(fp_line
			(start 0.120396 0.2794)
			(end -0.12065 0.2794)
			(stroke
				(width 0.1)
				(type default)
			)
			(layer "F.Fab")
		)
		(fp_line
			(start -0.12065 -0.2794)
			(end 0.12065 -0.2794)
			(stroke
				(width 0.1)
				(type default)
			)
			(layer "F.Fab")
		)
		(fp_line
			(start 0.12065 -0.2794)
			(end 0.12065 -0.3048)
			(stroke
				(width 0.1)
				(type default)
			)
			(layer "F.Fab")
		)
		(fp_line
			(start 0.12065 -0.3048)
			(end 0.67945 -0.3048)
			(stroke
				(width 0.1)
				(type default)
			)
			(layer "F.Fab")
		)
		(fp_line
			(start 0.67945 -0.3048)
			(end 0.67945 0.3048)
			(stroke
				(width 0.1)
				(type default)
			)
			(layer "F.Fab")
		)
		(fp_line
			(start -0.67945 -0.305054)
			(end -0.12065 -0.305054)
			(stroke
				(width 0.1)
				(type default)
			)
			(layer "F.Fab")
		)
		(fp_line
			(start -0.12065 -0.305054)
			(end -0.12065 -0.2794)
			(stroke
				(width 0.1)
				(type default)
			)
			(layer "F.Fab")
		)
		(pad "1" smd circle
			(at -0.40005 0 270)
			(size 0 0)
			(layers "F.Cu" "F.Mask" "F.Paste")
			(net "P3V3_AUX")
		)
		(pad "2" smd circle
			(at 0.40005 0 270)
			(size 0 0)
			(layers "F.Cu" "F.Mask" "F.Paste")
			(net "GND")
		)
	)
	(footprint ""
		(layer "F.Cu")
		(at 35.171126 -136.386062 -90)
		(property "Reference" "PJ50"
			(at -0.650494 -1.97866 0)
			(unlocked yes)
			(layer "F.SilkS")
			(effects
				(font
					(size 0.7874 0.5842)
					(thickness 0.1524)
				)
				(justify left)
			)
		)
		(property "Value" ""
			(at 0 0 270)
			(layer "F.Fab")
			(effects
				(font
					(size 1.27 1.27)
				)
			)
		)
		(duplicate_pad_numbers_are_jumpers no)
		(pad "1" smd circle
			(at -0.7493 0)
			(size 0 0)
			(layers "F.Cu" "F.Mask" "F.Paste")
			(net "VSENSE_PVCCINFAON_CPU1_DP")
		)
		(pad "2" smd rect
			(at 0.7493 0 180)
			(size 0.7112 0.8128)
			(layers "F.Cu" "F.Mask" "F.Paste")
			(net "SH_PVCCINFAON_CPU1")
		)
		(zone
			(layer "F.Cu")
			(hatch none 0.5)
			(connect_pads
				(clearance 0)
			)
			(min_thickness 0.25)
			(keepout
				(tracks allowed)
				(vias not_allowed)
				(pads allowed)
				(copperpour not_allowed)
				(footprints allowed)
			)
			(placement
				(enabled no)
				(sheetname "")
			)
			(fill
				(thermal_gap 0.5)
				(thermal_bridge_width 0.5)
				(island_removal_mode 0)
			)
			(polygon
				(pts
					(xy 34.7599 -135.179562) (xy 35.577526 -135.179562) (xy 35.577526 -137.567162) (xy 34.7599 -137.567162)
				)
			)
		)
	)
	(footprint ""
		(layer "F.Cu")
		(at 336.899758 -48.450246)
		(property "Reference" "U4"
			(at -13.479018 -11.486896 0)
			(unlocked yes)
			(layer "F.SilkS")
			(effects
				(font
					(size 0.7874 0.5842)
					(thickness 0.1524)
				)
				(justify left)
			)
		)
		(property "Value" ""
			(at 0 0 0)
			(layer "F.Fab")
			(effects
				(font
					(size 1.27 1.27)
				)
			)
		)
		(duplicate_pad_numbers_are_jumpers no)
		(fp_line
			(start -10.999978 -11.500104)
			(end -5.907278 -11.500104)
			(stroke
				(width 0.1524)
				(type default)
			)
			(layer "F.SilkS")
		)
		(fp_line
			(start -10.999978 11.500104)
			(end -10.999978 -11.500104)
			(stroke
				(width 0.1524)
				(type default)
			)
			(layer "F.SilkS")
		)
		(fp_line
			(start -5.300218 -11.500104)
			(end -2.864358 -11.500104)
			(stroke
				(width 0.1524)
				(type default)
			)
			(layer "F.SilkS")
		)
		(fp_line
			(start -2.315718 -11.500104)
			(end -0.994918 -11.500104)
			(stroke
				(width 0.1524)
				(type default)
			)
			(layer "F.SilkS")
		)
		(fp_line
			(start -0.301498 -11.500104)
			(end 1.057402 -11.500104)
			(stroke
				(width 0.1524)
				(type default)
			)
			(layer "F.SilkS")
		)
		(fp_line
			(start 1.804162 -11.500104)
			(end 2.103882 -11.500104)
			(stroke
				(width 0.1524)
				(type default)
			)
			(layer "F.SilkS")
		)
		(fp_line
			(start 3.409442 -11.500104)
			(end 3.528822 -11.500104)
			(stroke
				(width 0.1524)
				(type default)
			)
			(layer "F.SilkS")
		)
		(fp_line
			(start 4.107942 -11.500104)
			(end 4.407662 -11.500104)
			(stroke
				(width 0.1524)
				(type default)
			)
			(layer "F.SilkS")
		)
		(fp_line
			(start 8.352282 -11.500104)
			(end 10.999978 -11.500104)
			(stroke
				(width 0.1524)
				(type default)
			)
			(layer "F.SilkS")
		)
		(fp_line
			(start 10.999978 -11.500104)
			(end 10.999978 -6.571742)
			(stroke
				(width 0.1524)
				(type default)
			)
			(layer "F.SilkS")
		)
		(fp_line
			(start 10.999978 -5.111242)
			(end 10.999978 -4.328922)
			(stroke
				(width 0.1524)
				(type default)
			)
			(layer "F.SilkS")
		)
		(fp_line
			(start 10.999978 0.822198)
			(end 10.999978 2.318258)
			(stroke
				(width 0.1524)
				(type default)
			)
			(layer "F.SilkS")
		)
		(fp_line
			(start 10.999978 5.404358)
			(end 10.999978 6.504178)
			(stroke
				(width 0.1524)
				(type default)
			)
			(layer "F.SilkS")
		)
		(fp_line
			(start 10.999978 7.423658)
			(end 10.999978 11.500104)
			(stroke
				(width 0.1524)
				(type default)
			)
			(layer "F.SilkS")
		)
		(fp_line
			(start 10.999978 11.500104)
			(end -10.999978 11.500104)
			(stroke
				(width 0.1524)
				(type default)
			)
			(layer "F.SilkS")
		)
		(fp_poly
			(pts
				(xy -10.999978 -10.159746) (xy -11.761978 -10.159746) (xy -11.761978 -12.262104) (xy -9.65962 -12.262104)
				(xy -9.65962 -11.500104) (xy -10.999978 -11.500104)
			)
			(stroke
				(width 0)
				(type default)
			)
			(fill yes)
			(layer "F.SilkS")
		)
		(fp_line
			(start -10.999978 -11.500104)
			(end 10.999978 -11.500104)
			(stroke
				(width 0.1)
				(type default)
			)
			(layer "F.Fab")
		)
		(fp_line
			(start -10.999978 11.500104)
			(end -10.999978 -11.500104)
			(stroke
				(width 0.1)
				(type default)
			)
			(layer "F.Fab")
		)
		(fp_line
			(start 10.999978 -11.500104)
			(end 10.999978 11.500104)
			(stroke
				(width 0.1)
				(type default)
			)
			(layer "F.Fab")
		)
		(fp_line
			(start 10.999978 11.500104)
			(end -10.999978 11.500104)
			(stroke
				(width 0.1)
				(type default)
			)
			(layer "F.Fab")
		)
		(fp_poly
			(pts
				(xy -11.761978 -12.262104) (xy -9.65962 -12.262104) (xy -9.65962 -11.500104) (xy -10.999978 -11.500104)
				(xy -10.999978 -10.159746) (xy -11.761978 -10.159746)
			)
			(stroke
				(width 0)
				(type default)
			)
			(fill yes)
			(layer "F.Fab")
		)
		(pad "A4" smd circle
			(at -9.0043 -10.815066 180)
			(size 0.4064 0.4064)
			(layers "F.Cu" "F.Mask" "F.Paste")
			(net "TP_PCH_RSVD<2>")
		)
		(pad "A6" smd circle
			(at -8.003794 -10.815066 180)
			(size 0.4064 0.4064)
			(layers "F.Cu" "F.Mask" "F.Paste")
			(net "GND")
		)
		(pad "A8" smd oval
			(at -7.003288 -10.815066 180)
			(size 0.254 0.3302)
			(layers "F.Cu" "F.Mask" "F.Paste")
			(net "TP_CLK_100M_PCH_13_DN")
		)
		(pad "A10" smd oval
			(at -6.002782 -10.815066 180)
			(size 0.254 0.3302)
			(layers "F.Cu" "F.Mask" "F.Paste")
			(net "TP_CLK_100M_PCH_12_DN")
		)
		(pad "A12" smd oval
			(at -5.002276 -10.815066 180)
			(size 0.254 0.3302)
			(layers "F.Cu" "F.Mask" "F.Paste")
			(net "TP_CLK_100M_PCH_5_DN")
		)
		(pad "A14" smd oval
			(at -4.002024 -10.815066 180)
			(size 0.254 0.3302)
			(layers "F.Cu" "F.Mask" "F.Paste")
			(net "TP_CLK_100M_PCH_7_DN")
		)
		(pad "A16" smd oval
			(at -3.001518 -10.815066 180)
			(size 0.254 0.3302)
			(layers "F.Cu" "F.Mask" "F.Paste")
			(net "TP_CLK_100M_PCH_0_DN")
		)
		(pad "A18" smd oval
			(at -2.001012 -10.815066 180)
			(size 0.254 0.3302)
			(layers "F.Cu" "F.Mask" "F.Paste")
			(net "TP_CLK_100M_PCH_16_DN")
		)
		(pad "A20" smd oval
			(at -1.000506 -10.815066 180)
			(size 0.254 0.3302)
			(layers "F.Cu" "F.Mask" "F.Paste")
			(net "GND")
		)
		(pad "A22" smd oval
			(at 0 -10.815066 180)
			(size 0.254 0.3302)
			(layers "F.Cu" "F.Mask" "F.Paste")
			(net "GND")
		)
		(pad "A24" smd oval
			(at 1.000506 -10.815066 180)
			(size 0.254 0.3302)
			(layers "F.Cu" "F.Mask" "F.Paste")
			(net "GND")
		)
		(pad "A26" smd oval
			(at 2.001012 -10.815066 180)
			(size 0.254 0.3302)
			(layers "F.Cu" "F.Mask" "F.Paste")
			(net "GND")
		)
		(pad "A28" smd oval
			(at 3.001518 -10.815066 180)
			(size 0.254 0.3302)
			(layers "F.Cu" "F.Mask" "F.Paste")
			(net "CLK_25M_PCH_CPU1_DP")
		)
		(pad "A30" smd oval
			(at 4.002024 -10.815066 180)
			(size 0.254 0.3302)
			(layers "F.Cu" "F.Mask" "F.Paste")
			(net "DMI_CPU0_PCH_TX_C_DN<0>")
		)
		(pad "A32" smd oval
			(at 5.002276 -10.815066 180)
			(size 0.254 0.3302)
			(layers "F.Cu" "F.Mask" "F.Paste")
			(net "DMI_CPU0_PCH_TX_C_DN<2>")
		)
		(pad "A34" smd oval
			(at 6.002782 -10.815066 180)
			(size 0.254 0.3302)
			(layers "F.Cu" "F.Mask" "F.Paste")
			(net "DMI_CPU0_PCH_TX_C_DN<4>")
		)
		(pad "A36" smd oval
			(at 7.003288 -10.815066 180)
			(size 0.254 0.3302)
			(layers "F.Cu" "F.Mask" "F.Paste")
			(net "DMI_CPU0_PCH_TX_C_DN<6>")
		)
		(pad "A38" smd circle
			(at 8.003794 -10.815066 180)
			(size 0.4064 0.4064)
			(layers "F.Cu" "F.Mask" "F.Paste")
			(net "GND")
		)
		(pad "A40" smd circle
			(at 9.0043 -10.815066 180)
			(size 0.4064 0.4064)
			(layers "F.Cu" "F.Mask" "F.Paste")
			(net "GND")
		)
		(pad "A41" smd circle
			(at 9.65962 -10.815066 180)
			(size 0.4064 0.4064)
			(layers "F.Cu" "F.Mask" "F.Paste")
			(net "FM_PCH_PRSNT_N")
		)
		(pad "AA1" smd oval
			(at -10.31494 -1.500632 270)
			(size 0.254 0.3302)
			(layers "F.Cu" "F.Mask" "F.Paste")
			(net "FM_PCH_GLB_RST_WARN_N")
		)
		(pad "AA3" smd circle
			(at -9.484868 -1.500632 180)
			(size 0.3048 0.3048)
			(layers "F.Cu" "F.Mask" "F.Paste")
			(net "FM_BIOS_DEBUG_EN_R_N")
		)
		(pad "AA5" smd circle
			(at -8.654796 -1.500632 180)
			(size 0.3048 0.3048)
			(layers "F.Cu" "F.Mask" "F.Paste")
			(net "GND")
		)
		(pad "AA7" smd circle
			(at -7.733792 -1.4097 180)
			(size 0.381 0.381)
			(layers "F.Cu" "F.Mask" "F.Paste")
			(net "FAB_REV_ID2")
		)
		(pad "AA10" smd circle
			(at -6.105398 -1.4097 180)
			(size 0.381 0.381)
			(layers "F.Cu" "F.Mask" "F.Paste")
			(net "FM_BOARD_SKU_ID0")
		)
		(pad "AA13" smd circle
			(at -4.477512 -1.4097 180)
			(size 0.381 0.381)
			(layers "F.Cu" "F.Mask" "F.Paste")
			(net "FAB_REV_ID1")
		)
		(pad "AA17" smd circle
			(at -2.4003 -1.6002 180)
			(size 0.381 0.381)
			(layers "F.Cu" "F.Mask" "F.Paste")
			(net "GND")
		)
		(pad "AA19" smd circle
			(at -1.6002 -1.6002 180)
			(size 0.381 0.381)
			(layers "F.Cu" "F.Mask" "F.Paste")
			(net "GND")
		)
		(pad "AA20" smd circle
			(at -0.8001 -1.6002 180)
			(size 0.381 0.381)
			(layers "F.Cu" "F.Mask" "F.Paste")
			(net "GND")
		)
		(pad "AA22" smd circle
			(at 0 -1.6002 180)
			(size 0.381 0.381)
			(layers "F.Cu" "F.Mask" "F.Paste")
			(net "GND")
		)
		(pad "AA24" smd circle
			(at 0.8001 -1.6002 180)
			(size 0.381 0.381)
			(layers "F.Cu" "F.Mask" "F.Paste")
			(net "GND")
		)
		(pad "AA25" smd circle
			(at 1.6002 -1.6002 180)
			(size 0.381 0.381)
			(layers "F.Cu" "F.Mask" "F.Paste")
			(net "GND")
		)
		(pad "AA27" smd circle
			(at 2.4003 -1.6002 180)
			(size 0.381 0.381)
			(layers "F.Cu" "F.Mask" "F.Paste")
			(net "GND")
		)
		(pad "AA29" smd circle
			(at 3.663188 -1.4097 180)
			(size 0.381 0.381)
			(layers "F.Cu" "F.Mask" "F.Paste")
			(net "P1V05_PCH_PLL_AUX")
		)
		(pad "AA32" smd circle
			(at 5.291582 -1.4097 180)
			(size 0.381 0.381)
			(layers "F.Cu" "F.Mask" "F.Paste")
			(net "GND")
		)
		(pad "AA36" smd circle
			(at 6.919722 -1.4097 180)
			(size 0.381 0.381)
			(layers "F.Cu" "F.Mask" "F.Paste")
			(net "GND")
		)
		(pad "AA39" smd circle
			(at 8.654796 -1.500632 180)
			(size 0.3048 0.3048)
			(layers "F.Cu" "F.Mask" "F.Paste")
			(net "GND")
		)
		(pad "AA41" smd circle
			(at 9.484868 -1.500632 180)
			(size 0.3048 0.3048)
			(layers "F.Cu" "F.Mask" "F.Paste")
			(net "P3E_PCH_E1S_RX_DN<0>")
		)
		(pad "AA43" smd oval
			(at 10.31494 -1.500632 270)
			(size 0.254 0.3302)
			(layers "F.Cu" "F.Mask" "F.Paste")
			(net "P3E_PCH_E1S_RX_DP<0>")
		)
		(pad "AB2" smd circle
			(at -9.899904 -1.000506 180)
			(size 0.3048 0.3048)
			(layers "F.Cu" "F.Mask" "F.Paste")
			(net "IRQ_PCH_SCI_WHEA_N")
		)
		(pad "AB4" smd circle
			(at -9.069832 -1.000506 180)
			(size 0.3048 0.3048)
			(layers "F.Cu" "F.Mask" "F.Paste")
			(net "RST_PLTRST_N")
		)
		(pad "AB8" smd circle
			(at -6.919722 -0.9398 180)
			(size 0.381 0.381)
			(layers "F.Cu" "F.Mask" "F.Paste")
			(net "FM_PASSWORD_CLEAR_N")
		)
		(pad "AB11" smd circle
			(at -5.291582 -0.9398 180)
			(size 0.381 0.381)
			(layers "F.Cu" "F.Mask" "F.Paste")
			(net "FM_BOARD_SKU_ID4")
		)
		(pad "AB15" smd circle
			(at -3.663188 -0.9398 180)
			(size 0.381 0.381)
			(layers "F.Cu" "F.Mask" "F.Paste")
			(net "GND")
		)
		(pad "AB17" smd circle
			(at -2.4003 -0.8001 180)
			(size 0.381 0.381)
			(layers "F.Cu" "F.Mask" "F.Paste")
			(net "GND")
		)
		(pad "AB19" smd circle
			(at -1.6002 -0.8001 180)
			(size 0.381 0.381)
			(layers "F.Cu" "F.Mask" "F.Paste")
			(net "P1V05_PCH_AUX")
		)
		(pad "AB20" smd circle
			(at -0.8001 -0.8001 180)
			(size 0.381 0.381)
			(layers "F.Cu" "F.Mask" "F.Paste")
			(net "P1V05_PCH_AUX")
		)
		(pad "AB22" smd circle
			(at 0 -0.8001 180)
			(size 0.381 0.381)
			(layers "F.Cu" "F.Mask" "F.Paste")
			(net "P1V05_PCH_AUX")
		)
		(pad "AB24" smd circle
			(at 0.8001 -0.8001 180)
			(size 0.381 0.381)
			(layers "F.Cu" "F.Mask" "F.Paste")
			(net "P1V05_PCH_AUX")
		)
		(pad "AB25" smd circle
			(at 1.6002 -0.8001 180)
			(size 0.381 0.381)
			(layers "F.Cu" "F.Mask" "F.Paste")
			(net "GND")
		)
		(pad "AB27" smd circle
			(at 2.4003 -0.8001 180)
			(size 0.381 0.381)
			(layers "F.Cu" "F.Mask" "F.Paste")
			(net "P1V05_PCH_PLL_AUX")
		)
		(pad "AB31" smd circle
			(at 4.477512 -0.9398 180)
			(size 0.381 0.381)
			(layers "F.Cu" "F.Mask" "F.Paste")
			(net "P1V8_PCH_PLL_AUX")
		)
		(pad "AB34" smd circle
			(at 6.105398 -0.9398 180)
			(size 0.381 0.381)
			(layers "F.Cu" "F.Mask" "F.Paste")
			(net "P1V8_PCH_PLL_AUX")
		)
		(pad "AB37" smd circle
			(at 7.733792 -0.9398 180)
			(size 0.381 0.381)
			(layers "F.Cu" "F.Mask" "F.Paste")
			(net "GND")
		)
		(pad "AB40" smd circle
			(at 9.069832 -1.000506 180)
			(size 0.3048 0.3048)
			(layers "F.Cu" "F.Mask" "F.Paste")
			(net "P3E_PCH_M2_RX_DN<3>")
		)
		(pad "AB42" smd circle
			(at 9.899904 -1.000506 180)
			(size 0.3048 0.3048)
			(layers "F.Cu" "F.Mask" "F.Paste")
			(net "P3E_PCH_M2_RX_DP<3>")
		)
		(pad "AC1" smd oval
			(at -10.31494 -0.500126 270)
			(size 0.254 0.3302)
			(layers "F.Cu" "F.Mask" "F.Paste")
			(net "FM_ADR_COMPLETE")
		)
		(pad "AC3" smd circle
			(at -9.484868 -0.500126 180)
			(size 0.3048 0.3048)
			(layers "F.Cu" "F.Mask" "F.Paste")
			(net "PU_PCH_VRALERT_N")
		)
		(pad "AC5" smd circle
			(at -8.654796 -0.500126 180)
			(size 0.3048 0.3048)
			(layers "F.Cu" "F.Mask" "F.Paste")
			(net "GND")
		)
		(pad "AC7" smd circle
			(at -7.733792 -0.4699 180)
			(size 0.381 0.381)
			(layers "F.Cu" "F.Mask" "F.Paste")
			(net "TP_GPP_L_7")
		)
		(pad "AC10" smd circle
			(at -6.105398 -0.4699 180)
			(size 0.381 0.381)
			(layers "F.Cu" "F.Mask" "F.Paste")
			(net "TP_GPP_L_2")
		)
		(pad "AC13" smd circle
			(at -4.477512 -0.4699 180)
			(size 0.381 0.381)
			(layers "F.Cu" "F.Mask" "F.Paste")
			(net "PD_RCOMP_1P8_3P3")
		)
		(pad "AC29" smd circle
			(at 3.663188 -0.4699 180)
			(size 0.381 0.381)
			(layers "F.Cu" "F.Mask" "F.Paste")
			(net "GND")
		)
		(pad "AC32" smd circle
			(at 5.291582 -0.4699 180)
			(size 0.381 0.381)
			(layers "F.Cu" "F.Mask" "F.Paste")
			(net "GND")
		)
		(pad "AC36" smd circle
			(at 6.919722 -0.4699 180)
			(size 0.381 0.381)
			(layers "F.Cu" "F.Mask" "F.Paste")
			(net "GND")
		)
		(pad "AC39" smd circle
			(at 8.654796 -0.500126 180)
			(size 0.3048 0.3048)
			(layers "F.Cu" "F.Mask" "F.Paste")
			(net "GND")
		)
		(pad "AC41" smd circle
			(at 9.484868 -0.500126 180)
			(size 0.3048 0.3048)
			(layers "F.Cu" "F.Mask" "F.Paste")
			(net "P3E_PCH_M2_RX_DN<2>")
		)
		(pad "AC43" smd oval
			(at 10.31494 -0.500126 270)
			(size 0.254 0.3302)
			(layers "F.Cu" "F.Mask" "F.Paste")
			(net "P3E_PCH_M2_RX_DP<2>")
		)
		(pad "AD2" smd circle
			(at -9.899904 0 180)
			(size 0.3048 0.3048)
			(layers "F.Cu" "F.Mask" "F.Paste")
			(net "TP_PCH_GPP_D_2")
		)
		(pad "AD4" smd circle
			(at -9.069832 0 180)
			(size 0.3048 0.3048)
			(layers "F.Cu" "F.Mask" "F.Paste")
			(net "FM_ADR_ACK")
		)
		(pad "AD8" smd circle
			(at -6.919722 0 180)
			(size 0.381 0.381)
			(layers "F.Cu" "F.Mask" "F.Paste")
			(net "GND")
		)
		(pad "AD11" smd circle
			(at -5.291582 0 180)
			(size 0.381 0.381)
			(layers "F.Cu" "F.Mask" "F.Paste")
			(net "GND")
		)
		(pad "AD15" smd circle
			(at -3.663188 0 180)
			(size 0.381 0.381)
			(layers "F.Cu" "F.Mask" "F.Paste")
			(net "P3V3_AUX")
		)
		(pad "AD17" smd circle
			(at -2.4003 0 180)
			(size 0.381 0.381)
			(layers "F.Cu" "F.Mask" "F.Paste")
			(net "P3V3_AUX")
		)
		(pad "AD19" smd circle
			(at -1.6002 0 180)
			(size 0.381 0.381)
			(layers "F.Cu" "F.Mask" "F.Paste")
			(net "GND")
		)
		(pad "AD20" smd circle
			(at -0.8001 0 180)
			(size 0.381 0.381)
			(layers "F.Cu" "F.Mask" "F.Paste")
			(net "GND")
		)
		(pad "AD22" smd circle
			(at 0 0 180)
			(size 0.381 0.381)
			(layers "F.Cu" "F.Mask" "F.Paste")
			(net "GND")
		)
		(pad "AD24" smd circle
			(at 0.8001 0 180)
			(size 0.381 0.381)
			(layers "F.Cu" "F.Mask" "F.Paste")
			(net "GND")
		)
		(pad "AD25" smd circle
			(at 1.6002 0 180)
			(size 0.381 0.381)
			(layers "F.Cu" "F.Mask" "F.Paste")
			(net "P1V05_PCH_AUX")
		)
		(pad "AD27" smd circle
			(at 2.4003 0 180)
			(size 0.381 0.381)
			(layers "F.Cu" "F.Mask" "F.Paste")
			(net "P1V05_PCH_AUX")
		)
		(pad "AD31" smd circle
			(at 4.477512 0 180)
			(size 0.381 0.381)
			(layers "F.Cu" "F.Mask" "F.Paste")
			(net "GND")
		)
		(pad "AD34" smd circle
			(at 6.105398 0 180)
			(size 0.381 0.381)
			(layers "F.Cu" "F.Mask" "F.Paste")
			(net "GND")
		)
		(pad "AD37" smd circle
			(at 7.733792 0 180)
			(size 0.381 0.381)
			(layers "F.Cu" "F.Mask" "F.Paste")
			(net "P3E_PCH_BMC_TX_DP")
		)
		(pad "AD40" smd circle
			(at 9.069832 0 180)
			(size 0.3048 0.3048)
			(layers "F.Cu" "F.Mask" "F.Paste")
			(net "P3E_PCH_M2_RX_DN<1>")
		)
		(pad "AD42" smd circle
			(at 9.899904 0 180)
			(size 0.3048 0.3048)
			(layers "F.Cu" "F.Mask" "F.Paste")
			(net "P3E_PCH_M2_RX_DP<1>")
		)
		(pad "AE1" smd oval
			(at -10.31494 0.500126 270)
			(size 0.254 0.3302)
			(layers "F.Cu" "F.Mask" "F.Paste")
			(net "SMB_HOST_BMC_3V3AUX_SDA")
		)
		(pad "AE3" smd circle
			(at -9.484868 0.500126 180)
			(size 0.3048 0.3048)
			(layers "F.Cu" "F.Mask" "F.Paste")
			(net "FM_PCH_CRASHLOG_TRIG_N")
		)
		(pad "AE5" smd circle
			(at -8.654796 0.500126 180)
			(size 0.3048 0.3048)
			(layers "F.Cu" "F.Mask" "F.Paste")
			(net "GND")
		)
		(pad "AE7" smd circle
			(at -7.733792 0.4699 180)
			(size 0.381 0.381)
			(layers "F.Cu" "F.Mask" "F.Paste")
			(net "H_CPU0_PMDOWN_PCH")
		)
		(pad "AE10" smd circle
			(at -6.105398 0.4699 180)
			(size 0.381 0.381)
			(layers "F.Cu" "F.Mask" "F.Paste")
			(net "TP_GPP_L_8")
		)
		(pad "AE13" smd circle
			(at -4.477512 0.4699 180)
			(size 0.381 0.381)
			(layers "F.Cu" "F.Mask" "F.Paste")
			(net "GND")
		)
		(pad "AE29" smd circle
			(at 3.663188 0.4699 180)
			(size 0.381 0.381)
			(layers "F.Cu" "F.Mask" "F.Paste")
			(net "P1V05_PCH_PLL_AUX")
		)
		(pad "AE32" smd circle
			(at 5.291582 0.4699 180)
			(size 0.381 0.381)
			(layers "F.Cu" "F.Mask" "F.Paste")
			(net "USB3_PCH_TX_DN<4>")
		)
		(pad "AE36" smd circle
			(at 6.919722 0.4699 180)
			(size 0.381 0.381)
			(layers "F.Cu" "F.Mask" "F.Paste")
			(net "P3E_PCH_BMC_TX_DN")
		)
		(pad "AE39" smd circle
			(at 8.654796 0.500126 180)
			(size 0.3048 0.3048)
			(layers "F.Cu" "F.Mask" "F.Paste")
			(net "GND")
		)
		(pad "AE41" smd circle
			(at 9.484868 0.500126 180)
			(size 0.3048 0.3048)
			(layers "F.Cu" "F.Mask" "F.Paste")
			(net "P3E_PCH_M2_RX_DN<0>")
		)
		(pad "AE43" smd oval
			(at 10.31494 0.500126 270)
			(size 0.254 0.3302)
			(layers "F.Cu" "F.Mask" "F.Paste")
			(net "P3E_PCH_M2_RX_DP<0>")
		)
		(pad "AF2" smd circle
			(at -9.899904 1.000506 180)
			(size 0.3048 0.3048)
			(layers "F.Cu" "F.Mask" "F.Paste")
			(net "SMB_HOST_BMC_3V3AUX_SCL")
		)
		(pad "AF4" smd circle
			(at -9.069832 1.000506 180)
			(size 0.3048 0.3048)
			(layers "F.Cu" "F.Mask" "F.Paste")
			(net "FM_CPU_RMCA_CATERR_DLY_N")
		)
		(pad "AF8" smd circle
			(at -6.919722 0.9398 180)
			(size 0.381 0.381)
			(layers "F.Cu" "F.Mask" "F.Paste")
			(net "H_CPU0_PMSYNC_PCH_R2")
		)
		(pad "AF11" smd circle
			(at -5.291582 0.9398 180)
			(size 0.381 0.381)
			(layers "F.Cu" "F.Mask" "F.Paste")
			(net "FM_BIOS_ADV_FUNCTIONS")
		)
		(pad "AF15" smd circle
			(at -3.663188 0.9398 180)
			(size 0.381 0.381)
			(layers "F.Cu" "F.Mask" "F.Paste")
			(net "TP_PCH_RSVD<16>")
		)
		(pad "AF17" smd circle
			(at -2.4003 0.8001 180)
			(size 0.381 0.381)
			(layers "F.Cu" "F.Mask" "F.Paste")
			(net "P3V3_AUX")
		)
		(pad "AF19" smd circle
			(at -1.6002 0.8001 180)
			(size 0.381 0.381)
			(layers "F.Cu" "F.Mask" "F.Paste")
			(net "GND")
		)
		(pad "AF20" smd circle
			(at -0.8001 0.8001 180)
			(size 0.381 0.381)
			(layers "F.Cu" "F.Mask" "F.Paste")
			(net "P1V05_PCH_AUX")
		)
		(pad "AF22" smd circle
			(at 0 0.8001 180)
			(size 0.381 0.381)
			(layers "F.Cu" "F.Mask" "F.Paste")
			(net "P1V05_PCH_AUX")
		)
		(pad "AF24" smd circle
			(at 0.8001 0.8001 180)
			(size 0.381 0.381)
			(layers "F.Cu" "F.Mask" "F.Paste")
			(net "GND")
		)
		(pad "AF25" smd circle
			(at 1.6002 0.8001 180)
			(size 0.381 0.381)
			(layers "F.Cu" "F.Mask" "F.Paste")
			(net "P1V05_PCH_AUX")
		)
		(pad "AF27" smd circle
			(at 2.4003 0.8001 180)
			(size 0.381 0.381)
			(layers "F.Cu" "F.Mask" "F.Paste")
			(net "P1V05_PCH_AUX")
		)
		(pad "AF31" smd circle
			(at 4.477512 0.9398 180)
			(size 0.381 0.381)
			(layers "F.Cu" "F.Mask" "F.Paste")
			(net "GND")
		)
		(pad "AF34" smd circle
			(at 6.105398 0.9398 180)
			(size 0.381 0.381)
			(layers "F.Cu" "F.Mask" "F.Paste")
			(net "P3E_PCH_E1S_TX_DN<3>")
		)
		(pad "AF37" smd circle
			(at 7.733792 0.9398 180)
			(size 0.381 0.381)
			(layers "F.Cu" "F.Mask" "F.Paste")
			(net "P3E_PCH_E1S_TX_DN<2>")
		)
		(pad "AF40" smd circle
			(at 9.069832 1.000506 180)
			(size 0.3048 0.3048)
			(layers "F.Cu" "F.Mask" "F.Paste")
			(net "GND")
		)
		(pad "AF42" smd circle
			(at 9.899904 1.000506 180)
			(size 0.3048 0.3048)
			(layers "F.Cu" "F.Mask" "F.Paste")
			(net "GND")
		)
		(pad "AG1" smd oval
			(at -10.31494 1.500632 270)
			(size 0.254 0.3302)
			(layers "F.Cu" "F.Mask" "F.Paste")
			(net "FM_ESPI_FLASH_MODE")
		)
		(pad "AG3" smd circle
			(at -9.484868 1.500632 180)
			(size 0.3048 0.3048)
			(layers "F.Cu" "F.Mask" "F.Paste")
			(net "TP_PCH_GPP_D_20")
		)
		(pad "AG5" smd circle
			(at -8.654796 1.500632 180)
			(size 0.3048 0.3048)
			(layers "F.Cu" "F.Mask" "F.Paste")
			(net "GND")
		)
		(pad "AG7" smd circle
			(at -7.733792 1.4097 180)
			(size 0.381 0.381)
			(layers "F.Cu" "F.Mask" "F.Paste")
			(net "FM_ME_RCVR_N")
		)
		(pad "AG10" smd circle
			(at -6.105398 1.4097 180)
			(size 0.381 0.381)
			(layers "F.Cu" "F.Mask" "F.Paste")
			(net "FM_MFG_MODE")
		)
		(pad "AG13" smd circle
			(at -4.477512 1.4097 180)
			(size 0.381 0.381)
			(layers "F.Cu" "F.Mask" "F.Paste")
			(net "GND")
		)
		(pad "AG17" smd circle
			(at -2.4003 1.6002 180)
			(size 0.381 0.381)
			(layers "F.Cu" "F.Mask" "F.Paste")
			(net "P3V3_AUX")
		)
		(pad "AG19" smd circle
			(at -1.6002 1.6002 180)
			(size 0.381 0.381)
			(layers "F.Cu" "F.Mask" "F.Paste")
			(net "GND")
		)
		(pad "AG20" smd circle
			(at -0.8001 1.6002 180)
			(size 0.381 0.381)
			(layers "F.Cu" "F.Mask" "F.Paste")
			(net "P1V05_PCH_AUX")
		)
		(pad "AG22" smd circle
			(at 0 1.6002 180)
			(size 0.381 0.381)
			(layers "F.Cu" "F.Mask" "F.Paste")
			(net "P1V05_PCH_AUX")
		)
		(pad "AG24" smd circle
			(at 0.8001 1.6002 180)
			(size 0.381 0.381)
			(layers "F.Cu" "F.Mask" "F.Paste")
			(net "GND")
		)
		(pad "AG25" smd circle
			(at 1.6002 1.6002 180)
			(size 0.381 0.381)
			(layers "F.Cu" "F.Mask" "F.Paste")
			(net "P1V05_PCH_AUX")
		)
		(pad "AG27" smd circle
			(at 2.4003 1.6002 180)
			(size 0.381 0.381)
			(layers "F.Cu" "F.Mask" "F.Paste")
			(net "P1V05_PCH_AUX")
		)
		(pad "AG29" smd circle
			(at 3.663188 1.4097 180)
			(size 0.381 0.381)
			(layers "F.Cu" "F.Mask" "F.Paste")
			(net "P1V05_PCH_PLL_AUX")
		)
		(pad "AG32" smd circle
			(at 5.291582 1.4097 180)
			(size 0.381 0.381)
			(layers "F.Cu" "F.Mask" "F.Paste")
			(net "USB3_PCH_TX_DP<4>")
		)
		(pad "AG36" smd circle
			(at 6.919722 1.4097 180)
			(size 0.381 0.381)
			(layers "F.Cu" "F.Mask" "F.Paste")
			(net "P3E_PCH_E1S_TX_DP<3>")
		)
		(pad "AG39" smd circle
			(at 8.654796 1.500632 180)
			(size 0.3048 0.3048)
			(layers "F.Cu" "F.Mask" "F.Paste")
			(net "GND")
		)
		(pad "AG41" smd circle
			(at 9.484868 1.500632 180)
			(size 0.3048 0.3048)
			(layers "F.Cu" "F.Mask" "F.Paste")
			(net "TP_USB2_13_DP")
		)
		(pad "AG43" smd oval
			(at 10.31494 1.500632 270)
			(size 0.254 0.3302)
			(layers "F.Cu" "F.Mask" "F.Paste")
			(net "TP_USB2_13_DN")
		)
		(pad "AH2" smd circle
			(at -9.899904 2.001012 180)
			(size 0.3048 0.3048)
			(layers "F.Cu" "F.Mask" "F.Paste")
			(net "FM_PCHHOT_N")
		)
		(pad "AH4" smd circle
			(at -9.069832 2.001012 180)
			(size 0.3048 0.3048)
			(layers "F.Cu" "F.Mask" "F.Paste")
			(net "FM_ADR_TRIGGER_R_N")
		)
		(pad "AH8" smd circle
			(at -6.919722 1.8796 180)
			(size 0.381 0.381)
			(layers "F.Cu" "F.Mask" "F.Paste")
			(net "GND")
		)
		(pad "AH11" smd circle
			(at -5.291582 1.8796 180)
			(size 0.381 0.381)
			(layers "F.Cu" "F.Mask" "F.Paste")
			(net "IRQ_LVC3_WAKE_N")
		)
		(pad "AH15" smd circle
			(at -3.663188 1.8796 180)
			(size 0.381 0.381)
			(layers "F.Cu" "F.Mask" "F.Paste")
			(net "P3V3_RTC_AUX")
		)
		(pad "AH31" smd circle
			(at 4.477512 1.8796 180)
			(size 0.381 0.381)
			(layers "F.Cu" "F.Mask" "F.Paste")
			(net "GND")
		)
		(pad "AH34" smd circle
			(at 6.105398 1.8796 180)
			(size 0.381 0.381)
			(layers "F.Cu" "F.Mask" "F.Paste")
			(net "P3E_PCH_E1S_TX_DN<1>")
		)
		(pad "AH37" smd circle
			(at 7.733792 1.8796 180)
			(size 0.381 0.381)
			(layers "F.Cu" "F.Mask" "F.Paste")
			(net "P3E_PCH_E1S_TX_DP<2>")
		)
		(pad "AH40" smd circle
			(at 9.069832 2.001012 180)
			(size 0.3048 0.3048)
			(layers "F.Cu" "F.Mask" "F.Paste")
			(net "TP_USB2_11_DP")
		)
		(pad "AH42" smd circle
			(at 9.899904 2.001012 180)
			(size 0.3048 0.3048)
			(layers "F.Cu" "F.Mask" "F.Paste")
			(net "TP_USB2_11_DN")
		)
		(pad "AJ1" smd oval
			(at -10.31494 2.501138 270)
			(size 0.254 0.3302)
			(layers "F.Cu" "F.Mask" "F.Paste")
			(net "FM_FLASH_SECURITY_STRAP")
		)
		(pad "AJ3" smd circle
			(at -9.484868 2.501138 180)
			(size 0.3048 0.3048)
			(layers "F.Cu" "F.Mask" "F.Paste")
			(net "PU_LPC_PME_N")
		)
		(pad "AJ5" smd circle
			(at -8.654796 2.501138 180)
			(size 0.3048 0.3048)
			(layers "F.Cu" "F.Mask" "F.Paste")
			(net "GND")
		)
		(pad "AJ7" smd circle
			(at -7.733792 2.3495 180)
			(size 0.381 0.381)
			(layers "F.Cu" "F.Mask" "F.Paste")
			(net "TP_PCH_GPP_O_11")
		)
		(pad "AJ10" smd circle
			(at -6.105398 2.3495 180)
			(size 0.381 0.381)
			(layers "F.Cu" "F.Mask" "F.Paste")
			(net "RST_PCH_RSTBTN_R_N")
		)
		(pad "AJ13" smd circle
			(at -4.477512 2.3495 180)
			(size 0.381 0.381)
			(layers "F.Cu" "F.Mask" "F.Paste")
			(net "TP_PCH_SLP_S5_N")
		)
		(pad "AJ17" smd circle
			(at -2.4003 2.4003 180)
			(size 0.381 0.381)
			(layers "F.Cu" "F.Mask" "F.Paste")
			(net "P3V3_AUX")
		)
		(pad "AJ19" smd circle
			(at -1.6002 2.4003 180)
			(size 0.381 0.381)
			(layers "F.Cu" "F.Mask" "F.Paste")
			(net "GND")
		)
		(pad "AJ20" smd circle
			(at -0.8001 2.4003 180)
			(size 0.381 0.381)
			(layers "F.Cu" "F.Mask" "F.Paste")
			(net "P1V05_PCH_AUX")
		)
		(pad "AJ22" smd circle
			(at 0 2.4003 180)
			(size 0.381 0.381)
			(layers "F.Cu" "F.Mask" "F.Paste")
			(net "P1V05_PCH_AUX")
		)
		(pad "AJ24" smd circle
			(at 0.8001 2.4003 180)
			(size 0.381 0.381)
			(layers "F.Cu" "F.Mask" "F.Paste")
			(net "GND")
		)
		(pad "AJ25" smd circle
			(at 1.6002 2.4003 180)
			(size 0.381 0.381)
			(layers "F.Cu" "F.Mask" "F.Paste")
			(net "P1V05_PCH_AUX")
		)
		(pad "AJ27" smd circle
			(at 2.4003 2.4003 180)
			(size 0.381 0.381)
			(layers "F.Cu" "F.Mask" "F.Paste")
			(net "P1V05_PCH_AUX")
		)
		(pad "AJ29" smd circle
			(at 3.663188 2.3495 180)
			(size 0.381 0.381)
			(layers "F.Cu" "F.Mask" "F.Paste")
			(net "GND")
		)
		(pad "AJ32" smd circle
			(at 5.291582 2.3495 180)
			(size 0.381 0.381)
			(layers "F.Cu" "F.Mask" "F.Paste")
			(net "P3E_PCH_E1S_TX_DP<1>")
		)
		(pad "AJ36" smd circle
			(at 6.919722 2.3495 180)
			(size 0.381 0.381)
			(layers "F.Cu" "F.Mask" "F.Paste")
			(net "GND")
		)
		(pad "AJ39" smd circle
			(at 8.654796 2.501138 180)
			(size 0.3048 0.3048)
			(layers "F.Cu" "F.Mask" "F.Paste")
			(net "GND")
		)
		(pad "AJ41" smd circle
			(at 9.484868 2.501138 180)
			(size 0.3048 0.3048)
			(layers "F.Cu" "F.Mask" "F.Paste")
			(net "TP_USB2_9_DP")
		)
		(pad "AJ43" smd oval
			(at 10.31494 2.501138 270)
			(size 0.254 0.3302)
			(layers "F.Cu" "F.Mask" "F.Paste")
			(net "TP_USB2_9_DN")
		)
		(pad "AK2" smd circle
			(at -9.899904 3.001518 180)
			(size 0.3048 0.3048)
			(layers "F.Cu" "F.Mask" "F.Paste")
			(net "GND")
		)
		(pad "AK4" smd circle
			(at -9.069832 3.001518 180)
			(size 0.3048 0.3048)
			(layers "F.Cu" "F.Mask" "F.Paste")
			(net "GND")
		)
		(pad "AK8" smd circle
			(at -6.919722 2.8194 180)
			(size 0.381 0.381)
			(layers "F.Cu" "F.Mask" "F.Paste")
			(net "TP_SLP_LAN_N")
		)
		(pad "AK11" smd circle
			(at -5.291582 2.8194 180)
			(size 0.381 0.381)
			(layers "F.Cu" "F.Mask" "F.Paste")
			(net "GND")
		)
		(pad "AK15" smd circle
			(at -3.663188 2.8194 180)
			(size 0.381 0.381)
			(layers "F.Cu" "F.Mask" "F.Paste")
			(net "P3V3_AUX")
		)
		(pad "AK31" smd circle
			(at 4.477512 2.8194 180)
			(size 0.381 0.381)
			(layers "F.Cu" "F.Mask" "F.Paste")
			(net "P3E_PCH_M2_TX_DP<0>")
		)
		(pad "AK34" smd circle
			(at 6.105398 2.8194 180)
			(size 0.381 0.381)
			(layers "F.Cu" "F.Mask" "F.Paste")
			(net "P3E_PCH_M2_TX_DN<3>")
		)
		(pad "AK37" smd circle
			(at 7.733792 2.8194 180)
			(size 0.381 0.381)
			(layers "F.Cu" "F.Mask" "F.Paste")
			(net "GND")
		)
		(pad "AK40" smd circle
			(at 9.069832 3.001518 180)
			(size 0.3048 0.3048)
			(layers "F.Cu" "F.Mask" "F.Paste")
			(net "USB2_7_DP")
		)
		(pad "AK42" smd circle
			(at 9.899904 3.001518 180)
			(size 0.3048 0.3048)
			(layers "F.Cu" "F.Mask" "F.Paste")
			(net "USB2_7_DN")
		)
		(pad "AL1" smd oval
			(at -10.31494 3.501644 270)
			(size 0.254 0.3302)
			(layers "F.Cu" "F.Mask" "F.Paste")
			(net "PU_SMB_PCH_PLD_3V3AUX_SCL")
		)
		(pad "AL3" smd circle
			(at -9.484868 3.501644 180)
			(size 0.3048 0.3048)
			(layers "F.Cu" "F.Mask" "F.Paste")
			(net "FM_BIOS_POST_CMPLT_N")
		)
		(pad "AL5" smd circle
			(at -8.654796 3.501644 180)
			(size 0.3048 0.3048)
			(layers "F.Cu" "F.Mask" "F.Paste")
			(net "FM_ADR_MODE1")
		)
		(pad "AL7" smd circle
			(at -7.733792 3.2893 180)
			(size 0.381 0.381)
			(layers "F.Cu" "F.Mask" "F.Paste")
			(net "FM_PCH_SLP_SUS_N")
		)
		(pad "AL10" smd circle
			(at -6.105398 3.2893 180)
			(size 0.381 0.381)
			(layers "F.Cu" "F.Mask" "F.Paste")
			(net "PWRGD_SYS_PWROK")
		)
		(pad "AL13" smd circle
			(at -4.477512 3.2893 180)
			(size 0.381 0.381)
			(layers "F.Cu" "F.Mask" "F.Paste")
			(net "FM_PCH_SLP_S4_N")
		)
		(pad "AL17" smd circle
			(at -2.4003 3.2004 180)
			(size 0.381 0.381)
			(layers "F.Cu" "F.Mask" "F.Paste")
			(net "P3V3_AUX")
		)
		(pad "AL19" smd circle
			(at -1.6002 3.2004 180)
			(size 0.381 0.381)
			(layers "F.Cu" "F.Mask" "F.Paste")
			(net "GND")
		)
		(pad "AL20" smd circle
			(at -0.8001 3.2004 180)
			(size 0.381 0.381)
			(layers "F.Cu" "F.Mask" "F.Paste")
			(net "P1V05_PCH_AUX")
		)
		(pad "AL22" smd circle
			(at 0 3.2004 180)
			(size 0.381 0.381)
			(layers "F.Cu" "F.Mask" "F.Paste")
			(net "P1V05_PCH_AUX")
		)
		(pad "AL24" smd circle
			(at 0.8001 3.2004 180)
			(size 0.381 0.381)
			(layers "F.Cu" "F.Mask" "F.Paste")
			(net "GND")
		)
		(pad "AL25" smd circle
			(at 1.6002 3.2004 180)
			(size 0.381 0.381)
			(layers "F.Cu" "F.Mask" "F.Paste")
			(net "P1V05_PCH_PLL_AUX")
		)
		(pad "AL27" smd circle
			(at 2.4003 3.2004 180)
			(size 0.381 0.381)
			(layers "F.Cu" "F.Mask" "F.Paste")
			(net "GND")
		)
		(pad "AL29" smd circle
			(at 3.663188 3.2893 180)
			(size 0.381 0.381)
			(layers "F.Cu" "F.Mask" "F.Paste")
			(net "GND")
		)
		(pad "AL32" smd circle
			(at 5.291582 3.2893 180)
			(size 0.381 0.381)
			(layers "F.Cu" "F.Mask" "F.Paste")
			(net "P3E_PCH_M2_TX_DN<0>")
		)
		(pad "AL36" smd circle
			(at 6.919722 3.2893 180)
			(size 0.381 0.381)
			(layers "F.Cu" "F.Mask" "F.Paste")
			(net "P3E_PCH_E1S_TX_DN<0>")
		)
		(pad "AL39" smd circle
			(at 8.654796 3.501644 180)
			(size 0.3048 0.3048)
			(layers "F.Cu" "F.Mask" "F.Paste")
			(net "GND")
		)
		(pad "AL41" smd circle
			(at 9.484868 3.501644 180)
			(size 0.3048 0.3048)
			(layers "F.Cu" "F.Mask" "F.Paste")
			(net "USB2_5_DP")
		)
		(pad "AL43" smd oval
			(at 10.31494 3.501644 270)
			(size 0.254 0.3302)
			(layers "F.Cu" "F.Mask" "F.Paste")
			(net "USB2_5_DN")
		)
		(pad "AM8" smd circle
			(at -6.919722 3.7592 180)
			(size 0.381 0.381)
			(layers "F.Cu" "F.Mask" "F.Paste")
			(net "GND")
		)
		(pad "AM11" smd circle
			(at -5.291582 3.7592 180)
			(size 0.381 0.381)
			(layers "F.Cu" "F.Mask" "F.Paste")
			(net "TP_PCH_SLP_A_N")
		)
		(pad "AM15" smd circle
			(at -3.663188 3.7592 180)
			(size 0.381 0.381)
			(layers "F.Cu" "F.Mask" "F.Paste")
			(net "GND")
		)
		(pad "AM31" smd circle
			(at 4.477512 3.7592 180)
			(size 0.381 0.381)
			(layers "F.Cu" "F.Mask" "F.Paste")
			(net "GND")
		)
		(pad "AM34" smd circle
			(at 6.105398 3.7592 180)
			(size 0.381 0.381)
			(layers "F.Cu" "F.Mask" "F.Paste")
			(net "P3E_PCH_M2_TX_DP<3>")
		)
		(pad "AM37" smd circle
			(at 7.733792 3.7592 180)
			(size 0.381 0.381)
			(layers "F.Cu" "F.Mask" "F.Paste")
			(net "P3E_PCH_E1S_TX_DP<0>")
		)
		(pad "AN2" smd circle
			(at -9.899904 4.002024 180)
			(size 0.3048 0.3048)
			(layers "F.Cu" "F.Mask" "F.Paste")
			(net "PU_PCH_PLD_3V3AUX_ALERT_N")
		)
		(pad "AN4" smd circle
			(at -9.069832 4.002024 180)
			(size 0.3048 0.3048)
			(layers "F.Cu" "F.Mask" "F.Paste")
			(net "PU_SMB_SML3_3V3AUX_PCH_SCL")
		)
		(pad "AN7" smd circle
			(at -7.733792 4.2291 180)
			(size 0.381 0.381)
			(layers "F.Cu" "F.Mask" "F.Paste")
			(net "PU_ACPRESENT")
		)
		(pad "AN10" smd circle
			(at -6.105398 4.2291 180)
			(size 0.381 0.381)
			(layers "F.Cu" "F.Mask" "F.Paste")
			(net "FM_PCH_SPARE0")
		)
		(pad "AN13" smd circle
			(at -4.477512 4.2291 180)
			(size 0.381 0.381)
			(layers "F.Cu" "F.Mask" "F.Paste")
			(net "GND")
		)
		(pad "AN16" smd circle
			(at -2.849118 4.2291 180)
			(size 0.381 0.381)
			(layers "F.Cu" "F.Mask" "F.Paste")
			(net "GND")
		)
		(pad "AN20" smd circle
			(at -1.220978 4.2291 180)
			(size 0.381 0.381)
			(layers "F.Cu" "F.Mask" "F.Paste")
			(net "P3V3_AUX")
		)
		(pad "AN23" smd circle
			(at 0.406908 4.2291 180)
			(size 0.381 0.381)
			(layers "F.Cu" "F.Mask" "F.Paste")
			(net "P1V05_PCH_AUX")
		)
		(pad "AN26" smd circle
			(at 2.035302 4.2291 180)
			(size 0.381 0.381)
			(layers "F.Cu" "F.Mask" "F.Paste")
			(net "TP_PCH_RSVD<15>")
		)
		(pad "AN29" smd circle
			(at 3.663188 4.2291 180)
			(size 0.381 0.381)
			(layers "F.Cu" "F.Mask" "F.Paste")
			(net "GND")
		)
		(pad "AN32" smd circle
			(at 5.291582 4.2291 180)
			(size 0.381 0.381)
			(layers "F.Cu" "F.Mask" "F.Paste")
			(net "GND")
		)
		(pad "AN36" smd circle
			(at 6.919722 4.2291 180)
			(size 0.381 0.381)
			(layers "F.Cu" "F.Mask" "F.Paste")
			(net "P3E_PCH_M2_TX_DN<1>")
		)
		(pad "AN40" smd circle
			(at 9.069832 4.002024 180)
			(size 0.3048 0.3048)
			(layers "F.Cu" "F.Mask" "F.Paste")
			(net "USB2_3_DP")
		)
		(pad "AN42" smd circle
			(at 9.899904 4.002024 180)
			(size 0.3048 0.3048)
			(layers "F.Cu" "F.Mask" "F.Paste")
			(net "USB2_3_DN")
		)
		(pad "AP1" smd oval
			(at -10.31494 4.50215 270)
			(size 0.254 0.3302)
			(layers "F.Cu" "F.Mask" "F.Paste")
			(net "SMB_SML1_PMBUS_3V3AUX_PCH_SCL_1")
		)
		(pad "AP3" smd circle
			(at -9.484868 4.50215 180)
			(size 0.3048 0.3048)
			(layers "F.Cu" "F.Mask" "F.Paste")
			(net "PD_PCH_GPPC_C10")
		)
		(pad "AP5" smd circle
			(at -8.654796 4.50215 180)
			(size 0.3048 0.3048)
			(layers "F.Cu" "F.Mask" "F.Paste")
			(net "GND")
		)
		(pad "AP8" smd circle
			(at -6.919722 4.699 180)
			(size 0.381 0.381)
			(layers "F.Cu" "F.Mask" "F.Paste")
			(net "FM_PCH_SLP_S3_N")
		)
		(pad "AP11" smd circle
			(at -5.291582 4.699 180)
			(size 0.381 0.381)
			(layers "F.Cu" "F.Mask" "F.Paste")
			(net "GND")
		)
		(pad "AP15" smd circle
			(at -3.663188 4.699 180)
			(size 0.381 0.381)
			(layers "F.Cu" "F.Mask" "F.Paste")
			(net "IRQ_PCH_CPU_NMI_EVENT_R_N")
		)
		(pad "AP18" smd circle
			(at -2.035302 4.699 180)
			(size 0.381 0.381)
			(layers "F.Cu" "F.Mask" "F.Paste")
			(net "GND")
		)
		(pad "AP21" smd circle
			(at -0.406908 4.699 180)
			(size 0.381 0.381)
			(layers "F.Cu" "F.Mask" "F.Paste")
			(net "P1V05_PCH_AUX")
		)
		(pad "AP24" smd circle
			(at 1.220978 4.699 180)
			(size 0.381 0.381)
			(layers "F.Cu" "F.Mask" "F.Paste")
			(net "GND")
		)
		(pad "AP28" smd circle
			(at 2.849118 4.699 180)
			(size 0.381 0.381)
			(layers "F.Cu" "F.Mask" "F.Paste")
			(net "GND")
		)
		(pad "AP31" smd circle
			(at 4.477512 4.699 180)
			(size 0.381 0.381)
			(layers "F.Cu" "F.Mask" "F.Paste")
			(net "PCH_PCIEUP_RCOMPN")
		)
		(pad "AP34" smd circle
			(at 6.105398 4.699 180)
			(size 0.381 0.381)
			(layers "F.Cu" "F.Mask" "F.Paste")
			(net "P3E_PCH_M2_TX_DP<1>")
		)
		(pad "AP37" smd circle
			(at 7.733792 4.699 180)
			(size 0.381 0.381)
			(layers "F.Cu" "F.Mask" "F.Paste")
			(net "GND")
		)
		(pad "AP39" smd circle
			(at 8.654796 4.50215 180)
			(size 0.3048 0.3048)
			(layers "F.Cu" "F.Mask" "F.Paste")
			(net "GND")
		)
		(pad "AP41" smd circle
			(at 9.484868 4.50215 180)
			(size 0.3048 0.3048)
			(layers "F.Cu" "F.Mask" "F.Paste")
			(net "TP_USB2_1_DP")
		)
		(pad "AP43" smd oval
			(at 10.31494 4.50215 270)
			(size 0.254 0.3302)
			(layers "F.Cu" "F.Mask" "F.Paste")
			(net "TP_USB2_1_DN")
		)
		(pad "AR2" smd circle
			(at -9.899904 5.002276 180)
			(size 0.3048 0.3048)
			(layers "F.Cu" "F.Mask" "F.Paste")
			(net "PD_PCH_GPPC_C9")
		)
		(pad "AR4" smd circle
			(at -9.069832 5.002276 180)
			(size 0.3048 0.3048)
			(layers "F.Cu" "F.Mask" "F.Paste")
			(net "IRQ_SML1_PMBUS_ALERT_N")
		)
		(pad "AR7" smd circle
			(at -7.733792 5.1689 180)
			(size 0.381 0.381)
			(layers "F.Cu" "F.Mask" "F.Paste")
			(net "PD_SUSCLK")
		)
		(pad "AR10" smd circle
			(at -6.105398 5.1689 180)
			(size 0.381 0.381)
			(layers "F.Cu" "F.Mask" "F.Paste")
			(net "FM_BMC_PWRBTN_N")
		)
		(pad "AR13" smd circle
			(at -4.477512 5.1689 180)
			(size 0.381 0.381)
			(layers "F.Cu" "F.Mask" "F.Paste")
			(net "FM_EUP_LOT6_N")
		)
		(pad "AR16" smd circle
			(at -2.849118 5.1689 180)
			(size 0.381 0.381)
			(layers "F.Cu" "F.Mask" "F.Paste")
			(net "FM_XTAL_INPUT_FREQUENCY_1_MGPIO")
		)
		(pad "AR20" smd circle
			(at -1.220978 5.1689 180)
			(size 0.381 0.381)
			(layers "F.Cu" "F.Mask" "F.Paste")
			(net "GND")
		)
		(pad "AR23" smd circle
			(at 0.406908 5.1689 180)
			(size 0.381 0.381)
			(layers "F.Cu" "F.Mask" "F.Paste")
			(net "P1V05_PCH_AUX")
		)
		(pad "AR26" smd circle
			(at 2.035302 5.1689 180)
			(size 0.381 0.381)
			(layers "F.Cu" "F.Mask" "F.Paste")
			(net "P1V05_PCH_AUX")
		)
		(pad "AR29" smd circle
			(at 3.663188 5.1689 180)
			(size 0.381 0.381)
			(layers "F.Cu" "F.Mask" "F.Paste")
			(net "PCH_PCIEUP_RCOMPP")
		)
		(pad "AR32" smd circle
			(at 5.291582 5.1689 180)
			(size 0.381 0.381)
			(layers "F.Cu" "F.Mask" "F.Paste")
			(net "GND")
		)
		(pad "AR36" smd circle
			(at 6.919722 5.1689 180)
			(size 0.381 0.381)
			(layers "F.Cu" "F.Mask" "F.Paste")
			(net "P3E_PCH_M2_TX_DN<2>")
		)
		(pad "AR40" smd circle
			(at 9.069832 5.002276 180)
			(size 0.3048 0.3048)
			(layers "F.Cu" "F.Mask" "F.Paste")
			(net "USB2_0_DP")
		)
		(pad "AR42" smd circle
			(at 9.899904 5.002276 180)
			(size 0.3048 0.3048)
			(layers "F.Cu" "F.Mask" "F.Paste")
			(net "USB2_0_DN")
		)
		(pad "AT1" smd oval
			(at -10.31494 5.502656 270)
			(size 0.254 0.3302)
			(layers "F.Cu" "F.Mask" "F.Paste")
			(net "PU_SMB_PCH_PLD_3V3AUX_SDA")
		)
		(pad "AT3" smd circle
			(at -9.484868 5.502656 180)
			(size 0.3048 0.3048)
			(layers "F.Cu" "F.Mask" "F.Paste")
			(net "PD_PCH_GPPC_C5")
		)
		(pad "AT5" smd circle
			(at -8.654796 5.502656 180)
			(size 0.3048 0.3048)
			(layers "F.Cu" "F.Mask" "F.Paste")
			(net "GND")
		)
		(pad "AT8" smd circle
			(at -6.919722 5.6388 180)
			(size 0.381 0.381)
			(layers "F.Cu" "F.Mask" "F.Paste")
			(net "GND")
		)
		(pad "AT11" smd circle
			(at -5.291582 5.6388 180)
			(size 0.381 0.381)
			(layers "F.Cu" "F.Mask" "F.Paste")
			(net "GND")
		)
		(pad "AT15" smd circle
			(at -3.663188 5.6388 180)
			(size 0.381 0.381)
			(layers "F.Cu" "F.Mask" "F.Paste")
			(net "GND")
		)
		(pad "AT18" smd circle
			(at -2.035302 5.6388 180)
			(size 0.381 0.381)
			(layers "F.Cu" "F.Mask" "F.Paste")
			(net "FM_PCH_CONSENT_STRAP_N")
		)
		(pad "AT21" smd circle
			(at -0.406908 5.6388 180)
			(size 0.381 0.381)
			(layers "F.Cu" "F.Mask" "F.Paste")
			(net "GND")
		)
		(pad "AT24" smd circle
			(at 1.220978 5.6388 180)
			(size 0.381 0.381)
			(layers "F.Cu" "F.Mask" "F.Paste")
			(net "GND")
		)
		(pad "AT28" smd circle
			(at 2.849118 5.6388 180)
			(size 0.381 0.381)
			(layers "F.Cu" "F.Mask" "F.Paste")
			(net "GND")
		)
		(pad "AT31" smd circle
			(at 4.477512 5.6388 180)
			(size 0.381 0.381)
			(layers "F.Cu" "F.Mask" "F.Paste")
			(net "GND")
		)
		(pad "AT34" smd circle
			(at 6.105398 5.6388 180)
			(size 0.381 0.381)
			(layers "F.Cu" "F.Mask" "F.Paste")
			(net "GND")
		)
		(pad "AT37" smd circle
			(at 7.733792 5.6388 180)
			(size 0.381 0.381)
			(layers "F.Cu" "F.Mask" "F.Paste")
			(net "P3E_PCH_M2_TX_DP<2>")
		)
		(pad "AT39" smd circle
			(at 8.654796 5.502656 180)
			(size 0.3048 0.3048)
			(layers "F.Cu" "F.Mask" "F.Paste")
			(net "GND")
		)
		(pad "AT41" smd circle
			(at 9.484868 5.502656 180)
			(size 0.3048 0.3048)
			(layers "F.Cu" "F.Mask" "F.Paste")
			(net "TP_USB2_2_DP")
		)
		(pad "AT43" smd oval
			(at 10.31494 5.502656 270)
			(size 0.254 0.3302)
			(layers "F.Cu" "F.Mask" "F.Paste")
			(net "TP_USB2_2_DN")
		)
		(pad "AU2" smd circle
			(at -9.899904 6.002782 180)
			(size 0.3048 0.3048)
			(layers "F.Cu" "F.Mask" "F.Paste")
			(net "IRQ_SML0_ALERT_N")
		)
		(pad "AU4" smd circle
			(at -9.069832 6.002782 180)
			(size 0.3048 0.3048)
			(layers "F.Cu" "F.Mask" "F.Paste")
			(net "SMB_SML0B_3V3AUX_SDA")
		)
		(pad "AU7" smd circle
			(at -7.733792 6.1087 180)
			(size 0.381 0.381)
			(layers "F.Cu" "F.Mask" "F.Paste")
			(net "PU_LAN_WAKE_N")
		)
		(pad "AU10" smd circle
			(at -6.105398 6.1087 180)
			(size 0.381 0.381)
			(layers "F.Cu" "F.Mask" "F.Paste")
			(net "FM_PCH_SKIP_RTC_CLOCK")
		)
		(pad "AU13" smd circle
			(at -4.477512 6.1087 180)
			(size 0.381 0.381)
			(layers "F.Cu" "F.Mask" "F.Paste")
			(net "FM_SPI_3V3_1V8_VOLTAGE")
		)
		(pad "AU16" smd circle
			(at -2.849118 6.1087 180)
			(size 0.381 0.381)
			(layers "F.Cu" "F.Mask" "F.Paste")
			(net "FM_PCH_SPKR")
		)
		(pad "AU20" smd circle
			(at -1.220978 6.1087 180)
			(size 0.381 0.381)
			(layers "F.Cu" "F.Mask" "F.Paste")
			(net "GND")
		)
		(pad "AU23" smd circle
			(at 0.406908 6.1087 180)
			(size 0.381 0.381)
			(layers "F.Cu" "F.Mask" "F.Paste")
			(net "GND")
		)
		(pad "AU26" smd circle
			(at 2.035302 6.1087 180)
			(size 0.381 0.381)
			(layers "F.Cu" "F.Mask" "F.Paste")
			(net "GND")
		)
		(pad "AU29" smd circle
			(at 3.663188 6.1087 180)
			(size 0.381 0.381)
			(layers "F.Cu" "F.Mask" "F.Paste")
			(net "GND")
		)
		(pad "AU32" smd circle
			(at 5.291582 6.1087 180)
			(size 0.381 0.381)
			(layers "F.Cu" "F.Mask" "F.Paste")
			(net "GND")
		)
		(pad "AU36" smd circle
			(at 6.919722 6.1087 180)
			(size 0.381 0.381)
			(layers "F.Cu" "F.Mask" "F.Paste")
			(net "GND")
		)
		(pad "AU40" smd circle
			(at 9.069832 6.002782 180)
			(size 0.3048 0.3048)
			(layers "F.Cu" "F.Mask" "F.Paste")
			(net "TP_USB2_4_DP")
		)
		(pad "AU42" smd circle
			(at 9.899904 6.002782 180)
			(size 0.3048 0.3048)
			(layers "F.Cu" "F.Mask" "F.Paste")
			(net "TP_USB2_4_DN")
		)
		(pad "AV1" smd oval
			(at -10.31494 6.503162 270)
			(size 0.254 0.3302)
			(layers "F.Cu" "F.Mask" "F.Paste")
			(net "PU_SMB_SML4_3V3AUX_PCH_SDA")
		)
		(pad "AV3" smd circle
			(at -9.484868 6.503162 180)
			(size 0.3048 0.3048)
			(layers "F.Cu" "F.Mask" "F.Paste")
			(net "FM_PMBUS_ALERT_B_EN")
		)
		(pad "AV5" smd circle
			(at -8.654796 6.503162 180)
			(size 0.3048 0.3048)
			(layers "F.Cu" "F.Mask" "F.Paste")
			(net "GND")
		)
		(pad "AV8" smd circle
			(at -6.919722 6.5786 180)
			(size 0.381 0.381)
			(layers "F.Cu" "F.Mask" "F.Paste")
			(net "GND")
		)
		(pad "AV11" smd circle
			(at -5.291582 6.5786 180)
			(size 0.381 0.381)
			(layers "F.Cu" "F.Mask" "F.Paste")
			(net "FM_ADR_MODE0")
		)
		(pad "AV15" smd circle
			(at -3.663188 6.5786 180)
			(size 0.381 0.381)
			(layers "F.Cu" "F.Mask" "F.Paste")
			(net "SPI_PCH_IO2")
		)
		(pad "AV18" smd circle
			(at -2.035302 6.5786 180)
			(size 0.381 0.381)
			(layers "F.Cu" "F.Mask" "F.Paste")
			(net "IRQ_SMI_ACTIVE_N")
		)
		(pad "AV21" smd circle
			(at -0.406908 6.5786 180)
			(size 0.381 0.381)
			(layers "F.Cu" "F.Mask" "F.Paste")
			(net "NC_PCH_RSVD<4>")
		)
		(pad "AV24" smd circle
			(at 1.220978 6.5786 180)
			(size 0.381 0.381)
			(layers "F.Cu" "F.Mask" "F.Paste")
			(net "TP_EDSFF1A_TYPE_ID")
		)
		(pad "AV28" smd circle
			(at 2.849118 6.5786 180)
			(size 0.381 0.381)
			(layers "F.Cu" "F.Mask" "F.Paste")
			(net "TP_EDSFF1B_TYPE_ID")
		)
		(pad "AV31" smd circle
			(at 4.477512 6.5786 180)
			(size 0.381 0.381)
			(layers "F.Cu" "F.Mask" "F.Paste")
			(net "PD_PCH_GPP_E_10")
		)
		(pad "AV34" smd circle
			(at 6.105398 6.5786 180)
			(size 0.381 0.381)
			(layers "F.Cu" "F.Mask" "F.Paste")
			(net "PD_PCH_GPP_E_11")
		)
		(pad "AV37" smd circle
			(at 7.733792 6.5786 180)
			(size 0.381 0.381)
			(layers "F.Cu" "F.Mask" "F.Paste")
			(net "GND")
		)
		(pad "AV39" smd circle
			(at 8.654796 6.503162 180)
			(size 0.3048 0.3048)
			(layers "F.Cu" "F.Mask" "F.Paste")
			(net "GND")
		)
		(pad "AV41" smd circle
			(at 9.484868 6.503162 180)
			(size 0.3048 0.3048)
			(layers "F.Cu" "F.Mask" "F.Paste")
			(net "TP_USB2_6_DP")
		)
		(pad "AV43" smd oval
			(at 10.31494 6.503162 270)
			(size 0.254 0.3302)
			(layers "F.Cu" "F.Mask" "F.Paste")
			(net "TP_USB2_6_DN")
		)
		(pad "AW2" smd circle
			(at -9.899904 7.003288 180)
			(size 0.3048 0.3048)
			(layers "F.Cu" "F.Mask" "F.Paste")
			(net "FM_THROTTLE_N")
		)
		(pad "AW4" smd circle
			(at -9.069832 7.003288 180)
			(size 0.3048 0.3048)
			(layers "F.Cu" "F.Mask" "F.Paste")
			(net "SMB_SML1_PMBUS_3V3AUX_PCH_SDA_1")
		)
		(pad "AW7" smd circle
			(at -7.733792 7.0485 180)
			(size 0.381 0.381)
			(layers "F.Cu" "F.Mask" "F.Paste")
			(net "GND")
		)
		(pad "AW10" smd circle
			(at -6.105398 7.0485 180)
			(size 0.381 0.381)
			(layers "F.Cu" "F.Mask" "F.Paste")
			(net "FM_JTAG_ODT_DISABLE")
		)
		(pad "AW13" smd circle
			(at -4.477512 7.0485 180)
			(size 0.381 0.381)
			(layers "F.Cu" "F.Mask" "F.Paste")
			(net "SPI_PCH_CS0_R_N")
		)
		(pad "AW16" smd circle
			(at -2.849118 7.0485 180)
			(size 0.381 0.381)
			(layers "F.Cu" "F.Mask" "F.Paste")
			(net "SPI_PCH_IO1")
		)
		(pad "AW20" smd circle
			(at -1.220978 7.0485 180)
			(size 0.381 0.381)
			(layers "F.Cu" "F.Mask" "F.Paste")
			(net "FM_ME_AUTHN_FAIL")
		)
		(pad "AW23" smd circle
			(at 0.406908 7.0485 180)
			(size 0.381 0.381)
			(layers "F.Cu" "F.Mask" "F.Paste")
			(net "TP_PCH_GPP_E_2")
		)
		(pad "AW26" smd circle
			(at 2.035302 7.0485 180)
			(size 0.381 0.381)
			(layers "F.Cu" "F.Mask" "F.Paste")
			(net "NC_PCH_RSVD<3>")
		)
		(pad "AW29" smd circle
			(at 3.663188 7.0485 180)
			(size 0.381 0.381)
			(layers "F.Cu" "F.Mask" "F.Paste")
			(net "FM_ME_BT_DONE")
		)
		(pad "AW32" smd circle
			(at 5.291582 7.0485 180)
			(size 0.381 0.381)
			(layers "F.Cu" "F.Mask" "F.Paste")
			(net "FM_M2_SSD0_E7_PEDET")
		)
		(pad "AW36" smd circle
			(at 6.919722 7.0485 180)
			(size 0.381 0.381)
			(layers "F.Cu" "F.Mask" "F.Paste")
			(net "PD_PCH_GPP_E_8")
		)
		(pad "AW40" smd circle
			(at 9.069832 7.003288 180)
			(size 0.3048 0.3048)
			(layers "F.Cu" "F.Mask" "F.Paste")
			(net "USB2_8_DP")
		)
		(pad "AW42" smd circle
			(at 9.899904 7.003288 180)
			(size 0.3048 0.3048)
			(layers "F.Cu" "F.Mask" "F.Paste")
			(net "USB2_8_DN")
		)
		(pad "AY1" smd oval
			(at -10.31494 7.503668 270)
			(size 0.254 0.3302)
			(layers "F.Cu" "F.Mask" "F.Paste")
			(net "PU_SMB_SML3_3V3AUX_PCH_SDA")
		)
		(pad "AY3" smd circle
			(at -9.484868 7.503668 180)
			(size 0.3048 0.3048)
			(layers "F.Cu" "F.Mask" "F.Paste")
			(net "GND")
		)
		(pad "AY5" smd circle
			(at -8.654796 7.503668 180)
			(size 0.3048 0.3048)
			(layers "F.Cu" "F.Mask" "F.Paste")
			(net "GND")
		)
		(pad "AY8" smd circle
			(at -6.919722 7.5184 180)
			(size 0.381 0.381)
			(layers "F.Cu" "F.Mask" "F.Paste")
			(net "GND")
		)
		(pad "AY11" smd circle
			(at -5.291582 7.5184 180)
			(size 0.381 0.381)
			(layers "F.Cu" "F.Mask" "F.Paste")
			(net "GND")
		)
		(pad "AY15" smd circle
			(at -3.663188 7.5184 180)
			(size 0.381 0.381)
			(layers "F.Cu" "F.Mask" "F.Paste")
			(net "GND")
		)
		(pad "AY18" smd circle
			(at -2.035302 7.5184 180)
			(size 0.381 0.381)
			(layers "F.Cu" "F.Mask" "F.Paste")
			(net "GND")
		)
		(pad "AY21" smd circle
			(at -0.406908 7.5184 180)
			(size 0.381 0.381)
			(layers "F.Cu" "F.Mask" "F.Paste")
			(net "GND")
		)
		(pad "AY24" smd circle
			(at 1.220978 7.5184 180)
			(size 0.381 0.381)
			(layers "F.Cu" "F.Mask" "F.Paste")
			(net "GND")
		)
		(pad "AY28" smd circle
			(at 2.849118 7.5184 180)
			(size 0.381 0.381)
			(layers "F.Cu" "F.Mask" "F.Paste")
			(net "GND")
		)
		(pad "AY31" smd circle
			(at 4.477512 7.5184 180)
			(size 0.381 0.381)
			(layers "F.Cu" "F.Mask" "F.Paste")
			(net "GND")
		)
		(pad "AY34" smd circle
			(at 6.105398 7.5184 180)
			(size 0.381 0.381)
			(layers "F.Cu" "F.Mask" "F.Paste")
			(net "GND")
		)
		(pad "AY37" smd circle
			(at 7.733792 7.5184 180)
			(size 0.381 0.381)
			(layers "F.Cu" "F.Mask" "F.Paste")
			(net "GND")
		)
		(pad "AY39" smd circle
			(at 8.654796 7.503668 180)
			(size 0.3048 0.3048)
			(layers "F.Cu" "F.Mask" "F.Paste")
			(net "GND")
		)
		(pad "AY41" smd circle
			(at 9.484868 7.503668 180)
			(size 0.3048 0.3048)
			(layers "F.Cu" "F.Mask" "F.Paste")
			(net "TP_USB2_10_DP")
		)
		(pad "AY43" smd oval
			(at 10.31494 7.503668 270)
			(size 0.254 0.3302)
			(layers "F.Cu" "F.Mask" "F.Paste")
			(net "TP_USB2_10_DN")
		)
		(pad "B5" smd circle
			(at -8.504174 -10.40003 180)
			(size 0.3048 0.3048)
			(layers "F.Cu" "F.Mask" "F.Paste")
			(net "TP_CLK_100M_PCH_15_DN")
		)
		(pad "B7" smd circle
			(at -7.503668 -10.40003 180)
			(size 0.3048 0.3048)
			(layers "F.Cu" "F.Mask" "F.Paste")
			(net "TP_CLK_100M_PCH_14_DN")
		)
		(pad "B9" smd circle
			(at -6.503162 -10.40003 180)
			(size 0.3048 0.3048)
			(layers "F.Cu" "F.Mask" "F.Paste")
			(net "GND")
		)
		(pad "B11" smd circle
			(at -5.502656 -10.40003 180)
			(size 0.3048 0.3048)
			(layers "F.Cu" "F.Mask" "F.Paste")
			(net "CLK_100M_BMC_P3E_DN")
		)
		(pad "B13" smd circle
			(at -4.50215 -10.40003 180)
			(size 0.3048 0.3048)
			(layers "F.Cu" "F.Mask" "F.Paste")
			(net "GND")
		)
		(pad "B15" smd circle
			(at -3.501644 -10.40003 180)
			(size 0.3048 0.3048)
			(layers "F.Cu" "F.Mask" "F.Paste")
			(net "TP_CLK_100M_PCH_9_DN")
		)
		(pad "B17" smd circle
			(at -2.501138 -10.40003 180)
			(size 0.3048 0.3048)
			(layers "F.Cu" "F.Mask" "F.Paste")
			(net "CLK_100M_E1S_0_R_DN")
		)
		(pad "B19" smd circle
			(at -1.500632 -10.40003 180)
			(size 0.3048 0.3048)
			(layers "F.Cu" "F.Mask" "F.Paste")
			(net "TP_CLK_100M_PCH_4_DN")
		)
		(pad "B21" smd circle
			(at -0.500126 -10.40003 180)
			(size 0.3048 0.3048)
			(layers "F.Cu" "F.Mask" "F.Paste")
			(net "CLK_100M_CK440_PCH_EXTCLK_DP")
		)
		(pad "B23" smd circle
			(at 0.500126 -10.40003 180)
			(size 0.3048 0.3048)
			(layers "F.Cu" "F.Mask" "F.Paste")
			(net "XTAL_PCH_25M_IN")
		)
		(pad "B25" smd circle
			(at 1.500632 -10.40003 180)
			(size 0.3048 0.3048)
			(layers "F.Cu" "F.Mask" "F.Paste")
			(net "CLK_25M_PCH_REF_NS_DP")
		)
		(pad "B27" smd circle
			(at 2.501138 -10.40003 180)
			(size 0.3048 0.3048)
			(layers "F.Cu" "F.Mask" "F.Paste")
			(net "CLK_25M_PCH_CPU0_DP")
		)
		(pad "B29" smd circle
			(at 3.501644 -10.40003 180)
			(size 0.3048 0.3048)
			(layers "F.Cu" "F.Mask" "F.Paste")
			(net "GND")
		)
		(pad "B31" smd circle
			(at 4.50215 -10.40003 180)
			(size 0.3048 0.3048)
			(layers "F.Cu" "F.Mask" "F.Paste")
			(net "DMI_CPU0_PCH_TX_C_DN<1>")
		)
		(pad "B33" smd circle
			(at 5.502656 -10.40003 180)
			(size 0.3048 0.3048)
			(layers "F.Cu" "F.Mask" "F.Paste")
			(net "DMI_CPU0_PCH_TX_C_DN<3>")
		)
		(pad "B35" smd circle
			(at 6.503162 -10.40003 180)
			(size 0.3048 0.3048)
			(layers "F.Cu" "F.Mask" "F.Paste")
			(net "DMI_CPU0_PCH_TX_C_DN<5>")
		)
		(pad "B37" smd circle
			(at 7.503668 -10.40003 180)
			(size 0.3048 0.3048)
			(layers "F.Cu" "F.Mask" "F.Paste")
			(net "DMI_CPU0_PCH_TX_C_DN<7>")
		)
		(pad "B39" smd circle
			(at 8.504174 -10.40003 180)
			(size 0.3048 0.3048)
			(layers "F.Cu" "F.Mask" "F.Paste")
			(net "GND")
		)
		(pad "BA2" smd circle
			(at -9.899904 8.003794 180)
			(size 0.3048 0.3048)
			(layers "F.Cu" "F.Mask" "F.Paste")
			(net "PU_SMB_SML4_3V3AUX_PCH_SCL")
		)
		(pad "BA4" smd circle
			(at -9.069832 8.003794 180)
			(size 0.3048 0.3048)
			(layers "F.Cu" "F.Mask" "F.Paste")
			(net "SMB_SML0_3V3AUX_PCH_SDA")
		)
		(pad "BA7" smd circle
			(at -7.733792 7.9883 180)
			(size 0.381 0.381)
			(layers "F.Cu" "F.Mask" "F.Paste")
			(net "FM_SUSACK_N")
		)
		(pad "BA10" smd circle
			(at -6.105398 7.9883 180)
			(size 0.381 0.381)
			(layers "F.Cu" "F.Mask" "F.Paste")
			(net "TP_SPI_PCH_CS1_R_N")
		)
		(pad "BA13" smd circle
			(at -4.477512 7.9883 180)
			(size 0.381 0.381)
			(layers "F.Cu" "F.Mask" "F.Paste")
			(net "SPI_PCH_IO0")
		)
		(pad "BA16" smd circle
			(at -2.849118 7.9883 180)
			(size 0.381 0.381)
			(layers "F.Cu" "F.Mask" "F.Paste")
			(net "SPI_PCH_IO3")
		)
		(pad "BA20" smd circle
			(at -1.220978 7.9883 180)
			(size 0.381 0.381)
			(layers "F.Cu" "F.Mask" "F.Paste")
			(net "FM_PS_PWROK_DLY_R_SEL")
		)
		(pad "BA23" smd circle
			(at 0.406908 7.9883 180)
			(size 0.381 0.381)
			(layers "F.Cu" "F.Mask" "F.Paste")
			(net "TP_PCH_GPP_E_1")
		)
		(pad "BA26" smd circle
			(at 2.035302 7.9883 180)
			(size 0.381 0.381)
			(layers "F.Cu" "F.Mask" "F.Paste")
			(net "TP_PCH_GPP_E_0")
		)
		(pad "BA29" smd circle
			(at 3.663188 7.9883 180)
			(size 0.381 0.381)
			(layers "F.Cu" "F.Mask" "F.Paste")
			(net "PD_PCH_GPP_E_9")
		)
		(pad "BA32" smd circle
			(at 5.291582 7.9883 180)
			(size 0.381 0.381)
			(layers "F.Cu" "F.Mask" "F.Paste")
			(net "PD_PCH_GPP_E_13")
		)
		(pad "BA36" smd circle
			(at 6.919722 7.9883 180)
			(size 0.381 0.381)
			(layers "F.Cu" "F.Mask" "F.Paste")
			(net "FM_DEBUG_PORT_PRSNT_R_N")
		)
		(pad "BA40" smd circle
			(at 9.069832 8.003794 180)
			(size 0.3048 0.3048)
			(layers "F.Cu" "F.Mask" "F.Paste")
			(net "TP_USB2_12_DP")
		)
		(pad "BA42" smd circle
			(at 9.899904 8.003794 180)
			(size 0.3048 0.3048)
			(layers "F.Cu" "F.Mask" "F.Paste")
			(net "TP_USB2_12_DN")
		)
		(pad "BB1" smd circle
			(at -10.31494 8.504174 180)
			(size 0.3048 0.3048)
			(layers "F.Cu" "F.Mask" "F.Paste")
			(net "GND")
		)
		(pad "BB3" smd circle
			(at -9.484868 8.504174 180)
			(size 0.3048 0.3048)
			(layers "F.Cu" "F.Mask" "F.Paste")
			(net "SMB_SML0B_3V3AUX_SCL")
		)
		(pad "BB5" smd circle
			(at -8.654796 8.504174 180)
			(size 0.3048 0.3048)
			(layers "F.Cu" "F.Mask" "F.Paste")
			(net "GND")
		)
		(pad "BB8" smd circle
			(at -6.919722 8.4582 180)
			(size 0.381 0.381)
			(layers "F.Cu" "F.Mask" "F.Paste")
			(net "FM_ESPI_CS_SWIZZLE")
		)
		(pad "BB11" smd circle
			(at -5.291582 8.4582 180)
			(size 0.381 0.381)
			(layers "F.Cu" "F.Mask" "F.Paste")
			(net "SPI_PCH_TPM_CS_N")
		)
		(pad "BB15" smd circle
			(at -3.663188 8.4582 180)
			(size 0.381 0.381)
			(layers "F.Cu" "F.Mask" "F.Paste")
			(net "SPI_PCH_CLK")
		)
		(pad "BB18" smd circle
			(at -2.035302 8.4582 180)
			(size 0.381 0.381)
			(layers "F.Cu" "F.Mask" "F.Paste")
			(net "FM_XTAL_INPUT_FREQUENCY_0_MGPIO")
		)
		(pad "BB21" smd circle
			(at -0.406908 8.4582 180)
			(size 0.381 0.381)
			(layers "F.Cu" "F.Mask" "F.Paste")
			(net "PD_PCH_GPP_E_3")
		)
		(pad "BB24" smd circle
			(at 1.220978 8.4582 180)
			(size 0.381 0.381)
			(layers "F.Cu" "F.Mask" "F.Paste")
			(net "FM_M2_E1S_E6_PEDET")
		)
		(pad "BB28" smd circle
			(at 2.849118 8.4582 180)
			(size 0.381 0.381)
			(layers "F.Cu" "F.Mask" "F.Paste")
			(net "PD_PCH_GPP_E_12")
		)
		(pad "BB31" smd circle
			(at 4.477512 8.4582 180)
			(size 0.381 0.381)
			(layers "F.Cu" "F.Mask" "F.Paste")
			(net "FM_TPM_PRSNT_N")
		)
		(pad "BB34" smd circle
			(at 6.105398 8.4582 180)
			(size 0.381 0.381)
			(layers "F.Cu" "F.Mask" "F.Paste")
			(net "PD_PCH_GPP_E_14")
		)
		(pad "BB37" smd circle
			(at 7.733792 8.4582 180)
			(size 0.381 0.381)
			(layers "F.Cu" "F.Mask" "F.Paste")
			(net "H_DBP_PRDY_N_PCH")
		)
		(pad "BB39" smd circle
			(at 8.654796 8.504174 180)
			(size 0.3048 0.3048)
			(layers "F.Cu" "F.Mask" "F.Paste")
			(net "GND")
		)
		(pad "BB41" smd circle
			(at 9.484868 8.504174 180)
			(size 0.3048 0.3048)
			(layers "F.Cu" "F.Mask" "F.Paste")
			(net "PD_PCH_USB2_COMP")
		)
		(pad "BB43" smd circle
			(at 10.31494 8.504174 180)
			(size 0.4064 0.4064)
			(layers "F.Cu" "F.Mask" "F.Paste")
			(net "TP_PCH_RSVD<7>")
		)
		(pad "BC2" smd circle
			(at -9.899904 9.0043 180)
			(size 0.3048 0.3048)
			(layers "F.Cu" "F.Mask" "F.Paste")
			(net "GND")
		)
		(pad "BC4" smd circle
			(at -9.069832 9.0043 180)
			(size 0.3048 0.3048)
			(layers "F.Cu" "F.Mask" "F.Paste")
			(net "SMB_SML0_3V3AUX_PCH_SCL")
		)
		(pad "BC6" smd circle
			(at -8.003794 9.154922 180)
			(size 0.3048 0.3048)
			(layers "F.Cu" "F.Mask" "F.Paste")
			(net "GND")
		)
		(pad "BC8" smd circle
			(at -7.003288 9.154922 180)
			(size 0.3048 0.3048)
			(layers "F.Cu" "F.Mask" "F.Paste")
			(net "GND")
		)
		(pad "BC10" smd circle
			(at -6.002782 9.154922 180)
			(size 0.3048 0.3048)
			(layers "F.Cu" "F.Mask" "F.Paste")
			(net "GND")
		)
		(pad "BC12" smd circle
			(at -5.002276 9.154922 180)
			(size 0.3048 0.3048)
			(layers "F.Cu" "F.Mask" "F.Paste")
			(net "GND")
		)
		(pad "BC14" smd circle
			(at -4.002024 9.154922 180)
			(size 0.3048 0.3048)
			(layers "F.Cu" "F.Mask" "F.Paste")
			(net "GND")
		)
		(pad "BC16" smd circle
			(at -3.001518 9.154922 180)
			(size 0.3048 0.3048)
			(layers "F.Cu" "F.Mask" "F.Paste")
			(net "GND")
		)
		(pad "BC18" smd circle
			(at -2.001012 9.154922 180)
			(size 0.3048 0.3048)
			(layers "F.Cu" "F.Mask" "F.Paste")
			(net "GND")
		)
		(pad "BC20" smd circle
			(at -1.000506 9.154922 180)
			(size 0.3048 0.3048)
			(layers "F.Cu" "F.Mask" "F.Paste")
			(net "GND")
		)
		(pad "BC22" smd circle
			(at 0 9.154922 180)
			(size 0.3048 0.3048)
			(layers "F.Cu" "F.Mask" "F.Paste")
			(net "GND")
		)
		(pad "BC24" smd circle
			(at 1.000506 9.154922 180)
			(size 0.3048 0.3048)
			(layers "F.Cu" "F.Mask" "F.Paste")
			(net "GND")
		)
		(pad "BC26" smd circle
			(at 2.001012 9.154922 180)
			(size 0.3048 0.3048)
			(layers "F.Cu" "F.Mask" "F.Paste")
			(net "GND")
		)
		(pad "BC28" smd circle
			(at 3.001518 9.154922 180)
			(size 0.3048 0.3048)
			(layers "F.Cu" "F.Mask" "F.Paste")
			(net "GND")
		)
		(pad "BC30" smd circle
			(at 4.002024 9.154922 180)
			(size 0.3048 0.3048)
			(layers "F.Cu" "F.Mask" "F.Paste")
			(net "GND")
		)
		(pad "BC32" smd circle
			(at 5.002276 9.154922 180)
			(size 0.3048 0.3048)
			(layers "F.Cu" "F.Mask" "F.Paste")
			(net "GND")
		)
		(pad "BC34" smd circle
			(at 6.002782 9.154922 180)
			(size 0.3048 0.3048)
			(layers "F.Cu" "F.Mask" "F.Paste")
			(net "GND")
		)
		(pad "BC36" smd circle
			(at 7.003288 9.154922 180)
			(size 0.3048 0.3048)
			(layers "F.Cu" "F.Mask" "F.Paste")
			(net "GND")
		)
		(pad "BC38" smd circle
			(at 8.003794 9.154922 180)
			(size 0.3048 0.3048)
			(layers "F.Cu" "F.Mask" "F.Paste")
			(net "GND")
		)
		(pad "BC40" smd circle
			(at 9.069832 9.0043 180)
			(size 0.3048 0.3048)
			(layers "F.Cu" "F.Mask" "F.Paste")
			(net "NC_PCH_RSVD<14>")
		)
		(pad "BC42" smd circle
			(at 9.899904 9.0043 180)
			(size 0.3048 0.3048)
			(layers "F.Cu" "F.Mask" "F.Paste")
			(net "GND")
		)
		(pad "BD1" smd circle
			(at -10.31494 9.50468 180)
			(size 0.4064 0.4064)
			(layers "F.Cu" "F.Mask" "F.Paste")
			(net "GND")
		)
		(pad "BD3" smd circle
			(at -9.484868 9.50468 180)
			(size 0.3048 0.3048)
			(layers "F.Cu" "F.Mask" "F.Paste")
			(net "GND")
		)
		(pad "BD5" smd circle
			(at -8.504174 9.569958 180)
			(size 0.3048 0.3048)
			(layers "F.Cu" "F.Mask" "F.Paste")
			(net "GND")
		)
		(pad "BD7" smd circle
			(at -7.503668 9.569958 180)
			(size 0.3048 0.3048)
			(layers "F.Cu" "F.Mask" "F.Paste")
			(net "RST_RTCRST_N")
		)
		(pad "BD9" smd circle
			(at -6.503162 9.569958 180)
			(size 0.3048 0.3048)
			(layers "F.Cu" "F.Mask" "F.Paste")
			(net "RST_RSMRST_PCH_N")
		)
		(pad "BD11" smd circle
			(at -5.502656 9.569958 180)
			(size 0.3048 0.3048)
			(layers "F.Cu" "F.Mask" "F.Paste")
			(net "FM_PCH_SATA_RAID_KEY")
		)
		(pad "BD13" smd circle
			(at -4.50215 9.569958 180)
			(size 0.3048 0.3048)
			(layers "F.Cu" "F.Mask" "F.Paste")
			(net "CLK_24M_66M_LPC0_ESPI")
		)
		(pad "BD15" smd circle
			(at -3.501644 9.569958 180)
			(size 0.3048 0.3048)
			(layers "F.Cu" "F.Mask" "F.Paste")
			(net "ESPI_ALERT1_N_LPC_RCIN_N")
		)
		(pad "BD17" smd circle
			(at -2.501138 9.569958 180)
			(size 0.3048 0.3048)
			(layers "F.Cu" "F.Mask" "F.Paste")
			(net "PD_PCH_GPPC_A_10")
		)
		(pad "BD19" smd circle
			(at -1.500632 9.569958 180)
			(size 0.3048 0.3048)
			(layers "F.Cu" "F.Mask" "F.Paste")
			(net "ESPI_LAD0_DATA_IO3")
		)
		(pad "BD21" smd circle
			(at -0.500126 9.569958 180)
			(size 0.3048 0.3048)
			(layers "F.Cu" "F.Mask" "F.Paste")
			(net "GND")
		)
		(pad "BD23" smd circle
			(at 0.500126 9.569958 180)
			(size 0.3048 0.3048)
			(layers "F.Cu" "F.Mask" "F.Paste")
			(net "JTAG_TRC_PCH_PTI1_CLK")
		)
		(pad "BD25" smd circle
			(at 1.500632 9.569958 180)
			(size 0.3048 0.3048)
			(layers "F.Cu" "F.Mask" "F.Paste")
			(net "JTAG_TRC_PCH_PTI<11>")
		)
		(pad "BD27" smd circle
			(at 2.501138 9.569958 180)
			(size 0.3048 0.3048)
			(layers "F.Cu" "F.Mask" "F.Paste")
			(net "JTAG_TRC_PCH_PTI<8>")
		)
		(pad "BD29" smd circle
			(at 3.501644 9.569958 180)
			(size 0.3048 0.3048)
			(layers "F.Cu" "F.Mask" "F.Paste")
			(net "JTAG_TRC_PCH_PTI<5>")
		)
		(pad "BD31" smd circle
			(at 4.50215 9.569958 180)
			(size 0.3048 0.3048)
			(layers "F.Cu" "F.Mask" "F.Paste")
			(net "JTAG_TRC_PCH_PTI<2>")
		)
		(pad "BD33" smd circle
			(at 5.502656 9.569958 180)
			(size 0.3048 0.3048)
			(layers "F.Cu" "F.Mask" "F.Paste")
			(net "JTAG_TRC_PCH_PTI0_CLK")
		)
		(pad "BD35" smd circle
			(at 6.503162 9.569958 180)
			(size 0.3048 0.3048)
			(layers "F.Cu" "F.Mask" "F.Paste")
			(net "JTAG_DBP_CPU_GTL_TCK")
		)
		(pad "BD37" smd circle
			(at 7.503668 9.569958 180)
			(size 0.3048 0.3048)
			(layers "F.Cu" "F.Mask" "F.Paste")
			(net "JTAG_DBP_TMS_PCH")
		)
		(pad "BD39" smd circle
			(at 8.504174 9.569958 180)
			(size 0.3048 0.3048)
			(layers "F.Cu" "F.Mask" "F.Paste")
			(net "GND")
		)
		(pad "BD41" smd circle
			(at 9.484868 9.50468 180)
			(size 0.3048 0.3048)
			(layers "F.Cu" "F.Mask" "F.Paste")
			(net "GND")
		)
		(pad "BD43" smd circle
			(at 10.31494 9.50468 180)
			(size 0.4064 0.4064)
			(layers "F.Cu" "F.Mask" "F.Paste")
			(net "GND")
		)
		(pad "BE1" smd circle
			(at -10.31494 10.159746 180)
			(size 0.4064 0.4064)
			(layers "F.Cu" "F.Mask" "F.Paste")
			(net "GND")
		)
		(pad "BE3" smd circle
			(at -9.65962 10.159746 180)
			(size 0.3048 0.3048)
			(layers "F.Cu" "F.Mask" "F.Paste")
			(net "GND")
		)
		(pad "BE4" smd circle
			(at -9.0043 9.984994 180)
			(size 0.3048 0.3048)
			(layers "F.Cu" "F.Mask" "F.Paste")
			(net "PWRGD_PCH_PWROK")
		)
		(pad "BE6" smd circle
			(at -8.003794 9.984994 180)
			(size 0.3048 0.3048)
			(layers "F.Cu" "F.Mask" "F.Paste")
			(net "XTAL_PCH_RTC1")
		)
		(pad "BE8" smd circle
			(at -7.003288 9.984994 180)
			(size 0.3048 0.3048)
			(layers "F.Cu" "F.Mask" "F.Paste")
			(net "PWRGD_DSW_PWROK")
		)
		(pad "BE10" smd circle
			(at -6.002782 9.984994 180)
			(size 0.3048 0.3048)
			(layers "F.Cu" "F.Mask" "F.Paste")
			(net "GND")
		)
		(pad "BE12" smd circle
			(at -5.002276 9.984994 180)
			(size 0.3048 0.3048)
			(layers "F.Cu" "F.Mask" "F.Paste")
			(net "PD_PCH_GPPC_A_14")
		)
		(pad "BE14" smd circle
			(at -4.002024 9.984994 180)
			(size 0.3048 0.3048)
			(layers "F.Cu" "F.Mask" "F.Paste")
			(net "PD_PCH_GPPC_A_15")
		)
		(pad "BE16" smd circle
			(at -3.001518 9.984994 180)
			(size 0.3048 0.3048)
			(layers "F.Cu" "F.Mask" "F.Paste")
			(net "IRQ_LPC_SERIRQ_ESPI_CS1_N")
		)
		(pad "BE18" smd circle
			(at -2.001012 9.984994 180)
			(size 0.3048 0.3048)
			(layers "F.Cu" "F.Mask" "F.Paste")
			(net "ESPI_LAD0_DATA_IO2")
		)
		(pad "BE20" smd circle
			(at -1.000506 9.984994 180)
			(size 0.3048 0.3048)
			(layers "F.Cu" "F.Mask" "F.Paste")
			(net "ESPI_LFRAME_N_BMC_CS0_N")
		)
		(pad "BE22" smd circle
			(at 0 9.984994 180)
			(size 0.3048 0.3048)
			(layers "F.Cu" "F.Mask" "F.Paste")
			(net "JTAG_TRC_PCH_PTI<15>")
		)
		(pad "BE24" smd circle
			(at 1.000506 9.984994 180)
			(size 0.3048 0.3048)
			(layers "F.Cu" "F.Mask" "F.Paste")
			(net "JTAG_TRC_PCH_PTI<13>")
		)
		(pad "BE26" smd circle
			(at 2.001012 9.984994 180)
			(size 0.3048 0.3048)
			(layers "F.Cu" "F.Mask" "F.Paste")
			(net "JTAG_TRC_PCH_PTI<9>")
		)
		(pad "BE28" smd circle
			(at 3.001518 9.984994 180)
			(size 0.3048 0.3048)
			(layers "F.Cu" "F.Mask" "F.Paste")
			(net "JTAG_TRC_PCH_PTI<6>")
		)
		(pad "BE30" smd circle
			(at 4.002024 9.984994 180)
			(size 0.3048 0.3048)
			(layers "F.Cu" "F.Mask" "F.Paste")
			(net "JTAG_TRC_PCH_PTI<3>")
		)
		(pad "BE32" smd circle
			(at 5.002276 9.984994 180)
			(size 0.3048 0.3048)
			(layers "F.Cu" "F.Mask" "F.Paste")
			(net "JTAG_TRC_PCH_PTI<0>")
		)
		(pad "BE34" smd circle
			(at 6.002782 9.984994 180)
			(size 0.3048 0.3048)
			(layers "F.Cu" "F.Mask" "F.Paste")
			(net "GND")
		)
		(pad "BE36" smd circle
			(at 7.003288 9.984994 180)
			(size 0.3048 0.3048)
			(layers "F.Cu" "F.Mask" "F.Paste")
			(net "JTAG_DBP_TDO_PCH")
		)
		(pad "BE38" smd circle
			(at 8.003794 9.984994 180)
			(size 0.3048 0.3048)
			(layers "F.Cu" "F.Mask" "F.Paste")
			(net "JTAG_DBP_TDI_PCH")
		)
		(pad "BE40" smd circle
			(at 9.0043 9.984994 180)
			(size 0.3048 0.3048)
			(layers "F.Cu" "F.Mask" "F.Paste")
			(net "JTAG_DBP_PMODE")
		)
		(pad "BE41" smd circle
			(at 9.65962 10.159746 180)
			(size 0.3048 0.3048)
			(layers "F.Cu" "F.Mask" "F.Paste")
			(net "GND")
		)
		(pad "BE43" smd circle
			(at 10.31494 10.159746 180)
			(size 0.4064 0.4064)
			(layers "F.Cu" "F.Mask" "F.Paste")
			(net "GND")
		)
		(pad "BF5" smd circle
			(at -8.504174 10.40003 180)
			(size 0.3048 0.3048)
			(layers "F.Cu" "F.Mask" "F.Paste")
			(net "RTC_EXT_CAP")
		)
		(pad "BF7" smd circle
			(at -7.503668 10.40003 180)
			(size 0.3048 0.3048)
			(layers "F.Cu" "F.Mask" "F.Paste")
			(net "XTAL_PCH_RTC2")
		)
		(pad "BF9" smd circle
			(at -6.503162 10.40003 180)
			(size 0.3048 0.3048)
			(layers "F.Cu" "F.Mask" "F.Paste")
			(net "RST_SRTCRST_N")
		)
		(pad "BF11" smd circle
			(at -5.502656 10.40003 180)
			(size 0.3048 0.3048)
			(layers "F.Cu" "F.Mask" "F.Paste")
			(net "PD_PCH_GPPC_A_18")
		)
		(pad "BF13" smd circle
			(at -4.50215 10.40003 180)
			(size 0.3048 0.3048)
			(layers "F.Cu" "F.Mask" "F.Paste")
			(net "IRQ_BMC_PCH_NMI")
		)
		(pad "BF15" smd circle
			(at -3.501644 10.40003 180)
			(size 0.3048 0.3048)
			(layers "F.Cu" "F.Mask" "F.Paste")
			(net "FM_BMC_READY_R_N")
		)
		(pad "BF17" smd circle
			(at -2.501138 10.40003 180)
			(size 0.3048 0.3048)
			(layers "F.Cu" "F.Mask" "F.Paste")
			(net "RST_ESPI_RESET_N")
		)
		(pad "BF19" smd circle
			(at -1.500632 10.40003 180)
			(size 0.3048 0.3048)
			(layers "F.Cu" "F.Mask" "F.Paste")
			(net "ESPI_LAD0_DATA_IO1")
		)
		(pad "BF21" smd circle
			(at -0.500126 10.40003 180)
			(size 0.3048 0.3048)
			(layers "F.Cu" "F.Mask" "F.Paste")
			(net "GND")
		)
		(pad "BF23" smd circle
			(at 0.500126 10.40003 180)
			(size 0.3048 0.3048)
			(layers "F.Cu" "F.Mask" "F.Paste")
			(net "JTAG_TRC_PCH_PTI<14>")
		)
		(pad "BF25" smd circle
			(at 1.500632 10.40003 180)
			(size 0.3048 0.3048)
			(layers "F.Cu" "F.Mask" "F.Paste")
			(net "JTAG_TRC_PCH_PTI<12>")
		)
		(pad "BF27" smd circle
			(at 2.501138 10.40003 180)
			(size 0.3048 0.3048)
			(layers "F.Cu" "F.Mask" "F.Paste")
			(net "JTAG_TRC_PCH_PTI<10>")
		)
		(pad "BF29" smd circle
			(at 3.501644 10.40003 180)
			(size 0.3048 0.3048)
			(layers "F.Cu" "F.Mask" "F.Paste")
			(net "JTAG_TRC_PCH_PTI<7>")
		)
		(pad "BF31" smd circle
			(at 4.50215 10.40003 180)
			(size 0.3048 0.3048)
			(layers "F.Cu" "F.Mask" "F.Paste")
			(net "JTAG_TRC_PCH_PTI<4>")
		)
		(pad "BF33" smd circle
			(at 5.502656 10.40003 180)
			(size 0.3048 0.3048)
			(layers "F.Cu" "F.Mask" "F.Paste")
			(net "JTAG_TRC_PCH_PTI<1>")
		)
		(pad "BF35" smd circle
			(at 6.503162 10.40003 180)
			(size 0.3048 0.3048)
			(layers "F.Cu" "F.Mask" "F.Paste")
			(net "JTAG_DBP_TCK_PCH")
		)
		(pad "BF37" smd circle
			(at 7.503668 10.40003 180)
			(size 0.3048 0.3048)
			(layers "F.Cu" "F.Mask" "F.Paste")
			(net "H_DBP_PREQ_N_PCH")
		)
		(pad "BF39" smd circle
			(at 8.504174 10.40003 180)
			(size 0.3048 0.3048)
			(layers "F.Cu" "F.Mask" "F.Paste")
			(net "NC_PCH_RSVD<5>")
		)
		(pad "BG3" smd circle
			(at -9.65962 10.815066 180)
			(size 0.4064 0.4064)
			(layers "F.Cu" "F.Mask" "F.Paste")
			(net "TP_PCH_CGC_DUT_DETECTED")
		)
		(pad "BG4" smd circle
			(at -9.0043 10.815066 180)
			(size 0.4064 0.4064)
			(layers "F.Cu" "F.Mask" "F.Paste")
			(net "GND")
		)
		(pad "BG6" smd circle
			(at -8.003794 10.815066 180)
			(size 0.3048 0.3048)
			(layers "F.Cu" "F.Mask" "F.Paste")
			(net "GND")
		)
		(pad "BG8" smd oval
			(at -7.003288 10.815066 180)
			(size 0.254 0.3302)
			(layers "F.Cu" "F.Mask" "F.Paste")
			(net "FM_INTRUDER_HDR_PCH_N")
		)
		(pad "BG10" smd oval
			(at -6.002782 10.815066 180)
			(size 0.254 0.3302)
			(layers "F.Cu" "F.Mask" "F.Paste")
			(net "GND")
		)
		(pad "BG12" smd oval
			(at -5.002276 10.815066 180)
			(size 0.254 0.3302)
			(layers "F.Cu" "F.Mask" "F.Paste")
			(net "ESPI_LAD0_DATA_IO0")
		)
		(pad "BG14" smd oval
			(at -4.002024 10.815066 180)
			(size 0.254 0.3302)
			(layers "F.Cu" "F.Mask" "F.Paste")
			(net "PD_PCH_GPPC_A_19")
		)
		(pad "BG16" smd oval
			(at -3.001518 10.815066 180)
			(size 0.254 0.3302)
			(layers "F.Cu" "F.Mask" "F.Paste")
			(net "M2_SSD0_CLKREQ_EN_N")
		)
		(pad "BG18" smd oval
			(at -2.001012 10.815066 180)
			(size 0.254 0.3302)
			(layers "F.Cu" "F.Mask" "F.Paste")
			(net "E1S_0_CLKREQ_N")
		)
		(pad "BG20" smd oval
			(at -1.000506 10.815066 180)
			(size 0.254 0.3302)
			(layers "F.Cu" "F.Mask" "F.Paste")
			(net "IRQ_LPC_PIRQA_N_ESPI_ALERT0_N")
		)
		(pad "BG22" smd oval
			(at 0 10.815066 180)
			(size 0.254 0.3302)
			(layers "F.Cu" "F.Mask" "F.Paste")
			(net "PU_OC6_USB_N")
		)
		(pad "BG24" smd oval
			(at 1.000506 10.815066 180)
			(size 0.254 0.3302)
			(layers "F.Cu" "F.Mask" "F.Paste")
			(net "PU_OC5_USB_N")
		)
		(pad "BG26" smd oval
			(at 2.001012 10.815066 180)
			(size 0.254 0.3302)
			(layers "F.Cu" "F.Mask" "F.Paste")
			(net "PU_OC4_USB_N")
		)
		(pad "BG28" smd oval
			(at 3.001518 10.815066 180)
			(size 0.254 0.3302)
			(layers "F.Cu" "F.Mask" "F.Paste")
			(net "PU_OC3_USB_N")
		)
		(pad "BG30" smd oval
			(at 4.002024 10.815066 180)
			(size 0.254 0.3302)
			(layers "F.Cu" "F.Mask" "F.Paste")
			(net "PU_OC2_USB_N")
		)
		(pad "BG32" smd oval
			(at 5.002276 10.815066 180)
			(size 0.254 0.3302)
			(layers "F.Cu" "F.Mask" "F.Paste")
			(net "USB_OC1_REAR_R_N")
		)
		(pad "BG34" smd oval
			(at 6.002782 10.815066 180)
			(size 0.254 0.3302)
			(layers "F.Cu" "F.Mask" "F.Paste")
			(net "GND")
		)
		(pad "BG36" smd oval
			(at 7.003288 10.815066 180)
			(size 0.254 0.3302)
			(layers "F.Cu" "F.Mask" "F.Paste")
			(net "NC_PCH_RSVD<17>")
		)
		(pad "BG38" smd circle
			(at 8.003794 10.815066 180)
			(size 0.4064 0.4064)
			(layers "F.Cu" "F.Mask" "F.Paste")
			(net "GND")
		)
		(pad "BG40" smd circle
			(at 9.0043 10.815066 180)
			(size 0.4064 0.4064)
			(layers "F.Cu" "F.Mask" "F.Paste")
			(net "GND")
		)
		(pad "BG41" smd circle
			(at 9.65962 10.815066 180)
			(size 0.4064 0.4064)
			(layers "F.Cu" "F.Mask" "F.Paste")
			(net "GND")
		)
		(pad "C3" smd circle
			(at -9.65962 -10.159746 180)
			(size 0.4064 0.4064)
			(layers "F.Cu" "F.Mask" "F.Paste")
			(net "GND")
		)
		(pad "C4" smd circle
			(at -9.0043 -9.984994 180)
			(size 0.3048 0.3048)
			(layers "F.Cu" "F.Mask" "F.Paste")
			(net "GND")
		)
		(pad "C6" smd circle
			(at -8.003794 -9.984994 180)
			(size 0.3048 0.3048)
			(layers "F.Cu" "F.Mask" "F.Paste")
			(net "TP_CLK_100M_PCH_15_DP")
		)
		(pad "C8" smd circle
			(at -7.003288 -9.984994 180)
			(size 0.3048 0.3048)
			(layers "F.Cu" "F.Mask" "F.Paste")
			(net "TP_CLK_100M_PCH_13_DP")
		)
		(pad "C10" smd circle
			(at -6.002782 -9.984994 180)
			(size 0.3048 0.3048)
			(layers "F.Cu" "F.Mask" "F.Paste")
			(net "TP_CLK_100M_PCH_12_DP")
		)
		(pad "C12" smd circle
			(at -5.002276 -9.984994 180)
			(size 0.3048 0.3048)
			(layers "F.Cu" "F.Mask" "F.Paste")
			(net "TP_CLK_100M_PCH_5_DP")
		)
		(pad "C14" smd circle
			(at -4.002024 -9.984994 180)
			(size 0.3048 0.3048)
			(layers "F.Cu" "F.Mask" "F.Paste")
			(net "TP_CLK_100M_PCH_7_DP")
		)
		(pad "C16" smd circle
			(at -3.001518 -9.984994 180)
			(size 0.3048 0.3048)
			(layers "F.Cu" "F.Mask" "F.Paste")
			(net "TP_CLK_100M_PCH_0_DP")
		)
		(pad "C18" smd circle
			(at -2.001012 -9.984994 180)
			(size 0.3048 0.3048)
			(layers "F.Cu" "F.Mask" "F.Paste")
			(net "TP_CLK_100M_PCH_16_DP")
		)
		(pad "C20" smd circle
			(at -1.000506 -9.984994 180)
			(size 0.3048 0.3048)
			(layers "F.Cu" "F.Mask" "F.Paste")
			(net "GND")
		)
		(pad "C22" smd circle
			(at 0 -9.984994 180)
			(size 0.3048 0.3048)
			(layers "F.Cu" "F.Mask" "F.Paste")
			(net "GND")
		)
		(pad "C24" smd circle
			(at 1.000506 -9.984994 180)
			(size 0.3048 0.3048)
			(layers "F.Cu" "F.Mask" "F.Paste")
			(net "GND")
		)
		(pad "C26" smd circle
			(at 2.001012 -9.984994 180)
			(size 0.3048 0.3048)
			(layers "F.Cu" "F.Mask" "F.Paste")
			(net "GND")
		)
		(pad "C28" smd circle
			(at 3.001518 -9.984994 180)
			(size 0.3048 0.3048)
			(layers "F.Cu" "F.Mask" "F.Paste")
			(net "CLK_25M_PCH_CPU1_DN")
		)
		(pad "C30" smd circle
			(at 4.002024 -9.984994 180)
			(size 0.3048 0.3048)
			(layers "F.Cu" "F.Mask" "F.Paste")
			(net "DMI_CPU0_PCH_TX_C_DP<0>")
		)
		(pad "C32" smd circle
			(at 5.002276 -9.984994 180)
			(size 0.3048 0.3048)
			(layers "F.Cu" "F.Mask" "F.Paste")
			(net "DMI_CPU0_PCH_TX_C_DP<2>")
		)
		(pad "C34" smd circle
			(at 6.002782 -9.984994 180)
			(size 0.3048 0.3048)
			(layers "F.Cu" "F.Mask" "F.Paste")
			(net "DMI_CPU0_PCH_TX_C_DP<4>")
		)
		(pad "C36" smd circle
			(at 7.003288 -9.984994 180)
			(size 0.3048 0.3048)
			(layers "F.Cu" "F.Mask" "F.Paste")
			(net "DMI_CPU0_PCH_TX_C_DP<6>")
		)
		(pad "C38" smd circle
			(at 8.003794 -9.984994 180)
			(size 0.3048 0.3048)
			(layers "F.Cu" "F.Mask" "F.Paste")
			(net "GND")
		)
		(pad "C40" smd circle
			(at 9.0043 -9.984994 180)
			(size 0.3048 0.3048)
			(layers "F.Cu" "F.Mask" "F.Paste")
			(net "NC_PCH_RSVD<8>")
		)
		(pad "C41" smd circle
			(at 9.65962 -10.159746 180)
			(size 0.3048 0.3048)
			(layers "F.Cu" "F.Mask" "F.Paste")
			(net "GND")
		)
		(pad "C43" smd circle
			(at 10.31494 -10.159746 180)
			(size 0.4064 0.4064)
			(layers "F.Cu" "F.Mask" "F.Paste")
			(net "GND")
		)
		(pad "D1" smd circle
			(at -10.31494 -9.50468 180)
			(size 0.4064 0.4064)
			(layers "F.Cu" "F.Mask" "F.Paste")
			(net "GND")
		)
		(pad "D3" smd circle
			(at -9.484868 -9.50468 180)
			(size 0.3048 0.3048)
			(layers "F.Cu" "F.Mask" "F.Paste")
			(net "GND")
		)
		(pad "D5" smd circle
			(at -8.504174 -9.569958 180)
			(size 0.3048 0.3048)
			(layers "F.Cu" "F.Mask" "F.Paste")
			(net "GND")
		)
		(pad "D7" smd circle
			(at -7.503668 -9.569958 180)
			(size 0.3048 0.3048)
			(layers "F.Cu" "F.Mask" "F.Paste")
			(net "TP_CLK_100M_PCH_14_DP")
		)
		(pad "D9" smd circle
			(at -6.503162 -9.569958 180)
			(size 0.3048 0.3048)
			(layers "F.Cu" "F.Mask" "F.Paste")
			(net "GND")
		)
		(pad "D11" smd circle
			(at -5.502656 -9.569958 180)
			(size 0.3048 0.3048)
			(layers "F.Cu" "F.Mask" "F.Paste")
			(net "CLK_100M_BMC_P3E_DP")
		)
		(pad "D13" smd circle
			(at -4.50215 -9.569958 180)
			(size 0.3048 0.3048)
			(layers "F.Cu" "F.Mask" "F.Paste")
			(net "GND")
		)
		(pad "D15" smd circle
			(at -3.501644 -9.569958 180)
			(size 0.3048 0.3048)
			(layers "F.Cu" "F.Mask" "F.Paste")
			(net "TP_CLK_100M_PCH_9_DP")
		)
		(pad "D17" smd circle
			(at -2.501138 -9.569958 180)
			(size 0.3048 0.3048)
			(layers "F.Cu" "F.Mask" "F.Paste")
			(net "CLK_100M_E1S_0_R_DP")
		)
		(pad "D19" smd circle
			(at -1.500632 -9.569958 180)
			(size 0.3048 0.3048)
			(layers "F.Cu" "F.Mask" "F.Paste")
			(net "TP_CLK_100M_PCH_4_DP")
		)
		(pad "D21" smd circle
			(at -0.500126 -9.569958 180)
			(size 0.3048 0.3048)
			(layers "F.Cu" "F.Mask" "F.Paste")
			(net "CLK_100M_CK440_PCH_EXTCLK_DN")
		)
		(pad "D23" smd circle
			(at 0.500126 -9.569958 180)
			(size 0.3048 0.3048)
			(layers "F.Cu" "F.Mask" "F.Paste")
			(net "XTAL_PCH_25M_OUT")
		)
		(pad "D25" smd circle
			(at 1.500632 -9.569958 180)
			(size 0.3048 0.3048)
			(layers "F.Cu" "F.Mask" "F.Paste")
			(net "CLK_25M_PCH_REF_NS_DN")
		)
		(pad "D27" smd circle
			(at 2.501138 -9.569958 180)
			(size 0.3048 0.3048)
			(layers "F.Cu" "F.Mask" "F.Paste")
			(net "CLK_25M_PCH_CPU0_DN")
		)
		(pad "D29" smd circle
			(at 3.501644 -9.569958 180)
			(size 0.3048 0.3048)
			(layers "F.Cu" "F.Mask" "F.Paste")
			(net "GND")
		)
		(pad "D31" smd circle
			(at 4.50215 -9.569958 180)
			(size 0.3048 0.3048)
			(layers "F.Cu" "F.Mask" "F.Paste")
			(net "DMI_CPU0_PCH_TX_C_DP<1>")
		)
		(pad "D33" smd circle
			(at 5.502656 -9.569958 180)
			(size 0.3048 0.3048)
			(layers "F.Cu" "F.Mask" "F.Paste")
			(net "DMI_CPU0_PCH_TX_C_DP<3>")
		)
		(pad "D35" smd circle
			(at 6.503162 -9.569958 180)
			(size 0.3048 0.3048)
			(layers "F.Cu" "F.Mask" "F.Paste")
			(net "DMI_CPU0_PCH_TX_C_DP<5>")
		)
		(pad "D37" smd circle
			(at 7.503668 -9.569958 180)
			(size 0.3048 0.3048)
			(layers "F.Cu" "F.Mask" "F.Paste")
			(net "DMI_CPU0_PCH_TX_C_DP<7>")
		)
		(pad "D39" smd circle
			(at 8.504174 -9.569958 180)
			(size 0.3048 0.3048)
			(layers "F.Cu" "F.Mask" "F.Paste")
			(net "NC_PCH_RSVD<9>")
		)
		(pad "D41" smd circle
			(at 9.484868 -9.50468 180)
			(size 0.3048 0.3048)
			(layers "F.Cu" "F.Mask" "F.Paste")
			(net "GND")
		)
		(pad "D43" smd circle
			(at 10.31494 -9.50468 180)
			(size 0.4064 0.4064)
			(layers "F.Cu" "F.Mask" "F.Paste")
			(net "GND")
		)
		(pad "E2" smd circle
			(at -9.899904 -9.0043 180)
			(size 0.3048 0.3048)
			(layers "F.Cu" "F.Mask" "F.Paste")
			(net "GND")
		)
		(pad "E4" smd circle
			(at -9.069832 -9.0043 180)
			(size 0.3048 0.3048)
			(layers "F.Cu" "F.Mask" "F.Paste")
			(net "TP_PCH_CPU_MEMTRIP_N")
		)
		(pad "E6" smd circle
			(at -8.003794 -9.154922 180)
			(size 0.3048 0.3048)
			(layers "F.Cu" "F.Mask" "F.Paste")
			(net "GND")
		)
		(pad "E8" smd circle
			(at -7.003288 -9.154922 180)
			(size 0.3048 0.3048)
			(layers "F.Cu" "F.Mask" "F.Paste")
			(net "GND")
		)
		(pad "E10" smd circle
			(at -6.002782 -9.154922 180)
			(size 0.3048 0.3048)
			(layers "F.Cu" "F.Mask" "F.Paste")
			(net "GND")
		)
		(pad "E12" smd circle
			(at -5.002276 -9.154922 180)
			(size 0.3048 0.3048)
			(layers "F.Cu" "F.Mask" "F.Paste")
			(net "GND")
		)
		(pad "E14" smd circle
			(at -4.002024 -9.154922 180)
			(size 0.3048 0.3048)
			(layers "F.Cu" "F.Mask" "F.Paste")
			(net "GND")
		)
		(pad "E16" smd circle
			(at -3.001518 -9.154922 180)
			(size 0.3048 0.3048)
			(layers "F.Cu" "F.Mask" "F.Paste")
			(net "GND")
		)
		(pad "E18" smd circle
			(at -2.001012 -9.154922 180)
			(size 0.3048 0.3048)
			(layers "F.Cu" "F.Mask" "F.Paste")
			(net "GND")
		)
		(pad "E20" smd circle
			(at -1.000506 -9.154922 180)
			(size 0.3048 0.3048)
			(layers "F.Cu" "F.Mask" "F.Paste")
			(net "GND")
		)
		(pad "E22" smd circle
			(at 0 -9.154922 180)
			(size 0.3048 0.3048)
			(layers "F.Cu" "F.Mask" "F.Paste")
			(net "GND")
		)
		(pad "E24" smd circle
			(at 1.000506 -9.154922 180)
			(size 0.3048 0.3048)
			(layers "F.Cu" "F.Mask" "F.Paste")
			(net "GND")
		)
		(pad "E26" smd circle
			(at 2.001012 -9.154922 180)
			(size 0.3048 0.3048)
			(layers "F.Cu" "F.Mask" "F.Paste")
			(net "GND")
		)
		(pad "E28" smd circle
			(at 3.001518 -9.154922 180)
			(size 0.3048 0.3048)
			(layers "F.Cu" "F.Mask" "F.Paste")
			(net "GND")
		)
		(pad "E30" smd circle
			(at 4.002024 -9.154922 180)
			(size 0.3048 0.3048)
			(layers "F.Cu" "F.Mask" "F.Paste")
			(net "GND")
		)
		(pad "E32" smd circle
			(at 5.002276 -9.154922 180)
			(size 0.3048 0.3048)
			(layers "F.Cu" "F.Mask" "F.Paste")
			(net "GND")
		)
		(pad "E34" smd circle
			(at 6.002782 -9.154922 180)
			(size 0.3048 0.3048)
			(layers "F.Cu" "F.Mask" "F.Paste")
			(net "GND")
		)
		(pad "E36" smd circle
			(at 7.003288 -9.154922 180)
			(size 0.3048 0.3048)
			(layers "F.Cu" "F.Mask" "F.Paste")
			(net "GND")
		)
		(pad "E38" smd circle
			(at 8.003794 -9.154922 180)
			(size 0.3048 0.3048)
			(layers "F.Cu" "F.Mask" "F.Paste")
			(net "GND")
		)
		(pad "E40" smd circle
			(at 9.069832 -9.0043 180)
			(size 0.3048 0.3048)
			(layers "F.Cu" "F.Mask" "F.Paste")
			(net "GND")
		)
		(pad "E42" smd circle
			(at 9.899904 -9.0043 180)
			(size 0.3048 0.3048)
			(layers "F.Cu" "F.Mask" "F.Paste")
			(net "GND")
		)
		(pad "F1" smd circle
			(at -10.31494 -8.504174 180)
			(size 0.4064 0.4064)
			(layers "F.Cu" "F.Mask" "F.Paste")
			(net "TP_PCH_RSVD<1>")
		)
		(pad "F3" smd circle
			(at -9.484868 -8.504174 180)
			(size 0.3048 0.3048)
			(layers "F.Cu" "F.Mask" "F.Paste")
			(net "H_THERMTRIP_LVC1_N")
		)
		(pad "F5" smd circle
			(at -8.654796 -8.504174 180)
			(size 0.3048 0.3048)
			(layers "F.Cu" "F.Mask" "F.Paste")
			(net "FM_PCH_CPU_PWR_DEBUG_N")
		)
		(pad "F8" smd circle
			(at -6.919722 -8.4582 180)
			(size 0.381 0.381)
			(layers "F.Cu" "F.Mask" "F.Paste")
			(net "FM_PCIE_EV_BIF_EN")
		)
		(pad "F11" smd circle
			(at -5.291582 -8.4582 180)
			(size 0.381 0.381)
			(layers "F.Cu" "F.Mask" "F.Paste")
			(net "TP_PCH_CPU_MSMI_N")
		)
		(pad "F15" smd circle
			(at -3.663188 -8.4582 180)
			(size 0.381 0.381)
			(layers "F.Cu" "F.Mask" "F.Paste")
			(net "GND")
		)
		(pad "F18" smd circle
			(at -2.035302 -8.4582 180)
			(size 0.381 0.381)
			(layers "F.Cu" "F.Mask" "F.Paste")
			(net "TP_CLK_100M_PCH_8_DN")
		)
		(pad "F21" smd circle
			(at -0.406908 -8.4582 180)
			(size 0.381 0.381)
			(layers "F.Cu" "F.Mask" "F.Paste")
			(net "TP_CLK_100M_PCH_1_DP")
		)
		(pad "F24" smd circle
			(at 1.220978 -8.4582 180)
			(size 0.381 0.381)
			(layers "F.Cu" "F.Mask" "F.Paste")
			(net "GND")
		)
		(pad "F28" smd circle
			(at 2.849118 -8.4582 180)
			(size 0.381 0.381)
			(layers "F.Cu" "F.Mask" "F.Paste")
			(net "DMI_CPU0_PCH_RX_DP<1>")
		)
		(pad "F31" smd circle
			(at 4.477512 -8.4582 180)
			(size 0.381 0.381)
			(layers "F.Cu" "F.Mask" "F.Paste")
			(net "GND")
		)
		(pad "F34" smd circle
			(at 6.105398 -8.4582 180)
			(size 0.381 0.381)
			(layers "F.Cu" "F.Mask" "F.Paste")
			(net "GND")
		)
		(pad "F37" smd circle
			(at 7.733792 -8.4582 180)
			(size 0.381 0.381)
			(layers "F.Cu" "F.Mask" "F.Paste")
			(net "DMI_CPU0_PCH_RX_DN<7>")
		)
		(pad "F39" smd circle
			(at 8.654796 -8.504174 180)
			(size 0.3048 0.3048)
			(layers "F.Cu" "F.Mask" "F.Paste")
			(net "GND")
		)
		(pad "F41" smd circle
			(at 9.484868 -8.504174 180)
			(size 0.3048 0.3048)
			(layers "F.Cu" "F.Mask" "F.Paste")
			(net "GND")
		)
		(pad "F43" smd circle
			(at 10.31494 -8.504174 180)
			(size 0.4064 0.4064)
			(layers "F.Cu" "F.Mask" "F.Paste")
			(net "GND")
		)
		(pad "G2" smd circle
			(at -9.899904 -8.003794 180)
			(size 0.3048 0.3048)
			(layers "F.Cu" "F.Mask" "F.Paste")
			(net "FM_PCH_RING_OSC_BYPASS_MGPIO_TE")
		)
		(pad "G4" smd circle
			(at -9.069832 -8.003794 180)
			(size 0.3048 0.3048)
			(layers "F.Cu" "F.Mask" "F.Paste")
			(net "FM_PCH_VISA_DEFAULT")
		)
		(pad "G7" smd circle
			(at -7.733792 -7.9883 180)
			(size 0.381 0.381)
			(layers "F.Cu" "F.Mask" "F.Paste")
			(net "H_CPU_ERR1_PCH_R_N")
		)
		(pad "G10" smd circle
			(at -6.105398 -7.9883 180)
			(size 0.381 0.381)
			(layers "F.Cu" "F.Mask" "F.Paste")
			(net "PWRGD_CPUPWRGD_GTL")
		)
		(pad "G13" smd circle
			(at -4.477512 -7.9883 180)
			(size 0.381 0.381)
			(layers "F.Cu" "F.Mask" "F.Paste")
			(net "GND")
		)
		(pad "G16" smd circle
			(at -2.849118 -7.9883 180)
			(size 0.381 0.381)
			(layers "F.Cu" "F.Mask" "F.Paste")
			(net "TP_CLK_100M_PCH_11_DN")
		)
		(pad "G20" smd circle
			(at -1.220978 -7.9883 180)
			(size 0.381 0.381)
			(layers "F.Cu" "F.Mask" "F.Paste")
			(net "GND")
		)
		(pad "G23" smd circle
			(at 0.406908 -7.9883 180)
			(size 0.381 0.381)
			(layers "F.Cu" "F.Mask" "F.Paste")
			(net "TP_CLK_100M_PCH_1_DN")
		)
		(pad "G26" smd circle
			(at 2.035302 -7.9883 180)
			(size 0.381 0.381)
			(layers "F.Cu" "F.Mask" "F.Paste")
			(net "GND")
		)
		(pad "G29" smd circle
			(at 3.663188 -7.9883 180)
			(size 0.381 0.381)
			(layers "F.Cu" "F.Mask" "F.Paste")
			(net "DMI_CPU0_PCH_RX_DN<1>")
		)
		(pad "G32" smd circle
			(at 5.291582 -7.9883 180)
			(size 0.381 0.381)
			(layers "F.Cu" "F.Mask" "F.Paste")
			(net "DMI_CPU0_PCH_RX_DP<4>")
		)
		(pad "G36" smd circle
			(at 6.919722 -7.9883 180)
			(size 0.381 0.381)
			(layers "F.Cu" "F.Mask" "F.Paste")
			(net "DMI_CPU0_PCH_RX_DN<5>")
		)
		(pad "G40" smd circle
			(at 9.069832 -8.003794 180)
			(size 0.3048 0.3048)
			(layers "F.Cu" "F.Mask" "F.Paste")
			(net "TP_P3E_PCH_15_RX_DN")
		)
		(pad "G42" smd circle
			(at 9.899904 -8.003794 180)
			(size 0.3048 0.3048)
			(layers "F.Cu" "F.Mask" "F.Paste")
			(net "TP_P3E_PCH_15_RX_DP")
		)
		(pad "H1" smd oval
			(at -10.31494 -7.503668 270)
			(size 0.254 0.3302)
			(layers "F.Cu" "F.Mask" "F.Paste")
			(net "TP_PCH_RSVD<0>")
		)
		(pad "H3" smd circle
			(at -9.484868 -7.503668 180)
			(size 0.3048 0.3048)
			(layers "F.Cu" "F.Mask" "F.Paste")
			(net "FM_PCH_XTAL_INPUT_MODE_MGPIO_TE")
		)
		(pad "H5" smd circle
			(at -8.654796 -7.503668 180)
			(size 0.3048 0.3048)
			(layers "F.Cu" "F.Mask" "F.Paste")
			(net "GND")
		)
		(pad "H8" smd circle
			(at -6.919722 -7.5184 180)
			(size 0.381 0.381)
			(layers "F.Cu" "F.Mask" "F.Paste")
			(net "GND")
		)
		(pad "H11" smd circle
			(at -5.291582 -7.5184 180)
			(size 0.381 0.381)
			(layers "F.Cu" "F.Mask" "F.Paste")
			(net "FM_PCH_TRIGGER0_R_N")
		)
		(pad "H15" smd circle
			(at -3.663188 -7.5184 180)
			(size 0.381 0.381)
			(layers "F.Cu" "F.Mask" "F.Paste")
			(net "TP_CLK_100M_PCH_11_DP")
		)
		(pad "H18" smd circle
			(at -2.035302 -7.5184 180)
			(size 0.381 0.381)
			(layers "F.Cu" "F.Mask" "F.Paste")
			(net "TP_CLK_100M_PCH_8_DP")
		)
		(pad "H21" smd circle
			(at -0.406908 -7.5184 180)
			(size 0.381 0.381)
			(layers "F.Cu" "F.Mask" "F.Paste")
			(net "CLK_100M_PE_M2_0_R_DN")
		)
		(pad "H24" smd circle
			(at 1.220978 -7.5184 180)
			(size 0.381 0.381)
			(layers "F.Cu" "F.Mask" "F.Paste")
			(net "TP_PCH_RSVD<18>")
		)
		(pad "H28" smd circle
			(at 2.849118 -7.5184 180)
			(size 0.381 0.381)
			(layers "F.Cu" "F.Mask" "F.Paste")
			(net "DMI_CPU0_PCH_RX_DP<0>")
		)
		(pad "H31" smd circle
			(at 4.477512 -7.5184 180)
			(size 0.381 0.381)
			(layers "F.Cu" "F.Mask" "F.Paste")
			(net "DMI_CPU0_PCH_RX_DP<2>")
		)
		(pad "H34" smd circle
			(at 6.105398 -7.5184 180)
			(size 0.381 0.381)
			(layers "F.Cu" "F.Mask" "F.Paste")
			(net "DMI_CPU0_PCH_RX_DP<5>")
		)
		(pad "H37" smd circle
			(at 7.733792 -7.5184 180)
			(size 0.381 0.381)
			(layers "F.Cu" "F.Mask" "F.Paste")
			(net "DMI_CPU0_PCH_RX_DP<7>")
		)
		(pad "H39" smd circle
			(at 8.654796 -7.503668 180)
			(size 0.3048 0.3048)
			(layers "F.Cu" "F.Mask" "F.Paste")
			(net "GND")
		)
		(pad "H41" smd circle
			(at 9.484868 -7.503668 180)
			(size 0.3048 0.3048)
			(layers "F.Cu" "F.Mask" "F.Paste")
			(net "TP_P3E_PCH_14_RX_DN")
		)
		(pad "H43" smd oval
			(at 10.31494 -7.503668 270)
			(size 0.254 0.3302)
			(layers "F.Cu" "F.Mask" "F.Paste")
			(net "TP_P3E_PCH_14_RX_DP")
		)
		(pad "J2" smd circle
			(at -9.899904 -7.003288 180)
			(size 0.3048 0.3048)
			(layers "F.Cu" "F.Mask" "F.Paste")
			(net "TP_PCH_MGPIO_TEST1")
		)
		(pad "J4" smd circle
			(at -9.069832 -7.003288 180)
			(size 0.3048 0.3048)
			(layers "F.Cu" "F.Mask" "F.Paste")
			(net "PU_PCH_PMCALERT_N")
		)
		(pad "J7" smd circle
			(at -7.733792 -7.0485 180)
			(size 0.381 0.381)
			(layers "F.Cu" "F.Mask" "F.Paste")
			(net "H_CPU_ERR0_PCH_R_N")
		)
		(pad "J10" smd circle
			(at -6.105398 -7.0485 180)
			(size 0.381 0.381)
			(layers "F.Cu" "F.Mask" "F.Paste")
			(net "PECI_PCH")
		)
		(pad "J13" smd circle
			(at -4.477512 -7.0485 180)
			(size 0.381 0.381)
			(layers "F.Cu" "F.Mask" "F.Paste")
			(net "GND")
		)
		(pad "J16" smd circle
			(at -2.849118 -7.0485 180)
			(size 0.381 0.381)
			(layers "F.Cu" "F.Mask" "F.Paste")
			(net "TP_CLK_100M_PCH_10_DN")
		)
		(pad "J20" smd circle
			(at -1.220978 -7.0485 180)
			(size 0.381 0.381)
			(layers "F.Cu" "F.Mask" "F.Paste")
			(net "GND")
		)
		(pad "J23" smd circle
			(at 0.406908 -7.0485 180)
			(size 0.381 0.381)
			(layers "F.Cu" "F.Mask" "F.Paste")
			(net "TP_PCH_RSVD<19>")
		)
		(pad "J26" smd circle
			(at 2.035302 -7.0485 180)
			(size 0.381 0.381)
			(layers "F.Cu" "F.Mask" "F.Paste")
			(net "GND")
		)
		(pad "J29" smd circle
			(at 3.663188 -7.0485 180)
			(size 0.381 0.381)
			(layers "F.Cu" "F.Mask" "F.Paste")
			(net "DMI_CPU0_PCH_RX_DN<2>")
		)
		(pad "J32" smd circle
			(at 5.291582 -7.0485 180)
			(size 0.381 0.381)
			(layers "F.Cu" "F.Mask" "F.Paste")
			(net "DMI_CPU0_PCH_RX_DN<4>")
		)
		(pad "J36" smd circle
			(at 6.919722 -7.0485 180)
			(size 0.381 0.381)
			(layers "F.Cu" "F.Mask" "F.Paste")
			(net "DMI_CPU0_PCH_RX_DP<6>")
		)
		(pad "J40" smd circle
			(at 9.069832 -7.003288 180)
			(size 0.3048 0.3048)
			(layers "F.Cu" "F.Mask" "F.Paste")
			(net "TP_P3E_PCH_13_RX_DN")
		)
		(pad "J42" smd circle
			(at 9.899904 -7.003288 180)
			(size 0.3048 0.3048)
			(layers "F.Cu" "F.Mask" "F.Paste")
			(net "TP_P3E_PCH_13_RX_DP")
		)
		(pad "K1" smd oval
			(at -10.31494 -6.503162 270)
			(size 0.254 0.3302)
			(layers "F.Cu" "F.Mask" "F.Paste")
			(net "FM_PCH_IO_EXPANDER")
		)
		(pad "K3" smd circle
			(at -9.484868 -6.503162 180)
			(size 0.3048 0.3048)
			(layers "F.Cu" "F.Mask" "F.Paste")
			(net "FM_PCH_MCRO_LDO")
		)
		(pad "K5" smd circle
			(at -8.654796 -6.503162 180)
			(size 0.3048 0.3048)
			(layers "F.Cu" "F.Mask" "F.Paste")
			(net "GND")
		)
		(pad "K8" smd circle
			(at -6.919722 -6.5786 180)
			(size 0.381 0.381)
			(layers "F.Cu" "F.Mask" "F.Paste")
			(net "FM_PCH_TRIGGER1_R_N")
		)
		(pad "K11" smd circle
			(at -5.291582 -6.5786 180)
			(size 0.381 0.381)
			(layers "F.Cu" "F.Mask" "F.Paste")
			(net "GND")
		)
		(pad "K15" smd circle
			(at -3.663188 -6.5786 180)
			(size 0.381 0.381)
			(layers "F.Cu" "F.Mask" "F.Paste")
			(net "GND")
		)
		(pad "K18" smd circle
			(at -2.035302 -6.5786 180)
			(size 0.381 0.381)
			(layers "F.Cu" "F.Mask" "F.Paste")
			(net "TP_CLK_100M_PCH_10_DP")
		)
		(pad "K21" smd circle
			(at -0.406908 -6.5786 180)
			(size 0.381 0.381)
			(layers "F.Cu" "F.Mask" "F.Paste")
			(net "CLK_100M_PE_M2_0_R_DP")
		)
		(pad "K24" smd circle
			(at 1.220978 -6.5786 180)
			(size 0.381 0.381)
			(layers "F.Cu" "F.Mask" "F.Paste")
			(net "GND")
		)
		(pad "K28" smd circle
			(at 2.849118 -6.5786 180)
			(size 0.381 0.381)
			(layers "F.Cu" "F.Mask" "F.Paste")
			(net "DMI_CPU0_PCH_RX_DN<0>")
		)
		(pad "K31" smd circle
			(at 4.477512 -6.5786 180)
			(size 0.381 0.381)
			(layers "F.Cu" "F.Mask" "F.Paste")
			(net "DMI_CPU0_PCH_RX_DP<3>")
		)
		(pad "K34" smd circle
			(at 6.105398 -6.5786 180)
			(size 0.381 0.381)
			(layers "F.Cu" "F.Mask" "F.Paste")
			(net "GND")
		)
		(pad "K37" smd circle
			(at 7.733792 -6.5786 180)
			(size 0.381 0.381)
			(layers "F.Cu" "F.Mask" "F.Paste")
			(net "DMI_CPU0_PCH_RX_DN<6>")
		)
		(pad "K39" smd circle
			(at 8.654796 -6.503162 180)
			(size 0.3048 0.3048)
			(layers "F.Cu" "F.Mask" "F.Paste")
			(net "GND")
		)
		(pad "K41" smd circle
			(at 9.484868 -6.503162 180)
			(size 0.3048 0.3048)
			(layers "F.Cu" "F.Mask" "F.Paste")
			(net "TP_P3E_PCH_12_RX_DN")
		)
		(pad "K43" smd oval
			(at 10.31494 -6.503162 270)
			(size 0.254 0.3302)
			(layers "F.Cu" "F.Mask" "F.Paste")
			(net "TP_P3E_PCH_12_RX_DP")
		)
		(pad "L2" smd circle
			(at -9.899904 -6.002782 180)
			(size 0.3048 0.3048)
			(layers "F.Cu" "F.Mask" "F.Paste")
			(net "FM_PCH_EXTERNALCLKMODE")
		)
		(pad "L4" smd circle
			(at -9.069832 -6.002782 180)
			(size 0.3048 0.3048)
			(layers "F.Cu" "F.Mask" "F.Paste")
			(net "FM_LT_KEY_DOWNGRADE_N")
		)
		(pad "L7" smd circle
			(at -7.733792 -6.1087 180)
			(size 0.381 0.381)
			(layers "F.Cu" "F.Mask" "F.Paste")
			(net "H_CPU_ERR2_PCH_R_N")
		)
		(pad "L10" smd circle
			(at -6.105398 -6.1087 180)
			(size 0.381 0.381)
			(layers "F.Cu" "F.Mask" "F.Paste")
			(net "GND")
		)
		(pad "L13" smd circle
			(at -4.477512 -6.1087 180)
			(size 0.381 0.381)
			(layers "F.Cu" "F.Mask" "F.Paste")
			(net "TP_PCH_RSVD<13>")
		)
		(pad "L16" smd circle
			(at -2.849118 -6.1087 180)
			(size 0.381 0.381)
			(layers "F.Cu" "F.Mask" "F.Paste")
			(net "GND")
		)
		(pad "L20" smd circle
			(at -1.220978 -6.1087 180)
			(size 0.381 0.381)
			(layers "F.Cu" "F.Mask" "F.Paste")
			(net "GND")
		)
		(pad "L23" smd circle
			(at 0.406908 -6.1087 180)
			(size 0.381 0.381)
			(layers "F.Cu" "F.Mask" "F.Paste")
			(net "GND")
		)
		(pad "L26" smd circle
			(at 2.035302 -6.1087 180)
			(size 0.381 0.381)
			(layers "F.Cu" "F.Mask" "F.Paste")
			(net "GND")
		)
		(pad "L29" smd circle
			(at 3.663188 -6.1087 180)
			(size 0.381 0.381)
			(layers "F.Cu" "F.Mask" "F.Paste")
			(net "GND")
		)
		(pad "L32" smd circle
			(at 5.291582 -6.1087 180)
			(size 0.381 0.381)
			(layers "F.Cu" "F.Mask" "F.Paste")
			(net "DMI_CPU0_PCH_RX_DN<3>")
		)
		(pad "L36" smd circle
			(at 6.919722 -6.1087 180)
			(size 0.381 0.381)
			(layers "F.Cu" "F.Mask" "F.Paste")
			(net "GND")
		)
		(pad "L40" smd circle
			(at 9.069832 -6.002782 180)
			(size 0.3048 0.3048)
			(layers "F.Cu" "F.Mask" "F.Paste")
			(net "P3E_PCH_NVS_RX_DN<1>")
		)
		(pad "L42" smd circle
			(at 9.899904 -6.002782 180)
			(size 0.3048 0.3048)
			(layers "F.Cu" "F.Mask" "F.Paste")
			(net "P3E_PCH_NVS_RX_DP<1>")
		)
		(pad "M1" smd oval
			(at -10.31494 -5.502656 270)
			(size 0.254 0.3302)
			(layers "F.Cu" "F.Mask" "F.Paste")
			(net "GND")
		)
		(pad "M3" smd circle
			(at -9.484868 -5.502656 180)
			(size 0.3048 0.3048)
			(layers "F.Cu" "F.Mask" "F.Paste")
			(net "GND")
		)
		(pad "M5" smd circle
			(at -8.654796 -5.502656 180)
			(size 0.3048 0.3048)
			(layers "F.Cu" "F.Mask" "F.Paste")
			(net "GND")
		)
		(pad "M8" smd circle
			(at -6.919722 -5.6388 180)
			(size 0.381 0.381)
			(layers "F.Cu" "F.Mask" "F.Paste")
			(net "TP_PLTRST_N")
		)
		(pad "M11" smd circle
			(at -5.291582 -5.6388 180)
			(size 0.381 0.381)
			(layers "F.Cu" "F.Mask" "F.Paste")
			(net "GND")
		)
		(pad "M15" smd circle
			(at -3.663188 -5.6388 180)
			(size 0.381 0.381)
			(layers "F.Cu" "F.Mask" "F.Paste")
			(net "GND")
		)
		(pad "M18" smd circle
			(at -2.035302 -5.6388 180)
			(size 0.381 0.381)
			(layers "F.Cu" "F.Mask" "F.Paste")
			(net "GND")
		)
		(pad "M21" smd circle
			(at -0.406908 -5.6388 180)
			(size 0.381 0.381)
			(layers "F.Cu" "F.Mask" "F.Paste")
			(net "GND")
		)
		(pad "M24" smd circle
			(at 1.220978 -5.6388 180)
			(size 0.381 0.381)
			(layers "F.Cu" "F.Mask" "F.Paste")
			(net "P1V05_PCH_AUX")
		)
		(pad "M28" smd circle
			(at 2.849118 -5.6388 180)
			(size 0.381 0.381)
			(layers "F.Cu" "F.Mask" "F.Paste")
			(net "GND")
		)
		(pad "M31" smd circle
			(at 4.477512 -5.6388 180)
			(size 0.381 0.381)
			(layers "F.Cu" "F.Mask" "F.Paste")
			(net "GND")
		)
		(pad "M34" smd circle
			(at 6.105398 -5.6388 180)
			(size 0.381 0.381)
			(layers "F.Cu" "F.Mask" "F.Paste")
			(net "GND")
		)
		(pad "M37" smd circle
			(at 7.733792 -5.6388 180)
			(size 0.381 0.381)
			(layers "F.Cu" "F.Mask" "F.Paste")
			(net "GND")
		)
		(pad "M39" smd circle
			(at 8.654796 -5.502656 180)
			(size 0.3048 0.3048)
			(layers "F.Cu" "F.Mask" "F.Paste")
			(net "GND")
		)
		(pad "M41" smd circle
			(at 9.484868 -5.502656 180)
			(size 0.3048 0.3048)
			(layers "F.Cu" "F.Mask" "F.Paste")
			(net "P3E_PCH_NVS_RX_DN<0>")
		)
		(pad "M43" smd oval
			(at 10.31494 -5.502656 270)
			(size 0.254 0.3302)
			(layers "F.Cu" "F.Mask" "F.Paste")
			(net "P3E_PCH_NVS_RX_DP<0>")
		)
		(pad "N2" smd circle
			(at -9.899904 -5.002276 180)
			(size 0.3048 0.3048)
			(layers "F.Cu" "F.Mask" "F.Paste")
			(net "PD_GPP_I_13")
		)
		(pad "N4" smd circle
			(at -9.069832 -5.002276 180)
			(size 0.3048 0.3048)
			(layers "F.Cu" "F.Mask" "F.Paste")
			(net "IRQ_TPM_SPI_N")
		)
		(pad "N7" smd circle
			(at -7.733792 -5.1689 180)
			(size 0.381 0.381)
			(layers "F.Cu" "F.Mask" "F.Paste")
			(net "FAB_REV_ID0")
		)
		(pad "N10" smd circle
			(at -6.105398 -5.1689 180)
			(size 0.381 0.381)
			(layers "F.Cu" "F.Mask" "F.Paste")
			(net "PD_GPP_M_16")
		)
		(pad "N13" smd circle
			(at -4.477512 -5.1689 180)
			(size 0.381 0.381)
			(layers "F.Cu" "F.Mask" "F.Paste")
			(net "TP_PCH_RSVD<12>")
		)
		(pad "N16" smd circle
			(at -2.849118 -5.1689 180)
			(size 0.381 0.381)
			(layers "F.Cu" "F.Mask" "F.Paste")
			(net "GND")
		)
		(pad "N20" smd circle
			(at -1.220978 -5.1689 180)
			(size 0.381 0.381)
			(layers "F.Cu" "F.Mask" "F.Paste")
			(net "P1V8_PCH_AUX")
		)
		(pad "N23" smd circle
			(at 0.406908 -5.1689 180)
			(size 0.381 0.381)
			(layers "F.Cu" "F.Mask" "F.Paste")
			(net "P1V05_PCH_AUX")
		)
		(pad "N26" smd circle
			(at 2.035302 -5.1689 180)
			(size 0.381 0.381)
			(layers "F.Cu" "F.Mask" "F.Paste")
			(net "P1V05_PCH_AUX")
		)
		(pad "N29" smd circle
			(at 3.663188 -5.1689 180)
			(size 0.381 0.381)
			(layers "F.Cu" "F.Mask" "F.Paste")
			(net "PD_PCH_XCLK_BIASREF")
		)
		(pad "N32" smd circle
			(at 5.291582 -5.1689 180)
			(size 0.381 0.381)
			(layers "F.Cu" "F.Mask" "F.Paste")
			(net "GND")
		)
		(pad "N36" smd circle
			(at 6.919722 -5.1689 180)
			(size 0.381 0.381)
			(layers "F.Cu" "F.Mask" "F.Paste")
			(net "TP_P3E_PCH_15_TX_DP")
		)
		(pad "N40" smd circle
			(at 9.069832 -5.002276 180)
			(size 0.3048 0.3048)
			(layers "F.Cu" "F.Mask" "F.Paste")
			(net "NC_PCH_RSVD<10>")
		)
		(pad "N42" smd circle
			(at 9.899904 -5.002276 180)
			(size 0.3048 0.3048)
			(layers "F.Cu" "F.Mask" "F.Paste")
			(net "NC_PCH_RSVD<11>")
		)
		(pad "P1" smd oval
			(at -10.31494 -4.50215 270)
			(size 0.254 0.3302)
			(layers "F.Cu" "F.Mask" "F.Paste")
			(net "PD_GPP_I_14")
		)
		(pad "P3" smd circle
			(at -9.484868 -4.50215 180)
			(size 0.3048 0.3048)
			(layers "F.Cu" "F.Mask" "F.Paste")
			(net "FM_PCH_DFXTESTMODE")
		)
		(pad "P5" smd circle
			(at -8.654796 -4.50215 180)
			(size 0.3048 0.3048)
			(layers "F.Cu" "F.Mask" "F.Paste")
			(net "GND")
		)
		(pad "P8" smd circle
			(at -6.919722 -4.699 180)
			(size 0.381 0.381)
			(layers "F.Cu" "F.Mask" "F.Paste")
			(net "GND")
		)
		(pad "P11" smd circle
			(at -5.291582 -4.699 180)
			(size 0.381 0.381)
			(layers "F.Cu" "F.Mask" "F.Paste")
			(net "GND")
		)
		(pad "P15" smd circle
			(at -3.663188 -4.699 180)
			(size 0.381 0.381)
			(layers "F.Cu" "F.Mask" "F.Paste")
			(net "P1V05_PCH_AUX")
		)
		(pad "P18" smd circle
			(at -2.035302 -4.699 180)
			(size 0.381 0.381)
			(layers "F.Cu" "F.Mask" "F.Paste")
			(net "TP_PCH_RSVD<6>")
		)
		(pad "P21" smd circle
			(at -0.406908 -4.699 180)
			(size 0.381 0.381)
			(layers "F.Cu" "F.Mask" "F.Paste")
			(net "P3V3_AUX")
		)
		(pad "P24" smd circle
			(at 1.220978 -4.699 180)
			(size 0.381 0.381)
			(layers "F.Cu" "F.Mask" "F.Paste")
			(net "GND")
		)
		(pad "P28" smd circle
			(at 2.849118 -4.699 180)
			(size 0.381 0.381)
			(layers "F.Cu" "F.Mask" "F.Paste")
			(net "GND")
		)
		(pad "P31" smd circle
			(at 4.477512 -4.699 180)
			(size 0.381 0.381)
			(layers "F.Cu" "F.Mask" "F.Paste")
			(net "GND")
		)
		(pad "P34" smd circle
			(at 6.105398 -4.699 180)
			(size 0.381 0.381)
			(layers "F.Cu" "F.Mask" "F.Paste")
			(net "TP_P3E_PCH_15_TX_DN")
		)
		(pad "P37" smd circle
			(at 7.733792 -4.699 180)
			(size 0.381 0.381)
			(layers "F.Cu" "F.Mask" "F.Paste")
			(net "GND")
		)
		(pad "P39" smd circle
			(at 8.654796 -4.50215 180)
			(size 0.3048 0.3048)
			(layers "F.Cu" "F.Mask" "F.Paste")
			(net "GND")
		)
		(pad "P41" smd circle
			(at 9.484868 -4.50215 180)
			(size 0.3048 0.3048)
			(layers "F.Cu" "F.Mask" "F.Paste")
			(net "GND")
		)
		(pad "P43" smd oval
			(at 10.31494 -4.50215 270)
			(size 0.254 0.3302)
			(layers "F.Cu" "F.Mask" "F.Paste")
			(net "GND")
		)
		(pad "R2" smd circle
			(at -9.899904 -4.002024 180)
			(size 0.3048 0.3048)
			(layers "F.Cu" "F.Mask" "F.Paste")
			(net "PD_GPP_I_15")
		)
		(pad "R4" smd circle
			(at -9.069832 -4.002024 180)
			(size 0.3048 0.3048)
			(layers "F.Cu" "F.Mask" "F.Paste")
			(net "FM_PCH_XTALSEL")
		)
		(pad "R7" smd circle
			(at -7.733792 -4.2291 180)
			(size 0.381 0.381)
			(layers "F.Cu" "F.Mask" "F.Paste")
			(net "FM_PCH_BIOS_RCVR_MODE")
		)
		(pad "R10" smd circle
			(at -6.105398 -4.2291 180)
			(size 0.381 0.381)
			(layers "F.Cu" "F.Mask" "F.Paste")
			(net "FM_BOARD_SKU_ID3")
		)
		(pad "R13" smd circle
			(at -4.477512 -4.2291 180)
			(size 0.381 0.381)
			(layers "F.Cu" "F.Mask" "F.Paste")
			(net "GND")
		)
		(pad "R16" smd circle
			(at -2.849118 -4.2291 180)
			(size 0.381 0.381)
			(layers "F.Cu" "F.Mask" "F.Paste")
			(net "GND")
		)
		(pad "R20" smd circle
			(at -1.220978 -4.2291 180)
			(size 0.381 0.381)
			(layers "F.Cu" "F.Mask" "F.Paste")
			(net "GND")
		)
		(pad "R23" smd circle
			(at 0.406908 -4.2291 180)
			(size 0.381 0.381)
			(layers "F.Cu" "F.Mask" "F.Paste")
			(net "P1V05_PCH_PLL_AUX")
		)
		(pad "R26" smd circle
			(at 2.035302 -4.2291 180)
			(size 0.381 0.381)
			(layers "F.Cu" "F.Mask" "F.Paste")
			(net "P1V05_PCH_PLL_AUX")
		)
		(pad "R29" smd circle
			(at 3.663188 -4.2291 180)
			(size 0.381 0.381)
			(layers "F.Cu" "F.Mask" "F.Paste")
			(net "P1V05_PCH_PLL_AUX")
		)
		(pad "R32" smd circle
			(at 5.291582 -4.2291 180)
			(size 0.381 0.381)
			(layers "F.Cu" "F.Mask" "F.Paste")
			(net "TP_P3E_PCH_14_TX_DN")
		)
		(pad "R36" smd circle
			(at 6.919722 -4.2291 180)
			(size 0.381 0.381)
			(layers "F.Cu" "F.Mask" "F.Paste")
			(net "GND")
		)
		(pad "R40" smd circle
			(at 9.069832 -4.002024 180)
			(size 0.3048 0.3048)
			(layers "F.Cu" "F.Mask" "F.Paste")
			(net "USB3_PCH_RX_BUF_DN<4>")
		)
		(pad "R42" smd circle
			(at 9.899904 -4.002024 180)
			(size 0.3048 0.3048)
			(layers "F.Cu" "F.Mask" "F.Paste")
			(net "USB3_PCH_RX_BUF_DP<4>")
		)
		(pad "T8" smd circle
			(at -6.919722 -3.7592 180)
			(size 0.381 0.381)
			(layers "F.Cu" "F.Mask" "F.Paste")
			(net "PD_GPP_M_15")
		)
		(pad "T11" smd circle
			(at -5.291582 -3.7592 180)
			(size 0.381 0.381)
			(layers "F.Cu" "F.Mask" "F.Paste")
			(net "TP_PCH_GPP_N_1")
		)
		(pad "T15" smd circle
			(at -3.663188 -3.7592 180)
			(size 0.381 0.381)
			(layers "F.Cu" "F.Mask" "F.Paste")
			(net "P3V3_AUX")
		)
		(pad "T31" smd circle
			(at 4.477512 -3.7592 180)
			(size 0.381 0.381)
			(layers "F.Cu" "F.Mask" "F.Paste")
			(net "GND")
		)
		(pad "T34" smd circle
			(at 6.105398 -3.7592 180)
			(size 0.381 0.381)
			(layers "F.Cu" "F.Mask" "F.Paste")
			(net "TP_P3E_PCH_14_TX_DP")
		)
		(pad "T37" smd circle
			(at 7.733792 -3.7592 180)
			(size 0.381 0.381)
			(layers "F.Cu" "F.Mask" "F.Paste")
			(net "P3E_PCH_NVS_TX_DN<1>")
		)
		(pad "U1" smd oval
			(at -10.31494 -3.501644 270)
			(size 0.254 0.3302)
			(layers "F.Cu" "F.Mask" "F.Paste")
			(net "PD_GPP_I_16")
		)
		(pad "U3" smd circle
			(at -9.484868 -3.501644 180)
			(size 0.3048 0.3048)
			(layers "F.Cu" "F.Mask" "F.Paste")
			(net "FM_PCH_BMC_RST_R_N")
		)
		(pad "U5" smd circle
			(at -8.654796 -3.501644 180)
			(size 0.3048 0.3048)
			(layers "F.Cu" "F.Mask" "F.Paste")
			(net "GND")
		)
		(pad "U7" smd circle
			(at -7.733792 -3.2893 180)
			(size 0.381 0.381)
			(layers "F.Cu" "F.Mask" "F.Paste")
			(net "TP_GPP_M_12")
		)
		(pad "U10" smd circle
			(at -6.105398 -3.2893 180)
			(size 0.381 0.381)
			(layers "F.Cu" "F.Mask" "F.Paste")
			(net "GND")
		)
		(pad "U13" smd circle
			(at -4.477512 -3.2893 180)
			(size 0.381 0.381)
			(layers "F.Cu" "F.Mask" "F.Paste")
			(net "GND")
		)
		(pad "U17" smd circle
			(at -2.4003 -3.2004 180)
			(size 0.381 0.381)
			(layers "F.Cu" "F.Mask" "F.Paste")
			(net "P1V8_PCH_AUX")
		)
		(pad "U19" smd circle
			(at -1.6002 -3.2004 180)
			(size 0.381 0.381)
			(layers "F.Cu" "F.Mask" "F.Paste")
			(net "P1V8_PCH_AUX")
		)
		(pad "U20" smd circle
			(at -0.8001 -3.2004 180)
			(size 0.381 0.381)
			(layers "F.Cu" "F.Mask" "F.Paste")
			(net "P1V8_PCH_AUX")
		)
		(pad "U22" smd circle
			(at 0 -3.2004 180)
			(size 0.381 0.381)
			(layers "F.Cu" "F.Mask" "F.Paste")
			(net "P1V8_PCH_AUX")
		)
		(pad "U24" smd circle
			(at 0.8001 -3.2004 180)
			(size 0.381 0.381)
			(layers "F.Cu" "F.Mask" "F.Paste")
			(net "P1V8_PCH_AUX")
		)
		(pad "U25" smd circle
			(at 1.6002 -3.2004 180)
			(size 0.381 0.381)
			(layers "F.Cu" "F.Mask" "F.Paste")
			(net "GND")
		)
		(pad "U27" smd circle
			(at 2.4003 -3.2004 180)
			(size 0.381 0.381)
			(layers "F.Cu" "F.Mask" "F.Paste")
			(net "P1V05_PCH_PLL_AUX")
		)
		(pad "U29" smd circle
			(at 3.663188 -3.2893 180)
			(size 0.381 0.381)
			(layers "F.Cu" "F.Mask" "F.Paste")
			(net "P1V8_PCH_PLL_AUX")
		)
		(pad "U32" smd circle
			(at 5.291582 -3.2893 180)
			(size 0.381 0.381)
			(layers "F.Cu" "F.Mask" "F.Paste")
			(net "TP_P3E_PCH_13_TX_DN")
		)
		(pad "U36" smd circle
			(at 6.919722 -3.2893 180)
			(size 0.381 0.381)
			(layers "F.Cu" "F.Mask" "F.Paste")
			(net "TP_P3E_PCH_12_TX_DP")
		)
		(pad "U39" smd circle
			(at 8.654796 -3.501644 180)
			(size 0.3048 0.3048)
			(layers "F.Cu" "F.Mask" "F.Paste")
			(net "GND")
		)
		(pad "U41" smd circle
			(at 9.484868 -3.501644 180)
			(size 0.3048 0.3048)
			(layers "F.Cu" "F.Mask" "F.Paste")
			(net "P3E_PCH_BMC_RX_DN")
		)
		(pad "U43" smd oval
			(at 10.31494 -3.501644 270)
			(size 0.254 0.3302)
			(layers "F.Cu" "F.Mask" "F.Paste")
			(net "P3E_PCH_BMC_RX_DP")
		)
		(pad "V2" smd circle
			(at -9.899904 -3.001518 180)
			(size 0.3048 0.3048)
			(layers "F.Cu" "F.Mask" "F.Paste")
			(net "GND")
		)
		(pad "V4" smd circle
			(at -9.069832 -3.001518 180)
			(size 0.3048 0.3048)
			(layers "F.Cu" "F.Mask" "F.Paste")
			(net "PD_GPP_I_17")
		)
		(pad "V8" smd circle
			(at -6.919722 -2.8194 180)
			(size 0.381 0.381)
			(layers "F.Cu" "F.Mask" "F.Paste")
			(net "FM_BOARD_SKU_ID2")
		)
		(pad "V11" smd circle
			(at -5.291582 -2.8194 180)
			(size 0.381 0.381)
			(layers "F.Cu" "F.Mask" "F.Paste")
			(net "TP_PCH_GPP_N_4")
		)
		(pad "V15" smd circle
			(at -3.663188 -2.8194 180)
			(size 0.381 0.381)
			(layers "F.Cu" "F.Mask" "F.Paste")
			(net "P3V3_AUX")
		)
		(pad "V31" smd circle
			(at 4.477512 -2.8194 180)
			(size 0.381 0.381)
			(layers "F.Cu" "F.Mask" "F.Paste")
			(net "GND")
		)
		(pad "V34" smd circle
			(at 6.105398 -2.8194 180)
			(size 0.381 0.381)
			(layers "F.Cu" "F.Mask" "F.Paste")
			(net "TP_P3E_PCH_12_TX_DN")
		)
		(pad "V37" smd circle
			(at 7.733792 -2.8194 180)
			(size 0.381 0.381)
			(layers "F.Cu" "F.Mask" "F.Paste")
			(net "P3E_PCH_NVS_TX_DP<1>")
		)
		(pad "V40" smd circle
			(at 9.069832 -3.001518 180)
			(size 0.3048 0.3048)
			(layers "F.Cu" "F.Mask" "F.Paste")
			(net "P3E_PCH_E1S_RX_DN<3>")
		)
		(pad "V42" smd circle
			(at 9.899904 -3.001518 180)
			(size 0.3048 0.3048)
			(layers "F.Cu" "F.Mask" "F.Paste")
			(net "P3E_PCH_E1S_RX_DP<3>")
		)
		(pad "W1" smd oval
			(at -10.31494 -2.501138 270)
			(size 0.254 0.3302)
			(layers "F.Cu" "F.Mask" "F.Paste")
			(net "FM_PCH_BOOT_BIOS_STRAP")
		)
		(pad "W3" smd circle
			(at -9.484868 -2.501138 180)
			(size 0.3048 0.3048)
			(layers "F.Cu" "F.Mask" "F.Paste")
			(net "GND")
		)
		(pad "W5" smd circle
			(at -8.654796 -2.501138 180)
			(size 0.3048 0.3048)
			(layers "F.Cu" "F.Mask" "F.Paste")
			(net "GND")
		)
		(pad "W7" smd circle
			(at -7.733792 -2.3495 180)
			(size 0.381 0.381)
			(layers "F.Cu" "F.Mask" "F.Paste")
			(net "FM_BOARD_SKU_ID1")
		)
		(pad "W10" smd circle
			(at -6.105398 -2.3495 180)
			(size 0.381 0.381)
			(layers "F.Cu" "F.Mask" "F.Paste")
			(net "PD_GPP_M_8")
		)
		(pad "W13" smd circle
			(at -4.477512 -2.3495 180)
			(size 0.381 0.381)
			(layers "F.Cu" "F.Mask" "F.Paste")
			(net "PD_GPP_M_17")
		)
		(pad "W17" smd circle
			(at -2.4003 -2.4003 180)
			(size 0.381 0.381)
			(layers "F.Cu" "F.Mask" "F.Paste")
			(net "P1V05_PCH_AUX")
		)
		(pad "W19" smd circle
			(at -1.6002 -2.4003 180)
			(size 0.381 0.381)
			(layers "F.Cu" "F.Mask" "F.Paste")
			(net "P1V05_PCH_AUX")
		)
		(pad "W20" smd circle
			(at -0.8001 -2.4003 180)
			(size 0.381 0.381)
			(layers "F.Cu" "F.Mask" "F.Paste")
			(net "P1V05_PCH_AUX")
		)
		(pad "W22" smd circle
			(at 0 -2.4003 180)
			(size 0.381 0.381)
			(layers "F.Cu" "F.Mask" "F.Paste")
			(net "P1V05_PCH_AUX")
		)
		(pad "W24" smd circle
			(at 0.8001 -2.4003 180)
			(size 0.381 0.381)
			(layers "F.Cu" "F.Mask" "F.Paste")
			(net "P1V05_PCH_AUX")
		)
		(pad "W25" smd circle
			(at 1.6002 -2.4003 180)
			(size 0.381 0.381)
			(layers "F.Cu" "F.Mask" "F.Paste")
			(net "GND")
		)
		(pad "W27" smd circle
			(at 2.4003 -2.4003 180)
			(size 0.381 0.381)
			(layers "F.Cu" "F.Mask" "F.Paste")
			(net "P1V8_PCH_PLL_AUX")
		)
		(pad "W29" smd circle
			(at 3.663188 -2.3495 180)
			(size 0.381 0.381)
			(layers "F.Cu" "F.Mask" "F.Paste")
			(net "P1V8_PCH_PLL_AUX")
		)
		(pad "W32" smd circle
			(at 5.291582 -2.3495 180)
			(size 0.381 0.381)
			(layers "F.Cu" "F.Mask" "F.Paste")
			(net "TP_P3E_PCH_13_TX_DP")
		)
		(pad "W36" smd circle
			(at 6.919722 -2.3495 180)
			(size 0.381 0.381)
			(layers "F.Cu" "F.Mask" "F.Paste")
			(net "P3E_PCH_NVS_TX_DN<0>")
		)
		(pad "W39" smd circle
			(at 8.654796 -2.501138 180)
			(size 0.3048 0.3048)
			(layers "F.Cu" "F.Mask" "F.Paste")
			(net "GND")
		)
		(pad "W41" smd circle
			(at 9.484868 -2.501138 180)
			(size 0.3048 0.3048)
			(layers "F.Cu" "F.Mask" "F.Paste")
			(net "P3E_PCH_E1S_RX_DN<2>")
		)
		(pad "W43" smd oval
			(at 10.31494 -2.501138 270)
			(size 0.254 0.3302)
			(layers "F.Cu" "F.Mask" "F.Paste")
			(net "P3E_PCH_E1S_RX_DP<2>")
		)
		(pad "Y2" smd circle
			(at -9.899904 -2.001012 180)
			(size 0.3048 0.3048)
			(layers "F.Cu" "F.Mask" "F.Paste")
			(net "FM_PLT_BMC_THERMTRIP_R_N")
		)
		(pad "Y4" smd circle
			(at -9.069832 -2.001012 180)
			(size 0.3048 0.3048)
			(layers "F.Cu" "F.Mask" "F.Paste")
			(net "FM_BIOS_IMAGE_SWAP_N")
		)
		(pad "Y8" smd circle
			(at -6.919722 -1.8796 180)
			(size 0.381 0.381)
			(layers "F.Cu" "F.Mask" "F.Paste")
			(net "GND")
		)
		(pad "Y11" smd circle
			(at -5.291582 -1.8796 180)
			(size 0.381 0.381)
			(layers "F.Cu" "F.Mask" "F.Paste")
			(net "GND")
		)
		(pad "Y15" smd circle
			(at -3.663188 -1.8796 180)
			(size 0.381 0.381)
			(layers "F.Cu" "F.Mask" "F.Paste")
			(net "GND")
		)
		(pad "Y31" smd circle
			(at 4.477512 -1.8796 180)
			(size 0.381 0.381)
			(layers "F.Cu" "F.Mask" "F.Paste")
			(net "GND")
		)
		(pad "Y34" smd circle
			(at 6.105398 -1.8796 180)
			(size 0.381 0.381)
			(layers "F.Cu" "F.Mask" "F.Paste")
			(net "GND")
		)
		(pad "Y37" smd circle
			(at 7.733792 -1.8796 180)
			(size 0.381 0.381)
			(layers "F.Cu" "F.Mask" "F.Paste")
			(net "P3E_PCH_NVS_TX_DP<0>")
		)
		(pad "Y40" smd circle
			(at 9.069832 -2.001012 180)
			(size 0.3048 0.3048)
			(layers "F.Cu" "F.Mask" "F.Paste")
			(net "P3E_PCH_E1S_RX_DN<1>")
		)
		(pad "Y42" smd circle
			(at 9.899904 -2.001012 180)
			(size 0.3048 0.3048)
			(layers "F.Cu" "F.Mask" "F.Paste")
			(net "P3E_PCH_E1S_RX_DP<1>")
		)
		(zone
			(layer "F.Cu")
			(hatch none 0.5)
			(connect_pads
				(clearance 0)
			)
			(min_thickness 0.25)
			(keepout
				(tracks not_allowed)
				(vias allowed)
				(pads allowed)
				(copperpour not_allowed)
				(footprints allowed)
			)
			(placement
				(enabled no)
				(sheetname "")
			)
			(fill
				(thermal_gap 0.5)
				(thermal_bridge_width 0.5)
				(island_removal_mode 0)
			)
			(polygon
				(pts
					(arc
						(start 326.623426 -55.825136)
						(mid 326.666766 -55.832672)
						(end 326.704452 -55.855362)
					)
					(xy 326.704452 -55.723536) (xy 326.465184 -55.723536)
					(arc
						(start 326.465184 -55.854854)
						(mid 326.503032 -55.832362)
						(end 326.546464 -55.825136)
					)
				)
			)
		)
		(zone
			(layer "F.Cu")
			(hatch none 0.5)
			(connect_pads
				(clearance 0)
			)
			(min_thickness 0.25)
			(keepout
				(tracks not_allowed)
				(vias allowed)
				(pads allowed)
				(copperpour not_allowed)
				(footprints allowed)
			)
			(placement
				(enabled no)
				(sheetname "")
			)
			(fill
				(thermal_gap 0.5)
				(thermal_bridge_width 0.5)
				(island_removal_mode 0)
			)
			(polygon
				(pts
					(arc
						(start 326.623426 -54.82463)
						(mid 326.666766 -54.832166)
						(end 326.704452 -54.854856)
					)
					(xy 326.704452 -54.72303) (xy 326.465184 -54.72303)
					(arc
						(start 326.465184 -54.854348)
						(mid 326.503032 -54.831856)
						(end 326.546464 -54.82463)
					)
				)
			)
		)
		(zone
			(layer "F.Cu")
			(hatch none 0.5)
			(connect_pads
				(clearance 0)
			)
			(min_thickness 0.25)
			(keepout
				(tracks not_allowed)
				(vias allowed)
				(pads allowed)
				(copperpour not_allowed)
				(footprints allowed)
			)
			(placement
				(enabled no)
				(sheetname "")
			)
			(fill
				(thermal_gap 0.5)
				(thermal_bridge_width 0.5)
				(island_removal_mode 0)
			)
			(polygon
				(pts
					(arc
						(start 326.623426 -53.824124)
						(mid 326.666766 -53.83166)
						(end 326.704452 -53.85435)
					)
					(xy 326.704452 -53.722524) (xy 326.465184 -53.722524)
					(arc
						(start 326.465184 -53.853842)
						(mid 326.503032 -53.83135)
						(end 326.546464 -53.824124)
					)
				)
			)
		)
		(zone
			(layer "F.Cu")
			(hatch none 0.5)
			(connect_pads
				(clearance 0)
			)
			(min_thickness 0.25)
			(keepout
				(tracks not_allowed)
				(vias allowed)
				(pads allowed)
				(copperpour not_allowed)
				(footprints allowed)
			)
			(placement
				(enabled no)
				(sheetname "")
			)
			(fill
				(thermal_gap 0.5)
				(thermal_bridge_width 0.5)
				(island_removal_mode 0)
			)
			(polygon
				(pts
					(arc
						(start 326.623426 -52.823872)
						(mid 326.666734 -52.831298)
						(end 326.704452 -52.853844)
					)
					(xy 326.704452 -52.722272) (xy 326.465184 -52.722272)
					(arc
						(start 326.465184 -52.853336)
						(mid 326.503057 -52.830971)
						(end 326.546464 -52.823872)
					)
				)
			)
		)
		(zone
			(layer "F.Cu")
			(hatch none 0.5)
			(connect_pads
				(clearance 0)
			)
			(min_thickness 0.25)
			(keepout
				(tracks not_allowed)
				(vias allowed)
				(pads allowed)
				(copperpour not_allowed)
				(footprints allowed)
			)
			(placement
				(enabled no)
				(sheetname "")
			)
			(fill
				(thermal_gap 0.5)
				(thermal_bridge_width 0.5)
				(island_removal_mode 0)
			)
			(polygon
				(pts
					(arc
						(start 326.623426 -51.823366)
						(mid 326.666734 -51.830792)
						(end 326.704452 -51.853338)
					)
					(xy 326.704452 -51.721766) (xy 326.465184 -51.721766)
					(arc
						(start 326.465184 -51.85283)
						(mid 326.503057 -51.830465)
						(end 326.546464 -51.823366)
					)
				)
			)
		)
		(zone
			(layer "F.Cu")
			(hatch none 0.5)
			(connect_pads
				(clearance 0)
			)
			(min_thickness 0.25)
			(keepout
				(tracks not_allowed)
				(vias allowed)
				(pads allowed)
				(copperpour not_allowed)
				(footprints allowed)
			)
			(placement
				(enabled no)
				(sheetname "")
			)
			(fill
				(thermal_gap 0.5)
				(thermal_bridge_width 0.5)
				(island_removal_mode 0)
			)
			(polygon
				(pts
					(arc
						(start 326.623426 -50.82286)
						(mid 326.666734 -50.830286)
						(end 326.704452 -50.852832)
					)
					(xy 326.704452 -50.72126) (xy 326.465184 -50.72126)
					(arc
						(start 326.465184 -50.852324)
						(mid 326.503057 -50.829959)
						(end 326.546464 -50.82286)
					)
				)
			)
		)
		(zone
			(layer "F.Cu")
			(hatch none 0.5)
			(connect_pads
				(clearance 0)
			)
			(min_thickness 0.25)
			(keepout
				(tracks not_allowed)
				(vias allowed)
				(pads allowed)
				(copperpour not_allowed)
				(footprints allowed)
			)
			(placement
				(enabled no)
				(sheetname "")
			)
			(fill
				(thermal_gap 0.5)
				(thermal_bridge_width 0.5)
				(island_removal_mode 0)
			)
			(polygon
				(pts
					(arc
						(start 326.623426 -49.822354)
						(mid 326.666734 -49.82978)
						(end 326.704452 -49.852326)
					)
					(xy 326.704452 -49.720754) (xy 326.465184 -49.720754)
					(arc
						(start 326.465184 -49.852072)
						(mid 326.503032 -49.82958)
						(end 326.546464 -49.822354)
					)
				)
			)
		)
		(zone
			(layer "F.Cu")
			(hatch none 0.5)
			(connect_pads
				(clearance 0)
			)
			(min_thickness 0.25)
			(keepout
				(tracks not_allowed)
				(vias allowed)
				(pads allowed)
				(copperpour not_allowed)
				(footprints allowed)
			)
			(placement
				(enabled no)
				(sheetname "")
			)
			(fill
				(thermal_gap 0.5)
				(thermal_bridge_width 0.5)
				(island_removal_mode 0)
			)
			(polygon
				(pts
					(arc
						(start 326.623426 -48.821848)
						(mid 326.666734 -48.829274)
						(end 326.704452 -48.85182)
					)
					(xy 326.704452 -48.720248) (xy 326.465184 -48.720248)
					(arc
						(start 326.465184 -48.851566)
						(mid 326.503032 -48.829074)
						(end 326.546464 -48.821848)
					)
				)
			)
		)
		(zone
			(layer "F.Cu")
			(hatch none 0.5)
			(connect_pads
				(clearance 0)
			)
			(min_thickness 0.25)
			(keepout
				(tracks not_allowed)
				(vias allowed)
				(pads allowed)
				(copperpour not_allowed)
				(footprints allowed)
			)
			(placement
				(enabled no)
				(sheetname "")
			)
			(fill
				(thermal_gap 0.5)
				(thermal_bridge_width 0.5)
				(island_removal_mode 0)
			)
			(polygon
				(pts
					(arc
						(start 326.623426 -47.821342)
						(mid 326.666766 -47.828878)
						(end 326.704452 -47.851568)
					)
					(xy 326.704452 -47.719742) (xy 326.465184 -47.719742)
					(arc
						(start 326.465184 -47.85106)
						(mid 326.503032 -47.828568)
						(end 326.546464 -47.821342)
					)
				)
			)
		)
		(zone
			(layer "F.Cu")
			(hatch none 0.5)
			(connect_pads
				(clearance 0)
			)
			(min_thickness 0.25)
			(keepout
				(tracks not_allowed)
				(vias allowed)
				(pads allowed)
				(copperpour not_allowed)
				(footprints allowed)
			)
			(placement
				(enabled no)
				(sheetname "")
			)
			(fill
				(thermal_gap 0.5)
				(thermal_bridge_width 0.5)
				(island_removal_mode 0)
			)
			(polygon
				(pts
					(arc
						(start 326.623426 -46.820836)
						(mid 326.666766 -46.828372)
						(end 326.704452 -46.851062)
					)
					(xy 326.704452 -46.719236) (xy 326.465184 -46.719236)
					(arc
						(start 326.465184 -46.850554)
						(mid 326.503032 -46.828062)
						(end 326.546464 -46.820836)
					)
				)
			)
		)
		(zone
			(layer "F.Cu")
			(hatch none 0.5)
			(connect_pads
				(clearance 0)
			)
			(min_thickness 0.25)
			(keepout
				(tracks not_allowed)
				(vias allowed)
				(pads allowed)
				(copperpour not_allowed)
				(footprints allowed)
			)
			(placement
				(enabled no)
				(sheetname "")
			)
			(fill
				(thermal_gap 0.5)
				(thermal_bridge_width 0.5)
				(island_removal_mode 0)
			)
			(polygon
				(pts
					(arc
						(start 326.623426 -45.82033)
						(mid 326.666766 -45.827866)
						(end 326.704452 -45.850556)
					)
					(xy 326.704452 -45.71873) (xy 326.465184 -45.71873)
					(arc
						(start 326.465184 -45.850048)
						(mid 326.503032 -45.827556)
						(end 326.546464 -45.82033)
					)
				)
			)
		)
		(zone
			(layer "F.Cu")
			(hatch none 0.5)
			(connect_pads
				(clearance 0)
			)
			(min_thickness 0.25)
			(keepout
				(tracks not_allowed)
				(vias allowed)
				(pads allowed)
				(copperpour not_allowed)
				(footprints allowed)
			)
			(placement
				(enabled no)
				(sheetname "")
			)
			(fill
				(thermal_gap 0.5)
				(thermal_bridge_width 0.5)
				(island_removal_mode 0)
			)
			(polygon
				(pts
					(arc
						(start 326.623426 -44.819824)
						(mid 326.666766 -44.82736)
						(end 326.704452 -44.85005)
					)
					(xy 326.704452 -44.718224) (xy 326.465184 -44.718224)
					(arc
						(start 326.465184 -44.849542)
						(mid 326.503032 -44.82705)
						(end 326.546464 -44.819824)
					)
				)
			)
		)
		(zone
			(layer "F.Cu")
			(hatch none 0.5)
			(connect_pads
				(clearance 0)
			)
			(min_thickness 0.25)
			(keepout
				(tracks not_allowed)
				(vias allowed)
				(pads allowed)
				(copperpour not_allowed)
				(footprints allowed)
			)
			(placement
				(enabled no)
				(sheetname "")
			)
			(fill
				(thermal_gap 0.5)
				(thermal_bridge_width 0.5)
				(island_removal_mode 0)
			)
			(polygon
				(pts
					(arc
						(start 326.623426 -43.819572)
						(mid 326.666734 -43.826998)
						(end 326.704452 -43.849544)
					)
					(xy 326.704452 -43.717972) (xy 326.465184 -43.717972)
					(arc
						(start 326.465184 -43.849036)
						(mid 326.503057 -43.826671)
						(end 326.546464 -43.819572)
					)
				)
			)
		)
		(zone
			(layer "F.Cu")
			(hatch none 0.5)
			(connect_pads
				(clearance 0)
			)
			(min_thickness 0.25)
			(keepout
				(tracks not_allowed)
				(vias allowed)
				(pads allowed)
				(copperpour not_allowed)
				(footprints allowed)
			)
			(placement
				(enabled no)
				(sheetname "")
			)
			(fill
				(thermal_gap 0.5)
				(thermal_bridge_width 0.5)
				(island_removal_mode 0)
			)
			(polygon
				(pts
					(arc
						(start 326.623426 -42.819066)
						(mid 326.666734 -42.826492)
						(end 326.704452 -42.849038)
					)
					(xy 326.704452 -42.717466) (xy 326.465184 -42.717466)
					(arc
						(start 326.465184 -42.84853)
						(mid 326.503057 -42.826165)
						(end 326.546464 -42.819066)
					)
				)
			)
		)
		(zone
			(layer "F.Cu")
			(hatch none 0.5)
			(connect_pads
				(clearance 0)
			)
			(min_thickness 0.25)
			(keepout
				(tracks not_allowed)
				(vias allowed)
				(pads allowed)
				(copperpour not_allowed)
				(footprints allowed)
			)
			(placement
				(enabled no)
				(sheetname "")
			)
			(fill
				(thermal_gap 0.5)
				(thermal_bridge_width 0.5)
				(island_removal_mode 0)
			)
			(polygon
				(pts
					(arc
						(start 326.623426 -41.81856)
						(mid 326.666734 -41.825986)
						(end 326.704452 -41.848532)
					)
					(xy 326.704452 -41.71696) (xy 326.465184 -41.71696)
					(arc
						(start 326.465184 -41.848024)
						(mid 326.503057 -41.825659)
						(end 326.546464 -41.81856)
					)
				)
			)
		)
		(zone
			(layer "F.Cu")
			(hatch none 0.5)
			(connect_pads
				(clearance 0)
			)
			(min_thickness 0.25)
			(keepout
				(tracks not_allowed)
				(vias allowed)
				(pads allowed)
				(copperpour not_allowed)
				(footprints allowed)
			)
			(placement
				(enabled no)
				(sheetname "")
			)
			(fill
				(thermal_gap 0.5)
				(thermal_bridge_width 0.5)
				(island_removal_mode 0)
			)
			(polygon
				(pts
					(arc
						(start 326.623426 -40.818054)
						(mid 326.666734 -40.82548)
						(end 326.704452 -40.848026)
					)
					(xy 326.704452 -40.716454) (xy 326.465184 -40.716454)
					(arc
						(start 326.465184 -40.847518)
						(mid 326.503057 -40.825153)
						(end 326.546464 -40.818054)
					)
				)
			)
		)
		(zone
			(layer "F.Cu")
			(hatch none 0.5)
			(connect_pads
				(clearance 0)
			)
			(min_thickness 0.25)
			(keepout
				(tracks not_allowed)
				(vias allowed)
				(pads allowed)
				(copperpour not_allowed)
				(footprints allowed)
			)
			(placement
				(enabled no)
				(sheetname "")
			)
			(fill
				(thermal_gap 0.5)
				(thermal_bridge_width 0.5)
				(island_removal_mode 0)
			)
			(polygon
				(pts
					(xy 326.704452 -56.183784)
					(arc
						(start 326.704452 -56.052466)
						(mid 326.666604 -56.074958)
						(end 326.623172 -56.082184)
					)
					(arc
						(start 326.54621 -56.082184)
						(mid 326.50287 -56.074648)
						(end 326.465184 -56.051958)
					)
					(xy 326.465184 -56.183784)
				)
			)
		)
		(zone
			(layer "F.Cu")
			(hatch none 0.5)
			(connect_pads
				(clearance 0)
			)
			(min_thickness 0.25)
			(keepout
				(tracks not_allowed)
				(vias allowed)
				(pads allowed)
				(copperpour not_allowed)
				(footprints allowed)
			)
			(placement
				(enabled no)
				(sheetname "")
			)
			(fill
				(thermal_gap 0.5)
				(thermal_bridge_width 0.5)
				(island_removal_mode 0)
			)
			(polygon
				(pts
					(xy 326.704452 -55.183278)
					(arc
						(start 326.704452 -55.05196)
						(mid 326.666604 -55.074452)
						(end 326.623172 -55.081678)
					)
					(arc
						(start 326.54621 -55.081678)
						(mid 326.50287 -55.074142)
						(end 326.465184 -55.051452)
					)
					(xy 326.465184 -55.183278)
				)
			)
		)
		(zone
			(layer "F.Cu")
			(hatch none 0.5)
			(connect_pads
				(clearance 0)
			)
			(min_thickness 0.25)
			(keepout
				(tracks not_allowed)
				(vias allowed)
				(pads allowed)
				(copperpour not_allowed)
				(footprints allowed)
			)
			(placement
				(enabled no)
				(sheetname "")
			)
			(fill
				(thermal_gap 0.5)
				(thermal_bridge_width 0.5)
				(island_removal_mode 0)
			)
			(polygon
				(pts
					(xy 326.704452 -54.182772)
					(arc
						(start 326.704452 -54.051454)
						(mid 326.666604 -54.073946)
						(end 326.623172 -54.081172)
					)
					(arc
						(start 326.54621 -54.081172)
						(mid 326.50287 -54.073636)
						(end 326.465184 -54.050946)
					)
					(xy 326.465184 -54.182772)
				)
			)
		)
		(zone
			(layer "F.Cu")
			(hatch none 0.5)
			(connect_pads
				(clearance 0)
			)
			(min_thickness 0.25)
			(keepout
				(tracks not_allowed)
				(vias allowed)
				(pads allowed)
				(copperpour not_allowed)
				(footprints allowed)
			)
			(placement
				(enabled no)
				(sheetname "")
			)
			(fill
				(thermal_gap 0.5)
				(thermal_bridge_width 0.5)
				(island_removal_mode 0)
			)
			(polygon
				(pts
					(xy 326.704452 -53.182266)
					(arc
						(start 326.704452 -53.051202)
						(mid 326.666579 -53.073567)
						(end 326.623172 -53.080666)
					)
					(arc
						(start 326.54621 -53.080666)
						(mid 326.502902 -53.07324)
						(end 326.465184 -53.050694)
					)
					(xy 326.465184 -53.182266)
				)
			)
		)
		(zone
			(layer "F.Cu")
			(hatch none 0.5)
			(connect_pads
				(clearance 0)
			)
			(min_thickness 0.25)
			(keepout
				(tracks not_allowed)
				(vias allowed)
				(pads allowed)
				(copperpour not_allowed)
				(footprints allowed)
			)
			(placement
				(enabled no)
				(sheetname "")
			)
			(fill
				(thermal_gap 0.5)
				(thermal_bridge_width 0.5)
				(island_removal_mode 0)
			)
			(polygon
				(pts
					(xy 326.704452 -52.18176)
					(arc
						(start 326.704452 -52.050696)
						(mid 326.666579 -52.073061)
						(end 326.623172 -52.08016)
					)
					(arc
						(start 326.54621 -52.08016)
						(mid 326.502902 -52.072734)
						(end 326.465184 -52.050188)
					)
					(xy 326.465184 -52.18176)
				)
			)
		)
		(zone
			(layer "F.Cu")
			(hatch none 0.5)
			(connect_pads
				(clearance 0)
			)
			(min_thickness 0.25)
			(keepout
				(tracks not_allowed)
				(vias allowed)
				(pads allowed)
				(copperpour not_allowed)
				(footprints allowed)
			)
			(placement
				(enabled no)
				(sheetname "")
			)
			(fill
				(thermal_gap 0.5)
				(thermal_bridge_width 0.5)
				(island_removal_mode 0)
			)
			(polygon
				(pts
					(xy 326.704452 -51.181254)
					(arc
						(start 326.704452 -51.05019)
						(mid 326.666579 -51.072555)
						(end 326.623172 -51.079654)
					)
					(arc
						(start 326.54621 -51.079654)
						(mid 326.502902 -51.072228)
						(end 326.465184 -51.049682)
					)
					(xy 326.465184 -51.181254)
				)
			)
		)
		(zone
			(layer "F.Cu")
			(hatch none 0.5)
			(connect_pads
				(clearance 0)
			)
			(min_thickness 0.25)
			(keepout
				(tracks not_allowed)
				(vias allowed)
				(pads allowed)
				(copperpour not_allowed)
				(footprints allowed)
			)
			(placement
				(enabled no)
				(sheetname "")
			)
			(fill
				(thermal_gap 0.5)
				(thermal_bridge_width 0.5)
				(island_removal_mode 0)
			)
			(polygon
				(pts
					(xy 326.704452 -50.180748)
					(arc
						(start 326.704452 -50.049684)
						(mid 326.666579 -50.072049)
						(end 326.623172 -50.079148)
					)
					(arc
						(start 326.54621 -50.079148)
						(mid 326.502902 -50.071722)
						(end 326.465184 -50.049176)
					)
					(xy 326.465184 -50.180748)
				)
			)
		)
		(zone
			(layer "F.Cu")
			(hatch none 0.5)
			(connect_pads
				(clearance 0)
			)
			(min_thickness 0.25)
			(keepout
				(tracks not_allowed)
				(vias allowed)
				(pads allowed)
				(copperpour not_allowed)
				(footprints allowed)
			)
			(placement
				(enabled no)
				(sheetname "")
			)
			(fill
				(thermal_gap 0.5)
				(thermal_bridge_width 0.5)
				(island_removal_mode 0)
			)
			(polygon
				(pts
					(xy 326.704452 -49.180242)
					(arc
						(start 326.704452 -49.049178)
						(mid 326.666579 -49.071543)
						(end 326.623172 -49.078642)
					)
					(arc
						(start 326.54621 -49.078642)
						(mid 326.502902 -49.071216)
						(end 326.465184 -49.04867)
					)
					(xy 326.465184 -49.180242)
				)
			)
		)
		(zone
			(layer "F.Cu")
			(hatch none 0.5)
			(connect_pads
				(clearance 0)
			)
			(min_thickness 0.25)
			(keepout
				(tracks not_allowed)
				(vias allowed)
				(pads allowed)
				(copperpour not_allowed)
				(footprints allowed)
			)
			(placement
				(enabled no)
				(sheetname "")
			)
			(fill
				(thermal_gap 0.5)
				(thermal_bridge_width 0.5)
				(island_removal_mode 0)
			)
			(polygon
				(pts
					(xy 326.704452 -48.179736)
					(arc
						(start 326.704452 -48.048672)
						(mid 326.666579 -48.071037)
						(end 326.623172 -48.078136)
					)
					(arc
						(start 326.54621 -48.078136)
						(mid 326.502902 -48.07071)
						(end 326.465184 -48.048164)
					)
					(xy 326.465184 -48.179736)
				)
			)
		)
		(zone
			(layer "F.Cu")
			(hatch none 0.5)
			(connect_pads
				(clearance 0)
			)
			(min_thickness 0.25)
			(keepout
				(tracks not_allowed)
				(vias allowed)
				(pads allowed)
				(copperpour not_allowed)
				(footprints allowed)
			)
			(placement
				(enabled no)
				(sheetname "")
			)
			(fill
				(thermal_gap 0.5)
				(thermal_bridge_width 0.5)
				(island_removal_mode 0)
			)
			(polygon
				(pts
					(xy 326.704452 -47.17923)
					(arc
						(start 326.704452 -47.048166)
						(mid 326.666579 -47.070531)
						(end 326.623172 -47.07763)
					)
					(arc
						(start 326.54621 -47.07763)
						(mid 326.502902 -47.070204)
						(end 326.465184 -47.047658)
					)
					(xy 326.465184 -47.17923)
				)
			)
		)
		(zone
			(layer "F.Cu")
			(hatch none 0.5)
			(connect_pads
				(clearance 0)
			)
			(min_thickness 0.25)
			(keepout
				(tracks not_allowed)
				(vias allowed)
				(pads allowed)
				(copperpour not_allowed)
				(footprints allowed)
			)
			(placement
				(enabled no)
				(sheetname "")
			)
			(fill
				(thermal_gap 0.5)
				(thermal_bridge_width 0.5)
				(island_removal_mode 0)
			)
			(polygon
				(pts
					(xy 326.704452 -46.178724)
					(arc
						(start 326.704452 -46.04766)
						(mid 326.666579 -46.070025)
						(end 326.623172 -46.077124)
					)
					(arc
						(start 326.54621 -46.077124)
						(mid 326.502902 -46.069698)
						(end 326.465184 -46.047152)
					)
					(xy 326.465184 -46.178724)
				)
			)
		)
		(zone
			(layer "F.Cu")
			(hatch none 0.5)
			(connect_pads
				(clearance 0)
			)
			(min_thickness 0.25)
			(keepout
				(tracks not_allowed)
				(vias allowed)
				(pads allowed)
				(copperpour not_allowed)
				(footprints allowed)
			)
			(placement
				(enabled no)
				(sheetname "")
			)
			(fill
				(thermal_gap 0.5)
				(thermal_bridge_width 0.5)
				(island_removal_mode 0)
			)
			(polygon
				(pts
					(xy 326.704452 -45.178472)
					(arc
						(start 326.704452 -45.047154)
						(mid 326.666604 -45.069646)
						(end 326.623172 -45.076872)
					)
					(arc
						(start 326.54621 -45.076872)
						(mid 326.50287 -45.069336)
						(end 326.465184 -45.046646)
					)
					(xy 326.465184 -45.178472)
				)
			)
		)
		(zone
			(layer "F.Cu")
			(hatch none 0.5)
			(connect_pads
				(clearance 0)
			)
			(min_thickness 0.25)
			(keepout
				(tracks not_allowed)
				(vias allowed)
				(pads allowed)
				(copperpour not_allowed)
				(footprints allowed)
			)
			(placement
				(enabled no)
				(sheetname "")
			)
			(fill
				(thermal_gap 0.5)
				(thermal_bridge_width 0.5)
				(island_removal_mode 0)
			)
			(polygon
				(pts
					(xy 326.704452 -44.177966)
					(arc
						(start 326.704452 -44.046648)
						(mid 326.666604 -44.06914)
						(end 326.623172 -44.076366)
					)
					(arc
						(start 326.54621 -44.076366)
						(mid 326.50287 -44.06883)
						(end 326.465184 -44.04614)
					)
					(xy 326.465184 -44.177966)
				)
			)
		)
		(zone
			(layer "F.Cu")
			(hatch none 0.5)
			(connect_pads
				(clearance 0)
			)
			(min_thickness 0.25)
			(keepout
				(tracks not_allowed)
				(vias allowed)
				(pads allowed)
				(copperpour not_allowed)
				(footprints allowed)
			)
			(placement
				(enabled no)
				(sheetname "")
			)
			(fill
				(thermal_gap 0.5)
				(thermal_bridge_width 0.5)
				(island_removal_mode 0)
			)
			(polygon
				(pts
					(xy 326.704452 -43.17746)
					(arc
						(start 326.704452 -43.046142)
						(mid 326.666604 -43.068634)
						(end 326.623172 -43.07586)
					)
					(arc
						(start 326.54621 -43.07586)
						(mid 326.50287 -43.068324)
						(end 326.465184 -43.045634)
					)
					(xy 326.465184 -43.17746)
				)
			)
		)
		(zone
			(layer "F.Cu")
			(hatch none 0.5)
			(connect_pads
				(clearance 0)
			)
			(min_thickness 0.25)
			(keepout
				(tracks not_allowed)
				(vias allowed)
				(pads allowed)
				(copperpour not_allowed)
				(footprints allowed)
			)
			(placement
				(enabled no)
				(sheetname "")
			)
			(fill
				(thermal_gap 0.5)
				(thermal_bridge_width 0.5)
				(island_removal_mode 0)
			)
			(polygon
				(pts
					(xy 326.704452 -42.176954)
					(arc
						(start 326.704452 -42.045636)
						(mid 326.666604 -42.068128)
						(end 326.623172 -42.075354)
					)
					(arc
						(start 326.54621 -42.075354)
						(mid 326.50287 -42.067818)
						(end 326.465184 -42.045128)
					)
					(xy 326.465184 -42.176954)
				)
			)
		)
		(zone
			(layer "F.Cu")
			(hatch none 0.5)
			(connect_pads
				(clearance 0)
			)
			(min_thickness 0.25)
			(keepout
				(tracks not_allowed)
				(vias allowed)
				(pads allowed)
				(copperpour not_allowed)
				(footprints allowed)
			)
			(placement
				(enabled no)
				(sheetname "")
			)
			(fill
				(thermal_gap 0.5)
				(thermal_bridge_width 0.5)
				(island_removal_mode 0)
			)
			(polygon
				(pts
					(xy 326.704452 -41.176448)
					(arc
						(start 326.704452 -41.04513)
						(mid 326.666604 -41.067622)
						(end 326.623172 -41.074848)
					)
					(arc
						(start 326.54621 -41.074848)
						(mid 326.50287 -41.067312)
						(end 326.465184 -41.044622)
					)
					(xy 326.465184 -41.176448)
				)
			)
		)
		(zone
			(layer "F.Cu")
			(hatch none 0.5)
			(connect_pads
				(clearance 0)
			)
			(min_thickness 0.25)
			(keepout
				(tracks not_allowed)
				(vias allowed)
				(pads allowed)
				(copperpour not_allowed)
				(footprints allowed)
			)
			(placement
				(enabled no)
				(sheetname "")
			)
			(fill
				(thermal_gap 0.5)
				(thermal_bridge_width 0.5)
				(island_removal_mode 0)
			)
			(polygon
				(pts
					(xy 329.6666 -59.384946)
					(arc
						(start 329.797664 -59.384946)
						(mid 329.775299 -59.347073)
						(end 329.7682 -59.303666)
					)
					(arc
						(start 329.7682 -59.226704)
						(mid 329.775626 -59.183396)
						(end 329.798172 -59.145678)
					)
					(xy 329.6666 -59.145678)
				)
			)
		)
		(zone
			(layer "F.Cu")
			(hatch none 0.5)
			(connect_pads
				(clearance 0)
			)
			(min_thickness 0.25)
			(keepout
				(tracks not_allowed)
				(vias allowed)
				(pads allowed)
				(copperpour not_allowed)
				(footprints allowed)
			)
			(placement
				(enabled no)
				(sheetname "")
			)
			(fill
				(thermal_gap 0.5)
				(thermal_bridge_width 0.5)
				(island_removal_mode 0)
			)
			(polygon
				(pts
					(xy 329.6666 -37.754814)
					(arc
						(start 329.797664 -37.754814)
						(mid 329.775299 -37.716941)
						(end 329.7682 -37.673534)
					)
					(arc
						(start 329.7682 -37.596826)
						(mid 329.775626 -37.553518)
						(end 329.798172 -37.5158)
					)
					(xy 329.6666 -37.5158)
				)
			)
		)
		(zone
			(layer "F.Cu")
			(hatch none 0.5)
			(connect_pads
				(clearance 0)
			)
			(min_thickness 0.25)
			(keepout
				(tracks not_allowed)
				(vias allowed)
				(pads allowed)
				(copperpour not_allowed)
				(footprints allowed)
			)
			(placement
				(enabled no)
				(sheetname "")
			)
			(fill
				(thermal_gap 0.5)
				(thermal_bridge_width 0.5)
				(island_removal_mode 0)
			)
			(polygon
				(pts
					(arc
						(start 330.024994 -59.30392)
						(mid 330.017568 -59.347228)
						(end 329.995022 -59.384946)
					)
					(xy 330.126594 -59.384946) (xy 330.126594 -59.145678)
					(arc
						(start 329.99553 -59.145678)
						(mid 330.017895 -59.183551)
						(end 330.024994 -59.226958)
					)
				)
			)
		)
		(zone
			(layer "F.Cu")
			(hatch none 0.5)
			(connect_pads
				(clearance 0)
			)
			(min_thickness 0.25)
			(keepout
				(tracks not_allowed)
				(vias allowed)
				(pads allowed)
				(copperpour not_allowed)
				(footprints allowed)
			)
			(placement
				(enabled no)
				(sheetname "")
			)
			(fill
				(thermal_gap 0.5)
				(thermal_bridge_width 0.5)
				(island_removal_mode 0)
			)
			(polygon
				(pts
					(arc
						(start 330.024994 -37.673788)
						(mid 330.017568 -37.717096)
						(end 329.995022 -37.754814)
					)
					(xy 330.126594 -37.754814) (xy 330.126594 -37.5158)
					(arc
						(start 329.99553 -37.5158)
						(mid 330.017851 -37.553554)
						(end 330.024994 -37.596826)
					)
				)
			)
		)
		(zone
			(layer "F.Cu")
			(hatch none 0.5)
			(connect_pads
				(clearance 0)
			)
			(min_thickness 0.25)
			(keepout
				(tracks not_allowed)
				(vias allowed)
				(pads allowed)
				(copperpour not_allowed)
				(footprints allowed)
			)
			(placement
				(enabled no)
				(sheetname "")
			)
			(fill
				(thermal_gap 0.5)
				(thermal_bridge_width 0.5)
				(island_removal_mode 0)
			)
			(polygon
				(pts
					(xy 330.667106 -59.384946)
					(arc
						(start 330.79817 -59.384946)
						(mid 330.775805 -59.347073)
						(end 330.768706 -59.303666)
					)
					(arc
						(start 330.768706 -59.226704)
						(mid 330.776132 -59.183396)
						(end 330.798678 -59.145678)
					)
					(xy 330.667106 -59.145678)
				)
			)
		)
		(zone
			(layer "F.Cu")
			(hatch none 0.5)
			(connect_pads
				(clearance 0)
			)
			(min_thickness 0.25)
			(keepout
				(tracks not_allowed)
				(vias allowed)
				(pads allowed)
				(copperpour not_allowed)
				(footprints allowed)
			)
			(placement
				(enabled no)
				(sheetname "")
			)
			(fill
				(thermal_gap 0.5)
				(thermal_bridge_width 0.5)
				(island_removal_mode 0)
			)
			(polygon
				(pts
					(xy 330.667106 -37.754814)
					(arc
						(start 330.79817 -37.754814)
						(mid 330.775805 -37.716941)
						(end 330.768706 -37.673534)
					)
					(arc
						(start 330.768706 -37.596826)
						(mid 330.776132 -37.553518)
						(end 330.798678 -37.5158)
					)
					(xy 330.667106 -37.5158)
				)
			)
		)
		(zone
			(layer "F.Cu")
			(hatch none 0.5)
			(connect_pads
				(clearance 0)
			)
			(min_thickness 0.25)
			(keepout
				(tracks not_allowed)
				(vias allowed)
				(pads allowed)
				(copperpour not_allowed)
				(footprints allowed)
			)
			(placement
				(enabled no)
				(sheetname "")
			)
			(fill
				(thermal_gap 0.5)
				(thermal_bridge_width 0.5)
				(island_removal_mode 0)
			)
			(polygon
				(pts
					(arc
						(start 331.0255 -59.30392)
						(mid 331.018074 -59.347228)
						(end 330.995528 -59.384946)
					)
					(xy 331.1271 -59.384946) (xy 331.1271 -59.145678)
					(arc
						(start 330.996036 -59.145678)
						(mid 331.018401 -59.183551)
						(end 331.0255 -59.226958)
					)
				)
			)
		)
		(zone
			(layer "F.Cu")
			(hatch none 0.5)
			(connect_pads
				(clearance 0)
			)
			(min_thickness 0.25)
			(keepout
				(tracks not_allowed)
				(vias allowed)
				(pads allowed)
				(copperpour not_allowed)
				(footprints allowed)
			)
			(placement
				(enabled no)
				(sheetname "")
			)
			(fill
				(thermal_gap 0.5)
				(thermal_bridge_width 0.5)
				(island_removal_mode 0)
			)
			(polygon
				(pts
					(arc
						(start 331.0255 -37.673788)
						(mid 331.018074 -37.717096)
						(end 330.995528 -37.754814)
					)
					(xy 331.1271 -37.754814) (xy 331.1271 -37.5158)
					(arc
						(start 330.996036 -37.5158)
						(mid 331.018357 -37.553554)
						(end 331.0255 -37.596826)
					)
				)
			)
		)
		(zone
			(layer "F.Cu")
			(hatch none 0.5)
			(connect_pads
				(clearance 0)
			)
			(min_thickness 0.25)
			(keepout
				(tracks not_allowed)
				(vias allowed)
				(pads allowed)
				(copperpour not_allowed)
				(footprints allowed)
			)
			(placement
				(enabled no)
				(sheetname "")
			)
			(fill
				(thermal_gap 0.5)
				(thermal_bridge_width 0.5)
				(island_removal_mode 0)
			)
			(polygon
				(pts
					(xy 331.667612 -59.384946)
					(arc
						(start 331.798676 -59.384946)
						(mid 331.776311 -59.347073)
						(end 331.769212 -59.303666)
					)
					(arc
						(start 331.769212 -59.226704)
						(mid 331.776638 -59.183396)
						(end 331.799184 -59.145678)
					)
					(xy 331.667612 -59.145678)
				)
			)
		)
		(zone
			(layer "F.Cu")
			(hatch none 0.5)
			(connect_pads
				(clearance 0)
			)
			(min_thickness 0.25)
			(keepout
				(tracks not_allowed)
				(vias allowed)
				(pads allowed)
				(copperpour not_allowed)
				(footprints allowed)
			)
			(placement
				(enabled no)
				(sheetname "")
			)
			(fill
				(thermal_gap 0.5)
				(thermal_bridge_width 0.5)
				(island_removal_mode 0)
			)
			(polygon
				(pts
					(xy 331.667612 -37.754814)
					(arc
						(start 331.798676 -37.754814)
						(mid 331.776311 -37.716941)
						(end 331.769212 -37.673534)
					)
					(arc
						(start 331.769212 -37.596826)
						(mid 331.776638 -37.553518)
						(end 331.799184 -37.5158)
					)
					(xy 331.667612 -37.5158)
				)
			)
		)
		(zone
			(layer "F.Cu")
			(hatch none 0.5)
			(connect_pads
				(clearance 0)
			)
			(min_thickness 0.25)
			(keepout
				(tracks not_allowed)
				(vias allowed)
				(pads allowed)
				(copperpour not_allowed)
				(footprints allowed)
			)
			(placement
				(enabled no)
				(sheetname "")
			)
			(fill
				(thermal_gap 0.5)
				(thermal_bridge_width 0.5)
				(island_removal_mode 0)
			)
			(polygon
				(pts
					(arc
						(start 332.026006 -59.30392)
						(mid 332.01858 -59.347228)
						(end 331.996034 -59.384946)
					)
					(xy 332.127606 -59.384946) (xy 332.127606 -59.145678)
					(arc
						(start 331.996542 -59.145678)
						(mid 332.018907 -59.183551)
						(end 332.026006 -59.226958)
					)
				)
			)
		)
		(zone
			(layer "F.Cu")
			(hatch none 0.5)
			(connect_pads
				(clearance 0)
			)
			(min_thickness 0.25)
			(keepout
				(tracks not_allowed)
				(vias allowed)
				(pads allowed)
				(copperpour not_allowed)
				(footprints allowed)
			)
			(placement
				(enabled no)
				(sheetname "")
			)
			(fill
				(thermal_gap 0.5)
				(thermal_bridge_width 0.5)
				(island_removal_mode 0)
			)
			(polygon
				(pts
					(arc
						(start 332.026006 -37.673788)
						(mid 332.01858 -37.717096)
						(end 331.996034 -37.754814)
					)
					(xy 332.127606 -37.754814) (xy 332.127606 -37.5158)
					(arc
						(start 331.996542 -37.5158)
						(mid 332.018863 -37.553554)
						(end 332.026006 -37.596826)
					)
				)
			)
		)
		(zone
			(layer "F.Cu")
			(hatch none 0.5)
			(connect_pads
				(clearance 0)
			)
			(min_thickness 0.25)
			(keepout
				(tracks not_allowed)
				(vias allowed)
				(pads allowed)
				(copperpour not_allowed)
				(footprints allowed)
			)
			(placement
				(enabled no)
				(sheetname "")
			)
			(fill
				(thermal_gap 0.5)
				(thermal_bridge_width 0.5)
				(island_removal_mode 0)
			)
			(polygon
				(pts
					(xy 332.667864 -59.384946)
					(arc
						(start 332.799182 -59.384946)
						(mid 332.77669 -59.347098)
						(end 332.769464 -59.303666)
					)
					(arc
						(start 332.769464 -59.226704)
						(mid 332.777 -59.183364)
						(end 332.79969 -59.145678)
					)
					(xy 332.667864 -59.145678)
				)
			)
		)
		(zone
			(layer "F.Cu")
			(hatch none 0.5)
			(connect_pads
				(clearance 0)
			)
			(min_thickness 0.25)
			(keepout
				(tracks not_allowed)
				(vias allowed)
				(pads allowed)
				(copperpour not_allowed)
				(footprints allowed)
			)
			(placement
				(enabled no)
				(sheetname "")
			)
			(fill
				(thermal_gap 0.5)
				(thermal_bridge_width 0.5)
				(island_removal_mode 0)
			)
			(polygon
				(pts
					(xy 332.667864 -37.754814)
					(arc
						(start 332.799182 -37.754814)
						(mid 332.77669 -37.716966)
						(end 332.769464 -37.673534)
					)
					(arc
						(start 332.769464 -37.596826)
						(mid 332.777 -37.553486)
						(end 332.79969 -37.5158)
					)
					(xy 332.667864 -37.5158)
				)
			)
		)
		(zone
			(layer "F.Cu")
			(hatch none 0.5)
			(connect_pads
				(clearance 0)
			)
			(min_thickness 0.25)
			(keepout
				(tracks not_allowed)
				(vias allowed)
				(pads allowed)
				(copperpour not_allowed)
				(footprints allowed)
			)
			(placement
				(enabled no)
				(sheetname "")
			)
			(fill
				(thermal_gap 0.5)
				(thermal_bridge_width 0.5)
				(island_removal_mode 0)
			)
			(polygon
				(pts
					(arc
						(start 333.026512 -59.30392)
						(mid 333.018976 -59.34726)
						(end 332.996286 -59.384946)
					)
					(xy 333.128112 -59.384946) (xy 333.128112 -59.145678)
					(arc
						(start 332.996794 -59.145678)
						(mid 333.019286 -59.183526)
						(end 333.026512 -59.226958)
					)
				)
			)
		)
		(zone
			(layer "F.Cu")
			(hatch none 0.5)
			(connect_pads
				(clearance 0)
			)
			(min_thickness 0.25)
			(keepout
				(tracks not_allowed)
				(vias allowed)
				(pads allowed)
				(copperpour not_allowed)
				(footprints allowed)
			)
			(placement
				(enabled no)
				(sheetname "")
			)
			(fill
				(thermal_gap 0.5)
				(thermal_bridge_width 0.5)
				(island_removal_mode 0)
			)
			(polygon
				(pts
					(arc
						(start 333.026512 -37.673788)
						(mid 333.018976 -37.717128)
						(end 332.996286 -37.754814)
					)
					(xy 333.128112 -37.754814) (xy 333.128112 -37.5158)
					(arc
						(start 332.996794 -37.5158)
						(mid 333.019242 -37.553528)
						(end 333.026512 -37.596826)
					)
				)
			)
		)
		(zone
			(layer "F.Cu")
			(hatch none 0.5)
			(connect_pads
				(clearance 0)
			)
			(min_thickness 0.25)
			(keepout
				(tracks not_allowed)
				(vias allowed)
				(pads allowed)
				(copperpour not_allowed)
				(footprints allowed)
			)
			(placement
				(enabled no)
				(sheetname "")
			)
			(fill
				(thermal_gap 0.5)
				(thermal_bridge_width 0.5)
				(island_removal_mode 0)
			)
			(polygon
				(pts
					(xy 333.66837 -59.384946)
					(arc
						(start 333.799688 -59.384946)
						(mid 333.777196 -59.347098)
						(end 333.76997 -59.303666)
					)
					(arc
						(start 333.76997 -59.226704)
						(mid 333.777506 -59.183364)
						(end 333.800196 -59.145678)
					)
					(xy 333.66837 -59.145678)
				)
			)
		)
		(zone
			(layer "F.Cu")
			(hatch none 0.5)
			(connect_pads
				(clearance 0)
			)
			(min_thickness 0.25)
			(keepout
				(tracks not_allowed)
				(vias allowed)
				(pads allowed)
				(copperpour not_allowed)
				(footprints allowed)
			)
			(placement
				(enabled no)
				(sheetname "")
			)
			(fill
				(thermal_gap 0.5)
				(thermal_bridge_width 0.5)
				(island_removal_mode 0)
			)
			(polygon
				(pts
					(xy 333.66837 -37.754814)
					(arc
						(start 333.799688 -37.754814)
						(mid 333.777196 -37.716966)
						(end 333.76997 -37.673534)
					)
					(arc
						(start 333.76997 -37.596826)
						(mid 333.777506 -37.553486)
						(end 333.800196 -37.5158)
					)
					(xy 333.66837 -37.5158)
				)
			)
		)
		(zone
			(layer "F.Cu")
			(hatch none 0.5)
			(connect_pads
				(clearance 0)
			)
			(min_thickness 0.25)
			(keepout
				(tracks not_allowed)
				(vias allowed)
				(pads allowed)
				(copperpour not_allowed)
				(footprints allowed)
			)
			(placement
				(enabled no)
				(sheetname "")
			)
			(fill
				(thermal_gap 0.5)
				(thermal_bridge_width 0.5)
				(island_removal_mode 0)
			)
			(polygon
				(pts
					(arc
						(start 334.027018 -59.30392)
						(mid 334.019482 -59.34726)
						(end 333.996792 -59.384946)
					)
					(xy 334.128618 -59.384946) (xy 334.128618 -59.145678)
					(arc
						(start 333.9973 -59.145678)
						(mid 334.019792 -59.183526)
						(end 334.027018 -59.226958)
					)
				)
			)
		)
		(zone
			(layer "F.Cu")
			(hatch none 0.5)
			(connect_pads
				(clearance 0)
			)
			(min_thickness 0.25)
			(keepout
				(tracks not_allowed)
				(vias allowed)
				(pads allowed)
				(copperpour not_allowed)
				(footprints allowed)
			)
			(placement
				(enabled no)
				(sheetname "")
			)
			(fill
				(thermal_gap 0.5)
				(thermal_bridge_width 0.5)
				(island_removal_mode 0)
			)
			(polygon
				(pts
					(arc
						(start 334.027018 -37.673788)
						(mid 334.019482 -37.717128)
						(end 333.996792 -37.754814)
					)
					(xy 334.128618 -37.754814) (xy 334.128618 -37.5158)
					(arc
						(start 333.9973 -37.5158)
						(mid 334.019748 -37.553528)
						(end 334.027018 -37.596826)
					)
				)
			)
		)
		(zone
			(layer "F.Cu")
			(hatch none 0.5)
			(connect_pads
				(clearance 0)
			)
			(min_thickness 0.25)
			(keepout
				(tracks not_allowed)
				(vias allowed)
				(pads allowed)
				(copperpour not_allowed)
				(footprints allowed)
			)
			(placement
				(enabled no)
				(sheetname "")
			)
			(fill
				(thermal_gap 0.5)
				(thermal_bridge_width 0.5)
				(island_removal_mode 0)
			)
			(polygon
				(pts
					(xy 334.668876 -59.384946)
					(arc
						(start 334.800194 -59.384946)
						(mid 334.777702 -59.347098)
						(end 334.770476 -59.303666)
					)
					(arc
						(start 334.770476 -59.226704)
						(mid 334.778012 -59.183364)
						(end 334.800702 -59.145678)
					)
					(xy 334.668876 -59.145678)
				)
			)
		)
		(zone
			(layer "F.Cu")
			(hatch none 0.5)
			(connect_pads
				(clearance 0)
			)
			(min_thickness 0.25)
			(keepout
				(tracks not_allowed)
				(vias allowed)
				(pads allowed)
				(copperpour not_allowed)
				(footprints allowed)
			)
			(placement
				(enabled no)
				(sheetname "")
			)
			(fill
				(thermal_gap 0.5)
				(thermal_bridge_width 0.5)
				(island_removal_mode 0)
			)
			(polygon
				(pts
					(xy 334.668876 -37.754814)
					(arc
						(start 334.800194 -37.754814)
						(mid 334.777702 -37.716966)
						(end 334.770476 -37.673534)
					)
					(arc
						(start 334.770476 -37.596826)
						(mid 334.778012 -37.553486)
						(end 334.800702 -37.5158)
					)
					(xy 334.668876 -37.5158)
				)
			)
		)
		(zone
			(layer "F.Cu")
			(hatch none 0.5)
			(connect_pads
				(clearance 0)
			)
			(min_thickness 0.25)
			(keepout
				(tracks not_allowed)
				(vias allowed)
				(pads allowed)
				(copperpour not_allowed)
				(footprints allowed)
			)
			(placement
				(enabled no)
				(sheetname "")
			)
			(fill
				(thermal_gap 0.5)
				(thermal_bridge_width 0.5)
				(island_removal_mode 0)
			)
			(polygon
				(pts
					(arc
						(start 335.027524 -59.30392)
						(mid 335.019988 -59.34726)
						(end 334.997298 -59.384946)
					)
					(xy 335.129124 -59.384946) (xy 335.129124 -59.145678)
					(arc
						(start 334.997806 -59.145678)
						(mid 335.020298 -59.183526)
						(end 335.027524 -59.226958)
					)
				)
			)
		)
		(zone
			(layer "F.Cu")
			(hatch none 0.5)
			(connect_pads
				(clearance 0)
			)
			(min_thickness 0.25)
			(keepout
				(tracks not_allowed)
				(vias allowed)
				(pads allowed)
				(copperpour not_allowed)
				(footprints allowed)
			)
			(placement
				(enabled no)
				(sheetname "")
			)
			(fill
				(thermal_gap 0.5)
				(thermal_bridge_width 0.5)
				(island_removal_mode 0)
			)
			(polygon
				(pts
					(arc
						(start 335.027524 -37.673788)
						(mid 335.019988 -37.717128)
						(end 334.997298 -37.754814)
					)
					(xy 335.129124 -37.754814) (xy 335.129124 -37.5158)
					(arc
						(start 334.997806 -37.5158)
						(mid 335.020254 -37.553528)
						(end 335.027524 -37.596826)
					)
				)
			)
		)
		(zone
			(layer "F.Cu")
			(hatch none 0.5)
			(connect_pads
				(clearance 0)
			)
			(min_thickness 0.25)
			(keepout
				(tracks not_allowed)
				(vias allowed)
				(pads allowed)
				(copperpour not_allowed)
				(footprints allowed)
			)
			(placement
				(enabled no)
				(sheetname "")
			)
			(fill
				(thermal_gap 0.5)
				(thermal_bridge_width 0.5)
				(island_removal_mode 0)
			)
			(polygon
				(pts
					(xy 335.669382 -59.384946)
					(arc
						(start 335.8007 -59.384946)
						(mid 335.778208 -59.347098)
						(end 335.770982 -59.303666)
					)
					(arc
						(start 335.770982 -59.226704)
						(mid 335.778518 -59.183364)
						(end 335.801208 -59.145678)
					)
					(xy 335.669382 -59.145678)
				)
			)
		)
		(zone
			(layer "F.Cu")
			(hatch none 0.5)
			(connect_pads
				(clearance 0)
			)
			(min_thickness 0.25)
			(keepout
				(tracks not_allowed)
				(vias allowed)
				(pads allowed)
				(copperpour not_allowed)
				(footprints allowed)
			)
			(placement
				(enabled no)
				(sheetname "")
			)
			(fill
				(thermal_gap 0.5)
				(thermal_bridge_width 0.5)
				(island_removal_mode 0)
			)
			(polygon
				(pts
					(xy 335.669382 -37.754814)
					(arc
						(start 335.8007 -37.754814)
						(mid 335.778208 -37.716966)
						(end 335.770982 -37.673534)
					)
					(arc
						(start 335.770982 -37.596826)
						(mid 335.778518 -37.553486)
						(end 335.801208 -37.5158)
					)
					(xy 335.669382 -37.5158)
				)
			)
		)
		(zone
			(layer "F.Cu")
			(hatch none 0.5)
			(connect_pads
				(clearance 0)
			)
			(min_thickness 0.25)
			(keepout
				(tracks not_allowed)
				(vias allowed)
				(pads allowed)
				(copperpour not_allowed)
				(footprints allowed)
			)
			(placement
				(enabled no)
				(sheetname "")
			)
			(fill
				(thermal_gap 0.5)
				(thermal_bridge_width 0.5)
				(island_removal_mode 0)
			)
			(polygon
				(pts
					(arc
						(start 336.02803 -59.30392)
						(mid 336.020494 -59.34726)
						(end 335.997804 -59.384946)
					)
					(xy 336.12963 -59.384946) (xy 336.12963 -59.145678)
					(arc
						(start 335.998312 -59.145678)
						(mid 336.020804 -59.183526)
						(end 336.02803 -59.226958)
					)
				)
			)
		)
		(zone
			(layer "F.Cu")
			(hatch none 0.5)
			(connect_pads
				(clearance 0)
			)
			(min_thickness 0.25)
			(keepout
				(tracks not_allowed)
				(vias allowed)
				(pads allowed)
				(copperpour not_allowed)
				(footprints allowed)
			)
			(placement
				(enabled no)
				(sheetname "")
			)
			(fill
				(thermal_gap 0.5)
				(thermal_bridge_width 0.5)
				(island_removal_mode 0)
			)
			(polygon
				(pts
					(arc
						(start 336.02803 -37.673788)
						(mid 336.020494 -37.717128)
						(end 335.997804 -37.754814)
					)
					(xy 336.12963 -37.754814) (xy 336.12963 -37.5158)
					(arc
						(start 335.998312 -37.5158)
						(mid 336.02076 -37.553528)
						(end 336.02803 -37.596826)
					)
				)
			)
		)
		(zone
			(layer "F.Cu")
			(hatch none 0.5)
			(connect_pads
				(clearance 0)
			)
			(min_thickness 0.25)
			(keepout
				(tracks not_allowed)
				(vias allowed)
				(pads allowed)
				(copperpour not_allowed)
				(footprints allowed)
			)
			(placement
				(enabled no)
				(sheetname "")
			)
			(fill
				(thermal_gap 0.5)
				(thermal_bridge_width 0.5)
				(island_removal_mode 0)
			)
			(polygon
				(pts
					(xy 336.669888 -59.384946)
					(arc
						(start 336.801206 -59.384946)
						(mid 336.778714 -59.347098)
						(end 336.771488 -59.303666)
					)
					(arc
						(start 336.771488 -59.226704)
						(mid 336.779024 -59.183364)
						(end 336.801714 -59.145678)
					)
					(xy 336.669888 -59.145678)
				)
			)
		)
		(zone
			(layer "F.Cu")
			(hatch none 0.5)
			(connect_pads
				(clearance 0)
			)
			(min_thickness 0.25)
			(keepout
				(tracks not_allowed)
				(vias allowed)
				(pads allowed)
				(copperpour not_allowed)
				(footprints allowed)
			)
			(placement
				(enabled no)
				(sheetname "")
			)
			(fill
				(thermal_gap 0.5)
				(thermal_bridge_width 0.5)
				(island_removal_mode 0)
			)
			(polygon
				(pts
					(xy 336.669888 -37.754814)
					(arc
						(start 336.801206 -37.754814)
						(mid 336.778714 -37.716966)
						(end 336.771488 -37.673534)
					)
					(arc
						(start 336.771488 -37.596826)
						(mid 336.779024 -37.553486)
						(end 336.801714 -37.5158)
					)
					(xy 336.669888 -37.5158)
				)
			)
		)
		(zone
			(layer "F.Cu")
			(hatch none 0.5)
			(connect_pads
				(clearance 0)
			)
			(min_thickness 0.25)
			(keepout
				(tracks not_allowed)
				(vias allowed)
				(pads allowed)
				(copperpour not_allowed)
				(footprints allowed)
			)
			(placement
				(enabled no)
				(sheetname "")
			)
			(fill
				(thermal_gap 0.5)
				(thermal_bridge_width 0.5)
				(island_removal_mode 0)
			)
			(polygon
				(pts
					(arc
						(start 337.028536 -59.30392)
						(mid 337.021 -59.34726)
						(end 336.99831 -59.384946)
					)
					(xy 337.130136 -59.384946) (xy 337.130136 -59.145678)
					(arc
						(start 336.998818 -59.145678)
						(mid 337.02131 -59.183526)
						(end 337.028536 -59.226958)
					)
				)
			)
		)
		(zone
			(layer "F.Cu")
			(hatch none 0.5)
			(connect_pads
				(clearance 0)
			)
			(min_thickness 0.25)
			(keepout
				(tracks not_allowed)
				(vias allowed)
				(pads allowed)
				(copperpour not_allowed)
				(footprints allowed)
			)
			(placement
				(enabled no)
				(sheetname "")
			)
			(fill
				(thermal_gap 0.5)
				(thermal_bridge_width 0.5)
				(island_removal_mode 0)
			)
			(polygon
				(pts
					(arc
						(start 337.028536 -37.673788)
						(mid 337.021 -37.717128)
						(end 336.99831 -37.754814)
					)
					(xy 337.130136 -37.754814) (xy 337.130136 -37.5158)
					(arc
						(start 336.998818 -37.5158)
						(mid 337.021266 -37.553528)
						(end 337.028536 -37.596826)
					)
				)
			)
		)
		(zone
			(layer "F.Cu")
			(hatch none 0.5)
			(connect_pads
				(clearance 0)
			)
			(min_thickness 0.25)
			(keepout
				(tracks not_allowed)
				(vias allowed)
				(pads allowed)
				(copperpour not_allowed)
				(footprints allowed)
			)
			(placement
				(enabled no)
				(sheetname "")
			)
			(fill
				(thermal_gap 0.5)
				(thermal_bridge_width 0.5)
				(island_removal_mode 0)
			)
			(polygon
				(pts
					(xy 337.670394 -59.384946)
					(arc
						(start 337.801712 -59.384946)
						(mid 337.77922 -59.347098)
						(end 337.771994 -59.303666)
					)
					(arc
						(start 337.771994 -59.226704)
						(mid 337.77953 -59.183364)
						(end 337.80222 -59.145678)
					)
					(xy 337.670394 -59.145678)
				)
			)
		)
		(zone
			(layer "F.Cu")
			(hatch none 0.5)
			(connect_pads
				(clearance 0)
			)
			(min_thickness 0.25)
			(keepout
				(tracks not_allowed)
				(vias allowed)
				(pads allowed)
				(copperpour not_allowed)
				(footprints allowed)
			)
			(placement
				(enabled no)
				(sheetname "")
			)
			(fill
				(thermal_gap 0.5)
				(thermal_bridge_width 0.5)
				(island_removal_mode 0)
			)
			(polygon
				(pts
					(xy 337.670394 -37.754814)
					(arc
						(start 337.801712 -37.754814)
						(mid 337.77922 -37.716966)
						(end 337.771994 -37.673534)
					)
					(arc
						(start 337.771994 -37.596826)
						(mid 337.77953 -37.553486)
						(end 337.80222 -37.5158)
					)
					(xy 337.670394 -37.5158)
				)
			)
		)
		(zone
			(layer "F.Cu")
			(hatch none 0.5)
			(connect_pads
				(clearance 0)
			)
			(min_thickness 0.25)
			(keepout
				(tracks not_allowed)
				(vias allowed)
				(pads allowed)
				(copperpour not_allowed)
				(footprints allowed)
			)
			(placement
				(enabled no)
				(sheetname "")
			)
			(fill
				(thermal_gap 0.5)
				(thermal_bridge_width 0.5)
				(island_removal_mode 0)
			)
			(polygon
				(pts
					(arc
						(start 338.029042 -59.30392)
						(mid 338.021506 -59.34726)
						(end 337.998816 -59.384946)
					)
					(xy 338.130642 -59.384946) (xy 338.130642 -59.145678)
					(arc
						(start 337.999324 -59.145678)
						(mid 338.021816 -59.183526)
						(end 338.029042 -59.226958)
					)
				)
			)
		)
		(zone
			(layer "F.Cu")
			(hatch none 0.5)
			(connect_pads
				(clearance 0)
			)
			(min_thickness 0.25)
			(keepout
				(tracks not_allowed)
				(vias allowed)
				(pads allowed)
				(copperpour not_allowed)
				(footprints allowed)
			)
			(placement
				(enabled no)
				(sheetname "")
			)
			(fill
				(thermal_gap 0.5)
				(thermal_bridge_width 0.5)
				(island_removal_mode 0)
			)
			(polygon
				(pts
					(arc
						(start 338.029042 -37.673788)
						(mid 338.021506 -37.717128)
						(end 337.998816 -37.754814)
					)
					(xy 338.130642 -37.754814) (xy 338.130642 -37.5158)
					(arc
						(start 337.999324 -37.5158)
						(mid 338.021772 -37.553528)
						(end 338.029042 -37.596826)
					)
				)
			)
		)
		(zone
			(layer "F.Cu")
			(hatch none 0.5)
			(connect_pads
				(clearance 0)
			)
			(min_thickness 0.25)
			(keepout
				(tracks not_allowed)
				(vias allowed)
				(pads allowed)
				(copperpour not_allowed)
				(footprints allowed)
			)
			(placement
				(enabled no)
				(sheetname "")
			)
			(fill
				(thermal_gap 0.5)
				(thermal_bridge_width 0.5)
				(island_removal_mode 0)
			)
			(polygon
				(pts
					(xy 338.6709 -59.384946)
					(arc
						(start 338.802218 -59.384946)
						(mid 338.779726 -59.347098)
						(end 338.7725 -59.303666)
					)
					(arc
						(start 338.7725 -59.226704)
						(mid 338.780036 -59.183364)
						(end 338.802726 -59.145678)
					)
					(xy 338.6709 -59.145678)
				)
			)
		)
		(zone
			(layer "F.Cu")
			(hatch none 0.5)
			(connect_pads
				(clearance 0)
			)
			(min_thickness 0.25)
			(keepout
				(tracks not_allowed)
				(vias allowed)
				(pads allowed)
				(copperpour not_allowed)
				(footprints allowed)
			)
			(placement
				(enabled no)
				(sheetname "")
			)
			(fill
				(thermal_gap 0.5)
				(thermal_bridge_width 0.5)
				(island_removal_mode 0)
			)
			(polygon
				(pts
					(xy 338.6709 -37.754814)
					(arc
						(start 338.802218 -37.754814)
						(mid 338.779726 -37.716966)
						(end 338.7725 -37.673534)
					)
					(arc
						(start 338.7725 -37.596826)
						(mid 338.780036 -37.553486)
						(end 338.802726 -37.5158)
					)
					(xy 338.6709 -37.5158)
				)
			)
		)
		(zone
			(layer "F.Cu")
			(hatch none 0.5)
			(connect_pads
				(clearance 0)
			)
			(min_thickness 0.25)
			(keepout
				(tracks not_allowed)
				(vias allowed)
				(pads allowed)
				(copperpour not_allowed)
				(footprints allowed)
			)
			(placement
				(enabled no)
				(sheetname "")
			)
			(fill
				(thermal_gap 0.5)
				(thermal_bridge_width 0.5)
				(island_removal_mode 0)
			)
			(polygon
				(pts
					(arc
						(start 339.029548 -59.30392)
						(mid 339.022012 -59.34726)
						(end 338.999322 -59.384946)
					)
					(xy 339.131148 -59.384946) (xy 339.131148 -59.145678)
					(arc
						(start 338.99983 -59.145678)
						(mid 339.022322 -59.183526)
						(end 339.029548 -59.226958)
					)
				)
			)
		)
		(zone
			(layer "F.Cu")
			(hatch none 0.5)
			(connect_pads
				(clearance 0)
			)
			(min_thickness 0.25)
			(keepout
				(tracks not_allowed)
				(vias allowed)
				(pads allowed)
				(copperpour not_allowed)
				(footprints allowed)
			)
			(placement
				(enabled no)
				(sheetname "")
			)
			(fill
				(thermal_gap 0.5)
				(thermal_bridge_width 0.5)
				(island_removal_mode 0)
			)
			(polygon
				(pts
					(arc
						(start 339.029548 -37.673788)
						(mid 339.022012 -37.717128)
						(end 338.999322 -37.754814)
					)
					(xy 339.131148 -37.754814) (xy 339.131148 -37.5158)
					(arc
						(start 338.99983 -37.5158)
						(mid 339.022278 -37.553528)
						(end 339.029548 -37.596826)
					)
				)
			)
		)
		(zone
			(layer "F.Cu")
			(hatch none 0.5)
			(connect_pads
				(clearance 0)
			)
			(min_thickness 0.25)
			(keepout
				(tracks not_allowed)
				(vias allowed)
				(pads allowed)
				(copperpour not_allowed)
				(footprints allowed)
			)
			(placement
				(enabled no)
				(sheetname "")
			)
			(fill
				(thermal_gap 0.5)
				(thermal_bridge_width 0.5)
				(island_removal_mode 0)
			)
			(polygon
				(pts
					(xy 339.671406 -59.384946)
					(arc
						(start 339.802724 -59.384946)
						(mid 339.780232 -59.347098)
						(end 339.773006 -59.303666)
					)
					(arc
						(start 339.773006 -59.226704)
						(mid 339.780542 -59.183364)
						(end 339.803232 -59.145678)
					)
					(xy 339.671406 -59.145678)
				)
			)
		)
		(zone
			(layer "F.Cu")
			(hatch none 0.5)
			(connect_pads
				(clearance 0)
			)
			(min_thickness 0.25)
			(keepout
				(tracks not_allowed)
				(vias allowed)
				(pads allowed)
				(copperpour not_allowed)
				(footprints allowed)
			)
			(placement
				(enabled no)
				(sheetname "")
			)
			(fill
				(thermal_gap 0.5)
				(thermal_bridge_width 0.5)
				(island_removal_mode 0)
			)
			(polygon
				(pts
					(xy 339.671406 -37.754814)
					(arc
						(start 339.802724 -37.754814)
						(mid 339.780232 -37.716966)
						(end 339.773006 -37.673534)
					)
					(arc
						(start 339.773006 -37.596826)
						(mid 339.780542 -37.553486)
						(end 339.803232 -37.5158)
					)
					(xy 339.671406 -37.5158)
				)
			)
		)
		(zone
			(layer "F.Cu")
			(hatch none 0.5)
			(connect_pads
				(clearance 0)
			)
			(min_thickness 0.25)
			(keepout
				(tracks not_allowed)
				(vias allowed)
				(pads allowed)
				(copperpour not_allowed)
				(footprints allowed)
			)
			(placement
				(enabled no)
				(sheetname "")
			)
			(fill
				(thermal_gap 0.5)
				(thermal_bridge_width 0.5)
				(island_removal_mode 0)
			)
			(polygon
				(pts
					(arc
						(start 340.030054 -59.30392)
						(mid 340.022518 -59.34726)
						(end 339.999828 -59.384946)
					)
					(xy 340.131654 -59.384946) (xy 340.131654 -59.145678)
					(arc
						(start 340.000336 -59.145678)
						(mid 340.022828 -59.183526)
						(end 340.030054 -59.226958)
					)
				)
			)
		)
		(zone
			(layer "F.Cu")
			(hatch none 0.5)
			(connect_pads
				(clearance 0)
			)
			(min_thickness 0.25)
			(keepout
				(tracks not_allowed)
				(vias allowed)
				(pads allowed)
				(copperpour not_allowed)
				(footprints allowed)
			)
			(placement
				(enabled no)
				(sheetname "")
			)
			(fill
				(thermal_gap 0.5)
				(thermal_bridge_width 0.5)
				(island_removal_mode 0)
			)
			(polygon
				(pts
					(arc
						(start 340.030054 -37.673788)
						(mid 340.022518 -37.717128)
						(end 339.999828 -37.754814)
					)
					(xy 340.131654 -37.754814) (xy 340.131654 -37.5158)
					(arc
						(start 340.000336 -37.5158)
						(mid 340.022784 -37.553528)
						(end 340.030054 -37.596826)
					)
				)
			)
		)
		(zone
			(layer "F.Cu")
			(hatch none 0.5)
			(connect_pads
				(clearance 0)
			)
			(min_thickness 0.25)
			(keepout
				(tracks not_allowed)
				(vias allowed)
				(pads allowed)
				(copperpour not_allowed)
				(footprints allowed)
			)
			(placement
				(enabled no)
				(sheetname "")
			)
			(fill
				(thermal_gap 0.5)
				(thermal_bridge_width 0.5)
				(island_removal_mode 0)
			)
			(polygon
				(pts
					(xy 340.671912 -59.384946)
					(arc
						(start 340.80323 -59.384946)
						(mid 340.780738 -59.347098)
						(end 340.773512 -59.303666)
					)
					(arc
						(start 340.773512 -59.226704)
						(mid 340.781048 -59.183364)
						(end 340.803738 -59.145678)
					)
					(xy 340.671912 -59.145678)
				)
			)
		)
		(zone
			(layer "F.Cu")
			(hatch none 0.5)
			(connect_pads
				(clearance 0)
			)
			(min_thickness 0.25)
			(keepout
				(tracks not_allowed)
				(vias allowed)
				(pads allowed)
				(copperpour not_allowed)
				(footprints allowed)
			)
			(placement
				(enabled no)
				(sheetname "")
			)
			(fill
				(thermal_gap 0.5)
				(thermal_bridge_width 0.5)
				(island_removal_mode 0)
			)
			(polygon
				(pts
					(xy 340.671912 -37.754814)
					(arc
						(start 340.80323 -37.754814)
						(mid 340.780738 -37.716966)
						(end 340.773512 -37.673534)
					)
					(arc
						(start 340.773512 -37.596826)
						(mid 340.781048 -37.553486)
						(end 340.803738 -37.5158)
					)
					(xy 340.671912 -37.5158)
				)
			)
		)
		(zone
			(layer "F.Cu")
			(hatch none 0.5)
			(connect_pads
				(clearance 0)
			)
			(min_thickness 0.25)
			(keepout
				(tracks not_allowed)
				(vias allowed)
				(pads allowed)
				(copperpour not_allowed)
				(footprints allowed)
			)
			(placement
				(enabled no)
				(sheetname "")
			)
			(fill
				(thermal_gap 0.5)
				(thermal_bridge_width 0.5)
				(island_removal_mode 0)
			)
			(polygon
				(pts
					(arc
						(start 341.03056 -59.30392)
						(mid 341.023024 -59.34726)
						(end 341.000334 -59.384946)
					)
					(xy 341.13216 -59.384946) (xy 341.13216 -59.145678)
					(arc
						(start 341.000842 -59.145678)
						(mid 341.023334 -59.183526)
						(end 341.03056 -59.226958)
					)
				)
			)
		)
		(zone
			(layer "F.Cu")
			(hatch none 0.5)
			(connect_pads
				(clearance 0)
			)
			(min_thickness 0.25)
			(keepout
				(tracks not_allowed)
				(vias allowed)
				(pads allowed)
				(copperpour not_allowed)
				(footprints allowed)
			)
			(placement
				(enabled no)
				(sheetname "")
			)
			(fill
				(thermal_gap 0.5)
				(thermal_bridge_width 0.5)
				(island_removal_mode 0)
			)
			(polygon
				(pts
					(arc
						(start 341.03056 -37.673788)
						(mid 341.023024 -37.717128)
						(end 341.000334 -37.754814)
					)
					(xy 341.13216 -37.754814) (xy 341.13216 -37.5158)
					(arc
						(start 341.000842 -37.5158)
						(mid 341.02329 -37.553528)
						(end 341.03056 -37.596826)
					)
				)
			)
		)
		(zone
			(layer "F.Cu")
			(hatch none 0.5)
			(connect_pads
				(clearance 0)
			)
			(min_thickness 0.25)
			(keepout
				(tracks not_allowed)
				(vias allowed)
				(pads allowed)
				(copperpour not_allowed)
				(footprints allowed)
			)
			(placement
				(enabled no)
				(sheetname "")
			)
			(fill
				(thermal_gap 0.5)
				(thermal_bridge_width 0.5)
				(island_removal_mode 0)
			)
			(polygon
				(pts
					(xy 341.672418 -59.384946)
					(arc
						(start 341.803482 -59.384946)
						(mid 341.781117 -59.347073)
						(end 341.774018 -59.303666)
					)
					(arc
						(start 341.774018 -59.226704)
						(mid 341.781444 -59.183396)
						(end 341.80399 -59.145678)
					)
					(xy 341.672418 -59.145678)
				)
			)
		)
		(zone
			(layer "F.Cu")
			(hatch none 0.5)
			(connect_pads
				(clearance 0)
			)
			(min_thickness 0.25)
			(keepout
				(tracks not_allowed)
				(vias allowed)
				(pads allowed)
				(copperpour not_allowed)
				(footprints allowed)
			)
			(placement
				(enabled no)
				(sheetname "")
			)
			(fill
				(thermal_gap 0.5)
				(thermal_bridge_width 0.5)
				(island_removal_mode 0)
			)
			(polygon
				(pts
					(xy 341.672418 -37.754814)
					(arc
						(start 341.803482 -37.754814)
						(mid 341.781117 -37.716941)
						(end 341.774018 -37.673534)
					)
					(arc
						(start 341.774018 -37.596826)
						(mid 341.781444 -37.553518)
						(end 341.80399 -37.5158)
					)
					(xy 341.672418 -37.5158)
				)
			)
		)
		(zone
			(layer "F.Cu")
			(hatch none 0.5)
			(connect_pads
				(clearance 0)
			)
			(min_thickness 0.25)
			(keepout
				(tracks not_allowed)
				(vias allowed)
				(pads allowed)
				(copperpour not_allowed)
				(footprints allowed)
			)
			(placement
				(enabled no)
				(sheetname "")
			)
			(fill
				(thermal_gap 0.5)
				(thermal_bridge_width 0.5)
				(island_removal_mode 0)
			)
			(polygon
				(pts
					(arc
						(start 342.030812 -59.30392)
						(mid 342.023386 -59.347228)
						(end 342.00084 -59.384946)
					)
					(xy 342.132412 -59.384946) (xy 342.132412 -59.145678)
					(arc
						(start 342.001348 -59.145678)
						(mid 342.023713 -59.183551)
						(end 342.030812 -59.226958)
					)
				)
			)
		)
		(zone
			(layer "F.Cu")
			(hatch none 0.5)
			(connect_pads
				(clearance 0)
			)
			(min_thickness 0.25)
			(keepout
				(tracks not_allowed)
				(vias allowed)
				(pads allowed)
				(copperpour not_allowed)
				(footprints allowed)
			)
			(placement
				(enabled no)
				(sheetname "")
			)
			(fill
				(thermal_gap 0.5)
				(thermal_bridge_width 0.5)
				(island_removal_mode 0)
			)
			(polygon
				(pts
					(arc
						(start 342.030812 -37.673788)
						(mid 342.023386 -37.717096)
						(end 342.00084 -37.754814)
					)
					(xy 342.132412 -37.754814) (xy 342.132412 -37.5158)
					(arc
						(start 342.001348 -37.5158)
						(mid 342.023669 -37.553554)
						(end 342.030812 -37.596826)
					)
				)
			)
		)
		(zone
			(layer "F.Cu")
			(hatch none 0.5)
			(connect_pads
				(clearance 0)
			)
			(min_thickness 0.25)
			(keepout
				(tracks not_allowed)
				(vias allowed)
				(pads allowed)
				(copperpour not_allowed)
				(footprints allowed)
			)
			(placement
				(enabled no)
				(sheetname "")
			)
			(fill
				(thermal_gap 0.5)
				(thermal_bridge_width 0.5)
				(island_removal_mode 0)
			)
			(polygon
				(pts
					(xy 342.672924 -59.384946)
					(arc
						(start 342.803988 -59.384946)
						(mid 342.781623 -59.347073)
						(end 342.774524 -59.303666)
					)
					(arc
						(start 342.774524 -59.226704)
						(mid 342.78195 -59.183396)
						(end 342.804496 -59.145678)
					)
					(xy 342.672924 -59.145678)
				)
			)
		)
		(zone
			(layer "F.Cu")
			(hatch none 0.5)
			(connect_pads
				(clearance 0)
			)
			(min_thickness 0.25)
			(keepout
				(tracks not_allowed)
				(vias allowed)
				(pads allowed)
				(copperpour not_allowed)
				(footprints allowed)
			)
			(placement
				(enabled no)
				(sheetname "")
			)
			(fill
				(thermal_gap 0.5)
				(thermal_bridge_width 0.5)
				(island_removal_mode 0)
			)
			(polygon
				(pts
					(xy 342.672924 -37.754814)
					(arc
						(start 342.803988 -37.754814)
						(mid 342.781623 -37.716941)
						(end 342.774524 -37.673534)
					)
					(arc
						(start 342.774524 -37.596826)
						(mid 342.78195 -37.553518)
						(end 342.804496 -37.5158)
					)
					(xy 342.672924 -37.5158)
				)
			)
		)
		(zone
			(layer "F.Cu")
			(hatch none 0.5)
			(connect_pads
				(clearance 0)
			)
			(min_thickness 0.25)
			(keepout
				(tracks not_allowed)
				(vias allowed)
				(pads allowed)
				(copperpour not_allowed)
				(footprints allowed)
			)
			(placement
				(enabled no)
				(sheetname "")
			)
			(fill
				(thermal_gap 0.5)
				(thermal_bridge_width 0.5)
				(island_removal_mode 0)
			)
			(polygon
				(pts
					(arc
						(start 343.031318 -59.30392)
						(mid 343.023892 -59.347228)
						(end 343.001346 -59.384946)
					)
					(xy 343.132918 -59.384946) (xy 343.132918 -59.145678)
					(arc
						(start 343.001854 -59.145678)
						(mid 343.024219 -59.183551)
						(end 343.031318 -59.226958)
					)
				)
			)
		)
		(zone
			(layer "F.Cu")
			(hatch none 0.5)
			(connect_pads
				(clearance 0)
			)
			(min_thickness 0.25)
			(keepout
				(tracks not_allowed)
				(vias allowed)
				(pads allowed)
				(copperpour not_allowed)
				(footprints allowed)
			)
			(placement
				(enabled no)
				(sheetname "")
			)
			(fill
				(thermal_gap 0.5)
				(thermal_bridge_width 0.5)
				(island_removal_mode 0)
			)
			(polygon
				(pts
					(arc
						(start 343.031318 -37.673788)
						(mid 343.023892 -37.717096)
						(end 343.001346 -37.754814)
					)
					(xy 343.132918 -37.754814) (xy 343.132918 -37.5158)
					(arc
						(start 343.001854 -37.5158)
						(mid 343.024175 -37.553554)
						(end 343.031318 -37.596826)
					)
				)
			)
		)
		(zone
			(layer "F.Cu")
			(hatch none 0.5)
			(connect_pads
				(clearance 0)
			)
			(min_thickness 0.25)
			(keepout
				(tracks not_allowed)
				(vias allowed)
				(pads allowed)
				(copperpour not_allowed)
				(footprints allowed)
			)
			(placement
				(enabled no)
				(sheetname "")
			)
			(fill
				(thermal_gap 0.5)
				(thermal_bridge_width 0.5)
				(island_removal_mode 0)
			)
			(polygon
				(pts
					(xy 343.67343 -59.384946)
					(arc
						(start 343.804494 -59.384946)
						(mid 343.782129 -59.347073)
						(end 343.77503 -59.303666)
					)
					(arc
						(start 343.77503 -59.226704)
						(mid 343.782456 -59.183396)
						(end 343.805002 -59.145678)
					)
					(xy 343.67343 -59.145678)
				)
			)
		)
		(zone
			(layer "F.Cu")
			(hatch none 0.5)
			(connect_pads
				(clearance 0)
			)
			(min_thickness 0.25)
			(keepout
				(tracks not_allowed)
				(vias allowed)
				(pads allowed)
				(copperpour not_allowed)
				(footprints allowed)
			)
			(placement
				(enabled no)
				(sheetname "")
			)
			(fill
				(thermal_gap 0.5)
				(thermal_bridge_width 0.5)
				(island_removal_mode 0)
			)
			(polygon
				(pts
					(xy 343.67343 -37.754814)
					(arc
						(start 343.804494 -37.754814)
						(mid 343.782129 -37.716941)
						(end 343.77503 -37.673534)
					)
					(arc
						(start 343.77503 -37.596826)
						(mid 343.782456 -37.553518)
						(end 343.805002 -37.5158)
					)
					(xy 343.67343 -37.5158)
				)
			)
		)
		(zone
			(layer "F.Cu")
			(hatch none 0.5)
			(connect_pads
				(clearance 0)
			)
			(min_thickness 0.25)
			(keepout
				(tracks not_allowed)
				(vias allowed)
				(pads allowed)
				(copperpour not_allowed)
				(footprints allowed)
			)
			(placement
				(enabled no)
				(sheetname "")
			)
			(fill
				(thermal_gap 0.5)
				(thermal_bridge_width 0.5)
				(island_removal_mode 0)
			)
			(polygon
				(pts
					(arc
						(start 344.031824 -59.30392)
						(mid 344.024398 -59.347228)
						(end 344.001852 -59.384946)
					)
					(xy 344.133424 -59.384946) (xy 344.133424 -59.145678)
					(arc
						(start 344.00236 -59.145678)
						(mid 344.024725 -59.183551)
						(end 344.031824 -59.226958)
					)
				)
			)
		)
		(zone
			(layer "F.Cu")
			(hatch none 0.5)
			(connect_pads
				(clearance 0)
			)
			(min_thickness 0.25)
			(keepout
				(tracks not_allowed)
				(vias allowed)
				(pads allowed)
				(copperpour not_allowed)
				(footprints allowed)
			)
			(placement
				(enabled no)
				(sheetname "")
			)
			(fill
				(thermal_gap 0.5)
				(thermal_bridge_width 0.5)
				(island_removal_mode 0)
			)
			(polygon
				(pts
					(arc
						(start 344.031824 -37.673788)
						(mid 344.024398 -37.717096)
						(end 344.001852 -37.754814)
					)
					(xy 344.133424 -37.754814) (xy 344.133424 -37.5158)
					(arc
						(start 344.00236 -37.5158)
						(mid 344.024681 -37.553554)
						(end 344.031824 -37.596826)
					)
				)
			)
		)
		(zone
			(layer "F.Cu")
			(hatch none 0.5)
			(connect_pads
				(clearance 0)
			)
			(min_thickness 0.25)
			(keepout
				(tracks not_allowed)
				(vias allowed)
				(pads allowed)
				(copperpour not_allowed)
				(footprints allowed)
			)
			(placement
				(enabled no)
				(sheetname "")
			)
			(fill
				(thermal_gap 0.5)
				(thermal_bridge_width 0.5)
				(island_removal_mode 0)
			)
			(polygon
				(pts
					(arc
						(start 347.253306 -55.825136)
						(mid 347.296646 -55.832672)
						(end 347.334332 -55.855362)
					)
					(xy 347.334332 -55.723536) (xy 347.095318 -55.723536)
					(arc
						(start 347.095318 -55.854854)
						(mid 347.133046 -55.832406)
						(end 347.176344 -55.825136)
					)
				)
			)
		)
		(zone
			(layer "F.Cu")
			(hatch none 0.5)
			(connect_pads
				(clearance 0)
			)
			(min_thickness 0.25)
			(keepout
				(tracks not_allowed)
				(vias allowed)
				(pads allowed)
				(copperpour not_allowed)
				(footprints allowed)
			)
			(placement
				(enabled no)
				(sheetname "")
			)
			(fill
				(thermal_gap 0.5)
				(thermal_bridge_width 0.5)
				(island_removal_mode 0)
			)
			(polygon
				(pts
					(arc
						(start 347.253306 -54.82463)
						(mid 347.296646 -54.832166)
						(end 347.334332 -54.854856)
					)
					(xy 347.334332 -54.72303) (xy 347.095318 -54.72303)
					(arc
						(start 347.095318 -54.854348)
						(mid 347.133046 -54.8319)
						(end 347.176344 -54.82463)
					)
				)
			)
		)
		(zone
			(layer "F.Cu")
			(hatch none 0.5)
			(connect_pads
				(clearance 0)
			)
			(min_thickness 0.25)
			(keepout
				(tracks not_allowed)
				(vias allowed)
				(pads allowed)
				(copperpour not_allowed)
				(footprints allowed)
			)
			(placement
				(enabled no)
				(sheetname "")
			)
			(fill
				(thermal_gap 0.5)
				(thermal_bridge_width 0.5)
				(island_removal_mode 0)
			)
			(polygon
				(pts
					(arc
						(start 347.253306 -53.824124)
						(mid 347.296646 -53.83166)
						(end 347.334332 -53.85435)
					)
					(xy 347.334332 -53.722524) (xy 347.095318 -53.722524)
					(arc
						(start 347.095318 -53.853842)
						(mid 347.133046 -53.831394)
						(end 347.176344 -53.824124)
					)
				)
			)
		)
		(zone
			(layer "F.Cu")
			(hatch none 0.5)
			(connect_pads
				(clearance 0)
			)
			(min_thickness 0.25)
			(keepout
				(tracks not_allowed)
				(vias allowed)
				(pads allowed)
				(copperpour not_allowed)
				(footprints allowed)
			)
			(placement
				(enabled no)
				(sheetname "")
			)
			(fill
				(thermal_gap 0.5)
				(thermal_bridge_width 0.5)
				(island_removal_mode 0)
			)
			(polygon
				(pts
					(arc
						(start 347.253306 -52.823872)
						(mid 347.296614 -52.831298)
						(end 347.334332 -52.853844)
					)
					(xy 347.334332 -52.722272) (xy 347.095318 -52.722272)
					(arc
						(start 347.095318 -52.853336)
						(mid 347.133072 -52.831015)
						(end 347.176344 -52.823872)
					)
				)
			)
		)
		(zone
			(layer "F.Cu")
			(hatch none 0.5)
			(connect_pads
				(clearance 0)
			)
			(min_thickness 0.25)
			(keepout
				(tracks not_allowed)
				(vias allowed)
				(pads allowed)
				(copperpour not_allowed)
				(footprints allowed)
			)
			(placement
				(enabled no)
				(sheetname "")
			)
			(fill
				(thermal_gap 0.5)
				(thermal_bridge_width 0.5)
				(island_removal_mode 0)
			)
			(polygon
				(pts
					(arc
						(start 347.253306 -51.823366)
						(mid 347.296614 -51.830792)
						(end 347.334332 -51.853338)
					)
					(xy 347.334332 -51.721766) (xy 347.095318 -51.721766)
					(arc
						(start 347.095318 -51.85283)
						(mid 347.133072 -51.830509)
						(end 347.176344 -51.823366)
					)
				)
			)
		)
		(zone
			(layer "F.Cu")
			(hatch none 0.5)
			(connect_pads
				(clearance 0)
			)
			(min_thickness 0.25)
			(keepout
				(tracks not_allowed)
				(vias allowed)
				(pads allowed)
				(copperpour not_allowed)
				(footprints allowed)
			)
			(placement
				(enabled no)
				(sheetname "")
			)
			(fill
				(thermal_gap 0.5)
				(thermal_bridge_width 0.5)
				(island_removal_mode 0)
			)
			(polygon
				(pts
					(arc
						(start 347.253306 -50.82286)
						(mid 347.296614 -50.830286)
						(end 347.334332 -50.852832)
					)
					(xy 347.334332 -50.72126) (xy 347.095318 -50.72126)
					(arc
						(start 347.095318 -50.852324)
						(mid 347.133072 -50.830003)
						(end 347.176344 -50.82286)
					)
				)
			)
		)
		(zone
			(layer "F.Cu")
			(hatch none 0.5)
			(connect_pads
				(clearance 0)
			)
			(min_thickness 0.25)
			(keepout
				(tracks not_allowed)
				(vias allowed)
				(pads allowed)
				(copperpour not_allowed)
				(footprints allowed)
			)
			(placement
				(enabled no)
				(sheetname "")
			)
			(fill
				(thermal_gap 0.5)
				(thermal_bridge_width 0.5)
				(island_removal_mode 0)
			)
			(polygon
				(pts
					(arc
						(start 347.253306 -49.822354)
						(mid 347.296614 -49.82978)
						(end 347.334332 -49.852326)
					)
					(xy 347.334332 -49.720754) (xy 347.095318 -49.720754)
					(arc
						(start 347.095318 -49.852072)
						(mid 347.133046 -49.829624)
						(end 347.176344 -49.822354)
					)
				)
			)
		)
		(zone
			(layer "F.Cu")
			(hatch none 0.5)
			(connect_pads
				(clearance 0)
			)
			(min_thickness 0.25)
			(keepout
				(tracks not_allowed)
				(vias allowed)
				(pads allowed)
				(copperpour not_allowed)
				(footprints allowed)
			)
			(placement
				(enabled no)
				(sheetname "")
			)
			(fill
				(thermal_gap 0.5)
				(thermal_bridge_width 0.5)
				(island_removal_mode 0)
			)
			(polygon
				(pts
					(arc
						(start 347.253306 -48.821848)
						(mid 347.296614 -48.829274)
						(end 347.334332 -48.85182)
					)
					(xy 347.334332 -48.720248) (xy 347.095318 -48.720248)
					(arc
						(start 347.095318 -48.851566)
						(mid 347.133046 -48.829118)
						(end 347.176344 -48.821848)
					)
				)
			)
		)
		(zone
			(layer "F.Cu")
			(hatch none 0.5)
			(connect_pads
				(clearance 0)
			)
			(min_thickness 0.25)
			(keepout
				(tracks not_allowed)
				(vias allowed)
				(pads allowed)
				(copperpour not_allowed)
				(footprints allowed)
			)
			(placement
				(enabled no)
				(sheetname "")
			)
			(fill
				(thermal_gap 0.5)
				(thermal_bridge_width 0.5)
				(island_removal_mode 0)
			)
			(polygon
				(pts
					(arc
						(start 347.253306 -47.821342)
						(mid 347.296646 -47.828878)
						(end 347.334332 -47.851568)
					)
					(xy 347.334332 -47.719742) (xy 347.095318 -47.719742)
					(arc
						(start 347.095318 -47.85106)
						(mid 347.133046 -47.828612)
						(end 347.176344 -47.821342)
					)
				)
			)
		)
		(zone
			(layer "F.Cu")
			(hatch none 0.5)
			(connect_pads
				(clearance 0)
			)
			(min_thickness 0.25)
			(keepout
				(tracks not_allowed)
				(vias allowed)
				(pads allowed)
				(copperpour not_allowed)
				(footprints allowed)
			)
			(placement
				(enabled no)
				(sheetname "")
			)
			(fill
				(thermal_gap 0.5)
				(thermal_bridge_width 0.5)
				(island_removal_mode 0)
			)
			(polygon
				(pts
					(arc
						(start 347.253306 -46.820836)
						(mid 347.296646 -46.828372)
						(end 347.334332 -46.851062)
					)
					(xy 347.334332 -46.719236) (xy 347.095318 -46.719236)
					(arc
						(start 347.095318 -46.850554)
						(mid 347.133046 -46.828106)
						(end 347.176344 -46.820836)
					)
				)
			)
		)
		(zone
			(layer "F.Cu")
			(hatch none 0.5)
			(connect_pads
				(clearance 0)
			)
			(min_thickness 0.25)
			(keepout
				(tracks not_allowed)
				(vias allowed)
				(pads allowed)
				(copperpour not_allowed)
				(footprints allowed)
			)
			(placement
				(enabled no)
				(sheetname "")
			)
			(fill
				(thermal_gap 0.5)
				(thermal_bridge_width 0.5)
				(island_removal_mode 0)
			)
			(polygon
				(pts
					(arc
						(start 347.253306 -45.82033)
						(mid 347.296646 -45.827866)
						(end 347.334332 -45.850556)
					)
					(xy 347.334332 -45.71873) (xy 347.095318 -45.71873)
					(arc
						(start 347.095318 -45.850048)
						(mid 347.133046 -45.8276)
						(end 347.176344 -45.82033)
					)
				)
			)
		)
		(zone
			(layer "F.Cu")
			(hatch none 0.5)
			(connect_pads
				(clearance 0)
			)
			(min_thickness 0.25)
			(keepout
				(tracks not_allowed)
				(vias allowed)
				(pads allowed)
				(copperpour not_allowed)
				(footprints allowed)
			)
			(placement
				(enabled no)
				(sheetname "")
			)
			(fill
				(thermal_gap 0.5)
				(thermal_bridge_width 0.5)
				(island_removal_mode 0)
			)
			(polygon
				(pts
					(arc
						(start 347.253306 -44.819824)
						(mid 347.296646 -44.82736)
						(end 347.334332 -44.85005)
					)
					(xy 347.334332 -44.718224) (xy 347.095318 -44.718224)
					(arc
						(start 347.095318 -44.849542)
						(mid 347.133046 -44.827094)
						(end 347.176344 -44.819824)
					)
				)
			)
		)
		(zone
			(layer "F.Cu")
			(hatch none 0.5)
			(connect_pads
				(clearance 0)
			)
			(min_thickness 0.25)
			(keepout
				(tracks not_allowed)
				(vias allowed)
				(pads allowed)
				(copperpour not_allowed)
				(footprints allowed)
			)
			(placement
				(enabled no)
				(sheetname "")
			)
			(fill
				(thermal_gap 0.5)
				(thermal_bridge_width 0.5)
				(island_removal_mode 0)
			)
			(polygon
				(pts
					(arc
						(start 347.253306 -43.819572)
						(mid 347.296614 -43.826998)
						(end 347.334332 -43.849544)
					)
					(xy 347.334332 -43.717972) (xy 347.095318 -43.717972)
					(arc
						(start 347.095318 -43.849036)
						(mid 347.133072 -43.826715)
						(end 347.176344 -43.819572)
					)
				)
			)
		)
		(zone
			(layer "F.Cu")
			(hatch none 0.5)
			(connect_pads
				(clearance 0)
			)
			(min_thickness 0.25)
			(keepout
				(tracks not_allowed)
				(vias allowed)
				(pads allowed)
				(copperpour not_allowed)
				(footprints allowed)
			)
			(placement
				(enabled no)
				(sheetname "")
			)
			(fill
				(thermal_gap 0.5)
				(thermal_bridge_width 0.5)
				(island_removal_mode 0)
			)
			(polygon
				(pts
					(arc
						(start 347.253306 -42.819066)
						(mid 347.296614 -42.826492)
						(end 347.334332 -42.849038)
					)
					(xy 347.334332 -42.717466) (xy 347.095318 -42.717466)
					(arc
						(start 347.095318 -42.84853)
						(mid 347.133072 -42.826209)
						(end 347.176344 -42.819066)
					)
				)
			)
		)
		(zone
			(layer "F.Cu")
			(hatch none 0.5)
			(connect_pads
				(clearance 0)
			)
			(min_thickness 0.25)
			(keepout
				(tracks not_allowed)
				(vias allowed)
				(pads allowed)
				(copperpour not_allowed)
				(footprints allowed)
			)
			(placement
				(enabled no)
				(sheetname "")
			)
			(fill
				(thermal_gap 0.5)
				(thermal_bridge_width 0.5)
				(island_removal_mode 0)
			)
			(polygon
				(pts
					(arc
						(start 347.253306 -41.81856)
						(mid 347.296614 -41.825986)
						(end 347.334332 -41.848532)
					)
					(xy 347.334332 -41.71696) (xy 347.095318 -41.71696)
					(arc
						(start 347.095318 -41.848024)
						(mid 347.133072 -41.825703)
						(end 347.176344 -41.81856)
					)
				)
			)
		)
		(zone
			(layer "F.Cu")
			(hatch none 0.5)
			(connect_pads
				(clearance 0)
			)
			(min_thickness 0.25)
			(keepout
				(tracks not_allowed)
				(vias allowed)
				(pads allowed)
				(copperpour not_allowed)
				(footprints allowed)
			)
			(placement
				(enabled no)
				(sheetname "")
			)
			(fill
				(thermal_gap 0.5)
				(thermal_bridge_width 0.5)
				(island_removal_mode 0)
			)
			(polygon
				(pts
					(arc
						(start 347.253306 -40.818054)
						(mid 347.296614 -40.82548)
						(end 347.334332 -40.848026)
					)
					(xy 347.334332 -40.716454) (xy 347.095318 -40.716454)
					(arc
						(start 347.095318 -40.847518)
						(mid 347.133072 -40.825197)
						(end 347.176344 -40.818054)
					)
				)
			)
		)
		(zone
			(layer "F.Cu")
			(hatch none 0.5)
			(connect_pads
				(clearance 0)
			)
			(min_thickness 0.25)
			(keepout
				(tracks not_allowed)
				(vias allowed)
				(pads allowed)
				(copperpour not_allowed)
				(footprints allowed)
			)
			(placement
				(enabled no)
				(sheetname "")
			)
			(fill
				(thermal_gap 0.5)
				(thermal_bridge_width 0.5)
				(island_removal_mode 0)
			)
			(polygon
				(pts
					(xy 347.334332 -56.183784)
					(arc
						(start 347.334332 -56.052466)
						(mid 347.296484 -56.074958)
						(end 347.253052 -56.082184)
					)
					(arc
						(start 347.176344 -56.082184)
						(mid 347.133004 -56.074648)
						(end 347.095318 -56.051958)
					)
					(xy 347.095318 -56.183784)
				)
			)
		)
		(zone
			(layer "F.Cu")
			(hatch none 0.5)
			(connect_pads
				(clearance 0)
			)
			(min_thickness 0.25)
			(keepout
				(tracks not_allowed)
				(vias allowed)
				(pads allowed)
				(copperpour not_allowed)
				(footprints allowed)
			)
			(placement
				(enabled no)
				(sheetname "")
			)
			(fill
				(thermal_gap 0.5)
				(thermal_bridge_width 0.5)
				(island_removal_mode 0)
			)
			(polygon
				(pts
					(xy 347.334332 -55.183278)
					(arc
						(start 347.334332 -55.05196)
						(mid 347.296484 -55.074452)
						(end 347.253052 -55.081678)
					)
					(arc
						(start 347.176344 -55.081678)
						(mid 347.133004 -55.074142)
						(end 347.095318 -55.051452)
					)
					(xy 347.095318 -55.183278)
				)
			)
		)
		(zone
			(layer "F.Cu")
			(hatch none 0.5)
			(connect_pads
				(clearance 0)
			)
			(min_thickness 0.25)
			(keepout
				(tracks not_allowed)
				(vias allowed)
				(pads allowed)
				(copperpour not_allowed)
				(footprints allowed)
			)
			(placement
				(enabled no)
				(sheetname "")
			)
			(fill
				(thermal_gap 0.5)
				(thermal_bridge_width 0.5)
				(island_removal_mode 0)
			)
			(polygon
				(pts
					(xy 347.334332 -54.182772)
					(arc
						(start 347.334332 -54.051454)
						(mid 347.296484 -54.073946)
						(end 347.253052 -54.081172)
					)
					(arc
						(start 347.176344 -54.081172)
						(mid 347.133004 -54.073636)
						(end 347.095318 -54.050946)
					)
					(xy 347.095318 -54.182772)
				)
			)
		)
		(zone
			(layer "F.Cu")
			(hatch none 0.5)
			(connect_pads
				(clearance 0)
			)
			(min_thickness 0.25)
			(keepout
				(tracks not_allowed)
				(vias allowed)
				(pads allowed)
				(copperpour not_allowed)
				(footprints allowed)
			)
			(placement
				(enabled no)
				(sheetname "")
			)
			(fill
				(thermal_gap 0.5)
				(thermal_bridge_width 0.5)
				(island_removal_mode 0)
			)
			(polygon
				(pts
					(xy 347.334332 -53.182266)
					(arc
						(start 347.334332 -53.051202)
						(mid 347.296459 -53.073567)
						(end 347.253052 -53.080666)
					)
					(arc
						(start 347.176344 -53.080666)
						(mid 347.133036 -53.07324)
						(end 347.095318 -53.050694)
					)
					(xy 347.095318 -53.182266)
				)
			)
		)
		(zone
			(layer "F.Cu")
			(hatch none 0.5)
			(connect_pads
				(clearance 0)
			)
			(min_thickness 0.25)
			(keepout
				(tracks not_allowed)
				(vias allowed)
				(pads allowed)
				(copperpour not_allowed)
				(footprints allowed)
			)
			(placement
				(enabled no)
				(sheetname "")
			)
			(fill
				(thermal_gap 0.5)
				(thermal_bridge_width 0.5)
				(island_removal_mode 0)
			)
			(polygon
				(pts
					(xy 347.334332 -52.18176)
					(arc
						(start 347.334332 -52.050696)
						(mid 347.296459 -52.073061)
						(end 347.253052 -52.08016)
					)
					(arc
						(start 347.176344 -52.08016)
						(mid 347.133036 -52.072734)
						(end 347.095318 -52.050188)
					)
					(xy 347.095318 -52.18176)
				)
			)
		)
		(zone
			(layer "F.Cu")
			(hatch none 0.5)
			(connect_pads
				(clearance 0)
			)
			(min_thickness 0.25)
			(keepout
				(tracks not_allowed)
				(vias allowed)
				(pads allowed)
				(copperpour not_allowed)
				(footprints allowed)
			)
			(placement
				(enabled no)
				(sheetname "")
			)
			(fill
				(thermal_gap 0.5)
				(thermal_bridge_width 0.5)
				(island_removal_mode 0)
			)
			(polygon
				(pts
					(xy 347.334332 -51.181254)
					(arc
						(start 347.334332 -51.05019)
						(mid 347.296459 -51.072555)
						(end 347.253052 -51.079654)
					)
					(arc
						(start 347.176344 -51.079654)
						(mid 347.133036 -51.072228)
						(end 347.095318 -51.049682)
					)
					(xy 347.095318 -51.181254)
				)
			)
		)
		(zone
			(layer "F.Cu")
			(hatch none 0.5)
			(connect_pads
				(clearance 0)
			)
			(min_thickness 0.25)
			(keepout
				(tracks not_allowed)
				(vias allowed)
				(pads allowed)
				(copperpour not_allowed)
				(footprints allowed)
			)
			(placement
				(enabled no)
				(sheetname "")
			)
			(fill
				(thermal_gap 0.5)
				(thermal_bridge_width 0.5)
				(island_removal_mode 0)
			)
			(polygon
				(pts
					(xy 347.334332 -50.180748)
					(arc
						(start 347.334332 -50.049684)
						(mid 347.296459 -50.072049)
						(end 347.253052 -50.079148)
					)
					(arc
						(start 347.176344 -50.079148)
						(mid 347.133036 -50.071722)
						(end 347.095318 -50.049176)
					)
					(xy 347.095318 -50.180748)
				)
			)
		)
		(zone
			(layer "F.Cu")
			(hatch none 0.5)
			(connect_pads
				(clearance 0)
			)
			(min_thickness 0.25)
			(keepout
				(tracks not_allowed)
				(vias allowed)
				(pads allowed)
				(copperpour not_allowed)
				(footprints allowed)
			)
			(placement
				(enabled no)
				(sheetname "")
			)
			(fill
				(thermal_gap 0.5)
				(thermal_bridge_width 0.5)
				(island_removal_mode 0)
			)
			(polygon
				(pts
					(xy 347.334332 -49.180242)
					(arc
						(start 347.334332 -49.049178)
						(mid 347.296459 -49.071543)
						(end 347.253052 -49.078642)
					)
					(arc
						(start 347.176344 -49.078642)
						(mid 347.133036 -49.071216)
						(end 347.095318 -49.04867)
					)
					(xy 347.095318 -49.180242)
				)
			)
		)
		(zone
			(layer "F.Cu")
			(hatch none 0.5)
			(connect_pads
				(clearance 0)
			)
			(min_thickness 0.25)
			(keepout
				(tracks not_allowed)
				(vias allowed)
				(pads allowed)
				(copperpour not_allowed)
				(footprints allowed)
			)
			(placement
				(enabled no)
				(sheetname "")
			)
			(fill
				(thermal_gap 0.5)
				(thermal_bridge_width 0.5)
				(island_removal_mode 0)
			)
			(polygon
				(pts
					(xy 347.334332 -48.179736)
					(arc
						(start 347.334332 -48.048672)
						(mid 347.296459 -48.071037)
						(end 347.253052 -48.078136)
					)
					(arc
						(start 347.176344 -48.078136)
						(mid 347.133036 -48.07071)
						(end 347.095318 -48.048164)
					)
					(xy 347.095318 -48.179736)
				)
			)
		)
		(zone
			(layer "F.Cu")
			(hatch none 0.5)
			(connect_pads
				(clearance 0)
			)
			(min_thickness 0.25)
			(keepout
				(tracks not_allowed)
				(vias allowed)
				(pads allowed)
				(copperpour not_allowed)
				(footprints allowed)
			)
			(placement
				(enabled no)
				(sheetname "")
			)
			(fill
				(thermal_gap 0.5)
				(thermal_bridge_width 0.5)
				(island_removal_mode 0)
			)
			(polygon
				(pts
					(xy 347.334332 -47.17923)
					(arc
						(start 347.334332 -47.048166)
						(mid 347.296459 -47.070531)
						(end 347.253052 -47.07763)
					)
					(arc
						(start 347.176344 -47.07763)
						(mid 347.133036 -47.070204)
						(end 347.095318 -47.047658)
					)
					(xy 347.095318 -47.17923)
				)
			)
		)
		(zone
			(layer "F.Cu")
			(hatch none 0.5)
			(connect_pads
				(clearance 0)
			)
			(min_thickness 0.25)
			(keepout
				(tracks not_allowed)
				(vias allowed)
				(pads allowed)
				(copperpour not_allowed)
				(footprints allowed)
			)
			(placement
				(enabled no)
				(sheetname "")
			)
			(fill
				(thermal_gap 0.5)
				(thermal_bridge_width 0.5)
				(island_removal_mode 0)
			)
			(polygon
				(pts
					(xy 347.334332 -46.178724)
					(arc
						(start 347.334332 -46.04766)
						(mid 347.296459 -46.070025)
						(end 347.253052 -46.077124)
					)
					(arc
						(start 347.176344 -46.077124)
						(mid 347.133047 -46.069686)
						(end 347.095318 -46.047152)
					)
					(xy 347.095318 -46.178724)
				)
			)
		)
		(zone
			(layer "F.Cu")
			(hatch none 0.5)
			(connect_pads
				(clearance 0)
			)
			(min_thickness 0.25)
			(keepout
				(tracks not_allowed)
				(vias allowed)
				(pads allowed)
				(copperpour not_allowed)
				(footprints allowed)
			)
			(placement
				(enabled no)
				(sheetname "")
			)
			(fill
				(thermal_gap 0.5)
				(thermal_bridge_width 0.5)
				(island_removal_mode 0)
			)
			(polygon
				(pts
					(xy 347.334332 -45.178472)
					(arc
						(start 347.334332 -45.047154)
						(mid 347.296484 -45.069646)
						(end 347.253052 -45.076872)
					)
					(arc
						(start 347.176344 -45.076872)
						(mid 347.133004 -45.069336)
						(end 347.095318 -45.046646)
					)
					(xy 347.095318 -45.178472)
				)
			)
		)
		(zone
			(layer "F.Cu")
			(hatch none 0.5)
			(connect_pads
				(clearance 0)
			)
			(min_thickness 0.25)
			(keepout
				(tracks not_allowed)
				(vias allowed)
				(pads allowed)
				(copperpour not_allowed)
				(footprints allowed)
			)
			(placement
				(enabled no)
				(sheetname "")
			)
			(fill
				(thermal_gap 0.5)
				(thermal_bridge_width 0.5)
				(island_removal_mode 0)
			)
			(polygon
				(pts
					(xy 347.334332 -44.177966)
					(arc
						(start 347.334332 -44.046648)
						(mid 347.296484 -44.06914)
						(end 347.253052 -44.076366)
					)
					(arc
						(start 347.176344 -44.076366)
						(mid 347.133004 -44.06883)
						(end 347.095318 -44.04614)
					)
					(xy 347.095318 -44.177966)
				)
			)
		)
		(zone
			(layer "F.Cu")
			(hatch none 0.5)
			(connect_pads
				(clearance 0)
			)
			(min_thickness 0.25)
			(keepout
				(tracks not_allowed)
				(vias allowed)
				(pads allowed)
				(copperpour not_allowed)
				(footprints allowed)
			)
			(placement
				(enabled no)
				(sheetname "")
			)
			(fill
				(thermal_gap 0.5)
				(thermal_bridge_width 0.5)
				(island_removal_mode 0)
			)
			(polygon
				(pts
					(xy 347.334332 -43.17746)
					(arc
						(start 347.334332 -43.046142)
						(mid 347.296484 -43.068634)
						(end 347.253052 -43.07586)
					)
					(arc
						(start 347.176344 -43.07586)
						(mid 347.133004 -43.068324)
						(end 347.095318 -43.045634)
					)
					(xy 347.095318 -43.17746)
				)
			)
		)
		(zone
			(layer "F.Cu")
			(hatch none 0.5)
			(connect_pads
				(clearance 0)
			)
			(min_thickness 0.25)
			(keepout
				(tracks not_allowed)
				(vias allowed)
				(pads allowed)
				(copperpour not_allowed)
				(footprints allowed)
			)
			(placement
				(enabled no)
				(sheetname "")
			)
			(fill
				(thermal_gap 0.5)
				(thermal_bridge_width 0.5)
				(island_removal_mode 0)
			)
			(polygon
				(pts
					(xy 347.334332 -42.176954)
					(arc
						(start 347.334332 -42.045636)
						(mid 347.296484 -42.068128)
						(end 347.253052 -42.075354)
					)
					(arc
						(start 347.176344 -42.075354)
						(mid 347.133004 -42.067818)
						(end 347.095318 -42.045128)
					)
					(xy 347.095318 -42.176954)
				)
			)
		)
		(zone
			(layer "F.Cu")
			(hatch none 0.5)
			(connect_pads
				(clearance 0)
			)
			(min_thickness 0.25)
			(keepout
				(tracks not_allowed)
				(vias allowed)
				(pads allowed)
				(copperpour not_allowed)
				(footprints allowed)
			)
			(placement
				(enabled no)
				(sheetname "")
			)
			(fill
				(thermal_gap 0.5)
				(thermal_bridge_width 0.5)
				(island_removal_mode 0)
			)
			(polygon
				(pts
					(xy 347.334332 -41.176448)
					(arc
						(start 347.334332 -41.04513)
						(mid 347.296484 -41.067622)
						(end 347.253052 -41.074848)
					)
					(arc
						(start 347.176344 -41.074848)
						(mid 347.133004 -41.067312)
						(end 347.095318 -41.044622)
					)
					(xy 347.095318 -41.176448)
				)
			)
		)
		(zone
			(layer "F.Cu")
			(hatch none 0.5)
			(connect_pads
				(clearance 0)
			)
			(min_thickness 0.25)
			(keepout
				(tracks not_allowed)
				(vias allowed)
				(pads allowed)
				(copperpour not_allowed)
				(footprints allowed)
			)
			(placement
				(enabled no)
				(sheetname "")
			)
			(fill
				(thermal_gap 0.5)
				(thermal_bridge_width 0.5)
				(island_removal_mode 0)
			)
			(polygon
				(pts
					(arc
						(start 326.439784 -39.996872)
						(mid 326.476015 -40.054731)
						(end 326.533764 -40.091106)
					)
					(arc
						(start 326.533764 -40.196262)
						(mid 326.404043 -40.126593)
						(end 326.334374 -39.996872)
					)
				)
			)
		)
		(zone
			(layer "F.Cu")
			(hatch none 0.5)
			(connect_pads
				(clearance 0)
			)
			(min_thickness 0.25)
			(keepout
				(tracks not_allowed)
				(vias allowed)
				(pads allowed)
				(copperpour not_allowed)
				(footprints allowed)
			)
			(placement
				(enabled no)
				(sheetname "")
			)
			(fill
				(thermal_gap 0.5)
				(thermal_bridge_width 0.5)
				(island_removal_mode 0)
			)
			(polygon
				(pts
					(arc
						(start 326.533764 -39.801038)
						(mid 326.476065 -39.837464)
						(end 326.439784 -39.895272)
					)
					(arc
						(start 326.334374 -39.895272)
						(mid 326.404043 -39.765551)
						(end 326.533764 -39.695882)
					)
				)
			)
		)
		(zone
			(layer "F.Cu")
			(hatch none 0.5)
			(connect_pads
				(clearance 0)
			)
			(min_thickness 0.25)
			(keepout
				(tracks not_allowed)
				(vias allowed)
				(pads allowed)
				(copperpour not_allowed)
				(footprints allowed)
			)
			(placement
				(enabled no)
				(sheetname "")
			)
			(fill
				(thermal_gap 0.5)
				(thermal_bridge_width 0.5)
				(island_removal_mode 0)
			)
			(polygon
				(pts
					(arc
						(start 326.635364 -40.091106)
						(mid 326.693227 -40.054735)
						(end 326.729598 -39.996872)
					)
					(arc
						(start 326.834754 -39.996872)
						(mid 326.765085 -40.126593)
						(end 326.635364 -40.196262)
					)
				)
			)
		)
		(zone
			(layer "F.Cu")
			(hatch none 0.5)
			(connect_pads
				(clearance 0)
			)
			(min_thickness 0.25)
			(keepout
				(tracks not_allowed)
				(vias allowed)
				(pads allowed)
				(copperpour not_allowed)
				(footprints allowed)
			)
			(placement
				(enabled no)
				(sheetname "")
			)
			(fill
				(thermal_gap 0.5)
				(thermal_bridge_width 0.5)
				(island_removal_mode 0)
			)
			(polygon
				(pts
					(arc
						(start 326.729598 -39.895272)
						(mid 326.693227 -39.837409)
						(end 326.635364 -39.801038)
					)
					(arc
						(start 326.635364 -39.695882)
						(mid 326.765085 -39.765551)
						(end 326.834754 -39.895272)
					)
				)
			)
		)
		(zone
			(layer "F.Cu")
			(hatch none 0.5)
			(connect_pads
				(clearance 0)
			)
			(min_thickness 0.25)
			(keepout
				(tracks not_allowed)
				(vias allowed)
				(pads allowed)
				(copperpour not_allowed)
				(footprints allowed)
			)
			(placement
				(enabled no)
				(sheetname "")
			)
			(fill
				(thermal_gap 0.5)
				(thermal_bridge_width 0.5)
				(island_removal_mode 0)
			)
			(polygon
				(pts
					(arc
						(start 326.854566 -57.505346)
						(mid 326.890937 -57.563209)
						(end 326.9488 -57.59958)
					)
					(arc
						(start 326.9488 -57.704736)
						(mid 326.819079 -57.635067)
						(end 326.74941 -57.505346)
					)
				)
			)
		)
		(zone
			(layer "F.Cu")
			(hatch none 0.5)
			(connect_pads
				(clearance 0)
			)
			(min_thickness 0.25)
			(keepout
				(tracks not_allowed)
				(vias allowed)
				(pads allowed)
				(copperpour not_allowed)
				(footprints allowed)
			)
			(placement
				(enabled no)
				(sheetname "")
			)
			(fill
				(thermal_gap 0.5)
				(thermal_bridge_width 0.5)
				(island_removal_mode 0)
			)
			(polygon
				(pts
					(arc
						(start 326.854566 -56.50484)
						(mid 326.890937 -56.562703)
						(end 326.9488 -56.599074)
					)
					(arc
						(start 326.9488 -56.70423)
						(mid 326.819079 -56.634561)
						(end 326.74941 -56.50484)
					)
				)
			)
		)
		(zone
			(layer "F.Cu")
			(hatch none 0.5)
			(connect_pads
				(clearance 0)
			)
			(min_thickness 0.25)
			(keepout
				(tracks not_allowed)
				(vias allowed)
				(pads allowed)
				(copperpour not_allowed)
				(footprints allowed)
			)
			(placement
				(enabled no)
				(sheetname "")
			)
			(fill
				(thermal_gap 0.5)
				(thermal_bridge_width 0.5)
				(island_removal_mode 0)
			)
			(polygon
				(pts
					(arc
						(start 326.854566 -55.504334)
						(mid 326.890937 -55.562197)
						(end 326.9488 -55.598568)
					)
					(arc
						(start 326.9488 -55.703724)
						(mid 326.819079 -55.634055)
						(end 326.74941 -55.504334)
					)
				)
			)
		)
		(zone
			(layer "F.Cu")
			(hatch none 0.5)
			(connect_pads
				(clearance 0)
			)
			(min_thickness 0.25)
			(keepout
				(tracks not_allowed)
				(vias allowed)
				(pads allowed)
				(copperpour not_allowed)
				(footprints allowed)
			)
			(placement
				(enabled no)
				(sheetname "")
			)
			(fill
				(thermal_gap 0.5)
				(thermal_bridge_width 0.5)
				(island_removal_mode 0)
			)
			(polygon
				(pts
					(arc
						(start 326.854566 -54.503828)
						(mid 326.890937 -54.561691)
						(end 326.9488 -54.598062)
					)
					(arc
						(start 326.9488 -54.703472)
						(mid 326.818991 -54.633715)
						(end 326.74941 -54.503828)
					)
				)
			)
		)
		(zone
			(layer "F.Cu")
			(hatch none 0.5)
			(connect_pads
				(clearance 0)
			)
			(min_thickness 0.25)
			(keepout
				(tracks not_allowed)
				(vias allowed)
				(pads allowed)
				(copperpour not_allowed)
				(footprints allowed)
			)
			(placement
				(enabled no)
				(sheetname "")
			)
			(fill
				(thermal_gap 0.5)
				(thermal_bridge_width 0.5)
				(island_removal_mode 0)
			)
			(polygon
				(pts
					(arc
						(start 326.854566 -53.503322)
						(mid 326.890937 -53.561185)
						(end 326.9488 -53.597556)
					)
					(arc
						(start 326.9488 -53.702966)
						(mid 326.818991 -53.633209)
						(end 326.74941 -53.503322)
					)
				)
			)
		)
		(zone
			(layer "F.Cu")
			(hatch none 0.5)
			(connect_pads
				(clearance 0)
			)
			(min_thickness 0.25)
			(keepout
				(tracks not_allowed)
				(vias allowed)
				(pads allowed)
				(copperpour not_allowed)
				(footprints allowed)
			)
			(placement
				(enabled no)
				(sheetname "")
			)
			(fill
				(thermal_gap 0.5)
				(thermal_bridge_width 0.5)
				(island_removal_mode 0)
			)
			(polygon
				(pts
					(arc
						(start 326.854566 -52.50307)
						(mid 326.890937 -52.560933)
						(end 326.9488 -52.597304)
					)
					(arc
						(start 326.9488 -52.70246)
						(mid 326.819079 -52.632791)
						(end 326.74941 -52.50307)
					)
				)
			)
		)
		(zone
			(layer "F.Cu")
			(hatch none 0.5)
			(connect_pads
				(clearance 0)
			)
			(min_thickness 0.25)
			(keepout
				(tracks not_allowed)
				(vias allowed)
				(pads allowed)
				(copperpour not_allowed)
				(footprints allowed)
			)
			(placement
				(enabled no)
				(sheetname "")
			)
			(fill
				(thermal_gap 0.5)
				(thermal_bridge_width 0.5)
				(island_removal_mode 0)
			)
			(polygon
				(pts
					(arc
						(start 326.854566 -51.502564)
						(mid 326.890937 -51.560427)
						(end 326.9488 -51.596798)
					)
					(arc
						(start 326.9488 -51.701954)
						(mid 326.819079 -51.632285)
						(end 326.74941 -51.502564)
					)
				)
			)
		)
		(zone
			(layer "F.Cu")
			(hatch none 0.5)
			(connect_pads
				(clearance 0)
			)
			(min_thickness 0.25)
			(keepout
				(tracks not_allowed)
				(vias allowed)
				(pads allowed)
				(copperpour not_allowed)
				(footprints allowed)
			)
			(placement
				(enabled no)
				(sheetname "")
			)
			(fill
				(thermal_gap 0.5)
				(thermal_bridge_width 0.5)
				(island_removal_mode 0)
			)
			(polygon
				(pts
					(arc
						(start 326.854566 -50.502058)
						(mid 326.890937 -50.559921)
						(end 326.9488 -50.596292)
					)
					(arc
						(start 326.9488 -50.701448)
						(mid 326.819079 -50.631779)
						(end 326.74941 -50.502058)
					)
				)
			)
		)
		(zone
			(layer "F.Cu")
			(hatch none 0.5)
			(connect_pads
				(clearance 0)
			)
			(min_thickness 0.25)
			(keepout
				(tracks not_allowed)
				(vias allowed)
				(pads allowed)
				(copperpour not_allowed)
				(footprints allowed)
			)
			(placement
				(enabled no)
				(sheetname "")
			)
			(fill
				(thermal_gap 0.5)
				(thermal_bridge_width 0.5)
				(island_removal_mode 0)
			)
			(polygon
				(pts
					(arc
						(start 326.854566 -49.501552)
						(mid 326.890937 -49.559415)
						(end 326.9488 -49.595786)
					)
					(arc
						(start 326.9488 -49.700942)
						(mid 326.819079 -49.631273)
						(end 326.74941 -49.501552)
					)
				)
			)
		)
		(zone
			(layer "F.Cu")
			(hatch none 0.5)
			(connect_pads
				(clearance 0)
			)
			(min_thickness 0.25)
			(keepout
				(tracks not_allowed)
				(vias allowed)
				(pads allowed)
				(copperpour not_allowed)
				(footprints allowed)
			)
			(placement
				(enabled no)
				(sheetname "")
			)
			(fill
				(thermal_gap 0.5)
				(thermal_bridge_width 0.5)
				(island_removal_mode 0)
			)
			(polygon
				(pts
					(arc
						(start 326.854566 -48.501046)
						(mid 326.890937 -48.558909)
						(end 326.9488 -48.59528)
					)
					(arc
						(start 326.9488 -48.700436)
						(mid 326.819079 -48.630767)
						(end 326.74941 -48.501046)
					)
				)
			)
		)
		(zone
			(layer "F.Cu")
			(hatch none 0.5)
			(connect_pads
				(clearance 0)
			)
			(min_thickness 0.25)
			(keepout
				(tracks not_allowed)
				(vias allowed)
				(pads allowed)
				(copperpour not_allowed)
				(footprints allowed)
			)
			(placement
				(enabled no)
				(sheetname "")
			)
			(fill
				(thermal_gap 0.5)
				(thermal_bridge_width 0.5)
				(island_removal_mode 0)
			)
			(polygon
				(pts
					(arc
						(start 326.854566 -47.50054)
						(mid 326.890937 -47.558403)
						(end 326.9488 -47.594774)
					)
					(arc
						(start 326.9488 -47.69993)
						(mid 326.819079 -47.630261)
						(end 326.74941 -47.50054)
					)
				)
			)
		)
		(zone
			(layer "F.Cu")
			(hatch none 0.5)
			(connect_pads
				(clearance 0)
			)
			(min_thickness 0.25)
			(keepout
				(tracks not_allowed)
				(vias allowed)
				(pads allowed)
				(copperpour not_allowed)
				(footprints allowed)
			)
			(placement
				(enabled no)
				(sheetname "")
			)
			(fill
				(thermal_gap 0.5)
				(thermal_bridge_width 0.5)
				(island_removal_mode 0)
			)
			(polygon
				(pts
					(arc
						(start 326.854566 -46.500034)
						(mid 326.890937 -46.557897)
						(end 326.9488 -46.594268)
					)
					(arc
						(start 326.9488 -46.699424)
						(mid 326.819079 -46.629755)
						(end 326.74941 -46.500034)
					)
				)
			)
		)
		(zone
			(layer "F.Cu")
			(hatch none 0.5)
			(connect_pads
				(clearance 0)
			)
			(min_thickness 0.25)
			(keepout
				(tracks not_allowed)
				(vias allowed)
				(pads allowed)
				(copperpour not_allowed)
				(footprints allowed)
			)
			(placement
				(enabled no)
				(sheetname "")
			)
			(fill
				(thermal_gap 0.5)
				(thermal_bridge_width 0.5)
				(island_removal_mode 0)
			)
			(polygon
				(pts
					(arc
						(start 326.854566 -45.499528)
						(mid 326.890937 -45.557391)
						(end 326.9488 -45.593762)
					)
					(arc
						(start 326.9488 -45.698918)
						(mid 326.819079 -45.629249)
						(end 326.74941 -45.499528)
					)
				)
			)
		)
		(zone
			(layer "F.Cu")
			(hatch none 0.5)
			(connect_pads
				(clearance 0)
			)
			(min_thickness 0.25)
			(keepout
				(tracks not_allowed)
				(vias allowed)
				(pads allowed)
				(copperpour not_allowed)
				(footprints allowed)
			)
			(placement
				(enabled no)
				(sheetname "")
			)
			(fill
				(thermal_gap 0.5)
				(thermal_bridge_width 0.5)
				(island_removal_mode 0)
			)
			(polygon
				(pts
					(arc
						(start 326.854566 -44.499022)
						(mid 326.890937 -44.556885)
						(end 326.9488 -44.593256)
					)
					(arc
						(start 326.9488 -44.698412)
						(mid 326.819079 -44.628743)
						(end 326.74941 -44.499022)
					)
				)
			)
		)
		(zone
			(layer "F.Cu")
			(hatch none 0.5)
			(connect_pads
				(clearance 0)
			)
			(min_thickness 0.25)
			(keepout
				(tracks not_allowed)
				(vias allowed)
				(pads allowed)
				(copperpour not_allowed)
				(footprints allowed)
			)
			(placement
				(enabled no)
				(sheetname "")
			)
			(fill
				(thermal_gap 0.5)
				(thermal_bridge_width 0.5)
				(island_removal_mode 0)
			)
			(polygon
				(pts
					(arc
						(start 326.854566 -43.49877)
						(mid 326.890962 -43.556524)
						(end 326.9488 -43.59275)
					)
					(arc
						(start 326.9488 -43.69816)
						(mid 326.819079 -43.628491)
						(end 326.74941 -43.49877)
					)
				)
			)
		)
		(zone
			(layer "F.Cu")
			(hatch none 0.5)
			(connect_pads
				(clearance 0)
			)
			(min_thickness 0.25)
			(keepout
				(tracks not_allowed)
				(vias allowed)
				(pads allowed)
				(copperpour not_allowed)
				(footprints allowed)
			)
			(placement
				(enabled no)
				(sheetname "")
			)
			(fill
				(thermal_gap 0.5)
				(thermal_bridge_width 0.5)
				(island_removal_mode 0)
			)
			(polygon
				(pts
					(arc
						(start 326.854566 -42.498264)
						(mid 326.890962 -42.556018)
						(end 326.9488 -42.592244)
					)
					(arc
						(start 326.9488 -42.697654)
						(mid 326.819079 -42.627985)
						(end 326.74941 -42.498264)
					)
				)
			)
		)
		(zone
			(layer "F.Cu")
			(hatch none 0.5)
			(connect_pads
				(clearance 0)
			)
			(min_thickness 0.25)
			(keepout
				(tracks not_allowed)
				(vias allowed)
				(pads allowed)
				(copperpour not_allowed)
				(footprints allowed)
			)
			(placement
				(enabled no)
				(sheetname "")
			)
			(fill
				(thermal_gap 0.5)
				(thermal_bridge_width 0.5)
				(island_removal_mode 0)
			)
			(polygon
				(pts
					(arc
						(start 326.854566 -41.497758)
						(mid 326.890962 -41.555512)
						(end 326.9488 -41.591738)
					)
					(arc
						(start 326.9488 -41.697148)
						(mid 326.819079 -41.627479)
						(end 326.74941 -41.497758)
					)
				)
			)
		)
		(zone
			(layer "F.Cu")
			(hatch none 0.5)
			(connect_pads
				(clearance 0)
			)
			(min_thickness 0.25)
			(keepout
				(tracks not_allowed)
				(vias allowed)
				(pads allowed)
				(copperpour not_allowed)
				(footprints allowed)
			)
			(placement
				(enabled no)
				(sheetname "")
			)
			(fill
				(thermal_gap 0.5)
				(thermal_bridge_width 0.5)
				(island_removal_mode 0)
			)
			(polygon
				(pts
					(arc
						(start 326.854566 -40.497252)
						(mid 326.890962 -40.555006)
						(end 326.9488 -40.591232)
					)
					(arc
						(start 326.9488 -40.696642)
						(mid 326.819079 -40.626973)
						(end 326.74941 -40.497252)
					)
				)
			)
		)
		(zone
			(layer "F.Cu")
			(hatch none 0.5)
			(connect_pads
				(clearance 0)
			)
			(min_thickness 0.25)
			(keepout
				(tracks not_allowed)
				(vias allowed)
				(pads allowed)
				(copperpour not_allowed)
				(footprints allowed)
			)
			(placement
				(enabled no)
				(sheetname "")
			)
			(fill
				(thermal_gap 0.5)
				(thermal_bridge_width 0.5)
				(island_removal_mode 0)
			)
			(polygon
				(pts
					(arc
						(start 326.854566 -39.496746)
						(mid 326.890962 -39.5545)
						(end 326.9488 -39.590726)
					)
					(arc
						(start 326.9488 -39.696136)
						(mid 326.819079 -39.626467)
						(end 326.74941 -39.496746)
					)
				)
			)
		)
		(zone
			(layer "F.Cu")
			(hatch none 0.5)
			(connect_pads
				(clearance 0)
			)
			(min_thickness 0.25)
			(keepout
				(tracks not_allowed)
				(vias allowed)
				(pads allowed)
				(copperpour not_allowed)
				(footprints allowed)
			)
			(placement
				(enabled no)
				(sheetname "")
			)
			(fill
				(thermal_gap 0.5)
				(thermal_bridge_width 0.5)
				(island_removal_mode 0)
			)
			(polygon
				(pts
					(arc
						(start 326.9488 -57.309766)
						(mid 326.891021 -57.346052)
						(end 326.854566 -57.403746)
					)
					(arc
						(start 326.74941 -57.403746)
						(mid 326.819079 -57.274025)
						(end 326.9488 -57.204356)
					)
				)
			)
		)
		(zone
			(layer "F.Cu")
			(hatch none 0.5)
			(connect_pads
				(clearance 0)
			)
			(min_thickness 0.25)
			(keepout
				(tracks not_allowed)
				(vias allowed)
				(pads allowed)
				(copperpour not_allowed)
				(footprints allowed)
			)
			(placement
				(enabled no)
				(sheetname "")
			)
			(fill
				(thermal_gap 0.5)
				(thermal_bridge_width 0.5)
				(island_removal_mode 0)
			)
			(polygon
				(pts
					(arc
						(start 326.9488 -56.30926)
						(mid 326.891021 -56.345546)
						(end 326.854566 -56.40324)
					)
					(arc
						(start 326.74941 -56.40324)
						(mid 326.819079 -56.273519)
						(end 326.9488 -56.20385)
					)
				)
			)
		)
		(zone
			(layer "F.Cu")
			(hatch none 0.5)
			(connect_pads
				(clearance 0)
			)
			(min_thickness 0.25)
			(keepout
				(tracks not_allowed)
				(vias allowed)
				(pads allowed)
				(copperpour not_allowed)
				(footprints allowed)
			)
			(placement
				(enabled no)
				(sheetname "")
			)
			(fill
				(thermal_gap 0.5)
				(thermal_bridge_width 0.5)
				(island_removal_mode 0)
			)
			(polygon
				(pts
					(arc
						(start 326.9488 -55.308754)
						(mid 326.891021 -55.34504)
						(end 326.854566 -55.402734)
					)
					(arc
						(start 326.74941 -55.402734)
						(mid 326.819079 -55.273013)
						(end 326.9488 -55.203344)
					)
				)
			)
		)
		(zone
			(layer "F.Cu")
			(hatch none 0.5)
			(connect_pads
				(clearance 0)
			)
			(min_thickness 0.25)
			(keepout
				(tracks not_allowed)
				(vias allowed)
				(pads allowed)
				(copperpour not_allowed)
				(footprints allowed)
			)
			(placement
				(enabled no)
				(sheetname "")
			)
			(fill
				(thermal_gap 0.5)
				(thermal_bridge_width 0.5)
				(island_removal_mode 0)
			)
			(polygon
				(pts
					(arc
						(start 326.9488 -54.308248)
						(mid 326.891021 -54.344534)
						(end 326.854566 -54.402228)
					)
					(arc
						(start 326.74941 -54.402228)
						(mid 326.819079 -54.272507)
						(end 326.9488 -54.202838)
					)
				)
			)
		)
		(zone
			(layer "F.Cu")
			(hatch none 0.5)
			(connect_pads
				(clearance 0)
			)
			(min_thickness 0.25)
			(keepout
				(tracks not_allowed)
				(vias allowed)
				(pads allowed)
				(copperpour not_allowed)
				(footprints allowed)
			)
			(placement
				(enabled no)
				(sheetname "")
			)
			(fill
				(thermal_gap 0.5)
				(thermal_bridge_width 0.5)
				(island_removal_mode 0)
			)
			(polygon
				(pts
					(arc
						(start 326.9488 -53.307742)
						(mid 326.891021 -53.344028)
						(end 326.854566 -53.401722)
					)
					(arc
						(start 326.74941 -53.401722)
						(mid 326.819079 -53.272001)
						(end 326.9488 -53.202332)
					)
				)
			)
		)
		(zone
			(layer "F.Cu")
			(hatch none 0.5)
			(connect_pads
				(clearance 0)
			)
			(min_thickness 0.25)
			(keepout
				(tracks not_allowed)
				(vias allowed)
				(pads allowed)
				(copperpour not_allowed)
				(footprints allowed)
			)
			(placement
				(enabled no)
				(sheetname "")
			)
			(fill
				(thermal_gap 0.5)
				(thermal_bridge_width 0.5)
				(island_removal_mode 0)
			)
			(polygon
				(pts
					(arc
						(start 326.9488 -52.307236)
						(mid 326.890937 -52.343607)
						(end 326.854566 -52.40147)
					)
					(arc
						(start 326.74941 -52.40147)
						(mid 326.819079 -52.271749)
						(end 326.9488 -52.20208)
					)
				)
			)
		)
		(zone
			(layer "F.Cu")
			(hatch none 0.5)
			(connect_pads
				(clearance 0)
			)
			(min_thickness 0.25)
			(keepout
				(tracks not_allowed)
				(vias allowed)
				(pads allowed)
				(copperpour not_allowed)
				(footprints allowed)
			)
			(placement
				(enabled no)
				(sheetname "")
			)
			(fill
				(thermal_gap 0.5)
				(thermal_bridge_width 0.5)
				(island_removal_mode 0)
			)
			(polygon
				(pts
					(arc
						(start 326.9488 -51.30673)
						(mid 326.890937 -51.343101)
						(end 326.854566 -51.400964)
					)
					(arc
						(start 326.74941 -51.400964)
						(mid 326.819079 -51.271243)
						(end 326.9488 -51.201574)
					)
				)
			)
		)
		(zone
			(layer "F.Cu")
			(hatch none 0.5)
			(connect_pads
				(clearance 0)
			)
			(min_thickness 0.25)
			(keepout
				(tracks not_allowed)
				(vias allowed)
				(pads allowed)
				(copperpour not_allowed)
				(footprints allowed)
			)
			(placement
				(enabled no)
				(sheetname "")
			)
			(fill
				(thermal_gap 0.5)
				(thermal_bridge_width 0.5)
				(island_removal_mode 0)
			)
			(polygon
				(pts
					(arc
						(start 326.9488 -50.306224)
						(mid 326.890937 -50.342595)
						(end 326.854566 -50.400458)
					)
					(arc
						(start 326.74941 -50.400458)
						(mid 326.819079 -50.270737)
						(end 326.9488 -50.201068)
					)
				)
			)
		)
		(zone
			(layer "F.Cu")
			(hatch none 0.5)
			(connect_pads
				(clearance 0)
			)
			(min_thickness 0.25)
			(keepout
				(tracks not_allowed)
				(vias allowed)
				(pads allowed)
				(copperpour not_allowed)
				(footprints allowed)
			)
			(placement
				(enabled no)
				(sheetname "")
			)
			(fill
				(thermal_gap 0.5)
				(thermal_bridge_width 0.5)
				(island_removal_mode 0)
			)
			(polygon
				(pts
					(arc
						(start 326.9488 -49.305718)
						(mid 326.890937 -49.342089)
						(end 326.854566 -49.399952)
					)
					(arc
						(start 326.74941 -49.399952)
						(mid 326.819079 -49.270231)
						(end 326.9488 -49.200562)
					)
				)
			)
		)
		(zone
			(layer "F.Cu")
			(hatch none 0.5)
			(connect_pads
				(clearance 0)
			)
			(min_thickness 0.25)
			(keepout
				(tracks not_allowed)
				(vias allowed)
				(pads allowed)
				(copperpour not_allowed)
				(footprints allowed)
			)
			(placement
				(enabled no)
				(sheetname "")
			)
			(fill
				(thermal_gap 0.5)
				(thermal_bridge_width 0.5)
				(island_removal_mode 0)
			)
			(polygon
				(pts
					(arc
						(start 326.9488 -48.305212)
						(mid 326.890937 -48.341583)
						(end 326.854566 -48.399446)
					)
					(arc
						(start 326.74941 -48.399446)
						(mid 326.819079 -48.269725)
						(end 326.9488 -48.200056)
					)
				)
			)
		)
		(zone
			(layer "F.Cu")
			(hatch none 0.5)
			(connect_pads
				(clearance 0)
			)
			(min_thickness 0.25)
			(keepout
				(tracks not_allowed)
				(vias allowed)
				(pads allowed)
				(copperpour not_allowed)
				(footprints allowed)
			)
			(placement
				(enabled no)
				(sheetname "")
			)
			(fill
				(thermal_gap 0.5)
				(thermal_bridge_width 0.5)
				(island_removal_mode 0)
			)
			(polygon
				(pts
					(arc
						(start 326.9488 -47.304706)
						(mid 326.890937 -47.341077)
						(end 326.854566 -47.39894)
					)
					(arc
						(start 326.74941 -47.39894)
						(mid 326.819079 -47.269219)
						(end 326.9488 -47.19955)
					)
				)
			)
		)
		(zone
			(layer "F.Cu")
			(hatch none 0.5)
			(connect_pads
				(clearance 0)
			)
			(min_thickness 0.25)
			(keepout
				(tracks not_allowed)
				(vias allowed)
				(pads allowed)
				(copperpour not_allowed)
				(footprints allowed)
			)
			(placement
				(enabled no)
				(sheetname "")
			)
			(fill
				(thermal_gap 0.5)
				(thermal_bridge_width 0.5)
				(island_removal_mode 0)
			)
			(polygon
				(pts
					(arc
						(start 326.9488 -46.3042)
						(mid 326.890937 -46.340571)
						(end 326.854566 -46.398434)
					)
					(arc
						(start 326.74941 -46.398434)
						(mid 326.819079 -46.268713)
						(end 326.9488 -46.199044)
					)
				)
			)
		)
		(zone
			(layer "F.Cu")
			(hatch none 0.5)
			(connect_pads
				(clearance 0)
			)
			(min_thickness 0.25)
			(keepout
				(tracks not_allowed)
				(vias allowed)
				(pads allowed)
				(copperpour not_allowed)
				(footprints allowed)
			)
			(placement
				(enabled no)
				(sheetname "")
			)
			(fill
				(thermal_gap 0.5)
				(thermal_bridge_width 0.5)
				(island_removal_mode 0)
			)
			(polygon
				(pts
					(arc
						(start 326.9488 -45.303694)
						(mid 326.890937 -45.340065)
						(end 326.854566 -45.397928)
					)
					(arc
						(start 326.74941 -45.397928)
						(mid 326.819079 -45.268207)
						(end 326.9488 -45.198538)
					)
				)
			)
		)
		(zone
			(layer "F.Cu")
			(hatch none 0.5)
			(connect_pads
				(clearance 0)
			)
			(min_thickness 0.25)
			(keepout
				(tracks not_allowed)
				(vias allowed)
				(pads allowed)
				(copperpour not_allowed)
				(footprints allowed)
			)
			(placement
				(enabled no)
				(sheetname "")
			)
			(fill
				(thermal_gap 0.5)
				(thermal_bridge_width 0.5)
				(island_removal_mode 0)
			)
			(polygon
				(pts
					(arc
						(start 326.9488 -44.303188)
						(mid 326.890937 -44.339559)
						(end 326.854566 -44.397422)
					)
					(arc
						(start 326.74941 -44.397422)
						(mid 326.819079 -44.267701)
						(end 326.9488 -44.198032)
					)
				)
			)
		)
		(zone
			(layer "F.Cu")
			(hatch none 0.5)
			(connect_pads
				(clearance 0)
			)
			(min_thickness 0.25)
			(keepout
				(tracks not_allowed)
				(vias allowed)
				(pads allowed)
				(copperpour not_allowed)
				(footprints allowed)
			)
			(placement
				(enabled no)
				(sheetname "")
			)
			(fill
				(thermal_gap 0.5)
				(thermal_bridge_width 0.5)
				(island_removal_mode 0)
			)
			(polygon
				(pts
					(arc
						(start 326.9488 -43.302936)
						(mid 326.890937 -43.339307)
						(end 326.854566 -43.39717)
					)
					(arc
						(start 326.74941 -43.39717)
						(mid 326.819027 -43.267319)
						(end 326.9488 -43.197526)
					)
				)
			)
		)
		(zone
			(layer "F.Cu")
			(hatch none 0.5)
			(connect_pads
				(clearance 0)
			)
			(min_thickness 0.25)
			(keepout
				(tracks not_allowed)
				(vias allowed)
				(pads allowed)
				(copperpour not_allowed)
				(footprints allowed)
			)
			(placement
				(enabled no)
				(sheetname "")
			)
			(fill
				(thermal_gap 0.5)
				(thermal_bridge_width 0.5)
				(island_removal_mode 0)
			)
			(polygon
				(pts
					(arc
						(start 326.9488 -42.30243)
						(mid 326.890937 -42.338801)
						(end 326.854566 -42.396664)
					)
					(arc
						(start 326.74941 -42.396664)
						(mid 326.819027 -42.266813)
						(end 326.9488 -42.19702)
					)
				)
			)
		)
		(zone
			(layer "F.Cu")
			(hatch none 0.5)
			(connect_pads
				(clearance 0)
			)
			(min_thickness 0.25)
			(keepout
				(tracks not_allowed)
				(vias allowed)
				(pads allowed)
				(copperpour not_allowed)
				(footprints allowed)
			)
			(placement
				(enabled no)
				(sheetname "")
			)
			(fill
				(thermal_gap 0.5)
				(thermal_bridge_width 0.5)
				(island_removal_mode 0)
			)
			(polygon
				(pts
					(arc
						(start 326.9488 -41.301924)
						(mid 326.890937 -41.338295)
						(end 326.854566 -41.396158)
					)
					(arc
						(start 326.74941 -41.396158)
						(mid 326.819079 -41.266437)
						(end 326.9488 -41.196768)
					)
				)
			)
		)
		(zone
			(layer "F.Cu")
			(hatch none 0.5)
			(connect_pads
				(clearance 0)
			)
			(min_thickness 0.25)
			(keepout
				(tracks not_allowed)
				(vias allowed)
				(pads allowed)
				(copperpour not_allowed)
				(footprints allowed)
			)
			(placement
				(enabled no)
				(sheetname "")
			)
			(fill
				(thermal_gap 0.5)
				(thermal_bridge_width 0.5)
				(island_removal_mode 0)
			)
			(polygon
				(pts
					(arc
						(start 326.9488 -40.301418)
						(mid 326.890937 -40.337789)
						(end 326.854566 -40.395652)
					)
					(arc
						(start 326.74941 -40.395652)
						(mid 326.819079 -40.265931)
						(end 326.9488 -40.196262)
					)
				)
			)
		)
		(zone
			(layer "F.Cu")
			(hatch none 0.5)
			(connect_pads
				(clearance 0)
			)
			(min_thickness 0.25)
			(keepout
				(tracks not_allowed)
				(vias allowed)
				(pads allowed)
				(copperpour not_allowed)
				(footprints allowed)
			)
			(placement
				(enabled no)
				(sheetname "")
			)
			(fill
				(thermal_gap 0.5)
				(thermal_bridge_width 0.5)
				(island_removal_mode 0)
			)
			(polygon
				(pts
					(arc
						(start 326.9488 -39.300912)
						(mid 326.890937 -39.337283)
						(end 326.854566 -39.395146)
					)
					(arc
						(start 326.74941 -39.395146)
						(mid 326.819079 -39.265425)
						(end 326.9488 -39.195756)
					)
				)
			)
		)
		(zone
			(layer "F.Cu")
			(hatch none 0.5)
			(connect_pads
				(clearance 0)
			)
			(min_thickness 0.25)
			(keepout
				(tracks not_allowed)
				(vias allowed)
				(pads allowed)
				(copperpour not_allowed)
				(footprints allowed)
			)
			(placement
				(enabled no)
				(sheetname "")
			)
			(fill
				(thermal_gap 0.5)
				(thermal_bridge_width 0.5)
				(island_removal_mode 0)
			)
			(polygon
				(pts
					(arc
						(start 327.0504 -57.59958)
						(mid 327.108263 -57.563209)
						(end 327.144634 -57.505346)
					)
					(arc
						(start 327.24979 -57.505346)
						(mid 327.180121 -57.635067)
						(end 327.0504 -57.704736)
					)
				)
			)
		)
		(zone
			(layer "F.Cu")
			(hatch none 0.5)
			(connect_pads
				(clearance 0)
			)
			(min_thickness 0.25)
			(keepout
				(tracks not_allowed)
				(vias allowed)
				(pads allowed)
				(copperpour not_allowed)
				(footprints allowed)
			)
			(placement
				(enabled no)
				(sheetname "")
			)
			(fill
				(thermal_gap 0.5)
				(thermal_bridge_width 0.5)
				(island_removal_mode 0)
			)
			(polygon
				(pts
					(arc
						(start 327.0504 -56.599074)
						(mid 327.108263 -56.562703)
						(end 327.144634 -56.50484)
					)
					(arc
						(start 327.24979 -56.50484)
						(mid 327.180121 -56.634561)
						(end 327.0504 -56.70423)
					)
				)
			)
		)
		(zone
			(layer "F.Cu")
			(hatch none 0.5)
			(connect_pads
				(clearance 0)
			)
			(min_thickness 0.25)
			(keepout
				(tracks not_allowed)
				(vias allowed)
				(pads allowed)
				(copperpour not_allowed)
				(footprints allowed)
			)
			(placement
				(enabled no)
				(sheetname "")
			)
			(fill
				(thermal_gap 0.5)
				(thermal_bridge_width 0.5)
				(island_removal_mode 0)
			)
			(polygon
				(pts
					(arc
						(start 327.0504 -55.598568)
						(mid 327.108263 -55.562197)
						(end 327.144634 -55.504334)
					)
					(arc
						(start 327.24979 -55.504334)
						(mid 327.180121 -55.634055)
						(end 327.0504 -55.703724)
					)
				)
			)
		)
		(zone
			(layer "F.Cu")
			(hatch none 0.5)
			(connect_pads
				(clearance 0)
			)
			(min_thickness 0.25)
			(keepout
				(tracks not_allowed)
				(vias allowed)
				(pads allowed)
				(copperpour not_allowed)
				(footprints allowed)
			)
			(placement
				(enabled no)
				(sheetname "")
			)
			(fill
				(thermal_gap 0.5)
				(thermal_bridge_width 0.5)
				(island_removal_mode 0)
			)
			(polygon
				(pts
					(arc
						(start 327.0504 -54.598062)
						(mid 327.108263 -54.561691)
						(end 327.144634 -54.503828)
					)
					(arc
						(start 327.24979 -54.503828)
						(mid 327.180173 -54.633679)
						(end 327.0504 -54.703472)
					)
				)
			)
		)
		(zone
			(layer "F.Cu")
			(hatch none 0.5)
			(connect_pads
				(clearance 0)
			)
			(min_thickness 0.25)
			(keepout
				(tracks not_allowed)
				(vias allowed)
				(pads allowed)
				(copperpour not_allowed)
				(footprints allowed)
			)
			(placement
				(enabled no)
				(sheetname "")
			)
			(fill
				(thermal_gap 0.5)
				(thermal_bridge_width 0.5)
				(island_removal_mode 0)
			)
			(polygon
				(pts
					(arc
						(start 327.0504 -53.597556)
						(mid 327.108263 -53.561185)
						(end 327.144634 -53.503322)
					)
					(arc
						(start 327.24979 -53.503322)
						(mid 327.180173 -53.633173)
						(end 327.0504 -53.702966)
					)
				)
			)
		)
		(zone
			(layer "F.Cu")
			(hatch none 0.5)
			(connect_pads
				(clearance 0)
			)
			(min_thickness 0.25)
			(keepout
				(tracks not_allowed)
				(vias allowed)
				(pads allowed)
				(copperpour not_allowed)
				(footprints allowed)
			)
			(placement
				(enabled no)
				(sheetname "")
			)
			(fill
				(thermal_gap 0.5)
				(thermal_bridge_width 0.5)
				(island_removal_mode 0)
			)
			(polygon
				(pts
					(arc
						(start 327.0504 -52.597304)
						(mid 327.108263 -52.560933)
						(end 327.144634 -52.50307)
					)
					(arc
						(start 327.24979 -52.50307)
						(mid 327.180121 -52.632791)
						(end 327.0504 -52.70246)
					)
				)
			)
		)
		(zone
			(layer "F.Cu")
			(hatch none 0.5)
			(connect_pads
				(clearance 0)
			)
			(min_thickness 0.25)
			(keepout
				(tracks not_allowed)
				(vias allowed)
				(pads allowed)
				(copperpour not_allowed)
				(footprints allowed)
			)
			(placement
				(enabled no)
				(sheetname "")
			)
			(fill
				(thermal_gap 0.5)
				(thermal_bridge_width 0.5)
				(island_removal_mode 0)
			)
			(polygon
				(pts
					(arc
						(start 327.0504 -51.596798)
						(mid 327.108263 -51.560427)
						(end 327.144634 -51.502564)
					)
					(arc
						(start 327.24979 -51.502564)
						(mid 327.180121 -51.632285)
						(end 327.0504 -51.701954)
					)
				)
			)
		)
		(zone
			(layer "F.Cu")
			(hatch none 0.5)
			(connect_pads
				(clearance 0)
			)
			(min_thickness 0.25)
			(keepout
				(tracks not_allowed)
				(vias allowed)
				(pads allowed)
				(copperpour not_allowed)
				(footprints allowed)
			)
			(placement
				(enabled no)
				(sheetname "")
			)
			(fill
				(thermal_gap 0.5)
				(thermal_bridge_width 0.5)
				(island_removal_mode 0)
			)
			(polygon
				(pts
					(arc
						(start 327.0504 -50.596292)
						(mid 327.108263 -50.559921)
						(end 327.144634 -50.502058)
					)
					(arc
						(start 327.24979 -50.502058)
						(mid 327.180121 -50.631779)
						(end 327.0504 -50.701448)
					)
				)
			)
		)
		(zone
			(layer "F.Cu")
			(hatch none 0.5)
			(connect_pads
				(clearance 0)
			)
			(min_thickness 0.25)
			(keepout
				(tracks not_allowed)
				(vias allowed)
				(pads allowed)
				(copperpour not_allowed)
				(footprints allowed)
			)
			(placement
				(enabled no)
				(sheetname "")
			)
			(fill
				(thermal_gap 0.5)
				(thermal_bridge_width 0.5)
				(island_removal_mode 0)
			)
			(polygon
				(pts
					(arc
						(start 327.0504 -49.595786)
						(mid 327.108263 -49.559415)
						(end 327.144634 -49.501552)
					)
					(arc
						(start 327.24979 -49.501552)
						(mid 327.180121 -49.631273)
						(end 327.0504 -49.700942)
					)
				)
			)
		)
		(zone
			(layer "F.Cu")
			(hatch none 0.5)
			(connect_pads
				(clearance 0)
			)
			(min_thickness 0.25)
			(keepout
				(tracks not_allowed)
				(vias allowed)
				(pads allowed)
				(copperpour not_allowed)
				(footprints allowed)
			)
			(placement
				(enabled no)
				(sheetname "")
			)
			(fill
				(thermal_gap 0.5)
				(thermal_bridge_width 0.5)
				(island_removal_mode 0)
			)
			(polygon
				(pts
					(arc
						(start 327.0504 -48.59528)
						(mid 327.108263 -48.558909)
						(end 327.144634 -48.501046)
					)
					(arc
						(start 327.24979 -48.501046)
						(mid 327.180121 -48.630767)
						(end 327.0504 -48.700436)
					)
				)
			)
		)
		(zone
			(layer "F.Cu")
			(hatch none 0.5)
			(connect_pads
				(clearance 0)
			)
			(min_thickness 0.25)
			(keepout
				(tracks not_allowed)
				(vias allowed)
				(pads allowed)
				(copperpour not_allowed)
				(footprints allowed)
			)
			(placement
				(enabled no)
				(sheetname "")
			)
			(fill
				(thermal_gap 0.5)
				(thermal_bridge_width 0.5)
				(island_removal_mode 0)
			)
			(polygon
				(pts
					(arc
						(start 327.0504 -47.594774)
						(mid 327.108263 -47.558403)
						(end 327.144634 -47.50054)
					)
					(arc
						(start 327.24979 -47.50054)
						(mid 327.180121 -47.630261)
						(end 327.0504 -47.69993)
					)
				)
			)
		)
		(zone
			(layer "F.Cu")
			(hatch none 0.5)
			(connect_pads
				(clearance 0)
			)
			(min_thickness 0.25)
			(keepout
				(tracks not_allowed)
				(vias allowed)
				(pads allowed)
				(copperpour not_allowed)
				(footprints allowed)
			)
			(placement
				(enabled no)
				(sheetname "")
			)
			(fill
				(thermal_gap 0.5)
				(thermal_bridge_width 0.5)
				(island_removal_mode 0)
			)
			(polygon
				(pts
					(arc
						(start 327.0504 -46.594268)
						(mid 327.108263 -46.557897)
						(end 327.144634 -46.500034)
					)
					(arc
						(start 327.24979 -46.500034)
						(mid 327.180121 -46.629755)
						(end 327.0504 -46.699424)
					)
				)
			)
		)
		(zone
			(layer "F.Cu")
			(hatch none 0.5)
			(connect_pads
				(clearance 0)
			)
			(min_thickness 0.25)
			(keepout
				(tracks not_allowed)
				(vias allowed)
				(pads allowed)
				(copperpour not_allowed)
				(footprints allowed)
			)
			(placement
				(enabled no)
				(sheetname "")
			)
			(fill
				(thermal_gap 0.5)
				(thermal_bridge_width 0.5)
				(island_removal_mode 0)
			)
			(polygon
				(pts
					(arc
						(start 327.0504 -45.593762)
						(mid 327.108263 -45.557391)
						(end 327.144634 -45.499528)
					)
					(arc
						(start 327.24979 -45.499528)
						(mid 327.180121 -45.629249)
						(end 327.0504 -45.698918)
					)
				)
			)
		)
		(zone
			(layer "F.Cu")
			(hatch none 0.5)
			(connect_pads
				(clearance 0)
			)
			(min_thickness 0.25)
			(keepout
				(tracks not_allowed)
				(vias allowed)
				(pads allowed)
				(copperpour not_allowed)
				(footprints allowed)
			)
			(placement
				(enabled no)
				(sheetname "")
			)
			(fill
				(thermal_gap 0.5)
				(thermal_bridge_width 0.5)
				(island_removal_mode 0)
			)
			(polygon
				(pts
					(arc
						(start 327.0504 -44.593256)
						(mid 327.108263 -44.556885)
						(end 327.144634 -44.499022)
					)
					(arc
						(start 327.24979 -44.499022)
						(mid 327.180121 -44.628743)
						(end 327.0504 -44.698412)
					)
				)
			)
		)
		(zone
			(layer "F.Cu")
			(hatch none 0.5)
			(connect_pads
				(clearance 0)
			)
			(min_thickness 0.25)
			(keepout
				(tracks not_allowed)
				(vias allowed)
				(pads allowed)
				(copperpour not_allowed)
				(footprints allowed)
			)
			(placement
				(enabled no)
				(sheetname "")
			)
			(fill
				(thermal_gap 0.5)
				(thermal_bridge_width 0.5)
				(island_removal_mode 0)
			)
			(polygon
				(pts
					(arc
						(start 327.0504 -43.59275)
						(mid 327.108259 -43.556519)
						(end 327.144634 -43.49877)
					)
					(arc
						(start 327.24979 -43.49877)
						(mid 327.180121 -43.628491)
						(end 327.0504 -43.69816)
					)
				)
			)
		)
		(zone
			(layer "F.Cu")
			(hatch none 0.5)
			(connect_pads
				(clearance 0)
			)
			(min_thickness 0.25)
			(keepout
				(tracks not_allowed)
				(vias allowed)
				(pads allowed)
				(copperpour not_allowed)
				(footprints allowed)
			)
			(placement
				(enabled no)
				(sheetname "")
			)
			(fill
				(thermal_gap 0.5)
				(thermal_bridge_width 0.5)
				(island_removal_mode 0)
			)
			(polygon
				(pts
					(arc
						(start 327.0504 -42.592244)
						(mid 327.108259 -42.556013)
						(end 327.144634 -42.498264)
					)
					(arc
						(start 327.24979 -42.498264)
						(mid 327.180121 -42.627985)
						(end 327.0504 -42.697654)
					)
				)
			)
		)
		(zone
			(layer "F.Cu")
			(hatch none 0.5)
			(connect_pads
				(clearance 0)
			)
			(min_thickness 0.25)
			(keepout
				(tracks not_allowed)
				(vias allowed)
				(pads allowed)
				(copperpour not_allowed)
				(footprints allowed)
			)
			(placement
				(enabled no)
				(sheetname "")
			)
			(fill
				(thermal_gap 0.5)
				(thermal_bridge_width 0.5)
				(island_removal_mode 0)
			)
			(polygon
				(pts
					(arc
						(start 327.0504 -41.591738)
						(mid 327.108259 -41.555507)
						(end 327.144634 -41.497758)
					)
					(arc
						(start 327.24979 -41.497758)
						(mid 327.180121 -41.627479)
						(end 327.0504 -41.697148)
					)
				)
			)
		)
		(zone
			(layer "F.Cu")
			(hatch none 0.5)
			(connect_pads
				(clearance 0)
			)
			(min_thickness 0.25)
			(keepout
				(tracks not_allowed)
				(vias allowed)
				(pads allowed)
				(copperpour not_allowed)
				(footprints allowed)
			)
			(placement
				(enabled no)
				(sheetname "")
			)
			(fill
				(thermal_gap 0.5)
				(thermal_bridge_width 0.5)
				(island_removal_mode 0)
			)
			(polygon
				(pts
					(arc
						(start 327.0504 -40.591232)
						(mid 327.108259 -40.555001)
						(end 327.144634 -40.497252)
					)
					(arc
						(start 327.24979 -40.497252)
						(mid 327.180121 -40.626973)
						(end 327.0504 -40.696642)
					)
				)
			)
		)
		(zone
			(layer "F.Cu")
			(hatch none 0.5)
			(connect_pads
				(clearance 0)
			)
			(min_thickness 0.25)
			(keepout
				(tracks not_allowed)
				(vias allowed)
				(pads allowed)
				(copperpour not_allowed)
				(footprints allowed)
			)
			(placement
				(enabled no)
				(sheetname "")
			)
			(fill
				(thermal_gap 0.5)
				(thermal_bridge_width 0.5)
				(island_removal_mode 0)
			)
			(polygon
				(pts
					(arc
						(start 327.0504 -39.590726)
						(mid 327.108259 -39.554495)
						(end 327.144634 -39.496746)
					)
					(arc
						(start 327.24979 -39.496746)
						(mid 327.180121 -39.626467)
						(end 327.0504 -39.696136)
					)
				)
			)
		)
		(zone
			(layer "F.Cu")
			(hatch none 0.5)
			(connect_pads
				(clearance 0)
			)
			(min_thickness 0.25)
			(keepout
				(tracks not_allowed)
				(vias allowed)
				(pads allowed)
				(copperpour not_allowed)
				(footprints allowed)
			)
			(placement
				(enabled no)
				(sheetname "")
			)
			(fill
				(thermal_gap 0.5)
				(thermal_bridge_width 0.5)
				(island_removal_mode 0)
			)
			(polygon
				(pts
					(arc
						(start 327.09485 -38.3413)
						(mid 327.131221 -38.399163)
						(end 327.189084 -38.435534)
					)
					(arc
						(start 327.189084 -38.54069)
						(mid 327.059363 -38.471021)
						(end 326.989694 -38.3413)
					)
				)
			)
		)
		(zone
			(layer "F.Cu")
			(hatch none 0.5)
			(connect_pads
				(clearance 0)
			)
			(min_thickness 0.25)
			(keepout
				(tracks not_allowed)
				(vias allowed)
				(pads allowed)
				(copperpour not_allowed)
				(footprints allowed)
			)
			(placement
				(enabled no)
				(sheetname "")
			)
			(fill
				(thermal_gap 0.5)
				(thermal_bridge_width 0.5)
				(island_removal_mode 0)
			)
			(polygon
				(pts
					(arc
						(start 327.144634 -57.403746)
						(mid 327.108208 -57.346047)
						(end 327.0504 -57.309766)
					)
					(arc
						(start 327.0504 -57.204356)
						(mid 327.180121 -57.274025)
						(end 327.24979 -57.403746)
					)
				)
			)
		)
		(zone
			(layer "F.Cu")
			(hatch none 0.5)
			(connect_pads
				(clearance 0)
			)
			(min_thickness 0.25)
			(keepout
				(tracks not_allowed)
				(vias allowed)
				(pads allowed)
				(copperpour not_allowed)
				(footprints allowed)
			)
			(placement
				(enabled no)
				(sheetname "")
			)
			(fill
				(thermal_gap 0.5)
				(thermal_bridge_width 0.5)
				(island_removal_mode 0)
			)
			(polygon
				(pts
					(arc
						(start 327.144634 -56.40324)
						(mid 327.108208 -56.345541)
						(end 327.0504 -56.30926)
					)
					(arc
						(start 327.0504 -56.20385)
						(mid 327.180121 -56.273519)
						(end 327.24979 -56.40324)
					)
				)
			)
		)
		(zone
			(layer "F.Cu")
			(hatch none 0.5)
			(connect_pads
				(clearance 0)
			)
			(min_thickness 0.25)
			(keepout
				(tracks not_allowed)
				(vias allowed)
				(pads allowed)
				(copperpour not_allowed)
				(footprints allowed)
			)
			(placement
				(enabled no)
				(sheetname "")
			)
			(fill
				(thermal_gap 0.5)
				(thermal_bridge_width 0.5)
				(island_removal_mode 0)
			)
			(polygon
				(pts
					(arc
						(start 327.144634 -55.402734)
						(mid 327.108208 -55.345035)
						(end 327.0504 -55.308754)
					)
					(arc
						(start 327.0504 -55.203344)
						(mid 327.180121 -55.273013)
						(end 327.24979 -55.402734)
					)
				)
			)
		)
		(zone
			(layer "F.Cu")
			(hatch none 0.5)
			(connect_pads
				(clearance 0)
			)
			(min_thickness 0.25)
			(keepout
				(tracks not_allowed)
				(vias allowed)
				(pads allowed)
				(copperpour not_allowed)
				(footprints allowed)
			)
			(placement
				(enabled no)
				(sheetname "")
			)
			(fill
				(thermal_gap 0.5)
				(thermal_bridge_width 0.5)
				(island_removal_mode 0)
			)
			(polygon
				(pts
					(arc
						(start 327.144634 -54.402228)
						(mid 327.108208 -54.344529)
						(end 327.0504 -54.308248)
					)
					(arc
						(start 327.0504 -54.202838)
						(mid 327.180121 -54.272507)
						(end 327.24979 -54.402228)
					)
				)
			)
		)
		(zone
			(layer "F.Cu")
			(hatch none 0.5)
			(connect_pads
				(clearance 0)
			)
			(min_thickness 0.25)
			(keepout
				(tracks not_allowed)
				(vias allowed)
				(pads allowed)
				(copperpour not_allowed)
				(footprints allowed)
			)
			(placement
				(enabled no)
				(sheetname "")
			)
			(fill
				(thermal_gap 0.5)
				(thermal_bridge_width 0.5)
				(island_removal_mode 0)
			)
			(polygon
				(pts
					(arc
						(start 327.144634 -53.401722)
						(mid 327.108208 -53.344023)
						(end 327.0504 -53.307742)
					)
					(arc
						(start 327.0504 -53.202332)
						(mid 327.180121 -53.272001)
						(end 327.24979 -53.401722)
					)
				)
			)
		)
		(zone
			(layer "F.Cu")
			(hatch none 0.5)
			(connect_pads
				(clearance 0)
			)
			(min_thickness 0.25)
			(keepout
				(tracks not_allowed)
				(vias allowed)
				(pads allowed)
				(copperpour not_allowed)
				(footprints allowed)
			)
			(placement
				(enabled no)
				(sheetname "")
			)
			(fill
				(thermal_gap 0.5)
				(thermal_bridge_width 0.5)
				(island_removal_mode 0)
			)
			(polygon
				(pts
					(arc
						(start 327.144634 -52.40147)
						(mid 327.108263 -52.343607)
						(end 327.0504 -52.307236)
					)
					(arc
						(start 327.0504 -52.20208)
						(mid 327.180121 -52.271749)
						(end 327.24979 -52.40147)
					)
				)
			)
		)
		(zone
			(layer "F.Cu")
			(hatch none 0.5)
			(connect_pads
				(clearance 0)
			)
			(min_thickness 0.25)
			(keepout
				(tracks not_allowed)
				(vias allowed)
				(pads allowed)
				(copperpour not_allowed)
				(footprints allowed)
			)
			(placement
				(enabled no)
				(sheetname "")
			)
			(fill
				(thermal_gap 0.5)
				(thermal_bridge_width 0.5)
				(island_removal_mode 0)
			)
			(polygon
				(pts
					(arc
						(start 327.144634 -51.400964)
						(mid 327.108263 -51.343101)
						(end 327.0504 -51.30673)
					)
					(arc
						(start 327.0504 -51.201574)
						(mid 327.180121 -51.271243)
						(end 327.24979 -51.400964)
					)
				)
			)
		)
		(zone
			(layer "F.Cu")
			(hatch none 0.5)
			(connect_pads
				(clearance 0)
			)
			(min_thickness 0.25)
			(keepout
				(tracks not_allowed)
				(vias allowed)
				(pads allowed)
				(copperpour not_allowed)
				(footprints allowed)
			)
			(placement
				(enabled no)
				(sheetname "")
			)
			(fill
				(thermal_gap 0.5)
				(thermal_bridge_width 0.5)
				(island_removal_mode 0)
			)
			(polygon
				(pts
					(arc
						(start 327.144634 -50.400458)
						(mid 327.108263 -50.342595)
						(end 327.0504 -50.306224)
					)
					(arc
						(start 327.0504 -50.201068)
						(mid 327.180121 -50.270737)
						(end 327.24979 -50.400458)
					)
				)
			)
		)
		(zone
			(layer "F.Cu")
			(hatch none 0.5)
			(connect_pads
				(clearance 0)
			)
			(min_thickness 0.25)
			(keepout
				(tracks not_allowed)
				(vias allowed)
				(pads allowed)
				(copperpour not_allowed)
				(footprints allowed)
			)
			(placement
				(enabled no)
				(sheetname "")
			)
			(fill
				(thermal_gap 0.5)
				(thermal_bridge_width 0.5)
				(island_removal_mode 0)
			)
			(polygon
				(pts
					(arc
						(start 327.144634 -49.399952)
						(mid 327.108263 -49.342089)
						(end 327.0504 -49.305718)
					)
					(arc
						(start 327.0504 -49.200562)
						(mid 327.180121 -49.270231)
						(end 327.24979 -49.399952)
					)
				)
			)
		)
		(zone
			(layer "F.Cu")
			(hatch none 0.5)
			(connect_pads
				(clearance 0)
			)
			(min_thickness 0.25)
			(keepout
				(tracks not_allowed)
				(vias allowed)
				(pads allowed)
				(copperpour not_allowed)
				(footprints allowed)
			)
			(placement
				(enabled no)
				(sheetname "")
			)
			(fill
				(thermal_gap 0.5)
				(thermal_bridge_width 0.5)
				(island_removal_mode 0)
			)
			(polygon
				(pts
					(arc
						(start 327.144634 -48.399446)
						(mid 327.108263 -48.341583)
						(end 327.0504 -48.305212)
					)
					(arc
						(start 327.0504 -48.200056)
						(mid 327.180121 -48.269725)
						(end 327.24979 -48.399446)
					)
				)
			)
		)
		(zone
			(layer "F.Cu")
			(hatch none 0.5)
			(connect_pads
				(clearance 0)
			)
			(min_thickness 0.25)
			(keepout
				(tracks not_allowed)
				(vias allowed)
				(pads allowed)
				(copperpour not_allowed)
				(footprints allowed)
			)
			(placement
				(enabled no)
				(sheetname "")
			)
			(fill
				(thermal_gap 0.5)
				(thermal_bridge_width 0.5)
				(island_removal_mode 0)
			)
			(polygon
				(pts
					(arc
						(start 327.144634 -47.39894)
						(mid 327.108263 -47.341077)
						(end 327.0504 -47.304706)
					)
					(arc
						(start 327.0504 -47.19955)
						(mid 327.180121 -47.269219)
						(end 327.24979 -47.39894)
					)
				)
			)
		)
		(zone
			(layer "F.Cu")
			(hatch none 0.5)
			(connect_pads
				(clearance 0)
			)
			(min_thickness 0.25)
			(keepout
				(tracks not_allowed)
				(vias allowed)
				(pads allowed)
				(copperpour not_allowed)
				(footprints allowed)
			)
			(placement
				(enabled no)
				(sheetname "")
			)
			(fill
				(thermal_gap 0.5)
				(thermal_bridge_width 0.5)
				(island_removal_mode 0)
			)
			(polygon
				(pts
					(arc
						(start 327.144634 -46.398434)
						(mid 327.108263 -46.340571)
						(end 327.0504 -46.3042)
					)
					(arc
						(start 327.0504 -46.199044)
						(mid 327.180121 -46.268713)
						(end 327.24979 -46.398434)
					)
				)
			)
		)
		(zone
			(layer "F.Cu")
			(hatch none 0.5)
			(connect_pads
				(clearance 0)
			)
			(min_thickness 0.25)
			(keepout
				(tracks not_allowed)
				(vias allowed)
				(pads allowed)
				(copperpour not_allowed)
				(footprints allowed)
			)
			(placement
				(enabled no)
				(sheetname "")
			)
			(fill
				(thermal_gap 0.5)
				(thermal_bridge_width 0.5)
				(island_removal_mode 0)
			)
			(polygon
				(pts
					(arc
						(start 327.144634 -45.397928)
						(mid 327.108263 -45.340065)
						(end 327.0504 -45.303694)
					)
					(arc
						(start 327.0504 -45.198538)
						(mid 327.180121 -45.268207)
						(end 327.24979 -45.397928)
					)
				)
			)
		)
		(zone
			(layer "F.Cu")
			(hatch none 0.5)
			(connect_pads
				(clearance 0)
			)
			(min_thickness 0.25)
			(keepout
				(tracks not_allowed)
				(vias allowed)
				(pads allowed)
				(copperpour not_allowed)
				(footprints allowed)
			)
			(placement
				(enabled no)
				(sheetname "")
			)
			(fill
				(thermal_gap 0.5)
				(thermal_bridge_width 0.5)
				(island_removal_mode 0)
			)
			(polygon
				(pts
					(arc
						(start 327.144634 -44.397422)
						(mid 327.108263 -44.339559)
						(end 327.0504 -44.303188)
					)
					(arc
						(start 327.0504 -44.198032)
						(mid 327.180121 -44.267701)
						(end 327.24979 -44.397422)
					)
				)
			)
		)
		(zone
			(layer "F.Cu")
			(hatch none 0.5)
			(connect_pads
				(clearance 0)
			)
			(min_thickness 0.25)
			(keepout
				(tracks not_allowed)
				(vias allowed)
				(pads allowed)
				(copperpour not_allowed)
				(footprints allowed)
			)
			(placement
				(enabled no)
				(sheetname "")
			)
			(fill
				(thermal_gap 0.5)
				(thermal_bridge_width 0.5)
				(island_removal_mode 0)
			)
			(polygon
				(pts
					(arc
						(start 327.144634 -43.39717)
						(mid 327.108263 -43.339307)
						(end 327.0504 -43.302936)
					)
					(arc
						(start 327.0504 -43.197526)
						(mid 327.180209 -43.267283)
						(end 327.24979 -43.39717)
					)
				)
			)
		)
		(zone
			(layer "F.Cu")
			(hatch none 0.5)
			(connect_pads
				(clearance 0)
			)
			(min_thickness 0.25)
			(keepout
				(tracks not_allowed)
				(vias allowed)
				(pads allowed)
				(copperpour not_allowed)
				(footprints allowed)
			)
			(placement
				(enabled no)
				(sheetname "")
			)
			(fill
				(thermal_gap 0.5)
				(thermal_bridge_width 0.5)
				(island_removal_mode 0)
			)
			(polygon
				(pts
					(arc
						(start 327.144634 -42.396664)
						(mid 327.108263 -42.338801)
						(end 327.0504 -42.30243)
					)
					(arc
						(start 327.0504 -42.19702)
						(mid 327.180209 -42.266777)
						(end 327.24979 -42.396664)
					)
				)
			)
		)
		(zone
			(layer "F.Cu")
			(hatch none 0.5)
			(connect_pads
				(clearance 0)
			)
			(min_thickness 0.25)
			(keepout
				(tracks not_allowed)
				(vias allowed)
				(pads allowed)
				(copperpour not_allowed)
				(footprints allowed)
			)
			(placement
				(enabled no)
				(sheetname "")
			)
			(fill
				(thermal_gap 0.5)
				(thermal_bridge_width 0.5)
				(island_removal_mode 0)
			)
			(polygon
				(pts
					(arc
						(start 327.144634 -41.396158)
						(mid 327.108263 -41.338295)
						(end 327.0504 -41.301924)
					)
					(arc
						(start 327.0504 -41.196768)
						(mid 327.180121 -41.266437)
						(end 327.24979 -41.396158)
					)
				)
			)
		)
		(zone
			(layer "F.Cu")
			(hatch none 0.5)
			(connect_pads
				(clearance 0)
			)
			(min_thickness 0.25)
			(keepout
				(tracks not_allowed)
				(vias allowed)
				(pads allowed)
				(copperpour not_allowed)
				(footprints allowed)
			)
			(placement
				(enabled no)
				(sheetname "")
			)
			(fill
				(thermal_gap 0.5)
				(thermal_bridge_width 0.5)
				(island_removal_mode 0)
			)
			(polygon
				(pts
					(arc
						(start 327.144634 -40.395652)
						(mid 327.108263 -40.337789)
						(end 327.0504 -40.301418)
					)
					(arc
						(start 327.0504 -40.196262)
						(mid 327.180121 -40.265931)
						(end 327.24979 -40.395652)
					)
				)
			)
		)
		(zone
			(layer "F.Cu")
			(hatch none 0.5)
			(connect_pads
				(clearance 0)
			)
			(min_thickness 0.25)
			(keepout
				(tracks not_allowed)
				(vias allowed)
				(pads allowed)
				(copperpour not_allowed)
				(footprints allowed)
			)
			(placement
				(enabled no)
				(sheetname "")
			)
			(fill
				(thermal_gap 0.5)
				(thermal_bridge_width 0.5)
				(island_removal_mode 0)
			)
			(polygon
				(pts
					(arc
						(start 327.144634 -39.395146)
						(mid 327.108263 -39.337283)
						(end 327.0504 -39.300912)
					)
					(arc
						(start 327.0504 -39.195756)
						(mid 327.180121 -39.265425)
						(end 327.24979 -39.395146)
					)
				)
			)
		)
		(zone
			(layer "F.Cu")
			(hatch none 0.5)
			(connect_pads
				(clearance 0)
			)
			(min_thickness 0.25)
			(keepout
				(tracks not_allowed)
				(vias allowed)
				(pads allowed)
				(copperpour not_allowed)
				(footprints allowed)
			)
			(placement
				(enabled no)
				(sheetname "")
			)
			(fill
				(thermal_gap 0.5)
				(thermal_bridge_width 0.5)
				(island_removal_mode 0)
			)
			(polygon
				(pts
					(arc
						(start 327.189084 -38.145466)
						(mid 327.131221 -38.181837)
						(end 327.09485 -38.2397)
					)
					(arc
						(start 326.989694 -38.2397)
						(mid 327.059363 -38.109979)
						(end 327.189084 -38.04031)
					)
				)
			)
		)
		(zone
			(layer "F.Cu")
			(hatch none 0.5)
			(connect_pads
				(clearance 0)
			)
			(min_thickness 0.25)
			(keepout
				(tracks not_allowed)
				(vias allowed)
				(pads allowed)
				(copperpour not_allowed)
				(footprints allowed)
			)
			(placement
				(enabled no)
				(sheetname "")
			)
			(fill
				(thermal_gap 0.5)
				(thermal_bridge_width 0.5)
				(island_removal_mode 0)
			)
			(polygon
				(pts
					(arc
						(start 327.269856 -58.005726)
						(mid 327.306087 -58.063585)
						(end 327.363836 -58.09996)
					)
					(arc
						(start 327.363836 -58.205116)
						(mid 327.234115 -58.135447)
						(end 327.164446 -58.005726)
					)
				)
			)
		)
		(zone
			(layer "F.Cu")
			(hatch none 0.5)
			(connect_pads
				(clearance 0)
			)
			(min_thickness 0.25)
			(keepout
				(tracks not_allowed)
				(vias allowed)
				(pads allowed)
				(copperpour not_allowed)
				(footprints allowed)
			)
			(placement
				(enabled no)
				(sheetname "")
			)
			(fill
				(thermal_gap 0.5)
				(thermal_bridge_width 0.5)
				(island_removal_mode 0)
			)
			(polygon
				(pts
					(arc
						(start 327.269856 -57.00522)
						(mid 327.306087 -57.063079)
						(end 327.363836 -57.099454)
					)
					(arc
						(start 327.363836 -57.20461)
						(mid 327.234115 -57.134941)
						(end 327.164446 -57.00522)
					)
				)
			)
		)
		(zone
			(layer "F.Cu")
			(hatch none 0.5)
			(connect_pads
				(clearance 0)
			)
			(min_thickness 0.25)
			(keepout
				(tracks not_allowed)
				(vias allowed)
				(pads allowed)
				(copperpour not_allowed)
				(footprints allowed)
			)
			(placement
				(enabled no)
				(sheetname "")
			)
			(fill
				(thermal_gap 0.5)
				(thermal_bridge_width 0.5)
				(island_removal_mode 0)
			)
			(polygon
				(pts
					(arc
						(start 327.269856 -56.004714)
						(mid 327.306087 -56.062573)
						(end 327.363836 -56.098948)
					)
					(arc
						(start 327.363836 -56.204104)
						(mid 327.234115 -56.134435)
						(end 327.164446 -56.004714)
					)
				)
			)
		)
		(zone
			(layer "F.Cu")
			(hatch none 0.5)
			(connect_pads
				(clearance 0)
			)
			(min_thickness 0.25)
			(keepout
				(tracks not_allowed)
				(vias allowed)
				(pads allowed)
				(copperpour not_allowed)
				(footprints allowed)
			)
			(placement
				(enabled no)
				(sheetname "")
			)
			(fill
				(thermal_gap 0.5)
				(thermal_bridge_width 0.5)
				(island_removal_mode 0)
			)
			(polygon
				(pts
					(arc
						(start 327.269856 -55.004208)
						(mid 327.306087 -55.062067)
						(end 327.363836 -55.098442)
					)
					(arc
						(start 327.363836 -55.203598)
						(mid 327.234115 -55.133929)
						(end 327.164446 -55.004208)
					)
				)
			)
		)
		(zone
			(layer "F.Cu")
			(hatch none 0.5)
			(connect_pads
				(clearance 0)
			)
			(min_thickness 0.25)
			(keepout
				(tracks not_allowed)
				(vias allowed)
				(pads allowed)
				(copperpour not_allowed)
				(footprints allowed)
			)
			(placement
				(enabled no)
				(sheetname "")
			)
			(fill
				(thermal_gap 0.5)
				(thermal_bridge_width 0.5)
				(island_removal_mode 0)
			)
			(polygon
				(pts
					(arc
						(start 327.269856 -54.003702)
						(mid 327.306087 -54.061561)
						(end 327.363836 -54.097936)
					)
					(arc
						(start 327.363836 -54.203092)
						(mid 327.234115 -54.133423)
						(end 327.164446 -54.003702)
					)
				)
			)
		)
		(zone
			(layer "F.Cu")
			(hatch none 0.5)
			(connect_pads
				(clearance 0)
			)
			(min_thickness 0.25)
			(keepout
				(tracks not_allowed)
				(vias allowed)
				(pads allowed)
				(copperpour not_allowed)
				(footprints allowed)
			)
			(placement
				(enabled no)
				(sheetname "")
			)
			(fill
				(thermal_gap 0.5)
				(thermal_bridge_width 0.5)
				(island_removal_mode 0)
			)
			(polygon
				(pts
					(arc
						(start 327.269856 -53.003196)
						(mid 327.306087 -53.061055)
						(end 327.363836 -53.09743)
					)
					(arc
						(start 327.363836 -53.202586)
						(mid 327.234115 -53.132917)
						(end 327.164446 -53.003196)
					)
				)
			)
		)
		(zone
			(layer "F.Cu")
			(hatch none 0.5)
			(connect_pads
				(clearance 0)
			)
			(min_thickness 0.25)
			(keepout
				(tracks not_allowed)
				(vias allowed)
				(pads allowed)
				(copperpour not_allowed)
				(footprints allowed)
			)
			(placement
				(enabled no)
				(sheetname "")
			)
			(fill
				(thermal_gap 0.5)
				(thermal_bridge_width 0.5)
				(island_removal_mode 0)
			)
			(polygon
				(pts
					(arc
						(start 327.269856 -52.002944)
						(mid 327.306167 -52.060613)
						(end 327.363836 -52.096924)
					)
					(arc
						(start 327.363836 -52.202334)
						(mid 327.234115 -52.132665)
						(end 327.164446 -52.002944)
					)
				)
			)
		)
		(zone
			(layer "F.Cu")
			(hatch none 0.5)
			(connect_pads
				(clearance 0)
			)
			(min_thickness 0.25)
			(keepout
				(tracks not_allowed)
				(vias allowed)
				(pads allowed)
				(copperpour not_allowed)
				(footprints allowed)
			)
			(placement
				(enabled no)
				(sheetname "")
			)
			(fill
				(thermal_gap 0.5)
				(thermal_bridge_width 0.5)
				(island_removal_mode 0)
			)
			(polygon
				(pts
					(arc
						(start 327.269856 -51.002438)
						(mid 327.306142 -51.060217)
						(end 327.363836 -51.096672)
					)
					(arc
						(start 327.363836 -51.201828)
						(mid 327.234115 -51.132159)
						(end 327.164446 -51.002438)
					)
				)
			)
		)
		(zone
			(layer "F.Cu")
			(hatch none 0.5)
			(connect_pads
				(clearance 0)
			)
			(min_thickness 0.25)
			(keepout
				(tracks not_allowed)
				(vias allowed)
				(pads allowed)
				(copperpour not_allowed)
				(footprints allowed)
			)
			(placement
				(enabled no)
				(sheetname "")
			)
			(fill
				(thermal_gap 0.5)
				(thermal_bridge_width 0.5)
				(island_removal_mode 0)
			)
			(polygon
				(pts
					(arc
						(start 327.269856 -50.001932)
						(mid 327.306142 -50.059711)
						(end 327.363836 -50.096166)
					)
					(arc
						(start 327.363836 -50.201322)
						(mid 327.234115 -50.131653)
						(end 327.164446 -50.001932)
					)
				)
			)
		)
		(zone
			(layer "F.Cu")
			(hatch none 0.5)
			(connect_pads
				(clearance 0)
			)
			(min_thickness 0.25)
			(keepout
				(tracks not_allowed)
				(vias allowed)
				(pads allowed)
				(copperpour not_allowed)
				(footprints allowed)
			)
			(placement
				(enabled no)
				(sheetname "")
			)
			(fill
				(thermal_gap 0.5)
				(thermal_bridge_width 0.5)
				(island_removal_mode 0)
			)
			(polygon
				(pts
					(arc
						(start 327.269856 -49.001426)
						(mid 327.306142 -49.059205)
						(end 327.363836 -49.09566)
					)
					(arc
						(start 327.363836 -49.200816)
						(mid 327.234115 -49.131147)
						(end 327.164446 -49.001426)
					)
				)
			)
		)
		(zone
			(layer "F.Cu")
			(hatch none 0.5)
			(connect_pads
				(clearance 0)
			)
			(min_thickness 0.25)
			(keepout
				(tracks not_allowed)
				(vias allowed)
				(pads allowed)
				(copperpour not_allowed)
				(footprints allowed)
			)
			(placement
				(enabled no)
				(sheetname "")
			)
			(fill
				(thermal_gap 0.5)
				(thermal_bridge_width 0.5)
				(island_removal_mode 0)
			)
			(polygon
				(pts
					(arc
						(start 327.269856 -48.00092)
						(mid 327.306142 -48.058699)
						(end 327.363836 -48.095154)
					)
					(arc
						(start 327.363836 -48.20031)
						(mid 327.234115 -48.130641)
						(end 327.164446 -48.00092)
					)
				)
			)
		)
		(zone
			(layer "F.Cu")
			(hatch none 0.5)
			(connect_pads
				(clearance 0)
			)
			(min_thickness 0.25)
			(keepout
				(tracks not_allowed)
				(vias allowed)
				(pads allowed)
				(copperpour not_allowed)
				(footprints allowed)
			)
			(placement
				(enabled no)
				(sheetname "")
			)
			(fill
				(thermal_gap 0.5)
				(thermal_bridge_width 0.5)
				(island_removal_mode 0)
			)
			(polygon
				(pts
					(arc
						(start 327.269856 -47.000414)
						(mid 327.306142 -47.058193)
						(end 327.363836 -47.094648)
					)
					(arc
						(start 327.363836 -47.199804)
						(mid 327.234115 -47.130135)
						(end 327.164446 -47.000414)
					)
				)
			)
		)
		(zone
			(layer "F.Cu")
			(hatch none 0.5)
			(connect_pads
				(clearance 0)
			)
			(min_thickness 0.25)
			(keepout
				(tracks not_allowed)
				(vias allowed)
				(pads allowed)
				(copperpour not_allowed)
				(footprints allowed)
			)
			(placement
				(enabled no)
				(sheetname "")
			)
			(fill
				(thermal_gap 0.5)
				(thermal_bridge_width 0.5)
				(island_removal_mode 0)
			)
			(polygon
				(pts
					(arc
						(start 327.269856 -45.999908)
						(mid 327.306142 -46.057687)
						(end 327.363836 -46.094142)
					)
					(arc
						(start 327.363836 -46.199298)
						(mid 327.234115 -46.129629)
						(end 327.164446 -45.999908)
					)
				)
			)
		)
		(zone
			(layer "F.Cu")
			(hatch none 0.5)
			(connect_pads
				(clearance 0)
			)
			(min_thickness 0.25)
			(keepout
				(tracks not_allowed)
				(vias allowed)
				(pads allowed)
				(copperpour not_allowed)
				(footprints allowed)
			)
			(placement
				(enabled no)
				(sheetname "")
			)
			(fill
				(thermal_gap 0.5)
				(thermal_bridge_width 0.5)
				(island_removal_mode 0)
			)
			(polygon
				(pts
					(arc
						(start 327.269856 -44.999402)
						(mid 327.306142 -45.057181)
						(end 327.363836 -45.093636)
					)
					(arc
						(start 327.363836 -45.198792)
						(mid 327.234115 -45.129123)
						(end 327.164446 -44.999402)
					)
				)
			)
		)
		(zone
			(layer "F.Cu")
			(hatch none 0.5)
			(connect_pads
				(clearance 0)
			)
			(min_thickness 0.25)
			(keepout
				(tracks not_allowed)
				(vias allowed)
				(pads allowed)
				(copperpour not_allowed)
				(footprints allowed)
			)
			(placement
				(enabled no)
				(sheetname "")
			)
			(fill
				(thermal_gap 0.5)
				(thermal_bridge_width 0.5)
				(island_removal_mode 0)
			)
			(polygon
				(pts
					(arc
						(start 327.269856 -43.998896)
						(mid 327.306142 -44.056675)
						(end 327.363836 -44.09313)
					)
					(arc
						(start 327.363836 -44.198286)
						(mid 327.234115 -44.128617)
						(end 327.164446 -43.998896)
					)
				)
			)
		)
		(zone
			(layer "F.Cu")
			(hatch none 0.5)
			(connect_pads
				(clearance 0)
			)
			(min_thickness 0.25)
			(keepout
				(tracks not_allowed)
				(vias allowed)
				(pads allowed)
				(copperpour not_allowed)
				(footprints allowed)
			)
			(placement
				(enabled no)
				(sheetname "")
			)
			(fill
				(thermal_gap 0.5)
				(thermal_bridge_width 0.5)
				(island_removal_mode 0)
			)
			(polygon
				(pts
					(arc
						(start 327.269856 -42.99839)
						(mid 327.306087 -43.056249)
						(end 327.363836 -43.092624)
					)
					(arc
						(start 327.363836 -43.19778)
						(mid 327.234115 -43.128111)
						(end 327.164446 -42.99839)
					)
				)
			)
		)
		(zone
			(layer "F.Cu")
			(hatch none 0.5)
			(connect_pads
				(clearance 0)
			)
			(min_thickness 0.25)
			(keepout
				(tracks not_allowed)
				(vias allowed)
				(pads allowed)
				(copperpour not_allowed)
				(footprints allowed)
			)
			(placement
				(enabled no)
				(sheetname "")
			)
			(fill
				(thermal_gap 0.5)
				(thermal_bridge_width 0.5)
				(island_removal_mode 0)
			)
			(polygon
				(pts
					(arc
						(start 327.269856 -41.997884)
						(mid 327.306087 -42.055743)
						(end 327.363836 -42.092118)
					)
					(arc
						(start 327.363836 -42.197274)
						(mid 327.234115 -42.127605)
						(end 327.164446 -41.997884)
					)
				)
			)
		)
		(zone
			(layer "F.Cu")
			(hatch none 0.5)
			(connect_pads
				(clearance 0)
			)
			(min_thickness 0.25)
			(keepout
				(tracks not_allowed)
				(vias allowed)
				(pads allowed)
				(copperpour not_allowed)
				(footprints allowed)
			)
			(placement
				(enabled no)
				(sheetname "")
			)
			(fill
				(thermal_gap 0.5)
				(thermal_bridge_width 0.5)
				(island_removal_mode 0)
			)
			(polygon
				(pts
					(arc
						(start 327.269856 -40.997378)
						(mid 327.306087 -41.055237)
						(end 327.363836 -41.091612)
					)
					(arc
						(start 327.363836 -41.196768)
						(mid 327.234115 -41.127099)
						(end 327.164446 -40.997378)
					)
				)
			)
		)
		(zone
			(layer "F.Cu")
			(hatch none 0.5)
			(connect_pads
				(clearance 0)
			)
			(min_thickness 0.25)
			(keepout
				(tracks not_allowed)
				(vias allowed)
				(pads allowed)
				(copperpour not_allowed)
				(footprints allowed)
			)
			(placement
				(enabled no)
				(sheetname "")
			)
			(fill
				(thermal_gap 0.5)
				(thermal_bridge_width 0.5)
				(island_removal_mode 0)
			)
			(polygon
				(pts
					(arc
						(start 327.269856 -39.996872)
						(mid 327.306142 -40.054651)
						(end 327.363836 -40.091106)
					)
					(arc
						(start 327.363836 -40.196262)
						(mid 327.234115 -40.126593)
						(end 327.164446 -39.996872)
					)
				)
			)
		)
		(zone
			(layer "F.Cu")
			(hatch none 0.5)
			(connect_pads
				(clearance 0)
			)
			(min_thickness 0.25)
			(keepout
				(tracks not_allowed)
				(vias allowed)
				(pads allowed)
				(copperpour not_allowed)
				(footprints allowed)
			)
			(placement
				(enabled no)
				(sheetname "")
			)
			(fill
				(thermal_gap 0.5)
				(thermal_bridge_width 0.5)
				(island_removal_mode 0)
			)
			(polygon
				(pts
					(arc
						(start 327.269856 -38.996366)
						(mid 327.306142 -39.054145)
						(end 327.363836 -39.0906)
					)
					(arc
						(start 327.363836 -39.195756)
						(mid 327.234115 -39.126087)
						(end 327.164446 -38.996366)
					)
				)
			)
		)
		(zone
			(layer "F.Cu")
			(hatch none 0.5)
			(connect_pads
				(clearance 0)
			)
			(min_thickness 0.25)
			(keepout
				(tracks not_allowed)
				(vias allowed)
				(pads allowed)
				(copperpour not_allowed)
				(footprints allowed)
			)
			(placement
				(enabled no)
				(sheetname "")
			)
			(fill
				(thermal_gap 0.5)
				(thermal_bridge_width 0.5)
				(island_removal_mode 0)
			)
			(polygon
				(pts
					(arc
						(start 327.290684 -38.435534)
						(mid 327.348547 -38.399163)
						(end 327.384918 -38.3413)
					)
					(arc
						(start 327.490074 -38.3413)
						(mid 327.420405 -38.471021)
						(end 327.290684 -38.54069)
					)
				)
			)
		)
		(zone
			(layer "F.Cu")
			(hatch none 0.5)
			(connect_pads
				(clearance 0)
			)
			(min_thickness 0.25)
			(keepout
				(tracks not_allowed)
				(vias allowed)
				(pads allowed)
				(copperpour not_allowed)
				(footprints allowed)
			)
			(placement
				(enabled no)
				(sheetname "")
			)
			(fill
				(thermal_gap 0.5)
				(thermal_bridge_width 0.5)
				(island_removal_mode 0)
			)
			(polygon
				(pts
					(arc
						(start 327.363836 -57.809892)
						(mid 327.306082 -57.846288)
						(end 327.269856 -57.904126)
					)
					(arc
						(start 327.164446 -57.904126)
						(mid 327.234115 -57.774405)
						(end 327.363836 -57.704736)
					)
				)
			)
		)
		(zone
			(layer "F.Cu")
			(hatch none 0.5)
			(connect_pads
				(clearance 0)
			)
			(min_thickness 0.25)
			(keepout
				(tracks not_allowed)
				(vias allowed)
				(pads allowed)
				(copperpour not_allowed)
				(footprints allowed)
			)
			(placement
				(enabled no)
				(sheetname "")
			)
			(fill
				(thermal_gap 0.5)
				(thermal_bridge_width 0.5)
				(island_removal_mode 0)
			)
			(polygon
				(pts
					(arc
						(start 327.363836 -56.809386)
						(mid 327.306082 -56.845782)
						(end 327.269856 -56.90362)
					)
					(arc
						(start 327.164446 -56.90362)
						(mid 327.234115 -56.773899)
						(end 327.363836 -56.70423)
					)
				)
			)
		)
		(zone
			(layer "F.Cu")
			(hatch none 0.5)
			(connect_pads
				(clearance 0)
			)
			(min_thickness 0.25)
			(keepout
				(tracks not_allowed)
				(vias allowed)
				(pads allowed)
				(copperpour not_allowed)
				(footprints allowed)
			)
			(placement
				(enabled no)
				(sheetname "")
			)
			(fill
				(thermal_gap 0.5)
				(thermal_bridge_width 0.5)
				(island_removal_mode 0)
			)
			(polygon
				(pts
					(arc
						(start 327.363836 -55.80888)
						(mid 327.306082 -55.845276)
						(end 327.269856 -55.903114)
					)
					(arc
						(start 327.164446 -55.903114)
						(mid 327.234115 -55.773393)
						(end 327.363836 -55.703724)
					)
				)
			)
		)
		(zone
			(layer "F.Cu")
			(hatch none 0.5)
			(connect_pads
				(clearance 0)
			)
			(min_thickness 0.25)
			(keepout
				(tracks not_allowed)
				(vias allowed)
				(pads allowed)
				(copperpour not_allowed)
				(footprints allowed)
			)
			(placement
				(enabled no)
				(sheetname "")
			)
			(fill
				(thermal_gap 0.5)
				(thermal_bridge_width 0.5)
				(island_removal_mode 0)
			)
			(polygon
				(pts
					(arc
						(start 327.363836 -54.808374)
						(mid 327.306082 -54.84477)
						(end 327.269856 -54.902608)
					)
					(arc
						(start 327.164446 -54.902608)
						(mid 327.234115 -54.772887)
						(end 327.363836 -54.703218)
					)
				)
			)
		)
		(zone
			(layer "F.Cu")
			(hatch none 0.5)
			(connect_pads
				(clearance 0)
			)
			(min_thickness 0.25)
			(keepout
				(tracks not_allowed)
				(vias allowed)
				(pads allowed)
				(copperpour not_allowed)
				(footprints allowed)
			)
			(placement
				(enabled no)
				(sheetname "")
			)
			(fill
				(thermal_gap 0.5)
				(thermal_bridge_width 0.5)
				(island_removal_mode 0)
			)
			(polygon
				(pts
					(arc
						(start 327.363836 -53.807868)
						(mid 327.306082 -53.844264)
						(end 327.269856 -53.902102)
					)
					(arc
						(start 327.164446 -53.902102)
						(mid 327.234115 -53.772381)
						(end 327.363836 -53.702712)
					)
				)
			)
		)
		(zone
			(layer "F.Cu")
			(hatch none 0.5)
			(connect_pads
				(clearance 0)
			)
			(min_thickness 0.25)
			(keepout
				(tracks not_allowed)
				(vias allowed)
				(pads allowed)
				(copperpour not_allowed)
				(footprints allowed)
			)
			(placement
				(enabled no)
				(sheetname "")
			)
			(fill
				(thermal_gap 0.5)
				(thermal_bridge_width 0.5)
				(island_removal_mode 0)
			)
			(polygon
				(pts
					(arc
						(start 327.363836 -52.807362)
						(mid 327.306082 -52.843758)
						(end 327.269856 -52.901596)
					)
					(arc
						(start 327.164446 -52.901596)
						(mid 327.234115 -52.771875)
						(end 327.363836 -52.702206)
					)
				)
			)
		)
		(zone
			(layer "F.Cu")
			(hatch none 0.5)
			(connect_pads
				(clearance 0)
			)
			(min_thickness 0.25)
			(keepout
				(tracks not_allowed)
				(vias allowed)
				(pads allowed)
				(copperpour not_allowed)
				(footprints allowed)
			)
			(placement
				(enabled no)
				(sheetname "")
			)
			(fill
				(thermal_gap 0.5)
				(thermal_bridge_width 0.5)
				(island_removal_mode 0)
			)
			(polygon
				(pts
					(arc
						(start 327.363836 -51.80711)
						(mid 327.306137 -51.843536)
						(end 327.269856 -51.901344)
					)
					(arc
						(start 327.164446 -51.901344)
						(mid 327.234115 -51.771623)
						(end 327.363836 -51.701954)
					)
				)
			)
		)
		(zone
			(layer "F.Cu")
			(hatch none 0.5)
			(connect_pads
				(clearance 0)
			)
			(min_thickness 0.25)
			(keepout
				(tracks not_allowed)
				(vias allowed)
				(pads allowed)
				(copperpour not_allowed)
				(footprints allowed)
			)
			(placement
				(enabled no)
				(sheetname "")
			)
			(fill
				(thermal_gap 0.5)
				(thermal_bridge_width 0.5)
				(island_removal_mode 0)
			)
			(polygon
				(pts
					(arc
						(start 327.363836 -50.806604)
						(mid 327.306137 -50.84303)
						(end 327.269856 -50.900838)
					)
					(arc
						(start 327.164446 -50.900838)
						(mid 327.234115 -50.771117)
						(end 327.363836 -50.701448)
					)
				)
			)
		)
		(zone
			(layer "F.Cu")
			(hatch none 0.5)
			(connect_pads
				(clearance 0)
			)
			(min_thickness 0.25)
			(keepout
				(tracks not_allowed)
				(vias allowed)
				(pads allowed)
				(copperpour not_allowed)
				(footprints allowed)
			)
			(placement
				(enabled no)
				(sheetname "")
			)
			(fill
				(thermal_gap 0.5)
				(thermal_bridge_width 0.5)
				(island_removal_mode 0)
			)
			(polygon
				(pts
					(arc
						(start 327.363836 -49.806098)
						(mid 327.306137 -49.842524)
						(end 327.269856 -49.900332)
					)
					(arc
						(start 327.164446 -49.900332)
						(mid 327.234115 -49.770611)
						(end 327.363836 -49.700942)
					)
				)
			)
		)
		(zone
			(layer "F.Cu")
			(hatch none 0.5)
			(connect_pads
				(clearance 0)
			)
			(min_thickness 0.25)
			(keepout
				(tracks not_allowed)
				(vias allowed)
				(pads allowed)
				(copperpour not_allowed)
				(footprints allowed)
			)
			(placement
				(enabled no)
				(sheetname "")
			)
			(fill
				(thermal_gap 0.5)
				(thermal_bridge_width 0.5)
				(island_removal_mode 0)
			)
			(polygon
				(pts
					(arc
						(start 327.363836 -48.805592)
						(mid 327.306137 -48.842018)
						(end 327.269856 -48.899826)
					)
					(arc
						(start 327.164446 -48.899826)
						(mid 327.234115 -48.770105)
						(end 327.363836 -48.700436)
					)
				)
			)
		)
		(zone
			(layer "F.Cu")
			(hatch none 0.5)
			(connect_pads
				(clearance 0)
			)
			(min_thickness 0.25)
			(keepout
				(tracks not_allowed)
				(vias allowed)
				(pads allowed)
				(copperpour not_allowed)
				(footprints allowed)
			)
			(placement
				(enabled no)
				(sheetname "")
			)
			(fill
				(thermal_gap 0.5)
				(thermal_bridge_width 0.5)
				(island_removal_mode 0)
			)
			(polygon
				(pts
					(arc
						(start 327.363836 -47.805086)
						(mid 327.306137 -47.841512)
						(end 327.269856 -47.89932)
					)
					(arc
						(start 327.164446 -47.89932)
						(mid 327.234115 -47.769599)
						(end 327.363836 -47.69993)
					)
				)
			)
		)
		(zone
			(layer "F.Cu")
			(hatch none 0.5)
			(connect_pads
				(clearance 0)
			)
			(min_thickness 0.25)
			(keepout
				(tracks not_allowed)
				(vias allowed)
				(pads allowed)
				(copperpour not_allowed)
				(footprints allowed)
			)
			(placement
				(enabled no)
				(sheetname "")
			)
			(fill
				(thermal_gap 0.5)
				(thermal_bridge_width 0.5)
				(island_removal_mode 0)
			)
			(polygon
				(pts
					(arc
						(start 327.363836 -46.80458)
						(mid 327.306137 -46.841006)
						(end 327.269856 -46.898814)
					)
					(arc
						(start 327.164446 -46.898814)
						(mid 327.234115 -46.769093)
						(end 327.363836 -46.699424)
					)
				)
			)
		)
		(zone
			(layer "F.Cu")
			(hatch none 0.5)
			(connect_pads
				(clearance 0)
			)
			(min_thickness 0.25)
			(keepout
				(tracks not_allowed)
				(vias allowed)
				(pads allowed)
				(copperpour not_allowed)
				(footprints allowed)
			)
			(placement
				(enabled no)
				(sheetname "")
			)
			(fill
				(thermal_gap 0.5)
				(thermal_bridge_width 0.5)
				(island_removal_mode 0)
			)
			(polygon
				(pts
					(arc
						(start 327.363836 -45.804074)
						(mid 327.306137 -45.8405)
						(end 327.269856 -45.898308)
					)
					(arc
						(start 327.164446 -45.898308)
						(mid 327.234115 -45.768587)
						(end 327.363836 -45.698918)
					)
				)
			)
		)
		(zone
			(layer "F.Cu")
			(hatch none 0.5)
			(connect_pads
				(clearance 0)
			)
			(min_thickness 0.25)
			(keepout
				(tracks not_allowed)
				(vias allowed)
				(pads allowed)
				(copperpour not_allowed)
				(footprints allowed)
			)
			(placement
				(enabled no)
				(sheetname "")
			)
			(fill
				(thermal_gap 0.5)
				(thermal_bridge_width 0.5)
				(island_removal_mode 0)
			)
			(polygon
				(pts
					(arc
						(start 327.363836 -44.803568)
						(mid 327.306137 -44.839994)
						(end 327.269856 -44.897802)
					)
					(arc
						(start 327.164446 -44.897802)
						(mid 327.234115 -44.768081)
						(end 327.363836 -44.698412)
					)
				)
			)
		)
		(zone
			(layer "F.Cu")
			(hatch none 0.5)
			(connect_pads
				(clearance 0)
			)
			(min_thickness 0.25)
			(keepout
				(tracks not_allowed)
				(vias allowed)
				(pads allowed)
				(copperpour not_allowed)
				(footprints allowed)
			)
			(placement
				(enabled no)
				(sheetname "")
			)
			(fill
				(thermal_gap 0.5)
				(thermal_bridge_width 0.5)
				(island_removal_mode 0)
			)
			(polygon
				(pts
					(arc
						(start 327.363836 -43.803062)
						(mid 327.306137 -43.839488)
						(end 327.269856 -43.897296)
					)
					(arc
						(start 327.164446 -43.897296)
						(mid 327.234115 -43.767575)
						(end 327.363836 -43.697906)
					)
				)
			)
		)
		(zone
			(layer "F.Cu")
			(hatch none 0.5)
			(connect_pads
				(clearance 0)
			)
			(min_thickness 0.25)
			(keepout
				(tracks not_allowed)
				(vias allowed)
				(pads allowed)
				(copperpour not_allowed)
				(footprints allowed)
			)
			(placement
				(enabled no)
				(sheetname "")
			)
			(fill
				(thermal_gap 0.5)
				(thermal_bridge_width 0.5)
				(island_removal_mode 0)
			)
			(polygon
				(pts
					(arc
						(start 327.363836 -42.802556)
						(mid 327.306082 -42.838952)
						(end 327.269856 -42.89679)
					)
					(arc
						(start 327.164446 -42.89679)
						(mid 327.234115 -42.767069)
						(end 327.363836 -42.6974)
					)
				)
			)
		)
		(zone
			(layer "F.Cu")
			(hatch none 0.5)
			(connect_pads
				(clearance 0)
			)
			(min_thickness 0.25)
			(keepout
				(tracks not_allowed)
				(vias allowed)
				(pads allowed)
				(copperpour not_allowed)
				(footprints allowed)
			)
			(placement
				(enabled no)
				(sheetname "")
			)
			(fill
				(thermal_gap 0.5)
				(thermal_bridge_width 0.5)
				(island_removal_mode 0)
			)
			(polygon
				(pts
					(arc
						(start 327.363836 -41.80205)
						(mid 327.306082 -41.838446)
						(end 327.269856 -41.896284)
					)
					(arc
						(start 327.164446 -41.896284)
						(mid 327.234115 -41.766563)
						(end 327.363836 -41.696894)
					)
				)
			)
		)
		(zone
			(layer "F.Cu")
			(hatch none 0.5)
			(connect_pads
				(clearance 0)
			)
			(min_thickness 0.25)
			(keepout
				(tracks not_allowed)
				(vias allowed)
				(pads allowed)
				(copperpour not_allowed)
				(footprints allowed)
			)
			(placement
				(enabled no)
				(sheetname "")
			)
			(fill
				(thermal_gap 0.5)
				(thermal_bridge_width 0.5)
				(island_removal_mode 0)
			)
			(polygon
				(pts
					(arc
						(start 327.363836 -40.801544)
						(mid 327.306082 -40.83794)
						(end 327.269856 -40.895778)
					)
					(arc
						(start 327.164446 -40.895778)
						(mid 327.234115 -40.766057)
						(end 327.363836 -40.696388)
					)
				)
			)
		)
		(zone
			(layer "F.Cu")
			(hatch none 0.5)
			(connect_pads
				(clearance 0)
			)
			(min_thickness 0.25)
			(keepout
				(tracks not_allowed)
				(vias allowed)
				(pads allowed)
				(copperpour not_allowed)
				(footprints allowed)
			)
			(placement
				(enabled no)
				(sheetname "")
			)
			(fill
				(thermal_gap 0.5)
				(thermal_bridge_width 0.5)
				(island_removal_mode 0)
			)
			(polygon
				(pts
					(arc
						(start 327.363836 -39.801038)
						(mid 327.306137 -39.837464)
						(end 327.269856 -39.895272)
					)
					(arc
						(start 327.164446 -39.895272)
						(mid 327.234115 -39.765551)
						(end 327.363836 -39.695882)
					)
				)
			)
		)
		(zone
			(layer "F.Cu")
			(hatch none 0.5)
			(connect_pads
				(clearance 0)
			)
			(min_thickness 0.25)
			(keepout
				(tracks not_allowed)
				(vias allowed)
				(pads allowed)
				(copperpour not_allowed)
				(footprints allowed)
			)
			(placement
				(enabled no)
				(sheetname "")
			)
			(fill
				(thermal_gap 0.5)
				(thermal_bridge_width 0.5)
				(island_removal_mode 0)
			)
			(polygon
				(pts
					(arc
						(start 327.363836 -38.800532)
						(mid 327.306137 -38.836958)
						(end 327.269856 -38.894766)
					)
					(arc
						(start 327.164446 -38.894766)
						(mid 327.234115 -38.765045)
						(end 327.363836 -38.695376)
					)
				)
			)
		)
		(zone
			(layer "F.Cu")
			(hatch none 0.5)
			(connect_pads
				(clearance 0)
			)
			(min_thickness 0.25)
			(keepout
				(tracks not_allowed)
				(vias allowed)
				(pads allowed)
				(copperpour not_allowed)
				(footprints allowed)
			)
			(placement
				(enabled no)
				(sheetname "")
			)
			(fill
				(thermal_gap 0.5)
				(thermal_bridge_width 0.5)
				(island_removal_mode 0)
			)
			(polygon
				(pts
					(arc
						(start 327.384918 -38.2397)
						(mid 327.348547 -38.181837)
						(end 327.290684 -38.145466)
					)
					(arc
						(start 327.290684 -38.04031)
						(mid 327.420405 -38.109979)
						(end 327.490074 -38.2397)
					)
				)
			)
		)
		(zone
			(layer "F.Cu")
			(hatch none 0.5)
			(connect_pads
				(clearance 0)
			)
			(min_thickness 0.25)
			(keepout
				(tracks not_allowed)
				(vias allowed)
				(pads allowed)
				(copperpour not_allowed)
				(footprints allowed)
			)
			(placement
				(enabled no)
				(sheetname "")
			)
			(fill
				(thermal_gap 0.5)
				(thermal_bridge_width 0.5)
				(island_removal_mode 0)
			)
			(polygon
				(pts
					(arc
						(start 327.465436 -58.09996)
						(mid 327.523299 -58.063589)
						(end 327.55967 -58.005726)
					)
					(arc
						(start 327.66508 -58.005726)
						(mid 327.595323 -58.135535)
						(end 327.465436 -58.205116)
					)
				)
			)
		)
		(zone
			(layer "F.Cu")
			(hatch none 0.5)
			(connect_pads
				(clearance 0)
			)
			(min_thickness 0.25)
			(keepout
				(tracks not_allowed)
				(vias allowed)
				(pads allowed)
				(copperpour not_allowed)
				(footprints allowed)
			)
			(placement
				(enabled no)
				(sheetname "")
			)
			(fill
				(thermal_gap 0.5)
				(thermal_bridge_width 0.5)
				(island_removal_mode 0)
			)
			(polygon
				(pts
					(arc
						(start 327.465436 -57.099454)
						(mid 327.523299 -57.063083)
						(end 327.55967 -57.00522)
					)
					(arc
						(start 327.66508 -57.00522)
						(mid 327.595323 -57.135029)
						(end 327.465436 -57.20461)
					)
				)
			)
		)
		(zone
			(layer "F.Cu")
			(hatch none 0.5)
			(connect_pads
				(clearance 0)
			)
			(min_thickness 0.25)
			(keepout
				(tracks not_allowed)
				(vias allowed)
				(pads allowed)
				(copperpour not_allowed)
				(footprints allowed)
			)
			(placement
				(enabled no)
				(sheetname "")
			)
			(fill
				(thermal_gap 0.5)
				(thermal_bridge_width 0.5)
				(island_removal_mode 0)
			)
			(polygon
				(pts
					(arc
						(start 327.465436 -56.098948)
						(mid 327.523299 -56.062577)
						(end 327.55967 -56.004714)
					)
					(arc
						(start 327.66508 -56.004714)
						(mid 327.595323 -56.134523)
						(end 327.465436 -56.204104)
					)
				)
			)
		)
		(zone
			(layer "F.Cu")
			(hatch none 0.5)
			(connect_pads
				(clearance 0)
			)
			(min_thickness 0.25)
			(keepout
				(tracks not_allowed)
				(vias allowed)
				(pads allowed)
				(copperpour not_allowed)
				(footprints allowed)
			)
			(placement
				(enabled no)
				(sheetname "")
			)
			(fill
				(thermal_gap 0.5)
				(thermal_bridge_width 0.5)
				(island_removal_mode 0)
			)
			(polygon
				(pts
					(arc
						(start 327.465436 -55.098442)
						(mid 327.523299 -55.062071)
						(end 327.55967 -55.004208)
					)
					(arc
						(start 327.66508 -55.004208)
						(mid 327.595323 -55.134017)
						(end 327.465436 -55.203598)
					)
				)
			)
		)
		(zone
			(layer "F.Cu")
			(hatch none 0.5)
			(connect_pads
				(clearance 0)
			)
			(min_thickness 0.25)
			(keepout
				(tracks not_allowed)
				(vias allowed)
				(pads allowed)
				(copperpour not_allowed)
				(footprints allowed)
			)
			(placement
				(enabled no)
				(sheetname "")
			)
			(fill
				(thermal_gap 0.5)
				(thermal_bridge_width 0.5)
				(island_removal_mode 0)
			)
			(polygon
				(pts
					(arc
						(start 327.465436 -54.097936)
						(mid 327.523299 -54.061565)
						(end 327.55967 -54.003702)
					)
					(arc
						(start 327.66508 -54.003702)
						(mid 327.595323 -54.133511)
						(end 327.465436 -54.203092)
					)
				)
			)
		)
		(zone
			(layer "F.Cu")
			(hatch none 0.5)
			(connect_pads
				(clearance 0)
			)
			(min_thickness 0.25)
			(keepout
				(tracks not_allowed)
				(vias allowed)
				(pads allowed)
				(copperpour not_allowed)
				(footprints allowed)
			)
			(placement
				(enabled no)
				(sheetname "")
			)
			(fill
				(thermal_gap 0.5)
				(thermal_bridge_width 0.5)
				(island_removal_mode 0)
			)
			(polygon
				(pts
					(arc
						(start 327.465436 -53.09743)
						(mid 327.523299 -53.061059)
						(end 327.55967 -53.003196)
					)
					(arc
						(start 327.66508 -53.003196)
						(mid 327.595323 -53.133005)
						(end 327.465436 -53.202586)
					)
				)
			)
		)
		(zone
			(layer "F.Cu")
			(hatch none 0.5)
			(connect_pads
				(clearance 0)
			)
			(min_thickness 0.25)
			(keepout
				(tracks not_allowed)
				(vias allowed)
				(pads allowed)
				(copperpour not_allowed)
				(footprints allowed)
			)
			(placement
				(enabled no)
				(sheetname "")
			)
			(fill
				(thermal_gap 0.5)
				(thermal_bridge_width 0.5)
				(island_removal_mode 0)
			)
			(polygon
				(pts
					(arc
						(start 327.465436 -52.096924)
						(mid 327.523295 -52.060693)
						(end 327.55967 -52.002944)
					)
					(arc
						(start 327.66508 -52.002944)
						(mid 327.595323 -52.132753)
						(end 327.465436 -52.202334)
					)
				)
			)
		)
		(zone
			(layer "F.Cu")
			(hatch none 0.5)
			(connect_pads
				(clearance 0)
			)
			(min_thickness 0.25)
			(keepout
				(tracks not_allowed)
				(vias allowed)
				(pads allowed)
				(copperpour not_allowed)
				(footprints allowed)
			)
			(placement
				(enabled no)
				(sheetname "")
			)
			(fill
				(thermal_gap 0.5)
				(thermal_bridge_width 0.5)
				(island_removal_mode 0)
			)
			(polygon
				(pts
					(arc
						(start 327.465436 -51.096672)
						(mid 327.523299 -51.060301)
						(end 327.55967 -51.002438)
					)
					(arc
						(start 327.66508 -51.002438)
						(mid 327.595323 -51.132247)
						(end 327.465436 -51.201828)
					)
				)
			)
		)
		(zone
			(layer "F.Cu")
			(hatch none 0.5)
			(connect_pads
				(clearance 0)
			)
			(min_thickness 0.25)
			(keepout
				(tracks not_allowed)
				(vias allowed)
				(pads allowed)
				(copperpour not_allowed)
				(footprints allowed)
			)
			(placement
				(enabled no)
				(sheetname "")
			)
			(fill
				(thermal_gap 0.5)
				(thermal_bridge_width 0.5)
				(island_removal_mode 0)
			)
			(polygon
				(pts
					(arc
						(start 327.465436 -50.096166)
						(mid 327.523299 -50.059795)
						(end 327.55967 -50.001932)
					)
					(arc
						(start 327.66508 -50.001932)
						(mid 327.595323 -50.131741)
						(end 327.465436 -50.201322)
					)
				)
			)
		)
		(zone
			(layer "F.Cu")
			(hatch none 0.5)
			(connect_pads
				(clearance 0)
			)
			(min_thickness 0.25)
			(keepout
				(tracks not_allowed)
				(vias allowed)
				(pads allowed)
				(copperpour not_allowed)
				(footprints allowed)
			)
			(placement
				(enabled no)
				(sheetname "")
			)
			(fill
				(thermal_gap 0.5)
				(thermal_bridge_width 0.5)
				(island_removal_mode 0)
			)
			(polygon
				(pts
					(arc
						(start 327.465436 -49.09566)
						(mid 327.523299 -49.059289)
						(end 327.55967 -49.001426)
					)
					(arc
						(start 327.66508 -49.001426)
						(mid 327.595323 -49.131235)
						(end 327.465436 -49.200816)
					)
				)
			)
		)
		(zone
			(layer "F.Cu")
			(hatch none 0.5)
			(connect_pads
				(clearance 0)
			)
			(min_thickness 0.25)
			(keepout
				(tracks not_allowed)
				(vias allowed)
				(pads allowed)
				(copperpour not_allowed)
				(footprints allowed)
			)
			(placement
				(enabled no)
				(sheetname "")
			)
			(fill
				(thermal_gap 0.5)
				(thermal_bridge_width 0.5)
				(island_removal_mode 0)
			)
			(polygon
				(pts
					(arc
						(start 327.465436 -48.095154)
						(mid 327.523299 -48.058783)
						(end 327.55967 -48.00092)
					)
					(arc
						(start 327.66508 -48.00092)
						(mid 327.595323 -48.130729)
						(end 327.465436 -48.20031)
					)
				)
			)
		)
		(zone
			(layer "F.Cu")
			(hatch none 0.5)
			(connect_pads
				(clearance 0)
			)
			(min_thickness 0.25)
			(keepout
				(tracks not_allowed)
				(vias allowed)
				(pads allowed)
				(copperpour not_allowed)
				(footprints allowed)
			)
			(placement
				(enabled no)
				(sheetname "")
			)
			(fill
				(thermal_gap 0.5)
				(thermal_bridge_width 0.5)
				(island_removal_mode 0)
			)
			(polygon
				(pts
					(arc
						(start 327.465436 -47.094648)
						(mid 327.523299 -47.058277)
						(end 327.55967 -47.000414)
					)
					(arc
						(start 327.66508 -47.000414)
						(mid 327.595323 -47.130223)
						(end 327.465436 -47.199804)
					)
				)
			)
		)
		(zone
			(layer "F.Cu")
			(hatch none 0.5)
			(connect_pads
				(clearance 0)
			)
			(min_thickness 0.25)
			(keepout
				(tracks not_allowed)
				(vias allowed)
				(pads allowed)
				(copperpour not_allowed)
				(footprints allowed)
			)
			(placement
				(enabled no)
				(sheetname "")
			)
			(fill
				(thermal_gap 0.5)
				(thermal_bridge_width 0.5)
				(island_removal_mode 0)
			)
			(polygon
				(pts
					(arc
						(start 327.465436 -46.094142)
						(mid 327.523299 -46.057771)
						(end 327.55967 -45.999908)
					)
					(arc
						(start 327.66508 -45.999908)
						(mid 327.595323 -46.129717)
						(end 327.465436 -46.199298)
					)
				)
			)
		)
		(zone
			(layer "F.Cu")
			(hatch none 0.5)
			(connect_pads
				(clearance 0)
			)
			(min_thickness 0.25)
			(keepout
				(tracks not_allowed)
				(vias allowed)
				(pads allowed)
				(copperpour not_allowed)
				(footprints allowed)
			)
			(placement
				(enabled no)
				(sheetname "")
			)
			(fill
				(thermal_gap 0.5)
				(thermal_bridge_width 0.5)
				(island_removal_mode 0)
			)
			(polygon
				(pts
					(arc
						(start 327.465436 -45.093636)
						(mid 327.523299 -45.057265)
						(end 327.55967 -44.999402)
					)
					(arc
						(start 327.66508 -44.999402)
						(mid 327.595323 -45.129211)
						(end 327.465436 -45.198792)
					)
				)
			)
		)
		(zone
			(layer "F.Cu")
			(hatch none 0.5)
			(connect_pads
				(clearance 0)
			)
			(min_thickness 0.25)
			(keepout
				(tracks not_allowed)
				(vias allowed)
				(pads allowed)
				(copperpour not_allowed)
				(footprints allowed)
			)
			(placement
				(enabled no)
				(sheetname "")
			)
			(fill
				(thermal_gap 0.5)
				(thermal_bridge_width 0.5)
				(island_removal_mode 0)
			)
			(polygon
				(pts
					(arc
						(start 327.465436 -44.09313)
						(mid 327.523299 -44.056759)
						(end 327.55967 -43.998896)
					)
					(arc
						(start 327.66508 -43.998896)
						(mid 327.595323 -44.128705)
						(end 327.465436 -44.198286)
					)
				)
			)
		)
		(zone
			(layer "F.Cu")
			(hatch none 0.5)
			(connect_pads
				(clearance 0)
			)
			(min_thickness 0.25)
			(keepout
				(tracks not_allowed)
				(vias allowed)
				(pads allowed)
				(copperpour not_allowed)
				(footprints allowed)
			)
			(placement
				(enabled no)
				(sheetname "")
			)
			(fill
				(thermal_gap 0.5)
				(thermal_bridge_width 0.5)
				(island_removal_mode 0)
			)
			(polygon
				(pts
					(arc
						(start 327.465436 -43.092624)
						(mid 327.523299 -43.056253)
						(end 327.55967 -42.99839)
					)
					(arc
						(start 327.66508 -42.99839)
						(mid 327.595323 -43.128199)
						(end 327.465436 -43.19778)
					)
				)
			)
		)
		(zone
			(layer "F.Cu")
			(hatch none 0.5)
			(connect_pads
				(clearance 0)
			)
			(min_thickness 0.25)
			(keepout
				(tracks not_allowed)
				(vias allowed)
				(pads allowed)
				(copperpour not_allowed)
				(footprints allowed)
			)
			(placement
				(enabled no)
				(sheetname "")
			)
			(fill
				(thermal_gap 0.5)
				(thermal_bridge_width 0.5)
				(island_removal_mode 0)
			)
			(polygon
				(pts
					(arc
						(start 327.465436 -42.092118)
						(mid 327.523299 -42.055747)
						(end 327.55967 -41.997884)
					)
					(arc
						(start 327.66508 -41.997884)
						(mid 327.595323 -42.127693)
						(end 327.465436 -42.197274)
					)
				)
			)
		)
		(zone
			(layer "F.Cu")
			(hatch none 0.5)
			(connect_pads
				(clearance 0)
			)
			(min_thickness 0.25)
			(keepout
				(tracks not_allowed)
				(vias allowed)
				(pads allowed)
				(copperpour not_allowed)
				(footprints allowed)
			)
			(placement
				(enabled no)
				(sheetname "")
			)
			(fill
				(thermal_gap 0.5)
				(thermal_bridge_width 0.5)
				(island_removal_mode 0)
			)
			(polygon
				(pts
					(arc
						(start 327.465436 -41.091612)
						(mid 327.523299 -41.055241)
						(end 327.55967 -40.997378)
					)
					(arc
						(start 327.66508 -40.997378)
						(mid 327.595323 -41.127187)
						(end 327.465436 -41.196768)
					)
				)
			)
		)
		(zone
			(layer "F.Cu")
			(hatch none 0.5)
			(connect_pads
				(clearance 0)
			)
			(min_thickness 0.25)
			(keepout
				(tracks not_allowed)
				(vias allowed)
				(pads allowed)
				(copperpour not_allowed)
				(footprints allowed)
			)
			(placement
				(enabled no)
				(sheetname "")
			)
			(fill
				(thermal_gap 0.5)
				(thermal_bridge_width 0.5)
				(island_removal_mode 0)
			)
			(polygon
				(pts
					(arc
						(start 327.465436 -40.091106)
						(mid 327.523299 -40.054735)
						(end 327.55967 -39.996872)
					)
					(arc
						(start 327.66508 -39.996872)
						(mid 327.595323 -40.126681)
						(end 327.465436 -40.196262)
					)
				)
			)
		)
		(zone
			(layer "F.Cu")
			(hatch none 0.5)
			(connect_pads
				(clearance 0)
			)
			(min_thickness 0.25)
			(keepout
				(tracks not_allowed)
				(vias allowed)
				(pads allowed)
				(copperpour not_allowed)
				(footprints allowed)
			)
			(placement
				(enabled no)
				(sheetname "")
			)
			(fill
				(thermal_gap 0.5)
				(thermal_bridge_width 0.5)
				(island_removal_mode 0)
			)
			(polygon
				(pts
					(arc
						(start 327.465436 -39.0906)
						(mid 327.523299 -39.054229)
						(end 327.55967 -38.996366)
					)
					(arc
						(start 327.66508 -38.996366)
						(mid 327.595323 -39.126175)
						(end 327.465436 -39.195756)
					)
				)
			)
		)
		(zone
			(layer "F.Cu")
			(hatch none 0.5)
			(connect_pads
				(clearance 0)
			)
			(min_thickness 0.25)
			(keepout
				(tracks not_allowed)
				(vias allowed)
				(pads allowed)
				(copperpour not_allowed)
				(footprints allowed)
			)
			(placement
				(enabled no)
				(sheetname "")
			)
			(fill
				(thermal_gap 0.5)
				(thermal_bridge_width 0.5)
				(island_removal_mode 0)
			)
			(polygon
				(pts
					(arc
						(start 327.55967 -57.904126)
						(mid 327.523299 -57.846263)
						(end 327.465436 -57.809892)
					)
					(arc
						(start 327.465436 -57.704736)
						(mid 327.595287 -57.774353)
						(end 327.66508 -57.904126)
					)
				)
			)
		)
		(zone
			(layer "F.Cu")
			(hatch none 0.5)
			(connect_pads
				(clearance 0)
			)
			(min_thickness 0.25)
			(keepout
				(tracks not_allowed)
				(vias allowed)
				(pads allowed)
				(copperpour not_allowed)
				(footprints allowed)
			)
			(placement
				(enabled no)
				(sheetname "")
			)
			(fill
				(thermal_gap 0.5)
				(thermal_bridge_width 0.5)
				(island_removal_mode 0)
			)
			(polygon
				(pts
					(arc
						(start 327.55967 -56.90362)
						(mid 327.523299 -56.845757)
						(end 327.465436 -56.809386)
					)
					(arc
						(start 327.465436 -56.70423)
						(mid 327.595287 -56.773847)
						(end 327.66508 -56.90362)
					)
				)
			)
		)
		(zone
			(layer "F.Cu")
			(hatch none 0.5)
			(connect_pads
				(clearance 0)
			)
			(min_thickness 0.25)
			(keepout
				(tracks not_allowed)
				(vias allowed)
				(pads allowed)
				(copperpour not_allowed)
				(footprints allowed)
			)
			(placement
				(enabled no)
				(sheetname "")
			)
			(fill
				(thermal_gap 0.5)
				(thermal_bridge_width 0.5)
				(island_removal_mode 0)
			)
			(polygon
				(pts
					(arc
						(start 327.55967 -55.903114)
						(mid 327.523299 -55.845251)
						(end 327.465436 -55.80888)
					)
					(arc
						(start 327.465436 -55.703724)
						(mid 327.595287 -55.773341)
						(end 327.66508 -55.903114)
					)
				)
			)
		)
		(zone
			(layer "F.Cu")
			(hatch none 0.5)
			(connect_pads
				(clearance 0)
			)
			(min_thickness 0.25)
			(keepout
				(tracks not_allowed)
				(vias allowed)
				(pads allowed)
				(copperpour not_allowed)
				(footprints allowed)
			)
			(placement
				(enabled no)
				(sheetname "")
			)
			(fill
				(thermal_gap 0.5)
				(thermal_bridge_width 0.5)
				(island_removal_mode 0)
			)
			(polygon
				(pts
					(arc
						(start 327.55967 -54.902608)
						(mid 327.523299 -54.844745)
						(end 327.465436 -54.808374)
					)
					(arc
						(start 327.465436 -54.703218)
						(mid 327.595287 -54.772835)
						(end 327.66508 -54.902608)
					)
				)
			)
		)
		(zone
			(layer "F.Cu")
			(hatch none 0.5)
			(connect_pads
				(clearance 0)
			)
			(min_thickness 0.25)
			(keepout
				(tracks not_allowed)
				(vias allowed)
				(pads allowed)
				(copperpour not_allowed)
				(footprints allowed)
			)
			(placement
				(enabled no)
				(sheetname "")
			)
			(fill
				(thermal_gap 0.5)
				(thermal_bridge_width 0.5)
				(island_removal_mode 0)
			)
			(polygon
				(pts
					(arc
						(start 327.55967 -53.902102)
						(mid 327.523299 -53.844239)
						(end 327.465436 -53.807868)
					)
					(arc
						(start 327.465436 -53.702712)
						(mid 327.595287 -53.772329)
						(end 327.66508 -53.902102)
					)
				)
			)
		)
		(zone
			(layer "F.Cu")
			(hatch none 0.5)
			(connect_pads
				(clearance 0)
			)
			(min_thickness 0.25)
			(keepout
				(tracks not_allowed)
				(vias allowed)
				(pads allowed)
				(copperpour not_allowed)
				(footprints allowed)
			)
			(placement
				(enabled no)
				(sheetname "")
			)
			(fill
				(thermal_gap 0.5)
				(thermal_bridge_width 0.5)
				(island_removal_mode 0)
			)
			(polygon
				(pts
					(arc
						(start 327.55967 -52.901596)
						(mid 327.523299 -52.843733)
						(end 327.465436 -52.807362)
					)
					(arc
						(start 327.465436 -52.702206)
						(mid 327.595287 -52.771823)
						(end 327.66508 -52.901596)
					)
				)
			)
		)
		(zone
			(layer "F.Cu")
			(hatch none 0.5)
			(connect_pads
				(clearance 0)
			)
			(min_thickness 0.25)
			(keepout
				(tracks not_allowed)
				(vias allowed)
				(pads allowed)
				(copperpour not_allowed)
				(footprints allowed)
			)
			(placement
				(enabled no)
				(sheetname "")
			)
			(fill
				(thermal_gap 0.5)
				(thermal_bridge_width 0.5)
				(island_removal_mode 0)
			)
			(polygon
				(pts
					(arc
						(start 327.55967 -51.901344)
						(mid 327.523299 -51.843481)
						(end 327.465436 -51.80711)
					)
					(arc
						(start 327.465436 -51.701954)
						(mid 327.595287 -51.771571)
						(end 327.66508 -51.901344)
					)
				)
			)
		)
		(zone
			(layer "F.Cu")
			(hatch none 0.5)
			(connect_pads
				(clearance 0)
			)
			(min_thickness 0.25)
			(keepout
				(tracks not_allowed)
				(vias allowed)
				(pads allowed)
				(copperpour not_allowed)
				(footprints allowed)
			)
			(placement
				(enabled no)
				(sheetname "")
			)
			(fill
				(thermal_gap 0.5)
				(thermal_bridge_width 0.5)
				(island_removal_mode 0)
			)
			(polygon
				(pts
					(arc
						(start 327.55967 -50.900838)
						(mid 327.523299 -50.842975)
						(end 327.465436 -50.806604)
					)
					(arc
						(start 327.465436 -50.701448)
						(mid 327.595287 -50.771065)
						(end 327.66508 -50.900838)
					)
				)
			)
		)
		(zone
			(layer "F.Cu")
			(hatch none 0.5)
			(connect_pads
				(clearance 0)
			)
			(min_thickness 0.25)
			(keepout
				(tracks not_allowed)
				(vias allowed)
				(pads allowed)
				(copperpour not_allowed)
				(footprints allowed)
			)
			(placement
				(enabled no)
				(sheetname "")
			)
			(fill
				(thermal_gap 0.5)
				(thermal_bridge_width 0.5)
				(island_removal_mode 0)
			)
			(polygon
				(pts
					(arc
						(start 327.55967 -49.900332)
						(mid 327.523299 -49.842469)
						(end 327.465436 -49.806098)
					)
					(arc
						(start 327.465436 -49.700942)
						(mid 327.595287 -49.770559)
						(end 327.66508 -49.900332)
					)
				)
			)
		)
		(zone
			(layer "F.Cu")
			(hatch none 0.5)
			(connect_pads
				(clearance 0)
			)
			(min_thickness 0.25)
			(keepout
				(tracks not_allowed)
				(vias allowed)
				(pads allowed)
				(copperpour not_allowed)
				(footprints allowed)
			)
			(placement
				(enabled no)
				(sheetname "")
			)
			(fill
				(thermal_gap 0.5)
				(thermal_bridge_width 0.5)
				(island_removal_mode 0)
			)
			(polygon
				(pts
					(arc
						(start 327.55967 -48.899826)
						(mid 327.523299 -48.841963)
						(end 327.465436 -48.805592)
					)
					(arc
						(start 327.465436 -48.700436)
						(mid 327.595287 -48.770053)
						(end 327.66508 -48.899826)
					)
				)
			)
		)
		(zone
			(layer "F.Cu")
			(hatch none 0.5)
			(connect_pads
				(clearance 0)
			)
			(min_thickness 0.25)
			(keepout
				(tracks not_allowed)
				(vias allowed)
				(pads allowed)
				(copperpour not_allowed)
				(footprints allowed)
			)
			(placement
				(enabled no)
				(sheetname "")
			)
			(fill
				(thermal_gap 0.5)
				(thermal_bridge_width 0.5)
				(island_removal_mode 0)
			)
			(polygon
				(pts
					(arc
						(start 327.55967 -47.89932)
						(mid 327.523299 -47.841457)
						(end 327.465436 -47.805086)
					)
					(arc
						(start 327.465436 -47.69993)
						(mid 327.595287 -47.769547)
						(end 327.66508 -47.89932)
					)
				)
			)
		)
		(zone
			(layer "F.Cu")
			(hatch none 0.5)
			(connect_pads
				(clearance 0)
			)
			(min_thickness 0.25)
			(keepout
				(tracks not_allowed)
				(vias allowed)
				(pads allowed)
				(copperpour not_allowed)
				(footprints allowed)
			)
			(placement
				(enabled no)
				(sheetname "")
			)
			(fill
				(thermal_gap 0.5)
				(thermal_bridge_width 0.5)
				(island_removal_mode 0)
			)
			(polygon
				(pts
					(arc
						(start 327.55967 -46.898814)
						(mid 327.523299 -46.840951)
						(end 327.465436 -46.80458)
					)
					(arc
						(start 327.465436 -46.699424)
						(mid 327.595287 -46.769041)
						(end 327.66508 -46.898814)
					)
				)
			)
		)
		(zone
			(layer "F.Cu")
			(hatch none 0.5)
			(connect_pads
				(clearance 0)
			)
			(min_thickness 0.25)
			(keepout
				(tracks not_allowed)
				(vias allowed)
				(pads allowed)
				(copperpour not_allowed)
				(footprints allowed)
			)
			(placement
				(enabled no)
				(sheetname "")
			)
			(fill
				(thermal_gap 0.5)
				(thermal_bridge_width 0.5)
				(island_removal_mode 0)
			)
			(polygon
				(pts
					(arc
						(start 327.55967 -45.898308)
						(mid 327.523299 -45.840445)
						(end 327.465436 -45.804074)
					)
					(arc
						(start 327.465436 -45.698918)
						(mid 327.595287 -45.768535)
						(end 327.66508 -45.898308)
					)
				)
			)
		)
		(zone
			(layer "F.Cu")
			(hatch none 0.5)
			(connect_pads
				(clearance 0)
			)
			(min_thickness 0.25)
			(keepout
				(tracks not_allowed)
				(vias allowed)
				(pads allowed)
				(copperpour not_allowed)
				(footprints allowed)
			)
			(placement
				(enabled no)
				(sheetname "")
			)
			(fill
				(thermal_gap 0.5)
				(thermal_bridge_width 0.5)
				(island_removal_mode 0)
			)
			(polygon
				(pts
					(arc
						(start 327.55967 -44.897802)
						(mid 327.523299 -44.839939)
						(end 327.465436 -44.803568)
					)
					(arc
						(start 327.465436 -44.698412)
						(mid 327.595287 -44.768029)
						(end 327.66508 -44.897802)
					)
				)
			)
		)
		(zone
			(layer "F.Cu")
			(hatch none 0.5)
			(connect_pads
				(clearance 0)
			)
			(min_thickness 0.25)
			(keepout
				(tracks not_allowed)
				(vias allowed)
				(pads allowed)
				(copperpour not_allowed)
				(footprints allowed)
			)
			(placement
				(enabled no)
				(sheetname "")
			)
			(fill
				(thermal_gap 0.5)
				(thermal_bridge_width 0.5)
				(island_removal_mode 0)
			)
			(polygon
				(pts
					(arc
						(start 327.55967 -43.897296)
						(mid 327.523299 -43.839433)
						(end 327.465436 -43.803062)
					)
					(arc
						(start 327.465436 -43.697906)
						(mid 327.595287 -43.767523)
						(end 327.66508 -43.897296)
					)
				)
			)
		)
		(zone
			(layer "F.Cu")
			(hatch none 0.5)
			(connect_pads
				(clearance 0)
			)
			(min_thickness 0.25)
			(keepout
				(tracks not_allowed)
				(vias allowed)
				(pads allowed)
				(copperpour not_allowed)
				(footprints allowed)
			)
			(placement
				(enabled no)
				(sheetname "")
			)
			(fill
				(thermal_gap 0.5)
				(thermal_bridge_width 0.5)
				(island_removal_mode 0)
			)
			(polygon
				(pts
					(arc
						(start 327.55967 -42.89679)
						(mid 327.523299 -42.838927)
						(end 327.465436 -42.802556)
					)
					(arc
						(start 327.465436 -42.6974)
						(mid 327.595287 -42.767017)
						(end 327.66508 -42.89679)
					)
				)
			)
		)
		(zone
			(layer "F.Cu")
			(hatch none 0.5)
			(connect_pads
				(clearance 0)
			)
			(min_thickness 0.25)
			(keepout
				(tracks not_allowed)
				(vias allowed)
				(pads allowed)
				(copperpour not_allowed)
				(footprints allowed)
			)
			(placement
				(enabled no)
				(sheetname "")
			)
			(fill
				(thermal_gap 0.5)
				(thermal_bridge_width 0.5)
				(island_removal_mode 0)
			)
			(polygon
				(pts
					(arc
						(start 327.55967 -41.896284)
						(mid 327.523299 -41.838421)
						(end 327.465436 -41.80205)
					)
					(arc
						(start 327.465436 -41.696894)
						(mid 327.595287 -41.766511)
						(end 327.66508 -41.896284)
					)
				)
			)
		)
		(zone
			(layer "F.Cu")
			(hatch none 0.5)
			(connect_pads
				(clearance 0)
			)
			(min_thickness 0.25)
			(keepout
				(tracks not_allowed)
				(vias allowed)
				(pads allowed)
				(copperpour not_allowed)
				(footprints allowed)
			)
			(placement
				(enabled no)
				(sheetname "")
			)
			(fill
				(thermal_gap 0.5)
				(thermal_bridge_width 0.5)
				(island_removal_mode 0)
			)
			(polygon
				(pts
					(arc
						(start 327.55967 -40.895778)
						(mid 327.523299 -40.837915)
						(end 327.465436 -40.801544)
					)
					(arc
						(start 327.465436 -40.696388)
						(mid 327.595287 -40.766005)
						(end 327.66508 -40.895778)
					)
				)
			)
		)
		(zone
			(layer "F.Cu")
			(hatch none 0.5)
			(connect_pads
				(clearance 0)
			)
			(min_thickness 0.25)
			(keepout
				(tracks not_allowed)
				(vias allowed)
				(pads allowed)
				(copperpour not_allowed)
				(footprints allowed)
			)
			(placement
				(enabled no)
				(sheetname "")
			)
			(fill
				(thermal_gap 0.5)
				(thermal_bridge_width 0.5)
				(island_removal_mode 0)
			)
			(polygon
				(pts
					(arc
						(start 327.55967 -39.895272)
						(mid 327.523299 -39.837409)
						(end 327.465436 -39.801038)
					)
					(arc
						(start 327.465436 -39.695882)
						(mid 327.595287 -39.765499)
						(end 327.66508 -39.895272)
					)
				)
			)
		)
		(zone
			(layer "F.Cu")
			(hatch none 0.5)
			(connect_pads
				(clearance 0)
			)
			(min_thickness 0.25)
			(keepout
				(tracks not_allowed)
				(vias allowed)
				(pads allowed)
				(copperpour not_allowed)
				(footprints allowed)
			)
			(placement
				(enabled no)
				(sheetname "")
			)
			(fill
				(thermal_gap 0.5)
				(thermal_bridge_width 0.5)
				(island_removal_mode 0)
			)
			(polygon
				(pts
					(arc
						(start 327.55967 -38.894766)
						(mid 327.523299 -38.836903)
						(end 327.465436 -38.800532)
					)
					(arc
						(start 327.465436 -38.695376)
						(mid 327.595287 -38.764993)
						(end 327.66508 -38.894766)
					)
				)
			)
		)
		(zone
			(layer "F.Cu")
			(hatch none 0.5)
			(connect_pads
				(clearance 0)
			)
			(min_thickness 0.25)
			(keepout
				(tracks not_allowed)
				(vias allowed)
				(pads allowed)
				(copperpour not_allowed)
				(footprints allowed)
			)
			(placement
				(enabled no)
				(sheetname "")
			)
			(fill
				(thermal_gap 0.5)
				(thermal_bridge_width 0.5)
				(island_removal_mode 0)
			)
			(polygon
				(pts
					(arc
						(start 327.684638 -57.505346)
						(mid 327.721009 -57.563209)
						(end 327.778872 -57.59958)
					)
					(arc
						(start 327.778872 -57.704736)
						(mid 327.649151 -57.635067)
						(end 327.579482 -57.505346)
					)
				)
			)
		)
		(zone
			(layer "F.Cu")
			(hatch none 0.5)
			(connect_pads
				(clearance 0)
			)
			(min_thickness 0.25)
			(keepout
				(tracks not_allowed)
				(vias allowed)
				(pads allowed)
				(copperpour not_allowed)
				(footprints allowed)
			)
			(placement
				(enabled no)
				(sheetname "")
			)
			(fill
				(thermal_gap 0.5)
				(thermal_bridge_width 0.5)
				(island_removal_mode 0)
			)
			(polygon
				(pts
					(arc
						(start 327.684638 -56.50484)
						(mid 327.721009 -56.562703)
						(end 327.778872 -56.599074)
					)
					(arc
						(start 327.778872 -56.70423)
						(mid 327.649151 -56.634561)
						(end 327.579482 -56.50484)
					)
				)
			)
		)
		(zone
			(layer "F.Cu")
			(hatch none 0.5)
			(connect_pads
				(clearance 0)
			)
			(min_thickness 0.25)
			(keepout
				(tracks not_allowed)
				(vias allowed)
				(pads allowed)
				(copperpour not_allowed)
				(footprints allowed)
			)
			(placement
				(enabled no)
				(sheetname "")
			)
			(fill
				(thermal_gap 0.5)
				(thermal_bridge_width 0.5)
				(island_removal_mode 0)
			)
			(polygon
				(pts
					(arc
						(start 327.684638 -55.504334)
						(mid 327.721009 -55.562197)
						(end 327.778872 -55.598568)
					)
					(arc
						(start 327.778872 -55.703724)
						(mid 327.649151 -55.634055)
						(end 327.579482 -55.504334)
					)
				)
			)
		)
		(zone
			(layer "F.Cu")
			(hatch none 0.5)
			(connect_pads
				(clearance 0)
			)
			(min_thickness 0.25)
			(keepout
				(tracks not_allowed)
				(vias allowed)
				(pads allowed)
				(copperpour not_allowed)
				(footprints allowed)
			)
			(placement
				(enabled no)
				(sheetname "")
			)
			(fill
				(thermal_gap 0.5)
				(thermal_bridge_width 0.5)
				(island_removal_mode 0)
			)
			(polygon
				(pts
					(arc
						(start 327.684638 -54.503828)
						(mid 327.721009 -54.561691)
						(end 327.778872 -54.598062)
					)
					(arc
						(start 327.778872 -54.703472)
						(mid 327.649063 -54.633715)
						(end 327.579482 -54.503828)
					)
				)
			)
		)
		(zone
			(layer "F.Cu")
			(hatch none 0.5)
			(connect_pads
				(clearance 0)
			)
			(min_thickness 0.25)
			(keepout
				(tracks not_allowed)
				(vias allowed)
				(pads allowed)
				(copperpour not_allowed)
				(footprints allowed)
			)
			(placement
				(enabled no)
				(sheetname "")
			)
			(fill
				(thermal_gap 0.5)
				(thermal_bridge_width 0.5)
				(island_removal_mode 0)
			)
			(polygon
				(pts
					(arc
						(start 327.684638 -53.503322)
						(mid 327.721009 -53.561185)
						(end 327.778872 -53.597556)
					)
					(arc
						(start 327.778872 -53.702966)
						(mid 327.649063 -53.633209)
						(end 327.579482 -53.503322)
					)
				)
			)
		)
		(zone
			(layer "F.Cu")
			(hatch none 0.5)
			(connect_pads
				(clearance 0)
			)
			(min_thickness 0.25)
			(keepout
				(tracks not_allowed)
				(vias allowed)
				(pads allowed)
				(copperpour not_allowed)
				(footprints allowed)
			)
			(placement
				(enabled no)
				(sheetname "")
			)
			(fill
				(thermal_gap 0.5)
				(thermal_bridge_width 0.5)
				(island_removal_mode 0)
			)
			(polygon
				(pts
					(arc
						(start 327.684638 -52.50307)
						(mid 327.721034 -52.560824)
						(end 327.778872 -52.59705)
					)
					(arc
						(start 327.778872 -52.70246)
						(mid 327.649151 -52.632791)
						(end 327.579482 -52.50307)
					)
				)
			)
		)
		(zone
			(layer "F.Cu")
			(hatch none 0.5)
			(connect_pads
				(clearance 0)
			)
			(min_thickness 0.25)
			(keepout
				(tracks not_allowed)
				(vias allowed)
				(pads allowed)
				(copperpour not_allowed)
				(footprints allowed)
			)
			(placement
				(enabled no)
				(sheetname "")
			)
			(fill
				(thermal_gap 0.5)
				(thermal_bridge_width 0.5)
				(island_removal_mode 0)
			)
			(polygon
				(pts
					(arc
						(start 327.684638 -51.502564)
						(mid 327.721009 -51.560427)
						(end 327.778872 -51.596798)
					)
					(arc
						(start 327.778872 -51.701954)
						(mid 327.649151 -51.632285)
						(end 327.579482 -51.502564)
					)
				)
			)
		)
		(zone
			(layer "F.Cu")
			(hatch none 0.5)
			(connect_pads
				(clearance 0)
			)
			(min_thickness 0.25)
			(keepout
				(tracks not_allowed)
				(vias allowed)
				(pads allowed)
				(copperpour not_allowed)
				(footprints allowed)
			)
			(placement
				(enabled no)
				(sheetname "")
			)
			(fill
				(thermal_gap 0.5)
				(thermal_bridge_width 0.5)
				(island_removal_mode 0)
			)
			(polygon
				(pts
					(arc
						(start 327.684638 -50.502058)
						(mid 327.721009 -50.559921)
						(end 327.778872 -50.596292)
					)
					(arc
						(start 327.778872 -50.701448)
						(mid 327.649151 -50.631779)
						(end 327.579482 -50.502058)
					)
				)
			)
		)
		(zone
			(layer "F.Cu")
			(hatch none 0.5)
			(connect_pads
				(clearance 0)
			)
			(min_thickness 0.25)
			(keepout
				(tracks not_allowed)
				(vias allowed)
				(pads allowed)
				(copperpour not_allowed)
				(footprints allowed)
			)
			(placement
				(enabled no)
				(sheetname "")
			)
			(fill
				(thermal_gap 0.5)
				(thermal_bridge_width 0.5)
				(island_removal_mode 0)
			)
			(polygon
				(pts
					(arc
						(start 327.684638 -49.501552)
						(mid 327.721009 -49.559415)
						(end 327.778872 -49.595786)
					)
					(arc
						(start 327.778872 -49.700942)
						(mid 327.649151 -49.631273)
						(end 327.579482 -49.501552)
					)
				)
			)
		)
		(zone
			(layer "F.Cu")
			(hatch none 0.5)
			(connect_pads
				(clearance 0)
			)
			(min_thickness 0.25)
			(keepout
				(tracks not_allowed)
				(vias allowed)
				(pads allowed)
				(copperpour not_allowed)
				(footprints allowed)
			)
			(placement
				(enabled no)
				(sheetname "")
			)
			(fill
				(thermal_gap 0.5)
				(thermal_bridge_width 0.5)
				(island_removal_mode 0)
			)
			(polygon
				(pts
					(arc
						(start 327.684638 -48.501046)
						(mid 327.721009 -48.558909)
						(end 327.778872 -48.59528)
					)
					(arc
						(start 327.778872 -48.700436)
						(mid 327.649151 -48.630767)
						(end 327.579482 -48.501046)
					)
				)
			)
		)
		(zone
			(layer "F.Cu")
			(hatch none 0.5)
			(connect_pads
				(clearance 0)
			)
			(min_thickness 0.25)
			(keepout
				(tracks not_allowed)
				(vias allowed)
				(pads allowed)
				(copperpour not_allowed)
				(footprints allowed)
			)
			(placement
				(enabled no)
				(sheetname "")
			)
			(fill
				(thermal_gap 0.5)
				(thermal_bridge_width 0.5)
				(island_removal_mode 0)
			)
			(polygon
				(pts
					(arc
						(start 327.684638 -47.50054)
						(mid 327.721009 -47.558403)
						(end 327.778872 -47.594774)
					)
					(arc
						(start 327.778872 -47.69993)
						(mid 327.649151 -47.630261)
						(end 327.579482 -47.50054)
					)
				)
			)
		)
		(zone
			(layer "F.Cu")
			(hatch none 0.5)
			(connect_pads
				(clearance 0)
			)
			(min_thickness 0.25)
			(keepout
				(tracks not_allowed)
				(vias allowed)
				(pads allowed)
				(copperpour not_allowed)
				(footprints allowed)
			)
			(placement
				(enabled no)
				(sheetname "")
			)
			(fill
				(thermal_gap 0.5)
				(thermal_bridge_width 0.5)
				(island_removal_mode 0)
			)
			(polygon
				(pts
					(arc
						(start 327.684638 -46.500034)
						(mid 327.721009 -46.557897)
						(end 327.778872 -46.594268)
					)
					(arc
						(start 327.778872 -46.699424)
						(mid 327.649151 -46.629755)
						(end 327.579482 -46.500034)
					)
				)
			)
		)
		(zone
			(layer "F.Cu")
			(hatch none 0.5)
			(connect_pads
				(clearance 0)
			)
			(min_thickness 0.25)
			(keepout
				(tracks not_allowed)
				(vias allowed)
				(pads allowed)
				(copperpour not_allowed)
				(footprints allowed)
			)
			(placement
				(enabled no)
				(sheetname "")
			)
			(fill
				(thermal_gap 0.5)
				(thermal_bridge_width 0.5)
				(island_removal_mode 0)
			)
			(polygon
				(pts
					(arc
						(start 327.684638 -45.499528)
						(mid 327.721009 -45.557391)
						(end 327.778872 -45.593762)
					)
					(arc
						(start 327.778872 -45.698918)
						(mid 327.649151 -45.629249)
						(end 327.579482 -45.499528)
					)
				)
			)
		)
		(zone
			(layer "F.Cu")
			(hatch none 0.5)
			(connect_pads
				(clearance 0)
			)
			(min_thickness 0.25)
			(keepout
				(tracks not_allowed)
				(vias allowed)
				(pads allowed)
				(copperpour not_allowed)
				(footprints allowed)
			)
			(placement
				(enabled no)
				(sheetname "")
			)
			(fill
				(thermal_gap 0.5)
				(thermal_bridge_width 0.5)
				(island_removal_mode 0)
			)
			(polygon
				(pts
					(arc
						(start 327.684638 -44.499022)
						(mid 327.721009 -44.556885)
						(end 327.778872 -44.593256)
					)
					(arc
						(start 327.778872 -44.698412)
						(mid 327.649151 -44.628743)
						(end 327.579482 -44.499022)
					)
				)
			)
		)
		(zone
			(layer "F.Cu")
			(hatch none 0.5)
			(connect_pads
				(clearance 0)
			)
			(min_thickness 0.25)
			(keepout
				(tracks not_allowed)
				(vias allowed)
				(pads allowed)
				(copperpour not_allowed)
				(footprints allowed)
			)
			(placement
				(enabled no)
				(sheetname "")
			)
			(fill
				(thermal_gap 0.5)
				(thermal_bridge_width 0.5)
				(island_removal_mode 0)
			)
			(polygon
				(pts
					(arc
						(start 327.684638 -43.498516)
						(mid 327.721009 -43.556379)
						(end 327.778872 -43.59275)
					)
					(arc
						(start 327.778872 -43.697906)
						(mid 327.649151 -43.628237)
						(end 327.579482 -43.498516)
					)
				)
			)
		)
		(zone
			(layer "F.Cu")
			(hatch none 0.5)
			(connect_pads
				(clearance 0)
			)
			(min_thickness 0.25)
			(keepout
				(tracks not_allowed)
				(vias allowed)
				(pads allowed)
				(copperpour not_allowed)
				(footprints allowed)
			)
			(placement
				(enabled no)
				(sheetname "")
			)
			(fill
				(thermal_gap 0.5)
				(thermal_bridge_width 0.5)
				(island_removal_mode 0)
			)
			(polygon
				(pts
					(arc
						(start 327.684638 -42.498264)
						(mid 327.721034 -42.556018)
						(end 327.778872 -42.592244)
					)
					(arc
						(start 327.778872 -42.697654)
						(mid 327.649151 -42.627985)
						(end 327.579482 -42.498264)
					)
				)
			)
		)
		(zone
			(layer "F.Cu")
			(hatch none 0.5)
			(connect_pads
				(clearance 0)
			)
			(min_thickness 0.25)
			(keepout
				(tracks not_allowed)
				(vias allowed)
				(pads allowed)
				(copperpour not_allowed)
				(footprints allowed)
			)
			(placement
				(enabled no)
				(sheetname "")
			)
			(fill
				(thermal_gap 0.5)
				(thermal_bridge_width 0.5)
				(island_removal_mode 0)
			)
			(polygon
				(pts
					(arc
						(start 327.684638 -41.497758)
						(mid 327.721034 -41.555512)
						(end 327.778872 -41.591738)
					)
					(arc
						(start 327.778872 -41.697148)
						(mid 327.649151 -41.627479)
						(end 327.579482 -41.497758)
					)
				)
			)
		)
		(zone
			(layer "F.Cu")
			(hatch none 0.5)
			(connect_pads
				(clearance 0)
			)
			(min_thickness 0.25)
			(keepout
				(tracks not_allowed)
				(vias allowed)
				(pads allowed)
				(copperpour not_allowed)
				(footprints allowed)
			)
			(placement
				(enabled no)
				(sheetname "")
			)
			(fill
				(thermal_gap 0.5)
				(thermal_bridge_width 0.5)
				(island_removal_mode 0)
			)
			(polygon
				(pts
					(arc
						(start 327.684638 -40.497252)
						(mid 327.721034 -40.555006)
						(end 327.778872 -40.591232)
					)
					(arc
						(start 327.778872 -40.696642)
						(mid 327.649151 -40.626973)
						(end 327.579482 -40.497252)
					)
				)
			)
		)
		(zone
			(layer "F.Cu")
			(hatch none 0.5)
			(connect_pads
				(clearance 0)
			)
			(min_thickness 0.25)
			(keepout
				(tracks not_allowed)
				(vias allowed)
				(pads allowed)
				(copperpour not_allowed)
				(footprints allowed)
			)
			(placement
				(enabled no)
				(sheetname "")
			)
			(fill
				(thermal_gap 0.5)
				(thermal_bridge_width 0.5)
				(island_removal_mode 0)
			)
			(polygon
				(pts
					(arc
						(start 327.684638 -39.496746)
						(mid 327.721034 -39.5545)
						(end 327.778872 -39.590726)
					)
					(arc
						(start 327.778872 -39.696136)
						(mid 327.649151 -39.626467)
						(end 327.579482 -39.496746)
					)
				)
			)
		)
		(zone
			(layer "F.Cu")
			(hatch none 0.5)
			(connect_pads
				(clearance 0)
			)
			(min_thickness 0.25)
			(keepout
				(tracks not_allowed)
				(vias allowed)
				(pads allowed)
				(copperpour not_allowed)
				(footprints allowed)
			)
			(placement
				(enabled no)
				(sheetname "")
			)
			(fill
				(thermal_gap 0.5)
				(thermal_bridge_width 0.5)
				(island_removal_mode 0)
			)
			(polygon
				(pts
					(arc
						(start 327.75017 -58.48604)
						(mid 327.786566 -58.543794)
						(end 327.844404 -58.58002)
					)
					(arc
						(start 327.844404 -58.68543)
						(mid 327.714683 -58.615761)
						(end 327.645014 -58.48604)
					)
				)
			)
		)
		(zone
			(layer "F.Cu")
			(hatch none 0.5)
			(connect_pads
				(clearance 0)
			)
			(min_thickness 0.25)
			(keepout
				(tracks not_allowed)
				(vias allowed)
				(pads allowed)
				(copperpour not_allowed)
				(footprints allowed)
			)
			(placement
				(enabled no)
				(sheetname "")
			)
			(fill
				(thermal_gap 0.5)
				(thermal_bridge_width 0.5)
				(island_removal_mode 0)
			)
			(polygon
				(pts
					(arc
						(start 327.75017 -38.516052)
						(mid 327.786541 -38.573915)
						(end 327.844404 -38.610286)
					)
					(arc
						(start 327.844404 -38.715442)
						(mid 327.714683 -38.645773)
						(end 327.645014 -38.516052)
					)
				)
			)
		)
		(zone
			(layer "F.Cu")
			(hatch none 0.5)
			(connect_pads
				(clearance 0)
			)
			(min_thickness 0.25)
			(keepout
				(tracks not_allowed)
				(vias allowed)
				(pads allowed)
				(copperpour not_allowed)
				(footprints allowed)
			)
			(placement
				(enabled no)
				(sheetname "")
			)
			(fill
				(thermal_gap 0.5)
				(thermal_bridge_width 0.5)
				(island_removal_mode 0)
			)
			(polygon
				(pts
					(arc
						(start 327.778872 -57.309766)
						(mid 327.721093 -57.346052)
						(end 327.684638 -57.403746)
					)
					(arc
						(start 327.579482 -57.403746)
						(mid 327.649151 -57.274025)
						(end 327.778872 -57.204356)
					)
				)
			)
		)
		(zone
			(layer "F.Cu")
			(hatch none 0.5)
			(connect_pads
				(clearance 0)
			)
			(min_thickness 0.25)
			(keepout
				(tracks not_allowed)
				(vias allowed)
				(pads allowed)
				(copperpour not_allowed)
				(footprints allowed)
			)
			(placement
				(enabled no)
				(sheetname "")
			)
			(fill
				(thermal_gap 0.5)
				(thermal_bridge_width 0.5)
				(island_removal_mode 0)
			)
			(polygon
				(pts
					(arc
						(start 327.778872 -56.30926)
						(mid 327.721093 -56.345546)
						(end 327.684638 -56.40324)
					)
					(arc
						(start 327.579482 -56.40324)
						(mid 327.649151 -56.273519)
						(end 327.778872 -56.20385)
					)
				)
			)
		)
		(zone
			(layer "F.Cu")
			(hatch none 0.5)
			(connect_pads
				(clearance 0)
			)
			(min_thickness 0.25)
			(keepout
				(tracks not_allowed)
				(vias allowed)
				(pads allowed)
				(copperpour not_allowed)
				(footprints allowed)
			)
			(placement
				(enabled no)
				(sheetname "")
			)
			(fill
				(thermal_gap 0.5)
				(thermal_bridge_width 0.5)
				(island_removal_mode 0)
			)
			(polygon
				(pts
					(arc
						(start 327.778872 -55.308754)
						(mid 327.721093 -55.34504)
						(end 327.684638 -55.402734)
					)
					(arc
						(start 327.579482 -55.402734)
						(mid 327.649151 -55.273013)
						(end 327.778872 -55.203344)
					)
				)
			)
		)
		(zone
			(layer "F.Cu")
			(hatch none 0.5)
			(connect_pads
				(clearance 0)
			)
			(min_thickness 0.25)
			(keepout
				(tracks not_allowed)
				(vias allowed)
				(pads allowed)
				(copperpour not_allowed)
				(footprints allowed)
			)
			(placement
				(enabled no)
				(sheetname "")
			)
			(fill
				(thermal_gap 0.5)
				(thermal_bridge_width 0.5)
				(island_removal_mode 0)
			)
			(polygon
				(pts
					(arc
						(start 327.778872 -54.308248)
						(mid 327.721093 -54.344534)
						(end 327.684638 -54.402228)
					)
					(arc
						(start 327.579482 -54.402228)
						(mid 327.649151 -54.272507)
						(end 327.778872 -54.202838)
					)
				)
			)
		)
		(zone
			(layer "F.Cu")
			(hatch none 0.5)
			(connect_pads
				(clearance 0)
			)
			(min_thickness 0.25)
			(keepout
				(tracks not_allowed)
				(vias allowed)
				(pads allowed)
				(copperpour not_allowed)
				(footprints allowed)
			)
			(placement
				(enabled no)
				(sheetname "")
			)
			(fill
				(thermal_gap 0.5)
				(thermal_bridge_width 0.5)
				(island_removal_mode 0)
			)
			(polygon
				(pts
					(arc
						(start 327.778872 -53.307742)
						(mid 327.721093 -53.344028)
						(end 327.684638 -53.401722)
					)
					(arc
						(start 327.579482 -53.401722)
						(mid 327.649151 -53.272001)
						(end 327.778872 -53.202332)
					)
				)
			)
		)
		(zone
			(layer "F.Cu")
			(hatch none 0.5)
			(connect_pads
				(clearance 0)
			)
			(min_thickness 0.25)
			(keepout
				(tracks not_allowed)
				(vias allowed)
				(pads allowed)
				(copperpour not_allowed)
				(footprints allowed)
			)
			(placement
				(enabled no)
				(sheetname "")
			)
			(fill
				(thermal_gap 0.5)
				(thermal_bridge_width 0.5)
				(island_removal_mode 0)
			)
			(polygon
				(pts
					(arc
						(start 327.778872 -52.307236)
						(mid 327.721009 -52.343607)
						(end 327.684638 -52.40147)
					)
					(arc
						(start 327.579482 -52.40147)
						(mid 327.649099 -52.271619)
						(end 327.778872 -52.201826)
					)
				)
			)
		)
		(zone
			(layer "F.Cu")
			(hatch none 0.5)
			(connect_pads
				(clearance 0)
			)
			(min_thickness 0.25)
			(keepout
				(tracks not_allowed)
				(vias allowed)
				(pads allowed)
				(copperpour not_allowed)
				(footprints allowed)
			)
			(placement
				(enabled no)
				(sheetname "")
			)
			(fill
				(thermal_gap 0.5)
				(thermal_bridge_width 0.5)
				(island_removal_mode 0)
			)
			(polygon
				(pts
					(arc
						(start 327.778872 -51.30673)
						(mid 327.721009 -51.343101)
						(end 327.684638 -51.400964)
					)
					(arc
						(start 327.579482 -51.400964)
						(mid 327.649151 -51.271243)
						(end 327.778872 -51.201574)
					)
				)
			)
		)
		(zone
			(layer "F.Cu")
			(hatch none 0.5)
			(connect_pads
				(clearance 0)
			)
			(min_thickness 0.25)
			(keepout
				(tracks not_allowed)
				(vias allowed)
				(pads allowed)
				(copperpour not_allowed)
				(footprints allowed)
			)
			(placement
				(enabled no)
				(sheetname "")
			)
			(fill
				(thermal_gap 0.5)
				(thermal_bridge_width 0.5)
				(island_removal_mode 0)
			)
			(polygon
				(pts
					(arc
						(start 327.778872 -50.306224)
						(mid 327.721009 -50.342595)
						(end 327.684638 -50.400458)
					)
					(arc
						(start 327.579482 -50.400458)
						(mid 327.649151 -50.270737)
						(end 327.778872 -50.201068)
					)
				)
			)
		)
		(zone
			(layer "F.Cu")
			(hatch none 0.5)
			(connect_pads
				(clearance 0)
			)
			(min_thickness 0.25)
			(keepout
				(tracks not_allowed)
				(vias allowed)
				(pads allowed)
				(copperpour not_allowed)
				(footprints allowed)
			)
			(placement
				(enabled no)
				(sheetname "")
			)
			(fill
				(thermal_gap 0.5)
				(thermal_bridge_width 0.5)
				(island_removal_mode 0)
			)
			(polygon
				(pts
					(arc
						(start 327.778872 -49.305718)
						(mid 327.721009 -49.342089)
						(end 327.684638 -49.399952)
					)
					(arc
						(start 327.579482 -49.399952)
						(mid 327.649151 -49.270231)
						(end 327.778872 -49.200562)
					)
				)
			)
		)
		(zone
			(layer "F.Cu")
			(hatch none 0.5)
			(connect_pads
				(clearance 0)
			)
			(min_thickness 0.25)
			(keepout
				(tracks not_allowed)
				(vias allowed)
				(pads allowed)
				(copperpour not_allowed)
				(footprints allowed)
			)
			(placement
				(enabled no)
				(sheetname "")
			)
			(fill
				(thermal_gap 0.5)
				(thermal_bridge_width 0.5)
				(island_removal_mode 0)
			)
			(polygon
				(pts
					(arc
						(start 327.778872 -48.305212)
						(mid 327.721009 -48.341583)
						(end 327.684638 -48.399446)
					)
					(arc
						(start 327.579482 -48.399446)
						(mid 327.649151 -48.269725)
						(end 327.778872 -48.200056)
					)
				)
			)
		)
		(zone
			(layer "F.Cu")
			(hatch none 0.5)
			(connect_pads
				(clearance 0)
			)
			(min_thickness 0.25)
			(keepout
				(tracks not_allowed)
				(vias allowed)
				(pads allowed)
				(copperpour not_allowed)
				(footprints allowed)
			)
			(placement
				(enabled no)
				(sheetname "")
			)
			(fill
				(thermal_gap 0.5)
				(thermal_bridge_width 0.5)
				(island_removal_mode 0)
			)
			(polygon
				(pts
					(arc
						(start 327.778872 -47.304706)
						(mid 327.721009 -47.341077)
						(end 327.684638 -47.39894)
					)
					(arc
						(start 327.579482 -47.39894)
						(mid 327.649151 -47.269219)
						(end 327.778872 -47.19955)
					)
				)
			)
		)
		(zone
			(layer "F.Cu")
			(hatch none 0.5)
			(connect_pads
				(clearance 0)
			)
			(min_thickness 0.25)
			(keepout
				(tracks not_allowed)
				(vias allowed)
				(pads allowed)
				(copperpour not_allowed)
				(footprints allowed)
			)
			(placement
				(enabled no)
				(sheetname "")
			)
			(fill
				(thermal_gap 0.5)
				(thermal_bridge_width 0.5)
				(island_removal_mode 0)
			)
			(polygon
				(pts
					(arc
						(start 327.778872 -46.3042)
						(mid 327.721009 -46.340571)
						(end 327.684638 -46.398434)
					)
					(arc
						(start 327.579482 -46.398434)
						(mid 327.649151 -46.268713)
						(end 327.778872 -46.199044)
					)
				)
			)
		)
		(zone
			(layer "F.Cu")
			(hatch none 0.5)
			(connect_pads
				(clearance 0)
			)
			(min_thickness 0.25)
			(keepout
				(tracks not_allowed)
				(vias allowed)
				(pads allowed)
				(copperpour not_allowed)
				(footprints allowed)
			)
			(placement
				(enabled no)
				(sheetname "")
			)
			(fill
				(thermal_gap 0.5)
				(thermal_bridge_width 0.5)
				(island_removal_mode 0)
			)
			(polygon
				(pts
					(arc
						(start 327.778872 -45.303694)
						(mid 327.721009 -45.340065)
						(end 327.684638 -45.397928)
					)
					(arc
						(start 327.579482 -45.397928)
						(mid 327.649151 -45.268207)
						(end 327.778872 -45.198538)
					)
				)
			)
		)
		(zone
			(layer "F.Cu")
			(hatch none 0.5)
			(connect_pads
				(clearance 0)
			)
			(min_thickness 0.25)
			(keepout
				(tracks not_allowed)
				(vias allowed)
				(pads allowed)
				(copperpour not_allowed)
				(footprints allowed)
			)
			(placement
				(enabled no)
				(sheetname "")
			)
			(fill
				(thermal_gap 0.5)
				(thermal_bridge_width 0.5)
				(island_removal_mode 0)
			)
			(polygon
				(pts
					(arc
						(start 327.778872 -44.303188)
						(mid 327.721009 -44.339559)
						(end 327.684638 -44.397422)
					)
					(arc
						(start 327.579482 -44.397422)
						(mid 327.649151 -44.267701)
						(end 327.778872 -44.198032)
					)
				)
			)
		)
		(zone
			(layer "F.Cu")
			(hatch none 0.5)
			(connect_pads
				(clearance 0)
			)
			(min_thickness 0.25)
			(keepout
				(tracks not_allowed)
				(vias allowed)
				(pads allowed)
				(copperpour not_allowed)
				(footprints allowed)
			)
			(placement
				(enabled no)
				(sheetname "")
			)
			(fill
				(thermal_gap 0.5)
				(thermal_bridge_width 0.5)
				(island_removal_mode 0)
			)
			(polygon
				(pts
					(arc
						(start 327.778872 -43.302682)
						(mid 327.721009 -43.339053)
						(end 327.684638 -43.396916)
					)
					(arc
						(start 327.579482 -43.396916)
						(mid 327.649151 -43.267195)
						(end 327.778872 -43.197526)
					)
				)
			)
		)
		(zone
			(layer "F.Cu")
			(hatch none 0.5)
			(connect_pads
				(clearance 0)
			)
			(min_thickness 0.25)
			(keepout
				(tracks not_allowed)
				(vias allowed)
				(pads allowed)
				(copperpour not_allowed)
				(footprints allowed)
			)
			(placement
				(enabled no)
				(sheetname "")
			)
			(fill
				(thermal_gap 0.5)
				(thermal_bridge_width 0.5)
				(island_removal_mode 0)
			)
			(polygon
				(pts
					(arc
						(start 327.778872 -42.30243)
						(mid 327.721009 -42.338801)
						(end 327.684638 -42.396664)
					)
					(arc
						(start 327.579482 -42.396664)
						(mid 327.649099 -42.266813)
						(end 327.778872 -42.19702)
					)
				)
			)
		)
		(zone
			(layer "F.Cu")
			(hatch none 0.5)
			(connect_pads
				(clearance 0)
			)
			(min_thickness 0.25)
			(keepout
				(tracks not_allowed)
				(vias allowed)
				(pads allowed)
				(copperpour not_allowed)
				(footprints allowed)
			)
			(placement
				(enabled no)
				(sheetname "")
			)
			(fill
				(thermal_gap 0.5)
				(thermal_bridge_width 0.5)
				(island_removal_mode 0)
			)
			(polygon
				(pts
					(arc
						(start 327.778872 -41.301924)
						(mid 327.721009 -41.338295)
						(end 327.684638 -41.396158)
					)
					(arc
						(start 327.579482 -41.396158)
						(mid 327.649151 -41.266437)
						(end 327.778872 -41.196768)
					)
				)
			)
		)
		(zone
			(layer "F.Cu")
			(hatch none 0.5)
			(connect_pads
				(clearance 0)
			)
			(min_thickness 0.25)
			(keepout
				(tracks not_allowed)
				(vias allowed)
				(pads allowed)
				(copperpour not_allowed)
				(footprints allowed)
			)
			(placement
				(enabled no)
				(sheetname "")
			)
			(fill
				(thermal_gap 0.5)
				(thermal_bridge_width 0.5)
				(island_removal_mode 0)
			)
			(polygon
				(pts
					(arc
						(start 327.778872 -40.301418)
						(mid 327.721009 -40.337789)
						(end 327.684638 -40.395652)
					)
					(arc
						(start 327.579482 -40.395652)
						(mid 327.649151 -40.265931)
						(end 327.778872 -40.196262)
					)
				)
			)
		)
		(zone
			(layer "F.Cu")
			(hatch none 0.5)
			(connect_pads
				(clearance 0)
			)
			(min_thickness 0.25)
			(keepout
				(tracks not_allowed)
				(vias allowed)
				(pads allowed)
				(copperpour not_allowed)
				(footprints allowed)
			)
			(placement
				(enabled no)
				(sheetname "")
			)
			(fill
				(thermal_gap 0.5)
				(thermal_bridge_width 0.5)
				(island_removal_mode 0)
			)
			(polygon
				(pts
					(arc
						(start 327.778872 -39.300912)
						(mid 327.721009 -39.337283)
						(end 327.684638 -39.395146)
					)
					(arc
						(start 327.579482 -39.395146)
						(mid 327.649151 -39.265425)
						(end 327.778872 -39.195756)
					)
				)
			)
		)
		(zone
			(layer "F.Cu")
			(hatch none 0.5)
			(connect_pads
				(clearance 0)
			)
			(min_thickness 0.25)
			(keepout
				(tracks not_allowed)
				(vias allowed)
				(pads allowed)
				(copperpour not_allowed)
				(footprints allowed)
			)
			(placement
				(enabled no)
				(sheetname "")
			)
			(fill
				(thermal_gap 0.5)
				(thermal_bridge_width 0.5)
				(island_removal_mode 0)
			)
			(polygon
				(pts
					(arc
						(start 327.844404 -58.290206)
						(mid 327.786541 -58.326577)
						(end 327.75017 -58.38444)
					)
					(arc
						(start 327.645014 -58.38444)
						(mid 327.714683 -58.254719)
						(end 327.844404 -58.18505)
					)
				)
			)
		)
		(zone
			(layer "F.Cu")
			(hatch none 0.5)
			(connect_pads
				(clearance 0)
			)
			(min_thickness 0.25)
			(keepout
				(tracks not_allowed)
				(vias allowed)
				(pads allowed)
				(copperpour not_allowed)
				(footprints allowed)
			)
			(placement
				(enabled no)
				(sheetname "")
			)
			(fill
				(thermal_gap 0.5)
				(thermal_bridge_width 0.5)
				(island_removal_mode 0)
			)
			(polygon
				(pts
					(arc
						(start 327.844404 -38.320472)
						(mid 327.786625 -38.356758)
						(end 327.75017 -38.414452)
					)
					(arc
						(start 327.645014 -38.414452)
						(mid 327.714683 -38.284731)
						(end 327.844404 -38.215062)
					)
				)
			)
		)
		(zone
			(layer "F.Cu")
			(hatch none 0.5)
			(connect_pads
				(clearance 0)
			)
			(min_thickness 0.25)
			(keepout
				(tracks not_allowed)
				(vias allowed)
				(pads allowed)
				(copperpour not_allowed)
				(footprints allowed)
			)
			(placement
				(enabled no)
				(sheetname "")
			)
			(fill
				(thermal_gap 0.5)
				(thermal_bridge_width 0.5)
				(island_removal_mode 0)
			)
			(polygon
				(pts
					(arc
						(start 327.880472 -57.59958)
						(mid 327.938335 -57.563209)
						(end 327.974706 -57.505346)
					)
					(arc
						(start 328.079862 -57.505346)
						(mid 328.010193 -57.635067)
						(end 327.880472 -57.704736)
					)
				)
			)
		)
		(zone
			(layer "F.Cu")
			(hatch none 0.5)
			(connect_pads
				(clearance 0)
			)
			(min_thickness 0.25)
			(keepout
				(tracks not_allowed)
				(vias allowed)
				(pads allowed)
				(copperpour not_allowed)
				(footprints allowed)
			)
			(placement
				(enabled no)
				(sheetname "")
			)
			(fill
				(thermal_gap 0.5)
				(thermal_bridge_width 0.5)
				(island_removal_mode 0)
			)
			(polygon
				(pts
					(arc
						(start 327.880472 -56.599074)
						(mid 327.938335 -56.562703)
						(end 327.974706 -56.50484)
					)
					(arc
						(start 328.079862 -56.50484)
						(mid 328.010193 -56.634561)
						(end 327.880472 -56.70423)
					)
				)
			)
		)
		(zone
			(layer "F.Cu")
			(hatch none 0.5)
			(connect_pads
				(clearance 0)
			)
			(min_thickness 0.25)
			(keepout
				(tracks not_allowed)
				(vias allowed)
				(pads allowed)
				(copperpour not_allowed)
				(footprints allowed)
			)
			(placement
				(enabled no)
				(sheetname "")
			)
			(fill
				(thermal_gap 0.5)
				(thermal_bridge_width 0.5)
				(island_removal_mode 0)
			)
			(polygon
				(pts
					(arc
						(start 327.880472 -55.598568)
						(mid 327.938335 -55.562197)
						(end 327.974706 -55.504334)
					)
					(arc
						(start 328.079862 -55.504334)
						(mid 328.010193 -55.634055)
						(end 327.880472 -55.703724)
					)
				)
			)
		)
		(zone
			(layer "F.Cu")
			(hatch none 0.5)
			(connect_pads
				(clearance 0)
			)
			(min_thickness 0.25)
			(keepout
				(tracks not_allowed)
				(vias allowed)
				(pads allowed)
				(copperpour not_allowed)
				(footprints allowed)
			)
			(placement
				(enabled no)
				(sheetname "")
			)
			(fill
				(thermal_gap 0.5)
				(thermal_bridge_width 0.5)
				(island_removal_mode 0)
			)
			(polygon
				(pts
					(arc
						(start 327.880472 -54.598062)
						(mid 327.938335 -54.561691)
						(end 327.974706 -54.503828)
					)
					(arc
						(start 328.079862 -54.503828)
						(mid 328.010245 -54.633679)
						(end 327.880472 -54.703472)
					)
				)
			)
		)
		(zone
			(layer "F.Cu")
			(hatch none 0.5)
			(connect_pads
				(clearance 0)
			)
			(min_thickness 0.25)
			(keepout
				(tracks not_allowed)
				(vias allowed)
				(pads allowed)
				(copperpour not_allowed)
				(footprints allowed)
			)
			(placement
				(enabled no)
				(sheetname "")
			)
			(fill
				(thermal_gap 0.5)
				(thermal_bridge_width 0.5)
				(island_removal_mode 0)
			)
			(polygon
				(pts
					(arc
						(start 327.880472 -53.597556)
						(mid 327.938335 -53.561185)
						(end 327.974706 -53.503322)
					)
					(arc
						(start 328.079862 -53.503322)
						(mid 328.010245 -53.633173)
						(end 327.880472 -53.702966)
					)
				)
			)
		)
		(zone
			(layer "F.Cu")
			(hatch none 0.5)
			(connect_pads
				(clearance 0)
			)
			(min_thickness 0.25)
			(keepout
				(tracks not_allowed)
				(vias allowed)
				(pads allowed)
				(copperpour not_allowed)
				(footprints allowed)
			)
			(placement
				(enabled no)
				(sheetname "")
			)
			(fill
				(thermal_gap 0.5)
				(thermal_bridge_width 0.5)
				(island_removal_mode 0)
			)
			(polygon
				(pts
					(arc
						(start 327.880472 -52.59705)
						(mid 327.938331 -52.560819)
						(end 327.974706 -52.50307)
					)
					(arc
						(start 328.079862 -52.50307)
						(mid 328.010193 -52.632791)
						(end 327.880472 -52.70246)
					)
				)
			)
		)
		(zone
			(layer "F.Cu")
			(hatch none 0.5)
			(connect_pads
				(clearance 0)
			)
			(min_thickness 0.25)
			(keepout
				(tracks not_allowed)
				(vias allowed)
				(pads allowed)
				(copperpour not_allowed)
				(footprints allowed)
			)
			(placement
				(enabled no)
				(sheetname "")
			)
			(fill
				(thermal_gap 0.5)
				(thermal_bridge_width 0.5)
				(island_removal_mode 0)
			)
			(polygon
				(pts
					(arc
						(start 327.880472 -51.596798)
						(mid 327.938335 -51.560427)
						(end 327.974706 -51.502564)
					)
					(arc
						(start 328.079862 -51.502564)
						(mid 328.010193 -51.632285)
						(end 327.880472 -51.701954)
					)
				)
			)
		)
		(zone
			(layer "F.Cu")
			(hatch none 0.5)
			(connect_pads
				(clearance 0)
			)
			(min_thickness 0.25)
			(keepout
				(tracks not_allowed)
				(vias allowed)
				(pads allowed)
				(copperpour not_allowed)
				(footprints allowed)
			)
			(placement
				(enabled no)
				(sheetname "")
			)
			(fill
				(thermal_gap 0.5)
				(thermal_bridge_width 0.5)
				(island_removal_mode 0)
			)
			(polygon
				(pts
					(arc
						(start 327.880472 -50.596292)
						(mid 327.938335 -50.559921)
						(end 327.974706 -50.502058)
					)
					(arc
						(start 328.079862 -50.502058)
						(mid 328.010193 -50.631779)
						(end 327.880472 -50.701448)
					)
				)
			)
		)
		(zone
			(layer "F.Cu")
			(hatch none 0.5)
			(connect_pads
				(clearance 0)
			)
			(min_thickness 0.25)
			(keepout
				(tracks not_allowed)
				(vias allowed)
				(pads allowed)
				(copperpour not_allowed)
				(footprints allowed)
			)
			(placement
				(enabled no)
				(sheetname "")
			)
			(fill
				(thermal_gap 0.5)
				(thermal_bridge_width 0.5)
				(island_removal_mode 0)
			)
			(polygon
				(pts
					(arc
						(start 327.880472 -49.595786)
						(mid 327.938335 -49.559415)
						(end 327.974706 -49.501552)
					)
					(arc
						(start 328.079862 -49.501552)
						(mid 328.010193 -49.631273)
						(end 327.880472 -49.700942)
					)
				)
			)
		)
		(zone
			(layer "F.Cu")
			(hatch none 0.5)
			(connect_pads
				(clearance 0)
			)
			(min_thickness 0.25)
			(keepout
				(tracks not_allowed)
				(vias allowed)
				(pads allowed)
				(copperpour not_allowed)
				(footprints allowed)
			)
			(placement
				(enabled no)
				(sheetname "")
			)
			(fill
				(thermal_gap 0.5)
				(thermal_bridge_width 0.5)
				(island_removal_mode 0)
			)
			(polygon
				(pts
					(arc
						(start 327.880472 -48.59528)
						(mid 327.938335 -48.558909)
						(end 327.974706 -48.501046)
					)
					(arc
						(start 328.079862 -48.501046)
						(mid 328.010193 -48.630767)
						(end 327.880472 -48.700436)
					)
				)
			)
		)
		(zone
			(layer "F.Cu")
			(hatch none 0.5)
			(connect_pads
				(clearance 0)
			)
			(min_thickness 0.25)
			(keepout
				(tracks not_allowed)
				(vias allowed)
				(pads allowed)
				(copperpour not_allowed)
				(footprints allowed)
			)
			(placement
				(enabled no)
				(sheetname "")
			)
			(fill
				(thermal_gap 0.5)
				(thermal_bridge_width 0.5)
				(island_removal_mode 0)
			)
			(polygon
				(pts
					(arc
						(start 327.880472 -47.594774)
						(mid 327.938335 -47.558403)
						(end 327.974706 -47.50054)
					)
					(arc
						(start 328.079862 -47.50054)
						(mid 328.010193 -47.630261)
						(end 327.880472 -47.69993)
					)
				)
			)
		)
		(zone
			(layer "F.Cu")
			(hatch none 0.5)
			(connect_pads
				(clearance 0)
			)
			(min_thickness 0.25)
			(keepout
				(tracks not_allowed)
				(vias allowed)
				(pads allowed)
				(copperpour not_allowed)
				(footprints allowed)
			)
			(placement
				(enabled no)
				(sheetname "")
			)
			(fill
				(thermal_gap 0.5)
				(thermal_bridge_width 0.5)
				(island_removal_mode 0)
			)
			(polygon
				(pts
					(arc
						(start 327.880472 -46.594268)
						(mid 327.938335 -46.557897)
						(end 327.974706 -46.500034)
					)
					(arc
						(start 328.079862 -46.500034)
						(mid 328.010193 -46.629755)
						(end 327.880472 -46.699424)
					)
				)
			)
		)
		(zone
			(layer "F.Cu")
			(hatch none 0.5)
			(connect_pads
				(clearance 0)
			)
			(min_thickness 0.25)
			(keepout
				(tracks not_allowed)
				(vias allowed)
				(pads allowed)
				(copperpour not_allowed)
				(footprints allowed)
			)
			(placement
				(enabled no)
				(sheetname "")
			)
			(fill
				(thermal_gap 0.5)
				(thermal_bridge_width 0.5)
				(island_removal_mode 0)
			)
			(polygon
				(pts
					(arc
						(start 327.880472 -45.593762)
						(mid 327.938335 -45.557391)
						(end 327.974706 -45.499528)
					)
					(arc
						(start 328.079862 -45.499528)
						(mid 328.010193 -45.629249)
						(end 327.880472 -45.698918)
					)
				)
			)
		)
		(zone
			(layer "F.Cu")
			(hatch none 0.5)
			(connect_pads
				(clearance 0)
			)
			(min_thickness 0.25)
			(keepout
				(tracks not_allowed)
				(vias allowed)
				(pads allowed)
				(copperpour not_allowed)
				(footprints allowed)
			)
			(placement
				(enabled no)
				(sheetname "")
			)
			(fill
				(thermal_gap 0.5)
				(thermal_bridge_width 0.5)
				(island_removal_mode 0)
			)
			(polygon
				(pts
					(arc
						(start 327.880472 -44.593256)
						(mid 327.938335 -44.556885)
						(end 327.974706 -44.499022)
					)
					(arc
						(start 328.079862 -44.499022)
						(mid 328.010193 -44.628743)
						(end 327.880472 -44.698412)
					)
				)
			)
		)
		(zone
			(layer "F.Cu")
			(hatch none 0.5)
			(connect_pads
				(clearance 0)
			)
			(min_thickness 0.25)
			(keepout
				(tracks not_allowed)
				(vias allowed)
				(pads allowed)
				(copperpour not_allowed)
				(footprints allowed)
			)
			(placement
				(enabled no)
				(sheetname "")
			)
			(fill
				(thermal_gap 0.5)
				(thermal_bridge_width 0.5)
				(island_removal_mode 0)
			)
			(polygon
				(pts
					(arc
						(start 327.880472 -43.59275)
						(mid 327.938335 -43.556379)
						(end 327.974706 -43.498516)
					)
					(arc
						(start 328.079862 -43.498516)
						(mid 328.010193 -43.628237)
						(end 327.880472 -43.697906)
					)
				)
			)
		)
		(zone
			(layer "F.Cu")
			(hatch none 0.5)
			(connect_pads
				(clearance 0)
			)
			(min_thickness 0.25)
			(keepout
				(tracks not_allowed)
				(vias allowed)
				(pads allowed)
				(copperpour not_allowed)
				(footprints allowed)
			)
			(placement
				(enabled no)
				(sheetname "")
			)
			(fill
				(thermal_gap 0.5)
				(thermal_bridge_width 0.5)
				(island_removal_mode 0)
			)
			(polygon
				(pts
					(arc
						(start 327.880472 -42.592244)
						(mid 327.938331 -42.556013)
						(end 327.974706 -42.498264)
					)
					(arc
						(start 328.079862 -42.498264)
						(mid 328.010193 -42.627985)
						(end 327.880472 -42.697654)
					)
				)
			)
		)
		(zone
			(layer "F.Cu")
			(hatch none 0.5)
			(connect_pads
				(clearance 0)
			)
			(min_thickness 0.25)
			(keepout
				(tracks not_allowed)
				(vias allowed)
				(pads allowed)
				(copperpour not_allowed)
				(footprints allowed)
			)
			(placement
				(enabled no)
				(sheetname "")
			)
			(fill
				(thermal_gap 0.5)
				(thermal_bridge_width 0.5)
				(island_removal_mode 0)
			)
			(polygon
				(pts
					(arc
						(start 327.880472 -41.591738)
						(mid 327.938331 -41.555507)
						(end 327.974706 -41.497758)
					)
					(arc
						(start 328.079862 -41.497758)
						(mid 328.010193 -41.627479)
						(end 327.880472 -41.697148)
					)
				)
			)
		)
		(zone
			(layer "F.Cu")
			(hatch none 0.5)
			(connect_pads
				(clearance 0)
			)
			(min_thickness 0.25)
			(keepout
				(tracks not_allowed)
				(vias allowed)
				(pads allowed)
				(copperpour not_allowed)
				(footprints allowed)
			)
			(placement
				(enabled no)
				(sheetname "")
			)
			(fill
				(thermal_gap 0.5)
				(thermal_bridge_width 0.5)
				(island_removal_mode 0)
			)
			(polygon
				(pts
					(arc
						(start 327.880472 -40.591232)
						(mid 327.938331 -40.555001)
						(end 327.974706 -40.497252)
					)
					(arc
						(start 328.079862 -40.497252)
						(mid 328.010193 -40.626973)
						(end 327.880472 -40.696642)
					)
				)
			)
		)
		(zone
			(layer "F.Cu")
			(hatch none 0.5)
			(connect_pads
				(clearance 0)
			)
			(min_thickness 0.25)
			(keepout
				(tracks not_allowed)
				(vias allowed)
				(pads allowed)
				(copperpour not_allowed)
				(footprints allowed)
			)
			(placement
				(enabled no)
				(sheetname "")
			)
			(fill
				(thermal_gap 0.5)
				(thermal_bridge_width 0.5)
				(island_removal_mode 0)
			)
			(polygon
				(pts
					(arc
						(start 327.880472 -39.590726)
						(mid 327.938331 -39.554495)
						(end 327.974706 -39.496746)
					)
					(arc
						(start 328.079862 -39.496746)
						(mid 328.010193 -39.626467)
						(end 327.880472 -39.696136)
					)
				)
			)
		)
		(zone
			(layer "F.Cu")
			(hatch none 0.5)
			(connect_pads
				(clearance 0)
			)
			(min_thickness 0.25)
			(keepout
				(tracks not_allowed)
				(vias allowed)
				(pads allowed)
				(copperpour not_allowed)
				(footprints allowed)
			)
			(placement
				(enabled no)
				(sheetname "")
			)
			(fill
				(thermal_gap 0.5)
				(thermal_bridge_width 0.5)
				(island_removal_mode 0)
			)
			(polygon
				(pts
					(arc
						(start 327.946004 -58.58002)
						(mid 328.003863 -58.543789)
						(end 328.040238 -58.48604)
					)
					(arc
						(start 328.145394 -58.48604)
						(mid 328.075725 -58.615761)
						(end 327.946004 -58.68543)
					)
				)
			)
		)
		(zone
			(layer "F.Cu")
			(hatch none 0.5)
			(connect_pads
				(clearance 0)
			)
			(min_thickness 0.25)
			(keepout
				(tracks not_allowed)
				(vias allowed)
				(pads allowed)
				(copperpour not_allowed)
				(footprints allowed)
			)
			(placement
				(enabled no)
				(sheetname "")
			)
			(fill
				(thermal_gap 0.5)
				(thermal_bridge_width 0.5)
				(island_removal_mode 0)
			)
			(polygon
				(pts
					(arc
						(start 327.946004 -38.610286)
						(mid 328.003867 -38.573915)
						(end 328.040238 -38.516052)
					)
					(arc
						(start 328.145394 -38.516052)
						(mid 328.075725 -38.645773)
						(end 327.946004 -38.715442)
					)
				)
			)
		)
		(zone
			(layer "F.Cu")
			(hatch none 0.5)
			(connect_pads
				(clearance 0)
			)
			(min_thickness 0.25)
			(keepout
				(tracks not_allowed)
				(vias allowed)
				(pads allowed)
				(copperpour not_allowed)
				(footprints allowed)
			)
			(placement
				(enabled no)
				(sheetname "")
			)
			(fill
				(thermal_gap 0.5)
				(thermal_bridge_width 0.5)
				(island_removal_mode 0)
			)
			(polygon
				(pts
					(arc
						(start 327.974706 -57.403746)
						(mid 327.93828 -57.346047)
						(end 327.880472 -57.309766)
					)
					(arc
						(start 327.880472 -57.204356)
						(mid 328.010193 -57.274025)
						(end 328.079862 -57.403746)
					)
				)
			)
		)
		(zone
			(layer "F.Cu")
			(hatch none 0.5)
			(connect_pads
				(clearance 0)
			)
			(min_thickness 0.25)
			(keepout
				(tracks not_allowed)
				(vias allowed)
				(pads allowed)
				(copperpour not_allowed)
				(footprints allowed)
			)
			(placement
				(enabled no)
				(sheetname "")
			)
			(fill
				(thermal_gap 0.5)
				(thermal_bridge_width 0.5)
				(island_removal_mode 0)
			)
			(polygon
				(pts
					(arc
						(start 327.974706 -56.40324)
						(mid 327.93828 -56.345541)
						(end 327.880472 -56.30926)
					)
					(arc
						(start 327.880472 -56.20385)
						(mid 328.010193 -56.273519)
						(end 328.079862 -56.40324)
					)
				)
			)
		)
		(zone
			(layer "F.Cu")
			(hatch none 0.5)
			(connect_pads
				(clearance 0)
			)
			(min_thickness 0.25)
			(keepout
				(tracks not_allowed)
				(vias allowed)
				(pads allowed)
				(copperpour not_allowed)
				(footprints allowed)
			)
			(placement
				(enabled no)
				(sheetname "")
			)
			(fill
				(thermal_gap 0.5)
				(thermal_bridge_width 0.5)
				(island_removal_mode 0)
			)
			(polygon
				(pts
					(arc
						(start 327.974706 -55.402734)
						(mid 327.93828 -55.345035)
						(end 327.880472 -55.308754)
					)
					(arc
						(start 327.880472 -55.203344)
						(mid 328.010193 -55.273013)
						(end 328.079862 -55.402734)
					)
				)
			)
		)
		(zone
			(layer "F.Cu")
			(hatch none 0.5)
			(connect_pads
				(clearance 0)
			)
			(min_thickness 0.25)
			(keepout
				(tracks not_allowed)
				(vias allowed)
				(pads allowed)
				(copperpour not_allowed)
				(footprints allowed)
			)
			(placement
				(enabled no)
				(sheetname "")
			)
			(fill
				(thermal_gap 0.5)
				(thermal_bridge_width 0.5)
				(island_removal_mode 0)
			)
			(polygon
				(pts
					(arc
						(start 327.974706 -54.402228)
						(mid 327.93828 -54.344529)
						(end 327.880472 -54.308248)
					)
					(arc
						(start 327.880472 -54.202838)
						(mid 328.010193 -54.272507)
						(end 328.079862 -54.402228)
					)
				)
			)
		)
		(zone
			(layer "F.Cu")
			(hatch none 0.5)
			(connect_pads
				(clearance 0)
			)
			(min_thickness 0.25)
			(keepout
				(tracks not_allowed)
				(vias allowed)
				(pads allowed)
				(copperpour not_allowed)
				(footprints allowed)
			)
			(placement
				(enabled no)
				(sheetname "")
			)
			(fill
				(thermal_gap 0.5)
				(thermal_bridge_width 0.5)
				(island_removal_mode 0)
			)
			(polygon
				(pts
					(arc
						(start 327.974706 -53.401722)
						(mid 327.93828 -53.344023)
						(end 327.880472 -53.307742)
					)
					(arc
						(start 327.880472 -53.202332)
						(mid 328.010193 -53.272001)
						(end 328.079862 -53.401722)
					)
				)
			)
		)
		(zone
			(layer "F.Cu")
			(hatch none 0.5)
			(connect_pads
				(clearance 0)
			)
			(min_thickness 0.25)
			(keepout
				(tracks not_allowed)
				(vias allowed)
				(pads allowed)
				(copperpour not_allowed)
				(footprints allowed)
			)
			(placement
				(enabled no)
				(sheetname "")
			)
			(fill
				(thermal_gap 0.5)
				(thermal_bridge_width 0.5)
				(island_removal_mode 0)
			)
			(polygon
				(pts
					(arc
						(start 327.974706 -52.40147)
						(mid 327.938335 -52.343607)
						(end 327.880472 -52.307236)
					)
					(arc
						(start 327.880472 -52.201826)
						(mid 328.010281 -52.271583)
						(end 328.079862 -52.40147)
					)
				)
			)
		)
		(zone
			(layer "F.Cu")
			(hatch none 0.5)
			(connect_pads
				(clearance 0)
			)
			(min_thickness 0.25)
			(keepout
				(tracks not_allowed)
				(vias allowed)
				(pads allowed)
				(copperpour not_allowed)
				(footprints allowed)
			)
			(placement
				(enabled no)
				(sheetname "")
			)
			(fill
				(thermal_gap 0.5)
				(thermal_bridge_width 0.5)
				(island_removal_mode 0)
			)
			(polygon
				(pts
					(arc
						(start 327.974706 -51.400964)
						(mid 327.938335 -51.343101)
						(end 327.880472 -51.30673)
					)
					(arc
						(start 327.880472 -51.201574)
						(mid 328.010193 -51.271243)
						(end 328.079862 -51.400964)
					)
				)
			)
		)
		(zone
			(layer "F.Cu")
			(hatch none 0.5)
			(connect_pads
				(clearance 0)
			)
			(min_thickness 0.25)
			(keepout
				(tracks not_allowed)
				(vias allowed)
				(pads allowed)
				(copperpour not_allowed)
				(footprints allowed)
			)
			(placement
				(enabled no)
				(sheetname "")
			)
			(fill
				(thermal_gap 0.5)
				(thermal_bridge_width 0.5)
				(island_removal_mode 0)
			)
			(polygon
				(pts
					(arc
						(start 327.974706 -50.400458)
						(mid 327.938335 -50.342595)
						(end 327.880472 -50.306224)
					)
					(arc
						(start 327.880472 -50.201068)
						(mid 328.010193 -50.270737)
						(end 328.079862 -50.400458)
					)
				)
			)
		)
		(zone
			(layer "F.Cu")
			(hatch none 0.5)
			(connect_pads
				(clearance 0)
			)
			(min_thickness 0.25)
			(keepout
				(tracks not_allowed)
				(vias allowed)
				(pads allowed)
				(copperpour not_allowed)
				(footprints allowed)
			)
			(placement
				(enabled no)
				(sheetname "")
			)
			(fill
				(thermal_gap 0.5)
				(thermal_bridge_width 0.5)
				(island_removal_mode 0)
			)
			(polygon
				(pts
					(arc
						(start 327.974706 -49.399952)
						(mid 327.938335 -49.342089)
						(end 327.880472 -49.305718)
					)
					(arc
						(start 327.880472 -49.200562)
						(mid 328.010193 -49.270231)
						(end 328.079862 -49.399952)
					)
				)
			)
		)
		(zone
			(layer "F.Cu")
			(hatch none 0.5)
			(connect_pads
				(clearance 0)
			)
			(min_thickness 0.25)
			(keepout
				(tracks not_allowed)
				(vias allowed)
				(pads allowed)
				(copperpour not_allowed)
				(footprints allowed)
			)
			(placement
				(enabled no)
				(sheetname "")
			)
			(fill
				(thermal_gap 0.5)
				(thermal_bridge_width 0.5)
				(island_removal_mode 0)
			)
			(polygon
				(pts
					(arc
						(start 327.974706 -48.399446)
						(mid 327.938335 -48.341583)
						(end 327.880472 -48.305212)
					)
					(arc
						(start 327.880472 -48.200056)
						(mid 328.010193 -48.269725)
						(end 328.079862 -48.399446)
					)
				)
			)
		)
		(zone
			(layer "F.Cu")
			(hatch none 0.5)
			(connect_pads
				(clearance 0)
			)
			(min_thickness 0.25)
			(keepout
				(tracks not_allowed)
				(vias allowed)
				(pads allowed)
				(copperpour not_allowed)
				(footprints allowed)
			)
			(placement
				(enabled no)
				(sheetname "")
			)
			(fill
				(thermal_gap 0.5)
				(thermal_bridge_width 0.5)
				(island_removal_mode 0)
			)
			(polygon
				(pts
					(arc
						(start 327.974706 -47.39894)
						(mid 327.938335 -47.341077)
						(end 327.880472 -47.304706)
					)
					(arc
						(start 327.880472 -47.19955)
						(mid 328.010193 -47.269219)
						(end 328.079862 -47.39894)
					)
				)
			)
		)
		(zone
			(layer "F.Cu")
			(hatch none 0.5)
			(connect_pads
				(clearance 0)
			)
			(min_thickness 0.25)
			(keepout
				(tracks not_allowed)
				(vias allowed)
				(pads allowed)
				(copperpour not_allowed)
				(footprints allowed)
			)
			(placement
				(enabled no)
				(sheetname "")
			)
			(fill
				(thermal_gap 0.5)
				(thermal_bridge_width 0.5)
				(island_removal_mode 0)
			)
			(polygon
				(pts
					(arc
						(start 327.974706 -46.398434)
						(mid 327.938335 -46.340571)
						(end 327.880472 -46.3042)
					)
					(arc
						(start 327.880472 -46.199044)
						(mid 328.010193 -46.268713)
						(end 328.079862 -46.398434)
					)
				)
			)
		)
		(zone
			(layer "F.Cu")
			(hatch none 0.5)
			(connect_pads
				(clearance 0)
			)
			(min_thickness 0.25)
			(keepout
				(tracks not_allowed)
				(vias allowed)
				(pads allowed)
				(copperpour not_allowed)
				(footprints allowed)
			)
			(placement
				(enabled no)
				(sheetname "")
			)
			(fill
				(thermal_gap 0.5)
				(thermal_bridge_width 0.5)
				(island_removal_mode 0)
			)
			(polygon
				(pts
					(arc
						(start 327.974706 -45.397928)
						(mid 327.938335 -45.340065)
						(end 327.880472 -45.303694)
					)
					(arc
						(start 327.880472 -45.198538)
						(mid 328.010193 -45.268207)
						(end 328.079862 -45.397928)
					)
				)
			)
		)
		(zone
			(layer "F.Cu")
			(hatch none 0.5)
			(connect_pads
				(clearance 0)
			)
			(min_thickness 0.25)
			(keepout
				(tracks not_allowed)
				(vias allowed)
				(pads allowed)
				(copperpour not_allowed)
				(footprints allowed)
			)
			(placement
				(enabled no)
				(sheetname "")
			)
			(fill
				(thermal_gap 0.5)
				(thermal_bridge_width 0.5)
				(island_removal_mode 0)
			)
			(polygon
				(pts
					(arc
						(start 327.974706 -44.397422)
						(mid 327.938335 -44.339559)
						(end 327.880472 -44.303188)
					)
					(arc
						(start 327.880472 -44.198032)
						(mid 328.010193 -44.267701)
						(end 328.079862 -44.397422)
					)
				)
			)
		)
		(zone
			(layer "F.Cu")
			(hatch none 0.5)
			(connect_pads
				(clearance 0)
			)
			(min_thickness 0.25)
			(keepout
				(tracks not_allowed)
				(vias allowed)
				(pads allowed)
				(copperpour not_allowed)
				(footprints allowed)
			)
			(placement
				(enabled no)
				(sheetname "")
			)
			(fill
				(thermal_gap 0.5)
				(thermal_bridge_width 0.5)
				(island_removal_mode 0)
			)
			(polygon
				(pts
					(arc
						(start 327.974706 -43.396916)
						(mid 327.938335 -43.339053)
						(end 327.880472 -43.302682)
					)
					(arc
						(start 327.880472 -43.197526)
						(mid 328.010193 -43.267195)
						(end 328.079862 -43.396916)
					)
				)
			)
		)
		(zone
			(layer "F.Cu")
			(hatch none 0.5)
			(connect_pads
				(clearance 0)
			)
			(min_thickness 0.25)
			(keepout
				(tracks not_allowed)
				(vias allowed)
				(pads allowed)
				(copperpour not_allowed)
				(footprints allowed)
			)
			(placement
				(enabled no)
				(sheetname "")
			)
			(fill
				(thermal_gap 0.5)
				(thermal_bridge_width 0.5)
				(island_removal_mode 0)
			)
			(polygon
				(pts
					(arc
						(start 327.974706 -42.396664)
						(mid 327.938335 -42.338801)
						(end 327.880472 -42.30243)
					)
					(arc
						(start 327.880472 -42.19702)
						(mid 328.010281 -42.266777)
						(end 328.079862 -42.396664)
					)
				)
			)
		)
		(zone
			(layer "F.Cu")
			(hatch none 0.5)
			(connect_pads
				(clearance 0)
			)
			(min_thickness 0.25)
			(keepout
				(tracks not_allowed)
				(vias allowed)
				(pads allowed)
				(copperpour not_allowed)
				(footprints allowed)
			)
			(placement
				(enabled no)
				(sheetname "")
			)
			(fill
				(thermal_gap 0.5)
				(thermal_bridge_width 0.5)
				(island_removal_mode 0)
			)
			(polygon
				(pts
					(arc
						(start 327.974706 -41.396158)
						(mid 327.938335 -41.338295)
						(end 327.880472 -41.301924)
					)
					(arc
						(start 327.880472 -41.196768)
						(mid 328.010193 -41.266437)
						(end 328.079862 -41.396158)
					)
				)
			)
		)
		(zone
			(layer "F.Cu")
			(hatch none 0.5)
			(connect_pads
				(clearance 0)
			)
			(min_thickness 0.25)
			(keepout
				(tracks not_allowed)
				(vias allowed)
				(pads allowed)
				(copperpour not_allowed)
				(footprints allowed)
			)
			(placement
				(enabled no)
				(sheetname "")
			)
			(fill
				(thermal_gap 0.5)
				(thermal_bridge_width 0.5)
				(island_removal_mode 0)
			)
			(polygon
				(pts
					(arc
						(start 327.974706 -40.395652)
						(mid 327.938335 -40.337789)
						(end 327.880472 -40.301418)
					)
					(arc
						(start 327.880472 -40.196262)
						(mid 328.010193 -40.265931)
						(end 328.079862 -40.395652)
					)
				)
			)
		)
		(zone
			(layer "F.Cu")
			(hatch none 0.5)
			(connect_pads
				(clearance 0)
			)
			(min_thickness 0.25)
			(keepout
				(tracks not_allowed)
				(vias allowed)
				(pads allowed)
				(copperpour not_allowed)
				(footprints allowed)
			)
			(placement
				(enabled no)
				(sheetname "")
			)
			(fill
				(thermal_gap 0.5)
				(thermal_bridge_width 0.5)
				(island_removal_mode 0)
			)
			(polygon
				(pts
					(arc
						(start 327.974706 -39.395146)
						(mid 327.938335 -39.337283)
						(end 327.880472 -39.300912)
					)
					(arc
						(start 327.880472 -39.195756)
						(mid 328.010193 -39.265425)
						(end 328.079862 -39.395146)
					)
				)
			)
		)
		(zone
			(layer "F.Cu")
			(hatch none 0.5)
			(connect_pads
				(clearance 0)
			)
			(min_thickness 0.25)
			(keepout
				(tracks not_allowed)
				(vias allowed)
				(pads allowed)
				(copperpour not_allowed)
				(footprints allowed)
			)
			(placement
				(enabled no)
				(sheetname "")
			)
			(fill
				(thermal_gap 0.5)
				(thermal_bridge_width 0.5)
				(island_removal_mode 0)
			)
			(polygon
				(pts
					(arc
						(start 328.040238 -58.38444)
						(mid 328.003867 -58.326577)
						(end 327.946004 -58.290206)
					)
					(arc
						(start 327.946004 -58.18505)
						(mid 328.075725 -58.254719)
						(end 328.145394 -58.38444)
					)
				)
			)
		)
		(zone
			(layer "F.Cu")
			(hatch none 0.5)
			(connect_pads
				(clearance 0)
			)
			(min_thickness 0.25)
			(keepout
				(tracks not_allowed)
				(vias allowed)
				(pads allowed)
				(copperpour not_allowed)
				(footprints allowed)
			)
			(placement
				(enabled no)
				(sheetname "")
			)
			(fill
				(thermal_gap 0.5)
				(thermal_bridge_width 0.5)
				(island_removal_mode 0)
			)
			(polygon
				(pts
					(arc
						(start 328.040238 -38.414452)
						(mid 328.003812 -38.356753)
						(end 327.946004 -38.320472)
					)
					(arc
						(start 327.946004 -38.215062)
						(mid 328.075725 -38.284731)
						(end 328.145394 -38.414452)
					)
				)
			)
		)
		(zone
			(layer "F.Cu")
			(hatch none 0.5)
			(connect_pads
				(clearance 0)
			)
			(min_thickness 0.25)
			(keepout
				(tracks not_allowed)
				(vias allowed)
				(pads allowed)
				(copperpour not_allowed)
				(footprints allowed)
			)
			(placement
				(enabled no)
				(sheetname "")
			)
			(fill
				(thermal_gap 0.5)
				(thermal_bridge_width 0.5)
				(island_removal_mode 0)
			)
			(polygon
				(pts
					(arc
						(start 328.099674 -57.00522)
						(mid 328.136045 -57.063083)
						(end 328.193908 -57.099454)
					)
					(arc
						(start 328.193908 -57.20461)
						(mid 328.064187 -57.134941)
						(end 327.994518 -57.00522)
					)
				)
			)
		)
		(zone
			(layer "F.Cu")
			(hatch none 0.5)
			(connect_pads
				(clearance 0)
			)
			(min_thickness 0.25)
			(keepout
				(tracks not_allowed)
				(vias allowed)
				(pads allowed)
				(copperpour not_allowed)
				(footprints allowed)
			)
			(placement
				(enabled no)
				(sheetname "")
			)
			(fill
				(thermal_gap 0.5)
				(thermal_bridge_width 0.5)
				(island_removal_mode 0)
			)
			(polygon
				(pts
					(arc
						(start 328.099674 -56.004714)
						(mid 328.136045 -56.062577)
						(end 328.193908 -56.098948)
					)
					(arc
						(start 328.193908 -56.204104)
						(mid 328.064187 -56.134435)
						(end 327.994518 -56.004714)
					)
				)
			)
		)
		(zone
			(layer "F.Cu")
			(hatch none 0.5)
			(connect_pads
				(clearance 0)
			)
			(min_thickness 0.25)
			(keepout
				(tracks not_allowed)
				(vias allowed)
				(pads allowed)
				(copperpour not_allowed)
				(footprints allowed)
			)
			(placement
				(enabled no)
				(sheetname "")
			)
			(fill
				(thermal_gap 0.5)
				(thermal_bridge_width 0.5)
				(island_removal_mode 0)
			)
			(polygon
				(pts
					(arc
						(start 328.099674 -55.004208)
						(mid 328.136045 -55.062071)
						(end 328.193908 -55.098442)
					)
					(arc
						(start 328.193908 -55.203598)
						(mid 328.064187 -55.133929)
						(end 327.994518 -55.004208)
					)
				)
			)
		)
		(zone
			(layer "F.Cu")
			(hatch none 0.5)
			(connect_pads
				(clearance 0)
			)
			(min_thickness 0.25)
			(keepout
				(tracks not_allowed)
				(vias allowed)
				(pads allowed)
				(copperpour not_allowed)
				(footprints allowed)
			)
			(placement
				(enabled no)
				(sheetname "")
			)
			(fill
				(thermal_gap 0.5)
				(thermal_bridge_width 0.5)
				(island_removal_mode 0)
			)
			(polygon
				(pts
					(arc
						(start 328.099674 -54.003702)
						(mid 328.136045 -54.061565)
						(end 328.193908 -54.097936)
					)
					(arc
						(start 328.193908 -54.203092)
						(mid 328.064187 -54.133423)
						(end 327.994518 -54.003702)
					)
				)
			)
		)
		(zone
			(layer "F.Cu")
			(hatch none 0.5)
			(connect_pads
				(clearance 0)
			)
			(min_thickness 0.25)
			(keepout
				(tracks not_allowed)
				(vias allowed)
				(pads allowed)
				(copperpour not_allowed)
				(footprints allowed)
			)
			(placement
				(enabled no)
				(sheetname "")
			)
			(fill
				(thermal_gap 0.5)
				(thermal_bridge_width 0.5)
				(island_removal_mode 0)
			)
			(polygon
				(pts
					(arc
						(start 328.099674 -53.003196)
						(mid 328.136045 -53.061059)
						(end 328.193908 -53.09743)
					)
					(arc
						(start 328.193908 -53.202586)
						(mid 328.064187 -53.132917)
						(end 327.994518 -53.003196)
					)
				)
			)
		)
		(zone
			(layer "F.Cu")
			(hatch none 0.5)
			(connect_pads
				(clearance 0)
			)
			(min_thickness 0.25)
			(keepout
				(tracks not_allowed)
				(vias allowed)
				(pads allowed)
				(copperpour not_allowed)
				(footprints allowed)
			)
			(placement
				(enabled no)
				(sheetname "")
			)
			(fill
				(thermal_gap 0.5)
				(thermal_bridge_width 0.5)
				(island_removal_mode 0)
			)
			(polygon
				(pts
					(arc
						(start 328.099674 -52.00269)
						(mid 328.136045 -52.060553)
						(end 328.193908 -52.096924)
					)
					(arc
						(start 328.193908 -52.20208)
						(mid 328.064187 -52.132411)
						(end 327.994518 -52.00269)
					)
				)
			)
		)
		(zone
			(layer "F.Cu")
			(hatch none 0.5)
			(connect_pads
				(clearance 0)
			)
			(min_thickness 0.25)
			(keepout
				(tracks not_allowed)
				(vias allowed)
				(pads allowed)
				(copperpour not_allowed)
				(footprints allowed)
			)
			(placement
				(enabled no)
				(sheetname "")
			)
			(fill
				(thermal_gap 0.5)
				(thermal_bridge_width 0.5)
				(island_removal_mode 0)
			)
			(polygon
				(pts
					(arc
						(start 328.099674 -51.002438)
						(mid 328.136045 -51.060301)
						(end 328.193908 -51.096672)
					)
					(arc
						(start 328.193908 -51.201828)
						(mid 328.064187 -51.132159)
						(end 327.994518 -51.002438)
					)
				)
			)
		)
		(zone
			(layer "F.Cu")
			(hatch none 0.5)
			(connect_pads
				(clearance 0)
			)
			(min_thickness 0.25)
			(keepout
				(tracks not_allowed)
				(vias allowed)
				(pads allowed)
				(copperpour not_allowed)
				(footprints allowed)
			)
			(placement
				(enabled no)
				(sheetname "")
			)
			(fill
				(thermal_gap 0.5)
				(thermal_bridge_width 0.5)
				(island_removal_mode 0)
			)
			(polygon
				(pts
					(arc
						(start 328.099674 -50.001932)
						(mid 328.136045 -50.059795)
						(end 328.193908 -50.096166)
					)
					(arc
						(start 328.193908 -50.201322)
						(mid 328.064187 -50.131653)
						(end 327.994518 -50.001932)
					)
				)
			)
		)
		(zone
			(layer "F.Cu")
			(hatch none 0.5)
			(connect_pads
				(clearance 0)
			)
			(min_thickness 0.25)
			(keepout
				(tracks not_allowed)
				(vias allowed)
				(pads allowed)
				(copperpour not_allowed)
				(footprints allowed)
			)
			(placement
				(enabled no)
				(sheetname "")
			)
			(fill
				(thermal_gap 0.5)
				(thermal_bridge_width 0.5)
				(island_removal_mode 0)
			)
			(polygon
				(pts
					(arc
						(start 328.099674 -49.001426)
						(mid 328.136045 -49.059289)
						(end 328.193908 -49.09566)
					)
					(arc
						(start 328.193908 -49.200816)
						(mid 328.064187 -49.131147)
						(end 327.994518 -49.001426)
					)
				)
			)
		)
		(zone
			(layer "F.Cu")
			(hatch none 0.5)
			(connect_pads
				(clearance 0)
			)
			(min_thickness 0.25)
			(keepout
				(tracks not_allowed)
				(vias allowed)
				(pads allowed)
				(copperpour not_allowed)
				(footprints allowed)
			)
			(placement
				(enabled no)
				(sheetname "")
			)
			(fill
				(thermal_gap 0.5)
				(thermal_bridge_width 0.5)
				(island_removal_mode 0)
			)
			(polygon
				(pts
					(arc
						(start 328.099674 -48.00092)
						(mid 328.136045 -48.058783)
						(end 328.193908 -48.095154)
					)
					(arc
						(start 328.193908 -48.20031)
						(mid 328.064187 -48.130641)
						(end 327.994518 -48.00092)
					)
				)
			)
		)
		(zone
			(layer "F.Cu")
			(hatch none 0.5)
			(connect_pads
				(clearance 0)
			)
			(min_thickness 0.25)
			(keepout
				(tracks not_allowed)
				(vias allowed)
				(pads allowed)
				(copperpour not_allowed)
				(footprints allowed)
			)
			(placement
				(enabled no)
				(sheetname "")
			)
			(fill
				(thermal_gap 0.5)
				(thermal_bridge_width 0.5)
				(island_removal_mode 0)
			)
			(polygon
				(pts
					(arc
						(start 328.099674 -47.000414)
						(mid 328.136045 -47.058277)
						(end 328.193908 -47.094648)
					)
					(arc
						(start 328.193908 -47.199804)
						(mid 328.064187 -47.130135)
						(end 327.994518 -47.000414)
					)
				)
			)
		)
		(zone
			(layer "F.Cu")
			(hatch none 0.5)
			(connect_pads
				(clearance 0)
			)
			(min_thickness 0.25)
			(keepout
				(tracks not_allowed)
				(vias allowed)
				(pads allowed)
				(copperpour not_allowed)
				(footprints allowed)
			)
			(placement
				(enabled no)
				(sheetname "")
			)
			(fill
				(thermal_gap 0.5)
				(thermal_bridge_width 0.5)
				(island_removal_mode 0)
			)
			(polygon
				(pts
					(arc
						(start 328.099674 -45.999908)
						(mid 328.136045 -46.057771)
						(end 328.193908 -46.094142)
					)
					(arc
						(start 328.193908 -46.199298)
						(mid 328.064187 -46.129629)
						(end 327.994518 -45.999908)
					)
				)
			)
		)
		(zone
			(layer "F.Cu")
			(hatch none 0.5)
			(connect_pads
				(clearance 0)
			)
			(min_thickness 0.25)
			(keepout
				(tracks not_allowed)
				(vias allowed)
				(pads allowed)
				(copperpour not_allowed)
				(footprints allowed)
			)
			(placement
				(enabled no)
				(sheetname "")
			)
			(fill
				(thermal_gap 0.5)
				(thermal_bridge_width 0.5)
				(island_removal_mode 0)
			)
			(polygon
				(pts
					(arc
						(start 328.099674 -44.999402)
						(mid 328.136045 -45.057265)
						(end 328.193908 -45.093636)
					)
					(arc
						(start 328.193908 -45.198792)
						(mid 328.064187 -45.129123)
						(end 327.994518 -44.999402)
					)
				)
			)
		)
		(zone
			(layer "F.Cu")
			(hatch none 0.5)
			(connect_pads
				(clearance 0)
			)
			(min_thickness 0.25)
			(keepout
				(tracks not_allowed)
				(vias allowed)
				(pads allowed)
				(copperpour not_allowed)
				(footprints allowed)
			)
			(placement
				(enabled no)
				(sheetname "")
			)
			(fill
				(thermal_gap 0.5)
				(thermal_bridge_width 0.5)
				(island_removal_mode 0)
			)
			(polygon
				(pts
					(arc
						(start 328.099674 -43.998896)
						(mid 328.136045 -44.056759)
						(end 328.193908 -44.09313)
					)
					(arc
						(start 328.193908 -44.198286)
						(mid 328.064187 -44.128617)
						(end 327.994518 -43.998896)
					)
				)
			)
		)
		(zone
			(layer "F.Cu")
			(hatch none 0.5)
			(connect_pads
				(clearance 0)
			)
			(min_thickness 0.25)
			(keepout
				(tracks not_allowed)
				(vias allowed)
				(pads allowed)
				(copperpour not_allowed)
				(footprints allowed)
			)
			(placement
				(enabled no)
				(sheetname "")
			)
			(fill
				(thermal_gap 0.5)
				(thermal_bridge_width 0.5)
				(island_removal_mode 0)
			)
			(polygon
				(pts
					(arc
						(start 328.099674 -42.99839)
						(mid 328.136045 -43.056253)
						(end 328.193908 -43.092624)
					)
					(arc
						(start 328.193908 -43.19778)
						(mid 328.064187 -43.128111)
						(end 327.994518 -42.99839)
					)
				)
			)
		)
		(zone
			(layer "F.Cu")
			(hatch none 0.5)
			(connect_pads
				(clearance 0)
			)
			(min_thickness 0.25)
			(keepout
				(tracks not_allowed)
				(vias allowed)
				(pads allowed)
				(copperpour not_allowed)
				(footprints allowed)
			)
			(placement
				(enabled no)
				(sheetname "")
			)
			(fill
				(thermal_gap 0.5)
				(thermal_bridge_width 0.5)
				(island_removal_mode 0)
			)
			(polygon
				(pts
					(arc
						(start 328.099674 -41.997884)
						(mid 328.136045 -42.055747)
						(end 328.193908 -42.092118)
					)
					(arc
						(start 328.193908 -42.197274)
						(mid 328.064187 -42.127605)
						(end 327.994518 -41.997884)
					)
				)
			)
		)
		(zone
			(layer "F.Cu")
			(hatch none 0.5)
			(connect_pads
				(clearance 0)
			)
			(min_thickness 0.25)
			(keepout
				(tracks not_allowed)
				(vias allowed)
				(pads allowed)
				(copperpour not_allowed)
				(footprints allowed)
			)
			(placement
				(enabled no)
				(sheetname "")
			)
			(fill
				(thermal_gap 0.5)
				(thermal_bridge_width 0.5)
				(island_removal_mode 0)
			)
			(polygon
				(pts
					(arc
						(start 328.099674 -40.997378)
						(mid 328.136045 -41.055241)
						(end 328.193908 -41.091612)
					)
					(arc
						(start 328.193908 -41.196768)
						(mid 328.064187 -41.127099)
						(end 327.994518 -40.997378)
					)
				)
			)
		)
		(zone
			(layer "F.Cu")
			(hatch none 0.5)
			(connect_pads
				(clearance 0)
			)
			(min_thickness 0.25)
			(keepout
				(tracks not_allowed)
				(vias allowed)
				(pads allowed)
				(copperpour not_allowed)
				(footprints allowed)
			)
			(placement
				(enabled no)
				(sheetname "")
			)
			(fill
				(thermal_gap 0.5)
				(thermal_bridge_width 0.5)
				(island_removal_mode 0)
			)
			(polygon
				(pts
					(arc
						(start 328.099674 -39.996872)
						(mid 328.136045 -40.054735)
						(end 328.193908 -40.091106)
					)
					(arc
						(start 328.193908 -40.196262)
						(mid 328.064187 -40.126593)
						(end 327.994518 -39.996872)
					)
				)
			)
		)
		(zone
			(layer "F.Cu")
			(hatch none 0.5)
			(connect_pads
				(clearance 0)
			)
			(min_thickness 0.25)
			(keepout
				(tracks not_allowed)
				(vias allowed)
				(pads allowed)
				(copperpour not_allowed)
				(footprints allowed)
			)
			(placement
				(enabled no)
				(sheetname "")
			)
			(fill
				(thermal_gap 0.5)
				(thermal_bridge_width 0.5)
				(island_removal_mode 0)
			)
			(polygon
				(pts
					(arc
						(start 328.193908 -56.809386)
						(mid 328.136045 -56.845757)
						(end 328.099674 -56.90362)
					)
					(arc
						(start 327.994518 -56.90362)
						(mid 328.064187 -56.773899)
						(end 328.193908 -56.70423)
					)
				)
			)
		)
		(zone
			(layer "F.Cu")
			(hatch none 0.5)
			(connect_pads
				(clearance 0)
			)
			(min_thickness 0.25)
			(keepout
				(tracks not_allowed)
				(vias allowed)
				(pads allowed)
				(copperpour not_allowed)
				(footprints allowed)
			)
			(placement
				(enabled no)
				(sheetname "")
			)
			(fill
				(thermal_gap 0.5)
				(thermal_bridge_width 0.5)
				(island_removal_mode 0)
			)
			(polygon
				(pts
					(arc
						(start 328.193908 -55.80888)
						(mid 328.136045 -55.845251)
						(end 328.099674 -55.903114)
					)
					(arc
						(start 327.994518 -55.903114)
						(mid 328.064187 -55.773393)
						(end 328.193908 -55.703724)
					)
				)
			)
		)
		(zone
			(layer "F.Cu")
			(hatch none 0.5)
			(connect_pads
				(clearance 0)
			)
			(min_thickness 0.25)
			(keepout
				(tracks not_allowed)
				(vias allowed)
				(pads allowed)
				(copperpour not_allowed)
				(footprints allowed)
			)
			(placement
				(enabled no)
				(sheetname "")
			)
			(fill
				(thermal_gap 0.5)
				(thermal_bridge_width 0.5)
				(island_removal_mode 0)
			)
			(polygon
				(pts
					(arc
						(start 328.193908 -54.808374)
						(mid 328.136045 -54.844745)
						(end 328.099674 -54.902608)
					)
					(arc
						(start 327.994518 -54.902608)
						(mid 328.064187 -54.772887)
						(end 328.193908 -54.703218)
					)
				)
			)
		)
		(zone
			(layer "F.Cu")
			(hatch none 0.5)
			(connect_pads
				(clearance 0)
			)
			(min_thickness 0.25)
			(keepout
				(tracks not_allowed)
				(vias allowed)
				(pads allowed)
				(copperpour not_allowed)
				(footprints allowed)
			)
			(placement
				(enabled no)
				(sheetname "")
			)
			(fill
				(thermal_gap 0.5)
				(thermal_bridge_width 0.5)
				(island_removal_mode 0)
			)
			(polygon
				(pts
					(arc
						(start 328.193908 -53.807868)
						(mid 328.136045 -53.844239)
						(end 328.099674 -53.902102)
					)
					(arc
						(start 327.994518 -53.902102)
						(mid 328.064187 -53.772381)
						(end 328.193908 -53.702712)
					)
				)
			)
		)
		(zone
			(layer "F.Cu")
			(hatch none 0.5)
			(connect_pads
				(clearance 0)
			)
			(min_thickness 0.25)
			(keepout
				(tracks not_allowed)
				(vias allowed)
				(pads allowed)
				(copperpour not_allowed)
				(footprints allowed)
			)
			(placement
				(enabled no)
				(sheetname "")
			)
			(fill
				(thermal_gap 0.5)
				(thermal_bridge_width 0.5)
				(island_removal_mode 0)
			)
			(polygon
				(pts
					(arc
						(start 328.193908 -52.807362)
						(mid 328.136045 -52.843733)
						(end 328.099674 -52.901596)
					)
					(arc
						(start 327.994518 -52.901596)
						(mid 328.064187 -52.771875)
						(end 328.193908 -52.702206)
					)
				)
			)
		)
		(zone
			(layer "F.Cu")
			(hatch none 0.5)
			(connect_pads
				(clearance 0)
			)
			(min_thickness 0.25)
			(keepout
				(tracks not_allowed)
				(vias allowed)
				(pads allowed)
				(copperpour not_allowed)
				(footprints allowed)
			)
			(placement
				(enabled no)
				(sheetname "")
			)
			(fill
				(thermal_gap 0.5)
				(thermal_bridge_width 0.5)
				(island_removal_mode 0)
			)
			(polygon
				(pts
					(arc
						(start 328.193908 -51.806856)
						(mid 328.136045 -51.843227)
						(end 328.099674 -51.90109)
					)
					(arc
						(start 327.994518 -51.90109)
						(mid 328.064187 -51.771369)
						(end 328.193908 -51.7017)
					)
				)
			)
		)
		(zone
			(layer "F.Cu")
			(hatch none 0.5)
			(connect_pads
				(clearance 0)
			)
			(min_thickness 0.25)
			(keepout
				(tracks not_allowed)
				(vias allowed)
				(pads allowed)
				(copperpour not_allowed)
				(footprints allowed)
			)
			(placement
				(enabled no)
				(sheetname "")
			)
			(fill
				(thermal_gap 0.5)
				(thermal_bridge_width 0.5)
				(island_removal_mode 0)
			)
			(polygon
				(pts
					(arc
						(start 328.193908 -50.806604)
						(mid 328.136045 -50.842975)
						(end 328.099674 -50.900838)
					)
					(arc
						(start 327.994518 -50.900838)
						(mid 328.064187 -50.771117)
						(end 328.193908 -50.701448)
					)
				)
			)
		)
		(zone
			(layer "F.Cu")
			(hatch none 0.5)
			(connect_pads
				(clearance 0)
			)
			(min_thickness 0.25)
			(keepout
				(tracks not_allowed)
				(vias allowed)
				(pads allowed)
				(copperpour not_allowed)
				(footprints allowed)
			)
			(placement
				(enabled no)
				(sheetname "")
			)
			(fill
				(thermal_gap 0.5)
				(thermal_bridge_width 0.5)
				(island_removal_mode 0)
			)
			(polygon
				(pts
					(arc
						(start 328.193908 -49.806098)
						(mid 328.136045 -49.842469)
						(end 328.099674 -49.900332)
					)
					(arc
						(start 327.994518 -49.900332)
						(mid 328.064187 -49.770611)
						(end 328.193908 -49.700942)
					)
				)
			)
		)
		(zone
			(layer "F.Cu")
			(hatch none 0.5)
			(connect_pads
				(clearance 0)
			)
			(min_thickness 0.25)
			(keepout
				(tracks not_allowed)
				(vias allowed)
				(pads allowed)
				(copperpour not_allowed)
				(footprints allowed)
			)
			(placement
				(enabled no)
				(sheetname "")
			)
			(fill
				(thermal_gap 0.5)
				(thermal_bridge_width 0.5)
				(island_removal_mode 0)
			)
			(polygon
				(pts
					(arc
						(start 328.193908 -48.805592)
						(mid 328.136045 -48.841963)
						(end 328.099674 -48.899826)
					)
					(arc
						(start 327.994518 -48.899826)
						(mid 328.064187 -48.770105)
						(end 328.193908 -48.700436)
					)
				)
			)
		)
		(zone
			(layer "F.Cu")
			(hatch none 0.5)
			(connect_pads
				(clearance 0)
			)
			(min_thickness 0.25)
			(keepout
				(tracks not_allowed)
				(vias allowed)
				(pads allowed)
				(copperpour not_allowed)
				(footprints allowed)
			)
			(placement
				(enabled no)
				(sheetname "")
			)
			(fill
				(thermal_gap 0.5)
				(thermal_bridge_width 0.5)
				(island_removal_mode 0)
			)
			(polygon
				(pts
					(arc
						(start 328.193908 -47.805086)
						(mid 328.136045 -47.841457)
						(end 328.099674 -47.89932)
					)
					(arc
						(start 327.994518 -47.89932)
						(mid 328.064187 -47.769599)
						(end 328.193908 -47.69993)
					)
				)
			)
		)
		(zone
			(layer "F.Cu")
			(hatch none 0.5)
			(connect_pads
				(clearance 0)
			)
			(min_thickness 0.25)
			(keepout
				(tracks not_allowed)
				(vias allowed)
				(pads allowed)
				(copperpour not_allowed)
				(footprints allowed)
			)
			(placement
				(enabled no)
				(sheetname "")
			)
			(fill
				(thermal_gap 0.5)
				(thermal_bridge_width 0.5)
				(island_removal_mode 0)
			)
			(polygon
				(pts
					(arc
						(start 328.193908 -46.80458)
						(mid 328.136045 -46.840951)
						(end 328.099674 -46.898814)
					)
					(arc
						(start 327.994518 -46.898814)
						(mid 328.064187 -46.769093)
						(end 328.193908 -46.699424)
					)
				)
			)
		)
		(zone
			(layer "F.Cu")
			(hatch none 0.5)
			(connect_pads
				(clearance 0)
			)
			(min_thickness 0.25)
			(keepout
				(tracks not_allowed)
				(vias allowed)
				(pads allowed)
				(copperpour not_allowed)
				(footprints allowed)
			)
			(placement
				(enabled no)
				(sheetname "")
			)
			(fill
				(thermal_gap 0.5)
				(thermal_bridge_width 0.5)
				(island_removal_mode 0)
			)
			(polygon
				(pts
					(arc
						(start 328.193908 -45.804074)
						(mid 328.136045 -45.840445)
						(end 328.099674 -45.898308)
					)
					(arc
						(start 327.994518 -45.898308)
						(mid 328.064187 -45.768587)
						(end 328.193908 -45.698918)
					)
				)
			)
		)
		(zone
			(layer "F.Cu")
			(hatch none 0.5)
			(connect_pads
				(clearance 0)
			)
			(min_thickness 0.25)
			(keepout
				(tracks not_allowed)
				(vias allowed)
				(pads allowed)
				(copperpour not_allowed)
				(footprints allowed)
			)
			(placement
				(enabled no)
				(sheetname "")
			)
			(fill
				(thermal_gap 0.5)
				(thermal_bridge_width 0.5)
				(island_removal_mode 0)
			)
			(polygon
				(pts
					(arc
						(start 328.193908 -44.803568)
						(mid 328.136045 -44.839939)
						(end 328.099674 -44.897802)
					)
					(arc
						(start 327.994518 -44.897802)
						(mid 328.064187 -44.768081)
						(end 328.193908 -44.698412)
					)
				)
			)
		)
		(zone
			(layer "F.Cu")
			(hatch none 0.5)
			(connect_pads
				(clearance 0)
			)
			(min_thickness 0.25)
			(keepout
				(tracks not_allowed)
				(vias allowed)
				(pads allowed)
				(copperpour not_allowed)
				(footprints allowed)
			)
			(placement
				(enabled no)
				(sheetname "")
			)
			(fill
				(thermal_gap 0.5)
				(thermal_bridge_width 0.5)
				(island_removal_mode 0)
			)
			(polygon
				(pts
					(arc
						(start 328.193908 -43.803062)
						(mid 328.136045 -43.839433)
						(end 328.099674 -43.897296)
					)
					(arc
						(start 327.994518 -43.897296)
						(mid 328.064187 -43.767575)
						(end 328.193908 -43.697906)
					)
				)
			)
		)
		(zone
			(layer "F.Cu")
			(hatch none 0.5)
			(connect_pads
				(clearance 0)
			)
			(min_thickness 0.25)
			(keepout
				(tracks not_allowed)
				(vias allowed)
				(pads allowed)
				(copperpour not_allowed)
				(footprints allowed)
			)
			(placement
				(enabled no)
				(sheetname "")
			)
			(fill
				(thermal_gap 0.5)
				(thermal_bridge_width 0.5)
				(island_removal_mode 0)
			)
			(polygon
				(pts
					(arc
						(start 328.193908 -42.802556)
						(mid 328.136045 -42.838927)
						(end 328.099674 -42.89679)
					)
					(arc
						(start 327.994518 -42.89679)
						(mid 328.064187 -42.767069)
						(end 328.193908 -42.6974)
					)
				)
			)
		)
		(zone
			(layer "F.Cu")
			(hatch none 0.5)
			(connect_pads
				(clearance 0)
			)
			(min_thickness 0.25)
			(keepout
				(tracks not_allowed)
				(vias allowed)
				(pads allowed)
				(copperpour not_allowed)
				(footprints allowed)
			)
			(placement
				(enabled no)
				(sheetname "")
			)
			(fill
				(thermal_gap 0.5)
				(thermal_bridge_width 0.5)
				(island_removal_mode 0)
			)
			(polygon
				(pts
					(arc
						(start 328.193908 -41.80205)
						(mid 328.136045 -41.838421)
						(end 328.099674 -41.896284)
					)
					(arc
						(start 327.994518 -41.896284)
						(mid 328.064187 -41.766563)
						(end 328.193908 -41.696894)
					)
				)
			)
		)
		(zone
			(layer "F.Cu")
			(hatch none 0.5)
			(connect_pads
				(clearance 0)
			)
			(min_thickness 0.25)
			(keepout
				(tracks not_allowed)
				(vias allowed)
				(pads allowed)
				(copperpour not_allowed)
				(footprints allowed)
			)
			(placement
				(enabled no)
				(sheetname "")
			)
			(fill
				(thermal_gap 0.5)
				(thermal_bridge_width 0.5)
				(island_removal_mode 0)
			)
			(polygon
				(pts
					(arc
						(start 328.193908 -40.801544)
						(mid 328.136045 -40.837915)
						(end 328.099674 -40.895778)
					)
					(arc
						(start 327.994518 -40.895778)
						(mid 328.064187 -40.766057)
						(end 328.193908 -40.696388)
					)
				)
			)
		)
		(zone
			(layer "F.Cu")
			(hatch none 0.5)
			(connect_pads
				(clearance 0)
			)
			(min_thickness 0.25)
			(keepout
				(tracks not_allowed)
				(vias allowed)
				(pads allowed)
				(copperpour not_allowed)
				(footprints allowed)
			)
			(placement
				(enabled no)
				(sheetname "")
			)
			(fill
				(thermal_gap 0.5)
				(thermal_bridge_width 0.5)
				(island_removal_mode 0)
			)
			(polygon
				(pts
					(arc
						(start 328.193908 -39.801038)
						(mid 328.136045 -39.837409)
						(end 328.099674 -39.895272)
					)
					(arc
						(start 327.994518 -39.895272)
						(mid 328.064187 -39.765551)
						(end 328.193908 -39.695882)
					)
				)
			)
		)
		(zone
			(layer "F.Cu")
			(hatch none 0.5)
			(connect_pads
				(clearance 0)
			)
			(min_thickness 0.25)
			(keepout
				(tracks not_allowed)
				(vias allowed)
				(pads allowed)
				(copperpour not_allowed)
				(footprints allowed)
			)
			(placement
				(enabled no)
				(sheetname "")
			)
			(fill
				(thermal_gap 0.5)
				(thermal_bridge_width 0.5)
				(island_removal_mode 0)
			)
			(polygon
				(pts
					(arc
						(start 328.25055 -58.901076)
						(mid 328.286921 -58.958939)
						(end 328.344784 -58.99531)
					)
					(arc
						(start 328.344784 -59.100466)
						(mid 328.215063 -59.030797)
						(end 328.145394 -58.901076)
					)
				)
			)
		)
		(zone
			(layer "F.Cu")
			(hatch none 0.5)
			(connect_pads
				(clearance 0)
			)
			(min_thickness 0.25)
			(keepout
				(tracks not_allowed)
				(vias allowed)
				(pads allowed)
				(copperpour not_allowed)
				(footprints allowed)
			)
			(placement
				(enabled no)
				(sheetname "")
			)
			(fill
				(thermal_gap 0.5)
				(thermal_bridge_width 0.5)
				(island_removal_mode 0)
			)
			(polygon
				(pts
					(arc
						(start 328.25055 -58.071004)
						(mid 328.286921 -58.128867)
						(end 328.344784 -58.165238)
					)
					(arc
						(start 328.344784 -58.270394)
						(mid 328.214933 -58.200777)
						(end 328.14514 -58.071004)
					)
				)
			)
		)
		(zone
			(layer "F.Cu")
			(hatch none 0.5)
			(connect_pads
				(clearance 0)
			)
			(min_thickness 0.25)
			(keepout
				(tracks not_allowed)
				(vias allowed)
				(pads allowed)
				(copperpour not_allowed)
				(footprints allowed)
			)
			(placement
				(enabled no)
				(sheetname "")
			)
			(fill
				(thermal_gap 0.5)
				(thermal_bridge_width 0.5)
				(island_removal_mode 0)
			)
			(polygon
				(pts
					(arc
						(start 328.25055 -38.931088)
						(mid 328.286921 -38.988951)
						(end 328.344784 -39.025322)
					)
					(arc
						(start 328.344784 -39.130478)
						(mid 328.214933 -39.060861)
						(end 328.14514 -38.931088)
					)
				)
			)
		)
		(zone
			(layer "F.Cu")
			(hatch none 0.5)
			(connect_pads
				(clearance 0)
			)
			(min_thickness 0.25)
			(keepout
				(tracks not_allowed)
				(vias allowed)
				(pads allowed)
				(copperpour not_allowed)
				(footprints allowed)
			)
			(placement
				(enabled no)
				(sheetname "")
			)
			(fill
				(thermal_gap 0.5)
				(thermal_bridge_width 0.5)
				(island_removal_mode 0)
			)
			(polygon
				(pts
					(arc
						(start 328.25055 -38.101016)
						(mid 328.286921 -38.158879)
						(end 328.344784 -38.19525)
					)
					(arc
						(start 328.344784 -38.300406)
						(mid 328.214933 -38.230789)
						(end 328.14514 -38.101016)
					)
				)
			)
		)
		(zone
			(layer "F.Cu")
			(hatch none 0.5)
			(connect_pads
				(clearance 0)
			)
			(min_thickness 0.25)
			(keepout
				(tracks not_allowed)
				(vias allowed)
				(pads allowed)
				(copperpour not_allowed)
				(footprints allowed)
			)
			(placement
				(enabled no)
				(sheetname "")
			)
			(fill
				(thermal_gap 0.5)
				(thermal_bridge_width 0.5)
				(island_removal_mode 0)
			)
			(polygon
				(pts
					(arc
						(start 328.295508 -57.099454)
						(mid 328.353371 -57.063083)
						(end 328.389742 -57.00522)
					)
					(arc
						(start 328.494898 -57.00522)
						(mid 328.425229 -57.134941)
						(end 328.295508 -57.20461)
					)
				)
			)
		)
		(zone
			(layer "F.Cu")
			(hatch none 0.5)
			(connect_pads
				(clearance 0)
			)
			(min_thickness 0.25)
			(keepout
				(tracks not_allowed)
				(vias allowed)
				(pads allowed)
				(copperpour not_allowed)
				(footprints allowed)
			)
			(placement
				(enabled no)
				(sheetname "")
			)
			(fill
				(thermal_gap 0.5)
				(thermal_bridge_width 0.5)
				(island_removal_mode 0)
			)
			(polygon
				(pts
					(arc
						(start 328.295508 -56.098948)
						(mid 328.353371 -56.062577)
						(end 328.389742 -56.004714)
					)
					(arc
						(start 328.494898 -56.004714)
						(mid 328.425229 -56.134435)
						(end 328.295508 -56.204104)
					)
				)
			)
		)
		(zone
			(layer "F.Cu")
			(hatch none 0.5)
			(connect_pads
				(clearance 0)
			)
			(min_thickness 0.25)
			(keepout
				(tracks not_allowed)
				(vias allowed)
				(pads allowed)
				(copperpour not_allowed)
				(footprints allowed)
			)
			(placement
				(enabled no)
				(sheetname "")
			)
			(fill
				(thermal_gap 0.5)
				(thermal_bridge_width 0.5)
				(island_removal_mode 0)
			)
			(polygon
				(pts
					(arc
						(start 328.295508 -55.098442)
						(mid 328.353371 -55.062071)
						(end 328.389742 -55.004208)
					)
					(arc
						(start 328.494898 -55.004208)
						(mid 328.425229 -55.133929)
						(end 328.295508 -55.203598)
					)
				)
			)
		)
		(zone
			(layer "F.Cu")
			(hatch none 0.5)
			(connect_pads
				(clearance 0)
			)
			(min_thickness 0.25)
			(keepout
				(tracks not_allowed)
				(vias allowed)
				(pads allowed)
				(copperpour not_allowed)
				(footprints allowed)
			)
			(placement
				(enabled no)
				(sheetname "")
			)
			(fill
				(thermal_gap 0.5)
				(thermal_bridge_width 0.5)
				(island_removal_mode 0)
			)
			(polygon
				(pts
					(arc
						(start 328.295508 -54.097936)
						(mid 328.353371 -54.061565)
						(end 328.389742 -54.003702)
					)
					(arc
						(start 328.494898 -54.003702)
						(mid 328.425229 -54.133423)
						(end 328.295508 -54.203092)
					)
				)
			)
		)
		(zone
			(layer "F.Cu")
			(hatch none 0.5)
			(connect_pads
				(clearance 0)
			)
			(min_thickness 0.25)
			(keepout
				(tracks not_allowed)
				(vias allowed)
				(pads allowed)
				(copperpour not_allowed)
				(footprints allowed)
			)
			(placement
				(enabled no)
				(sheetname "")
			)
			(fill
				(thermal_gap 0.5)
				(thermal_bridge_width 0.5)
				(island_removal_mode 0)
			)
			(polygon
				(pts
					(arc
						(start 328.295508 -53.09743)
						(mid 328.353371 -53.061059)
						(end 328.389742 -53.003196)
					)
					(arc
						(start 328.494898 -53.003196)
						(mid 328.425229 -53.132917)
						(end 328.295508 -53.202586)
					)
				)
			)
		)
		(zone
			(layer "F.Cu")
			(hatch none 0.5)
			(connect_pads
				(clearance 0)
			)
			(min_thickness 0.25)
			(keepout
				(tracks not_allowed)
				(vias allowed)
				(pads allowed)
				(copperpour not_allowed)
				(footprints allowed)
			)
			(placement
				(enabled no)
				(sheetname "")
			)
			(fill
				(thermal_gap 0.5)
				(thermal_bridge_width 0.5)
				(island_removal_mode 0)
			)
			(polygon
				(pts
					(arc
						(start 328.295508 -52.096924)
						(mid 328.353371 -52.060553)
						(end 328.389742 -52.00269)
					)
					(arc
						(start 328.494898 -52.00269)
						(mid 328.425229 -52.132411)
						(end 328.295508 -52.20208)
					)
				)
			)
		)
		(zone
			(layer "F.Cu")
			(hatch none 0.5)
			(connect_pads
				(clearance 0)
			)
			(min_thickness 0.25)
			(keepout
				(tracks not_allowed)
				(vias allowed)
				(pads allowed)
				(copperpour not_allowed)
				(footprints allowed)
			)
			(placement
				(enabled no)
				(sheetname "")
			)
			(fill
				(thermal_gap 0.5)
				(thermal_bridge_width 0.5)
				(island_removal_mode 0)
			)
			(polygon
				(pts
					(arc
						(start 328.295508 -51.096672)
						(mid 328.353371 -51.060301)
						(end 328.389742 -51.002438)
					)
					(arc
						(start 328.494898 -51.002438)
						(mid 328.425229 -51.132159)
						(end 328.295508 -51.201828)
					)
				)
			)
		)
		(zone
			(layer "F.Cu")
			(hatch none 0.5)
			(connect_pads
				(clearance 0)
			)
			(min_thickness 0.25)
			(keepout
				(tracks not_allowed)
				(vias allowed)
				(pads allowed)
				(copperpour not_allowed)
				(footprints allowed)
			)
			(placement
				(enabled no)
				(sheetname "")
			)
			(fill
				(thermal_gap 0.5)
				(thermal_bridge_width 0.5)
				(island_removal_mode 0)
			)
			(polygon
				(pts
					(arc
						(start 328.295508 -50.096166)
						(mid 328.353371 -50.059795)
						(end 328.389742 -50.001932)
					)
					(arc
						(start 328.494898 -50.001932)
						(mid 328.425229 -50.131653)
						(end 328.295508 -50.201322)
					)
				)
			)
		)
		(zone
			(layer "F.Cu")
			(hatch none 0.5)
			(connect_pads
				(clearance 0)
			)
			(min_thickness 0.25)
			(keepout
				(tracks not_allowed)
				(vias allowed)
				(pads allowed)
				(copperpour not_allowed)
				(footprints allowed)
			)
			(placement
				(enabled no)
				(sheetname "")
			)
			(fill
				(thermal_gap 0.5)
				(thermal_bridge_width 0.5)
				(island_removal_mode 0)
			)
			(polygon
				(pts
					(arc
						(start 328.295508 -49.09566)
						(mid 328.353371 -49.059289)
						(end 328.389742 -49.001426)
					)
					(arc
						(start 328.494898 -49.001426)
						(mid 328.425229 -49.131147)
						(end 328.295508 -49.200816)
					)
				)
			)
		)
		(zone
			(layer "F.Cu")
			(hatch none 0.5)
			(connect_pads
				(clearance 0)
			)
			(min_thickness 0.25)
			(keepout
				(tracks not_allowed)
				(vias allowed)
				(pads allowed)
				(copperpour not_allowed)
				(footprints allowed)
			)
			(placement
				(enabled no)
				(sheetname "")
			)
			(fill
				(thermal_gap 0.5)
				(thermal_bridge_width 0.5)
				(island_removal_mode 0)
			)
			(polygon
				(pts
					(arc
						(start 328.295508 -48.095154)
						(mid 328.353371 -48.058783)
						(end 328.389742 -48.00092)
					)
					(arc
						(start 328.494898 -48.00092)
						(mid 328.425229 -48.130641)
						(end 328.295508 -48.20031)
					)
				)
			)
		)
		(zone
			(layer "F.Cu")
			(hatch none 0.5)
			(connect_pads
				(clearance 0)
			)
			(min_thickness 0.25)
			(keepout
				(tracks not_allowed)
				(vias allowed)
				(pads allowed)
				(copperpour not_allowed)
				(footprints allowed)
			)
			(placement
				(enabled no)
				(sheetname "")
			)
			(fill
				(thermal_gap 0.5)
				(thermal_bridge_width 0.5)
				(island_removal_mode 0)
			)
			(polygon
				(pts
					(arc
						(start 328.295508 -47.094648)
						(mid 328.353371 -47.058277)
						(end 328.389742 -47.000414)
					)
					(arc
						(start 328.494898 -47.000414)
						(mid 328.425229 -47.130135)
						(end 328.295508 -47.199804)
					)
				)
			)
		)
		(zone
			(layer "F.Cu")
			(hatch none 0.5)
			(connect_pads
				(clearance 0)
			)
			(min_thickness 0.25)
			(keepout
				(tracks not_allowed)
				(vias allowed)
				(pads allowed)
				(copperpour not_allowed)
				(footprints allowed)
			)
			(placement
				(enabled no)
				(sheetname "")
			)
			(fill
				(thermal_gap 0.5)
				(thermal_bridge_width 0.5)
				(island_removal_mode 0)
			)
			(polygon
				(pts
					(arc
						(start 328.295508 -46.094142)
						(mid 328.353371 -46.057771)
						(end 328.389742 -45.999908)
					)
					(arc
						(start 328.494898 -45.999908)
						(mid 328.425229 -46.129629)
						(end 328.295508 -46.199298)
					)
				)
			)
		)
		(zone
			(layer "F.Cu")
			(hatch none 0.5)
			(connect_pads
				(clearance 0)
			)
			(min_thickness 0.25)
			(keepout
				(tracks not_allowed)
				(vias allowed)
				(pads allowed)
				(copperpour not_allowed)
				(footprints allowed)
			)
			(placement
				(enabled no)
				(sheetname "")
			)
			(fill
				(thermal_gap 0.5)
				(thermal_bridge_width 0.5)
				(island_removal_mode 0)
			)
			(polygon
				(pts
					(arc
						(start 328.295508 -45.093636)
						(mid 328.353371 -45.057265)
						(end 328.389742 -44.999402)
					)
					(arc
						(start 328.494898 -44.999402)
						(mid 328.425229 -45.129123)
						(end 328.295508 -45.198792)
					)
				)
			)
		)
		(zone
			(layer "F.Cu")
			(hatch none 0.5)
			(connect_pads
				(clearance 0)
			)
			(min_thickness 0.25)
			(keepout
				(tracks not_allowed)
				(vias allowed)
				(pads allowed)
				(copperpour not_allowed)
				(footprints allowed)
			)
			(placement
				(enabled no)
				(sheetname "")
			)
			(fill
				(thermal_gap 0.5)
				(thermal_bridge_width 0.5)
				(island_removal_mode 0)
			)
			(polygon
				(pts
					(arc
						(start 328.295508 -44.09313)
						(mid 328.353371 -44.056759)
						(end 328.389742 -43.998896)
					)
					(arc
						(start 328.494898 -43.998896)
						(mid 328.425229 -44.128617)
						(end 328.295508 -44.198286)
					)
				)
			)
		)
		(zone
			(layer "F.Cu")
			(hatch none 0.5)
			(connect_pads
				(clearance 0)
			)
			(min_thickness 0.25)
			(keepout
				(tracks not_allowed)
				(vias allowed)
				(pads allowed)
				(copperpour not_allowed)
				(footprints allowed)
			)
			(placement
				(enabled no)
				(sheetname "")
			)
			(fill
				(thermal_gap 0.5)
				(thermal_bridge_width 0.5)
				(island_removal_mode 0)
			)
			(polygon
				(pts
					(arc
						(start 328.295508 -43.092624)
						(mid 328.353371 -43.056253)
						(end 328.389742 -42.99839)
					)
					(arc
						(start 328.494898 -42.99839)
						(mid 328.425229 -43.128111)
						(end 328.295508 -43.19778)
					)
				)
			)
		)
		(zone
			(layer "F.Cu")
			(hatch none 0.5)
			(connect_pads
				(clearance 0)
			)
			(min_thickness 0.25)
			(keepout
				(tracks not_allowed)
				(vias allowed)
				(pads allowed)
				(copperpour not_allowed)
				(footprints allowed)
			)
			(placement
				(enabled no)
				(sheetname "")
			)
			(fill
				(thermal_gap 0.5)
				(thermal_bridge_width 0.5)
				(island_removal_mode 0)
			)
			(polygon
				(pts
					(arc
						(start 328.295508 -42.092118)
						(mid 328.353371 -42.055747)
						(end 328.389742 -41.997884)
					)
					(arc
						(start 328.494898 -41.997884)
						(mid 328.425229 -42.127605)
						(end 328.295508 -42.197274)
					)
				)
			)
		)
		(zone
			(layer "F.Cu")
			(hatch none 0.5)
			(connect_pads
				(clearance 0)
			)
			(min_thickness 0.25)
			(keepout
				(tracks not_allowed)
				(vias allowed)
				(pads allowed)
				(copperpour not_allowed)
				(footprints allowed)
			)
			(placement
				(enabled no)
				(sheetname "")
			)
			(fill
				(thermal_gap 0.5)
				(thermal_bridge_width 0.5)
				(island_removal_mode 0)
			)
			(polygon
				(pts
					(arc
						(start 328.295508 -41.091612)
						(mid 328.353371 -41.055241)
						(end 328.389742 -40.997378)
					)
					(arc
						(start 328.494898 -40.997378)
						(mid 328.425229 -41.127099)
						(end 328.295508 -41.196768)
					)
				)
			)
		)
		(zone
			(layer "F.Cu")
			(hatch none 0.5)
			(connect_pads
				(clearance 0)
			)
			(min_thickness 0.25)
			(keepout
				(tracks not_allowed)
				(vias allowed)
				(pads allowed)
				(copperpour not_allowed)
				(footprints allowed)
			)
			(placement
				(enabled no)
				(sheetname "")
			)
			(fill
				(thermal_gap 0.5)
				(thermal_bridge_width 0.5)
				(island_removal_mode 0)
			)
			(polygon
				(pts
					(arc
						(start 328.295508 -40.091106)
						(mid 328.353371 -40.054735)
						(end 328.389742 -39.996872)
					)
					(arc
						(start 328.494898 -39.996872)
						(mid 328.425229 -40.126593)
						(end 328.295508 -40.196262)
					)
				)
			)
		)
		(zone
			(layer "F.Cu")
			(hatch none 0.5)
			(connect_pads
				(clearance 0)
			)
			(min_thickness 0.25)
			(keepout
				(tracks not_allowed)
				(vias allowed)
				(pads allowed)
				(copperpour not_allowed)
				(footprints allowed)
			)
			(placement
				(enabled no)
				(sheetname "")
			)
			(fill
				(thermal_gap 0.5)
				(thermal_bridge_width 0.5)
				(island_removal_mode 0)
			)
			(polygon
				(pts
					(arc
						(start 328.344784 -58.705242)
						(mid 328.286921 -58.741613)
						(end 328.25055 -58.799476)
					)
					(arc
						(start 328.145394 -58.799476)
						(mid 328.215063 -58.669755)
						(end 328.344784 -58.600086)
					)
				)
			)
		)
		(zone
			(layer "F.Cu")
			(hatch none 0.5)
			(connect_pads
				(clearance 0)
			)
			(min_thickness 0.25)
			(keepout
				(tracks not_allowed)
				(vias allowed)
				(pads allowed)
				(copperpour not_allowed)
				(footprints allowed)
			)
			(placement
				(enabled no)
				(sheetname "")
			)
			(fill
				(thermal_gap 0.5)
				(thermal_bridge_width 0.5)
				(island_removal_mode 0)
			)
			(polygon
				(pts
					(arc
						(start 328.344784 -57.87517)
						(mid 328.286921 -57.911541)
						(end 328.25055 -57.969404)
					)
					(arc
						(start 328.14514 -57.969404)
						(mid 328.214897 -57.839595)
						(end 328.344784 -57.770014)
					)
				)
			)
		)
		(zone
			(layer "F.Cu")
			(hatch none 0.5)
			(connect_pads
				(clearance 0)
			)
			(min_thickness 0.25)
			(keepout
				(tracks not_allowed)
				(vias allowed)
				(pads allowed)
				(copperpour not_allowed)
				(footprints allowed)
			)
			(placement
				(enabled no)
				(sheetname "")
			)
			(fill
				(thermal_gap 0.5)
				(thermal_bridge_width 0.5)
				(island_removal_mode 0)
			)
			(polygon
				(pts
					(arc
						(start 328.344784 -38.735254)
						(mid 328.286921 -38.771625)
						(end 328.25055 -38.829488)
					)
					(arc
						(start 328.14514 -38.829488)
						(mid 328.214897 -38.699679)
						(end 328.344784 -38.630098)
					)
				)
			)
		)
		(zone
			(layer "F.Cu")
			(hatch none 0.5)
			(connect_pads
				(clearance 0)
			)
			(min_thickness 0.25)
			(keepout
				(tracks not_allowed)
				(vias allowed)
				(pads allowed)
				(copperpour not_allowed)
				(footprints allowed)
			)
			(placement
				(enabled no)
				(sheetname "")
			)
			(fill
				(thermal_gap 0.5)
				(thermal_bridge_width 0.5)
				(island_removal_mode 0)
			)
			(polygon
				(pts
					(arc
						(start 328.344784 -37.905182)
						(mid 328.286921 -37.941553)
						(end 328.25055 -37.999416)
					)
					(arc
						(start 328.14514 -37.999416)
						(mid 328.214897 -37.869607)
						(end 328.344784 -37.800026)
					)
				)
			)
		)
		(zone
			(layer "F.Cu")
			(hatch none 0.5)
			(connect_pads
				(clearance 0)
			)
			(min_thickness 0.25)
			(keepout
				(tracks not_allowed)
				(vias allowed)
				(pads allowed)
				(copperpour not_allowed)
				(footprints allowed)
			)
			(placement
				(enabled no)
				(sheetname "")
			)
			(fill
				(thermal_gap 0.5)
				(thermal_bridge_width 0.5)
				(island_removal_mode 0)
			)
			(polygon
				(pts
					(arc
						(start 328.389742 -56.90362)
						(mid 328.353371 -56.845757)
						(end 328.295508 -56.809386)
					)
					(arc
						(start 328.295508 -56.70423)
						(mid 328.425229 -56.773899)
						(end 328.494898 -56.90362)
					)
				)
			)
		)
		(zone
			(layer "F.Cu")
			(hatch none 0.5)
			(connect_pads
				(clearance 0)
			)
			(min_thickness 0.25)
			(keepout
				(tracks not_allowed)
				(vias allowed)
				(pads allowed)
				(copperpour not_allowed)
				(footprints allowed)
			)
			(placement
				(enabled no)
				(sheetname "")
			)
			(fill
				(thermal_gap 0.5)
				(thermal_bridge_width 0.5)
				(island_removal_mode 0)
			)
			(polygon
				(pts
					(arc
						(start 328.389742 -55.903114)
						(mid 328.353371 -55.845251)
						(end 328.295508 -55.80888)
					)
					(arc
						(start 328.295508 -55.703724)
						(mid 328.425229 -55.773393)
						(end 328.494898 -55.903114)
					)
				)
			)
		)
		(zone
			(layer "F.Cu")
			(hatch none 0.5)
			(connect_pads
				(clearance 0)
			)
			(min_thickness 0.25)
			(keepout
				(tracks not_allowed)
				(vias allowed)
				(pads allowed)
				(copperpour not_allowed)
				(footprints allowed)
			)
			(placement
				(enabled no)
				(sheetname "")
			)
			(fill
				(thermal_gap 0.5)
				(thermal_bridge_width 0.5)
				(island_removal_mode 0)
			)
			(polygon
				(pts
					(arc
						(start 328.389742 -54.902608)
						(mid 328.353371 -54.844745)
						(end 328.295508 -54.808374)
					)
					(arc
						(start 328.295508 -54.703218)
						(mid 328.425229 -54.772887)
						(end 328.494898 -54.902608)
					)
				)
			)
		)
		(zone
			(layer "F.Cu")
			(hatch none 0.5)
			(connect_pads
				(clearance 0)
			)
			(min_thickness 0.25)
			(keepout
				(tracks not_allowed)
				(vias allowed)
				(pads allowed)
				(copperpour not_allowed)
				(footprints allowed)
			)
			(placement
				(enabled no)
				(sheetname "")
			)
			(fill
				(thermal_gap 0.5)
				(thermal_bridge_width 0.5)
				(island_removal_mode 0)
			)
			(polygon
				(pts
					(arc
						(start 328.389742 -53.902102)
						(mid 328.353371 -53.844239)
						(end 328.295508 -53.807868)
					)
					(arc
						(start 328.295508 -53.702712)
						(mid 328.425229 -53.772381)
						(end 328.494898 -53.902102)
					)
				)
			)
		)
		(zone
			(layer "F.Cu")
			(hatch none 0.5)
			(connect_pads
				(clearance 0)
			)
			(min_thickness 0.25)
			(keepout
				(tracks not_allowed)
				(vias allowed)
				(pads allowed)
				(copperpour not_allowed)
				(footprints allowed)
			)
			(placement
				(enabled no)
				(sheetname "")
			)
			(fill
				(thermal_gap 0.5)
				(thermal_bridge_width 0.5)
				(island_removal_mode 0)
			)
			(polygon
				(pts
					(arc
						(start 328.389742 -52.901596)
						(mid 328.353371 -52.843733)
						(end 328.295508 -52.807362)
					)
					(arc
						(start 328.295508 -52.702206)
						(mid 328.425229 -52.771875)
						(end 328.494898 -52.901596)
					)
				)
			)
		)
		(zone
			(layer "F.Cu")
			(hatch none 0.5)
			(connect_pads
				(clearance 0)
			)
			(min_thickness 0.25)
			(keepout
				(tracks not_allowed)
				(vias allowed)
				(pads allowed)
				(copperpour not_allowed)
				(footprints allowed)
			)
			(placement
				(enabled no)
				(sheetname "")
			)
			(fill
				(thermal_gap 0.5)
				(thermal_bridge_width 0.5)
				(island_removal_mode 0)
			)
			(polygon
				(pts
					(arc
						(start 328.389742 -51.90109)
						(mid 328.353371 -51.843227)
						(end 328.295508 -51.806856)
					)
					(arc
						(start 328.295508 -51.7017)
						(mid 328.425229 -51.771369)
						(end 328.494898 -51.90109)
					)
				)
			)
		)
		(zone
			(layer "F.Cu")
			(hatch none 0.5)
			(connect_pads
				(clearance 0)
			)
			(min_thickness 0.25)
			(keepout
				(tracks not_allowed)
				(vias allowed)
				(pads allowed)
				(copperpour not_allowed)
				(footprints allowed)
			)
			(placement
				(enabled no)
				(sheetname "")
			)
			(fill
				(thermal_gap 0.5)
				(thermal_bridge_width 0.5)
				(island_removal_mode 0)
			)
			(polygon
				(pts
					(arc
						(start 328.389742 -50.900838)
						(mid 328.353371 -50.842975)
						(end 328.295508 -50.806604)
					)
					(arc
						(start 328.295508 -50.701448)
						(mid 328.425229 -50.771117)
						(end 328.494898 -50.900838)
					)
				)
			)
		)
		(zone
			(layer "F.Cu")
			(hatch none 0.5)
			(connect_pads
				(clearance 0)
			)
			(min_thickness 0.25)
			(keepout
				(tracks not_allowed)
				(vias allowed)
				(pads allowed)
				(copperpour not_allowed)
				(footprints allowed)
			)
			(placement
				(enabled no)
				(sheetname "")
			)
			(fill
				(thermal_gap 0.5)
				(thermal_bridge_width 0.5)
				(island_removal_mode 0)
			)
			(polygon
				(pts
					(arc
						(start 328.389742 -49.900332)
						(mid 328.353371 -49.842469)
						(end 328.295508 -49.806098)
					)
					(arc
						(start 328.295508 -49.700942)
						(mid 328.425229 -49.770611)
						(end 328.494898 -49.900332)
					)
				)
			)
		)
		(zone
			(layer "F.Cu")
			(hatch none 0.5)
			(connect_pads
				(clearance 0)
			)
			(min_thickness 0.25)
			(keepout
				(tracks not_allowed)
				(vias allowed)
				(pads allowed)
				(copperpour not_allowed)
				(footprints allowed)
			)
			(placement
				(enabled no)
				(sheetname "")
			)
			(fill
				(thermal_gap 0.5)
				(thermal_bridge_width 0.5)
				(island_removal_mode 0)
			)
			(polygon
				(pts
					(arc
						(start 328.389742 -48.899826)
						(mid 328.353371 -48.841963)
						(end 328.295508 -48.805592)
					)
					(arc
						(start 328.295508 -48.700436)
						(mid 328.425229 -48.770105)
						(end 328.494898 -48.899826)
					)
				)
			)
		)
		(zone
			(layer "F.Cu")
			(hatch none 0.5)
			(connect_pads
				(clearance 0)
			)
			(min_thickness 0.25)
			(keepout
				(tracks not_allowed)
				(vias allowed)
				(pads allowed)
				(copperpour not_allowed)
				(footprints allowed)
			)
			(placement
				(enabled no)
				(sheetname "")
			)
			(fill
				(thermal_gap 0.5)
				(thermal_bridge_width 0.5)
				(island_removal_mode 0)
			)
			(polygon
				(pts
					(arc
						(start 328.389742 -47.89932)
						(mid 328.353371 -47.841457)
						(end 328.295508 -47.805086)
					)
					(arc
						(start 328.295508 -47.69993)
						(mid 328.425229 -47.769599)
						(end 328.494898 -47.89932)
					)
				)
			)
		)
		(zone
			(layer "F.Cu")
			(hatch none 0.5)
			(connect_pads
				(clearance 0)
			)
			(min_thickness 0.25)
			(keepout
				(tracks not_allowed)
				(vias allowed)
				(pads allowed)
				(copperpour not_allowed)
				(footprints allowed)
			)
			(placement
				(enabled no)
				(sheetname "")
			)
			(fill
				(thermal_gap 0.5)
				(thermal_bridge_width 0.5)
				(island_removal_mode 0)
			)
			(polygon
				(pts
					(arc
						(start 328.389742 -46.898814)
						(mid 328.353371 -46.840951)
						(end 328.295508 -46.80458)
					)
					(arc
						(start 328.295508 -46.699424)
						(mid 328.425229 -46.769093)
						(end 328.494898 -46.898814)
					)
				)
			)
		)
		(zone
			(layer "F.Cu")
			(hatch none 0.5)
			(connect_pads
				(clearance 0)
			)
			(min_thickness 0.25)
			(keepout
				(tracks not_allowed)
				(vias allowed)
				(pads allowed)
				(copperpour not_allowed)
				(footprints allowed)
			)
			(placement
				(enabled no)
				(sheetname "")
			)
			(fill
				(thermal_gap 0.5)
				(thermal_bridge_width 0.5)
				(island_removal_mode 0)
			)
			(polygon
				(pts
					(arc
						(start 328.389742 -45.898308)
						(mid 328.353371 -45.840445)
						(end 328.295508 -45.804074)
					)
					(arc
						(start 328.295508 -45.698918)
						(mid 328.425229 -45.768587)
						(end 328.494898 -45.898308)
					)
				)
			)
		)
		(zone
			(layer "F.Cu")
			(hatch none 0.5)
			(connect_pads
				(clearance 0)
			)
			(min_thickness 0.25)
			(keepout
				(tracks not_allowed)
				(vias allowed)
				(pads allowed)
				(copperpour not_allowed)
				(footprints allowed)
			)
			(placement
				(enabled no)
				(sheetname "")
			)
			(fill
				(thermal_gap 0.5)
				(thermal_bridge_width 0.5)
				(island_removal_mode 0)
			)
			(polygon
				(pts
					(arc
						(start 328.389742 -44.897802)
						(mid 328.353371 -44.839939)
						(end 328.295508 -44.803568)
					)
					(arc
						(start 328.295508 -44.698412)
						(mid 328.425229 -44.768081)
						(end 328.494898 -44.897802)
					)
				)
			)
		)
		(zone
			(layer "F.Cu")
			(hatch none 0.5)
			(connect_pads
				(clearance 0)
			)
			(min_thickness 0.25)
			(keepout
				(tracks not_allowed)
				(vias allowed)
				(pads allowed)
				(copperpour not_allowed)
				(footprints allowed)
			)
			(placement
				(enabled no)
				(sheetname "")
			)
			(fill
				(thermal_gap 0.5)
				(thermal_bridge_width 0.5)
				(island_removal_mode 0)
			)
			(polygon
				(pts
					(arc
						(start 328.389742 -43.897296)
						(mid 328.353371 -43.839433)
						(end 328.295508 -43.803062)
					)
					(arc
						(start 328.295508 -43.697906)
						(mid 328.425229 -43.767575)
						(end 328.494898 -43.897296)
					)
				)
			)
		)
		(zone
			(layer "F.Cu")
			(hatch none 0.5)
			(connect_pads
				(clearance 0)
			)
			(min_thickness 0.25)
			(keepout
				(tracks not_allowed)
				(vias allowed)
				(pads allowed)
				(copperpour not_allowed)
				(footprints allowed)
			)
			(placement
				(enabled no)
				(sheetname "")
			)
			(fill
				(thermal_gap 0.5)
				(thermal_bridge_width 0.5)
				(island_removal_mode 0)
			)
			(polygon
				(pts
					(arc
						(start 328.389742 -42.89679)
						(mid 328.353371 -42.838927)
						(end 328.295508 -42.802556)
					)
					(arc
						(start 328.295508 -42.6974)
						(mid 328.425229 -42.767069)
						(end 328.494898 -42.89679)
					)
				)
			)
		)
		(zone
			(layer "F.Cu")
			(hatch none 0.5)
			(connect_pads
				(clearance 0)
			)
			(min_thickness 0.25)
			(keepout
				(tracks not_allowed)
				(vias allowed)
				(pads allowed)
				(copperpour not_allowed)
				(footprints allowed)
			)
			(placement
				(enabled no)
				(sheetname "")
			)
			(fill
				(thermal_gap 0.5)
				(thermal_bridge_width 0.5)
				(island_removal_mode 0)
			)
			(polygon
				(pts
					(arc
						(start 328.389742 -41.896284)
						(mid 328.353371 -41.838421)
						(end 328.295508 -41.80205)
					)
					(arc
						(start 328.295508 -41.696894)
						(mid 328.425229 -41.766563)
						(end 328.494898 -41.896284)
					)
				)
			)
		)
		(zone
			(layer "F.Cu")
			(hatch none 0.5)
			(connect_pads
				(clearance 0)
			)
			(min_thickness 0.25)
			(keepout
				(tracks not_allowed)
				(vias allowed)
				(pads allowed)
				(copperpour not_allowed)
				(footprints allowed)
			)
			(placement
				(enabled no)
				(sheetname "")
			)
			(fill
				(thermal_gap 0.5)
				(thermal_bridge_width 0.5)
				(island_removal_mode 0)
			)
			(polygon
				(pts
					(arc
						(start 328.389742 -40.895778)
						(mid 328.353371 -40.837915)
						(end 328.295508 -40.801544)
					)
					(arc
						(start 328.295508 -40.696388)
						(mid 328.425229 -40.766057)
						(end 328.494898 -40.895778)
					)
				)
			)
		)
		(zone
			(layer "F.Cu")
			(hatch none 0.5)
			(connect_pads
				(clearance 0)
			)
			(min_thickness 0.25)
			(keepout
				(tracks not_allowed)
				(vias allowed)
				(pads allowed)
				(copperpour not_allowed)
				(footprints allowed)
			)
			(placement
				(enabled no)
				(sheetname "")
			)
			(fill
				(thermal_gap 0.5)
				(thermal_bridge_width 0.5)
				(island_removal_mode 0)
			)
			(polygon
				(pts
					(arc
						(start 328.389742 -39.895272)
						(mid 328.353371 -39.837409)
						(end 328.295508 -39.801038)
					)
					(arc
						(start 328.295508 -39.695882)
						(mid 328.425229 -39.765551)
						(end 328.494898 -39.895272)
					)
				)
			)
		)
		(zone
			(layer "F.Cu")
			(hatch none 0.5)
			(connect_pads
				(clearance 0)
			)
			(min_thickness 0.25)
			(keepout
				(tracks not_allowed)
				(vias allowed)
				(pads allowed)
				(copperpour not_allowed)
				(footprints allowed)
			)
			(placement
				(enabled no)
				(sheetname "")
			)
			(fill
				(thermal_gap 0.5)
				(thermal_bridge_width 0.5)
				(island_removal_mode 0)
			)
			(polygon
				(pts
					(arc
						(start 328.446384 -58.99531)
						(mid 328.504247 -58.958939)
						(end 328.540618 -58.901076)
					)
					(arc
						(start 328.645774 -58.901076)
						(mid 328.576105 -59.030797)
						(end 328.446384 -59.100466)
					)
				)
			)
		)
		(zone
			(layer "F.Cu")
			(hatch none 0.5)
			(connect_pads
				(clearance 0)
			)
			(min_thickness 0.25)
			(keepout
				(tracks not_allowed)
				(vias allowed)
				(pads allowed)
				(copperpour not_allowed)
				(footprints allowed)
			)
			(placement
				(enabled no)
				(sheetname "")
			)
			(fill
				(thermal_gap 0.5)
				(thermal_bridge_width 0.5)
				(island_removal_mode 0)
			)
			(polygon
				(pts
					(arc
						(start 328.446384 -58.165238)
						(mid 328.504138 -58.128842)
						(end 328.540364 -58.071004)
					)
					(arc
						(start 328.645774 -58.071004)
						(mid 328.576105 -58.200725)
						(end 328.446384 -58.270394)
					)
				)
			)
		)
		(zone
			(layer "F.Cu")
			(hatch none 0.5)
			(connect_pads
				(clearance 0)
			)
			(min_thickness 0.25)
			(keepout
				(tracks not_allowed)
				(vias allowed)
				(pads allowed)
				(copperpour not_allowed)
				(footprints allowed)
			)
			(placement
				(enabled no)
				(sheetname "")
			)
			(fill
				(thermal_gap 0.5)
				(thermal_bridge_width 0.5)
				(island_removal_mode 0)
			)
			(polygon
				(pts
					(arc
						(start 328.446384 -39.025322)
						(mid 328.504083 -38.988896)
						(end 328.540364 -38.931088)
					)
					(arc
						(start 328.645774 -38.931088)
						(mid 328.576105 -39.060809)
						(end 328.446384 -39.130478)
					)
				)
			)
		)
		(zone
			(layer "F.Cu")
			(hatch none 0.5)
			(connect_pads
				(clearance 0)
			)
			(min_thickness 0.25)
			(keepout
				(tracks not_allowed)
				(vias allowed)
				(pads allowed)
				(copperpour not_allowed)
				(footprints allowed)
			)
			(placement
				(enabled no)
				(sheetname "")
			)
			(fill
				(thermal_gap 0.5)
				(thermal_bridge_width 0.5)
				(island_removal_mode 0)
			)
			(polygon
				(pts
					(arc
						(start 328.446384 -38.19525)
						(mid 328.504083 -38.158824)
						(end 328.540364 -38.101016)
					)
					(arc
						(start 328.645774 -38.101016)
						(mid 328.576105 -38.230737)
						(end 328.446384 -38.300406)
					)
				)
			)
		)
		(zone
			(layer "F.Cu")
			(hatch none 0.5)
			(connect_pads
				(clearance 0)
			)
			(min_thickness 0.25)
			(keepout
				(tracks not_allowed)
				(vias allowed)
				(pads allowed)
				(copperpour not_allowed)
				(footprints allowed)
			)
			(placement
				(enabled no)
				(sheetname "")
			)
			(fill
				(thermal_gap 0.5)
				(thermal_bridge_width 0.5)
				(island_removal_mode 0)
			)
			(polygon
				(pts
					(arc
						(start 328.540364 -57.969404)
						(mid 328.504133 -57.911545)
						(end 328.446384 -57.87517)
					)
					(arc
						(start 328.446384 -57.770014)
						(mid 328.576105 -57.839683)
						(end 328.645774 -57.969404)
					)
				)
			)
		)
		(zone
			(layer "F.Cu")
			(hatch none 0.5)
			(connect_pads
				(clearance 0)
			)
			(min_thickness 0.25)
			(keepout
				(tracks not_allowed)
				(vias allowed)
				(pads allowed)
				(copperpour not_allowed)
				(footprints allowed)
			)
			(placement
				(enabled no)
				(sheetname "")
			)
			(fill
				(thermal_gap 0.5)
				(thermal_bridge_width 0.5)
				(island_removal_mode 0)
			)
			(polygon
				(pts
					(arc
						(start 328.540364 -38.829488)
						(mid 328.504078 -38.771709)
						(end 328.446384 -38.735254)
					)
					(arc
						(start 328.446384 -38.630098)
						(mid 328.576105 -38.699767)
						(end 328.645774 -38.829488)
					)
				)
			)
		)
		(zone
			(layer "F.Cu")
			(hatch none 0.5)
			(connect_pads
				(clearance 0)
			)
			(min_thickness 0.25)
			(keepout
				(tracks not_allowed)
				(vias allowed)
				(pads allowed)
				(copperpour not_allowed)
				(footprints allowed)
			)
			(placement
				(enabled no)
				(sheetname "")
			)
			(fill
				(thermal_gap 0.5)
				(thermal_bridge_width 0.5)
				(island_removal_mode 0)
			)
			(polygon
				(pts
					(arc
						(start 328.540364 -37.999416)
						(mid 328.504078 -37.941637)
						(end 328.446384 -37.905182)
					)
					(arc
						(start 328.446384 -37.800026)
						(mid 328.576105 -37.869695)
						(end 328.645774 -37.999416)
					)
				)
			)
		)
		(zone
			(layer "F.Cu")
			(hatch none 0.5)
			(connect_pads
				(clearance 0)
			)
			(min_thickness 0.25)
			(keepout
				(tracks not_allowed)
				(vias allowed)
				(pads allowed)
				(copperpour not_allowed)
				(footprints allowed)
			)
			(placement
				(enabled no)
				(sheetname "")
			)
			(fill
				(thermal_gap 0.5)
				(thermal_bridge_width 0.5)
				(island_removal_mode 0)
			)
			(polygon
				(pts
					(arc
						(start 328.540618 -58.799476)
						(mid 328.504247 -58.741613)
						(end 328.446384 -58.705242)
					)
					(arc
						(start 328.446384 -58.600086)
						(mid 328.576105 -58.669755)
						(end 328.645774 -58.799476)
					)
				)
			)
		)
		(zone
			(layer "F.Cu")
			(hatch none 0.5)
			(connect_pads
				(clearance 0)
			)
			(min_thickness 0.25)
			(keepout
				(tracks not_allowed)
				(vias allowed)
				(pads allowed)
				(copperpour not_allowed)
				(footprints allowed)
			)
			(placement
				(enabled no)
				(sheetname "")
			)
			(fill
				(thermal_gap 0.5)
				(thermal_bridge_width 0.5)
				(island_removal_mode 0)
			)
			(polygon
				(pts
					(arc
						(start 328.750676 -58.48604)
						(mid 328.787072 -58.543794)
						(end 328.84491 -58.58002)
					)
					(arc
						(start 328.84491 -58.68543)
						(mid 328.715189 -58.615761)
						(end 328.64552 -58.48604)
					)
				)
			)
		)
		(zone
			(layer "F.Cu")
			(hatch none 0.5)
			(connect_pads
				(clearance 0)
			)
			(min_thickness 0.25)
			(keepout
				(tracks not_allowed)
				(vias allowed)
				(pads allowed)
				(copperpour not_allowed)
				(footprints allowed)
			)
			(placement
				(enabled no)
				(sheetname "")
			)
			(fill
				(thermal_gap 0.5)
				(thermal_bridge_width 0.5)
				(island_removal_mode 0)
			)
			(polygon
				(pts
					(arc
						(start 328.750676 -57.655968)
						(mid 328.787047 -57.713831)
						(end 328.84491 -57.750202)
					)
					(arc
						(start 328.84491 -57.855358)
						(mid 328.715189 -57.785689)
						(end 328.64552 -57.655968)
					)
				)
			)
		)
		(zone
			(layer "F.Cu")
			(hatch none 0.5)
			(connect_pads
				(clearance 0)
			)
			(min_thickness 0.25)
			(keepout
				(tracks not_allowed)
				(vias allowed)
				(pads allowed)
				(copperpour not_allowed)
				(footprints allowed)
			)
			(placement
				(enabled no)
				(sheetname "")
			)
			(fill
				(thermal_gap 0.5)
				(thermal_bridge_width 0.5)
				(island_removal_mode 0)
			)
			(polygon
				(pts
					(arc
						(start 328.750676 -38.516052)
						(mid 328.787047 -38.573915)
						(end 328.84491 -38.610286)
					)
					(arc
						(start 328.84491 -38.715442)
						(mid 328.715189 -38.645773)
						(end 328.64552 -38.516052)
					)
				)
			)
		)
		(zone
			(layer "F.Cu")
			(hatch none 0.5)
			(connect_pads
				(clearance 0)
			)
			(min_thickness 0.25)
			(keepout
				(tracks not_allowed)
				(vias allowed)
				(pads allowed)
				(copperpour not_allowed)
				(footprints allowed)
			)
			(placement
				(enabled no)
				(sheetname "")
			)
			(fill
				(thermal_gap 0.5)
				(thermal_bridge_width 0.5)
				(island_removal_mode 0)
			)
			(polygon
				(pts
					(arc
						(start 328.750676 -37.68598)
						(mid 328.787047 -37.743843)
						(end 328.84491 -37.780214)
					)
					(arc
						(start 328.84491 -37.88537)
						(mid 328.715189 -37.815701)
						(end 328.64552 -37.68598)
					)
				)
			)
		)
		(zone
			(layer "F.Cu")
			(hatch none 0.5)
			(connect_pads
				(clearance 0)
			)
			(min_thickness 0.25)
			(keepout
				(tracks not_allowed)
				(vias allowed)
				(pads allowed)
				(copperpour not_allowed)
				(footprints allowed)
			)
			(placement
				(enabled no)
				(sheetname "")
			)
			(fill
				(thermal_gap 0.5)
				(thermal_bridge_width 0.5)
				(island_removal_mode 0)
			)
			(polygon
				(pts
					(arc
						(start 328.75093 -39.346124)
						(mid 328.787301 -39.403987)
						(end 328.845164 -39.440358)
					)
					(arc
						(start 328.845164 -39.545514)
						(mid 328.715443 -39.475845)
						(end 328.645774 -39.346124)
					)
				)
			)
		)
		(zone
			(layer "F.Cu")
			(hatch none 0.5)
			(connect_pads
				(clearance 0)
			)
			(min_thickness 0.25)
			(keepout
				(tracks not_allowed)
				(vias allowed)
				(pads allowed)
				(copperpour not_allowed)
				(footprints allowed)
			)
			(placement
				(enabled no)
				(sheetname "")
			)
			(fill
				(thermal_gap 0.5)
				(thermal_bridge_width 0.5)
				(island_removal_mode 0)
			)
			(polygon
				(pts
					(arc
						(start 328.84491 -58.290206)
						(mid 328.787047 -58.326577)
						(end 328.750676 -58.38444)
					)
					(arc
						(start 328.64552 -58.38444)
						(mid 328.715189 -58.254719)
						(end 328.84491 -58.18505)
					)
				)
			)
		)
		(zone
			(layer "F.Cu")
			(hatch none 0.5)
			(connect_pads
				(clearance 0)
			)
			(min_thickness 0.25)
			(keepout
				(tracks not_allowed)
				(vias allowed)
				(pads allowed)
				(copperpour not_allowed)
				(footprints allowed)
			)
			(placement
				(enabled no)
				(sheetname "")
			)
			(fill
				(thermal_gap 0.5)
				(thermal_bridge_width 0.5)
				(island_removal_mode 0)
			)
			(polygon
				(pts
					(arc
						(start 328.84491 -57.460134)
						(mid 328.787047 -57.496505)
						(end 328.750676 -57.554368)
					)
					(arc
						(start 328.64552 -57.554368)
						(mid 328.715189 -57.424647)
						(end 328.84491 -57.354978)
					)
				)
			)
		)
		(zone
			(layer "F.Cu")
			(hatch none 0.5)
			(connect_pads
				(clearance 0)
			)
			(min_thickness 0.25)
			(keepout
				(tracks not_allowed)
				(vias allowed)
				(pads allowed)
				(copperpour not_allowed)
				(footprints allowed)
			)
			(placement
				(enabled no)
				(sheetname "")
			)
			(fill
				(thermal_gap 0.5)
				(thermal_bridge_width 0.5)
				(island_removal_mode 0)
			)
			(polygon
				(pts
					(arc
						(start 328.84491 -38.320472)
						(mid 328.787131 -38.356758)
						(end 328.750676 -38.414452)
					)
					(arc
						(start 328.64552 -38.414452)
						(mid 328.715189 -38.284731)
						(end 328.84491 -38.215062)
					)
				)
			)
		)
		(zone
			(layer "F.Cu")
			(hatch none 0.5)
			(connect_pads
				(clearance 0)
			)
			(min_thickness 0.25)
			(keepout
				(tracks not_allowed)
				(vias allowed)
				(pads allowed)
				(copperpour not_allowed)
				(footprints allowed)
			)
			(placement
				(enabled no)
				(sheetname "")
			)
			(fill
				(thermal_gap 0.5)
				(thermal_bridge_width 0.5)
				(island_removal_mode 0)
			)
			(polygon
				(pts
					(arc
						(start 328.84491 -37.490146)
						(mid 328.787047 -37.526517)
						(end 328.750676 -37.58438)
					)
					(arc
						(start 328.64552 -37.58438)
						(mid 328.715189 -37.454659)
						(end 328.84491 -37.38499)
					)
				)
			)
		)
		(zone
			(layer "F.Cu")
			(hatch none 0.5)
			(connect_pads
				(clearance 0)
			)
			(min_thickness 0.25)
			(keepout
				(tracks not_allowed)
				(vias allowed)
				(pads allowed)
				(copperpour not_allowed)
				(footprints allowed)
			)
			(placement
				(enabled no)
				(sheetname "")
			)
			(fill
				(thermal_gap 0.5)
				(thermal_bridge_width 0.5)
				(island_removal_mode 0)
			)
			(polygon
				(pts
					(arc
						(start 328.845164 -39.15029)
						(mid 328.787301 -39.186661)
						(end 328.75093 -39.244524)
					)
					(arc
						(start 328.645774 -39.244524)
						(mid 328.715443 -39.114803)
						(end 328.845164 -39.045134)
					)
				)
			)
		)
		(zone
			(layer "F.Cu")
			(hatch none 0.5)
			(connect_pads
				(clearance 0)
			)
			(min_thickness 0.25)
			(keepout
				(tracks not_allowed)
				(vias allowed)
				(pads allowed)
				(copperpour not_allowed)
				(footprints allowed)
			)
			(placement
				(enabled no)
				(sheetname "")
			)
			(fill
				(thermal_gap 0.5)
				(thermal_bridge_width 0.5)
				(island_removal_mode 0)
			)
			(polygon
				(pts
					(arc
						(start 328.94651 -58.58002)
						(mid 329.004369 -58.543789)
						(end 329.040744 -58.48604)
					)
					(arc
						(start 329.1459 -58.48604)
						(mid 329.076231 -58.615761)
						(end 328.94651 -58.68543)
					)
				)
			)
		)
		(zone
			(layer "F.Cu")
			(hatch none 0.5)
			(connect_pads
				(clearance 0)
			)
			(min_thickness 0.25)
			(keepout
				(tracks not_allowed)
				(vias allowed)
				(pads allowed)
				(copperpour not_allowed)
				(footprints allowed)
			)
			(placement
				(enabled no)
				(sheetname "")
			)
			(fill
				(thermal_gap 0.5)
				(thermal_bridge_width 0.5)
				(island_removal_mode 0)
			)
			(polygon
				(pts
					(arc
						(start 328.94651 -57.750202)
						(mid 329.004373 -57.713831)
						(end 329.040744 -57.655968)
					)
					(arc
						(start 329.1459 -57.655968)
						(mid 329.076231 -57.785689)
						(end 328.94651 -57.855358)
					)
				)
			)
		)
		(zone
			(layer "F.Cu")
			(hatch none 0.5)
			(connect_pads
				(clearance 0)
			)
			(min_thickness 0.25)
			(keepout
				(tracks not_allowed)
				(vias allowed)
				(pads allowed)
				(copperpour not_allowed)
				(footprints allowed)
			)
			(placement
				(enabled no)
				(sheetname "")
			)
			(fill
				(thermal_gap 0.5)
				(thermal_bridge_width 0.5)
				(island_removal_mode 0)
			)
			(polygon
				(pts
					(arc
						(start 328.94651 -38.610286)
						(mid 329.004373 -38.573915)
						(end 329.040744 -38.516052)
					)
					(arc
						(start 329.1459 -38.516052)
						(mid 329.076231 -38.645773)
						(end 328.94651 -38.715442)
					)
				)
			)
		)
		(zone
			(layer "F.Cu")
			(hatch none 0.5)
			(connect_pads
				(clearance 0)
			)
			(min_thickness 0.25)
			(keepout
				(tracks not_allowed)
				(vias allowed)
				(pads allowed)
				(copperpour not_allowed)
				(footprints allowed)
			)
			(placement
				(enabled no)
				(sheetname "")
			)
			(fill
				(thermal_gap 0.5)
				(thermal_bridge_width 0.5)
				(island_removal_mode 0)
			)
			(polygon
				(pts
					(arc
						(start 328.94651 -37.780214)
						(mid 329.004373 -37.743843)
						(end 329.040744 -37.68598)
					)
					(arc
						(start 329.1459 -37.68598)
						(mid 329.076231 -37.815701)
						(end 328.94651 -37.88537)
					)
				)
			)
		)
		(zone
			(layer "F.Cu")
			(hatch none 0.5)
			(connect_pads
				(clearance 0)
			)
			(min_thickness 0.25)
			(keepout
				(tracks not_allowed)
				(vias allowed)
				(pads allowed)
				(copperpour not_allowed)
				(footprints allowed)
			)
			(placement
				(enabled no)
				(sheetname "")
			)
			(fill
				(thermal_gap 0.5)
				(thermal_bridge_width 0.5)
				(island_removal_mode 0)
			)
			(polygon
				(pts
					(arc
						(start 328.946764 -39.440358)
						(mid 329.004463 -39.403932)
						(end 329.040744 -39.346124)
					)
					(arc
						(start 329.146154 -39.346124)
						(mid 329.076485 -39.475845)
						(end 328.946764 -39.545514)
					)
				)
			)
		)
		(zone
			(layer "F.Cu")
			(hatch none 0.5)
			(connect_pads
				(clearance 0)
			)
			(min_thickness 0.25)
			(keepout
				(tracks not_allowed)
				(vias allowed)
				(pads allowed)
				(copperpour not_allowed)
				(footprints allowed)
			)
			(placement
				(enabled no)
				(sheetname "")
			)
			(fill
				(thermal_gap 0.5)
				(thermal_bridge_width 0.5)
				(island_removal_mode 0)
			)
			(polygon
				(pts
					(arc
						(start 329.040744 -58.38444)
						(mid 329.004373 -58.326577)
						(end 328.94651 -58.290206)
					)
					(arc
						(start 328.94651 -58.18505)
						(mid 329.076231 -58.254719)
						(end 329.1459 -58.38444)
					)
				)
			)
		)
		(zone
			(layer "F.Cu")
			(hatch none 0.5)
			(connect_pads
				(clearance 0)
			)
			(min_thickness 0.25)
			(keepout
				(tracks not_allowed)
				(vias allowed)
				(pads allowed)
				(copperpour not_allowed)
				(footprints allowed)
			)
			(placement
				(enabled no)
				(sheetname "")
			)
			(fill
				(thermal_gap 0.5)
				(thermal_bridge_width 0.5)
				(island_removal_mode 0)
			)
			(polygon
				(pts
					(arc
						(start 329.040744 -57.554368)
						(mid 329.004373 -57.496505)
						(end 328.94651 -57.460134)
					)
					(arc
						(start 328.94651 -57.354978)
						(mid 329.076231 -57.424647)
						(end 329.1459 -57.554368)
					)
				)
			)
		)
		(zone
			(layer "F.Cu")
			(hatch none 0.5)
			(connect_pads
				(clearance 0)
			)
			(min_thickness 0.25)
			(keepout
				(tracks not_allowed)
				(vias allowed)
				(pads allowed)
				(copperpour not_allowed)
				(footprints allowed)
			)
			(placement
				(enabled no)
				(sheetname "")
			)
			(fill
				(thermal_gap 0.5)
				(thermal_bridge_width 0.5)
				(island_removal_mode 0)
			)
			(polygon
				(pts
					(arc
						(start 329.040744 -39.244524)
						(mid 329.004513 -39.186665)
						(end 328.946764 -39.15029)
					)
					(arc
						(start 328.946764 -39.045134)
						(mid 329.076485 -39.114803)
						(end 329.146154 -39.244524)
					)
				)
			)
		)
		(zone
			(layer "F.Cu")
			(hatch none 0.5)
			(connect_pads
				(clearance 0)
			)
			(min_thickness 0.25)
			(keepout
				(tracks not_allowed)
				(vias allowed)
				(pads allowed)
				(copperpour not_allowed)
				(footprints allowed)
			)
			(placement
				(enabled no)
				(sheetname "")
			)
			(fill
				(thermal_gap 0.5)
				(thermal_bridge_width 0.5)
				(island_removal_mode 0)
			)
			(polygon
				(pts
					(arc
						(start 329.040744 -38.414452)
						(mid 329.004318 -38.356753)
						(end 328.94651 -38.320472)
					)
					(arc
						(start 328.94651 -38.215062)
						(mid 329.076231 -38.284731)
						(end 329.1459 -38.414452)
					)
				)
			)
		)
		(zone
			(layer "F.Cu")
			(hatch none 0.5)
			(connect_pads
				(clearance 0)
			)
			(min_thickness 0.25)
			(keepout
				(tracks not_allowed)
				(vias allowed)
				(pads allowed)
				(copperpour not_allowed)
				(footprints allowed)
			)
			(placement
				(enabled no)
				(sheetname "")
			)
			(fill
				(thermal_gap 0.5)
				(thermal_bridge_width 0.5)
				(island_removal_mode 0)
			)
			(polygon
				(pts
					(arc
						(start 329.040744 -37.58438)
						(mid 329.004373 -37.526517)
						(end 328.94651 -37.490146)
					)
					(arc
						(start 328.94651 -37.38499)
						(mid 329.076231 -37.454659)
						(end 329.1459 -37.58438)
					)
				)
			)
		)
		(zone
			(layer "F.Cu")
			(hatch none 0.5)
			(connect_pads
				(clearance 0)
			)
			(min_thickness 0.25)
			(keepout
				(tracks not_allowed)
				(vias allowed)
				(pads allowed)
				(copperpour not_allowed)
				(footprints allowed)
			)
			(placement
				(enabled no)
				(sheetname "")
			)
			(fill
				(thermal_gap 0.5)
				(thermal_bridge_width 0.5)
				(island_removal_mode 0)
			)
			(polygon
				(pts
					(arc
						(start 329.251056 -58.901076)
						(mid 329.287427 -58.958939)
						(end 329.34529 -58.99531)
					)
					(arc
						(start 329.34529 -59.100466)
						(mid 329.215569 -59.030797)
						(end 329.1459 -58.901076)
					)
				)
			)
		)
		(zone
			(layer "F.Cu")
			(hatch none 0.5)
			(connect_pads
				(clearance 0)
			)
			(min_thickness 0.25)
			(keepout
				(tracks not_allowed)
				(vias allowed)
				(pads allowed)
				(copperpour not_allowed)
				(footprints allowed)
			)
			(placement
				(enabled no)
				(sheetname "")
			)
			(fill
				(thermal_gap 0.5)
				(thermal_bridge_width 0.5)
				(island_removal_mode 0)
			)
			(polygon
				(pts
					(arc
						(start 329.251056 -58.071004)
						(mid 329.287427 -58.128867)
						(end 329.34529 -58.165238)
					)
					(arc
						(start 329.34529 -58.270394)
						(mid 329.215569 -58.200725)
						(end 329.1459 -58.071004)
					)
				)
			)
		)
		(zone
			(layer "F.Cu")
			(hatch none 0.5)
			(connect_pads
				(clearance 0)
			)
			(min_thickness 0.25)
			(keepout
				(tracks not_allowed)
				(vias allowed)
				(pads allowed)
				(copperpour not_allowed)
				(footprints allowed)
			)
			(placement
				(enabled no)
				(sheetname "")
			)
			(fill
				(thermal_gap 0.5)
				(thermal_bridge_width 0.5)
				(island_removal_mode 0)
			)
			(polygon
				(pts
					(arc
						(start 329.251056 -38.931088)
						(mid 329.287427 -38.988951)
						(end 329.34529 -39.025322)
					)
					(arc
						(start 329.34529 -39.130478)
						(mid 329.215569 -39.060809)
						(end 329.1459 -38.931088)
					)
				)
			)
		)
		(zone
			(layer "F.Cu")
			(hatch none 0.5)
			(connect_pads
				(clearance 0)
			)
			(min_thickness 0.25)
			(keepout
				(tracks not_allowed)
				(vias allowed)
				(pads allowed)
				(copperpour not_allowed)
				(footprints allowed)
			)
			(placement
				(enabled no)
				(sheetname "")
			)
			(fill
				(thermal_gap 0.5)
				(thermal_bridge_width 0.5)
				(island_removal_mode 0)
			)
			(polygon
				(pts
					(arc
						(start 329.251056 -38.101016)
						(mid 329.287287 -38.158875)
						(end 329.345036 -38.19525)
					)
					(arc
						(start 329.345036 -38.300406)
						(mid 329.215315 -38.230737)
						(end 329.145646 -38.101016)
					)
				)
			)
		)
		(zone
			(layer "F.Cu")
			(hatch none 0.5)
			(connect_pads
				(clearance 0)
			)
			(min_thickness 0.25)
			(keepout
				(tracks not_allowed)
				(vias allowed)
				(pads allowed)
				(copperpour not_allowed)
				(footprints allowed)
			)
			(placement
				(enabled no)
				(sheetname "")
			)
			(fill
				(thermal_gap 0.5)
				(thermal_bridge_width 0.5)
				(island_removal_mode 0)
			)
			(polygon
				(pts
					(arc
						(start 329.345036 -37.905182)
						(mid 329.287282 -37.941578)
						(end 329.251056 -37.999416)
					)
					(arc
						(start 329.145646 -37.999416)
						(mid 329.215315 -37.869695)
						(end 329.345036 -37.800026)
					)
				)
			)
		)
		(zone
			(layer "F.Cu")
			(hatch none 0.5)
			(connect_pads
				(clearance 0)
			)
			(min_thickness 0.25)
			(keepout
				(tracks not_allowed)
				(vias allowed)
				(pads allowed)
				(copperpour not_allowed)
				(footprints allowed)
			)
			(placement
				(enabled no)
				(sheetname "")
			)
			(fill
				(thermal_gap 0.5)
				(thermal_bridge_width 0.5)
				(island_removal_mode 0)
			)
			(polygon
				(pts
					(arc
						(start 329.34529 -58.705242)
						(mid 329.287427 -58.741613)
						(end 329.251056 -58.799476)
					)
					(arc
						(start 329.1459 -58.799476)
						(mid 329.215569 -58.669755)
						(end 329.34529 -58.600086)
					)
				)
			)
		)
		(zone
			(layer "F.Cu")
			(hatch none 0.5)
			(connect_pads
				(clearance 0)
			)
			(min_thickness 0.25)
			(keepout
				(tracks not_allowed)
				(vias allowed)
				(pads allowed)
				(copperpour not_allowed)
				(footprints allowed)
			)
			(placement
				(enabled no)
				(sheetname "")
			)
			(fill
				(thermal_gap 0.5)
				(thermal_bridge_width 0.5)
				(island_removal_mode 0)
			)
			(polygon
				(pts
					(arc
						(start 329.34529 -57.87517)
						(mid 329.287427 -57.911541)
						(end 329.251056 -57.969404)
					)
					(arc
						(start 329.1459 -57.969404)
						(mid 329.215569 -57.839683)
						(end 329.34529 -57.770014)
					)
				)
			)
		)
		(zone
			(layer "F.Cu")
			(hatch none 0.5)
			(connect_pads
				(clearance 0)
			)
			(min_thickness 0.25)
			(keepout
				(tracks not_allowed)
				(vias allowed)
				(pads allowed)
				(copperpour not_allowed)
				(footprints allowed)
			)
			(placement
				(enabled no)
				(sheetname "")
			)
			(fill
				(thermal_gap 0.5)
				(thermal_bridge_width 0.5)
				(island_removal_mode 0)
			)
			(polygon
				(pts
					(arc
						(start 329.34529 -38.735254)
						(mid 329.287427 -38.771625)
						(end 329.251056 -38.829488)
					)
					(arc
						(start 329.1459 -38.829488)
						(mid 329.215569 -38.699767)
						(end 329.34529 -38.630098)
					)
				)
			)
		)
		(zone
			(layer "F.Cu")
			(hatch none 0.5)
			(connect_pads
				(clearance 0)
			)
			(min_thickness 0.25)
			(keepout
				(tracks not_allowed)
				(vias allowed)
				(pads allowed)
				(copperpour not_allowed)
				(footprints allowed)
			)
			(placement
				(enabled no)
				(sheetname "")
			)
			(fill
				(thermal_gap 0.5)
				(thermal_bridge_width 0.5)
				(island_removal_mode 0)
			)
			(polygon
				(pts
					(arc
						(start 329.446636 -38.19525)
						(mid 329.504499 -38.158879)
						(end 329.54087 -38.101016)
					)
					(arc
						(start 329.64628 -38.101016)
						(mid 329.576523 -38.230825)
						(end 329.446636 -38.300406)
					)
				)
			)
		)
		(zone
			(layer "F.Cu")
			(hatch none 0.5)
			(connect_pads
				(clearance 0)
			)
			(min_thickness 0.25)
			(keepout
				(tracks not_allowed)
				(vias allowed)
				(pads allowed)
				(copperpour not_allowed)
				(footprints allowed)
			)
			(placement
				(enabled no)
				(sheetname "")
			)
			(fill
				(thermal_gap 0.5)
				(thermal_bridge_width 0.5)
				(island_removal_mode 0)
			)
			(polygon
				(pts
					(arc
						(start 329.44689 -58.99531)
						(mid 329.504753 -58.958939)
						(end 329.541124 -58.901076)
					)
					(arc
						(start 329.64628 -58.901076)
						(mid 329.576611 -59.030797)
						(end 329.44689 -59.100466)
					)
				)
			)
		)
		(zone
			(layer "F.Cu")
			(hatch none 0.5)
			(connect_pads
				(clearance 0)
			)
			(min_thickness 0.25)
			(keepout
				(tracks not_allowed)
				(vias allowed)
				(pads allowed)
				(copperpour not_allowed)
				(footprints allowed)
			)
			(placement
				(enabled no)
				(sheetname "")
			)
			(fill
				(thermal_gap 0.5)
				(thermal_bridge_width 0.5)
				(island_removal_mode 0)
			)
			(polygon
				(pts
					(arc
						(start 329.44689 -58.165238)
						(mid 329.504753 -58.128867)
						(end 329.541124 -58.071004)
					)
					(arc
						(start 329.64628 -58.071004)
						(mid 329.576611 -58.200725)
						(end 329.44689 -58.270394)
					)
				)
			)
		)
		(zone
			(layer "F.Cu")
			(hatch none 0.5)
			(connect_pads
				(clearance 0)
			)
			(min_thickness 0.25)
			(keepout
				(tracks not_allowed)
				(vias allowed)
				(pads allowed)
				(copperpour not_allowed)
				(footprints allowed)
			)
			(placement
				(enabled no)
				(sheetname "")
			)
			(fill
				(thermal_gap 0.5)
				(thermal_bridge_width 0.5)
				(island_removal_mode 0)
			)
			(polygon
				(pts
					(arc
						(start 329.44689 -39.025322)
						(mid 329.504753 -38.988951)
						(end 329.541124 -38.931088)
					)
					(arc
						(start 329.64628 -38.931088)
						(mid 329.576611 -39.060809)
						(end 329.44689 -39.130478)
					)
				)
			)
		)
		(zone
			(layer "F.Cu")
			(hatch none 0.5)
			(connect_pads
				(clearance 0)
			)
			(min_thickness 0.25)
			(keepout
				(tracks not_allowed)
				(vias allowed)
				(pads allowed)
				(copperpour not_allowed)
				(footprints allowed)
			)
			(placement
				(enabled no)
				(sheetname "")
			)
			(fill
				(thermal_gap 0.5)
				(thermal_bridge_width 0.5)
				(island_removal_mode 0)
			)
			(polygon
				(pts
					(arc
						(start 329.54087 -37.999416)
						(mid 329.504499 -37.941553)
						(end 329.446636 -37.905182)
					)
					(arc
						(start 329.446636 -37.800026)
						(mid 329.576487 -37.869643)
						(end 329.64628 -37.999416)
					)
				)
			)
		)
		(zone
			(layer "F.Cu")
			(hatch none 0.5)
			(connect_pads
				(clearance 0)
			)
			(min_thickness 0.25)
			(keepout
				(tracks not_allowed)
				(vias allowed)
				(pads allowed)
				(copperpour not_allowed)
				(footprints allowed)
			)
			(placement
				(enabled no)
				(sheetname "")
			)
			(fill
				(thermal_gap 0.5)
				(thermal_bridge_width 0.5)
				(island_removal_mode 0)
			)
			(polygon
				(pts
					(arc
						(start 329.541124 -58.799476)
						(mid 329.504753 -58.741613)
						(end 329.44689 -58.705242)
					)
					(arc
						(start 329.44689 -58.600086)
						(mid 329.576611 -58.669755)
						(end 329.64628 -58.799476)
					)
				)
			)
		)
		(zone
			(layer "F.Cu")
			(hatch none 0.5)
			(connect_pads
				(clearance 0)
			)
			(min_thickness 0.25)
			(keepout
				(tracks not_allowed)
				(vias allowed)
				(pads allowed)
				(copperpour not_allowed)
				(footprints allowed)
			)
			(placement
				(enabled no)
				(sheetname "")
			)
			(fill
				(thermal_gap 0.5)
				(thermal_bridge_width 0.5)
				(island_removal_mode 0)
			)
			(polygon
				(pts
					(arc
						(start 329.541124 -57.969404)
						(mid 329.504753 -57.911541)
						(end 329.44689 -57.87517)
					)
					(arc
						(start 329.44689 -57.770014)
						(mid 329.576611 -57.839683)
						(end 329.64628 -57.969404)
					)
				)
			)
		)
		(zone
			(layer "F.Cu")
			(hatch none 0.5)
			(connect_pads
				(clearance 0)
			)
			(min_thickness 0.25)
			(keepout
				(tracks not_allowed)
				(vias allowed)
				(pads allowed)
				(copperpour not_allowed)
				(footprints allowed)
			)
			(placement
				(enabled no)
				(sheetname "")
			)
			(fill
				(thermal_gap 0.5)
				(thermal_bridge_width 0.5)
				(island_removal_mode 0)
			)
			(polygon
				(pts
					(arc
						(start 329.541124 -38.829488)
						(mid 329.504753 -38.771625)
						(end 329.44689 -38.735254)
					)
					(arc
						(start 329.44689 -38.630098)
						(mid 329.576611 -38.699767)
						(end 329.64628 -38.829488)
					)
				)
			)
		)
		(zone
			(layer "F.Cu")
			(hatch none 0.5)
			(connect_pads
				(clearance 0)
			)
			(min_thickness 0.25)
			(keepout
				(tracks not_allowed)
				(vias allowed)
				(pads allowed)
				(copperpour not_allowed)
				(footprints allowed)
			)
			(placement
				(enabled no)
				(sheetname "")
			)
			(fill
				(thermal_gap 0.5)
				(thermal_bridge_width 0.5)
				(island_removal_mode 0)
			)
			(polygon
				(pts
					(arc
						(start 329.751182 -58.48604)
						(mid 329.787608 -58.543739)
						(end 329.845416 -58.58002)
					)
					(arc
						(start 329.845416 -58.68543)
						(mid 329.715695 -58.615761)
						(end 329.646026 -58.48604)
					)
				)
			)
		)
		(zone
			(layer "F.Cu")
			(hatch none 0.5)
			(connect_pads
				(clearance 0)
			)
			(min_thickness 0.25)
			(keepout
				(tracks not_allowed)
				(vias allowed)
				(pads allowed)
				(copperpour not_allowed)
				(footprints allowed)
			)
			(placement
				(enabled no)
				(sheetname "")
			)
			(fill
				(thermal_gap 0.5)
				(thermal_bridge_width 0.5)
				(island_removal_mode 0)
			)
			(polygon
				(pts
					(arc
						(start 329.751182 -57.655968)
						(mid 329.787553 -57.713831)
						(end 329.845416 -57.750202)
					)
					(arc
						(start 329.845416 -57.855358)
						(mid 329.715695 -57.785689)
						(end 329.646026 -57.655968)
					)
				)
			)
		)
		(zone
			(layer "F.Cu")
			(hatch none 0.5)
			(connect_pads
				(clearance 0)
			)
			(min_thickness 0.25)
			(keepout
				(tracks not_allowed)
				(vias allowed)
				(pads allowed)
				(copperpour not_allowed)
				(footprints allowed)
			)
			(placement
				(enabled no)
				(sheetname "")
			)
			(fill
				(thermal_gap 0.5)
				(thermal_bridge_width 0.5)
				(island_removal_mode 0)
			)
			(polygon
				(pts
					(arc
						(start 329.751436 -39.346124)
						(mid 329.787807 -39.403987)
						(end 329.84567 -39.440358)
					)
					(arc
						(start 329.84567 -39.545514)
						(mid 329.715949 -39.475845)
						(end 329.64628 -39.346124)
					)
				)
			)
		)
		(zone
			(layer "F.Cu")
			(hatch none 0.5)
			(connect_pads
				(clearance 0)
			)
			(min_thickness 0.25)
			(keepout
				(tracks not_allowed)
				(vias allowed)
				(pads allowed)
				(copperpour not_allowed)
				(footprints allowed)
			)
			(placement
				(enabled no)
				(sheetname "")
			)
			(fill
				(thermal_gap 0.5)
				(thermal_bridge_width 0.5)
				(island_removal_mode 0)
			)
			(polygon
				(pts
					(arc
						(start 329.751436 -38.516052)
						(mid 329.787807 -38.573915)
						(end 329.84567 -38.610286)
					)
					(arc
						(start 329.84567 -38.715442)
						(mid 329.715949 -38.645773)
						(end 329.64628 -38.516052)
					)
				)
			)
		)
		(zone
			(layer "F.Cu")
			(hatch none 0.5)
			(connect_pads
				(clearance 0)
			)
			(min_thickness 0.25)
			(keepout
				(tracks not_allowed)
				(vias allowed)
				(pads allowed)
				(copperpour not_allowed)
				(footprints allowed)
			)
			(placement
				(enabled no)
				(sheetname "")
			)
			(fill
				(thermal_gap 0.5)
				(thermal_bridge_width 0.5)
				(island_removal_mode 0)
			)
			(polygon
				(pts
					(arc
						(start 329.845416 -58.290206)
						(mid 329.787553 -58.326577)
						(end 329.751182 -58.38444)
					)
					(arc
						(start 329.646026 -58.38444)
						(mid 329.715695 -58.254719)
						(end 329.845416 -58.18505)
					)
				)
			)
		)
		(zone
			(layer "F.Cu")
			(hatch none 0.5)
			(connect_pads
				(clearance 0)
			)
			(min_thickness 0.25)
			(keepout
				(tracks not_allowed)
				(vias allowed)
				(pads allowed)
				(copperpour not_allowed)
				(footprints allowed)
			)
			(placement
				(enabled no)
				(sheetname "")
			)
			(fill
				(thermal_gap 0.5)
				(thermal_bridge_width 0.5)
				(island_removal_mode 0)
			)
			(polygon
				(pts
					(arc
						(start 329.845416 -57.460134)
						(mid 329.787553 -57.496505)
						(end 329.751182 -57.554368)
					)
					(arc
						(start 329.646026 -57.554368)
						(mid 329.715695 -57.424647)
						(end 329.845416 -57.354978)
					)
				)
			)
		)
		(zone
			(layer "F.Cu")
			(hatch none 0.5)
			(connect_pads
				(clearance 0)
			)
			(min_thickness 0.25)
			(keepout
				(tracks not_allowed)
				(vias allowed)
				(pads allowed)
				(copperpour not_allowed)
				(footprints allowed)
			)
			(placement
				(enabled no)
				(sheetname "")
			)
			(fill
				(thermal_gap 0.5)
				(thermal_bridge_width 0.5)
				(island_removal_mode 0)
			)
			(polygon
				(pts
					(arc
						(start 329.84567 -39.15029)
						(mid 329.787807 -39.186661)
						(end 329.751436 -39.244524)
					)
					(arc
						(start 329.64628 -39.244524)
						(mid 329.715949 -39.114803)
						(end 329.84567 -39.045134)
					)
				)
			)
		)
		(zone
			(layer "F.Cu")
			(hatch none 0.5)
			(connect_pads
				(clearance 0)
			)
			(min_thickness 0.25)
			(keepout
				(tracks not_allowed)
				(vias allowed)
				(pads allowed)
				(copperpour not_allowed)
				(footprints allowed)
			)
			(placement
				(enabled no)
				(sheetname "")
			)
			(fill
				(thermal_gap 0.5)
				(thermal_bridge_width 0.5)
				(island_removal_mode 0)
			)
			(polygon
				(pts
					(arc
						(start 329.84567 -38.320218)
						(mid 329.787807 -38.356589)
						(end 329.751436 -38.414452)
					)
					(arc
						(start 329.64628 -38.414452)
						(mid 329.715949 -38.284731)
						(end 329.84567 -38.215062)
					)
				)
			)
		)
		(zone
			(layer "F.Cu")
			(hatch none 0.5)
			(connect_pads
				(clearance 0)
			)
			(min_thickness 0.25)
			(keepout
				(tracks not_allowed)
				(vias allowed)
				(pads allowed)
				(copperpour not_allowed)
				(footprints allowed)
			)
			(placement
				(enabled no)
				(sheetname "")
			)
			(fill
				(thermal_gap 0.5)
				(thermal_bridge_width 0.5)
				(island_removal_mode 0)
			)
			(polygon
				(pts
					(arc
						(start 329.947016 -58.58002)
						(mid 330.004875 -58.543789)
						(end 330.04125 -58.48604)
					)
					(arc
						(start 330.146406 -58.48604)
						(mid 330.076737 -58.615761)
						(end 329.947016 -58.68543)
					)
				)
			)
		)
		(zone
			(layer "F.Cu")
			(hatch none 0.5)
			(connect_pads
				(clearance 0)
			)
			(min_thickness 0.25)
			(keepout
				(tracks not_allowed)
				(vias allowed)
				(pads allowed)
				(copperpour not_allowed)
				(footprints allowed)
			)
			(placement
				(enabled no)
				(sheetname "")
			)
			(fill
				(thermal_gap 0.5)
				(thermal_bridge_width 0.5)
				(island_removal_mode 0)
			)
			(polygon
				(pts
					(arc
						(start 329.947016 -57.750202)
						(mid 330.004879 -57.713831)
						(end 330.04125 -57.655968)
					)
					(arc
						(start 330.146406 -57.655968)
						(mid 330.076737 -57.785689)
						(end 329.947016 -57.855358)
					)
				)
			)
		)
		(zone
			(layer "F.Cu")
			(hatch none 0.5)
			(connect_pads
				(clearance 0)
			)
			(min_thickness 0.25)
			(keepout
				(tracks not_allowed)
				(vias allowed)
				(pads allowed)
				(copperpour not_allowed)
				(footprints allowed)
			)
			(placement
				(enabled no)
				(sheetname "")
			)
			(fill
				(thermal_gap 0.5)
				(thermal_bridge_width 0.5)
				(island_removal_mode 0)
			)
			(polygon
				(pts
					(arc
						(start 329.94727 -39.440358)
						(mid 330.004969 -39.403932)
						(end 330.04125 -39.346124)
					)
					(arc
						(start 330.14666 -39.346124)
						(mid 330.076991 -39.475845)
						(end 329.94727 -39.545514)
					)
				)
			)
		)
		(zone
			(layer "F.Cu")
			(hatch none 0.5)
			(connect_pads
				(clearance 0)
			)
			(min_thickness 0.25)
			(keepout
				(tracks not_allowed)
				(vias allowed)
				(pads allowed)
				(copperpour not_allowed)
				(footprints allowed)
			)
			(placement
				(enabled no)
				(sheetname "")
			)
			(fill
				(thermal_gap 0.5)
				(thermal_bridge_width 0.5)
				(island_removal_mode 0)
			)
			(polygon
				(pts
					(arc
						(start 329.94727 -38.610286)
						(mid 330.004969 -38.57386)
						(end 330.04125 -38.516052)
					)
					(arc
						(start 330.14666 -38.516052)
						(mid 330.076991 -38.645773)
						(end 329.94727 -38.715442)
					)
				)
			)
		)
		(zone
			(layer "F.Cu")
			(hatch none 0.5)
			(connect_pads
				(clearance 0)
			)
			(min_thickness 0.25)
			(keepout
				(tracks not_allowed)
				(vias allowed)
				(pads allowed)
				(copperpour not_allowed)
				(footprints allowed)
			)
			(placement
				(enabled no)
				(sheetname "")
			)
			(fill
				(thermal_gap 0.5)
				(thermal_bridge_width 0.5)
				(island_removal_mode 0)
			)
			(polygon
				(pts
					(arc
						(start 330.04125 -58.38444)
						(mid 330.004879 -58.326577)
						(end 329.947016 -58.290206)
					)
					(arc
						(start 329.947016 -58.18505)
						(mid 330.076737 -58.254719)
						(end 330.146406 -58.38444)
					)
				)
			)
		)
		(zone
			(layer "F.Cu")
			(hatch none 0.5)
			(connect_pads
				(clearance 0)
			)
			(min_thickness 0.25)
			(keepout
				(tracks not_allowed)
				(vias allowed)
				(pads allowed)
				(copperpour not_allowed)
				(footprints allowed)
			)
			(placement
				(enabled no)
				(sheetname "")
			)
			(fill
				(thermal_gap 0.5)
				(thermal_bridge_width 0.5)
				(island_removal_mode 0)
			)
			(polygon
				(pts
					(arc
						(start 330.04125 -57.554368)
						(mid 330.004879 -57.496505)
						(end 329.947016 -57.460134)
					)
					(arc
						(start 329.947016 -57.354978)
						(mid 330.076737 -57.424647)
						(end 330.146406 -57.554368)
					)
				)
			)
		)
		(zone
			(layer "F.Cu")
			(hatch none 0.5)
			(connect_pads
				(clearance 0)
			)
			(min_thickness 0.25)
			(keepout
				(tracks not_allowed)
				(vias allowed)
				(pads allowed)
				(copperpour not_allowed)
				(footprints allowed)
			)
			(placement
				(enabled no)
				(sheetname "")
			)
			(fill
				(thermal_gap 0.5)
				(thermal_bridge_width 0.5)
				(island_removal_mode 0)
			)
			(polygon
				(pts
					(arc
						(start 330.04125 -39.244524)
						(mid 330.005019 -39.186665)
						(end 329.94727 -39.15029)
					)
					(arc
						(start 329.94727 -39.045134)
						(mid 330.076991 -39.114803)
						(end 330.14666 -39.244524)
					)
				)
			)
		)
		(zone
			(layer "F.Cu")
			(hatch none 0.5)
			(connect_pads
				(clearance 0)
			)
			(min_thickness 0.25)
			(keepout
				(tracks not_allowed)
				(vias allowed)
				(pads allowed)
				(copperpour not_allowed)
				(footprints allowed)
			)
			(placement
				(enabled no)
				(sheetname "")
			)
			(fill
				(thermal_gap 0.5)
				(thermal_bridge_width 0.5)
				(island_removal_mode 0)
			)
			(polygon
				(pts
					(arc
						(start 330.04125 -38.414452)
						(mid 330.005019 -38.356593)
						(end 329.94727 -38.320218)
					)
					(arc
						(start 329.94727 -38.215062)
						(mid 330.076991 -38.284731)
						(end 330.14666 -38.414452)
					)
				)
			)
		)
		(zone
			(layer "F.Cu")
			(hatch none 0.5)
			(connect_pads
				(clearance 0)
			)
			(min_thickness 0.25)
			(keepout
				(tracks not_allowed)
				(vias allowed)
				(pads allowed)
				(copperpour not_allowed)
				(footprints allowed)
			)
			(placement
				(enabled no)
				(sheetname "")
			)
			(fill
				(thermal_gap 0.5)
				(thermal_bridge_width 0.5)
				(island_removal_mode 0)
			)
			(polygon
				(pts
					(arc
						(start 330.251562 -58.901076)
						(mid 330.287933 -58.958939)
						(end 330.345796 -58.99531)
					)
					(arc
						(start 330.345796 -59.100466)
						(mid 330.216075 -59.030797)
						(end 330.146406 -58.901076)
					)
				)
			)
		)
		(zone
			(layer "F.Cu")
			(hatch none 0.5)
			(connect_pads
				(clearance 0)
			)
			(min_thickness 0.25)
			(keepout
				(tracks not_allowed)
				(vias allowed)
				(pads allowed)
				(copperpour not_allowed)
				(footprints allowed)
			)
			(placement
				(enabled no)
				(sheetname "")
			)
			(fill
				(thermal_gap 0.5)
				(thermal_bridge_width 0.5)
				(island_removal_mode 0)
			)
			(polygon
				(pts
					(arc
						(start 330.251562 -58.071004)
						(mid 330.287933 -58.128867)
						(end 330.345796 -58.165238)
					)
					(arc
						(start 330.345796 -58.270394)
						(mid 330.216075 -58.200725)
						(end 330.146406 -58.071004)
					)
				)
			)
		)
		(zone
			(layer "F.Cu")
			(hatch none 0.5)
			(connect_pads
				(clearance 0)
			)
			(min_thickness 0.25)
			(keepout
				(tracks not_allowed)
				(vias allowed)
				(pads allowed)
				(copperpour not_allowed)
				(footprints allowed)
			)
			(placement
				(enabled no)
				(sheetname "")
			)
			(fill
				(thermal_gap 0.5)
				(thermal_bridge_width 0.5)
				(island_removal_mode 0)
			)
			(polygon
				(pts
					(arc
						(start 330.251562 -38.931088)
						(mid 330.287933 -38.988951)
						(end 330.345796 -39.025322)
					)
					(arc
						(start 330.345796 -39.130478)
						(mid 330.216075 -39.060809)
						(end 330.146406 -38.931088)
					)
				)
			)
		)
		(zone
			(layer "F.Cu")
			(hatch none 0.5)
			(connect_pads
				(clearance 0)
			)
			(min_thickness 0.25)
			(keepout
				(tracks not_allowed)
				(vias allowed)
				(pads allowed)
				(copperpour not_allowed)
				(footprints allowed)
			)
			(placement
				(enabled no)
				(sheetname "")
			)
			(fill
				(thermal_gap 0.5)
				(thermal_bridge_width 0.5)
				(island_removal_mode 0)
			)
			(polygon
				(pts
					(arc
						(start 330.251562 -38.101016)
						(mid 330.287933 -38.158879)
						(end 330.345796 -38.19525)
					)
					(arc
						(start 330.345796 -38.300406)
						(mid 330.216075 -38.230737)
						(end 330.146406 -38.101016)
					)
				)
			)
		)
		(zone
			(layer "F.Cu")
			(hatch none 0.5)
			(connect_pads
				(clearance 0)
			)
			(min_thickness 0.25)
			(keepout
				(tracks not_allowed)
				(vias allowed)
				(pads allowed)
				(copperpour not_allowed)
				(footprints allowed)
			)
			(placement
				(enabled no)
				(sheetname "")
			)
			(fill
				(thermal_gap 0.5)
				(thermal_bridge_width 0.5)
				(island_removal_mode 0)
			)
			(polygon
				(pts
					(arc
						(start 330.345796 -58.705242)
						(mid 330.287933 -58.741613)
						(end 330.251562 -58.799476)
					)
					(arc
						(start 330.146406 -58.799476)
						(mid 330.216075 -58.669755)
						(end 330.345796 -58.600086)
					)
				)
			)
		)
		(zone
			(layer "F.Cu")
			(hatch none 0.5)
			(connect_pads
				(clearance 0)
			)
			(min_thickness 0.25)
			(keepout
				(tracks not_allowed)
				(vias allowed)
				(pads allowed)
				(copperpour not_allowed)
				(footprints allowed)
			)
			(placement
				(enabled no)
				(sheetname "")
			)
			(fill
				(thermal_gap 0.5)
				(thermal_bridge_width 0.5)
				(island_removal_mode 0)
			)
			(polygon
				(pts
					(arc
						(start 330.345796 -57.87517)
						(mid 330.287933 -57.911541)
						(end 330.251562 -57.969404)
					)
					(arc
						(start 330.146406 -57.969404)
						(mid 330.216075 -57.839683)
						(end 330.345796 -57.770014)
					)
				)
			)
		)
		(zone
			(layer "F.Cu")
			(hatch none 0.5)
			(connect_pads
				(clearance 0)
			)
			(min_thickness 0.25)
			(keepout
				(tracks not_allowed)
				(vias allowed)
				(pads allowed)
				(copperpour not_allowed)
				(footprints allowed)
			)
			(placement
				(enabled no)
				(sheetname "")
			)
			(fill
				(thermal_gap 0.5)
				(thermal_bridge_width 0.5)
				(island_removal_mode 0)
			)
			(polygon
				(pts
					(arc
						(start 330.345796 -38.735254)
						(mid 330.287933 -38.771625)
						(end 330.251562 -38.829488)
					)
					(arc
						(start 330.146406 -38.829488)
						(mid 330.216075 -38.699767)
						(end 330.345796 -38.630098)
					)
				)
			)
		)
		(zone
			(layer "F.Cu")
			(hatch none 0.5)
			(connect_pads
				(clearance 0)
			)
			(min_thickness 0.25)
			(keepout
				(tracks not_allowed)
				(vias allowed)
				(pads allowed)
				(copperpour not_allowed)
				(footprints allowed)
			)
			(placement
				(enabled no)
				(sheetname "")
			)
			(fill
				(thermal_gap 0.5)
				(thermal_bridge_width 0.5)
				(island_removal_mode 0)
			)
			(polygon
				(pts
					(arc
						(start 330.345796 -37.905182)
						(mid 330.287933 -37.941553)
						(end 330.251562 -37.999416)
					)
					(arc
						(start 330.146406 -37.999416)
						(mid 330.216075 -37.869695)
						(end 330.345796 -37.800026)
					)
				)
			)
		)
		(zone
			(layer "F.Cu")
			(hatch none 0.5)
			(connect_pads
				(clearance 0)
			)
			(min_thickness 0.25)
			(keepout
				(tracks not_allowed)
				(vias allowed)
				(pads allowed)
				(copperpour not_allowed)
				(footprints allowed)
			)
			(placement
				(enabled no)
				(sheetname "")
			)
			(fill
				(thermal_gap 0.5)
				(thermal_bridge_width 0.5)
				(island_removal_mode 0)
			)
			(polygon
				(pts
					(arc
						(start 330.447396 -58.99531)
						(mid 330.505259 -58.958939)
						(end 330.54163 -58.901076)
					)
					(arc
						(start 330.646786 -58.901076)
						(mid 330.577117 -59.030797)
						(end 330.447396 -59.100466)
					)
				)
			)
		)
		(zone
			(layer "F.Cu")
			(hatch none 0.5)
			(connect_pads
				(clearance 0)
			)
			(min_thickness 0.25)
			(keepout
				(tracks not_allowed)
				(vias allowed)
				(pads allowed)
				(copperpour not_allowed)
				(footprints allowed)
			)
			(placement
				(enabled no)
				(sheetname "")
			)
			(fill
				(thermal_gap 0.5)
				(thermal_bridge_width 0.5)
				(island_removal_mode 0)
			)
			(polygon
				(pts
					(arc
						(start 330.447396 -58.165238)
						(mid 330.505259 -58.128867)
						(end 330.54163 -58.071004)
					)
					(arc
						(start 330.646786 -58.071004)
						(mid 330.577117 -58.200725)
						(end 330.447396 -58.270394)
					)
				)
			)
		)
		(zone
			(layer "F.Cu")
			(hatch none 0.5)
			(connect_pads
				(clearance 0)
			)
			(min_thickness 0.25)
			(keepout
				(tracks not_allowed)
				(vias allowed)
				(pads allowed)
				(copperpour not_allowed)
				(footprints allowed)
			)
			(placement
				(enabled no)
				(sheetname "")
			)
			(fill
				(thermal_gap 0.5)
				(thermal_bridge_width 0.5)
				(island_removal_mode 0)
			)
			(polygon
				(pts
					(arc
						(start 330.447396 -39.025322)
						(mid 330.505259 -38.988951)
						(end 330.54163 -38.931088)
					)
					(arc
						(start 330.646786 -38.931088)
						(mid 330.577117 -39.060809)
						(end 330.447396 -39.130478)
					)
				)
			)
		)
		(zone
			(layer "F.Cu")
			(hatch none 0.5)
			(connect_pads
				(clearance 0)
			)
			(min_thickness 0.25)
			(keepout
				(tracks not_allowed)
				(vias allowed)
				(pads allowed)
				(copperpour not_allowed)
				(footprints allowed)
			)
			(placement
				(enabled no)
				(sheetname "")
			)
			(fill
				(thermal_gap 0.5)
				(thermal_bridge_width 0.5)
				(island_removal_mode 0)
			)
			(polygon
				(pts
					(arc
						(start 330.447396 -38.19525)
						(mid 330.505259 -38.158879)
						(end 330.54163 -38.101016)
					)
					(arc
						(start 330.646786 -38.101016)
						(mid 330.577117 -38.230737)
						(end 330.447396 -38.300406)
					)
				)
			)
		)
		(zone
			(layer "F.Cu")
			(hatch none 0.5)
			(connect_pads
				(clearance 0)
			)
			(min_thickness 0.25)
			(keepout
				(tracks not_allowed)
				(vias allowed)
				(pads allowed)
				(copperpour not_allowed)
				(footprints allowed)
			)
			(placement
				(enabled no)
				(sheetname "")
			)
			(fill
				(thermal_gap 0.5)
				(thermal_bridge_width 0.5)
				(island_removal_mode 0)
			)
			(polygon
				(pts
					(arc
						(start 330.54163 -58.799476)
						(mid 330.505259 -58.741613)
						(end 330.447396 -58.705242)
					)
					(arc
						(start 330.447396 -58.600086)
						(mid 330.577117 -58.669755)
						(end 330.646786 -58.799476)
					)
				)
			)
		)
		(zone
			(layer "F.Cu")
			(hatch none 0.5)
			(connect_pads
				(clearance 0)
			)
			(min_thickness 0.25)
			(keepout
				(tracks not_allowed)
				(vias allowed)
				(pads allowed)
				(copperpour not_allowed)
				(footprints allowed)
			)
			(placement
				(enabled no)
				(sheetname "")
			)
			(fill
				(thermal_gap 0.5)
				(thermal_bridge_width 0.5)
				(island_removal_mode 0)
			)
			(polygon
				(pts
					(arc
						(start 330.54163 -57.969404)
						(mid 330.505259 -57.911541)
						(end 330.447396 -57.87517)
					)
					(arc
						(start 330.447396 -57.770014)
						(mid 330.577117 -57.839683)
						(end 330.646786 -57.969404)
					)
				)
			)
		)
		(zone
			(layer "F.Cu")
			(hatch none 0.5)
			(connect_pads
				(clearance 0)
			)
			(min_thickness 0.25)
			(keepout
				(tracks not_allowed)
				(vias allowed)
				(pads allowed)
				(copperpour not_allowed)
				(footprints allowed)
			)
			(placement
				(enabled no)
				(sheetname "")
			)
			(fill
				(thermal_gap 0.5)
				(thermal_bridge_width 0.5)
				(island_removal_mode 0)
			)
			(polygon
				(pts
					(arc
						(start 330.54163 -38.829488)
						(mid 330.505259 -38.771625)
						(end 330.447396 -38.735254)
					)
					(arc
						(start 330.447396 -38.630098)
						(mid 330.577117 -38.699767)
						(end 330.646786 -38.829488)
					)
				)
			)
		)
		(zone
			(layer "F.Cu")
			(hatch none 0.5)
			(connect_pads
				(clearance 0)
			)
			(min_thickness 0.25)
			(keepout
				(tracks not_allowed)
				(vias allowed)
				(pads allowed)
				(copperpour not_allowed)
				(footprints allowed)
			)
			(placement
				(enabled no)
				(sheetname "")
			)
			(fill
				(thermal_gap 0.5)
				(thermal_bridge_width 0.5)
				(island_removal_mode 0)
			)
			(polygon
				(pts
					(arc
						(start 330.54163 -37.999416)
						(mid 330.505259 -37.941553)
						(end 330.447396 -37.905182)
					)
					(arc
						(start 330.447396 -37.800026)
						(mid 330.577117 -37.869695)
						(end 330.646786 -37.999416)
					)
				)
			)
		)
		(zone
			(layer "F.Cu")
			(hatch none 0.5)
			(connect_pads
				(clearance 0)
			)
			(min_thickness 0.25)
			(keepout
				(tracks not_allowed)
				(vias allowed)
				(pads allowed)
				(copperpour not_allowed)
				(footprints allowed)
			)
			(placement
				(enabled no)
				(sheetname "")
			)
			(fill
				(thermal_gap 0.5)
				(thermal_bridge_width 0.5)
				(island_removal_mode 0)
			)
			(polygon
				(pts
					(arc
						(start 330.751688 -58.48604)
						(mid 330.788114 -58.543739)
						(end 330.845922 -58.58002)
					)
					(arc
						(start 330.845922 -58.68543)
						(mid 330.716201 -58.615761)
						(end 330.646532 -58.48604)
					)
				)
			)
		)
		(zone
			(layer "F.Cu")
			(hatch none 0.5)
			(connect_pads
				(clearance 0)
			)
			(min_thickness 0.25)
			(keepout
				(tracks not_allowed)
				(vias allowed)
				(pads allowed)
				(copperpour not_allowed)
				(footprints allowed)
			)
			(placement
				(enabled no)
				(sheetname "")
			)
			(fill
				(thermal_gap 0.5)
				(thermal_bridge_width 0.5)
				(island_removal_mode 0)
			)
			(polygon
				(pts
					(arc
						(start 330.751688 -57.655968)
						(mid 330.788059 -57.713831)
						(end 330.845922 -57.750202)
					)
					(arc
						(start 330.845922 -57.855358)
						(mid 330.716201 -57.785689)
						(end 330.646532 -57.655968)
					)
				)
			)
		)
		(zone
			(layer "F.Cu")
			(hatch none 0.5)
			(connect_pads
				(clearance 0)
			)
			(min_thickness 0.25)
			(keepout
				(tracks not_allowed)
				(vias allowed)
				(pads allowed)
				(copperpour not_allowed)
				(footprints allowed)
			)
			(placement
				(enabled no)
				(sheetname "")
			)
			(fill
				(thermal_gap 0.5)
				(thermal_bridge_width 0.5)
				(island_removal_mode 0)
			)
			(polygon
				(pts
					(arc
						(start 330.751942 -39.346124)
						(mid 330.788313 -39.403987)
						(end 330.846176 -39.440358)
					)
					(arc
						(start 330.846176 -39.545514)
						(mid 330.716325 -39.475897)
						(end 330.646532 -39.346124)
					)
				)
			)
		)
		(zone
			(layer "F.Cu")
			(hatch none 0.5)
			(connect_pads
				(clearance 0)
			)
			(min_thickness 0.25)
			(keepout
				(tracks not_allowed)
				(vias allowed)
				(pads allowed)
				(copperpour not_allowed)
				(footprints allowed)
			)
			(placement
				(enabled no)
				(sheetname "")
			)
			(fill
				(thermal_gap 0.5)
				(thermal_bridge_width 0.5)
				(island_removal_mode 0)
			)
			(polygon
				(pts
					(arc
						(start 330.751942 -38.516052)
						(mid 330.788313 -38.573915)
						(end 330.846176 -38.610286)
					)
					(arc
						(start 330.846176 -38.715442)
						(mid 330.716325 -38.645825)
						(end 330.646532 -38.516052)
					)
				)
			)
		)
		(zone
			(layer "F.Cu")
			(hatch none 0.5)
			(connect_pads
				(clearance 0)
			)
			(min_thickness 0.25)
			(keepout
				(tracks not_allowed)
				(vias allowed)
				(pads allowed)
				(copperpour not_allowed)
				(footprints allowed)
			)
			(placement
				(enabled no)
				(sheetname "")
			)
			(fill
				(thermal_gap 0.5)
				(thermal_bridge_width 0.5)
				(island_removal_mode 0)
			)
			(polygon
				(pts
					(arc
						(start 330.845922 -58.290206)
						(mid 330.788059 -58.326577)
						(end 330.751688 -58.38444)
					)
					(arc
						(start 330.646532 -58.38444)
						(mid 330.716201 -58.254719)
						(end 330.845922 -58.18505)
					)
				)
			)
		)
		(zone
			(layer "F.Cu")
			(hatch none 0.5)
			(connect_pads
				(clearance 0)
			)
			(min_thickness 0.25)
			(keepout
				(tracks not_allowed)
				(vias allowed)
				(pads allowed)
				(copperpour not_allowed)
				(footprints allowed)
			)
			(placement
				(enabled no)
				(sheetname "")
			)
			(fill
				(thermal_gap 0.5)
				(thermal_bridge_width 0.5)
				(island_removal_mode 0)
			)
			(polygon
				(pts
					(arc
						(start 330.845922 -57.460134)
						(mid 330.788059 -57.496505)
						(end 330.751688 -57.554368)
					)
					(arc
						(start 330.646532 -57.554368)
						(mid 330.716201 -57.424647)
						(end 330.845922 -57.354978)
					)
				)
			)
		)
		(zone
			(layer "F.Cu")
			(hatch none 0.5)
			(connect_pads
				(clearance 0)
			)
			(min_thickness 0.25)
			(keepout
				(tracks not_allowed)
				(vias allowed)
				(pads allowed)
				(copperpour not_allowed)
				(footprints allowed)
			)
			(placement
				(enabled no)
				(sheetname "")
			)
			(fill
				(thermal_gap 0.5)
				(thermal_bridge_width 0.5)
				(island_removal_mode 0)
			)
			(polygon
				(pts
					(arc
						(start 330.846176 -39.15029)
						(mid 330.788313 -39.186661)
						(end 330.751942 -39.244524)
					)
					(arc
						(start 330.646532 -39.244524)
						(mid 330.716289 -39.114715)
						(end 330.846176 -39.045134)
					)
				)
			)
		)
		(zone
			(layer "F.Cu")
			(hatch none 0.5)
			(connect_pads
				(clearance 0)
			)
			(min_thickness 0.25)
			(keepout
				(tracks not_allowed)
				(vias allowed)
				(pads allowed)
				(copperpour not_allowed)
				(footprints allowed)
			)
			(placement
				(enabled no)
				(sheetname "")
			)
			(fill
				(thermal_gap 0.5)
				(thermal_bridge_width 0.5)
				(island_removal_mode 0)
			)
			(polygon
				(pts
					(arc
						(start 330.846176 -38.320218)
						(mid 330.788313 -38.356589)
						(end 330.751942 -38.414452)
					)
					(arc
						(start 330.646532 -38.414452)
						(mid 330.716289 -38.284643)
						(end 330.846176 -38.215062)
					)
				)
			)
		)
		(zone
			(layer "F.Cu")
			(hatch none 0.5)
			(connect_pads
				(clearance 0)
			)
			(min_thickness 0.25)
			(keepout
				(tracks not_allowed)
				(vias allowed)
				(pads allowed)
				(copperpour not_allowed)
				(footprints allowed)
			)
			(placement
				(enabled no)
				(sheetname "")
			)
			(fill
				(thermal_gap 0.5)
				(thermal_bridge_width 0.5)
				(island_removal_mode 0)
			)
			(polygon
				(pts
					(arc
						(start 330.947522 -58.58002)
						(mid 331.005381 -58.543789)
						(end 331.041756 -58.48604)
					)
					(arc
						(start 331.146912 -58.48604)
						(mid 331.077243 -58.615761)
						(end 330.947522 -58.68543)
					)
				)
			)
		)
		(zone
			(layer "F.Cu")
			(hatch none 0.5)
			(connect_pads
				(clearance 0)
			)
			(min_thickness 0.25)
			(keepout
				(tracks not_allowed)
				(vias allowed)
				(pads allowed)
				(copperpour not_allowed)
				(footprints allowed)
			)
			(placement
				(enabled no)
				(sheetname "")
			)
			(fill
				(thermal_gap 0.5)
				(thermal_bridge_width 0.5)
				(island_removal_mode 0)
			)
			(polygon
				(pts
					(arc
						(start 330.947522 -57.750202)
						(mid 331.005385 -57.713831)
						(end 331.041756 -57.655968)
					)
					(arc
						(start 331.146912 -57.655968)
						(mid 331.077243 -57.785689)
						(end 330.947522 -57.855358)
					)
				)
			)
		)
		(zone
			(layer "F.Cu")
			(hatch none 0.5)
			(connect_pads
				(clearance 0)
			)
			(min_thickness 0.25)
			(keepout
				(tracks not_allowed)
				(vias allowed)
				(pads allowed)
				(copperpour not_allowed)
				(footprints allowed)
			)
			(placement
				(enabled no)
				(sheetname "")
			)
			(fill
				(thermal_gap 0.5)
				(thermal_bridge_width 0.5)
				(island_removal_mode 0)
			)
			(polygon
				(pts
					(arc
						(start 330.947776 -39.440358)
						(mid 331.005475 -39.403932)
						(end 331.041756 -39.346124)
					)
					(arc
						(start 331.147166 -39.346124)
						(mid 331.077497 -39.475845)
						(end 330.947776 -39.545514)
					)
				)
			)
		)
		(zone
			(layer "F.Cu")
			(hatch none 0.5)
			(connect_pads
				(clearance 0)
			)
			(min_thickness 0.25)
			(keepout
				(tracks not_allowed)
				(vias allowed)
				(pads allowed)
				(copperpour not_allowed)
				(footprints allowed)
			)
			(placement
				(enabled no)
				(sheetname "")
			)
			(fill
				(thermal_gap 0.5)
				(thermal_bridge_width 0.5)
				(island_removal_mode 0)
			)
			(polygon
				(pts
					(arc
						(start 330.947776 -38.610286)
						(mid 331.005475 -38.57386)
						(end 331.041756 -38.516052)
					)
					(arc
						(start 331.147166 -38.516052)
						(mid 331.077497 -38.645773)
						(end 330.947776 -38.715442)
					)
				)
			)
		)
		(zone
			(layer "F.Cu")
			(hatch none 0.5)
			(connect_pads
				(clearance 0)
			)
			(min_thickness 0.25)
			(keepout
				(tracks not_allowed)
				(vias allowed)
				(pads allowed)
				(copperpour not_allowed)
				(footprints allowed)
			)
			(placement
				(enabled no)
				(sheetname "")
			)
			(fill
				(thermal_gap 0.5)
				(thermal_bridge_width 0.5)
				(island_removal_mode 0)
			)
			(polygon
				(pts
					(arc
						(start 331.041756 -58.38444)
						(mid 331.005385 -58.326577)
						(end 330.947522 -58.290206)
					)
					(arc
						(start 330.947522 -58.18505)
						(mid 331.077243 -58.254719)
						(end 331.146912 -58.38444)
					)
				)
			)
		)
		(zone
			(layer "F.Cu")
			(hatch none 0.5)
			(connect_pads
				(clearance 0)
			)
			(min_thickness 0.25)
			(keepout
				(tracks not_allowed)
				(vias allowed)
				(pads allowed)
				(copperpour not_allowed)
				(footprints allowed)
			)
			(placement
				(enabled no)
				(sheetname "")
			)
			(fill
				(thermal_gap 0.5)
				(thermal_bridge_width 0.5)
				(island_removal_mode 0)
			)
			(polygon
				(pts
					(arc
						(start 331.041756 -57.554368)
						(mid 331.005385 -57.496505)
						(end 330.947522 -57.460134)
					)
					(arc
						(start 330.947522 -57.354978)
						(mid 331.077243 -57.424647)
						(end 331.146912 -57.554368)
					)
				)
			)
		)
		(zone
			(layer "F.Cu")
			(hatch none 0.5)
			(connect_pads
				(clearance 0)
			)
			(min_thickness 0.25)
			(keepout
				(tracks not_allowed)
				(vias allowed)
				(pads allowed)
				(copperpour not_allowed)
				(footprints allowed)
			)
			(placement
				(enabled no)
				(sheetname "")
			)
			(fill
				(thermal_gap 0.5)
				(thermal_bridge_width 0.5)
				(island_removal_mode 0)
			)
			(polygon
				(pts
					(arc
						(start 331.041756 -39.244524)
						(mid 331.00547 -39.186745)
						(end 330.947776 -39.15029)
					)
					(arc
						(start 330.947776 -39.045134)
						(mid 331.077497 -39.114803)
						(end 331.147166 -39.244524)
					)
				)
			)
		)
		(zone
			(layer "F.Cu")
			(hatch none 0.5)
			(connect_pads
				(clearance 0)
			)
			(min_thickness 0.25)
			(keepout
				(tracks not_allowed)
				(vias allowed)
				(pads allowed)
				(copperpour not_allowed)
				(footprints allowed)
			)
			(placement
				(enabled no)
				(sheetname "")
			)
			(fill
				(thermal_gap 0.5)
				(thermal_bridge_width 0.5)
				(island_removal_mode 0)
			)
			(polygon
				(pts
					(arc
						(start 331.041756 -38.414452)
						(mid 331.005525 -38.356593)
						(end 330.947776 -38.320218)
					)
					(arc
						(start 330.947776 -38.215062)
						(mid 331.077497 -38.284731)
						(end 331.147166 -38.414452)
					)
				)
			)
		)
		(zone
			(layer "F.Cu")
			(hatch none 0.5)
			(connect_pads
				(clearance 0)
			)
			(min_thickness 0.25)
			(keepout
				(tracks not_allowed)
				(vias allowed)
				(pads allowed)
				(copperpour not_allowed)
				(footprints allowed)
			)
			(placement
				(enabled no)
				(sheetname "")
			)
			(fill
				(thermal_gap 0.5)
				(thermal_bridge_width 0.5)
				(island_removal_mode 0)
			)
			(polygon
				(pts
					(arc
						(start 331.252068 -58.901076)
						(mid 331.288439 -58.958939)
						(end 331.346302 -58.99531)
					)
					(arc
						(start 331.346302 -59.100466)
						(mid 331.216581 -59.030797)
						(end 331.146912 -58.901076)
					)
				)
			)
		)
		(zone
			(layer "F.Cu")
			(hatch none 0.5)
			(connect_pads
				(clearance 0)
			)
			(min_thickness 0.25)
			(keepout
				(tracks not_allowed)
				(vias allowed)
				(pads allowed)
				(copperpour not_allowed)
				(footprints allowed)
			)
			(placement
				(enabled no)
				(sheetname "")
			)
			(fill
				(thermal_gap 0.5)
				(thermal_bridge_width 0.5)
				(island_removal_mode 0)
			)
			(polygon
				(pts
					(arc
						(start 331.252068 -58.071004)
						(mid 331.288439 -58.128867)
						(end 331.346302 -58.165238)
					)
					(arc
						(start 331.346302 -58.270394)
						(mid 331.216581 -58.200725)
						(end 331.146912 -58.071004)
					)
				)
			)
		)
		(zone
			(layer "F.Cu")
			(hatch none 0.5)
			(connect_pads
				(clearance 0)
			)
			(min_thickness 0.25)
			(keepout
				(tracks not_allowed)
				(vias allowed)
				(pads allowed)
				(copperpour not_allowed)
				(footprints allowed)
			)
			(placement
				(enabled no)
				(sheetname "")
			)
			(fill
				(thermal_gap 0.5)
				(thermal_bridge_width 0.5)
				(island_removal_mode 0)
			)
			(polygon
				(pts
					(arc
						(start 331.252068 -38.931088)
						(mid 331.288439 -38.988951)
						(end 331.346302 -39.025322)
					)
					(arc
						(start 331.346302 -39.130478)
						(mid 331.216581 -39.060809)
						(end 331.146912 -38.931088)
					)
				)
			)
		)
		(zone
			(layer "F.Cu")
			(hatch none 0.5)
			(connect_pads
				(clearance 0)
			)
			(min_thickness 0.25)
			(keepout
				(tracks not_allowed)
				(vias allowed)
				(pads allowed)
				(copperpour not_allowed)
				(footprints allowed)
			)
			(placement
				(enabled no)
				(sheetname "")
			)
			(fill
				(thermal_gap 0.5)
				(thermal_bridge_width 0.5)
				(island_removal_mode 0)
			)
			(polygon
				(pts
					(arc
						(start 331.252068 -38.101016)
						(mid 331.288439 -38.158879)
						(end 331.346302 -38.19525)
					)
					(arc
						(start 331.346302 -38.300406)
						(mid 331.216581 -38.230737)
						(end 331.146912 -38.101016)
					)
				)
			)
		)
		(zone
			(layer "F.Cu")
			(hatch none 0.5)
			(connect_pads
				(clearance 0)
			)
			(min_thickness 0.25)
			(keepout
				(tracks not_allowed)
				(vias allowed)
				(pads allowed)
				(copperpour not_allowed)
				(footprints allowed)
			)
			(placement
				(enabled no)
				(sheetname "")
			)
			(fill
				(thermal_gap 0.5)
				(thermal_bridge_width 0.5)
				(island_removal_mode 0)
			)
			(polygon
				(pts
					(arc
						(start 331.346302 -58.705242)
						(mid 331.288439 -58.741613)
						(end 331.252068 -58.799476)
					)
					(arc
						(start 331.146912 -58.799476)
						(mid 331.216581 -58.669755)
						(end 331.346302 -58.600086)
					)
				)
			)
		)
		(zone
			(layer "F.Cu")
			(hatch none 0.5)
			(connect_pads
				(clearance 0)
			)
			(min_thickness 0.25)
			(keepout
				(tracks not_allowed)
				(vias allowed)
				(pads allowed)
				(copperpour not_allowed)
				(footprints allowed)
			)
			(placement
				(enabled no)
				(sheetname "")
			)
			(fill
				(thermal_gap 0.5)
				(thermal_bridge_width 0.5)
				(island_removal_mode 0)
			)
			(polygon
				(pts
					(arc
						(start 331.346302 -57.87517)
						(mid 331.288439 -57.911541)
						(end 331.252068 -57.969404)
					)
					(arc
						(start 331.146912 -57.969404)
						(mid 331.216581 -57.839683)
						(end 331.346302 -57.770014)
					)
				)
			)
		)
		(zone
			(layer "F.Cu")
			(hatch none 0.5)
			(connect_pads
				(clearance 0)
			)
			(min_thickness 0.25)
			(keepout
				(tracks not_allowed)
				(vias allowed)
				(pads allowed)
				(copperpour not_allowed)
				(footprints allowed)
			)
			(placement
				(enabled no)
				(sheetname "")
			)
			(fill
				(thermal_gap 0.5)
				(thermal_bridge_width 0.5)
				(island_removal_mode 0)
			)
			(polygon
				(pts
					(arc
						(start 331.346302 -38.735254)
						(mid 331.288439 -38.771625)
						(end 331.252068 -38.829488)
					)
					(arc
						(start 331.146912 -38.829488)
						(mid 331.216581 -38.699767)
						(end 331.346302 -38.630098)
					)
				)
			)
		)
		(zone
			(layer "F.Cu")
			(hatch none 0.5)
			(connect_pads
				(clearance 0)
			)
			(min_thickness 0.25)
			(keepout
				(tracks not_allowed)
				(vias allowed)
				(pads allowed)
				(copperpour not_allowed)
				(footprints allowed)
			)
			(placement
				(enabled no)
				(sheetname "")
			)
			(fill
				(thermal_gap 0.5)
				(thermal_bridge_width 0.5)
				(island_removal_mode 0)
			)
			(polygon
				(pts
					(arc
						(start 331.346302 -37.905182)
						(mid 331.288439 -37.941553)
						(end 331.252068 -37.999416)
					)
					(arc
						(start 331.146912 -37.999416)
						(mid 331.216581 -37.869695)
						(end 331.346302 -37.800026)
					)
				)
			)
		)
		(zone
			(layer "F.Cu")
			(hatch none 0.5)
			(connect_pads
				(clearance 0)
			)
			(min_thickness 0.25)
			(keepout
				(tracks not_allowed)
				(vias allowed)
				(pads allowed)
				(copperpour not_allowed)
				(footprints allowed)
			)
			(placement
				(enabled no)
				(sheetname "")
			)
			(fill
				(thermal_gap 0.5)
				(thermal_bridge_width 0.5)
				(island_removal_mode 0)
			)
			(polygon
				(pts
					(arc
						(start 331.447902 -58.99531)
						(mid 331.505765 -58.958939)
						(end 331.542136 -58.901076)
					)
					(arc
						(start 331.647292 -58.901076)
						(mid 331.577623 -59.030797)
						(end 331.447902 -59.100466)
					)
				)
			)
		)
		(zone
			(layer "F.Cu")
			(hatch none 0.5)
			(connect_pads
				(clearance 0)
			)
			(min_thickness 0.25)
			(keepout
				(tracks not_allowed)
				(vias allowed)
				(pads allowed)
				(copperpour not_allowed)
				(footprints allowed)
			)
			(placement
				(enabled no)
				(sheetname "")
			)
			(fill
				(thermal_gap 0.5)
				(thermal_bridge_width 0.5)
				(island_removal_mode 0)
			)
			(polygon
				(pts
					(arc
						(start 331.447902 -58.165238)
						(mid 331.505765 -58.128867)
						(end 331.542136 -58.071004)
					)
					(arc
						(start 331.647292 -58.071004)
						(mid 331.577623 -58.200725)
						(end 331.447902 -58.270394)
					)
				)
			)
		)
		(zone
			(layer "F.Cu")
			(hatch none 0.5)
			(connect_pads
				(clearance 0)
			)
			(min_thickness 0.25)
			(keepout
				(tracks not_allowed)
				(vias allowed)
				(pads allowed)
				(copperpour not_allowed)
				(footprints allowed)
			)
			(placement
				(enabled no)
				(sheetname "")
			)
			(fill
				(thermal_gap 0.5)
				(thermal_bridge_width 0.5)
				(island_removal_mode 0)
			)
			(polygon
				(pts
					(arc
						(start 331.447902 -39.025322)
						(mid 331.505765 -38.988951)
						(end 331.542136 -38.931088)
					)
					(arc
						(start 331.647292 -38.931088)
						(mid 331.577623 -39.060809)
						(end 331.447902 -39.130478)
					)
				)
			)
		)
		(zone
			(layer "F.Cu")
			(hatch none 0.5)
			(connect_pads
				(clearance 0)
			)
			(min_thickness 0.25)
			(keepout
				(tracks not_allowed)
				(vias allowed)
				(pads allowed)
				(copperpour not_allowed)
				(footprints allowed)
			)
			(placement
				(enabled no)
				(sheetname "")
			)
			(fill
				(thermal_gap 0.5)
				(thermal_bridge_width 0.5)
				(island_removal_mode 0)
			)
			(polygon
				(pts
					(arc
						(start 331.447902 -38.19525)
						(mid 331.505765 -38.158879)
						(end 331.542136 -38.101016)
					)
					(arc
						(start 331.647292 -38.101016)
						(mid 331.577623 -38.230737)
						(end 331.447902 -38.300406)
					)
				)
			)
		)
		(zone
			(layer "F.Cu")
			(hatch none 0.5)
			(connect_pads
				(clearance 0)
			)
			(min_thickness 0.25)
			(keepout
				(tracks not_allowed)
				(vias allowed)
				(pads allowed)
				(copperpour not_allowed)
				(footprints allowed)
			)
			(placement
				(enabled no)
				(sheetname "")
			)
			(fill
				(thermal_gap 0.5)
				(thermal_bridge_width 0.5)
				(island_removal_mode 0)
			)
			(polygon
				(pts
					(arc
						(start 331.542136 -58.799476)
						(mid 331.505765 -58.741613)
						(end 331.447902 -58.705242)
					)
					(arc
						(start 331.447902 -58.600086)
						(mid 331.577623 -58.669755)
						(end 331.647292 -58.799476)
					)
				)
			)
		)
		(zone
			(layer "F.Cu")
			(hatch none 0.5)
			(connect_pads
				(clearance 0)
			)
			(min_thickness 0.25)
			(keepout
				(tracks not_allowed)
				(vias allowed)
				(pads allowed)
				(copperpour not_allowed)
				(footprints allowed)
			)
			(placement
				(enabled no)
				(sheetname "")
			)
			(fill
				(thermal_gap 0.5)
				(thermal_bridge_width 0.5)
				(island_removal_mode 0)
			)
			(polygon
				(pts
					(arc
						(start 331.542136 -57.969404)
						(mid 331.505765 -57.911541)
						(end 331.447902 -57.87517)
					)
					(arc
						(start 331.447902 -57.770014)
						(mid 331.577623 -57.839683)
						(end 331.647292 -57.969404)
					)
				)
			)
		)
		(zone
			(layer "F.Cu")
			(hatch none 0.5)
			(connect_pads
				(clearance 0)
			)
			(min_thickness 0.25)
			(keepout
				(tracks not_allowed)
				(vias allowed)
				(pads allowed)
				(copperpour not_allowed)
				(footprints allowed)
			)
			(placement
				(enabled no)
				(sheetname "")
			)
			(fill
				(thermal_gap 0.5)
				(thermal_bridge_width 0.5)
				(island_removal_mode 0)
			)
			(polygon
				(pts
					(arc
						(start 331.542136 -38.829488)
						(mid 331.505765 -38.771625)
						(end 331.447902 -38.735254)
					)
					(arc
						(start 331.447902 -38.630098)
						(mid 331.577623 -38.699767)
						(end 331.647292 -38.829488)
					)
				)
			)
		)
		(zone
			(layer "F.Cu")
			(hatch none 0.5)
			(connect_pads
				(clearance 0)
			)
			(min_thickness 0.25)
			(keepout
				(tracks not_allowed)
				(vias allowed)
				(pads allowed)
				(copperpour not_allowed)
				(footprints allowed)
			)
			(placement
				(enabled no)
				(sheetname "")
			)
			(fill
				(thermal_gap 0.5)
				(thermal_bridge_width 0.5)
				(island_removal_mode 0)
			)
			(polygon
				(pts
					(arc
						(start 331.542136 -37.999416)
						(mid 331.505765 -37.941553)
						(end 331.447902 -37.905182)
					)
					(arc
						(start 331.447902 -37.800026)
						(mid 331.577623 -37.869695)
						(end 331.647292 -37.999416)
					)
				)
			)
		)
		(zone
			(layer "F.Cu")
			(hatch none 0.5)
			(connect_pads
				(clearance 0)
			)
			(min_thickness 0.25)
			(keepout
				(tracks not_allowed)
				(vias allowed)
				(pads allowed)
				(copperpour not_allowed)
				(footprints allowed)
			)
			(placement
				(enabled no)
				(sheetname "")
			)
			(fill
				(thermal_gap 0.5)
				(thermal_bridge_width 0.5)
				(island_removal_mode 0)
			)
			(polygon
				(pts
					(arc
						(start 331.752194 -58.48604)
						(mid 331.78862 -58.543739)
						(end 331.846428 -58.58002)
					)
					(arc
						(start 331.846428 -58.68543)
						(mid 331.716707 -58.615761)
						(end 331.647038 -58.48604)
					)
				)
			)
		)
		(zone
			(layer "F.Cu")
			(hatch none 0.5)
			(connect_pads
				(clearance 0)
			)
			(min_thickness 0.25)
			(keepout
				(tracks not_allowed)
				(vias allowed)
				(pads allowed)
				(copperpour not_allowed)
				(footprints allowed)
			)
			(placement
				(enabled no)
				(sheetname "")
			)
			(fill
				(thermal_gap 0.5)
				(thermal_bridge_width 0.5)
				(island_removal_mode 0)
			)
			(polygon
				(pts
					(arc
						(start 331.752194 -57.655968)
						(mid 331.788565 -57.713831)
						(end 331.846428 -57.750202)
					)
					(arc
						(start 331.846428 -57.855358)
						(mid 331.716707 -57.785689)
						(end 331.647038 -57.655968)
					)
				)
			)
		)
		(zone
			(layer "F.Cu")
			(hatch none 0.5)
			(connect_pads
				(clearance 0)
			)
			(min_thickness 0.25)
			(keepout
				(tracks not_allowed)
				(vias allowed)
				(pads allowed)
				(copperpour not_allowed)
				(footprints allowed)
			)
			(placement
				(enabled no)
				(sheetname "")
			)
			(fill
				(thermal_gap 0.5)
				(thermal_bridge_width 0.5)
				(island_removal_mode 0)
			)
			(polygon
				(pts
					(arc
						(start 331.752448 -39.346124)
						(mid 331.788819 -39.403987)
						(end 331.846682 -39.440358)
					)
					(arc
						(start 331.846682 -39.545514)
						(mid 331.716831 -39.475897)
						(end 331.647038 -39.346124)
					)
				)
			)
		)
		(zone
			(layer "F.Cu")
			(hatch none 0.5)
			(connect_pads
				(clearance 0)
			)
			(min_thickness 0.25)
			(keepout
				(tracks not_allowed)
				(vias allowed)
				(pads allowed)
				(copperpour not_allowed)
				(footprints allowed)
			)
			(placement
				(enabled no)
				(sheetname "")
			)
			(fill
				(thermal_gap 0.5)
				(thermal_bridge_width 0.5)
				(island_removal_mode 0)
			)
			(polygon
				(pts
					(arc
						(start 331.752448 -38.516052)
						(mid 331.788819 -38.573915)
						(end 331.846682 -38.610286)
					)
					(arc
						(start 331.846682 -38.715442)
						(mid 331.716831 -38.645825)
						(end 331.647038 -38.516052)
					)
				)
			)
		)
		(zone
			(layer "F.Cu")
			(hatch none 0.5)
			(connect_pads
				(clearance 0)
			)
			(min_thickness 0.25)
			(keepout
				(tracks not_allowed)
				(vias allowed)
				(pads allowed)
				(copperpour not_allowed)
				(footprints allowed)
			)
			(placement
				(enabled no)
				(sheetname "")
			)
			(fill
				(thermal_gap 0.5)
				(thermal_bridge_width 0.5)
				(island_removal_mode 0)
			)
			(polygon
				(pts
					(arc
						(start 331.846428 -58.290206)
						(mid 331.788565 -58.326577)
						(end 331.752194 -58.38444)
					)
					(arc
						(start 331.647038 -58.38444)
						(mid 331.716707 -58.254719)
						(end 331.846428 -58.18505)
					)
				)
			)
		)
		(zone
			(layer "F.Cu")
			(hatch none 0.5)
			(connect_pads
				(clearance 0)
			)
			(min_thickness 0.25)
			(keepout
				(tracks not_allowed)
				(vias allowed)
				(pads allowed)
				(copperpour not_allowed)
				(footprints allowed)
			)
			(placement
				(enabled no)
				(sheetname "")
			)
			(fill
				(thermal_gap 0.5)
				(thermal_bridge_width 0.5)
				(island_removal_mode 0)
			)
			(polygon
				(pts
					(arc
						(start 331.846428 -57.460134)
						(mid 331.788565 -57.496505)
						(end 331.752194 -57.554368)
					)
					(arc
						(start 331.647038 -57.554368)
						(mid 331.716707 -57.424647)
						(end 331.846428 -57.354978)
					)
				)
			)
		)
		(zone
			(layer "F.Cu")
			(hatch none 0.5)
			(connect_pads
				(clearance 0)
			)
			(min_thickness 0.25)
			(keepout
				(tracks not_allowed)
				(vias allowed)
				(pads allowed)
				(copperpour not_allowed)
				(footprints allowed)
			)
			(placement
				(enabled no)
				(sheetname "")
			)
			(fill
				(thermal_gap 0.5)
				(thermal_bridge_width 0.5)
				(island_removal_mode 0)
			)
			(polygon
				(pts
					(arc
						(start 331.846682 -39.15029)
						(mid 331.788819 -39.186661)
						(end 331.752448 -39.244524)
					)
					(arc
						(start 331.647038 -39.244524)
						(mid 331.716795 -39.114715)
						(end 331.846682 -39.045134)
					)
				)
			)
		)
		(zone
			(layer "F.Cu")
			(hatch none 0.5)
			(connect_pads
				(clearance 0)
			)
			(min_thickness 0.25)
			(keepout
				(tracks not_allowed)
				(vias allowed)
				(pads allowed)
				(copperpour not_allowed)
				(footprints allowed)
			)
			(placement
				(enabled no)
				(sheetname "")
			)
			(fill
				(thermal_gap 0.5)
				(thermal_bridge_width 0.5)
				(island_removal_mode 0)
			)
			(polygon
				(pts
					(arc
						(start 331.846682 -38.320218)
						(mid 331.788819 -38.356589)
						(end 331.752448 -38.414452)
					)
					(arc
						(start 331.647038 -38.414452)
						(mid 331.716795 -38.284643)
						(end 331.846682 -38.215062)
					)
				)
			)
		)
		(zone
			(layer "F.Cu")
			(hatch none 0.5)
			(connect_pads
				(clearance 0)
			)
			(min_thickness 0.25)
			(keepout
				(tracks not_allowed)
				(vias allowed)
				(pads allowed)
				(copperpour not_allowed)
				(footprints allowed)
			)
			(placement
				(enabled no)
				(sheetname "")
			)
			(fill
				(thermal_gap 0.5)
				(thermal_bridge_width 0.5)
				(island_removal_mode 0)
			)
			(polygon
				(pts
					(arc
						(start 331.948028 -58.58002)
						(mid 332.005887 -58.543789)
						(end 332.042262 -58.48604)
					)
					(arc
						(start 332.147418 -58.48604)
						(mid 332.077749 -58.615761)
						(end 331.948028 -58.68543)
					)
				)
			)
		)
		(zone
			(layer "F.Cu")
			(hatch none 0.5)
			(connect_pads
				(clearance 0)
			)
			(min_thickness 0.25)
			(keepout
				(tracks not_allowed)
				(vias allowed)
				(pads allowed)
				(copperpour not_allowed)
				(footprints allowed)
			)
			(placement
				(enabled no)
				(sheetname "")
			)
			(fill
				(thermal_gap 0.5)
				(thermal_bridge_width 0.5)
				(island_removal_mode 0)
			)
			(polygon
				(pts
					(arc
						(start 331.948028 -57.750202)
						(mid 332.005891 -57.713831)
						(end 332.042262 -57.655968)
					)
					(arc
						(start 332.147418 -57.655968)
						(mid 332.077749 -57.785689)
						(end 331.948028 -57.855358)
					)
				)
			)
		)
		(zone
			(layer "F.Cu")
			(hatch none 0.5)
			(connect_pads
				(clearance 0)
			)
			(min_thickness 0.25)
			(keepout
				(tracks not_allowed)
				(vias allowed)
				(pads allowed)
				(copperpour not_allowed)
				(footprints allowed)
			)
			(placement
				(enabled no)
				(sheetname "")
			)
			(fill
				(thermal_gap 0.5)
				(thermal_bridge_width 0.5)
				(island_removal_mode 0)
			)
			(polygon
				(pts
					(arc
						(start 331.948282 -39.440358)
						(mid 332.005981 -39.403932)
						(end 332.042262 -39.346124)
					)
					(arc
						(start 332.147672 -39.346124)
						(mid 332.078003 -39.475845)
						(end 331.948282 -39.545514)
					)
				)
			)
		)
		(zone
			(layer "F.Cu")
			(hatch none 0.5)
			(connect_pads
				(clearance 0)
			)
			(min_thickness 0.25)
			(keepout
				(tracks not_allowed)
				(vias allowed)
				(pads allowed)
				(copperpour not_allowed)
				(footprints allowed)
			)
			(placement
				(enabled no)
				(sheetname "")
			)
			(fill
				(thermal_gap 0.5)
				(thermal_bridge_width 0.5)
				(island_removal_mode 0)
			)
			(polygon
				(pts
					(arc
						(start 331.948282 -38.610286)
						(mid 332.005981 -38.57386)
						(end 332.042262 -38.516052)
					)
					(arc
						(start 332.147672 -38.516052)
						(mid 332.078003 -38.645773)
						(end 331.948282 -38.715442)
					)
				)
			)
		)
		(zone
			(layer "F.Cu")
			(hatch none 0.5)
			(connect_pads
				(clearance 0)
			)
			(min_thickness 0.25)
			(keepout
				(tracks not_allowed)
				(vias allowed)
				(pads allowed)
				(copperpour not_allowed)
				(footprints allowed)
			)
			(placement
				(enabled no)
				(sheetname "")
			)
			(fill
				(thermal_gap 0.5)
				(thermal_bridge_width 0.5)
				(island_removal_mode 0)
			)
			(polygon
				(pts
					(arc
						(start 332.042262 -58.38444)
						(mid 332.005891 -58.326577)
						(end 331.948028 -58.290206)
					)
					(arc
						(start 331.948028 -58.18505)
						(mid 332.077749 -58.254719)
						(end 332.147418 -58.38444)
					)
				)
			)
		)
		(zone
			(layer "F.Cu")
			(hatch none 0.5)
			(connect_pads
				(clearance 0)
			)
			(min_thickness 0.25)
			(keepout
				(tracks not_allowed)
				(vias allowed)
				(pads allowed)
				(copperpour not_allowed)
				(footprints allowed)
			)
			(placement
				(enabled no)
				(sheetname "")
			)
			(fill
				(thermal_gap 0.5)
				(thermal_bridge_width 0.5)
				(island_removal_mode 0)
			)
			(polygon
				(pts
					(arc
						(start 332.042262 -57.554368)
						(mid 332.005891 -57.496505)
						(end 331.948028 -57.460134)
					)
					(arc
						(start 331.948028 -57.354978)
						(mid 332.077749 -57.424647)
						(end 332.147418 -57.554368)
					)
				)
			)
		)
		(zone
			(layer "F.Cu")
			(hatch none 0.5)
			(connect_pads
				(clearance 0)
			)
			(min_thickness 0.25)
			(keepout
				(tracks not_allowed)
				(vias allowed)
				(pads allowed)
				(copperpour not_allowed)
				(footprints allowed)
			)
			(placement
				(enabled no)
				(sheetname "")
			)
			(fill
				(thermal_gap 0.5)
				(thermal_bridge_width 0.5)
				(island_removal_mode 0)
			)
			(polygon
				(pts
					(arc
						(start 332.042262 -39.244524)
						(mid 332.005976 -39.186745)
						(end 331.948282 -39.15029)
					)
					(arc
						(start 331.948282 -39.045134)
						(mid 332.078003 -39.114803)
						(end 332.147672 -39.244524)
					)
				)
			)
		)
		(zone
			(layer "F.Cu")
			(hatch none 0.5)
			(connect_pads
				(clearance 0)
			)
			(min_thickness 0.25)
			(keepout
				(tracks not_allowed)
				(vias allowed)
				(pads allowed)
				(copperpour not_allowed)
				(footprints allowed)
			)
			(placement
				(enabled no)
				(sheetname "")
			)
			(fill
				(thermal_gap 0.5)
				(thermal_bridge_width 0.5)
				(island_removal_mode 0)
			)
			(polygon
				(pts
					(arc
						(start 332.042262 -38.414452)
						(mid 332.006031 -38.356593)
						(end 331.948282 -38.320218)
					)
					(arc
						(start 331.948282 -38.215062)
						(mid 332.078003 -38.284731)
						(end 332.147672 -38.414452)
					)
				)
			)
		)
		(zone
			(layer "F.Cu")
			(hatch none 0.5)
			(connect_pads
				(clearance 0)
			)
			(min_thickness 0.25)
			(keepout
				(tracks not_allowed)
				(vias allowed)
				(pads allowed)
				(copperpour not_allowed)
				(footprints allowed)
			)
			(placement
				(enabled no)
				(sheetname "")
			)
			(fill
				(thermal_gap 0.5)
				(thermal_bridge_width 0.5)
				(island_removal_mode 0)
			)
			(polygon
				(pts
					(arc
						(start 332.252574 -58.901076)
						(mid 332.288945 -58.958939)
						(end 332.346808 -58.99531)
					)
					(arc
						(start 332.346808 -59.100466)
						(mid 332.217087 -59.030797)
						(end 332.147418 -58.901076)
					)
				)
			)
		)
		(zone
			(layer "F.Cu")
			(hatch none 0.5)
			(connect_pads
				(clearance 0)
			)
			(min_thickness 0.25)
			(keepout
				(tracks not_allowed)
				(vias allowed)
				(pads allowed)
				(copperpour not_allowed)
				(footprints allowed)
			)
			(placement
				(enabled no)
				(sheetname "")
			)
			(fill
				(thermal_gap 0.5)
				(thermal_bridge_width 0.5)
				(island_removal_mode 0)
			)
			(polygon
				(pts
					(arc
						(start 332.252574 -58.071004)
						(mid 332.288945 -58.128867)
						(end 332.346808 -58.165238)
					)
					(arc
						(start 332.346808 -58.270394)
						(mid 332.217087 -58.200725)
						(end 332.147418 -58.071004)
					)
				)
			)
		)
		(zone
			(layer "F.Cu")
			(hatch none 0.5)
			(connect_pads
				(clearance 0)
			)
			(min_thickness 0.25)
			(keepout
				(tracks not_allowed)
				(vias allowed)
				(pads allowed)
				(copperpour not_allowed)
				(footprints allowed)
			)
			(placement
				(enabled no)
				(sheetname "")
			)
			(fill
				(thermal_gap 0.5)
				(thermal_bridge_width 0.5)
				(island_removal_mode 0)
			)
			(polygon
				(pts
					(arc
						(start 332.252574 -38.931088)
						(mid 332.288945 -38.988951)
						(end 332.346808 -39.025322)
					)
					(arc
						(start 332.346808 -39.130478)
						(mid 332.217087 -39.060809)
						(end 332.147418 -38.931088)
					)
				)
			)
		)
		(zone
			(layer "F.Cu")
			(hatch none 0.5)
			(connect_pads
				(clearance 0)
			)
			(min_thickness 0.25)
			(keepout
				(tracks not_allowed)
				(vias allowed)
				(pads allowed)
				(copperpour not_allowed)
				(footprints allowed)
			)
			(placement
				(enabled no)
				(sheetname "")
			)
			(fill
				(thermal_gap 0.5)
				(thermal_bridge_width 0.5)
				(island_removal_mode 0)
			)
			(polygon
				(pts
					(arc
						(start 332.252574 -38.101016)
						(mid 332.288945 -38.158879)
						(end 332.346808 -38.19525)
					)
					(arc
						(start 332.346808 -38.300406)
						(mid 332.217087 -38.230737)
						(end 332.147418 -38.101016)
					)
				)
			)
		)
		(zone
			(layer "F.Cu")
			(hatch none 0.5)
			(connect_pads
				(clearance 0)
			)
			(min_thickness 0.25)
			(keepout
				(tracks not_allowed)
				(vias allowed)
				(pads allowed)
				(copperpour not_allowed)
				(footprints allowed)
			)
			(placement
				(enabled no)
				(sheetname "")
			)
			(fill
				(thermal_gap 0.5)
				(thermal_bridge_width 0.5)
				(island_removal_mode 0)
			)
			(polygon
				(pts
					(arc
						(start 332.346808 -58.705242)
						(mid 332.288945 -58.741613)
						(end 332.252574 -58.799476)
					)
					(arc
						(start 332.147418 -58.799476)
						(mid 332.217087 -58.669755)
						(end 332.346808 -58.600086)
					)
				)
			)
		)
		(zone
			(layer "F.Cu")
			(hatch none 0.5)
			(connect_pads
				(clearance 0)
			)
			(min_thickness 0.25)
			(keepout
				(tracks not_allowed)
				(vias allowed)
				(pads allowed)
				(copperpour not_allowed)
				(footprints allowed)
			)
			(placement
				(enabled no)
				(sheetname "")
			)
			(fill
				(thermal_gap 0.5)
				(thermal_bridge_width 0.5)
				(island_removal_mode 0)
			)
			(polygon
				(pts
					(arc
						(start 332.346808 -57.87517)
						(mid 332.288945 -57.911541)
						(end 332.252574 -57.969404)
					)
					(arc
						(start 332.147418 -57.969404)
						(mid 332.217087 -57.839683)
						(end 332.346808 -57.770014)
					)
				)
			)
		)
		(zone
			(layer "F.Cu")
			(hatch none 0.5)
			(connect_pads
				(clearance 0)
			)
			(min_thickness 0.25)
			(keepout
				(tracks not_allowed)
				(vias allowed)
				(pads allowed)
				(copperpour not_allowed)
				(footprints allowed)
			)
			(placement
				(enabled no)
				(sheetname "")
			)
			(fill
				(thermal_gap 0.5)
				(thermal_bridge_width 0.5)
				(island_removal_mode 0)
			)
			(polygon
				(pts
					(arc
						(start 332.346808 -38.735254)
						(mid 332.288945 -38.771625)
						(end 332.252574 -38.829488)
					)
					(arc
						(start 332.147418 -38.829488)
						(mid 332.217087 -38.699767)
						(end 332.346808 -38.630098)
					)
				)
			)
		)
		(zone
			(layer "F.Cu")
			(hatch none 0.5)
			(connect_pads
				(clearance 0)
			)
			(min_thickness 0.25)
			(keepout
				(tracks not_allowed)
				(vias allowed)
				(pads allowed)
				(copperpour not_allowed)
				(footprints allowed)
			)
			(placement
				(enabled no)
				(sheetname "")
			)
			(fill
				(thermal_gap 0.5)
				(thermal_bridge_width 0.5)
				(island_removal_mode 0)
			)
			(polygon
				(pts
					(arc
						(start 332.346808 -37.905182)
						(mid 332.288945 -37.941553)
						(end 332.252574 -37.999416)
					)
					(arc
						(start 332.147418 -37.999416)
						(mid 332.217087 -37.869695)
						(end 332.346808 -37.800026)
					)
				)
			)
		)
		(zone
			(layer "F.Cu")
			(hatch none 0.5)
			(connect_pads
				(clearance 0)
			)
			(min_thickness 0.25)
			(keepout
				(tracks not_allowed)
				(vias allowed)
				(pads allowed)
				(copperpour not_allowed)
				(footprints allowed)
			)
			(placement
				(enabled no)
				(sheetname "")
			)
			(fill
				(thermal_gap 0.5)
				(thermal_bridge_width 0.5)
				(island_removal_mode 0)
			)
			(polygon
				(pts
					(arc
						(start 332.448408 -58.99531)
						(mid 332.506271 -58.958939)
						(end 332.542642 -58.901076)
					)
					(arc
						(start 332.647798 -58.901076)
						(mid 332.578129 -59.030797)
						(end 332.448408 -59.100466)
					)
				)
			)
		)
		(zone
			(layer "F.Cu")
			(hatch none 0.5)
			(connect_pads
				(clearance 0)
			)
			(min_thickness 0.25)
			(keepout
				(tracks not_allowed)
				(vias allowed)
				(pads allowed)
				(copperpour not_allowed)
				(footprints allowed)
			)
			(placement
				(enabled no)
				(sheetname "")
			)
			(fill
				(thermal_gap 0.5)
				(thermal_bridge_width 0.5)
				(island_removal_mode 0)
			)
			(polygon
				(pts
					(arc
						(start 332.448408 -58.165238)
						(mid 332.506271 -58.128867)
						(end 332.542642 -58.071004)
					)
					(arc
						(start 332.647798 -58.071004)
						(mid 332.578129 -58.200725)
						(end 332.448408 -58.270394)
					)
				)
			)
		)
		(zone
			(layer "F.Cu")
			(hatch none 0.5)
			(connect_pads
				(clearance 0)
			)
			(min_thickness 0.25)
			(keepout
				(tracks not_allowed)
				(vias allowed)
				(pads allowed)
				(copperpour not_allowed)
				(footprints allowed)
			)
			(placement
				(enabled no)
				(sheetname "")
			)
			(fill
				(thermal_gap 0.5)
				(thermal_bridge_width 0.5)
				(island_removal_mode 0)
			)
			(polygon
				(pts
					(arc
						(start 332.448408 -39.025322)
						(mid 332.506271 -38.988951)
						(end 332.542642 -38.931088)
					)
					(arc
						(start 332.647798 -38.931088)
						(mid 332.578129 -39.060809)
						(end 332.448408 -39.130478)
					)
				)
			)
		)
		(zone
			(layer "F.Cu")
			(hatch none 0.5)
			(connect_pads
				(clearance 0)
			)
			(min_thickness 0.25)
			(keepout
				(tracks not_allowed)
				(vias allowed)
				(pads allowed)
				(copperpour not_allowed)
				(footprints allowed)
			)
			(placement
				(enabled no)
				(sheetname "")
			)
			(fill
				(thermal_gap 0.5)
				(thermal_bridge_width 0.5)
				(island_removal_mode 0)
			)
			(polygon
				(pts
					(arc
						(start 332.448408 -38.19525)
						(mid 332.506271 -38.158879)
						(end 332.542642 -38.101016)
					)
					(arc
						(start 332.647798 -38.101016)
						(mid 332.578129 -38.230737)
						(end 332.448408 -38.300406)
					)
				)
			)
		)
		(zone
			(layer "F.Cu")
			(hatch none 0.5)
			(connect_pads
				(clearance 0)
			)
			(min_thickness 0.25)
			(keepout
				(tracks not_allowed)
				(vias allowed)
				(pads allowed)
				(copperpour not_allowed)
				(footprints allowed)
			)
			(placement
				(enabled no)
				(sheetname "")
			)
			(fill
				(thermal_gap 0.5)
				(thermal_bridge_width 0.5)
				(island_removal_mode 0)
			)
			(polygon
				(pts
					(arc
						(start 332.542642 -58.799476)
						(mid 332.506271 -58.741613)
						(end 332.448408 -58.705242)
					)
					(arc
						(start 332.448408 -58.600086)
						(mid 332.578129 -58.669755)
						(end 332.647798 -58.799476)
					)
				)
			)
		)
		(zone
			(layer "F.Cu")
			(hatch none 0.5)
			(connect_pads
				(clearance 0)
			)
			(min_thickness 0.25)
			(keepout
				(tracks not_allowed)
				(vias allowed)
				(pads allowed)
				(copperpour not_allowed)
				(footprints allowed)
			)
			(placement
				(enabled no)
				(sheetname "")
			)
			(fill
				(thermal_gap 0.5)
				(thermal_bridge_width 0.5)
				(island_removal_mode 0)
			)
			(polygon
				(pts
					(arc
						(start 332.542642 -57.969404)
						(mid 332.506271 -57.911541)
						(end 332.448408 -57.87517)
					)
					(arc
						(start 332.448408 -57.770014)
						(mid 332.578129 -57.839683)
						(end 332.647798 -57.969404)
					)
				)
			)
		)
		(zone
			(layer "F.Cu")
			(hatch none 0.5)
			(connect_pads
				(clearance 0)
			)
			(min_thickness 0.25)
			(keepout
				(tracks not_allowed)
				(vias allowed)
				(pads allowed)
				(copperpour not_allowed)
				(footprints allowed)
			)
			(placement
				(enabled no)
				(sheetname "")
			)
			(fill
				(thermal_gap 0.5)
				(thermal_bridge_width 0.5)
				(island_removal_mode 0)
			)
			(polygon
				(pts
					(arc
						(start 332.542642 -38.829488)
						(mid 332.506271 -38.771625)
						(end 332.448408 -38.735254)
					)
					(arc
						(start 332.448408 -38.630098)
						(mid 332.578129 -38.699767)
						(end 332.647798 -38.829488)
					)
				)
			)
		)
		(zone
			(layer "F.Cu")
			(hatch none 0.5)
			(connect_pads
				(clearance 0)
			)
			(min_thickness 0.25)
			(keepout
				(tracks not_allowed)
				(vias allowed)
				(pads allowed)
				(copperpour not_allowed)
				(footprints allowed)
			)
			(placement
				(enabled no)
				(sheetname "")
			)
			(fill
				(thermal_gap 0.5)
				(thermal_bridge_width 0.5)
				(island_removal_mode 0)
			)
			(polygon
				(pts
					(arc
						(start 332.542642 -37.999416)
						(mid 332.506271 -37.941553)
						(end 332.448408 -37.905182)
					)
					(arc
						(start 332.448408 -37.800026)
						(mid 332.578129 -37.869695)
						(end 332.647798 -37.999416)
					)
				)
			)
		)
		(zone
			(layer "F.Cu")
			(hatch none 0.5)
			(connect_pads
				(clearance 0)
			)
			(min_thickness 0.25)
			(keepout
				(tracks not_allowed)
				(vias allowed)
				(pads allowed)
				(copperpour not_allowed)
				(footprints allowed)
			)
			(placement
				(enabled no)
				(sheetname "")
			)
			(fill
				(thermal_gap 0.5)
				(thermal_bridge_width 0.5)
				(island_removal_mode 0)
			)
			(polygon
				(pts
					(arc
						(start 332.7527 -58.48604)
						(mid 332.789126 -58.543739)
						(end 332.846934 -58.58002)
					)
					(arc
						(start 332.846934 -58.68543)
						(mid 332.717213 -58.615761)
						(end 332.647544 -58.48604)
					)
				)
			)
		)
		(zone
			(layer "F.Cu")
			(hatch none 0.5)
			(connect_pads
				(clearance 0)
			)
			(min_thickness 0.25)
			(keepout
				(tracks not_allowed)
				(vias allowed)
				(pads allowed)
				(copperpour not_allowed)
				(footprints allowed)
			)
			(placement
				(enabled no)
				(sheetname "")
			)
			(fill
				(thermal_gap 0.5)
				(thermal_bridge_width 0.5)
				(island_removal_mode 0)
			)
			(polygon
				(pts
					(arc
						(start 332.7527 -57.655968)
						(mid 332.789071 -57.713831)
						(end 332.846934 -57.750202)
					)
					(arc
						(start 332.846934 -57.855358)
						(mid 332.717213 -57.785689)
						(end 332.647544 -57.655968)
					)
				)
			)
		)
		(zone
			(layer "F.Cu")
			(hatch none 0.5)
			(connect_pads
				(clearance 0)
			)
			(min_thickness 0.25)
			(keepout
				(tracks not_allowed)
				(vias allowed)
				(pads allowed)
				(copperpour not_allowed)
				(footprints allowed)
			)
			(placement
				(enabled no)
				(sheetname "")
			)
			(fill
				(thermal_gap 0.5)
				(thermal_bridge_width 0.5)
				(island_removal_mode 0)
			)
			(polygon
				(pts
					(arc
						(start 332.7527 -39.346124)
						(mid 332.789071 -39.403987)
						(end 332.846934 -39.440358)
					)
					(arc
						(start 332.846934 -39.545514)
						(mid 332.717213 -39.475845)
						(end 332.647544 -39.346124)
					)
				)
			)
		)
		(zone
			(layer "F.Cu")
			(hatch none 0.5)
			(connect_pads
				(clearance 0)
			)
			(min_thickness 0.25)
			(keepout
				(tracks not_allowed)
				(vias allowed)
				(pads allowed)
				(copperpour not_allowed)
				(footprints allowed)
			)
			(placement
				(enabled no)
				(sheetname "")
			)
			(fill
				(thermal_gap 0.5)
				(thermal_bridge_width 0.5)
				(island_removal_mode 0)
			)
			(polygon
				(pts
					(arc
						(start 332.752954 -38.516052)
						(mid 332.789185 -38.573911)
						(end 332.846934 -38.610286)
					)
					(arc
						(start 332.846934 -38.715442)
						(mid 332.717213 -38.645773)
						(end 332.647544 -38.516052)
					)
				)
			)
		)
		(zone
			(layer "F.Cu")
			(hatch none 0.5)
			(connect_pads
				(clearance 0)
			)
			(min_thickness 0.25)
			(keepout
				(tracks not_allowed)
				(vias allowed)
				(pads allowed)
				(copperpour not_allowed)
				(footprints allowed)
			)
			(placement
				(enabled no)
				(sheetname "")
			)
			(fill
				(thermal_gap 0.5)
				(thermal_bridge_width 0.5)
				(island_removal_mode 0)
			)
			(polygon
				(pts
					(arc
						(start 332.846934 -58.290206)
						(mid 332.789071 -58.326577)
						(end 332.7527 -58.38444)
					)
					(arc
						(start 332.647544 -58.38444)
						(mid 332.717213 -58.254719)
						(end 332.846934 -58.18505)
					)
				)
			)
		)
		(zone
			(layer "F.Cu")
			(hatch none 0.5)
			(connect_pads
				(clearance 0)
			)
			(min_thickness 0.25)
			(keepout
				(tracks not_allowed)
				(vias allowed)
				(pads allowed)
				(copperpour not_allowed)
				(footprints allowed)
			)
			(placement
				(enabled no)
				(sheetname "")
			)
			(fill
				(thermal_gap 0.5)
				(thermal_bridge_width 0.5)
				(island_removal_mode 0)
			)
			(polygon
				(pts
					(arc
						(start 332.846934 -57.460134)
						(mid 332.789071 -57.496505)
						(end 332.7527 -57.554368)
					)
					(arc
						(start 332.647544 -57.554368)
						(mid 332.717213 -57.424647)
						(end 332.846934 -57.354978)
					)
				)
			)
		)
		(zone
			(layer "F.Cu")
			(hatch none 0.5)
			(connect_pads
				(clearance 0)
			)
			(min_thickness 0.25)
			(keepout
				(tracks not_allowed)
				(vias allowed)
				(pads allowed)
				(copperpour not_allowed)
				(footprints allowed)
			)
			(placement
				(enabled no)
				(sheetname "")
			)
			(fill
				(thermal_gap 0.5)
				(thermal_bridge_width 0.5)
				(island_removal_mode 0)
			)
			(polygon
				(pts
					(arc
						(start 332.846934 -39.15029)
						(mid 332.789071 -39.186661)
						(end 332.7527 -39.244524)
					)
					(arc
						(start 332.647544 -39.244524)
						(mid 332.717213 -39.114803)
						(end 332.846934 -39.045134)
					)
				)
			)
		)
		(zone
			(layer "F.Cu")
			(hatch none 0.5)
			(connect_pads
				(clearance 0)
			)
			(min_thickness 0.25)
			(keepout
				(tracks not_allowed)
				(vias allowed)
				(pads allowed)
				(copperpour not_allowed)
				(footprints allowed)
			)
			(placement
				(enabled no)
				(sheetname "")
			)
			(fill
				(thermal_gap 0.5)
				(thermal_bridge_width 0.5)
				(island_removal_mode 0)
			)
			(polygon
				(pts
					(arc
						(start 332.846934 -38.320218)
						(mid 332.789235 -38.356644)
						(end 332.752954 -38.414452)
					)
					(arc
						(start 332.647544 -38.414452)
						(mid 332.717213 -38.284731)
						(end 332.846934 -38.215062)
					)
				)
			)
		)
		(zone
			(layer "F.Cu")
			(hatch none 0.5)
			(connect_pads
				(clearance 0)
			)
			(min_thickness 0.25)
			(keepout
				(tracks not_allowed)
				(vias allowed)
				(pads allowed)
				(copperpour not_allowed)
				(footprints allowed)
			)
			(placement
				(enabled no)
				(sheetname "")
			)
			(fill
				(thermal_gap 0.5)
				(thermal_bridge_width 0.5)
				(island_removal_mode 0)
			)
			(polygon
				(pts
					(arc
						(start 332.948534 -58.58002)
						(mid 333.006393 -58.543789)
						(end 333.042768 -58.48604)
					)
					(arc
						(start 333.147924 -58.48604)
						(mid 333.078255 -58.615761)
						(end 332.948534 -58.68543)
					)
				)
			)
		)
		(zone
			(layer "F.Cu")
			(hatch none 0.5)
			(connect_pads
				(clearance 0)
			)
			(min_thickness 0.25)
			(keepout
				(tracks not_allowed)
				(vias allowed)
				(pads allowed)
				(copperpour not_allowed)
				(footprints allowed)
			)
			(placement
				(enabled no)
				(sheetname "")
			)
			(fill
				(thermal_gap 0.5)
				(thermal_bridge_width 0.5)
				(island_removal_mode 0)
			)
			(polygon
				(pts
					(arc
						(start 332.948534 -57.750202)
						(mid 333.006397 -57.713831)
						(end 333.042768 -57.655968)
					)
					(arc
						(start 333.147924 -57.655968)
						(mid 333.078255 -57.785689)
						(end 332.948534 -57.855358)
					)
				)
			)
		)
		(zone
			(layer "F.Cu")
			(hatch none 0.5)
			(connect_pads
				(clearance 0)
			)
			(min_thickness 0.25)
			(keepout
				(tracks not_allowed)
				(vias allowed)
				(pads allowed)
				(copperpour not_allowed)
				(footprints allowed)
			)
			(placement
				(enabled no)
				(sheetname "")
			)
			(fill
				(thermal_gap 0.5)
				(thermal_bridge_width 0.5)
				(island_removal_mode 0)
			)
			(polygon
				(pts
					(arc
						(start 332.948534 -39.440358)
						(mid 333.006397 -39.403987)
						(end 333.042768 -39.346124)
					)
					(arc
						(start 333.147924 -39.346124)
						(mid 333.078255 -39.475845)
						(end 332.948534 -39.545514)
					)
				)
			)
		)
		(zone
			(layer "F.Cu")
			(hatch none 0.5)
			(connect_pads
				(clearance 0)
			)
			(min_thickness 0.25)
			(keepout
				(tracks not_allowed)
				(vias allowed)
				(pads allowed)
				(copperpour not_allowed)
				(footprints allowed)
			)
			(placement
				(enabled no)
				(sheetname "")
			)
			(fill
				(thermal_gap 0.5)
				(thermal_bridge_width 0.5)
				(island_removal_mode 0)
			)
			(polygon
				(pts
					(arc
						(start 332.948534 -38.610286)
						(mid 333.006397 -38.573915)
						(end 333.042768 -38.516052)
					)
					(arc
						(start 333.148178 -38.516052)
						(mid 333.078421 -38.645861)
						(end 332.948534 -38.715442)
					)
				)
			)
		)
		(zone
			(layer "F.Cu")
			(hatch none 0.5)
			(connect_pads
				(clearance 0)
			)
			(min_thickness 0.25)
			(keepout
				(tracks not_allowed)
				(vias allowed)
				(pads allowed)
				(copperpour not_allowed)
				(footprints allowed)
			)
			(placement
				(enabled no)
				(sheetname "")
			)
			(fill
				(thermal_gap 0.5)
				(thermal_bridge_width 0.5)
				(island_removal_mode 0)
			)
			(polygon
				(pts
					(arc
						(start 333.042768 -58.38444)
						(mid 333.006397 -58.326577)
						(end 332.948534 -58.290206)
					)
					(arc
						(start 332.948534 -58.18505)
						(mid 333.078255 -58.254719)
						(end 333.147924 -58.38444)
					)
				)
			)
		)
		(zone
			(layer "F.Cu")
			(hatch none 0.5)
			(connect_pads
				(clearance 0)
			)
			(min_thickness 0.25)
			(keepout
				(tracks not_allowed)
				(vias allowed)
				(pads allowed)
				(copperpour not_allowed)
				(footprints allowed)
			)
			(placement
				(enabled no)
				(sheetname "")
			)
			(fill
				(thermal_gap 0.5)
				(thermal_bridge_width 0.5)
				(island_removal_mode 0)
			)
			(polygon
				(pts
					(arc
						(start 333.042768 -57.554368)
						(mid 333.006397 -57.496505)
						(end 332.948534 -57.460134)
					)
					(arc
						(start 332.948534 -57.354978)
						(mid 333.078255 -57.424647)
						(end 333.147924 -57.554368)
					)
				)
			)
		)
		(zone
			(layer "F.Cu")
			(hatch none 0.5)
			(connect_pads
				(clearance 0)
			)
			(min_thickness 0.25)
			(keepout
				(tracks not_allowed)
				(vias allowed)
				(pads allowed)
				(copperpour not_allowed)
				(footprints allowed)
			)
			(placement
				(enabled no)
				(sheetname "")
			)
			(fill
				(thermal_gap 0.5)
				(thermal_bridge_width 0.5)
				(island_removal_mode 0)
			)
			(polygon
				(pts
					(arc
						(start 333.042768 -39.244524)
						(mid 333.006397 -39.186661)
						(end 332.948534 -39.15029)
					)
					(arc
						(start 332.948534 -39.045134)
						(mid 333.078255 -39.114803)
						(end 333.147924 -39.244524)
					)
				)
			)
		)
		(zone
			(layer "F.Cu")
			(hatch none 0.5)
			(connect_pads
				(clearance 0)
			)
			(min_thickness 0.25)
			(keepout
				(tracks not_allowed)
				(vias allowed)
				(pads allowed)
				(copperpour not_allowed)
				(footprints allowed)
			)
			(placement
				(enabled no)
				(sheetname "")
			)
			(fill
				(thermal_gap 0.5)
				(thermal_bridge_width 0.5)
				(island_removal_mode 0)
			)
			(polygon
				(pts
					(arc
						(start 333.042768 -38.414452)
						(mid 333.006397 -38.356589)
						(end 332.948534 -38.320218)
					)
					(arc
						(start 332.948534 -38.215062)
						(mid 333.078385 -38.284679)
						(end 333.148178 -38.414452)
					)
				)
			)
		)
		(zone
			(layer "F.Cu")
			(hatch none 0.5)
			(connect_pads
				(clearance 0)
			)
			(min_thickness 0.25)
			(keepout
				(tracks not_allowed)
				(vias allowed)
				(pads allowed)
				(copperpour not_allowed)
				(footprints allowed)
			)
			(placement
				(enabled no)
				(sheetname "")
			)
			(fill
				(thermal_gap 0.5)
				(thermal_bridge_width 0.5)
				(island_removal_mode 0)
			)
			(polygon
				(pts
					(arc
						(start 333.25308 -58.901076)
						(mid 333.289451 -58.958939)
						(end 333.347314 -58.99531)
					)
					(arc
						(start 333.347314 -59.100466)
						(mid 333.217593 -59.030797)
						(end 333.147924 -58.901076)
					)
				)
			)
		)
		(zone
			(layer "F.Cu")
			(hatch none 0.5)
			(connect_pads
				(clearance 0)
			)
			(min_thickness 0.25)
			(keepout
				(tracks not_allowed)
				(vias allowed)
				(pads allowed)
				(copperpour not_allowed)
				(footprints allowed)
			)
			(placement
				(enabled no)
				(sheetname "")
			)
			(fill
				(thermal_gap 0.5)
				(thermal_bridge_width 0.5)
				(island_removal_mode 0)
			)
			(polygon
				(pts
					(arc
						(start 333.25308 -58.071004)
						(mid 333.289451 -58.128867)
						(end 333.347314 -58.165238)
					)
					(arc
						(start 333.347314 -58.270394)
						(mid 333.217593 -58.200725)
						(end 333.147924 -58.071004)
					)
				)
			)
		)
		(zone
			(layer "F.Cu")
			(hatch none 0.5)
			(connect_pads
				(clearance 0)
			)
			(min_thickness 0.25)
			(keepout
				(tracks not_allowed)
				(vias allowed)
				(pads allowed)
				(copperpour not_allowed)
				(footprints allowed)
			)
			(placement
				(enabled no)
				(sheetname "")
			)
			(fill
				(thermal_gap 0.5)
				(thermal_bridge_width 0.5)
				(island_removal_mode 0)
			)
			(polygon
				(pts
					(arc
						(start 333.25308 -38.931088)
						(mid 333.289366 -38.988867)
						(end 333.34706 -39.025322)
					)
					(arc
						(start 333.34706 -39.130478)
						(mid 333.217339 -39.060809)
						(end 333.14767 -38.931088)
					)
				)
			)
		)
		(zone
			(layer "F.Cu")
			(hatch none 0.5)
			(connect_pads
				(clearance 0)
			)
			(min_thickness 0.25)
			(keepout
				(tracks not_allowed)
				(vias allowed)
				(pads allowed)
				(copperpour not_allowed)
				(footprints allowed)
			)
			(placement
				(enabled no)
				(sheetname "")
			)
			(fill
				(thermal_gap 0.5)
				(thermal_bridge_width 0.5)
				(island_removal_mode 0)
			)
			(polygon
				(pts
					(arc
						(start 333.25308 -38.101016)
						(mid 333.289451 -38.158879)
						(end 333.347314 -38.19525)
					)
					(arc
						(start 333.347314 -38.300406)
						(mid 333.217593 -38.230737)
						(end 333.147924 -38.101016)
					)
				)
			)
		)
		(zone
			(layer "F.Cu")
			(hatch none 0.5)
			(connect_pads
				(clearance 0)
			)
			(min_thickness 0.25)
			(keepout
				(tracks not_allowed)
				(vias allowed)
				(pads allowed)
				(copperpour not_allowed)
				(footprints allowed)
			)
			(placement
				(enabled no)
				(sheetname "")
			)
			(fill
				(thermal_gap 0.5)
				(thermal_bridge_width 0.5)
				(island_removal_mode 0)
			)
			(polygon
				(pts
					(arc
						(start 333.34706 -38.735254)
						(mid 333.289361 -38.77168)
						(end 333.25308 -38.829488)
					)
					(arc
						(start 333.14767 -38.829488)
						(mid 333.217339 -38.699767)
						(end 333.34706 -38.630098)
					)
				)
			)
		)
		(zone
			(layer "F.Cu")
			(hatch none 0.5)
			(connect_pads
				(clearance 0)
			)
			(min_thickness 0.25)
			(keepout
				(tracks not_allowed)
				(vias allowed)
				(pads allowed)
				(copperpour not_allowed)
				(footprints allowed)
			)
			(placement
				(enabled no)
				(sheetname "")
			)
			(fill
				(thermal_gap 0.5)
				(thermal_bridge_width 0.5)
				(island_removal_mode 0)
			)
			(polygon
				(pts
					(arc
						(start 333.347314 -58.705242)
						(mid 333.289451 -58.741613)
						(end 333.25308 -58.799476)
					)
					(arc
						(start 333.147924 -58.799476)
						(mid 333.217593 -58.669755)
						(end 333.347314 -58.600086)
					)
				)
			)
		)
		(zone
			(layer "F.Cu")
			(hatch none 0.5)
			(connect_pads
				(clearance 0)
			)
			(min_thickness 0.25)
			(keepout
				(tracks not_allowed)
				(vias allowed)
				(pads allowed)
				(copperpour not_allowed)
				(footprints allowed)
			)
			(placement
				(enabled no)
				(sheetname "")
			)
			(fill
				(thermal_gap 0.5)
				(thermal_bridge_width 0.5)
				(island_removal_mode 0)
			)
			(polygon
				(pts
					(arc
						(start 333.347314 -57.87517)
						(mid 333.289451 -57.911541)
						(end 333.25308 -57.969404)
					)
					(arc
						(start 333.147924 -57.969404)
						(mid 333.217593 -57.839683)
						(end 333.347314 -57.770014)
					)
				)
			)
		)
		(zone
			(layer "F.Cu")
			(hatch none 0.5)
			(connect_pads
				(clearance 0)
			)
			(min_thickness 0.25)
			(keepout
				(tracks not_allowed)
				(vias allowed)
				(pads allowed)
				(copperpour not_allowed)
				(footprints allowed)
			)
			(placement
				(enabled no)
				(sheetname "")
			)
			(fill
				(thermal_gap 0.5)
				(thermal_bridge_width 0.5)
				(island_removal_mode 0)
			)
			(polygon
				(pts
					(arc
						(start 333.347314 -37.905182)
						(mid 333.289451 -37.941553)
						(end 333.25308 -37.999416)
					)
					(arc
						(start 333.147924 -37.999416)
						(mid 333.217593 -37.869695)
						(end 333.347314 -37.800026)
					)
				)
			)
		)
		(zone
			(layer "F.Cu")
			(hatch none 0.5)
			(connect_pads
				(clearance 0)
			)
			(min_thickness 0.25)
			(keepout
				(tracks not_allowed)
				(vias allowed)
				(pads allowed)
				(copperpour not_allowed)
				(footprints allowed)
			)
			(placement
				(enabled no)
				(sheetname "")
			)
			(fill
				(thermal_gap 0.5)
				(thermal_bridge_width 0.5)
				(island_removal_mode 0)
			)
			(polygon
				(pts
					(arc
						(start 333.44866 -39.025322)
						(mid 333.506523 -38.988951)
						(end 333.542894 -38.931088)
					)
					(arc
						(start 333.64805 -38.931088)
						(mid 333.578381 -39.060809)
						(end 333.44866 -39.130478)
					)
				)
			)
		)
		(zone
			(layer "F.Cu")
			(hatch none 0.5)
			(connect_pads
				(clearance 0)
			)
			(min_thickness 0.25)
			(keepout
				(tracks not_allowed)
				(vias allowed)
				(pads allowed)
				(copperpour not_allowed)
				(footprints allowed)
			)
			(placement
				(enabled no)
				(sheetname "")
			)
			(fill
				(thermal_gap 0.5)
				(thermal_bridge_width 0.5)
				(island_removal_mode 0)
			)
			(polygon
				(pts
					(arc
						(start 333.448914 -58.99531)
						(mid 333.506777 -58.958939)
						(end 333.543148 -58.901076)
					)
					(arc
						(start 333.648304 -58.901076)
						(mid 333.578635 -59.030797)
						(end 333.448914 -59.100466)
					)
				)
			)
		)
		(zone
			(layer "F.Cu")
			(hatch none 0.5)
			(connect_pads
				(clearance 0)
			)
			(min_thickness 0.25)
			(keepout
				(tracks not_allowed)
				(vias allowed)
				(pads allowed)
				(copperpour not_allowed)
				(footprints allowed)
			)
			(placement
				(enabled no)
				(sheetname "")
			)
			(fill
				(thermal_gap 0.5)
				(thermal_bridge_width 0.5)
				(island_removal_mode 0)
			)
			(polygon
				(pts
					(arc
						(start 333.448914 -58.165238)
						(mid 333.506777 -58.128867)
						(end 333.543148 -58.071004)
					)
					(arc
						(start 333.648304 -58.071004)
						(mid 333.578635 -58.200725)
						(end 333.448914 -58.270394)
					)
				)
			)
		)
		(zone
			(layer "F.Cu")
			(hatch none 0.5)
			(connect_pads
				(clearance 0)
			)
			(min_thickness 0.25)
			(keepout
				(tracks not_allowed)
				(vias allowed)
				(pads allowed)
				(copperpour not_allowed)
				(footprints allowed)
			)
			(placement
				(enabled no)
				(sheetname "")
			)
			(fill
				(thermal_gap 0.5)
				(thermal_bridge_width 0.5)
				(island_removal_mode 0)
			)
			(polygon
				(pts
					(arc
						(start 333.448914 -38.19525)
						(mid 333.506777 -38.158879)
						(end 333.543148 -38.101016)
					)
					(arc
						(start 333.648304 -38.101016)
						(mid 333.578635 -38.230737)
						(end 333.448914 -38.300406)
					)
				)
			)
		)
		(zone
			(layer "F.Cu")
			(hatch none 0.5)
			(connect_pads
				(clearance 0)
			)
			(min_thickness 0.25)
			(keepout
				(tracks not_allowed)
				(vias allowed)
				(pads allowed)
				(copperpour not_allowed)
				(footprints allowed)
			)
			(placement
				(enabled no)
				(sheetname "")
			)
			(fill
				(thermal_gap 0.5)
				(thermal_bridge_width 0.5)
				(island_removal_mode 0)
			)
			(polygon
				(pts
					(arc
						(start 333.542894 -38.829488)
						(mid 333.506523 -38.771625)
						(end 333.44866 -38.735254)
					)
					(arc
						(start 333.44866 -38.630098)
						(mid 333.578381 -38.699767)
						(end 333.64805 -38.829488)
					)
				)
			)
		)
		(zone
			(layer "F.Cu")
			(hatch none 0.5)
			(connect_pads
				(clearance 0)
			)
			(min_thickness 0.25)
			(keepout
				(tracks not_allowed)
				(vias allowed)
				(pads allowed)
				(copperpour not_allowed)
				(footprints allowed)
			)
			(placement
				(enabled no)
				(sheetname "")
			)
			(fill
				(thermal_gap 0.5)
				(thermal_bridge_width 0.5)
				(island_removal_mode 0)
			)
			(polygon
				(pts
					(arc
						(start 333.543148 -58.799476)
						(mid 333.506777 -58.741613)
						(end 333.448914 -58.705242)
					)
					(arc
						(start 333.448914 -58.600086)
						(mid 333.578635 -58.669755)
						(end 333.648304 -58.799476)
					)
				)
			)
		)
		(zone
			(layer "F.Cu")
			(hatch none 0.5)
			(connect_pads
				(clearance 0)
			)
			(min_thickness 0.25)
			(keepout
				(tracks not_allowed)
				(vias allowed)
				(pads allowed)
				(copperpour not_allowed)
				(footprints allowed)
			)
			(placement
				(enabled no)
				(sheetname "")
			)
			(fill
				(thermal_gap 0.5)
				(thermal_bridge_width 0.5)
				(island_removal_mode 0)
			)
			(polygon
				(pts
					(arc
						(start 333.543148 -57.969404)
						(mid 333.506777 -57.911541)
						(end 333.448914 -57.87517)
					)
					(arc
						(start 333.448914 -57.770014)
						(mid 333.578635 -57.839683)
						(end 333.648304 -57.969404)
					)
				)
			)
		)
		(zone
			(layer "F.Cu")
			(hatch none 0.5)
			(connect_pads
				(clearance 0)
			)
			(min_thickness 0.25)
			(keepout
				(tracks not_allowed)
				(vias allowed)
				(pads allowed)
				(copperpour not_allowed)
				(footprints allowed)
			)
			(placement
				(enabled no)
				(sheetname "")
			)
			(fill
				(thermal_gap 0.5)
				(thermal_bridge_width 0.5)
				(island_removal_mode 0)
			)
			(polygon
				(pts
					(arc
						(start 333.543148 -37.999416)
						(mid 333.506777 -37.941553)
						(end 333.448914 -37.905182)
					)
					(arc
						(start 333.448914 -37.800026)
						(mid 333.578635 -37.869695)
						(end 333.648304 -37.999416)
					)
				)
			)
		)
		(zone
			(layer "F.Cu")
			(hatch none 0.5)
			(connect_pads
				(clearance 0)
			)
			(min_thickness 0.25)
			(keepout
				(tracks not_allowed)
				(vias allowed)
				(pads allowed)
				(copperpour not_allowed)
				(footprints allowed)
			)
			(placement
				(enabled no)
				(sheetname "")
			)
			(fill
				(thermal_gap 0.5)
				(thermal_bridge_width 0.5)
				(island_removal_mode 0)
			)
			(polygon
				(pts
					(arc
						(start 333.753206 -58.48604)
						(mid 333.789632 -58.543739)
						(end 333.84744 -58.58002)
					)
					(arc
						(start 333.84744 -58.68543)
						(mid 333.717719 -58.615761)
						(end 333.64805 -58.48604)
					)
				)
			)
		)
		(zone
			(layer "F.Cu")
			(hatch none 0.5)
			(connect_pads
				(clearance 0)
			)
			(min_thickness 0.25)
			(keepout
				(tracks not_allowed)
				(vias allowed)
				(pads allowed)
				(copperpour not_allowed)
				(footprints allowed)
			)
			(placement
				(enabled no)
				(sheetname "")
			)
			(fill
				(thermal_gap 0.5)
				(thermal_bridge_width 0.5)
				(island_removal_mode 0)
			)
			(polygon
				(pts
					(arc
						(start 333.753206 -57.655968)
						(mid 333.789577 -57.713831)
						(end 333.84744 -57.750202)
					)
					(arc
						(start 333.84744 -57.855358)
						(mid 333.717719 -57.785689)
						(end 333.64805 -57.655968)
					)
				)
			)
		)
		(zone
			(layer "F.Cu")
			(hatch none 0.5)
			(connect_pads
				(clearance 0)
			)
			(min_thickness 0.25)
			(keepout
				(tracks not_allowed)
				(vias allowed)
				(pads allowed)
				(copperpour not_allowed)
				(footprints allowed)
			)
			(placement
				(enabled no)
				(sheetname "")
			)
			(fill
				(thermal_gap 0.5)
				(thermal_bridge_width 0.5)
				(island_removal_mode 0)
			)
			(polygon
				(pts
					(arc
						(start 333.753206 -39.346124)
						(mid 333.789577 -39.403987)
						(end 333.84744 -39.440358)
					)
					(arc
						(start 333.84744 -39.545514)
						(mid 333.717719 -39.475845)
						(end 333.64805 -39.346124)
					)
				)
			)
		)
		(zone
			(layer "F.Cu")
			(hatch none 0.5)
			(connect_pads
				(clearance 0)
			)
			(min_thickness 0.25)
			(keepout
				(tracks not_allowed)
				(vias allowed)
				(pads allowed)
				(copperpour not_allowed)
				(footprints allowed)
			)
			(placement
				(enabled no)
				(sheetname "")
			)
			(fill
				(thermal_gap 0.5)
				(thermal_bridge_width 0.5)
				(island_removal_mode 0)
			)
			(polygon
				(pts
					(arc
						(start 333.753206 -38.516052)
						(mid 333.789577 -38.573915)
						(end 333.84744 -38.610286)
					)
					(arc
						(start 333.84744 -38.715442)
						(mid 333.717719 -38.645773)
						(end 333.64805 -38.516052)
					)
				)
			)
		)
		(zone
			(layer "F.Cu")
			(hatch none 0.5)
			(connect_pads
				(clearance 0)
			)
			(min_thickness 0.25)
			(keepout
				(tracks not_allowed)
				(vias allowed)
				(pads allowed)
				(copperpour not_allowed)
				(footprints allowed)
			)
			(placement
				(enabled no)
				(sheetname "")
			)
			(fill
				(thermal_gap 0.5)
				(thermal_bridge_width 0.5)
				(island_removal_mode 0)
			)
			(polygon
				(pts
					(arc
						(start 333.84744 -58.290206)
						(mid 333.789577 -58.326577)
						(end 333.753206 -58.38444)
					)
					(arc
						(start 333.64805 -58.38444)
						(mid 333.717719 -58.254719)
						(end 333.84744 -58.18505)
					)
				)
			)
		)
		(zone
			(layer "F.Cu")
			(hatch none 0.5)
			(connect_pads
				(clearance 0)
			)
			(min_thickness 0.25)
			(keepout
				(tracks not_allowed)
				(vias allowed)
				(pads allowed)
				(copperpour not_allowed)
				(footprints allowed)
			)
			(placement
				(enabled no)
				(sheetname "")
			)
			(fill
				(thermal_gap 0.5)
				(thermal_bridge_width 0.5)
				(island_removal_mode 0)
			)
			(polygon
				(pts
					(arc
						(start 333.84744 -57.460134)
						(mid 333.789577 -57.496505)
						(end 333.753206 -57.554368)
					)
					(arc
						(start 333.64805 -57.554368)
						(mid 333.717719 -57.424647)
						(end 333.84744 -57.354978)
					)
				)
			)
		)
		(zone
			(layer "F.Cu")
			(hatch none 0.5)
			(connect_pads
				(clearance 0)
			)
			(min_thickness 0.25)
			(keepout
				(tracks not_allowed)
				(vias allowed)
				(pads allowed)
				(copperpour not_allowed)
				(footprints allowed)
			)
			(placement
				(enabled no)
				(sheetname "")
			)
			(fill
				(thermal_gap 0.5)
				(thermal_bridge_width 0.5)
				(island_removal_mode 0)
			)
			(polygon
				(pts
					(arc
						(start 333.84744 -39.15029)
						(mid 333.789577 -39.186661)
						(end 333.753206 -39.244524)
					)
					(arc
						(start 333.64805 -39.244524)
						(mid 333.717719 -39.114803)
						(end 333.84744 -39.045134)
					)
				)
			)
		)
		(zone
			(layer "F.Cu")
			(hatch none 0.5)
			(connect_pads
				(clearance 0)
			)
			(min_thickness 0.25)
			(keepout
				(tracks not_allowed)
				(vias allowed)
				(pads allowed)
				(copperpour not_allowed)
				(footprints allowed)
			)
			(placement
				(enabled no)
				(sheetname "")
			)
			(fill
				(thermal_gap 0.5)
				(thermal_bridge_width 0.5)
				(island_removal_mode 0)
			)
			(polygon
				(pts
					(arc
						(start 333.84744 -38.320218)
						(mid 333.789577 -38.356589)
						(end 333.753206 -38.414452)
					)
					(arc
						(start 333.64805 -38.414452)
						(mid 333.717719 -38.284731)
						(end 333.84744 -38.215062)
					)
				)
			)
		)
		(zone
			(layer "F.Cu")
			(hatch none 0.5)
			(connect_pads
				(clearance 0)
			)
			(min_thickness 0.25)
			(keepout
				(tracks not_allowed)
				(vias allowed)
				(pads allowed)
				(copperpour not_allowed)
				(footprints allowed)
			)
			(placement
				(enabled no)
				(sheetname "")
			)
			(fill
				(thermal_gap 0.5)
				(thermal_bridge_width 0.5)
				(island_removal_mode 0)
			)
			(polygon
				(pts
					(arc
						(start 333.94904 -58.58002)
						(mid 334.006899 -58.543789)
						(end 334.043274 -58.48604)
					)
					(arc
						(start 334.14843 -58.48604)
						(mid 334.078761 -58.615761)
						(end 333.94904 -58.68543)
					)
				)
			)
		)
		(zone
			(layer "F.Cu")
			(hatch none 0.5)
			(connect_pads
				(clearance 0)
			)
			(min_thickness 0.25)
			(keepout
				(tracks not_allowed)
				(vias allowed)
				(pads allowed)
				(copperpour not_allowed)
				(footprints allowed)
			)
			(placement
				(enabled no)
				(sheetname "")
			)
			(fill
				(thermal_gap 0.5)
				(thermal_bridge_width 0.5)
				(island_removal_mode 0)
			)
			(polygon
				(pts
					(arc
						(start 333.94904 -57.750202)
						(mid 334.006903 -57.713831)
						(end 334.043274 -57.655968)
					)
					(arc
						(start 334.14843 -57.655968)
						(mid 334.078761 -57.785689)
						(end 333.94904 -57.855358)
					)
				)
			)
		)
		(zone
			(layer "F.Cu")
			(hatch none 0.5)
			(connect_pads
				(clearance 0)
			)
			(min_thickness 0.25)
			(keepout
				(tracks not_allowed)
				(vias allowed)
				(pads allowed)
				(copperpour not_allowed)
				(footprints allowed)
			)
			(placement
				(enabled no)
				(sheetname "")
			)
			(fill
				(thermal_gap 0.5)
				(thermal_bridge_width 0.5)
				(island_removal_mode 0)
			)
			(polygon
				(pts
					(arc
						(start 333.94904 -39.440358)
						(mid 334.006903 -39.403987)
						(end 334.043274 -39.346124)
					)
					(arc
						(start 334.14843 -39.346124)
						(mid 334.078761 -39.475845)
						(end 333.94904 -39.545514)
					)
				)
			)
		)
		(zone
			(layer "F.Cu")
			(hatch none 0.5)
			(connect_pads
				(clearance 0)
			)
			(min_thickness 0.25)
			(keepout
				(tracks not_allowed)
				(vias allowed)
				(pads allowed)
				(copperpour not_allowed)
				(footprints allowed)
			)
			(placement
				(enabled no)
				(sheetname "")
			)
			(fill
				(thermal_gap 0.5)
				(thermal_bridge_width 0.5)
				(island_removal_mode 0)
			)
			(polygon
				(pts
					(arc
						(start 333.94904 -38.610286)
						(mid 334.006903 -38.573915)
						(end 334.043274 -38.516052)
					)
					(arc
						(start 334.14843 -38.516052)
						(mid 334.078761 -38.645773)
						(end 333.94904 -38.715442)
					)
				)
			)
		)
		(zone
			(layer "F.Cu")
			(hatch none 0.5)
			(connect_pads
				(clearance 0)
			)
			(min_thickness 0.25)
			(keepout
				(tracks not_allowed)
				(vias allowed)
				(pads allowed)
				(copperpour not_allowed)
				(footprints allowed)
			)
			(placement
				(enabled no)
				(sheetname "")
			)
			(fill
				(thermal_gap 0.5)
				(thermal_bridge_width 0.5)
				(island_removal_mode 0)
			)
			(polygon
				(pts
					(arc
						(start 334.043274 -58.38444)
						(mid 334.006903 -58.326577)
						(end 333.94904 -58.290206)
					)
					(arc
						(start 333.94904 -58.18505)
						(mid 334.078761 -58.254719)
						(end 334.14843 -58.38444)
					)
				)
			)
		)
		(zone
			(layer "F.Cu")
			(hatch none 0.5)
			(connect_pads
				(clearance 0)
			)
			(min_thickness 0.25)
			(keepout
				(tracks not_allowed)
				(vias allowed)
				(pads allowed)
				(copperpour not_allowed)
				(footprints allowed)
			)
			(placement
				(enabled no)
				(sheetname "")
			)
			(fill
				(thermal_gap 0.5)
				(thermal_bridge_width 0.5)
				(island_removal_mode 0)
			)
			(polygon
				(pts
					(arc
						(start 334.043274 -57.554368)
						(mid 334.006903 -57.496505)
						(end 333.94904 -57.460134)
					)
					(arc
						(start 333.94904 -57.354978)
						(mid 334.078761 -57.424647)
						(end 334.14843 -57.554368)
					)
				)
			)
		)
		(zone
			(layer "F.Cu")
			(hatch none 0.5)
			(connect_pads
				(clearance 0)
			)
			(min_thickness 0.25)
			(keepout
				(tracks not_allowed)
				(vias allowed)
				(pads allowed)
				(copperpour not_allowed)
				(footprints allowed)
			)
			(placement
				(enabled no)
				(sheetname "")
			)
			(fill
				(thermal_gap 0.5)
				(thermal_bridge_width 0.5)
				(island_removal_mode 0)
			)
			(polygon
				(pts
					(arc
						(start 334.043274 -39.244524)
						(mid 334.006903 -39.186661)
						(end 333.94904 -39.15029)
					)
					(arc
						(start 333.94904 -39.045134)
						(mid 334.078761 -39.114803)
						(end 334.14843 -39.244524)
					)
				)
			)
		)
		(zone
			(layer "F.Cu")
			(hatch none 0.5)
			(connect_pads
				(clearance 0)
			)
			(min_thickness 0.25)
			(keepout
				(tracks not_allowed)
				(vias allowed)
				(pads allowed)
				(copperpour not_allowed)
				(footprints allowed)
			)
			(placement
				(enabled no)
				(sheetname "")
			)
			(fill
				(thermal_gap 0.5)
				(thermal_bridge_width 0.5)
				(island_removal_mode 0)
			)
			(polygon
				(pts
					(arc
						(start 334.043274 -38.414452)
						(mid 334.006903 -38.356589)
						(end 333.94904 -38.320218)
					)
					(arc
						(start 333.94904 -38.215062)
						(mid 334.078761 -38.284731)
						(end 334.14843 -38.414452)
					)
				)
			)
		)
		(zone
			(layer "F.Cu")
			(hatch none 0.5)
			(connect_pads
				(clearance 0)
			)
			(min_thickness 0.25)
			(keepout
				(tracks not_allowed)
				(vias allowed)
				(pads allowed)
				(copperpour not_allowed)
				(footprints allowed)
			)
			(placement
				(enabled no)
				(sheetname "")
			)
			(fill
				(thermal_gap 0.5)
				(thermal_bridge_width 0.5)
				(island_removal_mode 0)
			)
			(polygon
				(pts
					(arc
						(start 334.253332 -38.931088)
						(mid 334.289703 -38.988951)
						(end 334.347566 -39.025322)
					)
					(arc
						(start 334.347566 -39.130478)
						(mid 334.217845 -39.060809)
						(end 334.148176 -38.931088)
					)
				)
			)
		)
		(zone
			(layer "F.Cu")
			(hatch none 0.5)
			(connect_pads
				(clearance 0)
			)
			(min_thickness 0.25)
			(keepout
				(tracks not_allowed)
				(vias allowed)
				(pads allowed)
				(copperpour not_allowed)
				(footprints allowed)
			)
			(placement
				(enabled no)
				(sheetname "")
			)
			(fill
				(thermal_gap 0.5)
				(thermal_bridge_width 0.5)
				(island_removal_mode 0)
			)
			(polygon
				(pts
					(arc
						(start 334.253332 -38.101016)
						(mid 334.289703 -38.158879)
						(end 334.347566 -38.19525)
					)
					(arc
						(start 334.347566 -38.300406)
						(mid 334.217845 -38.230737)
						(end 334.148176 -38.101016)
					)
				)
			)
		)
		(zone
			(layer "F.Cu")
			(hatch none 0.5)
			(connect_pads
				(clearance 0)
			)
			(min_thickness 0.25)
			(keepout
				(tracks not_allowed)
				(vias allowed)
				(pads allowed)
				(copperpour not_allowed)
				(footprints allowed)
			)
			(placement
				(enabled no)
				(sheetname "")
			)
			(fill
				(thermal_gap 0.5)
				(thermal_bridge_width 0.5)
				(island_removal_mode 0)
			)
			(polygon
				(pts
					(arc
						(start 334.253586 -58.901076)
						(mid 334.289957 -58.958939)
						(end 334.34782 -58.99531)
					)
					(arc
						(start 334.34782 -59.100466)
						(mid 334.218099 -59.030797)
						(end 334.14843 -58.901076)
					)
				)
			)
		)
		(zone
			(layer "F.Cu")
			(hatch none 0.5)
			(connect_pads
				(clearance 0)
			)
			(min_thickness 0.25)
			(keepout
				(tracks not_allowed)
				(vias allowed)
				(pads allowed)
				(copperpour not_allowed)
				(footprints allowed)
			)
			(placement
				(enabled no)
				(sheetname "")
			)
			(fill
				(thermal_gap 0.5)
				(thermal_bridge_width 0.5)
				(island_removal_mode 0)
			)
			(polygon
				(pts
					(arc
						(start 334.253586 -58.071004)
						(mid 334.289957 -58.128867)
						(end 334.34782 -58.165238)
					)
					(arc
						(start 334.34782 -58.270394)
						(mid 334.218099 -58.200725)
						(end 334.14843 -58.071004)
					)
				)
			)
		)
		(zone
			(layer "F.Cu")
			(hatch none 0.5)
			(connect_pads
				(clearance 0)
			)
			(min_thickness 0.25)
			(keepout
				(tracks not_allowed)
				(vias allowed)
				(pads allowed)
				(copperpour not_allowed)
				(footprints allowed)
			)
			(placement
				(enabled no)
				(sheetname "")
			)
			(fill
				(thermal_gap 0.5)
				(thermal_bridge_width 0.5)
				(island_removal_mode 0)
			)
			(polygon
				(pts
					(arc
						(start 334.347566 -38.735254)
						(mid 334.289703 -38.771625)
						(end 334.253332 -38.829488)
					)
					(arc
						(start 334.148176 -38.829488)
						(mid 334.217845 -38.699767)
						(end 334.347566 -38.630098)
					)
				)
			)
		)
		(zone
			(layer "F.Cu")
			(hatch none 0.5)
			(connect_pads
				(clearance 0)
			)
			(min_thickness 0.25)
			(keepout
				(tracks not_allowed)
				(vias allowed)
				(pads allowed)
				(copperpour not_allowed)
				(footprints allowed)
			)
			(placement
				(enabled no)
				(sheetname "")
			)
			(fill
				(thermal_gap 0.5)
				(thermal_bridge_width 0.5)
				(island_removal_mode 0)
			)
			(polygon
				(pts
					(arc
						(start 334.347566 -37.905182)
						(mid 334.289703 -37.941553)
						(end 334.253332 -37.999416)
					)
					(arc
						(start 334.148176 -37.999416)
						(mid 334.217845 -37.869695)
						(end 334.347566 -37.800026)
					)
				)
			)
		)
		(zone
			(layer "F.Cu")
			(hatch none 0.5)
			(connect_pads
				(clearance 0)
			)
			(min_thickness 0.25)
			(keepout
				(tracks not_allowed)
				(vias allowed)
				(pads allowed)
				(copperpour not_allowed)
				(footprints allowed)
			)
			(placement
				(enabled no)
				(sheetname "")
			)
			(fill
				(thermal_gap 0.5)
				(thermal_bridge_width 0.5)
				(island_removal_mode 0)
			)
			(polygon
				(pts
					(arc
						(start 334.34782 -58.705242)
						(mid 334.289957 -58.741613)
						(end 334.253586 -58.799476)
					)
					(arc
						(start 334.14843 -58.799476)
						(mid 334.218099 -58.669755)
						(end 334.34782 -58.600086)
					)
				)
			)
		)
		(zone
			(layer "F.Cu")
			(hatch none 0.5)
			(connect_pads
				(clearance 0)
			)
			(min_thickness 0.25)
			(keepout
				(tracks not_allowed)
				(vias allowed)
				(pads allowed)
				(copperpour not_allowed)
				(footprints allowed)
			)
			(placement
				(enabled no)
				(sheetname "")
			)
			(fill
				(thermal_gap 0.5)
				(thermal_bridge_width 0.5)
				(island_removal_mode 0)
			)
			(polygon
				(pts
					(arc
						(start 334.34782 -57.87517)
						(mid 334.289957 -57.911541)
						(end 334.253586 -57.969404)
					)
					(arc
						(start 334.14843 -57.969404)
						(mid 334.218099 -57.839683)
						(end 334.34782 -57.770014)
					)
				)
			)
		)
		(zone
			(layer "F.Cu")
			(hatch none 0.5)
			(connect_pads
				(clearance 0)
			)
			(min_thickness 0.25)
			(keepout
				(tracks not_allowed)
				(vias allowed)
				(pads allowed)
				(copperpour not_allowed)
				(footprints allowed)
			)
			(placement
				(enabled no)
				(sheetname "")
			)
			(fill
				(thermal_gap 0.5)
				(thermal_bridge_width 0.5)
				(island_removal_mode 0)
			)
			(polygon
				(pts
					(arc
						(start 334.449166 -39.025322)
						(mid 334.507029 -38.988951)
						(end 334.5434 -38.931088)
					)
					(arc
						(start 334.648556 -38.931088)
						(mid 334.578887 -39.060809)
						(end 334.449166 -39.130478)
					)
				)
			)
		)
		(zone
			(layer "F.Cu")
			(hatch none 0.5)
			(connect_pads
				(clearance 0)
			)
			(min_thickness 0.25)
			(keepout
				(tracks not_allowed)
				(vias allowed)
				(pads allowed)
				(copperpour not_allowed)
				(footprints allowed)
			)
			(placement
				(enabled no)
				(sheetname "")
			)
			(fill
				(thermal_gap 0.5)
				(thermal_bridge_width 0.5)
				(island_removal_mode 0)
			)
			(polygon
				(pts
					(arc
						(start 334.449166 -38.19525)
						(mid 334.507029 -38.158879)
						(end 334.5434 -38.101016)
					)
					(arc
						(start 334.648556 -38.101016)
						(mid 334.578887 -38.230737)
						(end 334.449166 -38.300406)
					)
				)
			)
		)
		(zone
			(layer "F.Cu")
			(hatch none 0.5)
			(connect_pads
				(clearance 0)
			)
			(min_thickness 0.25)
			(keepout
				(tracks not_allowed)
				(vias allowed)
				(pads allowed)
				(copperpour not_allowed)
				(footprints allowed)
			)
			(placement
				(enabled no)
				(sheetname "")
			)
			(fill
				(thermal_gap 0.5)
				(thermal_bridge_width 0.5)
				(island_removal_mode 0)
			)
			(polygon
				(pts
					(arc
						(start 334.44942 -58.99531)
						(mid 334.507283 -58.958939)
						(end 334.543654 -58.901076)
					)
					(arc
						(start 334.64881 -58.901076)
						(mid 334.579141 -59.030797)
						(end 334.44942 -59.100466)
					)
				)
			)
		)
		(zone
			(layer "F.Cu")
			(hatch none 0.5)
			(connect_pads
				(clearance 0)
			)
			(min_thickness 0.25)
			(keepout
				(tracks not_allowed)
				(vias allowed)
				(pads allowed)
				(copperpour not_allowed)
				(footprints allowed)
			)
			(placement
				(enabled no)
				(sheetname "")
			)
			(fill
				(thermal_gap 0.5)
				(thermal_bridge_width 0.5)
				(island_removal_mode 0)
			)
			(polygon
				(pts
					(arc
						(start 334.44942 -58.165238)
						(mid 334.507283 -58.128867)
						(end 334.543654 -58.071004)
					)
					(arc
						(start 334.64881 -58.071004)
						(mid 334.579141 -58.200725)
						(end 334.44942 -58.270394)
					)
				)
			)
		)
		(zone
			(layer "F.Cu")
			(hatch none 0.5)
			(connect_pads
				(clearance 0)
			)
			(min_thickness 0.25)
			(keepout
				(tracks not_allowed)
				(vias allowed)
				(pads allowed)
				(copperpour not_allowed)
				(footprints allowed)
			)
			(placement
				(enabled no)
				(sheetname "")
			)
			(fill
				(thermal_gap 0.5)
				(thermal_bridge_width 0.5)
				(island_removal_mode 0)
			)
			(polygon
				(pts
					(arc
						(start 334.5434 -38.829488)
						(mid 334.507029 -38.771625)
						(end 334.449166 -38.735254)
					)
					(arc
						(start 334.449166 -38.630098)
						(mid 334.578887 -38.699767)
						(end 334.648556 -38.829488)
					)
				)
			)
		)
		(zone
			(layer "F.Cu")
			(hatch none 0.5)
			(connect_pads
				(clearance 0)
			)
			(min_thickness 0.25)
			(keepout
				(tracks not_allowed)
				(vias allowed)
				(pads allowed)
				(copperpour not_allowed)
				(footprints allowed)
			)
			(placement
				(enabled no)
				(sheetname "")
			)
			(fill
				(thermal_gap 0.5)
				(thermal_bridge_width 0.5)
				(island_removal_mode 0)
			)
			(polygon
				(pts
					(arc
						(start 334.5434 -37.999416)
						(mid 334.507029 -37.941553)
						(end 334.449166 -37.905182)
					)
					(arc
						(start 334.449166 -37.800026)
						(mid 334.578887 -37.869695)
						(end 334.648556 -37.999416)
					)
				)
			)
		)
		(zone
			(layer "F.Cu")
			(hatch none 0.5)
			(connect_pads
				(clearance 0)
			)
			(min_thickness 0.25)
			(keepout
				(tracks not_allowed)
				(vias allowed)
				(pads allowed)
				(copperpour not_allowed)
				(footprints allowed)
			)
			(placement
				(enabled no)
				(sheetname "")
			)
			(fill
				(thermal_gap 0.5)
				(thermal_bridge_width 0.5)
				(island_removal_mode 0)
			)
			(polygon
				(pts
					(arc
						(start 334.543654 -58.799476)
						(mid 334.507283 -58.741613)
						(end 334.44942 -58.705242)
					)
					(arc
						(start 334.44942 -58.600086)
						(mid 334.579141 -58.669755)
						(end 334.64881 -58.799476)
					)
				)
			)
		)
		(zone
			(layer "F.Cu")
			(hatch none 0.5)
			(connect_pads
				(clearance 0)
			)
			(min_thickness 0.25)
			(keepout
				(tracks not_allowed)
				(vias allowed)
				(pads allowed)
				(copperpour not_allowed)
				(footprints allowed)
			)
			(placement
				(enabled no)
				(sheetname "")
			)
			(fill
				(thermal_gap 0.5)
				(thermal_bridge_width 0.5)
				(island_removal_mode 0)
			)
			(polygon
				(pts
					(arc
						(start 334.543654 -57.969404)
						(mid 334.507283 -57.911541)
						(end 334.44942 -57.87517)
					)
					(arc
						(start 334.44942 -57.770014)
						(mid 334.579141 -57.839683)
						(end 334.64881 -57.969404)
					)
				)
			)
		)
		(zone
			(layer "F.Cu")
			(hatch none 0.5)
			(connect_pads
				(clearance 0)
			)
			(min_thickness 0.25)
			(keepout
				(tracks not_allowed)
				(vias allowed)
				(pads allowed)
				(copperpour not_allowed)
				(footprints allowed)
			)
			(placement
				(enabled no)
				(sheetname "")
			)
			(fill
				(thermal_gap 0.5)
				(thermal_bridge_width 0.5)
				(island_removal_mode 0)
			)
			(polygon
				(pts
					(arc
						(start 334.753712 -58.48604)
						(mid 334.790138 -58.543739)
						(end 334.847946 -58.58002)
					)
					(arc
						(start 334.847946 -58.68543)
						(mid 334.718225 -58.615761)
						(end 334.648556 -58.48604)
					)
				)
			)
		)
		(zone
			(layer "F.Cu")
			(hatch none 0.5)
			(connect_pads
				(clearance 0)
			)
			(min_thickness 0.25)
			(keepout
				(tracks not_allowed)
				(vias allowed)
				(pads allowed)
				(copperpour not_allowed)
				(footprints allowed)
			)
			(placement
				(enabled no)
				(sheetname "")
			)
			(fill
				(thermal_gap 0.5)
				(thermal_bridge_width 0.5)
				(island_removal_mode 0)
			)
			(polygon
				(pts
					(arc
						(start 334.753712 -57.655968)
						(mid 334.790083 -57.713831)
						(end 334.847946 -57.750202)
					)
					(arc
						(start 334.847946 -57.855358)
						(mid 334.718225 -57.785689)
						(end 334.648556 -57.655968)
					)
				)
			)
		)
		(zone
			(layer "F.Cu")
			(hatch none 0.5)
			(connect_pads
				(clearance 0)
			)
			(min_thickness 0.25)
			(keepout
				(tracks not_allowed)
				(vias allowed)
				(pads allowed)
				(copperpour not_allowed)
				(footprints allowed)
			)
			(placement
				(enabled no)
				(sheetname "")
			)
			(fill
				(thermal_gap 0.5)
				(thermal_bridge_width 0.5)
				(island_removal_mode 0)
			)
			(polygon
				(pts
					(arc
						(start 334.753712 -39.346124)
						(mid 334.790083 -39.403987)
						(end 334.847946 -39.440358)
					)
					(arc
						(start 334.847946 -39.545514)
						(mid 334.718225 -39.475845)
						(end 334.648556 -39.346124)
					)
				)
			)
		)
		(zone
			(layer "F.Cu")
			(hatch none 0.5)
			(connect_pads
				(clearance 0)
			)
			(min_thickness 0.25)
			(keepout
				(tracks not_allowed)
				(vias allowed)
				(pads allowed)
				(copperpour not_allowed)
				(footprints allowed)
			)
			(placement
				(enabled no)
				(sheetname "")
			)
			(fill
				(thermal_gap 0.5)
				(thermal_bridge_width 0.5)
				(island_removal_mode 0)
			)
			(polygon
				(pts
					(arc
						(start 334.753712 -38.516052)
						(mid 334.790083 -38.573915)
						(end 334.847946 -38.610286)
					)
					(arc
						(start 334.847946 -38.715442)
						(mid 334.718225 -38.645773)
						(end 334.648556 -38.516052)
					)
				)
			)
		)
		(zone
			(layer "F.Cu")
			(hatch none 0.5)
			(connect_pads
				(clearance 0)
			)
			(min_thickness 0.25)
			(keepout
				(tracks not_allowed)
				(vias allowed)
				(pads allowed)
				(copperpour not_allowed)
				(footprints allowed)
			)
			(placement
				(enabled no)
				(sheetname "")
			)
			(fill
				(thermal_gap 0.5)
				(thermal_bridge_width 0.5)
				(island_removal_mode 0)
			)
			(polygon
				(pts
					(arc
						(start 334.847946 -58.290206)
						(mid 334.790083 -58.326577)
						(end 334.753712 -58.38444)
					)
					(arc
						(start 334.648556 -58.38444)
						(mid 334.718225 -58.254719)
						(end 334.847946 -58.18505)
					)
				)
			)
		)
		(zone
			(layer "F.Cu")
			(hatch none 0.5)
			(connect_pads
				(clearance 0)
			)
			(min_thickness 0.25)
			(keepout
				(tracks not_allowed)
				(vias allowed)
				(pads allowed)
				(copperpour not_allowed)
				(footprints allowed)
			)
			(placement
				(enabled no)
				(sheetname "")
			)
			(fill
				(thermal_gap 0.5)
				(thermal_bridge_width 0.5)
				(island_removal_mode 0)
			)
			(polygon
				(pts
					(arc
						(start 334.847946 -57.460134)
						(mid 334.790083 -57.496505)
						(end 334.753712 -57.554368)
					)
					(arc
						(start 334.648556 -57.554368)
						(mid 334.718225 -57.424647)
						(end 334.847946 -57.354978)
					)
				)
			)
		)
		(zone
			(layer "F.Cu")
			(hatch none 0.5)
			(connect_pads
				(clearance 0)
			)
			(min_thickness 0.25)
			(keepout
				(tracks not_allowed)
				(vias allowed)
				(pads allowed)
				(copperpour not_allowed)
				(footprints allowed)
			)
			(placement
				(enabled no)
				(sheetname "")
			)
			(fill
				(thermal_gap 0.5)
				(thermal_bridge_width 0.5)
				(island_removal_mode 0)
			)
			(polygon
				(pts
					(arc
						(start 334.847946 -39.15029)
						(mid 334.790083 -39.186661)
						(end 334.753712 -39.244524)
					)
					(arc
						(start 334.648556 -39.244524)
						(mid 334.718225 -39.114803)
						(end 334.847946 -39.045134)
					)
				)
			)
		)
		(zone
			(layer "F.Cu")
			(hatch none 0.5)
			(connect_pads
				(clearance 0)
			)
			(min_thickness 0.25)
			(keepout
				(tracks not_allowed)
				(vias allowed)
				(pads allowed)
				(copperpour not_allowed)
				(footprints allowed)
			)
			(placement
				(enabled no)
				(sheetname "")
			)
			(fill
				(thermal_gap 0.5)
				(thermal_bridge_width 0.5)
				(island_removal_mode 0)
			)
			(polygon
				(pts
					(arc
						(start 334.847946 -38.320218)
						(mid 334.790083 -38.356589)
						(end 334.753712 -38.414452)
					)
					(arc
						(start 334.648556 -38.414452)
						(mid 334.718225 -38.284731)
						(end 334.847946 -38.215062)
					)
				)
			)
		)
		(zone
			(layer "F.Cu")
			(hatch none 0.5)
			(connect_pads
				(clearance 0)
			)
			(min_thickness 0.25)
			(keepout
				(tracks not_allowed)
				(vias allowed)
				(pads allowed)
				(copperpour not_allowed)
				(footprints allowed)
			)
			(placement
				(enabled no)
				(sheetname "")
			)
			(fill
				(thermal_gap 0.5)
				(thermal_bridge_width 0.5)
				(island_removal_mode 0)
			)
			(polygon
				(pts
					(arc
						(start 334.949546 -58.58002)
						(mid 335.007405 -58.543789)
						(end 335.04378 -58.48604)
					)
					(arc
						(start 335.148936 -58.48604)
						(mid 335.079267 -58.615761)
						(end 334.949546 -58.68543)
					)
				)
			)
		)
		(zone
			(layer "F.Cu")
			(hatch none 0.5)
			(connect_pads
				(clearance 0)
			)
			(min_thickness 0.25)
			(keepout
				(tracks not_allowed)
				(vias allowed)
				(pads allowed)
				(copperpour not_allowed)
				(footprints allowed)
			)
			(placement
				(enabled no)
				(sheetname "")
			)
			(fill
				(thermal_gap 0.5)
				(thermal_bridge_width 0.5)
				(island_removal_mode 0)
			)
			(polygon
				(pts
					(arc
						(start 334.949546 -57.750202)
						(mid 335.007409 -57.713831)
						(end 335.04378 -57.655968)
					)
					(arc
						(start 335.148936 -57.655968)
						(mid 335.079267 -57.785689)
						(end 334.949546 -57.855358)
					)
				)
			)
		)
		(zone
			(layer "F.Cu")
			(hatch none 0.5)
			(connect_pads
				(clearance 0)
			)
			(min_thickness 0.25)
			(keepout
				(tracks not_allowed)
				(vias allowed)
				(pads allowed)
				(copperpour not_allowed)
				(footprints allowed)
			)
			(placement
				(enabled no)
				(sheetname "")
			)
			(fill
				(thermal_gap 0.5)
				(thermal_bridge_width 0.5)
				(island_removal_mode 0)
			)
			(polygon
				(pts
					(arc
						(start 334.949546 -39.440358)
						(mid 335.007409 -39.403987)
						(end 335.04378 -39.346124)
					)
					(arc
						(start 335.148936 -39.346124)
						(mid 335.079267 -39.475845)
						(end 334.949546 -39.545514)
					)
				)
			)
		)
		(zone
			(layer "F.Cu")
			(hatch none 0.5)
			(connect_pads
				(clearance 0)
			)
			(min_thickness 0.25)
			(keepout
				(tracks not_allowed)
				(vias allowed)
				(pads allowed)
				(copperpour not_allowed)
				(footprints allowed)
			)
			(placement
				(enabled no)
				(sheetname "")
			)
			(fill
				(thermal_gap 0.5)
				(thermal_bridge_width 0.5)
				(island_removal_mode 0)
			)
			(polygon
				(pts
					(arc
						(start 334.949546 -38.610286)
						(mid 335.007409 -38.573915)
						(end 335.04378 -38.516052)
					)
					(arc
						(start 335.148936 -38.516052)
						(mid 335.079267 -38.645773)
						(end 334.949546 -38.715442)
					)
				)
			)
		)
		(zone
			(layer "F.Cu")
			(hatch none 0.5)
			(connect_pads
				(clearance 0)
			)
			(min_thickness 0.25)
			(keepout
				(tracks not_allowed)
				(vias allowed)
				(pads allowed)
				(copperpour not_allowed)
				(footprints allowed)
			)
			(placement
				(enabled no)
				(sheetname "")
			)
			(fill
				(thermal_gap 0.5)
				(thermal_bridge_width 0.5)
				(island_removal_mode 0)
			)
			(polygon
				(pts
					(arc
						(start 335.04378 -58.38444)
						(mid 335.007409 -58.326577)
						(end 334.949546 -58.290206)
					)
					(arc
						(start 334.949546 -58.18505)
						(mid 335.079267 -58.254719)
						(end 335.148936 -58.38444)
					)
				)
			)
		)
		(zone
			(layer "F.Cu")
			(hatch none 0.5)
			(connect_pads
				(clearance 0)
			)
			(min_thickness 0.25)
			(keepout
				(tracks not_allowed)
				(vias allowed)
				(pads allowed)
				(copperpour not_allowed)
				(footprints allowed)
			)
			(placement
				(enabled no)
				(sheetname "")
			)
			(fill
				(thermal_gap 0.5)
				(thermal_bridge_width 0.5)
				(island_removal_mode 0)
			)
			(polygon
				(pts
					(arc
						(start 335.04378 -57.554368)
						(mid 335.007409 -57.496505)
						(end 334.949546 -57.460134)
					)
					(arc
						(start 334.949546 -57.354978)
						(mid 335.079267 -57.424647)
						(end 335.148936 -57.554368)
					)
				)
			)
		)
		(zone
			(layer "F.Cu")
			(hatch none 0.5)
			(connect_pads
				(clearance 0)
			)
			(min_thickness 0.25)
			(keepout
				(tracks not_allowed)
				(vias allowed)
				(pads allowed)
				(copperpour not_allowed)
				(footprints allowed)
			)
			(placement
				(enabled no)
				(sheetname "")
			)
			(fill
				(thermal_gap 0.5)
				(thermal_bridge_width 0.5)
				(island_removal_mode 0)
			)
			(polygon
				(pts
					(arc
						(start 335.04378 -39.244524)
						(mid 335.007409 -39.186661)
						(end 334.949546 -39.15029)
					)
					(arc
						(start 334.949546 -39.045134)
						(mid 335.079267 -39.114803)
						(end 335.148936 -39.244524)
					)
				)
			)
		)
		(zone
			(layer "F.Cu")
			(hatch none 0.5)
			(connect_pads
				(clearance 0)
			)
			(min_thickness 0.25)
			(keepout
				(tracks not_allowed)
				(vias allowed)
				(pads allowed)
				(copperpour not_allowed)
				(footprints allowed)
			)
			(placement
				(enabled no)
				(sheetname "")
			)
			(fill
				(thermal_gap 0.5)
				(thermal_bridge_width 0.5)
				(island_removal_mode 0)
			)
			(polygon
				(pts
					(arc
						(start 335.04378 -38.414452)
						(mid 335.007409 -38.356589)
						(end 334.949546 -38.320218)
					)
					(arc
						(start 334.949546 -38.215062)
						(mid 335.079267 -38.284731)
						(end 335.148936 -38.414452)
					)
				)
			)
		)
		(zone
			(layer "F.Cu")
			(hatch none 0.5)
			(connect_pads
				(clearance 0)
			)
			(min_thickness 0.25)
			(keepout
				(tracks not_allowed)
				(vias allowed)
				(pads allowed)
				(copperpour not_allowed)
				(footprints allowed)
			)
			(placement
				(enabled no)
				(sheetname "")
			)
			(fill
				(thermal_gap 0.5)
				(thermal_bridge_width 0.5)
				(island_removal_mode 0)
			)
			(polygon
				(pts
					(arc
						(start 335.253838 -38.931088)
						(mid 335.290209 -38.988951)
						(end 335.348072 -39.025322)
					)
					(arc
						(start 335.348072 -39.130478)
						(mid 335.218351 -39.060809)
						(end 335.148682 -38.931088)
					)
				)
			)
		)
		(zone
			(layer "F.Cu")
			(hatch none 0.5)
			(connect_pads
				(clearance 0)
			)
			(min_thickness 0.25)
			(keepout
				(tracks not_allowed)
				(vias allowed)
				(pads allowed)
				(copperpour not_allowed)
				(footprints allowed)
			)
			(placement
				(enabled no)
				(sheetname "")
			)
			(fill
				(thermal_gap 0.5)
				(thermal_bridge_width 0.5)
				(island_removal_mode 0)
			)
			(polygon
				(pts
					(arc
						(start 335.253838 -38.101016)
						(mid 335.290209 -38.158879)
						(end 335.348072 -38.19525)
					)
					(arc
						(start 335.348072 -38.300406)
						(mid 335.218351 -38.230737)
						(end 335.148682 -38.101016)
					)
				)
			)
		)
		(zone
			(layer "F.Cu")
			(hatch none 0.5)
			(connect_pads
				(clearance 0)
			)
			(min_thickness 0.25)
			(keepout
				(tracks not_allowed)
				(vias allowed)
				(pads allowed)
				(copperpour not_allowed)
				(footprints allowed)
			)
			(placement
				(enabled no)
				(sheetname "")
			)
			(fill
				(thermal_gap 0.5)
				(thermal_bridge_width 0.5)
				(island_removal_mode 0)
			)
			(polygon
				(pts
					(arc
						(start 335.254092 -58.901076)
						(mid 335.290463 -58.958939)
						(end 335.348326 -58.99531)
					)
					(arc
						(start 335.348326 -59.100466)
						(mid 335.218605 -59.030797)
						(end 335.148936 -58.901076)
					)
				)
			)
		)
		(zone
			(layer "F.Cu")
			(hatch none 0.5)
			(connect_pads
				(clearance 0)
			)
			(min_thickness 0.25)
			(keepout
				(tracks not_allowed)
				(vias allowed)
				(pads allowed)
				(copperpour not_allowed)
				(footprints allowed)
			)
			(placement
				(enabled no)
				(sheetname "")
			)
			(fill
				(thermal_gap 0.5)
				(thermal_bridge_width 0.5)
				(island_removal_mode 0)
			)
			(polygon
				(pts
					(arc
						(start 335.254092 -58.071004)
						(mid 335.290463 -58.128867)
						(end 335.348326 -58.165238)
					)
					(arc
						(start 335.348326 -58.270394)
						(mid 335.218605 -58.200725)
						(end 335.148936 -58.071004)
					)
				)
			)
		)
		(zone
			(layer "F.Cu")
			(hatch none 0.5)
			(connect_pads
				(clearance 0)
			)
			(min_thickness 0.25)
			(keepout
				(tracks not_allowed)
				(vias allowed)
				(pads allowed)
				(copperpour not_allowed)
				(footprints allowed)
			)
			(placement
				(enabled no)
				(sheetname "")
			)
			(fill
				(thermal_gap 0.5)
				(thermal_bridge_width 0.5)
				(island_removal_mode 0)
			)
			(polygon
				(pts
					(arc
						(start 335.348072 -38.735254)
						(mid 335.290209 -38.771625)
						(end 335.253838 -38.829488)
					)
					(arc
						(start 335.148682 -38.829488)
						(mid 335.218351 -38.699767)
						(end 335.348072 -38.630098)
					)
				)
			)
		)
		(zone
			(layer "F.Cu")
			(hatch none 0.5)
			(connect_pads
				(clearance 0)
			)
			(min_thickness 0.25)
			(keepout
				(tracks not_allowed)
				(vias allowed)
				(pads allowed)
				(copperpour not_allowed)
				(footprints allowed)
			)
			(placement
				(enabled no)
				(sheetname "")
			)
			(fill
				(thermal_gap 0.5)
				(thermal_bridge_width 0.5)
				(island_removal_mode 0)
			)
			(polygon
				(pts
					(arc
						(start 335.348072 -37.905182)
						(mid 335.290209 -37.941553)
						(end 335.253838 -37.999416)
					)
					(arc
						(start 335.148682 -37.999416)
						(mid 335.218351 -37.869695)
						(end 335.348072 -37.800026)
					)
				)
			)
		)
		(zone
			(layer "F.Cu")
			(hatch none 0.5)
			(connect_pads
				(clearance 0)
			)
			(min_thickness 0.25)
			(keepout
				(tracks not_allowed)
				(vias allowed)
				(pads allowed)
				(copperpour not_allowed)
				(footprints allowed)
			)
			(placement
				(enabled no)
				(sheetname "")
			)
			(fill
				(thermal_gap 0.5)
				(thermal_bridge_width 0.5)
				(island_removal_mode 0)
			)
			(polygon
				(pts
					(arc
						(start 335.348326 -58.705242)
						(mid 335.290463 -58.741613)
						(end 335.254092 -58.799476)
					)
					(arc
						(start 335.148936 -58.799476)
						(mid 335.218605 -58.669755)
						(end 335.348326 -58.600086)
					)
				)
			)
		)
		(zone
			(layer "F.Cu")
			(hatch none 0.5)
			(connect_pads
				(clearance 0)
			)
			(min_thickness 0.25)
			(keepout
				(tracks not_allowed)
				(vias allowed)
				(pads allowed)
				(copperpour not_allowed)
				(footprints allowed)
			)
			(placement
				(enabled no)
				(sheetname "")
			)
			(fill
				(thermal_gap 0.5)
				(thermal_bridge_width 0.5)
				(island_removal_mode 0)
			)
			(polygon
				(pts
					(arc
						(start 335.348326 -57.87517)
						(mid 335.290463 -57.911541)
						(end 335.254092 -57.969404)
					)
					(arc
						(start 335.148936 -57.969404)
						(mid 335.218605 -57.839683)
						(end 335.348326 -57.770014)
					)
				)
			)
		)
		(zone
			(layer "F.Cu")
			(hatch none 0.5)
			(connect_pads
				(clearance 0)
			)
			(min_thickness 0.25)
			(keepout
				(tracks not_allowed)
				(vias allowed)
				(pads allowed)
				(copperpour not_allowed)
				(footprints allowed)
			)
			(placement
				(enabled no)
				(sheetname "")
			)
			(fill
				(thermal_gap 0.5)
				(thermal_bridge_width 0.5)
				(island_removal_mode 0)
			)
			(polygon
				(pts
					(arc
						(start 335.449672 -39.025322)
						(mid 335.507535 -38.988951)
						(end 335.543906 -38.931088)
					)
					(arc
						(start 335.649062 -38.931088)
						(mid 335.579393 -39.060809)
						(end 335.449672 -39.130478)
					)
				)
			)
		)
		(zone
			(layer "F.Cu")
			(hatch none 0.5)
			(connect_pads
				(clearance 0)
			)
			(min_thickness 0.25)
			(keepout
				(tracks not_allowed)
				(vias allowed)
				(pads allowed)
				(copperpour not_allowed)
				(footprints allowed)
			)
			(placement
				(enabled no)
				(sheetname "")
			)
			(fill
				(thermal_gap 0.5)
				(thermal_bridge_width 0.5)
				(island_removal_mode 0)
			)
			(polygon
				(pts
					(arc
						(start 335.449672 -38.19525)
						(mid 335.507535 -38.158879)
						(end 335.543906 -38.101016)
					)
					(arc
						(start 335.649062 -38.101016)
						(mid 335.579393 -38.230737)
						(end 335.449672 -38.300406)
					)
				)
			)
		)
		(zone
			(layer "F.Cu")
			(hatch none 0.5)
			(connect_pads
				(clearance 0)
			)
			(min_thickness 0.25)
			(keepout
				(tracks not_allowed)
				(vias allowed)
				(pads allowed)
				(copperpour not_allowed)
				(footprints allowed)
			)
			(placement
				(enabled no)
				(sheetname "")
			)
			(fill
				(thermal_gap 0.5)
				(thermal_bridge_width 0.5)
				(island_removal_mode 0)
			)
			(polygon
				(pts
					(arc
						(start 335.449926 -58.99531)
						(mid 335.507789 -58.958939)
						(end 335.54416 -58.901076)
					)
					(arc
						(start 335.649316 -58.901076)
						(mid 335.579647 -59.030797)
						(end 335.449926 -59.100466)
					)
				)
			)
		)
		(zone
			(layer "F.Cu")
			(hatch none 0.5)
			(connect_pads
				(clearance 0)
			)
			(min_thickness 0.25)
			(keepout
				(tracks not_allowed)
				(vias allowed)
				(pads allowed)
				(copperpour not_allowed)
				(footprints allowed)
			)
			(placement
				(enabled no)
				(sheetname "")
			)
			(fill
				(thermal_gap 0.5)
				(thermal_bridge_width 0.5)
				(island_removal_mode 0)
			)
			(polygon
				(pts
					(arc
						(start 335.449926 -58.165238)
						(mid 335.507789 -58.128867)
						(end 335.54416 -58.071004)
					)
					(arc
						(start 335.649316 -58.071004)
						(mid 335.579647 -58.200725)
						(end 335.449926 -58.270394)
					)
				)
			)
		)
		(zone
			(layer "F.Cu")
			(hatch none 0.5)
			(connect_pads
				(clearance 0)
			)
			(min_thickness 0.25)
			(keepout
				(tracks not_allowed)
				(vias allowed)
				(pads allowed)
				(copperpour not_allowed)
				(footprints allowed)
			)
			(placement
				(enabled no)
				(sheetname "")
			)
			(fill
				(thermal_gap 0.5)
				(thermal_bridge_width 0.5)
				(island_removal_mode 0)
			)
			(polygon
				(pts
					(arc
						(start 335.543906 -38.829488)
						(mid 335.507535 -38.771625)
						(end 335.449672 -38.735254)
					)
					(arc
						(start 335.449672 -38.630098)
						(mid 335.579393 -38.699767)
						(end 335.649062 -38.829488)
					)
				)
			)
		)
		(zone
			(layer "F.Cu")
			(hatch none 0.5)
			(connect_pads
				(clearance 0)
			)
			(min_thickness 0.25)
			(keepout
				(tracks not_allowed)
				(vias allowed)
				(pads allowed)
				(copperpour not_allowed)
				(footprints allowed)
			)
			(placement
				(enabled no)
				(sheetname "")
			)
			(fill
				(thermal_gap 0.5)
				(thermal_bridge_width 0.5)
				(island_removal_mode 0)
			)
			(polygon
				(pts
					(arc
						(start 335.543906 -37.999416)
						(mid 335.507535 -37.941553)
						(end 335.449672 -37.905182)
					)
					(arc
						(start 335.449672 -37.800026)
						(mid 335.579393 -37.869695)
						(end 335.649062 -37.999416)
					)
				)
			)
		)
		(zone
			(layer "F.Cu")
			(hatch none 0.5)
			(connect_pads
				(clearance 0)
			)
			(min_thickness 0.25)
			(keepout
				(tracks not_allowed)
				(vias allowed)
				(pads allowed)
				(copperpour not_allowed)
				(footprints allowed)
			)
			(placement
				(enabled no)
				(sheetname "")
			)
			(fill
				(thermal_gap 0.5)
				(thermal_bridge_width 0.5)
				(island_removal_mode 0)
			)
			(polygon
				(pts
					(arc
						(start 335.54416 -58.799476)
						(mid 335.507789 -58.741613)
						(end 335.449926 -58.705242)
					)
					(arc
						(start 335.449926 -58.600086)
						(mid 335.579647 -58.669755)
						(end 335.649316 -58.799476)
					)
				)
			)
		)
		(zone
			(layer "F.Cu")
			(hatch none 0.5)
			(connect_pads
				(clearance 0)
			)
			(min_thickness 0.25)
			(keepout
				(tracks not_allowed)
				(vias allowed)
				(pads allowed)
				(copperpour not_allowed)
				(footprints allowed)
			)
			(placement
				(enabled no)
				(sheetname "")
			)
			(fill
				(thermal_gap 0.5)
				(thermal_bridge_width 0.5)
				(island_removal_mode 0)
			)
			(polygon
				(pts
					(arc
						(start 335.54416 -57.969404)
						(mid 335.507789 -57.911541)
						(end 335.449926 -57.87517)
					)
					(arc
						(start 335.449926 -57.770014)
						(mid 335.579647 -57.839683)
						(end 335.649316 -57.969404)
					)
				)
			)
		)
		(zone
			(layer "F.Cu")
			(hatch none 0.5)
			(connect_pads
				(clearance 0)
			)
			(min_thickness 0.25)
			(keepout
				(tracks not_allowed)
				(vias allowed)
				(pads allowed)
				(copperpour not_allowed)
				(footprints allowed)
			)
			(placement
				(enabled no)
				(sheetname "")
			)
			(fill
				(thermal_gap 0.5)
				(thermal_bridge_width 0.5)
				(island_removal_mode 0)
			)
			(polygon
				(pts
					(arc
						(start 335.754218 -58.48604)
						(mid 335.790644 -58.543739)
						(end 335.848452 -58.58002)
					)
					(arc
						(start 335.848452 -58.68543)
						(mid 335.718731 -58.615761)
						(end 335.649062 -58.48604)
					)
				)
			)
		)
		(zone
			(layer "F.Cu")
			(hatch none 0.5)
			(connect_pads
				(clearance 0)
			)
			(min_thickness 0.25)
			(keepout
				(tracks not_allowed)
				(vias allowed)
				(pads allowed)
				(copperpour not_allowed)
				(footprints allowed)
			)
			(placement
				(enabled no)
				(sheetname "")
			)
			(fill
				(thermal_gap 0.5)
				(thermal_bridge_width 0.5)
				(island_removal_mode 0)
			)
			(polygon
				(pts
					(arc
						(start 335.754218 -57.655968)
						(mid 335.790589 -57.713831)
						(end 335.848452 -57.750202)
					)
					(arc
						(start 335.848452 -57.855358)
						(mid 335.718731 -57.785689)
						(end 335.649062 -57.655968)
					)
				)
			)
		)
		(zone
			(layer "F.Cu")
			(hatch none 0.5)
			(connect_pads
				(clearance 0)
			)
			(min_thickness 0.25)
			(keepout
				(tracks not_allowed)
				(vias allowed)
				(pads allowed)
				(copperpour not_allowed)
				(footprints allowed)
			)
			(placement
				(enabled no)
				(sheetname "")
			)
			(fill
				(thermal_gap 0.5)
				(thermal_bridge_width 0.5)
				(island_removal_mode 0)
			)
			(polygon
				(pts
					(arc
						(start 335.754218 -39.346124)
						(mid 335.790589 -39.403987)
						(end 335.848452 -39.440358)
					)
					(arc
						(start 335.848452 -39.545514)
						(mid 335.718731 -39.475845)
						(end 335.649062 -39.346124)
					)
				)
			)
		)
		(zone
			(layer "F.Cu")
			(hatch none 0.5)
			(connect_pads
				(clearance 0)
			)
			(min_thickness 0.25)
			(keepout
				(tracks not_allowed)
				(vias allowed)
				(pads allowed)
				(copperpour not_allowed)
				(footprints allowed)
			)
			(placement
				(enabled no)
				(sheetname "")
			)
			(fill
				(thermal_gap 0.5)
				(thermal_bridge_width 0.5)
				(island_removal_mode 0)
			)
			(polygon
				(pts
					(arc
						(start 335.754218 -38.516052)
						(mid 335.790589 -38.573915)
						(end 335.848452 -38.610286)
					)
					(arc
						(start 335.848452 -38.715442)
						(mid 335.718731 -38.645773)
						(end 335.649062 -38.516052)
					)
				)
			)
		)
		(zone
			(layer "F.Cu")
			(hatch none 0.5)
			(connect_pads
				(clearance 0)
			)
			(min_thickness 0.25)
			(keepout
				(tracks not_allowed)
				(vias allowed)
				(pads allowed)
				(copperpour not_allowed)
				(footprints allowed)
			)
			(placement
				(enabled no)
				(sheetname "")
			)
			(fill
				(thermal_gap 0.5)
				(thermal_bridge_width 0.5)
				(island_removal_mode 0)
			)
			(polygon
				(pts
					(arc
						(start 335.848452 -58.290206)
						(mid 335.790589 -58.326577)
						(end 335.754218 -58.38444)
					)
					(arc
						(start 335.649062 -58.38444)
						(mid 335.718731 -58.254719)
						(end 335.848452 -58.18505)
					)
				)
			)
		)
		(zone
			(layer "F.Cu")
			(hatch none 0.5)
			(connect_pads
				(clearance 0)
			)
			(min_thickness 0.25)
			(keepout
				(tracks not_allowed)
				(vias allowed)
				(pads allowed)
				(copperpour not_allowed)
				(footprints allowed)
			)
			(placement
				(enabled no)
				(sheetname "")
			)
			(fill
				(thermal_gap 0.5)
				(thermal_bridge_width 0.5)
				(island_removal_mode 0)
			)
			(polygon
				(pts
					(arc
						(start 335.848452 -57.460134)
						(mid 335.790589 -57.496505)
						(end 335.754218 -57.554368)
					)
					(arc
						(start 335.649062 -57.554368)
						(mid 335.718731 -57.424647)
						(end 335.848452 -57.354978)
					)
				)
			)
		)
		(zone
			(layer "F.Cu")
			(hatch none 0.5)
			(connect_pads
				(clearance 0)
			)
			(min_thickness 0.25)
			(keepout
				(tracks not_allowed)
				(vias allowed)
				(pads allowed)
				(copperpour not_allowed)
				(footprints allowed)
			)
			(placement
				(enabled no)
				(sheetname "")
			)
			(fill
				(thermal_gap 0.5)
				(thermal_bridge_width 0.5)
				(island_removal_mode 0)
			)
			(polygon
				(pts
					(arc
						(start 335.848452 -39.15029)
						(mid 335.790589 -39.186661)
						(end 335.754218 -39.244524)
					)
					(arc
						(start 335.649062 -39.244524)
						(mid 335.718731 -39.114803)
						(end 335.848452 -39.045134)
					)
				)
			)
		)
		(zone
			(layer "F.Cu")
			(hatch none 0.5)
			(connect_pads
				(clearance 0)
			)
			(min_thickness 0.25)
			(keepout
				(tracks not_allowed)
				(vias allowed)
				(pads allowed)
				(copperpour not_allowed)
				(footprints allowed)
			)
			(placement
				(enabled no)
				(sheetname "")
			)
			(fill
				(thermal_gap 0.5)
				(thermal_bridge_width 0.5)
				(island_removal_mode 0)
			)
			(polygon
				(pts
					(arc
						(start 335.848452 -38.320218)
						(mid 335.790589 -38.356589)
						(end 335.754218 -38.414452)
					)
					(arc
						(start 335.649062 -38.414452)
						(mid 335.718731 -38.284731)
						(end 335.848452 -38.215062)
					)
				)
			)
		)
		(zone
			(layer "F.Cu")
			(hatch none 0.5)
			(connect_pads
				(clearance 0)
			)
			(min_thickness 0.25)
			(keepout
				(tracks not_allowed)
				(vias allowed)
				(pads allowed)
				(copperpour not_allowed)
				(footprints allowed)
			)
			(placement
				(enabled no)
				(sheetname "")
			)
			(fill
				(thermal_gap 0.5)
				(thermal_bridge_width 0.5)
				(island_removal_mode 0)
			)
			(polygon
				(pts
					(arc
						(start 335.950052 -58.58002)
						(mid 336.007911 -58.543789)
						(end 336.044286 -58.48604)
					)
					(arc
						(start 336.149442 -58.48604)
						(mid 336.079773 -58.615761)
						(end 335.950052 -58.68543)
					)
				)
			)
		)
		(zone
			(layer "F.Cu")
			(hatch none 0.5)
			(connect_pads
				(clearance 0)
			)
			(min_thickness 0.25)
			(keepout
				(tracks not_allowed)
				(vias allowed)
				(pads allowed)
				(copperpour not_allowed)
				(footprints allowed)
			)
			(placement
				(enabled no)
				(sheetname "")
			)
			(fill
				(thermal_gap 0.5)
				(thermal_bridge_width 0.5)
				(island_removal_mode 0)
			)
			(polygon
				(pts
					(arc
						(start 335.950052 -57.750202)
						(mid 336.007915 -57.713831)
						(end 336.044286 -57.655968)
					)
					(arc
						(start 336.149442 -57.655968)
						(mid 336.079773 -57.785689)
						(end 335.950052 -57.855358)
					)
				)
			)
		)
		(zone
			(layer "F.Cu")
			(hatch none 0.5)
			(connect_pads
				(clearance 0)
			)
			(min_thickness 0.25)
			(keepout
				(tracks not_allowed)
				(vias allowed)
				(pads allowed)
				(copperpour not_allowed)
				(footprints allowed)
			)
			(placement
				(enabled no)
				(sheetname "")
			)
			(fill
				(thermal_gap 0.5)
				(thermal_bridge_width 0.5)
				(island_removal_mode 0)
			)
			(polygon
				(pts
					(arc
						(start 335.950052 -39.440358)
						(mid 336.007915 -39.403987)
						(end 336.044286 -39.346124)
					)
					(arc
						(start 336.149442 -39.346124)
						(mid 336.079773 -39.475845)
						(end 335.950052 -39.545514)
					)
				)
			)
		)
		(zone
			(layer "F.Cu")
			(hatch none 0.5)
			(connect_pads
				(clearance 0)
			)
			(min_thickness 0.25)
			(keepout
				(tracks not_allowed)
				(vias allowed)
				(pads allowed)
				(copperpour not_allowed)
				(footprints allowed)
			)
			(placement
				(enabled no)
				(sheetname "")
			)
			(fill
				(thermal_gap 0.5)
				(thermal_bridge_width 0.5)
				(island_removal_mode 0)
			)
			(polygon
				(pts
					(arc
						(start 335.950052 -38.610286)
						(mid 336.007915 -38.573915)
						(end 336.044286 -38.516052)
					)
					(arc
						(start 336.149442 -38.516052)
						(mid 336.079773 -38.645773)
						(end 335.950052 -38.715442)
					)
				)
			)
		)
		(zone
			(layer "F.Cu")
			(hatch none 0.5)
			(connect_pads
				(clearance 0)
			)
			(min_thickness 0.25)
			(keepout
				(tracks not_allowed)
				(vias allowed)
				(pads allowed)
				(copperpour not_allowed)
				(footprints allowed)
			)
			(placement
				(enabled no)
				(sheetname "")
			)
			(fill
				(thermal_gap 0.5)
				(thermal_bridge_width 0.5)
				(island_removal_mode 0)
			)
			(polygon
				(pts
					(arc
						(start 336.044286 -58.38444)
						(mid 336.007915 -58.326577)
						(end 335.950052 -58.290206)
					)
					(arc
						(start 335.950052 -58.18505)
						(mid 336.079773 -58.254719)
						(end 336.149442 -58.38444)
					)
				)
			)
		)
		(zone
			(layer "F.Cu")
			(hatch none 0.5)
			(connect_pads
				(clearance 0)
			)
			(min_thickness 0.25)
			(keepout
				(tracks not_allowed)
				(vias allowed)
				(pads allowed)
				(copperpour not_allowed)
				(footprints allowed)
			)
			(placement
				(enabled no)
				(sheetname "")
			)
			(fill
				(thermal_gap 0.5)
				(thermal_bridge_width 0.5)
				(island_removal_mode 0)
			)
			(polygon
				(pts
					(arc
						(start 336.044286 -57.554368)
						(mid 336.007915 -57.496505)
						(end 335.950052 -57.460134)
					)
					(arc
						(start 335.950052 -57.354978)
						(mid 336.079773 -57.424647)
						(end 336.149442 -57.554368)
					)
				)
			)
		)
		(zone
			(layer "F.Cu")
			(hatch none 0.5)
			(connect_pads
				(clearance 0)
			)
			(min_thickness 0.25)
			(keepout
				(tracks not_allowed)
				(vias allowed)
				(pads allowed)
				(copperpour not_allowed)
				(footprints allowed)
			)
			(placement
				(enabled no)
				(sheetname "")
			)
			(fill
				(thermal_gap 0.5)
				(thermal_bridge_width 0.5)
				(island_removal_mode 0)
			)
			(polygon
				(pts
					(arc
						(start 336.044286 -39.244524)
						(mid 336.007915 -39.186661)
						(end 335.950052 -39.15029)
					)
					(arc
						(start 335.950052 -39.045134)
						(mid 336.079773 -39.114803)
						(end 336.149442 -39.244524)
					)
				)
			)
		)
		(zone
			(layer "F.Cu")
			(hatch none 0.5)
			(connect_pads
				(clearance 0)
			)
			(min_thickness 0.25)
			(keepout
				(tracks not_allowed)
				(vias allowed)
				(pads allowed)
				(copperpour not_allowed)
				(footprints allowed)
			)
			(placement
				(enabled no)
				(sheetname "")
			)
			(fill
				(thermal_gap 0.5)
				(thermal_bridge_width 0.5)
				(island_removal_mode 0)
			)
			(polygon
				(pts
					(arc
						(start 336.044286 -38.414452)
						(mid 336.007915 -38.356589)
						(end 335.950052 -38.320218)
					)
					(arc
						(start 335.950052 -38.215062)
						(mid 336.079773 -38.284731)
						(end 336.149442 -38.414452)
					)
				)
			)
		)
		(zone
			(layer "F.Cu")
			(hatch none 0.5)
			(connect_pads
				(clearance 0)
			)
			(min_thickness 0.25)
			(keepout
				(tracks not_allowed)
				(vias allowed)
				(pads allowed)
				(copperpour not_allowed)
				(footprints allowed)
			)
			(placement
				(enabled no)
				(sheetname "")
			)
			(fill
				(thermal_gap 0.5)
				(thermal_bridge_width 0.5)
				(island_removal_mode 0)
			)
			(polygon
				(pts
					(arc
						(start 336.254344 -38.931088)
						(mid 336.290715 -38.988951)
						(end 336.348578 -39.025322)
					)
					(arc
						(start 336.348578 -39.130478)
						(mid 336.218857 -39.060809)
						(end 336.149188 -38.931088)
					)
				)
			)
		)
		(zone
			(layer "F.Cu")
			(hatch none 0.5)
			(connect_pads
				(clearance 0)
			)
			(min_thickness 0.25)
			(keepout
				(tracks not_allowed)
				(vias allowed)
				(pads allowed)
				(copperpour not_allowed)
				(footprints allowed)
			)
			(placement
				(enabled no)
				(sheetname "")
			)
			(fill
				(thermal_gap 0.5)
				(thermal_bridge_width 0.5)
				(island_removal_mode 0)
			)
			(polygon
				(pts
					(arc
						(start 336.254344 -38.101016)
						(mid 336.290715 -38.158879)
						(end 336.348578 -38.19525)
					)
					(arc
						(start 336.348578 -38.300406)
						(mid 336.218857 -38.230737)
						(end 336.149188 -38.101016)
					)
				)
			)
		)
		(zone
			(layer "F.Cu")
			(hatch none 0.5)
			(connect_pads
				(clearance 0)
			)
			(min_thickness 0.25)
			(keepout
				(tracks not_allowed)
				(vias allowed)
				(pads allowed)
				(copperpour not_allowed)
				(footprints allowed)
			)
			(placement
				(enabled no)
				(sheetname "")
			)
			(fill
				(thermal_gap 0.5)
				(thermal_bridge_width 0.5)
				(island_removal_mode 0)
			)
			(polygon
				(pts
					(arc
						(start 336.254598 -58.901076)
						(mid 336.290969 -58.958939)
						(end 336.348832 -58.99531)
					)
					(arc
						(start 336.348832 -59.100466)
						(mid 336.219111 -59.030797)
						(end 336.149442 -58.901076)
					)
				)
			)
		)
		(zone
			(layer "F.Cu")
			(hatch none 0.5)
			(connect_pads
				(clearance 0)
			)
			(min_thickness 0.25)
			(keepout
				(tracks not_allowed)
				(vias allowed)
				(pads allowed)
				(copperpour not_allowed)
				(footprints allowed)
			)
			(placement
				(enabled no)
				(sheetname "")
			)
			(fill
				(thermal_gap 0.5)
				(thermal_bridge_width 0.5)
				(island_removal_mode 0)
			)
			(polygon
				(pts
					(arc
						(start 336.254598 -58.071004)
						(mid 336.290969 -58.128867)
						(end 336.348832 -58.165238)
					)
					(arc
						(start 336.348832 -58.270394)
						(mid 336.219111 -58.200725)
						(end 336.149442 -58.071004)
					)
				)
			)
		)
		(zone
			(layer "F.Cu")
			(hatch none 0.5)
			(connect_pads
				(clearance 0)
			)
			(min_thickness 0.25)
			(keepout
				(tracks not_allowed)
				(vias allowed)
				(pads allowed)
				(copperpour not_allowed)
				(footprints allowed)
			)
			(placement
				(enabled no)
				(sheetname "")
			)
			(fill
				(thermal_gap 0.5)
				(thermal_bridge_width 0.5)
				(island_removal_mode 0)
			)
			(polygon
				(pts
					(arc
						(start 336.348578 -38.735254)
						(mid 336.290715 -38.771625)
						(end 336.254344 -38.829488)
					)
					(arc
						(start 336.149188 -38.829488)
						(mid 336.218857 -38.699767)
						(end 336.348578 -38.630098)
					)
				)
			)
		)
		(zone
			(layer "F.Cu")
			(hatch none 0.5)
			(connect_pads
				(clearance 0)
			)
			(min_thickness 0.25)
			(keepout
				(tracks not_allowed)
				(vias allowed)
				(pads allowed)
				(copperpour not_allowed)
				(footprints allowed)
			)
			(placement
				(enabled no)
				(sheetname "")
			)
			(fill
				(thermal_gap 0.5)
				(thermal_bridge_width 0.5)
				(island_removal_mode 0)
			)
			(polygon
				(pts
					(arc
						(start 336.348578 -37.905182)
						(mid 336.290715 -37.941553)
						(end 336.254344 -37.999416)
					)
					(arc
						(start 336.149188 -37.999416)
						(mid 336.218857 -37.869695)
						(end 336.348578 -37.800026)
					)
				)
			)
		)
		(zone
			(layer "F.Cu")
			(hatch none 0.5)
			(connect_pads
				(clearance 0)
			)
			(min_thickness 0.25)
			(keepout
				(tracks not_allowed)
				(vias allowed)
				(pads allowed)
				(copperpour not_allowed)
				(footprints allowed)
			)
			(placement
				(enabled no)
				(sheetname "")
			)
			(fill
				(thermal_gap 0.5)
				(thermal_bridge_width 0.5)
				(island_removal_mode 0)
			)
			(polygon
				(pts
					(arc
						(start 336.348832 -58.705242)
						(mid 336.290969 -58.741613)
						(end 336.254598 -58.799476)
					)
					(arc
						(start 336.149442 -58.799476)
						(mid 336.219111 -58.669755)
						(end 336.348832 -58.600086)
					)
				)
			)
		)
		(zone
			(layer "F.Cu")
			(hatch none 0.5)
			(connect_pads
				(clearance 0)
			)
			(min_thickness 0.25)
			(keepout
				(tracks not_allowed)
				(vias allowed)
				(pads allowed)
				(copperpour not_allowed)
				(footprints allowed)
			)
			(placement
				(enabled no)
				(sheetname "")
			)
			(fill
				(thermal_gap 0.5)
				(thermal_bridge_width 0.5)
				(island_removal_mode 0)
			)
			(polygon
				(pts
					(arc
						(start 336.348832 -57.87517)
						(mid 336.290969 -57.911541)
						(end 336.254598 -57.969404)
					)
					(arc
						(start 336.149442 -57.969404)
						(mid 336.219111 -57.839683)
						(end 336.348832 -57.770014)
					)
				)
			)
		)
		(zone
			(layer "F.Cu")
			(hatch none 0.5)
			(connect_pads
				(clearance 0)
			)
			(min_thickness 0.25)
			(keepout
				(tracks not_allowed)
				(vias allowed)
				(pads allowed)
				(copperpour not_allowed)
				(footprints allowed)
			)
			(placement
				(enabled no)
				(sheetname "")
			)
			(fill
				(thermal_gap 0.5)
				(thermal_bridge_width 0.5)
				(island_removal_mode 0)
			)
			(polygon
				(pts
					(arc
						(start 336.450178 -39.025322)
						(mid 336.508041 -38.988951)
						(end 336.544412 -38.931088)
					)
					(arc
						(start 336.649568 -38.931088)
						(mid 336.579899 -39.060809)
						(end 336.450178 -39.130478)
					)
				)
			)
		)
		(zone
			(layer "F.Cu")
			(hatch none 0.5)
			(connect_pads
				(clearance 0)
			)
			(min_thickness 0.25)
			(keepout
				(tracks not_allowed)
				(vias allowed)
				(pads allowed)
				(copperpour not_allowed)
				(footprints allowed)
			)
			(placement
				(enabled no)
				(sheetname "")
			)
			(fill
				(thermal_gap 0.5)
				(thermal_bridge_width 0.5)
				(island_removal_mode 0)
			)
			(polygon
				(pts
					(arc
						(start 336.450178 -38.19525)
						(mid 336.508041 -38.158879)
						(end 336.544412 -38.101016)
					)
					(arc
						(start 336.649568 -38.101016)
						(mid 336.579899 -38.230737)
						(end 336.450178 -38.300406)
					)
				)
			)
		)
		(zone
			(layer "F.Cu")
			(hatch none 0.5)
			(connect_pads
				(clearance 0)
			)
			(min_thickness 0.25)
			(keepout
				(tracks not_allowed)
				(vias allowed)
				(pads allowed)
				(copperpour not_allowed)
				(footprints allowed)
			)
			(placement
				(enabled no)
				(sheetname "")
			)
			(fill
				(thermal_gap 0.5)
				(thermal_bridge_width 0.5)
				(island_removal_mode 0)
			)
			(polygon
				(pts
					(arc
						(start 336.450432 -58.99531)
						(mid 336.508295 -58.958939)
						(end 336.544666 -58.901076)
					)
					(arc
						(start 336.649822 -58.901076)
						(mid 336.580153 -59.030797)
						(end 336.450432 -59.100466)
					)
				)
			)
		)
		(zone
			(layer "F.Cu")
			(hatch none 0.5)
			(connect_pads
				(clearance 0)
			)
			(min_thickness 0.25)
			(keepout
				(tracks not_allowed)
				(vias allowed)
				(pads allowed)
				(copperpour not_allowed)
				(footprints allowed)
			)
			(placement
				(enabled no)
				(sheetname "")
			)
			(fill
				(thermal_gap 0.5)
				(thermal_bridge_width 0.5)
				(island_removal_mode 0)
			)
			(polygon
				(pts
					(arc
						(start 336.450432 -58.165238)
						(mid 336.508295 -58.128867)
						(end 336.544666 -58.071004)
					)
					(arc
						(start 336.649822 -58.071004)
						(mid 336.580153 -58.200725)
						(end 336.450432 -58.270394)
					)
				)
			)
		)
		(zone
			(layer "F.Cu")
			(hatch none 0.5)
			(connect_pads
				(clearance 0)
			)
			(min_thickness 0.25)
			(keepout
				(tracks not_allowed)
				(vias allowed)
				(pads allowed)
				(copperpour not_allowed)
				(footprints allowed)
			)
			(placement
				(enabled no)
				(sheetname "")
			)
			(fill
				(thermal_gap 0.5)
				(thermal_bridge_width 0.5)
				(island_removal_mode 0)
			)
			(polygon
				(pts
					(arc
						(start 336.544412 -38.829488)
						(mid 336.508041 -38.771625)
						(end 336.450178 -38.735254)
					)
					(arc
						(start 336.450178 -38.630098)
						(mid 336.579899 -38.699767)
						(end 336.649568 -38.829488)
					)
				)
			)
		)
		(zone
			(layer "F.Cu")
			(hatch none 0.5)
			(connect_pads
				(clearance 0)
			)
			(min_thickness 0.25)
			(keepout
				(tracks not_allowed)
				(vias allowed)
				(pads allowed)
				(copperpour not_allowed)
				(footprints allowed)
			)
			(placement
				(enabled no)
				(sheetname "")
			)
			(fill
				(thermal_gap 0.5)
				(thermal_bridge_width 0.5)
				(island_removal_mode 0)
			)
			(polygon
				(pts
					(arc
						(start 336.544412 -37.999416)
						(mid 336.508041 -37.941553)
						(end 336.450178 -37.905182)
					)
					(arc
						(start 336.450178 -37.800026)
						(mid 336.579899 -37.869695)
						(end 336.649568 -37.999416)
					)
				)
			)
		)
		(zone
			(layer "F.Cu")
			(hatch none 0.5)
			(connect_pads
				(clearance 0)
			)
			(min_thickness 0.25)
			(keepout
				(tracks not_allowed)
				(vias allowed)
				(pads allowed)
				(copperpour not_allowed)
				(footprints allowed)
			)
			(placement
				(enabled no)
				(sheetname "")
			)
			(fill
				(thermal_gap 0.5)
				(thermal_bridge_width 0.5)
				(island_removal_mode 0)
			)
			(polygon
				(pts
					(arc
						(start 336.544666 -58.799476)
						(mid 336.508295 -58.741613)
						(end 336.450432 -58.705242)
					)
					(arc
						(start 336.450432 -58.600086)
						(mid 336.580153 -58.669755)
						(end 336.649822 -58.799476)
					)
				)
			)
		)
		(zone
			(layer "F.Cu")
			(hatch none 0.5)
			(connect_pads
				(clearance 0)
			)
			(min_thickness 0.25)
			(keepout
				(tracks not_allowed)
				(vias allowed)
				(pads allowed)
				(copperpour not_allowed)
				(footprints allowed)
			)
			(placement
				(enabled no)
				(sheetname "")
			)
			(fill
				(thermal_gap 0.5)
				(thermal_bridge_width 0.5)
				(island_removal_mode 0)
			)
			(polygon
				(pts
					(arc
						(start 336.544666 -57.969404)
						(mid 336.508295 -57.911541)
						(end 336.450432 -57.87517)
					)
					(arc
						(start 336.450432 -57.770014)
						(mid 336.580153 -57.839683)
						(end 336.649822 -57.969404)
					)
				)
			)
		)
		(zone
			(layer "F.Cu")
			(hatch none 0.5)
			(connect_pads
				(clearance 0)
			)
			(min_thickness 0.25)
			(keepout
				(tracks not_allowed)
				(vias allowed)
				(pads allowed)
				(copperpour not_allowed)
				(footprints allowed)
			)
			(placement
				(enabled no)
				(sheetname "")
			)
			(fill
				(thermal_gap 0.5)
				(thermal_bridge_width 0.5)
				(island_removal_mode 0)
			)
			(polygon
				(pts
					(arc
						(start 336.754724 -58.48604)
						(mid 336.79115 -58.543739)
						(end 336.848958 -58.58002)
					)
					(arc
						(start 336.848958 -58.68543)
						(mid 336.719237 -58.615761)
						(end 336.649568 -58.48604)
					)
				)
			)
		)
		(zone
			(layer "F.Cu")
			(hatch none 0.5)
			(connect_pads
				(clearance 0)
			)
			(min_thickness 0.25)
			(keepout
				(tracks not_allowed)
				(vias allowed)
				(pads allowed)
				(copperpour not_allowed)
				(footprints allowed)
			)
			(placement
				(enabled no)
				(sheetname "")
			)
			(fill
				(thermal_gap 0.5)
				(thermal_bridge_width 0.5)
				(island_removal_mode 0)
			)
			(polygon
				(pts
					(arc
						(start 336.754724 -57.655968)
						(mid 336.791095 -57.713831)
						(end 336.848958 -57.750202)
					)
					(arc
						(start 336.848958 -57.855358)
						(mid 336.719237 -57.785689)
						(end 336.649568 -57.655968)
					)
				)
			)
		)
		(zone
			(layer "F.Cu")
			(hatch none 0.5)
			(connect_pads
				(clearance 0)
			)
			(min_thickness 0.25)
			(keepout
				(tracks not_allowed)
				(vias allowed)
				(pads allowed)
				(copperpour not_allowed)
				(footprints allowed)
			)
			(placement
				(enabled no)
				(sheetname "")
			)
			(fill
				(thermal_gap 0.5)
				(thermal_bridge_width 0.5)
				(island_removal_mode 0)
			)
			(polygon
				(pts
					(arc
						(start 336.754724 -39.346124)
						(mid 336.791095 -39.403987)
						(end 336.848958 -39.440358)
					)
					(arc
						(start 336.848958 -39.545514)
						(mid 336.719237 -39.475845)
						(end 336.649568 -39.346124)
					)
				)
			)
		)
		(zone
			(layer "F.Cu")
			(hatch none 0.5)
			(connect_pads
				(clearance 0)
			)
			(min_thickness 0.25)
			(keepout
				(tracks not_allowed)
				(vias allowed)
				(pads allowed)
				(copperpour not_allowed)
				(footprints allowed)
			)
			(placement
				(enabled no)
				(sheetname "")
			)
			(fill
				(thermal_gap 0.5)
				(thermal_bridge_width 0.5)
				(island_removal_mode 0)
			)
			(polygon
				(pts
					(arc
						(start 336.754724 -38.516052)
						(mid 336.791095 -38.573915)
						(end 336.848958 -38.610286)
					)
					(arc
						(start 336.848958 -38.715442)
						(mid 336.719237 -38.645773)
						(end 336.649568 -38.516052)
					)
				)
			)
		)
		(zone
			(layer "F.Cu")
			(hatch none 0.5)
			(connect_pads
				(clearance 0)
			)
			(min_thickness 0.25)
			(keepout
				(tracks not_allowed)
				(vias allowed)
				(pads allowed)
				(copperpour not_allowed)
				(footprints allowed)
			)
			(placement
				(enabled no)
				(sheetname "")
			)
			(fill
				(thermal_gap 0.5)
				(thermal_bridge_width 0.5)
				(island_removal_mode 0)
			)
			(polygon
				(pts
					(arc
						(start 336.848958 -58.290206)
						(mid 336.791095 -58.326577)
						(end 336.754724 -58.38444)
					)
					(arc
						(start 336.649568 -58.38444)
						(mid 336.719237 -58.254719)
						(end 336.848958 -58.18505)
					)
				)
			)
		)
		(zone
			(layer "F.Cu")
			(hatch none 0.5)
			(connect_pads
				(clearance 0)
			)
			(min_thickness 0.25)
			(keepout
				(tracks not_allowed)
				(vias allowed)
				(pads allowed)
				(copperpour not_allowed)
				(footprints allowed)
			)
			(placement
				(enabled no)
				(sheetname "")
			)
			(fill
				(thermal_gap 0.5)
				(thermal_bridge_width 0.5)
				(island_removal_mode 0)
			)
			(polygon
				(pts
					(arc
						(start 336.848958 -57.460134)
						(mid 336.791095 -57.496505)
						(end 336.754724 -57.554368)
					)
					(arc
						(start 336.649568 -57.554368)
						(mid 336.719237 -57.424647)
						(end 336.848958 -57.354978)
					)
				)
			)
		)
		(zone
			(layer "F.Cu")
			(hatch none 0.5)
			(connect_pads
				(clearance 0)
			)
			(min_thickness 0.25)
			(keepout
				(tracks not_allowed)
				(vias allowed)
				(pads allowed)
				(copperpour not_allowed)
				(footprints allowed)
			)
			(placement
				(enabled no)
				(sheetname "")
			)
			(fill
				(thermal_gap 0.5)
				(thermal_bridge_width 0.5)
				(island_removal_mode 0)
			)
			(polygon
				(pts
					(arc
						(start 336.848958 -39.15029)
						(mid 336.791095 -39.186661)
						(end 336.754724 -39.244524)
					)
					(arc
						(start 336.649568 -39.244524)
						(mid 336.719237 -39.114803)
						(end 336.848958 -39.045134)
					)
				)
			)
		)
		(zone
			(layer "F.Cu")
			(hatch none 0.5)
			(connect_pads
				(clearance 0)
			)
			(min_thickness 0.25)
			(keepout
				(tracks not_allowed)
				(vias allowed)
				(pads allowed)
				(copperpour not_allowed)
				(footprints allowed)
			)
			(placement
				(enabled no)
				(sheetname "")
			)
			(fill
				(thermal_gap 0.5)
				(thermal_bridge_width 0.5)
				(island_removal_mode 0)
			)
			(polygon
				(pts
					(arc
						(start 336.848958 -38.320218)
						(mid 336.791095 -38.356589)
						(end 336.754724 -38.414452)
					)
					(arc
						(start 336.649568 -38.414452)
						(mid 336.719237 -38.284731)
						(end 336.848958 -38.215062)
					)
				)
			)
		)
		(zone
			(layer "F.Cu")
			(hatch none 0.5)
			(connect_pads
				(clearance 0)
			)
			(min_thickness 0.25)
			(keepout
				(tracks not_allowed)
				(vias allowed)
				(pads allowed)
				(copperpour not_allowed)
				(footprints allowed)
			)
			(placement
				(enabled no)
				(sheetname "")
			)
			(fill
				(thermal_gap 0.5)
				(thermal_bridge_width 0.5)
				(island_removal_mode 0)
			)
			(polygon
				(pts
					(arc
						(start 336.950558 -58.58002)
						(mid 337.008417 -58.543789)
						(end 337.044792 -58.48604)
					)
					(arc
						(start 337.149948 -58.48604)
						(mid 337.080279 -58.615761)
						(end 336.950558 -58.68543)
					)
				)
			)
		)
		(zone
			(layer "F.Cu")
			(hatch none 0.5)
			(connect_pads
				(clearance 0)
			)
			(min_thickness 0.25)
			(keepout
				(tracks not_allowed)
				(vias allowed)
				(pads allowed)
				(copperpour not_allowed)
				(footprints allowed)
			)
			(placement
				(enabled no)
				(sheetname "")
			)
			(fill
				(thermal_gap 0.5)
				(thermal_bridge_width 0.5)
				(island_removal_mode 0)
			)
			(polygon
				(pts
					(arc
						(start 336.950558 -57.750202)
						(mid 337.008421 -57.713831)
						(end 337.044792 -57.655968)
					)
					(arc
						(start 337.149948 -57.655968)
						(mid 337.080279 -57.785689)
						(end 336.950558 -57.855358)
					)
				)
			)
		)
		(zone
			(layer "F.Cu")
			(hatch none 0.5)
			(connect_pads
				(clearance 0)
			)
			(min_thickness 0.25)
			(keepout
				(tracks not_allowed)
				(vias allowed)
				(pads allowed)
				(copperpour not_allowed)
				(footprints allowed)
			)
			(placement
				(enabled no)
				(sheetname "")
			)
			(fill
				(thermal_gap 0.5)
				(thermal_bridge_width 0.5)
				(island_removal_mode 0)
			)
			(polygon
				(pts
					(arc
						(start 336.950558 -39.440358)
						(mid 337.008421 -39.403987)
						(end 337.044792 -39.346124)
					)
					(arc
						(start 337.149948 -39.346124)
						(mid 337.080279 -39.475845)
						(end 336.950558 -39.545514)
					)
				)
			)
		)
		(zone
			(layer "F.Cu")
			(hatch none 0.5)
			(connect_pads
				(clearance 0)
			)
			(min_thickness 0.25)
			(keepout
				(tracks not_allowed)
				(vias allowed)
				(pads allowed)
				(copperpour not_allowed)
				(footprints allowed)
			)
			(placement
				(enabled no)
				(sheetname "")
			)
			(fill
				(thermal_gap 0.5)
				(thermal_bridge_width 0.5)
				(island_removal_mode 0)
			)
			(polygon
				(pts
					(arc
						(start 336.950558 -38.610286)
						(mid 337.008421 -38.573915)
						(end 337.044792 -38.516052)
					)
					(arc
						(start 337.149948 -38.516052)
						(mid 337.080279 -38.645773)
						(end 336.950558 -38.715442)
					)
				)
			)
		)
		(zone
			(layer "F.Cu")
			(hatch none 0.5)
			(connect_pads
				(clearance 0)
			)
			(min_thickness 0.25)
			(keepout
				(tracks not_allowed)
				(vias allowed)
				(pads allowed)
				(copperpour not_allowed)
				(footprints allowed)
			)
			(placement
				(enabled no)
				(sheetname "")
			)
			(fill
				(thermal_gap 0.5)
				(thermal_bridge_width 0.5)
				(island_removal_mode 0)
			)
			(polygon
				(pts
					(arc
						(start 337.044792 -58.38444)
						(mid 337.008421 -58.326577)
						(end 336.950558 -58.290206)
					)
					(arc
						(start 336.950558 -58.18505)
						(mid 337.080279 -58.254719)
						(end 337.149948 -58.38444)
					)
				)
			)
		)
		(zone
			(layer "F.Cu")
			(hatch none 0.5)
			(connect_pads
				(clearance 0)
			)
			(min_thickness 0.25)
			(keepout
				(tracks not_allowed)
				(vias allowed)
				(pads allowed)
				(copperpour not_allowed)
				(footprints allowed)
			)
			(placement
				(enabled no)
				(sheetname "")
			)
			(fill
				(thermal_gap 0.5)
				(thermal_bridge_width 0.5)
				(island_removal_mode 0)
			)
			(polygon
				(pts
					(arc
						(start 337.044792 -57.554368)
						(mid 337.008421 -57.496505)
						(end 336.950558 -57.460134)
					)
					(arc
						(start 336.950558 -57.354978)
						(mid 337.080279 -57.424647)
						(end 337.149948 -57.554368)
					)
				)
			)
		)
		(zone
			(layer "F.Cu")
			(hatch none 0.5)
			(connect_pads
				(clearance 0)
			)
			(min_thickness 0.25)
			(keepout
				(tracks not_allowed)
				(vias allowed)
				(pads allowed)
				(copperpour not_allowed)
				(footprints allowed)
			)
			(placement
				(enabled no)
				(sheetname "")
			)
			(fill
				(thermal_gap 0.5)
				(thermal_bridge_width 0.5)
				(island_removal_mode 0)
			)
			(polygon
				(pts
					(arc
						(start 337.044792 -39.244524)
						(mid 337.008421 -39.186661)
						(end 336.950558 -39.15029)
					)
					(arc
						(start 336.950558 -39.045134)
						(mid 337.080279 -39.114803)
						(end 337.149948 -39.244524)
					)
				)
			)
		)
		(zone
			(layer "F.Cu")
			(hatch none 0.5)
			(connect_pads
				(clearance 0)
			)
			(min_thickness 0.25)
			(keepout
				(tracks not_allowed)
				(vias allowed)
				(pads allowed)
				(copperpour not_allowed)
				(footprints allowed)
			)
			(placement
				(enabled no)
				(sheetname "")
			)
			(fill
				(thermal_gap 0.5)
				(thermal_bridge_width 0.5)
				(island_removal_mode 0)
			)
			(polygon
				(pts
					(arc
						(start 337.044792 -38.414452)
						(mid 337.008421 -38.356589)
						(end 336.950558 -38.320218)
					)
					(arc
						(start 336.950558 -38.215062)
						(mid 337.080279 -38.284731)
						(end 337.149948 -38.414452)
					)
				)
			)
		)
		(zone
			(layer "F.Cu")
			(hatch none 0.5)
			(connect_pads
				(clearance 0)
			)
			(min_thickness 0.25)
			(keepout
				(tracks not_allowed)
				(vias allowed)
				(pads allowed)
				(copperpour not_allowed)
				(footprints allowed)
			)
			(placement
				(enabled no)
				(sheetname "")
			)
			(fill
				(thermal_gap 0.5)
				(thermal_bridge_width 0.5)
				(island_removal_mode 0)
			)
			(polygon
				(pts
					(arc
						(start 337.25485 -58.901076)
						(mid 337.291221 -58.958939)
						(end 337.349084 -58.99531)
					)
					(arc
						(start 337.349084 -59.100466)
						(mid 337.219363 -59.030797)
						(end 337.149694 -58.901076)
					)
				)
			)
		)
		(zone
			(layer "F.Cu")
			(hatch none 0.5)
			(connect_pads
				(clearance 0)
			)
			(min_thickness 0.25)
			(keepout
				(tracks not_allowed)
				(vias allowed)
				(pads allowed)
				(copperpour not_allowed)
				(footprints allowed)
			)
			(placement
				(enabled no)
				(sheetname "")
			)
			(fill
				(thermal_gap 0.5)
				(thermal_bridge_width 0.5)
				(island_removal_mode 0)
			)
			(polygon
				(pts
					(arc
						(start 337.25485 -38.931088)
						(mid 337.291221 -38.988951)
						(end 337.349084 -39.025322)
					)
					(arc
						(start 337.349084 -39.130478)
						(mid 337.219363 -39.060809)
						(end 337.149694 -38.931088)
					)
				)
			)
		)
		(zone
			(layer "F.Cu")
			(hatch none 0.5)
			(connect_pads
				(clearance 0)
			)
			(min_thickness 0.25)
			(keepout
				(tracks not_allowed)
				(vias allowed)
				(pads allowed)
				(copperpour not_allowed)
				(footprints allowed)
			)
			(placement
				(enabled no)
				(sheetname "")
			)
			(fill
				(thermal_gap 0.5)
				(thermal_bridge_width 0.5)
				(island_removal_mode 0)
			)
			(polygon
				(pts
					(arc
						(start 337.25485 -38.101016)
						(mid 337.291221 -38.158879)
						(end 337.349084 -38.19525)
					)
					(arc
						(start 337.349084 -38.300406)
						(mid 337.219363 -38.230737)
						(end 337.149694 -38.101016)
					)
				)
			)
		)
		(zone
			(layer "F.Cu")
			(hatch none 0.5)
			(connect_pads
				(clearance 0)
			)
			(min_thickness 0.25)
			(keepout
				(tracks not_allowed)
				(vias allowed)
				(pads allowed)
				(copperpour not_allowed)
				(footprints allowed)
			)
			(placement
				(enabled no)
				(sheetname "")
			)
			(fill
				(thermal_gap 0.5)
				(thermal_bridge_width 0.5)
				(island_removal_mode 0)
			)
			(polygon
				(pts
					(arc
						(start 337.255104 -58.071004)
						(mid 337.291475 -58.128867)
						(end 337.349338 -58.165238)
					)
					(arc
						(start 337.349338 -58.270394)
						(mid 337.219617 -58.200725)
						(end 337.149948 -58.071004)
					)
				)
			)
		)
		(zone
			(layer "F.Cu")
			(hatch none 0.5)
			(connect_pads
				(clearance 0)
			)
			(min_thickness 0.25)
			(keepout
				(tracks not_allowed)
				(vias allowed)
				(pads allowed)
				(copperpour not_allowed)
				(footprints allowed)
			)
			(placement
				(enabled no)
				(sheetname "")
			)
			(fill
				(thermal_gap 0.5)
				(thermal_bridge_width 0.5)
				(island_removal_mode 0)
			)
			(polygon
				(pts
					(arc
						(start 337.349084 -58.705242)
						(mid 337.291221 -58.741613)
						(end 337.25485 -58.799476)
					)
					(arc
						(start 337.149694 -58.799476)
						(mid 337.219363 -58.669755)
						(end 337.349084 -58.600086)
					)
				)
			)
		)
		(zone
			(layer "F.Cu")
			(hatch none 0.5)
			(connect_pads
				(clearance 0)
			)
			(min_thickness 0.25)
			(keepout
				(tracks not_allowed)
				(vias allowed)
				(pads allowed)
				(copperpour not_allowed)
				(footprints allowed)
			)
			(placement
				(enabled no)
				(sheetname "")
			)
			(fill
				(thermal_gap 0.5)
				(thermal_bridge_width 0.5)
				(island_removal_mode 0)
			)
			(polygon
				(pts
					(arc
						(start 337.349084 -38.735254)
						(mid 337.291221 -38.771625)
						(end 337.25485 -38.829488)
					)
					(arc
						(start 337.149694 -38.829488)
						(mid 337.219363 -38.699767)
						(end 337.349084 -38.630098)
					)
				)
			)
		)
		(zone
			(layer "F.Cu")
			(hatch none 0.5)
			(connect_pads
				(clearance 0)
			)
			(min_thickness 0.25)
			(keepout
				(tracks not_allowed)
				(vias allowed)
				(pads allowed)
				(copperpour not_allowed)
				(footprints allowed)
			)
			(placement
				(enabled no)
				(sheetname "")
			)
			(fill
				(thermal_gap 0.5)
				(thermal_bridge_width 0.5)
				(island_removal_mode 0)
			)
			(polygon
				(pts
					(arc
						(start 337.349084 -37.905182)
						(mid 337.291221 -37.941553)
						(end 337.25485 -37.999416)
					)
					(arc
						(start 337.149694 -37.999416)
						(mid 337.219363 -37.869695)
						(end 337.349084 -37.800026)
					)
				)
			)
		)
		(zone
			(layer "F.Cu")
			(hatch none 0.5)
			(connect_pads
				(clearance 0)
			)
			(min_thickness 0.25)
			(keepout
				(tracks not_allowed)
				(vias allowed)
				(pads allowed)
				(copperpour not_allowed)
				(footprints allowed)
			)
			(placement
				(enabled no)
				(sheetname "")
			)
			(fill
				(thermal_gap 0.5)
				(thermal_bridge_width 0.5)
				(island_removal_mode 0)
			)
			(polygon
				(pts
					(arc
						(start 337.349338 -57.87517)
						(mid 337.291475 -57.911541)
						(end 337.255104 -57.969404)
					)
					(arc
						(start 337.149948 -57.969404)
						(mid 337.219617 -57.839683)
						(end 337.349338 -57.770014)
					)
				)
			)
		)
		(zone
			(layer "F.Cu")
			(hatch none 0.5)
			(connect_pads
				(clearance 0)
			)
			(min_thickness 0.25)
			(keepout
				(tracks not_allowed)
				(vias allowed)
				(pads allowed)
				(copperpour not_allowed)
				(footprints allowed)
			)
			(placement
				(enabled no)
				(sheetname "")
			)
			(fill
				(thermal_gap 0.5)
				(thermal_bridge_width 0.5)
				(island_removal_mode 0)
			)
			(polygon
				(pts
					(arc
						(start 337.450684 -58.99531)
						(mid 337.508547 -58.958939)
						(end 337.544918 -58.901076)
					)
					(arc
						(start 337.650074 -58.901076)
						(mid 337.580405 -59.030797)
						(end 337.450684 -59.100466)
					)
				)
			)
		)
		(zone
			(layer "F.Cu")
			(hatch none 0.5)
			(connect_pads
				(clearance 0)
			)
			(min_thickness 0.25)
			(keepout
				(tracks not_allowed)
				(vias allowed)
				(pads allowed)
				(copperpour not_allowed)
				(footprints allowed)
			)
			(placement
				(enabled no)
				(sheetname "")
			)
			(fill
				(thermal_gap 0.5)
				(thermal_bridge_width 0.5)
				(island_removal_mode 0)
			)
			(polygon
				(pts
					(arc
						(start 337.450684 -39.025322)
						(mid 337.508547 -38.988951)
						(end 337.544918 -38.931088)
					)
					(arc
						(start 337.650074 -38.931088)
						(mid 337.580405 -39.060809)
						(end 337.450684 -39.130478)
					)
				)
			)
		)
		(zone
			(layer "F.Cu")
			(hatch none 0.5)
			(connect_pads
				(clearance 0)
			)
			(min_thickness 0.25)
			(keepout
				(tracks not_allowed)
				(vias allowed)
				(pads allowed)
				(copperpour not_allowed)
				(footprints allowed)
			)
			(placement
				(enabled no)
				(sheetname "")
			)
			(fill
				(thermal_gap 0.5)
				(thermal_bridge_width 0.5)
				(island_removal_mode 0)
			)
			(polygon
				(pts
					(arc
						(start 337.450684 -38.19525)
						(mid 337.508547 -38.158879)
						(end 337.544918 -38.101016)
					)
					(arc
						(start 337.650074 -38.101016)
						(mid 337.580405 -38.230737)
						(end 337.450684 -38.300406)
					)
				)
			)
		)
		(zone
			(layer "F.Cu")
			(hatch none 0.5)
			(connect_pads
				(clearance 0)
			)
			(min_thickness 0.25)
			(keepout
				(tracks not_allowed)
				(vias allowed)
				(pads allowed)
				(copperpour not_allowed)
				(footprints allowed)
			)
			(placement
				(enabled no)
				(sheetname "")
			)
			(fill
				(thermal_gap 0.5)
				(thermal_bridge_width 0.5)
				(island_removal_mode 0)
			)
			(polygon
				(pts
					(arc
						(start 337.450938 -58.165238)
						(mid 337.508801 -58.128867)
						(end 337.545172 -58.071004)
					)
					(arc
						(start 337.650328 -58.071004)
						(mid 337.580659 -58.200725)
						(end 337.450938 -58.270394)
					)
				)
			)
		)
		(zone
			(layer "F.Cu")
			(hatch none 0.5)
			(connect_pads
				(clearance 0)
			)
			(min_thickness 0.25)
			(keepout
				(tracks not_allowed)
				(vias allowed)
				(pads allowed)
				(copperpour not_allowed)
				(footprints allowed)
			)
			(placement
				(enabled no)
				(sheetname "")
			)
			(fill
				(thermal_gap 0.5)
				(thermal_bridge_width 0.5)
				(island_removal_mode 0)
			)
			(polygon
				(pts
					(arc
						(start 337.544918 -58.799476)
						(mid 337.508547 -58.741613)
						(end 337.450684 -58.705242)
					)
					(arc
						(start 337.450684 -58.600086)
						(mid 337.580405 -58.669755)
						(end 337.650074 -58.799476)
					)
				)
			)
		)
		(zone
			(layer "F.Cu")
			(hatch none 0.5)
			(connect_pads
				(clearance 0)
			)
			(min_thickness 0.25)
			(keepout
				(tracks not_allowed)
				(vias allowed)
				(pads allowed)
				(copperpour not_allowed)
				(footprints allowed)
			)
			(placement
				(enabled no)
				(sheetname "")
			)
			(fill
				(thermal_gap 0.5)
				(thermal_bridge_width 0.5)
				(island_removal_mode 0)
			)
			(polygon
				(pts
					(arc
						(start 337.544918 -38.829488)
						(mid 337.508547 -38.771625)
						(end 337.450684 -38.735254)
					)
					(arc
						(start 337.450684 -38.630098)
						(mid 337.580405 -38.699767)
						(end 337.650074 -38.829488)
					)
				)
			)
		)
		(zone
			(layer "F.Cu")
			(hatch none 0.5)
			(connect_pads
				(clearance 0)
			)
			(min_thickness 0.25)
			(keepout
				(tracks not_allowed)
				(vias allowed)
				(pads allowed)
				(copperpour not_allowed)
				(footprints allowed)
			)
			(placement
				(enabled no)
				(sheetname "")
			)
			(fill
				(thermal_gap 0.5)
				(thermal_bridge_width 0.5)
				(island_removal_mode 0)
			)
			(polygon
				(pts
					(arc
						(start 337.544918 -37.999416)
						(mid 337.508547 -37.941553)
						(end 337.450684 -37.905182)
					)
					(arc
						(start 337.450684 -37.800026)
						(mid 337.580405 -37.869695)
						(end 337.650074 -37.999416)
					)
				)
			)
		)
		(zone
			(layer "F.Cu")
			(hatch none 0.5)
			(connect_pads
				(clearance 0)
			)
			(min_thickness 0.25)
			(keepout
				(tracks not_allowed)
				(vias allowed)
				(pads allowed)
				(copperpour not_allowed)
				(footprints allowed)
			)
			(placement
				(enabled no)
				(sheetname "")
			)
			(fill
				(thermal_gap 0.5)
				(thermal_bridge_width 0.5)
				(island_removal_mode 0)
			)
			(polygon
				(pts
					(arc
						(start 337.545172 -57.969404)
						(mid 337.508801 -57.911541)
						(end 337.450938 -57.87517)
					)
					(arc
						(start 337.450938 -57.770014)
						(mid 337.580659 -57.839683)
						(end 337.650328 -57.969404)
					)
				)
			)
		)
		(zone
			(layer "F.Cu")
			(hatch none 0.5)
			(connect_pads
				(clearance 0)
			)
			(min_thickness 0.25)
			(keepout
				(tracks not_allowed)
				(vias allowed)
				(pads allowed)
				(copperpour not_allowed)
				(footprints allowed)
			)
			(placement
				(enabled no)
				(sheetname "")
			)
			(fill
				(thermal_gap 0.5)
				(thermal_bridge_width 0.5)
				(island_removal_mode 0)
			)
			(polygon
				(pts
					(arc
						(start 337.75523 -58.48604)
						(mid 337.791656 -58.543739)
						(end 337.849464 -58.58002)
					)
					(arc
						(start 337.849464 -58.68543)
						(mid 337.719743 -58.615761)
						(end 337.650074 -58.48604)
					)
				)
			)
		)
		(zone
			(layer "F.Cu")
			(hatch none 0.5)
			(connect_pads
				(clearance 0)
			)
			(min_thickness 0.25)
			(keepout
				(tracks not_allowed)
				(vias allowed)
				(pads allowed)
				(copperpour not_allowed)
				(footprints allowed)
			)
			(placement
				(enabled no)
				(sheetname "")
			)
			(fill
				(thermal_gap 0.5)
				(thermal_bridge_width 0.5)
				(island_removal_mode 0)
			)
			(polygon
				(pts
					(arc
						(start 337.75523 -57.655968)
						(mid 337.791601 -57.713831)
						(end 337.849464 -57.750202)
					)
					(arc
						(start 337.849464 -57.855358)
						(mid 337.719743 -57.785689)
						(end 337.650074 -57.655968)
					)
				)
			)
		)
		(zone
			(layer "F.Cu")
			(hatch none 0.5)
			(connect_pads
				(clearance 0)
			)
			(min_thickness 0.25)
			(keepout
				(tracks not_allowed)
				(vias allowed)
				(pads allowed)
				(copperpour not_allowed)
				(footprints allowed)
			)
			(placement
				(enabled no)
				(sheetname "")
			)
			(fill
				(thermal_gap 0.5)
				(thermal_bridge_width 0.5)
				(island_removal_mode 0)
			)
			(polygon
				(pts
					(arc
						(start 337.75523 -39.346124)
						(mid 337.791601 -39.403987)
						(end 337.849464 -39.440358)
					)
					(arc
						(start 337.849464 -39.545514)
						(mid 337.719743 -39.475845)
						(end 337.650074 -39.346124)
					)
				)
			)
		)
		(zone
			(layer "F.Cu")
			(hatch none 0.5)
			(connect_pads
				(clearance 0)
			)
			(min_thickness 0.25)
			(keepout
				(tracks not_allowed)
				(vias allowed)
				(pads allowed)
				(copperpour not_allowed)
				(footprints allowed)
			)
			(placement
				(enabled no)
				(sheetname "")
			)
			(fill
				(thermal_gap 0.5)
				(thermal_bridge_width 0.5)
				(island_removal_mode 0)
			)
			(polygon
				(pts
					(arc
						(start 337.75523 -38.516052)
						(mid 337.791601 -38.573915)
						(end 337.849464 -38.610286)
					)
					(arc
						(start 337.849464 -38.715442)
						(mid 337.719743 -38.645773)
						(end 337.650074 -38.516052)
					)
				)
			)
		)
		(zone
			(layer "F.Cu")
			(hatch none 0.5)
			(connect_pads
				(clearance 0)
			)
			(min_thickness 0.25)
			(keepout
				(tracks not_allowed)
				(vias allowed)
				(pads allowed)
				(copperpour not_allowed)
				(footprints allowed)
			)
			(placement
				(enabled no)
				(sheetname "")
			)
			(fill
				(thermal_gap 0.5)
				(thermal_bridge_width 0.5)
				(island_removal_mode 0)
			)
			(polygon
				(pts
					(arc
						(start 337.849464 -58.290206)
						(mid 337.791601 -58.326577)
						(end 337.75523 -58.38444)
					)
					(arc
						(start 337.650074 -58.38444)
						(mid 337.719743 -58.254719)
						(end 337.849464 -58.18505)
					)
				)
			)
		)
		(zone
			(layer "F.Cu")
			(hatch none 0.5)
			(connect_pads
				(clearance 0)
			)
			(min_thickness 0.25)
			(keepout
				(tracks not_allowed)
				(vias allowed)
				(pads allowed)
				(copperpour not_allowed)
				(footprints allowed)
			)
			(placement
				(enabled no)
				(sheetname "")
			)
			(fill
				(thermal_gap 0.5)
				(thermal_bridge_width 0.5)
				(island_removal_mode 0)
			)
			(polygon
				(pts
					(arc
						(start 337.849464 -57.460134)
						(mid 337.791601 -57.496505)
						(end 337.75523 -57.554368)
					)
					(arc
						(start 337.650074 -57.554368)
						(mid 337.719743 -57.424647)
						(end 337.849464 -57.354978)
					)
				)
			)
		)
		(zone
			(layer "F.Cu")
			(hatch none 0.5)
			(connect_pads
				(clearance 0)
			)
			(min_thickness 0.25)
			(keepout
				(tracks not_allowed)
				(vias allowed)
				(pads allowed)
				(copperpour not_allowed)
				(footprints allowed)
			)
			(placement
				(enabled no)
				(sheetname "")
			)
			(fill
				(thermal_gap 0.5)
				(thermal_bridge_width 0.5)
				(island_removal_mode 0)
			)
			(polygon
				(pts
					(arc
						(start 337.849464 -39.15029)
						(mid 337.791601 -39.186661)
						(end 337.75523 -39.244524)
					)
					(arc
						(start 337.650074 -39.244524)
						(mid 337.719743 -39.114803)
						(end 337.849464 -39.045134)
					)
				)
			)
		)
		(zone
			(layer "F.Cu")
			(hatch none 0.5)
			(connect_pads
				(clearance 0)
			)
			(min_thickness 0.25)
			(keepout
				(tracks not_allowed)
				(vias allowed)
				(pads allowed)
				(copperpour not_allowed)
				(footprints allowed)
			)
			(placement
				(enabled no)
				(sheetname "")
			)
			(fill
				(thermal_gap 0.5)
				(thermal_bridge_width 0.5)
				(island_removal_mode 0)
			)
			(polygon
				(pts
					(arc
						(start 337.849464 -38.320218)
						(mid 337.791601 -38.356589)
						(end 337.75523 -38.414452)
					)
					(arc
						(start 337.650074 -38.414452)
						(mid 337.719743 -38.284731)
						(end 337.849464 -38.215062)
					)
				)
			)
		)
		(zone
			(layer "F.Cu")
			(hatch none 0.5)
			(connect_pads
				(clearance 0)
			)
			(min_thickness 0.25)
			(keepout
				(tracks not_allowed)
				(vias allowed)
				(pads allowed)
				(copperpour not_allowed)
				(footprints allowed)
			)
			(placement
				(enabled no)
				(sheetname "")
			)
			(fill
				(thermal_gap 0.5)
				(thermal_bridge_width 0.5)
				(island_removal_mode 0)
			)
			(polygon
				(pts
					(arc
						(start 337.951064 -58.58002)
						(mid 338.008758 -58.543734)
						(end 338.045044 -58.48604)
					)
					(arc
						(start 338.150454 -58.48604)
						(mid 338.080785 -58.615761)
						(end 337.951064 -58.68543)
					)
				)
			)
		)
		(zone
			(layer "F.Cu")
			(hatch none 0.5)
			(connect_pads
				(clearance 0)
			)
			(min_thickness 0.25)
			(keepout
				(tracks not_allowed)
				(vias allowed)
				(pads allowed)
				(copperpour not_allowed)
				(footprints allowed)
			)
			(placement
				(enabled no)
				(sheetname "")
			)
			(fill
				(thermal_gap 0.5)
				(thermal_bridge_width 0.5)
				(island_removal_mode 0)
			)
			(polygon
				(pts
					(arc
						(start 337.951064 -57.750202)
						(mid 338.008927 -57.713831)
						(end 338.045298 -57.655968)
					)
					(arc
						(start 338.150454 -57.655968)
						(mid 338.080785 -57.785689)
						(end 337.951064 -57.855358)
					)
				)
			)
		)
		(zone
			(layer "F.Cu")
			(hatch none 0.5)
			(connect_pads
				(clearance 0)
			)
			(min_thickness 0.25)
			(keepout
				(tracks not_allowed)
				(vias allowed)
				(pads allowed)
				(copperpour not_allowed)
				(footprints allowed)
			)
			(placement
				(enabled no)
				(sheetname "")
			)
			(fill
				(thermal_gap 0.5)
				(thermal_bridge_width 0.5)
				(island_removal_mode 0)
			)
			(polygon
				(pts
					(arc
						(start 337.951064 -39.440358)
						(mid 338.008927 -39.403987)
						(end 338.045298 -39.346124)
					)
					(arc
						(start 338.150454 -39.346124)
						(mid 338.080785 -39.475845)
						(end 337.951064 -39.545514)
					)
				)
			)
		)
		(zone
			(layer "F.Cu")
			(hatch none 0.5)
			(connect_pads
				(clearance 0)
			)
			(min_thickness 0.25)
			(keepout
				(tracks not_allowed)
				(vias allowed)
				(pads allowed)
				(copperpour not_allowed)
				(footprints allowed)
			)
			(placement
				(enabled no)
				(sheetname "")
			)
			(fill
				(thermal_gap 0.5)
				(thermal_bridge_width 0.5)
				(island_removal_mode 0)
			)
			(polygon
				(pts
					(arc
						(start 337.951064 -38.610286)
						(mid 338.008927 -38.573915)
						(end 338.045298 -38.516052)
					)
					(arc
						(start 338.150454 -38.516052)
						(mid 338.080785 -38.645773)
						(end 337.951064 -38.715442)
					)
				)
			)
		)
		(zone
			(layer "F.Cu")
			(hatch none 0.5)
			(connect_pads
				(clearance 0)
			)
			(min_thickness 0.25)
			(keepout
				(tracks not_allowed)
				(vias allowed)
				(pads allowed)
				(copperpour not_allowed)
				(footprints allowed)
			)
			(placement
				(enabled no)
				(sheetname "")
			)
			(fill
				(thermal_gap 0.5)
				(thermal_bridge_width 0.5)
				(island_removal_mode 0)
			)
			(polygon
				(pts
					(arc
						(start 338.045044 -58.38444)
						(mid 338.008813 -58.326581)
						(end 337.951064 -58.290206)
					)
					(arc
						(start 337.951064 -58.18505)
						(mid 338.080785 -58.254719)
						(end 338.150454 -58.38444)
					)
				)
			)
		)
		(zone
			(layer "F.Cu")
			(hatch none 0.5)
			(connect_pads
				(clearance 0)
			)
			(min_thickness 0.25)
			(keepout
				(tracks not_allowed)
				(vias allowed)
				(pads allowed)
				(copperpour not_allowed)
				(footprints allowed)
			)
			(placement
				(enabled no)
				(sheetname "")
			)
			(fill
				(thermal_gap 0.5)
				(thermal_bridge_width 0.5)
				(island_removal_mode 0)
			)
			(polygon
				(pts
					(arc
						(start 338.045298 -57.554368)
						(mid 338.008927 -57.496505)
						(end 337.951064 -57.460134)
					)
					(arc
						(start 337.951064 -57.354978)
						(mid 338.080785 -57.424647)
						(end 338.150454 -57.554368)
					)
				)
			)
		)
		(zone
			(layer "F.Cu")
			(hatch none 0.5)
			(connect_pads
				(clearance 0)
			)
			(min_thickness 0.25)
			(keepout
				(tracks not_allowed)
				(vias allowed)
				(pads allowed)
				(copperpour not_allowed)
				(footprints allowed)
			)
			(placement
				(enabled no)
				(sheetname "")
			)
			(fill
				(thermal_gap 0.5)
				(thermal_bridge_width 0.5)
				(island_removal_mode 0)
			)
			(polygon
				(pts
					(arc
						(start 338.045298 -39.244524)
						(mid 338.008927 -39.186661)
						(end 337.951064 -39.15029)
					)
					(arc
						(start 337.951064 -39.045134)
						(mid 338.080785 -39.114803)
						(end 338.150454 -39.244524)
					)
				)
			)
		)
		(zone
			(layer "F.Cu")
			(hatch none 0.5)
			(connect_pads
				(clearance 0)
			)
			(min_thickness 0.25)
			(keepout
				(tracks not_allowed)
				(vias allowed)
				(pads allowed)
				(copperpour not_allowed)
				(footprints allowed)
			)
			(placement
				(enabled no)
				(sheetname "")
			)
			(fill
				(thermal_gap 0.5)
				(thermal_bridge_width 0.5)
				(island_removal_mode 0)
			)
			(polygon
				(pts
					(arc
						(start 338.045298 -38.414452)
						(mid 338.008927 -38.356589)
						(end 337.951064 -38.320218)
					)
					(arc
						(start 337.951064 -38.215062)
						(mid 338.080785 -38.284731)
						(end 338.150454 -38.414452)
					)
				)
			)
		)
		(zone
			(layer "F.Cu")
			(hatch none 0.5)
			(connect_pads
				(clearance 0)
			)
			(min_thickness 0.25)
			(keepout
				(tracks not_allowed)
				(vias allowed)
				(pads allowed)
				(copperpour not_allowed)
				(footprints allowed)
			)
			(placement
				(enabled no)
				(sheetname "")
			)
			(fill
				(thermal_gap 0.5)
				(thermal_bridge_width 0.5)
				(island_removal_mode 0)
			)
			(polygon
				(pts
					(arc
						(start 338.255356 -58.901076)
						(mid 338.291727 -58.958939)
						(end 338.34959 -58.99531)
					)
					(arc
						(start 338.34959 -59.100466)
						(mid 338.219869 -59.030797)
						(end 338.1502 -58.901076)
					)
				)
			)
		)
		(zone
			(layer "F.Cu")
			(hatch none 0.5)
			(connect_pads
				(clearance 0)
			)
			(min_thickness 0.25)
			(keepout
				(tracks not_allowed)
				(vias allowed)
				(pads allowed)
				(copperpour not_allowed)
				(footprints allowed)
			)
			(placement
				(enabled no)
				(sheetname "")
			)
			(fill
				(thermal_gap 0.5)
				(thermal_bridge_width 0.5)
				(island_removal_mode 0)
			)
			(polygon
				(pts
					(arc
						(start 338.255356 -58.071004)
						(mid 338.291727 -58.128867)
						(end 338.34959 -58.165238)
					)
					(arc
						(start 338.34959 -58.270394)
						(mid 338.219869 -58.200725)
						(end 338.1502 -58.071004)
					)
				)
			)
		)
		(zone
			(layer "F.Cu")
			(hatch none 0.5)
			(connect_pads
				(clearance 0)
			)
			(min_thickness 0.25)
			(keepout
				(tracks not_allowed)
				(vias allowed)
				(pads allowed)
				(copperpour not_allowed)
				(footprints allowed)
			)
			(placement
				(enabled no)
				(sheetname "")
			)
			(fill
				(thermal_gap 0.5)
				(thermal_bridge_width 0.5)
				(island_removal_mode 0)
			)
			(polygon
				(pts
					(arc
						(start 338.255356 -38.931088)
						(mid 338.291727 -38.988951)
						(end 338.34959 -39.025322)
					)
					(arc
						(start 338.34959 -39.130478)
						(mid 338.219869 -39.060809)
						(end 338.1502 -38.931088)
					)
				)
			)
		)
		(zone
			(layer "F.Cu")
			(hatch none 0.5)
			(connect_pads
				(clearance 0)
			)
			(min_thickness 0.25)
			(keepout
				(tracks not_allowed)
				(vias allowed)
				(pads allowed)
				(copperpour not_allowed)
				(footprints allowed)
			)
			(placement
				(enabled no)
				(sheetname "")
			)
			(fill
				(thermal_gap 0.5)
				(thermal_bridge_width 0.5)
				(island_removal_mode 0)
			)
			(polygon
				(pts
					(arc
						(start 338.255356 -38.101016)
						(mid 338.291727 -38.158879)
						(end 338.34959 -38.19525)
					)
					(arc
						(start 338.34959 -38.300406)
						(mid 338.219869 -38.230737)
						(end 338.1502 -38.101016)
					)
				)
			)
		)
		(zone
			(layer "F.Cu")
			(hatch none 0.5)
			(connect_pads
				(clearance 0)
			)
			(min_thickness 0.25)
			(keepout
				(tracks not_allowed)
				(vias allowed)
				(pads allowed)
				(copperpour not_allowed)
				(footprints allowed)
			)
			(placement
				(enabled no)
				(sheetname "")
			)
			(fill
				(thermal_gap 0.5)
				(thermal_bridge_width 0.5)
				(island_removal_mode 0)
			)
			(polygon
				(pts
					(arc
						(start 338.34959 -58.705242)
						(mid 338.291727 -58.741613)
						(end 338.255356 -58.799476)
					)
					(arc
						(start 338.1502 -58.799476)
						(mid 338.219869 -58.669755)
						(end 338.34959 -58.600086)
					)
				)
			)
		)
		(zone
			(layer "F.Cu")
			(hatch none 0.5)
			(connect_pads
				(clearance 0)
			)
			(min_thickness 0.25)
			(keepout
				(tracks not_allowed)
				(vias allowed)
				(pads allowed)
				(copperpour not_allowed)
				(footprints allowed)
			)
			(placement
				(enabled no)
				(sheetname "")
			)
			(fill
				(thermal_gap 0.5)
				(thermal_bridge_width 0.5)
				(island_removal_mode 0)
			)
			(polygon
				(pts
					(arc
						(start 338.34959 -57.87517)
						(mid 338.291727 -57.911541)
						(end 338.255356 -57.969404)
					)
					(arc
						(start 338.1502 -57.969404)
						(mid 338.219869 -57.839683)
						(end 338.34959 -57.770014)
					)
				)
			)
		)
		(zone
			(layer "F.Cu")
			(hatch none 0.5)
			(connect_pads
				(clearance 0)
			)
			(min_thickness 0.25)
			(keepout
				(tracks not_allowed)
				(vias allowed)
				(pads allowed)
				(copperpour not_allowed)
				(footprints allowed)
			)
			(placement
				(enabled no)
				(sheetname "")
			)
			(fill
				(thermal_gap 0.5)
				(thermal_bridge_width 0.5)
				(island_removal_mode 0)
			)
			(polygon
				(pts
					(arc
						(start 338.34959 -38.735254)
						(mid 338.291727 -38.771625)
						(end 338.255356 -38.829488)
					)
					(arc
						(start 338.1502 -38.829488)
						(mid 338.219869 -38.699767)
						(end 338.34959 -38.630098)
					)
				)
			)
		)
		(zone
			(layer "F.Cu")
			(hatch none 0.5)
			(connect_pads
				(clearance 0)
			)
			(min_thickness 0.25)
			(keepout
				(tracks not_allowed)
				(vias allowed)
				(pads allowed)
				(copperpour not_allowed)
				(footprints allowed)
			)
			(placement
				(enabled no)
				(sheetname "")
			)
			(fill
				(thermal_gap 0.5)
				(thermal_bridge_width 0.5)
				(island_removal_mode 0)
			)
			(polygon
				(pts
					(arc
						(start 338.34959 -37.905182)
						(mid 338.291727 -37.941553)
						(end 338.255356 -37.999416)
					)
					(arc
						(start 338.1502 -37.999416)
						(mid 338.219869 -37.869695)
						(end 338.34959 -37.800026)
					)
				)
			)
		)
		(zone
			(layer "F.Cu")
			(hatch none 0.5)
			(connect_pads
				(clearance 0)
			)
			(min_thickness 0.25)
			(keepout
				(tracks not_allowed)
				(vias allowed)
				(pads allowed)
				(copperpour not_allowed)
				(footprints allowed)
			)
			(placement
				(enabled no)
				(sheetname "")
			)
			(fill
				(thermal_gap 0.5)
				(thermal_bridge_width 0.5)
				(island_removal_mode 0)
			)
			(polygon
				(pts
					(arc
						(start 338.45119 -58.99531)
						(mid 338.509053 -58.958939)
						(end 338.545424 -58.901076)
					)
					(arc
						(start 338.65058 -58.901076)
						(mid 338.580911 -59.030797)
						(end 338.45119 -59.100466)
					)
				)
			)
		)
		(zone
			(layer "F.Cu")
			(hatch none 0.5)
			(connect_pads
				(clearance 0)
			)
			(min_thickness 0.25)
			(keepout
				(tracks not_allowed)
				(vias allowed)
				(pads allowed)
				(copperpour not_allowed)
				(footprints allowed)
			)
			(placement
				(enabled no)
				(sheetname "")
			)
			(fill
				(thermal_gap 0.5)
				(thermal_bridge_width 0.5)
				(island_removal_mode 0)
			)
			(polygon
				(pts
					(arc
						(start 338.45119 -58.165238)
						(mid 338.509053 -58.128867)
						(end 338.545424 -58.071004)
					)
					(arc
						(start 338.65058 -58.071004)
						(mid 338.580911 -58.200725)
						(end 338.45119 -58.270394)
					)
				)
			)
		)
		(zone
			(layer "F.Cu")
			(hatch none 0.5)
			(connect_pads
				(clearance 0)
			)
			(min_thickness 0.25)
			(keepout
				(tracks not_allowed)
				(vias allowed)
				(pads allowed)
				(copperpour not_allowed)
				(footprints allowed)
			)
			(placement
				(enabled no)
				(sheetname "")
			)
			(fill
				(thermal_gap 0.5)
				(thermal_bridge_width 0.5)
				(island_removal_mode 0)
			)
			(polygon
				(pts
					(arc
						(start 338.45119 -39.025322)
						(mid 338.509053 -38.988951)
						(end 338.545424 -38.931088)
					)
					(arc
						(start 338.65058 -38.931088)
						(mid 338.580911 -39.060809)
						(end 338.45119 -39.130478)
					)
				)
			)
		)
		(zone
			(layer "F.Cu")
			(hatch none 0.5)
			(connect_pads
				(clearance 0)
			)
			(min_thickness 0.25)
			(keepout
				(tracks not_allowed)
				(vias allowed)
				(pads allowed)
				(copperpour not_allowed)
				(footprints allowed)
			)
			(placement
				(enabled no)
				(sheetname "")
			)
			(fill
				(thermal_gap 0.5)
				(thermal_bridge_width 0.5)
				(island_removal_mode 0)
			)
			(polygon
				(pts
					(arc
						(start 338.45119 -38.19525)
						(mid 338.509053 -38.158879)
						(end 338.545424 -38.101016)
					)
					(arc
						(start 338.65058 -38.101016)
						(mid 338.580911 -38.230737)
						(end 338.45119 -38.300406)
					)
				)
			)
		)
		(zone
			(layer "F.Cu")
			(hatch none 0.5)
			(connect_pads
				(clearance 0)
			)
			(min_thickness 0.25)
			(keepout
				(tracks not_allowed)
				(vias allowed)
				(pads allowed)
				(copperpour not_allowed)
				(footprints allowed)
			)
			(placement
				(enabled no)
				(sheetname "")
			)
			(fill
				(thermal_gap 0.5)
				(thermal_bridge_width 0.5)
				(island_removal_mode 0)
			)
			(polygon
				(pts
					(arc
						(start 338.545424 -58.799476)
						(mid 338.509053 -58.741613)
						(end 338.45119 -58.705242)
					)
					(arc
						(start 338.45119 -58.600086)
						(mid 338.580911 -58.669755)
						(end 338.65058 -58.799476)
					)
				)
			)
		)
		(zone
			(layer "F.Cu")
			(hatch none 0.5)
			(connect_pads
				(clearance 0)
			)
			(min_thickness 0.25)
			(keepout
				(tracks not_allowed)
				(vias allowed)
				(pads allowed)
				(copperpour not_allowed)
				(footprints allowed)
			)
			(placement
				(enabled no)
				(sheetname "")
			)
			(fill
				(thermal_gap 0.5)
				(thermal_bridge_width 0.5)
				(island_removal_mode 0)
			)
			(polygon
				(pts
					(arc
						(start 338.545424 -57.969404)
						(mid 338.509053 -57.911541)
						(end 338.45119 -57.87517)
					)
					(arc
						(start 338.45119 -57.770014)
						(mid 338.580911 -57.839683)
						(end 338.65058 -57.969404)
					)
				)
			)
		)
		(zone
			(layer "F.Cu")
			(hatch none 0.5)
			(connect_pads
				(clearance 0)
			)
			(min_thickness 0.25)
			(keepout
				(tracks not_allowed)
				(vias allowed)
				(pads allowed)
				(copperpour not_allowed)
				(footprints allowed)
			)
			(placement
				(enabled no)
				(sheetname "")
			)
			(fill
				(thermal_gap 0.5)
				(thermal_bridge_width 0.5)
				(island_removal_mode 0)
			)
			(polygon
				(pts
					(arc
						(start 338.545424 -38.829488)
						(mid 338.509053 -38.771625)
						(end 338.45119 -38.735254)
					)
					(arc
						(start 338.45119 -38.630098)
						(mid 338.580911 -38.699767)
						(end 338.65058 -38.829488)
					)
				)
			)
		)
		(zone
			(layer "F.Cu")
			(hatch none 0.5)
			(connect_pads
				(clearance 0)
			)
			(min_thickness 0.25)
			(keepout
				(tracks not_allowed)
				(vias allowed)
				(pads allowed)
				(copperpour not_allowed)
				(footprints allowed)
			)
			(placement
				(enabled no)
				(sheetname "")
			)
			(fill
				(thermal_gap 0.5)
				(thermal_bridge_width 0.5)
				(island_removal_mode 0)
			)
			(polygon
				(pts
					(arc
						(start 338.545424 -37.999416)
						(mid 338.509053 -37.941553)
						(end 338.45119 -37.905182)
					)
					(arc
						(start 338.45119 -37.800026)
						(mid 338.580911 -37.869695)
						(end 338.65058 -37.999416)
					)
				)
			)
		)
		(zone
			(layer "F.Cu")
			(hatch none 0.5)
			(connect_pads
				(clearance 0)
			)
			(min_thickness 0.25)
			(keepout
				(tracks not_allowed)
				(vias allowed)
				(pads allowed)
				(copperpour not_allowed)
				(footprints allowed)
			)
			(placement
				(enabled no)
				(sheetname "")
			)
			(fill
				(thermal_gap 0.5)
				(thermal_bridge_width 0.5)
				(island_removal_mode 0)
			)
			(polygon
				(pts
					(arc
						(start 338.755736 -58.48604)
						(mid 338.792162 -58.543739)
						(end 338.84997 -58.58002)
					)
					(arc
						(start 338.84997 -58.68543)
						(mid 338.720249 -58.615761)
						(end 338.65058 -58.48604)
					)
				)
			)
		)
		(zone
			(layer "F.Cu")
			(hatch none 0.5)
			(connect_pads
				(clearance 0)
			)
			(min_thickness 0.25)
			(keepout
				(tracks not_allowed)
				(vias allowed)
				(pads allowed)
				(copperpour not_allowed)
				(footprints allowed)
			)
			(placement
				(enabled no)
				(sheetname "")
			)
			(fill
				(thermal_gap 0.5)
				(thermal_bridge_width 0.5)
				(island_removal_mode 0)
			)
			(polygon
				(pts
					(arc
						(start 338.755736 -57.655968)
						(mid 338.792107 -57.713831)
						(end 338.84997 -57.750202)
					)
					(arc
						(start 338.84997 -57.855358)
						(mid 338.720249 -57.785689)
						(end 338.65058 -57.655968)
					)
				)
			)
		)
		(zone
			(layer "F.Cu")
			(hatch none 0.5)
			(connect_pads
				(clearance 0)
			)
			(min_thickness 0.25)
			(keepout
				(tracks not_allowed)
				(vias allowed)
				(pads allowed)
				(copperpour not_allowed)
				(footprints allowed)
			)
			(placement
				(enabled no)
				(sheetname "")
			)
			(fill
				(thermal_gap 0.5)
				(thermal_bridge_width 0.5)
				(island_removal_mode 0)
			)
			(polygon
				(pts
					(arc
						(start 338.755736 -39.346124)
						(mid 338.792107 -39.403987)
						(end 338.84997 -39.440358)
					)
					(arc
						(start 338.84997 -39.545514)
						(mid 338.720249 -39.475845)
						(end 338.65058 -39.346124)
					)
				)
			)
		)
		(zone
			(layer "F.Cu")
			(hatch none 0.5)
			(connect_pads
				(clearance 0)
			)
			(min_thickness 0.25)
			(keepout
				(tracks not_allowed)
				(vias allowed)
				(pads allowed)
				(copperpour not_allowed)
				(footprints allowed)
			)
			(placement
				(enabled no)
				(sheetname "")
			)
			(fill
				(thermal_gap 0.5)
				(thermal_bridge_width 0.5)
				(island_removal_mode 0)
			)
			(polygon
				(pts
					(arc
						(start 338.755736 -38.516052)
						(mid 338.792107 -38.573915)
						(end 338.84997 -38.610286)
					)
					(arc
						(start 338.84997 -38.715442)
						(mid 338.720249 -38.645773)
						(end 338.65058 -38.516052)
					)
				)
			)
		)
		(zone
			(layer "F.Cu")
			(hatch none 0.5)
			(connect_pads
				(clearance 0)
			)
			(min_thickness 0.25)
			(keepout
				(tracks not_allowed)
				(vias allowed)
				(pads allowed)
				(copperpour not_allowed)
				(footprints allowed)
			)
			(placement
				(enabled no)
				(sheetname "")
			)
			(fill
				(thermal_gap 0.5)
				(thermal_bridge_width 0.5)
				(island_removal_mode 0)
			)
			(polygon
				(pts
					(arc
						(start 338.84997 -58.290206)
						(mid 338.792107 -58.326577)
						(end 338.755736 -58.38444)
					)
					(arc
						(start 338.65058 -58.38444)
						(mid 338.720249 -58.254719)
						(end 338.84997 -58.18505)
					)
				)
			)
		)
		(zone
			(layer "F.Cu")
			(hatch none 0.5)
			(connect_pads
				(clearance 0)
			)
			(min_thickness 0.25)
			(keepout
				(tracks not_allowed)
				(vias allowed)
				(pads allowed)
				(copperpour not_allowed)
				(footprints allowed)
			)
			(placement
				(enabled no)
				(sheetname "")
			)
			(fill
				(thermal_gap 0.5)
				(thermal_bridge_width 0.5)
				(island_removal_mode 0)
			)
			(polygon
				(pts
					(arc
						(start 338.84997 -57.460134)
						(mid 338.792107 -57.496505)
						(end 338.755736 -57.554368)
					)
					(arc
						(start 338.65058 -57.554368)
						(mid 338.720249 -57.424647)
						(end 338.84997 -57.354978)
					)
				)
			)
		)
		(zone
			(layer "F.Cu")
			(hatch none 0.5)
			(connect_pads
				(clearance 0)
			)
			(min_thickness 0.25)
			(keepout
				(tracks not_allowed)
				(vias allowed)
				(pads allowed)
				(copperpour not_allowed)
				(footprints allowed)
			)
			(placement
				(enabled no)
				(sheetname "")
			)
			(fill
				(thermal_gap 0.5)
				(thermal_bridge_width 0.5)
				(island_removal_mode 0)
			)
			(polygon
				(pts
					(arc
						(start 338.84997 -39.15029)
						(mid 338.792107 -39.186661)
						(end 338.755736 -39.244524)
					)
					(arc
						(start 338.65058 -39.244524)
						(mid 338.720249 -39.114803)
						(end 338.84997 -39.045134)
					)
				)
			)
		)
		(zone
			(layer "F.Cu")
			(hatch none 0.5)
			(connect_pads
				(clearance 0)
			)
			(min_thickness 0.25)
			(keepout
				(tracks not_allowed)
				(vias allowed)
				(pads allowed)
				(copperpour not_allowed)
				(footprints allowed)
			)
			(placement
				(enabled no)
				(sheetname "")
			)
			(fill
				(thermal_gap 0.5)
				(thermal_bridge_width 0.5)
				(island_removal_mode 0)
			)
			(polygon
				(pts
					(arc
						(start 338.84997 -38.320218)
						(mid 338.792107 -38.356589)
						(end 338.755736 -38.414452)
					)
					(arc
						(start 338.65058 -38.414452)
						(mid 338.720249 -38.284731)
						(end 338.84997 -38.215062)
					)
				)
			)
		)
		(zone
			(layer "F.Cu")
			(hatch none 0.5)
			(connect_pads
				(clearance 0)
			)
			(min_thickness 0.25)
			(keepout
				(tracks not_allowed)
				(vias allowed)
				(pads allowed)
				(copperpour not_allowed)
				(footprints allowed)
			)
			(placement
				(enabled no)
				(sheetname "")
			)
			(fill
				(thermal_gap 0.5)
				(thermal_bridge_width 0.5)
				(island_removal_mode 0)
			)
			(polygon
				(pts
					(arc
						(start 338.95157 -58.58002)
						(mid 339.009264 -58.543734)
						(end 339.04555 -58.48604)
					)
					(arc
						(start 339.15096 -58.48604)
						(mid 339.081291 -58.615761)
						(end 338.95157 -58.68543)
					)
				)
			)
		)
		(zone
			(layer "F.Cu")
			(hatch none 0.5)
			(connect_pads
				(clearance 0)
			)
			(min_thickness 0.25)
			(keepout
				(tracks not_allowed)
				(vias allowed)
				(pads allowed)
				(copperpour not_allowed)
				(footprints allowed)
			)
			(placement
				(enabled no)
				(sheetname "")
			)
			(fill
				(thermal_gap 0.5)
				(thermal_bridge_width 0.5)
				(island_removal_mode 0)
			)
			(polygon
				(pts
					(arc
						(start 338.95157 -57.750202)
						(mid 339.009269 -57.713776)
						(end 339.04555 -57.655968)
					)
					(arc
						(start 339.15096 -57.655968)
						(mid 339.081291 -57.785689)
						(end 338.95157 -57.855358)
					)
				)
			)
		)
		(zone
			(layer "F.Cu")
			(hatch none 0.5)
			(connect_pads
				(clearance 0)
			)
			(min_thickness 0.25)
			(keepout
				(tracks not_allowed)
				(vias allowed)
				(pads allowed)
				(copperpour not_allowed)
				(footprints allowed)
			)
			(placement
				(enabled no)
				(sheetname "")
			)
			(fill
				(thermal_gap 0.5)
				(thermal_bridge_width 0.5)
				(island_removal_mode 0)
			)
			(polygon
				(pts
					(arc
						(start 338.95157 -39.440358)
						(mid 339.009433 -39.403987)
						(end 339.045804 -39.346124)
					)
					(arc
						(start 339.15096 -39.346124)
						(mid 339.081291 -39.475845)
						(end 338.95157 -39.545514)
					)
				)
			)
		)
		(zone
			(layer "F.Cu")
			(hatch none 0.5)
			(connect_pads
				(clearance 0)
			)
			(min_thickness 0.25)
			(keepout
				(tracks not_allowed)
				(vias allowed)
				(pads allowed)
				(copperpour not_allowed)
				(footprints allowed)
			)
			(placement
				(enabled no)
				(sheetname "")
			)
			(fill
				(thermal_gap 0.5)
				(thermal_bridge_width 0.5)
				(island_removal_mode 0)
			)
			(polygon
				(pts
					(arc
						(start 338.95157 -38.610286)
						(mid 339.009433 -38.573915)
						(end 339.045804 -38.516052)
					)
					(arc
						(start 339.15096 -38.516052)
						(mid 339.081291 -38.645773)
						(end 338.95157 -38.715442)
					)
				)
			)
		)
		(zone
			(layer "F.Cu")
			(hatch none 0.5)
			(connect_pads
				(clearance 0)
			)
			(min_thickness 0.25)
			(keepout
				(tracks not_allowed)
				(vias allowed)
				(pads allowed)
				(copperpour not_allowed)
				(footprints allowed)
			)
			(placement
				(enabled no)
				(sheetname "")
			)
			(fill
				(thermal_gap 0.5)
				(thermal_bridge_width 0.5)
				(island_removal_mode 0)
			)
			(polygon
				(pts
					(arc
						(start 339.04555 -58.38444)
						(mid 339.009319 -58.326581)
						(end 338.95157 -58.290206)
					)
					(arc
						(start 338.95157 -58.18505)
						(mid 339.081291 -58.254719)
						(end 339.15096 -58.38444)
					)
				)
			)
		)
		(zone
			(layer "F.Cu")
			(hatch none 0.5)
			(connect_pads
				(clearance 0)
			)
			(min_thickness 0.25)
			(keepout
				(tracks not_allowed)
				(vias allowed)
				(pads allowed)
				(copperpour not_allowed)
				(footprints allowed)
			)
			(placement
				(enabled no)
				(sheetname "")
			)
			(fill
				(thermal_gap 0.5)
				(thermal_bridge_width 0.5)
				(island_removal_mode 0)
			)
			(polygon
				(pts
					(arc
						(start 339.04555 -57.554368)
						(mid 339.009319 -57.496509)
						(end 338.95157 -57.460134)
					)
					(arc
						(start 338.95157 -57.354978)
						(mid 339.081291 -57.424647)
						(end 339.15096 -57.554368)
					)
				)
			)
		)
		(zone
			(layer "F.Cu")
			(hatch none 0.5)
			(connect_pads
				(clearance 0)
			)
			(min_thickness 0.25)
			(keepout
				(tracks not_allowed)
				(vias allowed)
				(pads allowed)
				(copperpour not_allowed)
				(footprints allowed)
			)
			(placement
				(enabled no)
				(sheetname "")
			)
			(fill
				(thermal_gap 0.5)
				(thermal_bridge_width 0.5)
				(island_removal_mode 0)
			)
			(polygon
				(pts
					(arc
						(start 339.045804 -39.244524)
						(mid 339.009433 -39.186661)
						(end 338.95157 -39.15029)
					)
					(arc
						(start 338.95157 -39.045134)
						(mid 339.081291 -39.114803)
						(end 339.15096 -39.244524)
					)
				)
			)
		)
		(zone
			(layer "F.Cu")
			(hatch none 0.5)
			(connect_pads
				(clearance 0)
			)
			(min_thickness 0.25)
			(keepout
				(tracks not_allowed)
				(vias allowed)
				(pads allowed)
				(copperpour not_allowed)
				(footprints allowed)
			)
			(placement
				(enabled no)
				(sheetname "")
			)
			(fill
				(thermal_gap 0.5)
				(thermal_bridge_width 0.5)
				(island_removal_mode 0)
			)
			(polygon
				(pts
					(arc
						(start 339.045804 -38.414452)
						(mid 339.009433 -38.356589)
						(end 338.95157 -38.320218)
					)
					(arc
						(start 338.95157 -38.215062)
						(mid 339.081291 -38.284731)
						(end 339.15096 -38.414452)
					)
				)
			)
		)
		(zone
			(layer "F.Cu")
			(hatch none 0.5)
			(connect_pads
				(clearance 0)
			)
			(min_thickness 0.25)
			(keepout
				(tracks not_allowed)
				(vias allowed)
				(pads allowed)
				(copperpour not_allowed)
				(footprints allowed)
			)
			(placement
				(enabled no)
				(sheetname "")
			)
			(fill
				(thermal_gap 0.5)
				(thermal_bridge_width 0.5)
				(island_removal_mode 0)
			)
			(polygon
				(pts
					(arc
						(start 339.255862 -58.901076)
						(mid 339.292233 -58.958939)
						(end 339.350096 -58.99531)
					)
					(arc
						(start 339.350096 -59.100466)
						(mid 339.220375 -59.030797)
						(end 339.150706 -58.901076)
					)
				)
			)
		)
		(zone
			(layer "F.Cu")
			(hatch none 0.5)
			(connect_pads
				(clearance 0)
			)
			(min_thickness 0.25)
			(keepout
				(tracks not_allowed)
				(vias allowed)
				(pads allowed)
				(copperpour not_allowed)
				(footprints allowed)
			)
			(placement
				(enabled no)
				(sheetname "")
			)
			(fill
				(thermal_gap 0.5)
				(thermal_bridge_width 0.5)
				(island_removal_mode 0)
			)
			(polygon
				(pts
					(arc
						(start 339.255862 -58.071004)
						(mid 339.292233 -58.128867)
						(end 339.350096 -58.165238)
					)
					(arc
						(start 339.350096 -58.270394)
						(mid 339.220375 -58.200725)
						(end 339.150706 -58.071004)
					)
				)
			)
		)
		(zone
			(layer "F.Cu")
			(hatch none 0.5)
			(connect_pads
				(clearance 0)
			)
			(min_thickness 0.25)
			(keepout
				(tracks not_allowed)
				(vias allowed)
				(pads allowed)
				(copperpour not_allowed)
				(footprints allowed)
			)
			(placement
				(enabled no)
				(sheetname "")
			)
			(fill
				(thermal_gap 0.5)
				(thermal_bridge_width 0.5)
				(island_removal_mode 0)
			)
			(polygon
				(pts
					(arc
						(start 339.255862 -38.931088)
						(mid 339.292233 -38.988951)
						(end 339.350096 -39.025322)
					)
					(arc
						(start 339.350096 -39.130478)
						(mid 339.220375 -39.060809)
						(end 339.150706 -38.931088)
					)
				)
			)
		)
		(zone
			(layer "F.Cu")
			(hatch none 0.5)
			(connect_pads
				(clearance 0)
			)
			(min_thickness 0.25)
			(keepout
				(tracks not_allowed)
				(vias allowed)
				(pads allowed)
				(copperpour not_allowed)
				(footprints allowed)
			)
			(placement
				(enabled no)
				(sheetname "")
			)
			(fill
				(thermal_gap 0.5)
				(thermal_bridge_width 0.5)
				(island_removal_mode 0)
			)
			(polygon
				(pts
					(arc
						(start 339.255862 -38.101016)
						(mid 339.292233 -38.158879)
						(end 339.350096 -38.19525)
					)
					(arc
						(start 339.350096 -38.300406)
						(mid 339.220375 -38.230737)
						(end 339.150706 -38.101016)
					)
				)
			)
		)
		(zone
			(layer "F.Cu")
			(hatch none 0.5)
			(connect_pads
				(clearance 0)
			)
			(min_thickness 0.25)
			(keepout
				(tracks not_allowed)
				(vias allowed)
				(pads allowed)
				(copperpour not_allowed)
				(footprints allowed)
			)
			(placement
				(enabled no)
				(sheetname "")
			)
			(fill
				(thermal_gap 0.5)
				(thermal_bridge_width 0.5)
				(island_removal_mode 0)
			)
			(polygon
				(pts
					(arc
						(start 339.350096 -58.705242)
						(mid 339.292233 -58.741613)
						(end 339.255862 -58.799476)
					)
					(arc
						(start 339.150706 -58.799476)
						(mid 339.220375 -58.669755)
						(end 339.350096 -58.600086)
					)
				)
			)
		)
		(zone
			(layer "F.Cu")
			(hatch none 0.5)
			(connect_pads
				(clearance 0)
			)
			(min_thickness 0.25)
			(keepout
				(tracks not_allowed)
				(vias allowed)
				(pads allowed)
				(copperpour not_allowed)
				(footprints allowed)
			)
			(placement
				(enabled no)
				(sheetname "")
			)
			(fill
				(thermal_gap 0.5)
				(thermal_bridge_width 0.5)
				(island_removal_mode 0)
			)
			(polygon
				(pts
					(arc
						(start 339.350096 -57.87517)
						(mid 339.292233 -57.911541)
						(end 339.255862 -57.969404)
					)
					(arc
						(start 339.150706 -57.969404)
						(mid 339.220375 -57.839683)
						(end 339.350096 -57.770014)
					)
				)
			)
		)
		(zone
			(layer "F.Cu")
			(hatch none 0.5)
			(connect_pads
				(clearance 0)
			)
			(min_thickness 0.25)
			(keepout
				(tracks not_allowed)
				(vias allowed)
				(pads allowed)
				(copperpour not_allowed)
				(footprints allowed)
			)
			(placement
				(enabled no)
				(sheetname "")
			)
			(fill
				(thermal_gap 0.5)
				(thermal_bridge_width 0.5)
				(island_removal_mode 0)
			)
			(polygon
				(pts
					(arc
						(start 339.350096 -38.735254)
						(mid 339.292233 -38.771625)
						(end 339.255862 -38.829488)
					)
					(arc
						(start 339.150706 -38.829488)
						(mid 339.220375 -38.699767)
						(end 339.350096 -38.630098)
					)
				)
			)
		)
		(zone
			(layer "F.Cu")
			(hatch none 0.5)
			(connect_pads
				(clearance 0)
			)
			(min_thickness 0.25)
			(keepout
				(tracks not_allowed)
				(vias allowed)
				(pads allowed)
				(copperpour not_allowed)
				(footprints allowed)
			)
			(placement
				(enabled no)
				(sheetname "")
			)
			(fill
				(thermal_gap 0.5)
				(thermal_bridge_width 0.5)
				(island_removal_mode 0)
			)
			(polygon
				(pts
					(arc
						(start 339.350096 -37.905182)
						(mid 339.292233 -37.941553)
						(end 339.255862 -37.999416)
					)
					(arc
						(start 339.150706 -37.999416)
						(mid 339.220375 -37.869695)
						(end 339.350096 -37.800026)
					)
				)
			)
		)
		(zone
			(layer "F.Cu")
			(hatch none 0.5)
			(connect_pads
				(clearance 0)
			)
			(min_thickness 0.25)
			(keepout
				(tracks not_allowed)
				(vias allowed)
				(pads allowed)
				(copperpour not_allowed)
				(footprints allowed)
			)
			(placement
				(enabled no)
				(sheetname "")
			)
			(fill
				(thermal_gap 0.5)
				(thermal_bridge_width 0.5)
				(island_removal_mode 0)
			)
			(polygon
				(pts
					(arc
						(start 339.451696 -58.99531)
						(mid 339.509559 -58.958939)
						(end 339.54593 -58.901076)
					)
					(arc
						(start 339.651086 -58.901076)
						(mid 339.581417 -59.030797)
						(end 339.451696 -59.100466)
					)
				)
			)
		)
		(zone
			(layer "F.Cu")
			(hatch none 0.5)
			(connect_pads
				(clearance 0)
			)
			(min_thickness 0.25)
			(keepout
				(tracks not_allowed)
				(vias allowed)
				(pads allowed)
				(copperpour not_allowed)
				(footprints allowed)
			)
			(placement
				(enabled no)
				(sheetname "")
			)
			(fill
				(thermal_gap 0.5)
				(thermal_bridge_width 0.5)
				(island_removal_mode 0)
			)
			(polygon
				(pts
					(arc
						(start 339.451696 -58.165238)
						(mid 339.509559 -58.128867)
						(end 339.54593 -58.071004)
					)
					(arc
						(start 339.651086 -58.071004)
						(mid 339.581417 -58.200725)
						(end 339.451696 -58.270394)
					)
				)
			)
		)
		(zone
			(layer "F.Cu")
			(hatch none 0.5)
			(connect_pads
				(clearance 0)
			)
			(min_thickness 0.25)
			(keepout
				(tracks not_allowed)
				(vias allowed)
				(pads allowed)
				(copperpour not_allowed)
				(footprints allowed)
			)
			(placement
				(enabled no)
				(sheetname "")
			)
			(fill
				(thermal_gap 0.5)
				(thermal_bridge_width 0.5)
				(island_removal_mode 0)
			)
			(polygon
				(pts
					(arc
						(start 339.451696 -39.025322)
						(mid 339.509559 -38.988951)
						(end 339.54593 -38.931088)
					)
					(arc
						(start 339.651086 -38.931088)
						(mid 339.581417 -39.060809)
						(end 339.451696 -39.130478)
					)
				)
			)
		)
		(zone
			(layer "F.Cu")
			(hatch none 0.5)
			(connect_pads
				(clearance 0)
			)
			(min_thickness 0.25)
			(keepout
				(tracks not_allowed)
				(vias allowed)
				(pads allowed)
				(copperpour not_allowed)
				(footprints allowed)
			)
			(placement
				(enabled no)
				(sheetname "")
			)
			(fill
				(thermal_gap 0.5)
				(thermal_bridge_width 0.5)
				(island_removal_mode 0)
			)
			(polygon
				(pts
					(arc
						(start 339.451696 -38.19525)
						(mid 339.509559 -38.158879)
						(end 339.54593 -38.101016)
					)
					(arc
						(start 339.651086 -38.101016)
						(mid 339.581417 -38.230737)
						(end 339.451696 -38.300406)
					)
				)
			)
		)
		(zone
			(layer "F.Cu")
			(hatch none 0.5)
			(connect_pads
				(clearance 0)
			)
			(min_thickness 0.25)
			(keepout
				(tracks not_allowed)
				(vias allowed)
				(pads allowed)
				(copperpour not_allowed)
				(footprints allowed)
			)
			(placement
				(enabled no)
				(sheetname "")
			)
			(fill
				(thermal_gap 0.5)
				(thermal_bridge_width 0.5)
				(island_removal_mode 0)
			)
			(polygon
				(pts
					(arc
						(start 339.54593 -58.799476)
						(mid 339.509559 -58.741613)
						(end 339.451696 -58.705242)
					)
					(arc
						(start 339.451696 -58.600086)
						(mid 339.581417 -58.669755)
						(end 339.651086 -58.799476)
					)
				)
			)
		)
		(zone
			(layer "F.Cu")
			(hatch none 0.5)
			(connect_pads
				(clearance 0)
			)
			(min_thickness 0.25)
			(keepout
				(tracks not_allowed)
				(vias allowed)
				(pads allowed)
				(copperpour not_allowed)
				(footprints allowed)
			)
			(placement
				(enabled no)
				(sheetname "")
			)
			(fill
				(thermal_gap 0.5)
				(thermal_bridge_width 0.5)
				(island_removal_mode 0)
			)
			(polygon
				(pts
					(arc
						(start 339.54593 -57.969404)
						(mid 339.509559 -57.911541)
						(end 339.451696 -57.87517)
					)
					(arc
						(start 339.451696 -57.770014)
						(mid 339.581417 -57.839683)
						(end 339.651086 -57.969404)
					)
				)
			)
		)
		(zone
			(layer "F.Cu")
			(hatch none 0.5)
			(connect_pads
				(clearance 0)
			)
			(min_thickness 0.25)
			(keepout
				(tracks not_allowed)
				(vias allowed)
				(pads allowed)
				(copperpour not_allowed)
				(footprints allowed)
			)
			(placement
				(enabled no)
				(sheetname "")
			)
			(fill
				(thermal_gap 0.5)
				(thermal_bridge_width 0.5)
				(island_removal_mode 0)
			)
			(polygon
				(pts
					(arc
						(start 339.54593 -38.829488)
						(mid 339.509559 -38.771625)
						(end 339.451696 -38.735254)
					)
					(arc
						(start 339.451696 -38.630098)
						(mid 339.581417 -38.699767)
						(end 339.651086 -38.829488)
					)
				)
			)
		)
		(zone
			(layer "F.Cu")
			(hatch none 0.5)
			(connect_pads
				(clearance 0)
			)
			(min_thickness 0.25)
			(keepout
				(tracks not_allowed)
				(vias allowed)
				(pads allowed)
				(copperpour not_allowed)
				(footprints allowed)
			)
			(placement
				(enabled no)
				(sheetname "")
			)
			(fill
				(thermal_gap 0.5)
				(thermal_bridge_width 0.5)
				(island_removal_mode 0)
			)
			(polygon
				(pts
					(arc
						(start 339.54593 -37.999416)
						(mid 339.509559 -37.941553)
						(end 339.451696 -37.905182)
					)
					(arc
						(start 339.451696 -37.800026)
						(mid 339.581417 -37.869695)
						(end 339.651086 -37.999416)
					)
				)
			)
		)
		(zone
			(layer "F.Cu")
			(hatch none 0.5)
			(connect_pads
				(clearance 0)
			)
			(min_thickness 0.25)
			(keepout
				(tracks not_allowed)
				(vias allowed)
				(pads allowed)
				(copperpour not_allowed)
				(footprints allowed)
			)
			(placement
				(enabled no)
				(sheetname "")
			)
			(fill
				(thermal_gap 0.5)
				(thermal_bridge_width 0.5)
				(island_removal_mode 0)
			)
			(polygon
				(pts
					(arc
						(start 339.756242 -58.48604)
						(mid 339.792668 -58.543739)
						(end 339.850476 -58.58002)
					)
					(arc
						(start 339.850476 -58.68543)
						(mid 339.720625 -58.615813)
						(end 339.650832 -58.48604)
					)
				)
			)
		)
		(zone
			(layer "F.Cu")
			(hatch none 0.5)
			(connect_pads
				(clearance 0)
			)
			(min_thickness 0.25)
			(keepout
				(tracks not_allowed)
				(vias allowed)
				(pads allowed)
				(copperpour not_allowed)
				(footprints allowed)
			)
			(placement
				(enabled no)
				(sheetname "")
			)
			(fill
				(thermal_gap 0.5)
				(thermal_bridge_width 0.5)
				(island_removal_mode 0)
			)
			(polygon
				(pts
					(arc
						(start 339.756242 -57.655968)
						(mid 339.792613 -57.713831)
						(end 339.850476 -57.750202)
					)
					(arc
						(start 339.850476 -57.855358)
						(mid 339.720625 -57.785741)
						(end 339.650832 -57.655968)
					)
				)
			)
		)
		(zone
			(layer "F.Cu")
			(hatch none 0.5)
			(connect_pads
				(clearance 0)
			)
			(min_thickness 0.25)
			(keepout
				(tracks not_allowed)
				(vias allowed)
				(pads allowed)
				(copperpour not_allowed)
				(footprints allowed)
			)
			(placement
				(enabled no)
				(sheetname "")
			)
			(fill
				(thermal_gap 0.5)
				(thermal_bridge_width 0.5)
				(island_removal_mode 0)
			)
			(polygon
				(pts
					(arc
						(start 339.756242 -39.346124)
						(mid 339.792613 -39.403987)
						(end 339.850476 -39.440358)
					)
					(arc
						(start 339.850476 -39.545514)
						(mid 339.720755 -39.475845)
						(end 339.651086 -39.346124)
					)
				)
			)
		)
		(zone
			(layer "F.Cu")
			(hatch none 0.5)
			(connect_pads
				(clearance 0)
			)
			(min_thickness 0.25)
			(keepout
				(tracks not_allowed)
				(vias allowed)
				(pads allowed)
				(copperpour not_allowed)
				(footprints allowed)
			)
			(placement
				(enabled no)
				(sheetname "")
			)
			(fill
				(thermal_gap 0.5)
				(thermal_bridge_width 0.5)
				(island_removal_mode 0)
			)
			(polygon
				(pts
					(arc
						(start 339.756242 -38.516052)
						(mid 339.792613 -38.573915)
						(end 339.850476 -38.610286)
					)
					(arc
						(start 339.850476 -38.715442)
						(mid 339.720755 -38.645773)
						(end 339.651086 -38.516052)
					)
				)
			)
		)
		(zone
			(layer "F.Cu")
			(hatch none 0.5)
			(connect_pads
				(clearance 0)
			)
			(min_thickness 0.25)
			(keepout
				(tracks not_allowed)
				(vias allowed)
				(pads allowed)
				(copperpour not_allowed)
				(footprints allowed)
			)
			(placement
				(enabled no)
				(sheetname "")
			)
			(fill
				(thermal_gap 0.5)
				(thermal_bridge_width 0.5)
				(island_removal_mode 0)
			)
			(polygon
				(pts
					(arc
						(start 339.850476 -58.290206)
						(mid 339.792613 -58.326577)
						(end 339.756242 -58.38444)
					)
					(arc
						(start 339.650832 -58.38444)
						(mid 339.720589 -58.254631)
						(end 339.850476 -58.18505)
					)
				)
			)
		)
		(zone
			(layer "F.Cu")
			(hatch none 0.5)
			(connect_pads
				(clearance 0)
			)
			(min_thickness 0.25)
			(keepout
				(tracks not_allowed)
				(vias allowed)
				(pads allowed)
				(copperpour not_allowed)
				(footprints allowed)
			)
			(placement
				(enabled no)
				(sheetname "")
			)
			(fill
				(thermal_gap 0.5)
				(thermal_bridge_width 0.5)
				(island_removal_mode 0)
			)
			(polygon
				(pts
					(arc
						(start 339.850476 -57.460134)
						(mid 339.792613 -57.496505)
						(end 339.756242 -57.554368)
					)
					(arc
						(start 339.650832 -57.554368)
						(mid 339.720589 -57.424559)
						(end 339.850476 -57.354978)
					)
				)
			)
		)
		(zone
			(layer "F.Cu")
			(hatch none 0.5)
			(connect_pads
				(clearance 0)
			)
			(min_thickness 0.25)
			(keepout
				(tracks not_allowed)
				(vias allowed)
				(pads allowed)
				(copperpour not_allowed)
				(footprints allowed)
			)
			(placement
				(enabled no)
				(sheetname "")
			)
			(fill
				(thermal_gap 0.5)
				(thermal_bridge_width 0.5)
				(island_removal_mode 0)
			)
			(polygon
				(pts
					(arc
						(start 339.850476 -39.15029)
						(mid 339.792613 -39.186661)
						(end 339.756242 -39.244524)
					)
					(arc
						(start 339.651086 -39.244524)
						(mid 339.720755 -39.114803)
						(end 339.850476 -39.045134)
					)
				)
			)
		)
		(zone
			(layer "F.Cu")
			(hatch none 0.5)
			(connect_pads
				(clearance 0)
			)
			(min_thickness 0.25)
			(keepout
				(tracks not_allowed)
				(vias allowed)
				(pads allowed)
				(copperpour not_allowed)
				(footprints allowed)
			)
			(placement
				(enabled no)
				(sheetname "")
			)
			(fill
				(thermal_gap 0.5)
				(thermal_bridge_width 0.5)
				(island_removal_mode 0)
			)
			(polygon
				(pts
					(arc
						(start 339.850476 -38.320218)
						(mid 339.792613 -38.356589)
						(end 339.756242 -38.414452)
					)
					(arc
						(start 339.651086 -38.414452)
						(mid 339.720755 -38.284731)
						(end 339.850476 -38.215062)
					)
				)
			)
		)
		(zone
			(layer "F.Cu")
			(hatch none 0.5)
			(connect_pads
				(clearance 0)
			)
			(min_thickness 0.25)
			(keepout
				(tracks not_allowed)
				(vias allowed)
				(pads allowed)
				(copperpour not_allowed)
				(footprints allowed)
			)
			(placement
				(enabled no)
				(sheetname "")
			)
			(fill
				(thermal_gap 0.5)
				(thermal_bridge_width 0.5)
				(island_removal_mode 0)
			)
			(polygon
				(pts
					(arc
						(start 339.952076 -58.58002)
						(mid 340.00977 -58.543734)
						(end 340.046056 -58.48604)
					)
					(arc
						(start 340.151466 -58.48604)
						(mid 340.081797 -58.615761)
						(end 339.952076 -58.68543)
					)
				)
			)
		)
		(zone
			(layer "F.Cu")
			(hatch none 0.5)
			(connect_pads
				(clearance 0)
			)
			(min_thickness 0.25)
			(keepout
				(tracks not_allowed)
				(vias allowed)
				(pads allowed)
				(copperpour not_allowed)
				(footprints allowed)
			)
			(placement
				(enabled no)
				(sheetname "")
			)
			(fill
				(thermal_gap 0.5)
				(thermal_bridge_width 0.5)
				(island_removal_mode 0)
			)
			(polygon
				(pts
					(arc
						(start 339.952076 -57.750202)
						(mid 340.00983 -57.713806)
						(end 340.046056 -57.655968)
					)
					(arc
						(start 340.151466 -57.655968)
						(mid 340.081797 -57.785689)
						(end 339.952076 -57.855358)
					)
				)
			)
		)
		(zone
			(layer "F.Cu")
			(hatch none 0.5)
			(connect_pads
				(clearance 0)
			)
			(min_thickness 0.25)
			(keepout
				(tracks not_allowed)
				(vias allowed)
				(pads allowed)
				(copperpour not_allowed)
				(footprints allowed)
			)
			(placement
				(enabled no)
				(sheetname "")
			)
			(fill
				(thermal_gap 0.5)
				(thermal_bridge_width 0.5)
				(island_removal_mode 0)
			)
			(polygon
				(pts
					(arc
						(start 339.952076 -39.440358)
						(mid 340.009939 -39.403987)
						(end 340.04631 -39.346124)
					)
					(arc
						(start 340.151466 -39.346124)
						(mid 340.081797 -39.475845)
						(end 339.952076 -39.545514)
					)
				)
			)
		)
		(zone
			(layer "F.Cu")
			(hatch none 0.5)
			(connect_pads
				(clearance 0)
			)
			(min_thickness 0.25)
			(keepout
				(tracks not_allowed)
				(vias allowed)
				(pads allowed)
				(copperpour not_allowed)
				(footprints allowed)
			)
			(placement
				(enabled no)
				(sheetname "")
			)
			(fill
				(thermal_gap 0.5)
				(thermal_bridge_width 0.5)
				(island_removal_mode 0)
			)
			(polygon
				(pts
					(arc
						(start 339.952076 -38.610286)
						(mid 340.009939 -38.573915)
						(end 340.04631 -38.516052)
					)
					(arc
						(start 340.151466 -38.516052)
						(mid 340.081797 -38.645773)
						(end 339.952076 -38.715442)
					)
				)
			)
		)
		(zone
			(layer "F.Cu")
			(hatch none 0.5)
			(connect_pads
				(clearance 0)
			)
			(min_thickness 0.25)
			(keepout
				(tracks not_allowed)
				(vias allowed)
				(pads allowed)
				(copperpour not_allowed)
				(footprints allowed)
			)
			(placement
				(enabled no)
				(sheetname "")
			)
			(fill
				(thermal_gap 0.5)
				(thermal_bridge_width 0.5)
				(island_removal_mode 0)
			)
			(polygon
				(pts
					(arc
						(start 340.046056 -58.38444)
						(mid 340.009825 -58.326581)
						(end 339.952076 -58.290206)
					)
					(arc
						(start 339.952076 -58.18505)
						(mid 340.081797 -58.254719)
						(end 340.151466 -58.38444)
					)
				)
			)
		)
		(zone
			(layer "F.Cu")
			(hatch none 0.5)
			(connect_pads
				(clearance 0)
			)
			(min_thickness 0.25)
			(keepout
				(tracks not_allowed)
				(vias allowed)
				(pads allowed)
				(copperpour not_allowed)
				(footprints allowed)
			)
			(placement
				(enabled no)
				(sheetname "")
			)
			(fill
				(thermal_gap 0.5)
				(thermal_bridge_width 0.5)
				(island_removal_mode 0)
			)
			(polygon
				(pts
					(arc
						(start 340.046056 -57.554368)
						(mid 340.009825 -57.496509)
						(end 339.952076 -57.460134)
					)
					(arc
						(start 339.952076 -57.354978)
						(mid 340.081797 -57.424647)
						(end 340.151466 -57.554368)
					)
				)
			)
		)
		(zone
			(layer "F.Cu")
			(hatch none 0.5)
			(connect_pads
				(clearance 0)
			)
			(min_thickness 0.25)
			(keepout
				(tracks not_allowed)
				(vias allowed)
				(pads allowed)
				(copperpour not_allowed)
				(footprints allowed)
			)
			(placement
				(enabled no)
				(sheetname "")
			)
			(fill
				(thermal_gap 0.5)
				(thermal_bridge_width 0.5)
				(island_removal_mode 0)
			)
			(polygon
				(pts
					(arc
						(start 340.04631 -39.244524)
						(mid 340.009939 -39.186661)
						(end 339.952076 -39.15029)
					)
					(arc
						(start 339.952076 -39.045134)
						(mid 340.081797 -39.114803)
						(end 340.151466 -39.244524)
					)
				)
			)
		)
		(zone
			(layer "F.Cu")
			(hatch none 0.5)
			(connect_pads
				(clearance 0)
			)
			(min_thickness 0.25)
			(keepout
				(tracks not_allowed)
				(vias allowed)
				(pads allowed)
				(copperpour not_allowed)
				(footprints allowed)
			)
			(placement
				(enabled no)
				(sheetname "")
			)
			(fill
				(thermal_gap 0.5)
				(thermal_bridge_width 0.5)
				(island_removal_mode 0)
			)
			(polygon
				(pts
					(arc
						(start 340.04631 -38.414452)
						(mid 340.009939 -38.356589)
						(end 339.952076 -38.320218)
					)
					(arc
						(start 339.952076 -38.215062)
						(mid 340.081797 -38.284731)
						(end 340.151466 -38.414452)
					)
				)
			)
		)
		(zone
			(layer "F.Cu")
			(hatch none 0.5)
			(connect_pads
				(clearance 0)
			)
			(min_thickness 0.25)
			(keepout
				(tracks not_allowed)
				(vias allowed)
				(pads allowed)
				(copperpour not_allowed)
				(footprints allowed)
			)
			(placement
				(enabled no)
				(sheetname "")
			)
			(fill
				(thermal_gap 0.5)
				(thermal_bridge_width 0.5)
				(island_removal_mode 0)
			)
			(polygon
				(pts
					(arc
						(start 340.256368 -58.901076)
						(mid 340.292739 -58.958939)
						(end 340.350602 -58.99531)
					)
					(arc
						(start 340.350602 -59.100466)
						(mid 340.220881 -59.030797)
						(end 340.151212 -58.901076)
					)
				)
			)
		)
		(zone
			(layer "F.Cu")
			(hatch none 0.5)
			(connect_pads
				(clearance 0)
			)
			(min_thickness 0.25)
			(keepout
				(tracks not_allowed)
				(vias allowed)
				(pads allowed)
				(copperpour not_allowed)
				(footprints allowed)
			)
			(placement
				(enabled no)
				(sheetname "")
			)
			(fill
				(thermal_gap 0.5)
				(thermal_bridge_width 0.5)
				(island_removal_mode 0)
			)
			(polygon
				(pts
					(arc
						(start 340.256368 -58.071004)
						(mid 340.292739 -58.128867)
						(end 340.350602 -58.165238)
					)
					(arc
						(start 340.350602 -58.270394)
						(mid 340.220881 -58.200725)
						(end 340.151212 -58.071004)
					)
				)
			)
		)
		(zone
			(layer "F.Cu")
			(hatch none 0.5)
			(connect_pads
				(clearance 0)
			)
			(min_thickness 0.25)
			(keepout
				(tracks not_allowed)
				(vias allowed)
				(pads allowed)
				(copperpour not_allowed)
				(footprints allowed)
			)
			(placement
				(enabled no)
				(sheetname "")
			)
			(fill
				(thermal_gap 0.5)
				(thermal_bridge_width 0.5)
				(island_removal_mode 0)
			)
			(polygon
				(pts
					(arc
						(start 340.256368 -38.931088)
						(mid 340.292739 -38.988951)
						(end 340.350602 -39.025322)
					)
					(arc
						(start 340.350602 -39.130478)
						(mid 340.220881 -39.060809)
						(end 340.151212 -38.931088)
					)
				)
			)
		)
		(zone
			(layer "F.Cu")
			(hatch none 0.5)
			(connect_pads
				(clearance 0)
			)
			(min_thickness 0.25)
			(keepout
				(tracks not_allowed)
				(vias allowed)
				(pads allowed)
				(copperpour not_allowed)
				(footprints allowed)
			)
			(placement
				(enabled no)
				(sheetname "")
			)
			(fill
				(thermal_gap 0.5)
				(thermal_bridge_width 0.5)
				(island_removal_mode 0)
			)
			(polygon
				(pts
					(arc
						(start 340.256368 -38.101016)
						(mid 340.292739 -38.158879)
						(end 340.350602 -38.19525)
					)
					(arc
						(start 340.350602 -38.300406)
						(mid 340.220881 -38.230737)
						(end 340.151212 -38.101016)
					)
				)
			)
		)
		(zone
			(layer "F.Cu")
			(hatch none 0.5)
			(connect_pads
				(clearance 0)
			)
			(min_thickness 0.25)
			(keepout
				(tracks not_allowed)
				(vias allowed)
				(pads allowed)
				(copperpour not_allowed)
				(footprints allowed)
			)
			(placement
				(enabled no)
				(sheetname "")
			)
			(fill
				(thermal_gap 0.5)
				(thermal_bridge_width 0.5)
				(island_removal_mode 0)
			)
			(polygon
				(pts
					(arc
						(start 340.350602 -58.705242)
						(mid 340.292739 -58.741613)
						(end 340.256368 -58.799476)
					)
					(arc
						(start 340.151212 -58.799476)
						(mid 340.220881 -58.669755)
						(end 340.350602 -58.600086)
					)
				)
			)
		)
		(zone
			(layer "F.Cu")
			(hatch none 0.5)
			(connect_pads
				(clearance 0)
			)
			(min_thickness 0.25)
			(keepout
				(tracks not_allowed)
				(vias allowed)
				(pads allowed)
				(copperpour not_allowed)
				(footprints allowed)
			)
			(placement
				(enabled no)
				(sheetname "")
			)
			(fill
				(thermal_gap 0.5)
				(thermal_bridge_width 0.5)
				(island_removal_mode 0)
			)
			(polygon
				(pts
					(arc
						(start 340.350602 -57.87517)
						(mid 340.292739 -57.911541)
						(end 340.256368 -57.969404)
					)
					(arc
						(start 340.151212 -57.969404)
						(mid 340.220881 -57.839683)
						(end 340.350602 -57.770014)
					)
				)
			)
		)
		(zone
			(layer "F.Cu")
			(hatch none 0.5)
			(connect_pads
				(clearance 0)
			)
			(min_thickness 0.25)
			(keepout
				(tracks not_allowed)
				(vias allowed)
				(pads allowed)
				(copperpour not_allowed)
				(footprints allowed)
			)
			(placement
				(enabled no)
				(sheetname "")
			)
			(fill
				(thermal_gap 0.5)
				(thermal_bridge_width 0.5)
				(island_removal_mode 0)
			)
			(polygon
				(pts
					(arc
						(start 340.350602 -38.735254)
						(mid 340.292739 -38.771625)
						(end 340.256368 -38.829488)
					)
					(arc
						(start 340.151212 -38.829488)
						(mid 340.220881 -38.699767)
						(end 340.350602 -38.630098)
					)
				)
			)
		)
		(zone
			(layer "F.Cu")
			(hatch none 0.5)
			(connect_pads
				(clearance 0)
			)
			(min_thickness 0.25)
			(keepout
				(tracks not_allowed)
				(vias allowed)
				(pads allowed)
				(copperpour not_allowed)
				(footprints allowed)
			)
			(placement
				(enabled no)
				(sheetname "")
			)
			(fill
				(thermal_gap 0.5)
				(thermal_bridge_width 0.5)
				(island_removal_mode 0)
			)
			(polygon
				(pts
					(arc
						(start 340.350602 -37.905182)
						(mid 340.292739 -37.941553)
						(end 340.256368 -37.999416)
					)
					(arc
						(start 340.151212 -37.999416)
						(mid 340.220881 -37.869695)
						(end 340.350602 -37.800026)
					)
				)
			)
		)
		(zone
			(layer "F.Cu")
			(hatch none 0.5)
			(connect_pads
				(clearance 0)
			)
			(min_thickness 0.25)
			(keepout
				(tracks not_allowed)
				(vias allowed)
				(pads allowed)
				(copperpour not_allowed)
				(footprints allowed)
			)
			(placement
				(enabled no)
				(sheetname "")
			)
			(fill
				(thermal_gap 0.5)
				(thermal_bridge_width 0.5)
				(island_removal_mode 0)
			)
			(polygon
				(pts
					(arc
						(start 340.452202 -58.99531)
						(mid 340.510065 -58.958939)
						(end 340.546436 -58.901076)
					)
					(arc
						(start 340.651592 -58.901076)
						(mid 340.581923 -59.030797)
						(end 340.452202 -59.100466)
					)
				)
			)
		)
		(zone
			(layer "F.Cu")
			(hatch none 0.5)
			(connect_pads
				(clearance 0)
			)
			(min_thickness 0.25)
			(keepout
				(tracks not_allowed)
				(vias allowed)
				(pads allowed)
				(copperpour not_allowed)
				(footprints allowed)
			)
			(placement
				(enabled no)
				(sheetname "")
			)
			(fill
				(thermal_gap 0.5)
				(thermal_bridge_width 0.5)
				(island_removal_mode 0)
			)
			(polygon
				(pts
					(arc
						(start 340.452202 -58.165238)
						(mid 340.510065 -58.128867)
						(end 340.546436 -58.071004)
					)
					(arc
						(start 340.651592 -58.071004)
						(mid 340.581923 -58.200725)
						(end 340.452202 -58.270394)
					)
				)
			)
		)
		(zone
			(layer "F.Cu")
			(hatch none 0.5)
			(connect_pads
				(clearance 0)
			)
			(min_thickness 0.25)
			(keepout
				(tracks not_allowed)
				(vias allowed)
				(pads allowed)
				(copperpour not_allowed)
				(footprints allowed)
			)
			(placement
				(enabled no)
				(sheetname "")
			)
			(fill
				(thermal_gap 0.5)
				(thermal_bridge_width 0.5)
				(island_removal_mode 0)
			)
			(polygon
				(pts
					(arc
						(start 340.452202 -39.025322)
						(mid 340.510065 -38.988951)
						(end 340.546436 -38.931088)
					)
					(arc
						(start 340.651592 -38.931088)
						(mid 340.581923 -39.060809)
						(end 340.452202 -39.130478)
					)
				)
			)
		)
		(zone
			(layer "F.Cu")
			(hatch none 0.5)
			(connect_pads
				(clearance 0)
			)
			(min_thickness 0.25)
			(keepout
				(tracks not_allowed)
				(vias allowed)
				(pads allowed)
				(copperpour not_allowed)
				(footprints allowed)
			)
			(placement
				(enabled no)
				(sheetname "")
			)
			(fill
				(thermal_gap 0.5)
				(thermal_bridge_width 0.5)
				(island_removal_mode 0)
			)
			(polygon
				(pts
					(arc
						(start 340.452202 -38.19525)
						(mid 340.510065 -38.158879)
						(end 340.546436 -38.101016)
					)
					(arc
						(start 340.651592 -38.101016)
						(mid 340.581923 -38.230737)
						(end 340.452202 -38.300406)
					)
				)
			)
		)
		(zone
			(layer "F.Cu")
			(hatch none 0.5)
			(connect_pads
				(clearance 0)
			)
			(min_thickness 0.25)
			(keepout
				(tracks not_allowed)
				(vias allowed)
				(pads allowed)
				(copperpour not_allowed)
				(footprints allowed)
			)
			(placement
				(enabled no)
				(sheetname "")
			)
			(fill
				(thermal_gap 0.5)
				(thermal_bridge_width 0.5)
				(island_removal_mode 0)
			)
			(polygon
				(pts
					(arc
						(start 340.546436 -58.799476)
						(mid 340.510065 -58.741613)
						(end 340.452202 -58.705242)
					)
					(arc
						(start 340.452202 -58.600086)
						(mid 340.581923 -58.669755)
						(end 340.651592 -58.799476)
					)
				)
			)
		)
		(zone
			(layer "F.Cu")
			(hatch none 0.5)
			(connect_pads
				(clearance 0)
			)
			(min_thickness 0.25)
			(keepout
				(tracks not_allowed)
				(vias allowed)
				(pads allowed)
				(copperpour not_allowed)
				(footprints allowed)
			)
			(placement
				(enabled no)
				(sheetname "")
			)
			(fill
				(thermal_gap 0.5)
				(thermal_bridge_width 0.5)
				(island_removal_mode 0)
			)
			(polygon
				(pts
					(arc
						(start 340.546436 -57.969404)
						(mid 340.510065 -57.911541)
						(end 340.452202 -57.87517)
					)
					(arc
						(start 340.452202 -57.770014)
						(mid 340.581923 -57.839683)
						(end 340.651592 -57.969404)
					)
				)
			)
		)
		(zone
			(layer "F.Cu")
			(hatch none 0.5)
			(connect_pads
				(clearance 0)
			)
			(min_thickness 0.25)
			(keepout
				(tracks not_allowed)
				(vias allowed)
				(pads allowed)
				(copperpour not_allowed)
				(footprints allowed)
			)
			(placement
				(enabled no)
				(sheetname "")
			)
			(fill
				(thermal_gap 0.5)
				(thermal_bridge_width 0.5)
				(island_removal_mode 0)
			)
			(polygon
				(pts
					(arc
						(start 340.546436 -38.829488)
						(mid 340.510065 -38.771625)
						(end 340.452202 -38.735254)
					)
					(arc
						(start 340.452202 -38.630098)
						(mid 340.581923 -38.699767)
						(end 340.651592 -38.829488)
					)
				)
			)
		)
		(zone
			(layer "F.Cu")
			(hatch none 0.5)
			(connect_pads
				(clearance 0)
			)
			(min_thickness 0.25)
			(keepout
				(tracks not_allowed)
				(vias allowed)
				(pads allowed)
				(copperpour not_allowed)
				(footprints allowed)
			)
			(placement
				(enabled no)
				(sheetname "")
			)
			(fill
				(thermal_gap 0.5)
				(thermal_bridge_width 0.5)
				(island_removal_mode 0)
			)
			(polygon
				(pts
					(arc
						(start 340.546436 -37.999416)
						(mid 340.510065 -37.941553)
						(end 340.452202 -37.905182)
					)
					(arc
						(start 340.452202 -37.800026)
						(mid 340.581923 -37.869695)
						(end 340.651592 -37.999416)
					)
				)
			)
		)
		(zone
			(layer "F.Cu")
			(hatch none 0.5)
			(connect_pads
				(clearance 0)
			)
			(min_thickness 0.25)
			(keepout
				(tracks not_allowed)
				(vias allowed)
				(pads allowed)
				(copperpour not_allowed)
				(footprints allowed)
			)
			(placement
				(enabled no)
				(sheetname "")
			)
			(fill
				(thermal_gap 0.5)
				(thermal_bridge_width 0.5)
				(island_removal_mode 0)
			)
			(polygon
				(pts
					(arc
						(start 340.756748 -58.48604)
						(mid 340.793174 -58.543739)
						(end 340.850982 -58.58002)
					)
					(arc
						(start 340.850982 -58.68543)
						(mid 340.721131 -58.615813)
						(end 340.651338 -58.48604)
					)
				)
			)
		)
		(zone
			(layer "F.Cu")
			(hatch none 0.5)
			(connect_pads
				(clearance 0)
			)
			(min_thickness 0.25)
			(keepout
				(tracks not_allowed)
				(vias allowed)
				(pads allowed)
				(copperpour not_allowed)
				(footprints allowed)
			)
			(placement
				(enabled no)
				(sheetname "")
			)
			(fill
				(thermal_gap 0.5)
				(thermal_bridge_width 0.5)
				(island_removal_mode 0)
			)
			(polygon
				(pts
					(arc
						(start 340.756748 -57.655968)
						(mid 340.793119 -57.713831)
						(end 340.850982 -57.750202)
					)
					(arc
						(start 340.850982 -57.855358)
						(mid 340.721131 -57.785741)
						(end 340.651338 -57.655968)
					)
				)
			)
		)
		(zone
			(layer "F.Cu")
			(hatch none 0.5)
			(connect_pads
				(clearance 0)
			)
			(min_thickness 0.25)
			(keepout
				(tracks not_allowed)
				(vias allowed)
				(pads allowed)
				(copperpour not_allowed)
				(footprints allowed)
			)
			(placement
				(enabled no)
				(sheetname "")
			)
			(fill
				(thermal_gap 0.5)
				(thermal_bridge_width 0.5)
				(island_removal_mode 0)
			)
			(polygon
				(pts
					(arc
						(start 340.756748 -39.346124)
						(mid 340.793119 -39.403987)
						(end 340.850982 -39.440358)
					)
					(arc
						(start 340.850982 -39.545514)
						(mid 340.721261 -39.475845)
						(end 340.651592 -39.346124)
					)
				)
			)
		)
		(zone
			(layer "F.Cu")
			(hatch none 0.5)
			(connect_pads
				(clearance 0)
			)
			(min_thickness 0.25)
			(keepout
				(tracks not_allowed)
				(vias allowed)
				(pads allowed)
				(copperpour not_allowed)
				(footprints allowed)
			)
			(placement
				(enabled no)
				(sheetname "")
			)
			(fill
				(thermal_gap 0.5)
				(thermal_bridge_width 0.5)
				(island_removal_mode 0)
			)
			(polygon
				(pts
					(arc
						(start 340.756748 -38.516052)
						(mid 340.793119 -38.573915)
						(end 340.850982 -38.610286)
					)
					(arc
						(start 340.850982 -38.715442)
						(mid 340.721261 -38.645773)
						(end 340.651592 -38.516052)
					)
				)
			)
		)
		(zone
			(layer "F.Cu")
			(hatch none 0.5)
			(connect_pads
				(clearance 0)
			)
			(min_thickness 0.25)
			(keepout
				(tracks not_allowed)
				(vias allowed)
				(pads allowed)
				(copperpour not_allowed)
				(footprints allowed)
			)
			(placement
				(enabled no)
				(sheetname "")
			)
			(fill
				(thermal_gap 0.5)
				(thermal_bridge_width 0.5)
				(island_removal_mode 0)
			)
			(polygon
				(pts
					(arc
						(start 340.850982 -58.290206)
						(mid 340.793119 -58.326577)
						(end 340.756748 -58.38444)
					)
					(arc
						(start 340.651338 -58.38444)
						(mid 340.721095 -58.254631)
						(end 340.850982 -58.18505)
					)
				)
			)
		)
		(zone
			(layer "F.Cu")
			(hatch none 0.5)
			(connect_pads
				(clearance 0)
			)
			(min_thickness 0.25)
			(keepout
				(tracks not_allowed)
				(vias allowed)
				(pads allowed)
				(copperpour not_allowed)
				(footprints allowed)
			)
			(placement
				(enabled no)
				(sheetname "")
			)
			(fill
				(thermal_gap 0.5)
				(thermal_bridge_width 0.5)
				(island_removal_mode 0)
			)
			(polygon
				(pts
					(arc
						(start 340.850982 -57.460134)
						(mid 340.793119 -57.496505)
						(end 340.756748 -57.554368)
					)
					(arc
						(start 340.651338 -57.554368)
						(mid 340.721095 -57.424559)
						(end 340.850982 -57.354978)
					)
				)
			)
		)
		(zone
			(layer "F.Cu")
			(hatch none 0.5)
			(connect_pads
				(clearance 0)
			)
			(min_thickness 0.25)
			(keepout
				(tracks not_allowed)
				(vias allowed)
				(pads allowed)
				(copperpour not_allowed)
				(footprints allowed)
			)
			(placement
				(enabled no)
				(sheetname "")
			)
			(fill
				(thermal_gap 0.5)
				(thermal_bridge_width 0.5)
				(island_removal_mode 0)
			)
			(polygon
				(pts
					(arc
						(start 340.850982 -39.15029)
						(mid 340.793119 -39.186661)
						(end 340.756748 -39.244524)
					)
					(arc
						(start 340.651592 -39.244524)
						(mid 340.721261 -39.114803)
						(end 340.850982 -39.045134)
					)
				)
			)
		)
		(zone
			(layer "F.Cu")
			(hatch none 0.5)
			(connect_pads
				(clearance 0)
			)
			(min_thickness 0.25)
			(keepout
				(tracks not_allowed)
				(vias allowed)
				(pads allowed)
				(copperpour not_allowed)
				(footprints allowed)
			)
			(placement
				(enabled no)
				(sheetname "")
			)
			(fill
				(thermal_gap 0.5)
				(thermal_bridge_width 0.5)
				(island_removal_mode 0)
			)
			(polygon
				(pts
					(arc
						(start 340.850982 -38.320218)
						(mid 340.793119 -38.356589)
						(end 340.756748 -38.414452)
					)
					(arc
						(start 340.651592 -38.414452)
						(mid 340.721261 -38.284731)
						(end 340.850982 -38.215062)
					)
				)
			)
		)
		(zone
			(layer "F.Cu")
			(hatch none 0.5)
			(connect_pads
				(clearance 0)
			)
			(min_thickness 0.25)
			(keepout
				(tracks not_allowed)
				(vias allowed)
				(pads allowed)
				(copperpour not_allowed)
				(footprints allowed)
			)
			(placement
				(enabled no)
				(sheetname "")
			)
			(fill
				(thermal_gap 0.5)
				(thermal_bridge_width 0.5)
				(island_removal_mode 0)
			)
			(polygon
				(pts
					(arc
						(start 340.952582 -58.58002)
						(mid 341.010276 -58.543734)
						(end 341.046562 -58.48604)
					)
					(arc
						(start 341.151972 -58.48604)
						(mid 341.082303 -58.615761)
						(end 340.952582 -58.68543)
					)
				)
			)
		)
		(zone
			(layer "F.Cu")
			(hatch none 0.5)
			(connect_pads
				(clearance 0)
			)
			(min_thickness 0.25)
			(keepout
				(tracks not_allowed)
				(vias allowed)
				(pads allowed)
				(copperpour not_allowed)
				(footprints allowed)
			)
			(placement
				(enabled no)
				(sheetname "")
			)
			(fill
				(thermal_gap 0.5)
				(thermal_bridge_width 0.5)
				(island_removal_mode 0)
			)
			(polygon
				(pts
					(arc
						(start 340.952582 -57.750202)
						(mid 341.010336 -57.713806)
						(end 341.046562 -57.655968)
					)
					(arc
						(start 341.151972 -57.655968)
						(mid 341.082303 -57.785689)
						(end 340.952582 -57.855358)
					)
				)
			)
		)
		(zone
			(layer "F.Cu")
			(hatch none 0.5)
			(connect_pads
				(clearance 0)
			)
			(min_thickness 0.25)
			(keepout
				(tracks not_allowed)
				(vias allowed)
				(pads allowed)
				(copperpour not_allowed)
				(footprints allowed)
			)
			(placement
				(enabled no)
				(sheetname "")
			)
			(fill
				(thermal_gap 0.5)
				(thermal_bridge_width 0.5)
				(island_removal_mode 0)
			)
			(polygon
				(pts
					(arc
						(start 340.952582 -39.440358)
						(mid 341.010445 -39.403987)
						(end 341.046816 -39.346124)
					)
					(arc
						(start 341.151972 -39.346124)
						(mid 341.082303 -39.475845)
						(end 340.952582 -39.545514)
					)
				)
			)
		)
		(zone
			(layer "F.Cu")
			(hatch none 0.5)
			(connect_pads
				(clearance 0)
			)
			(min_thickness 0.25)
			(keepout
				(tracks not_allowed)
				(vias allowed)
				(pads allowed)
				(copperpour not_allowed)
				(footprints allowed)
			)
			(placement
				(enabled no)
				(sheetname "")
			)
			(fill
				(thermal_gap 0.5)
				(thermal_bridge_width 0.5)
				(island_removal_mode 0)
			)
			(polygon
				(pts
					(arc
						(start 340.952582 -38.610286)
						(mid 341.010445 -38.573915)
						(end 341.046816 -38.516052)
					)
					(arc
						(start 341.151972 -38.516052)
						(mid 341.082303 -38.645773)
						(end 340.952582 -38.715442)
					)
				)
			)
		)
		(zone
			(layer "F.Cu")
			(hatch none 0.5)
			(connect_pads
				(clearance 0)
			)
			(min_thickness 0.25)
			(keepout
				(tracks not_allowed)
				(vias allowed)
				(pads allowed)
				(copperpour not_allowed)
				(footprints allowed)
			)
			(placement
				(enabled no)
				(sheetname "")
			)
			(fill
				(thermal_gap 0.5)
				(thermal_bridge_width 0.5)
				(island_removal_mode 0)
			)
			(polygon
				(pts
					(arc
						(start 341.046562 -58.38444)
						(mid 341.010331 -58.326581)
						(end 340.952582 -58.290206)
					)
					(arc
						(start 340.952582 -58.18505)
						(mid 341.082303 -58.254719)
						(end 341.151972 -58.38444)
					)
				)
			)
		)
		(zone
			(layer "F.Cu")
			(hatch none 0.5)
			(connect_pads
				(clearance 0)
			)
			(min_thickness 0.25)
			(keepout
				(tracks not_allowed)
				(vias allowed)
				(pads allowed)
				(copperpour not_allowed)
				(footprints allowed)
			)
			(placement
				(enabled no)
				(sheetname "")
			)
			(fill
				(thermal_gap 0.5)
				(thermal_bridge_width 0.5)
				(island_removal_mode 0)
			)
			(polygon
				(pts
					(arc
						(start 341.046562 -57.554368)
						(mid 341.010331 -57.496509)
						(end 340.952582 -57.460134)
					)
					(arc
						(start 340.952582 -57.354978)
						(mid 341.082303 -57.424647)
						(end 341.151972 -57.554368)
					)
				)
			)
		)
		(zone
			(layer "F.Cu")
			(hatch none 0.5)
			(connect_pads
				(clearance 0)
			)
			(min_thickness 0.25)
			(keepout
				(tracks not_allowed)
				(vias allowed)
				(pads allowed)
				(copperpour not_allowed)
				(footprints allowed)
			)
			(placement
				(enabled no)
				(sheetname "")
			)
			(fill
				(thermal_gap 0.5)
				(thermal_bridge_width 0.5)
				(island_removal_mode 0)
			)
			(polygon
				(pts
					(arc
						(start 341.046816 -39.244524)
						(mid 341.010445 -39.186661)
						(end 340.952582 -39.15029)
					)
					(arc
						(start 340.952582 -39.045134)
						(mid 341.082303 -39.114803)
						(end 341.151972 -39.244524)
					)
				)
			)
		)
		(zone
			(layer "F.Cu")
			(hatch none 0.5)
			(connect_pads
				(clearance 0)
			)
			(min_thickness 0.25)
			(keepout
				(tracks not_allowed)
				(vias allowed)
				(pads allowed)
				(copperpour not_allowed)
				(footprints allowed)
			)
			(placement
				(enabled no)
				(sheetname "")
			)
			(fill
				(thermal_gap 0.5)
				(thermal_bridge_width 0.5)
				(island_removal_mode 0)
			)
			(polygon
				(pts
					(arc
						(start 341.046816 -38.414452)
						(mid 341.010445 -38.356589)
						(end 340.952582 -38.320218)
					)
					(arc
						(start 340.952582 -38.215062)
						(mid 341.082303 -38.284731)
						(end 341.151972 -38.414452)
					)
				)
			)
		)
		(zone
			(layer "F.Cu")
			(hatch none 0.5)
			(connect_pads
				(clearance 0)
			)
			(min_thickness 0.25)
			(keepout
				(tracks not_allowed)
				(vias allowed)
				(pads allowed)
				(copperpour not_allowed)
				(footprints allowed)
			)
			(placement
				(enabled no)
				(sheetname "")
			)
			(fill
				(thermal_gap 0.5)
				(thermal_bridge_width 0.5)
				(island_removal_mode 0)
			)
			(polygon
				(pts
					(arc
						(start 341.256874 -58.901076)
						(mid 341.293245 -58.958939)
						(end 341.351108 -58.99531)
					)
					(arc
						(start 341.351108 -59.100466)
						(mid 341.221387 -59.030797)
						(end 341.151718 -58.901076)
					)
				)
			)
		)
		(zone
			(layer "F.Cu")
			(hatch none 0.5)
			(connect_pads
				(clearance 0)
			)
			(min_thickness 0.25)
			(keepout
				(tracks not_allowed)
				(vias allowed)
				(pads allowed)
				(copperpour not_allowed)
				(footprints allowed)
			)
			(placement
				(enabled no)
				(sheetname "")
			)
			(fill
				(thermal_gap 0.5)
				(thermal_bridge_width 0.5)
				(island_removal_mode 0)
			)
			(polygon
				(pts
					(arc
						(start 341.256874 -58.071004)
						(mid 341.293245 -58.128867)
						(end 341.351108 -58.165238)
					)
					(arc
						(start 341.351108 -58.270394)
						(mid 341.221387 -58.200725)
						(end 341.151718 -58.071004)
					)
				)
			)
		)
		(zone
			(layer "F.Cu")
			(hatch none 0.5)
			(connect_pads
				(clearance 0)
			)
			(min_thickness 0.25)
			(keepout
				(tracks not_allowed)
				(vias allowed)
				(pads allowed)
				(copperpour not_allowed)
				(footprints allowed)
			)
			(placement
				(enabled no)
				(sheetname "")
			)
			(fill
				(thermal_gap 0.5)
				(thermal_bridge_width 0.5)
				(island_removal_mode 0)
			)
			(polygon
				(pts
					(arc
						(start 341.256874 -38.931088)
						(mid 341.293245 -38.988951)
						(end 341.351108 -39.025322)
					)
					(arc
						(start 341.351108 -39.130478)
						(mid 341.221387 -39.060809)
						(end 341.151718 -38.931088)
					)
				)
			)
		)
		(zone
			(layer "F.Cu")
			(hatch none 0.5)
			(connect_pads
				(clearance 0)
			)
			(min_thickness 0.25)
			(keepout
				(tracks not_allowed)
				(vias allowed)
				(pads allowed)
				(copperpour not_allowed)
				(footprints allowed)
			)
			(placement
				(enabled no)
				(sheetname "")
			)
			(fill
				(thermal_gap 0.5)
				(thermal_bridge_width 0.5)
				(island_removal_mode 0)
			)
			(polygon
				(pts
					(arc
						(start 341.256874 -38.101016)
						(mid 341.293245 -38.158879)
						(end 341.351108 -38.19525)
					)
					(arc
						(start 341.351108 -38.300406)
						(mid 341.221387 -38.230737)
						(end 341.151718 -38.101016)
					)
				)
			)
		)
		(zone
			(layer "F.Cu")
			(hatch none 0.5)
			(connect_pads
				(clearance 0)
			)
			(min_thickness 0.25)
			(keepout
				(tracks not_allowed)
				(vias allowed)
				(pads allowed)
				(copperpour not_allowed)
				(footprints allowed)
			)
			(placement
				(enabled no)
				(sheetname "")
			)
			(fill
				(thermal_gap 0.5)
				(thermal_bridge_width 0.5)
				(island_removal_mode 0)
			)
			(polygon
				(pts
					(arc
						(start 341.351108 -58.705242)
						(mid 341.293245 -58.741613)
						(end 341.256874 -58.799476)
					)
					(arc
						(start 341.151718 -58.799476)
						(mid 341.221387 -58.669755)
						(end 341.351108 -58.600086)
					)
				)
			)
		)
		(zone
			(layer "F.Cu")
			(hatch none 0.5)
			(connect_pads
				(clearance 0)
			)
			(min_thickness 0.25)
			(keepout
				(tracks not_allowed)
				(vias allowed)
				(pads allowed)
				(copperpour not_allowed)
				(footprints allowed)
			)
			(placement
				(enabled no)
				(sheetname "")
			)
			(fill
				(thermal_gap 0.5)
				(thermal_bridge_width 0.5)
				(island_removal_mode 0)
			)
			(polygon
				(pts
					(arc
						(start 341.351108 -57.87517)
						(mid 341.293245 -57.911541)
						(end 341.256874 -57.969404)
					)
					(arc
						(start 341.151718 -57.969404)
						(mid 341.221387 -57.839683)
						(end 341.351108 -57.770014)
					)
				)
			)
		)
		(zone
			(layer "F.Cu")
			(hatch none 0.5)
			(connect_pads
				(clearance 0)
			)
			(min_thickness 0.25)
			(keepout
				(tracks not_allowed)
				(vias allowed)
				(pads allowed)
				(copperpour not_allowed)
				(footprints allowed)
			)
			(placement
				(enabled no)
				(sheetname "")
			)
			(fill
				(thermal_gap 0.5)
				(thermal_bridge_width 0.5)
				(island_removal_mode 0)
			)
			(polygon
				(pts
					(arc
						(start 341.351108 -38.735254)
						(mid 341.293245 -38.771625)
						(end 341.256874 -38.829488)
					)
					(arc
						(start 341.151718 -38.829488)
						(mid 341.221387 -38.699767)
						(end 341.351108 -38.630098)
					)
				)
			)
		)
		(zone
			(layer "F.Cu")
			(hatch none 0.5)
			(connect_pads
				(clearance 0)
			)
			(min_thickness 0.25)
			(keepout
				(tracks not_allowed)
				(vias allowed)
				(pads allowed)
				(copperpour not_allowed)
				(footprints allowed)
			)
			(placement
				(enabled no)
				(sheetname "")
			)
			(fill
				(thermal_gap 0.5)
				(thermal_bridge_width 0.5)
				(island_removal_mode 0)
			)
			(polygon
				(pts
					(arc
						(start 341.351108 -37.905182)
						(mid 341.293245 -37.941553)
						(end 341.256874 -37.999416)
					)
					(arc
						(start 341.151718 -37.999416)
						(mid 341.221387 -37.869695)
						(end 341.351108 -37.800026)
					)
				)
			)
		)
		(zone
			(layer "F.Cu")
			(hatch none 0.5)
			(connect_pads
				(clearance 0)
			)
			(min_thickness 0.25)
			(keepout
				(tracks not_allowed)
				(vias allowed)
				(pads allowed)
				(copperpour not_allowed)
				(footprints allowed)
			)
			(placement
				(enabled no)
				(sheetname "")
			)
			(fill
				(thermal_gap 0.5)
				(thermal_bridge_width 0.5)
				(island_removal_mode 0)
			)
			(polygon
				(pts
					(arc
						(start 341.452708 -58.99531)
						(mid 341.510571 -58.958939)
						(end 341.546942 -58.901076)
					)
					(arc
						(start 341.652098 -58.901076)
						(mid 341.582429 -59.030797)
						(end 341.452708 -59.100466)
					)
				)
			)
		)
		(zone
			(layer "F.Cu")
			(hatch none 0.5)
			(connect_pads
				(clearance 0)
			)
			(min_thickness 0.25)
			(keepout
				(tracks not_allowed)
				(vias allowed)
				(pads allowed)
				(copperpour not_allowed)
				(footprints allowed)
			)
			(placement
				(enabled no)
				(sheetname "")
			)
			(fill
				(thermal_gap 0.5)
				(thermal_bridge_width 0.5)
				(island_removal_mode 0)
			)
			(polygon
				(pts
					(arc
						(start 341.452708 -58.165238)
						(mid 341.510571 -58.128867)
						(end 341.546942 -58.071004)
					)
					(arc
						(start 341.652098 -58.071004)
						(mid 341.582429 -58.200725)
						(end 341.452708 -58.270394)
					)
				)
			)
		)
		(zone
			(layer "F.Cu")
			(hatch none 0.5)
			(connect_pads
				(clearance 0)
			)
			(min_thickness 0.25)
			(keepout
				(tracks not_allowed)
				(vias allowed)
				(pads allowed)
				(copperpour not_allowed)
				(footprints allowed)
			)
			(placement
				(enabled no)
				(sheetname "")
			)
			(fill
				(thermal_gap 0.5)
				(thermal_bridge_width 0.5)
				(island_removal_mode 0)
			)
			(polygon
				(pts
					(arc
						(start 341.452708 -39.025322)
						(mid 341.510571 -38.988951)
						(end 341.546942 -38.931088)
					)
					(arc
						(start 341.652098 -38.931088)
						(mid 341.582429 -39.060809)
						(end 341.452708 -39.130478)
					)
				)
			)
		)
		(zone
			(layer "F.Cu")
			(hatch none 0.5)
			(connect_pads
				(clearance 0)
			)
			(min_thickness 0.25)
			(keepout
				(tracks not_allowed)
				(vias allowed)
				(pads allowed)
				(copperpour not_allowed)
				(footprints allowed)
			)
			(placement
				(enabled no)
				(sheetname "")
			)
			(fill
				(thermal_gap 0.5)
				(thermal_bridge_width 0.5)
				(island_removal_mode 0)
			)
			(polygon
				(pts
					(arc
						(start 341.452708 -38.19525)
						(mid 341.510571 -38.158879)
						(end 341.546942 -38.101016)
					)
					(arc
						(start 341.652098 -38.101016)
						(mid 341.582429 -38.230737)
						(end 341.452708 -38.300406)
					)
				)
			)
		)
		(zone
			(layer "F.Cu")
			(hatch none 0.5)
			(connect_pads
				(clearance 0)
			)
			(min_thickness 0.25)
			(keepout
				(tracks not_allowed)
				(vias allowed)
				(pads allowed)
				(copperpour not_allowed)
				(footprints allowed)
			)
			(placement
				(enabled no)
				(sheetname "")
			)
			(fill
				(thermal_gap 0.5)
				(thermal_bridge_width 0.5)
				(island_removal_mode 0)
			)
			(polygon
				(pts
					(arc
						(start 341.546942 -58.799476)
						(mid 341.510571 -58.741613)
						(end 341.452708 -58.705242)
					)
					(arc
						(start 341.452708 -58.600086)
						(mid 341.582429 -58.669755)
						(end 341.652098 -58.799476)
					)
				)
			)
		)
		(zone
			(layer "F.Cu")
			(hatch none 0.5)
			(connect_pads
				(clearance 0)
			)
			(min_thickness 0.25)
			(keepout
				(tracks not_allowed)
				(vias allowed)
				(pads allowed)
				(copperpour not_allowed)
				(footprints allowed)
			)
			(placement
				(enabled no)
				(sheetname "")
			)
			(fill
				(thermal_gap 0.5)
				(thermal_bridge_width 0.5)
				(island_removal_mode 0)
			)
			(polygon
				(pts
					(arc
						(start 341.546942 -57.969404)
						(mid 341.510571 -57.911541)
						(end 341.452708 -57.87517)
					)
					(arc
						(start 341.452708 -57.770014)
						(mid 341.582429 -57.839683)
						(end 341.652098 -57.969404)
					)
				)
			)
		)
		(zone
			(layer "F.Cu")
			(hatch none 0.5)
			(connect_pads
				(clearance 0)
			)
			(min_thickness 0.25)
			(keepout
				(tracks not_allowed)
				(vias allowed)
				(pads allowed)
				(copperpour not_allowed)
				(footprints allowed)
			)
			(placement
				(enabled no)
				(sheetname "")
			)
			(fill
				(thermal_gap 0.5)
				(thermal_bridge_width 0.5)
				(island_removal_mode 0)
			)
			(polygon
				(pts
					(arc
						(start 341.546942 -38.829488)
						(mid 341.510571 -38.771625)
						(end 341.452708 -38.735254)
					)
					(arc
						(start 341.452708 -38.630098)
						(mid 341.582429 -38.699767)
						(end 341.652098 -38.829488)
					)
				)
			)
		)
		(zone
			(layer "F.Cu")
			(hatch none 0.5)
			(connect_pads
				(clearance 0)
			)
			(min_thickness 0.25)
			(keepout
				(tracks not_allowed)
				(vias allowed)
				(pads allowed)
				(copperpour not_allowed)
				(footprints allowed)
			)
			(placement
				(enabled no)
				(sheetname "")
			)
			(fill
				(thermal_gap 0.5)
				(thermal_bridge_width 0.5)
				(island_removal_mode 0)
			)
			(polygon
				(pts
					(arc
						(start 341.546942 -37.999416)
						(mid 341.510571 -37.941553)
						(end 341.452708 -37.905182)
					)
					(arc
						(start 341.452708 -37.800026)
						(mid 341.582429 -37.869695)
						(end 341.652098 -37.999416)
					)
				)
			)
		)
		(zone
			(layer "F.Cu")
			(hatch none 0.5)
			(connect_pads
				(clearance 0)
			)
			(min_thickness 0.25)
			(keepout
				(tracks not_allowed)
				(vias allowed)
				(pads allowed)
				(copperpour not_allowed)
				(footprints allowed)
			)
			(placement
				(enabled no)
				(sheetname "")
			)
			(fill
				(thermal_gap 0.5)
				(thermal_bridge_width 0.5)
				(island_removal_mode 0)
			)
			(polygon
				(pts
					(arc
						(start 341.757254 -58.48604)
						(mid 341.79354 -58.543734)
						(end 341.851234 -58.58002)
					)
					(arc
						(start 341.851234 -58.68543)
						(mid 341.721513 -58.615761)
						(end 341.651844 -58.48604)
					)
				)
			)
		)
		(zone
			(layer "F.Cu")
			(hatch none 0.5)
			(connect_pads
				(clearance 0)
			)
			(min_thickness 0.25)
			(keepout
				(tracks not_allowed)
				(vias allowed)
				(pads allowed)
				(copperpour not_allowed)
				(footprints allowed)
			)
			(placement
				(enabled no)
				(sheetname "")
			)
			(fill
				(thermal_gap 0.5)
				(thermal_bridge_width 0.5)
				(island_removal_mode 0)
			)
			(polygon
				(pts
					(arc
						(start 341.757254 -57.655968)
						(mid 341.79354 -57.713747)
						(end 341.851234 -57.750202)
					)
					(arc
						(start 341.851234 -57.855358)
						(mid 341.721513 -57.785689)
						(end 341.651844 -57.655968)
					)
				)
			)
		)
		(zone
			(layer "F.Cu")
			(hatch none 0.5)
			(connect_pads
				(clearance 0)
			)
			(min_thickness 0.25)
			(keepout
				(tracks not_allowed)
				(vias allowed)
				(pads allowed)
				(copperpour not_allowed)
				(footprints allowed)
			)
			(placement
				(enabled no)
				(sheetname "")
			)
			(fill
				(thermal_gap 0.5)
				(thermal_bridge_width 0.5)
				(island_removal_mode 0)
			)
			(polygon
				(pts
					(arc
						(start 341.757254 -39.346124)
						(mid 341.793485 -39.403983)
						(end 341.851234 -39.440358)
					)
					(arc
						(start 341.851234 -39.545514)
						(mid 341.721513 -39.475845)
						(end 341.651844 -39.346124)
					)
				)
			)
		)
		(zone
			(layer "F.Cu")
			(hatch none 0.5)
			(connect_pads
				(clearance 0)
			)
			(min_thickness 0.25)
			(keepout
				(tracks not_allowed)
				(vias allowed)
				(pads allowed)
				(copperpour not_allowed)
				(footprints allowed)
			)
			(placement
				(enabled no)
				(sheetname "")
			)
			(fill
				(thermal_gap 0.5)
				(thermal_bridge_width 0.5)
				(island_removal_mode 0)
			)
			(polygon
				(pts
					(arc
						(start 341.757254 -38.516052)
						(mid 341.793625 -38.573915)
						(end 341.851488 -38.610286)
					)
					(arc
						(start 341.851488 -38.715442)
						(mid 341.721767 -38.645773)
						(end 341.652098 -38.516052)
					)
				)
			)
		)
		(zone
			(layer "F.Cu")
			(hatch none 0.5)
			(connect_pads
				(clearance 0)
			)
			(min_thickness 0.25)
			(keepout
				(tracks not_allowed)
				(vias allowed)
				(pads allowed)
				(copperpour not_allowed)
				(footprints allowed)
			)
			(placement
				(enabled no)
				(sheetname "")
			)
			(fill
				(thermal_gap 0.5)
				(thermal_bridge_width 0.5)
				(island_removal_mode 0)
			)
			(polygon
				(pts
					(arc
						(start 341.851234 -58.290206)
						(mid 341.793535 -58.326632)
						(end 341.757254 -58.38444)
					)
					(arc
						(start 341.651844 -58.38444)
						(mid 341.721513 -58.254719)
						(end 341.851234 -58.18505)
					)
				)
			)
		)
		(zone
			(layer "F.Cu")
			(hatch none 0.5)
			(connect_pads
				(clearance 0)
			)
			(min_thickness 0.25)
			(keepout
				(tracks not_allowed)
				(vias allowed)
				(pads allowed)
				(copperpour not_allowed)
				(footprints allowed)
			)
			(placement
				(enabled no)
				(sheetname "")
			)
			(fill
				(thermal_gap 0.5)
				(thermal_bridge_width 0.5)
				(island_removal_mode 0)
			)
			(polygon
				(pts
					(arc
						(start 341.851234 -57.460134)
						(mid 341.793535 -57.49656)
						(end 341.757254 -57.554368)
					)
					(arc
						(start 341.651844 -57.554368)
						(mid 341.721513 -57.424647)
						(end 341.851234 -57.354978)
					)
				)
			)
		)
		(zone
			(layer "F.Cu")
			(hatch none 0.5)
			(connect_pads
				(clearance 0)
			)
			(min_thickness 0.25)
			(keepout
				(tracks not_allowed)
				(vias allowed)
				(pads allowed)
				(copperpour not_allowed)
				(footprints allowed)
			)
			(placement
				(enabled no)
				(sheetname "")
			)
			(fill
				(thermal_gap 0.5)
				(thermal_bridge_width 0.5)
				(island_removal_mode 0)
			)
			(polygon
				(pts
					(arc
						(start 341.851234 -39.15029)
						(mid 341.79348 -39.186686)
						(end 341.757254 -39.244524)
					)
					(arc
						(start 341.651844 -39.244524)
						(mid 341.721513 -39.114803)
						(end 341.851234 -39.045134)
					)
				)
			)
		)
		(zone
			(layer "F.Cu")
			(hatch none 0.5)
			(connect_pads
				(clearance 0)
			)
			(min_thickness 0.25)
			(keepout
				(tracks not_allowed)
				(vias allowed)
				(pads allowed)
				(copperpour not_allowed)
				(footprints allowed)
			)
			(placement
				(enabled no)
				(sheetname "")
			)
			(fill
				(thermal_gap 0.5)
				(thermal_bridge_width 0.5)
				(island_removal_mode 0)
			)
			(polygon
				(pts
					(arc
						(start 341.851488 -38.320218)
						(mid 341.793625 -38.356589)
						(end 341.757254 -38.414452)
					)
					(arc
						(start 341.652098 -38.414452)
						(mid 341.721767 -38.284731)
						(end 341.851488 -38.215062)
					)
				)
			)
		)
		(zone
			(layer "F.Cu")
			(hatch none 0.5)
			(connect_pads
				(clearance 0)
			)
			(min_thickness 0.25)
			(keepout
				(tracks not_allowed)
				(vias allowed)
				(pads allowed)
				(copperpour not_allowed)
				(footprints allowed)
			)
			(placement
				(enabled no)
				(sheetname "")
			)
			(fill
				(thermal_gap 0.5)
				(thermal_bridge_width 0.5)
				(island_removal_mode 0)
			)
			(polygon
				(pts
					(arc
						(start 341.952834 -58.58002)
						(mid 342.010693 -58.543789)
						(end 342.047068 -58.48604)
					)
					(arc
						(start 342.152478 -58.48604)
						(mid 342.082721 -58.615849)
						(end 341.952834 -58.68543)
					)
				)
			)
		)
		(zone
			(layer "F.Cu")
			(hatch none 0.5)
			(connect_pads
				(clearance 0)
			)
			(min_thickness 0.25)
			(keepout
				(tracks not_allowed)
				(vias allowed)
				(pads allowed)
				(copperpour not_allowed)
				(footprints allowed)
			)
			(placement
				(enabled no)
				(sheetname "")
			)
			(fill
				(thermal_gap 0.5)
				(thermal_bridge_width 0.5)
				(island_removal_mode 0)
			)
			(polygon
				(pts
					(arc
						(start 341.952834 -57.750202)
						(mid 342.010697 -57.713831)
						(end 342.047068 -57.655968)
					)
					(arc
						(start 342.152478 -57.655968)
						(mid 342.082721 -57.785777)
						(end 341.952834 -57.855358)
					)
				)
			)
		)
		(zone
			(layer "F.Cu")
			(hatch none 0.5)
			(connect_pads
				(clearance 0)
			)
			(min_thickness 0.25)
			(keepout
				(tracks not_allowed)
				(vias allowed)
				(pads allowed)
				(copperpour not_allowed)
				(footprints allowed)
			)
			(placement
				(enabled no)
				(sheetname "")
			)
			(fill
				(thermal_gap 0.5)
				(thermal_bridge_width 0.5)
				(island_removal_mode 0)
			)
			(polygon
				(pts
					(arc
						(start 341.952834 -39.440358)
						(mid 342.010697 -39.403987)
						(end 342.047068 -39.346124)
					)
					(arc
						(start 342.152478 -39.346124)
						(mid 342.082721 -39.475933)
						(end 341.952834 -39.545514)
					)
				)
			)
		)
		(zone
			(layer "F.Cu")
			(hatch none 0.5)
			(connect_pads
				(clearance 0)
			)
			(min_thickness 0.25)
			(keepout
				(tracks not_allowed)
				(vias allowed)
				(pads allowed)
				(copperpour not_allowed)
				(footprints allowed)
			)
			(placement
				(enabled no)
				(sheetname "")
			)
			(fill
				(thermal_gap 0.5)
				(thermal_bridge_width 0.5)
				(island_removal_mode 0)
			)
			(polygon
				(pts
					(arc
						(start 341.953088 -38.610286)
						(mid 342.010951 -38.573915)
						(end 342.047322 -38.516052)
					)
					(arc
						(start 342.152478 -38.516052)
						(mid 342.082809 -38.645773)
						(end 341.953088 -38.715442)
					)
				)
			)
		)
		(zone
			(layer "F.Cu")
			(hatch none 0.5)
			(connect_pads
				(clearance 0)
			)
			(min_thickness 0.25)
			(keepout
				(tracks not_allowed)
				(vias allowed)
				(pads allowed)
				(copperpour not_allowed)
				(footprints allowed)
			)
			(placement
				(enabled no)
				(sheetname "")
			)
			(fill
				(thermal_gap 0.5)
				(thermal_bridge_width 0.5)
				(island_removal_mode 0)
			)
			(polygon
				(pts
					(arc
						(start 342.047068 -58.38444)
						(mid 342.010697 -58.326577)
						(end 341.952834 -58.290206)
					)
					(arc
						(start 341.952834 -58.18505)
						(mid 342.082685 -58.254667)
						(end 342.152478 -58.38444)
					)
				)
			)
		)
		(zone
			(layer "F.Cu")
			(hatch none 0.5)
			(connect_pads
				(clearance 0)
			)
			(min_thickness 0.25)
			(keepout
				(tracks not_allowed)
				(vias allowed)
				(pads allowed)
				(copperpour not_allowed)
				(footprints allowed)
			)
			(placement
				(enabled no)
				(sheetname "")
			)
			(fill
				(thermal_gap 0.5)
				(thermal_bridge_width 0.5)
				(island_removal_mode 0)
			)
			(polygon
				(pts
					(arc
						(start 342.047068 -57.554368)
						(mid 342.010697 -57.496505)
						(end 341.952834 -57.460134)
					)
					(arc
						(start 341.952834 -57.354978)
						(mid 342.082685 -57.424595)
						(end 342.152478 -57.554368)
					)
				)
			)
		)
		(zone
			(layer "F.Cu")
			(hatch none 0.5)
			(connect_pads
				(clearance 0)
			)
			(min_thickness 0.25)
			(keepout
				(tracks not_allowed)
				(vias allowed)
				(pads allowed)
				(copperpour not_allowed)
				(footprints allowed)
			)
			(placement
				(enabled no)
				(sheetname "")
			)
			(fill
				(thermal_gap 0.5)
				(thermal_bridge_width 0.5)
				(island_removal_mode 0)
			)
			(polygon
				(pts
					(arc
						(start 342.047068 -39.244524)
						(mid 342.010697 -39.186661)
						(end 341.952834 -39.15029)
					)
					(arc
						(start 341.952834 -39.045134)
						(mid 342.082685 -39.114751)
						(end 342.152478 -39.244524)
					)
				)
			)
		)
		(zone
			(layer "F.Cu")
			(hatch none 0.5)
			(connect_pads
				(clearance 0)
			)
			(min_thickness 0.25)
			(keepout
				(tracks not_allowed)
				(vias allowed)
				(pads allowed)
				(copperpour not_allowed)
				(footprints allowed)
			)
			(placement
				(enabled no)
				(sheetname "")
			)
			(fill
				(thermal_gap 0.5)
				(thermal_bridge_width 0.5)
				(island_removal_mode 0)
			)
			(polygon
				(pts
					(arc
						(start 342.047322 -38.414452)
						(mid 342.010951 -38.356589)
						(end 341.953088 -38.320218)
					)
					(arc
						(start 341.953088 -38.215062)
						(mid 342.082809 -38.284731)
						(end 342.152478 -38.414452)
					)
				)
			)
		)
		(zone
			(layer "F.Cu")
			(hatch none 0.5)
			(connect_pads
				(clearance 0)
			)
			(min_thickness 0.25)
			(keepout
				(tracks not_allowed)
				(vias allowed)
				(pads allowed)
				(copperpour not_allowed)
				(footprints allowed)
			)
			(placement
				(enabled no)
				(sheetname "")
			)
			(fill
				(thermal_gap 0.5)
				(thermal_bridge_width 0.5)
				(island_removal_mode 0)
			)
			(polygon
				(pts
					(arc
						(start 342.25738 -58.901076)
						(mid 342.293751 -58.958939)
						(end 342.351614 -58.99531)
					)
					(arc
						(start 342.351614 -59.100466)
						(mid 342.221893 -59.030797)
						(end 342.152224 -58.901076)
					)
				)
			)
		)
		(zone
			(layer "F.Cu")
			(hatch none 0.5)
			(connect_pads
				(clearance 0)
			)
			(min_thickness 0.25)
			(keepout
				(tracks not_allowed)
				(vias allowed)
				(pads allowed)
				(copperpour not_allowed)
				(footprints allowed)
			)
			(placement
				(enabled no)
				(sheetname "")
			)
			(fill
				(thermal_gap 0.5)
				(thermal_bridge_width 0.5)
				(island_removal_mode 0)
			)
			(polygon
				(pts
					(arc
						(start 342.25738 -58.071004)
						(mid 342.293751 -58.128867)
						(end 342.351614 -58.165238)
					)
					(arc
						(start 342.351614 -58.270394)
						(mid 342.221893 -58.200725)
						(end 342.152224 -58.071004)
					)
				)
			)
		)
		(zone
			(layer "F.Cu")
			(hatch none 0.5)
			(connect_pads
				(clearance 0)
			)
			(min_thickness 0.25)
			(keepout
				(tracks not_allowed)
				(vias allowed)
				(pads allowed)
				(copperpour not_allowed)
				(footprints allowed)
			)
			(placement
				(enabled no)
				(sheetname "")
			)
			(fill
				(thermal_gap 0.5)
				(thermal_bridge_width 0.5)
				(island_removal_mode 0)
			)
			(polygon
				(pts
					(arc
						(start 342.25738 -38.931088)
						(mid 342.293751 -38.988951)
						(end 342.351614 -39.025322)
					)
					(arc
						(start 342.351614 -39.130478)
						(mid 342.221893 -39.060809)
						(end 342.152224 -38.931088)
					)
				)
			)
		)
		(zone
			(layer "F.Cu")
			(hatch none 0.5)
			(connect_pads
				(clearance 0)
			)
			(min_thickness 0.25)
			(keepout
				(tracks not_allowed)
				(vias allowed)
				(pads allowed)
				(copperpour not_allowed)
				(footprints allowed)
			)
			(placement
				(enabled no)
				(sheetname "")
			)
			(fill
				(thermal_gap 0.5)
				(thermal_bridge_width 0.5)
				(island_removal_mode 0)
			)
			(polygon
				(pts
					(arc
						(start 342.25738 -38.101016)
						(mid 342.293751 -38.158879)
						(end 342.351614 -38.19525)
					)
					(arc
						(start 342.351614 -38.300406)
						(mid 342.221893 -38.230737)
						(end 342.152224 -38.101016)
					)
				)
			)
		)
		(zone
			(layer "F.Cu")
			(hatch none 0.5)
			(connect_pads
				(clearance 0)
			)
			(min_thickness 0.25)
			(keepout
				(tracks not_allowed)
				(vias allowed)
				(pads allowed)
				(copperpour not_allowed)
				(footprints allowed)
			)
			(placement
				(enabled no)
				(sheetname "")
			)
			(fill
				(thermal_gap 0.5)
				(thermal_bridge_width 0.5)
				(island_removal_mode 0)
			)
			(polygon
				(pts
					(arc
						(start 342.351614 -58.705242)
						(mid 342.293751 -58.741613)
						(end 342.25738 -58.799476)
					)
					(arc
						(start 342.152224 -58.799476)
						(mid 342.221893 -58.669755)
						(end 342.351614 -58.600086)
					)
				)
			)
		)
		(zone
			(layer "F.Cu")
			(hatch none 0.5)
			(connect_pads
				(clearance 0)
			)
			(min_thickness 0.25)
			(keepout
				(tracks not_allowed)
				(vias allowed)
				(pads allowed)
				(copperpour not_allowed)
				(footprints allowed)
			)
			(placement
				(enabled no)
				(sheetname "")
			)
			(fill
				(thermal_gap 0.5)
				(thermal_bridge_width 0.5)
				(island_removal_mode 0)
			)
			(polygon
				(pts
					(arc
						(start 342.351614 -57.87517)
						(mid 342.293751 -57.911541)
						(end 342.25738 -57.969404)
					)
					(arc
						(start 342.152224 -57.969404)
						(mid 342.221893 -57.839683)
						(end 342.351614 -57.770014)
					)
				)
			)
		)
		(zone
			(layer "F.Cu")
			(hatch none 0.5)
			(connect_pads
				(clearance 0)
			)
			(min_thickness 0.25)
			(keepout
				(tracks not_allowed)
				(vias allowed)
				(pads allowed)
				(copperpour not_allowed)
				(footprints allowed)
			)
			(placement
				(enabled no)
				(sheetname "")
			)
			(fill
				(thermal_gap 0.5)
				(thermal_bridge_width 0.5)
				(island_removal_mode 0)
			)
			(polygon
				(pts
					(arc
						(start 342.351614 -38.735254)
						(mid 342.293751 -38.771625)
						(end 342.25738 -38.829488)
					)
					(arc
						(start 342.152224 -38.829488)
						(mid 342.221893 -38.699767)
						(end 342.351614 -38.630098)
					)
				)
			)
		)
		(zone
			(layer "F.Cu")
			(hatch none 0.5)
			(connect_pads
				(clearance 0)
			)
			(min_thickness 0.25)
			(keepout
				(tracks not_allowed)
				(vias allowed)
				(pads allowed)
				(copperpour not_allowed)
				(footprints allowed)
			)
			(placement
				(enabled no)
				(sheetname "")
			)
			(fill
				(thermal_gap 0.5)
				(thermal_bridge_width 0.5)
				(island_removal_mode 0)
			)
			(polygon
				(pts
					(arc
						(start 342.351614 -37.905182)
						(mid 342.293751 -37.941553)
						(end 342.25738 -37.999416)
					)
					(arc
						(start 342.152224 -37.999416)
						(mid 342.221893 -37.869695)
						(end 342.351614 -37.800026)
					)
				)
			)
		)
		(zone
			(layer "F.Cu")
			(hatch none 0.5)
			(connect_pads
				(clearance 0)
			)
			(min_thickness 0.25)
			(keepout
				(tracks not_allowed)
				(vias allowed)
				(pads allowed)
				(copperpour not_allowed)
				(footprints allowed)
			)
			(placement
				(enabled no)
				(sheetname "")
			)
			(fill
				(thermal_gap 0.5)
				(thermal_bridge_width 0.5)
				(island_removal_mode 0)
			)
			(polygon
				(pts
					(arc
						(start 342.453214 -58.99531)
						(mid 342.511077 -58.958939)
						(end 342.547448 -58.901076)
					)
					(arc
						(start 342.652604 -58.901076)
						(mid 342.582935 -59.030797)
						(end 342.453214 -59.100466)
					)
				)
			)
		)
		(zone
			(layer "F.Cu")
			(hatch none 0.5)
			(connect_pads
				(clearance 0)
			)
			(min_thickness 0.25)
			(keepout
				(tracks not_allowed)
				(vias allowed)
				(pads allowed)
				(copperpour not_allowed)
				(footprints allowed)
			)
			(placement
				(enabled no)
				(sheetname "")
			)
			(fill
				(thermal_gap 0.5)
				(thermal_bridge_width 0.5)
				(island_removal_mode 0)
			)
			(polygon
				(pts
					(arc
						(start 342.453214 -58.165238)
						(mid 342.511077 -58.128867)
						(end 342.547448 -58.071004)
					)
					(arc
						(start 342.652604 -58.071004)
						(mid 342.582935 -58.200725)
						(end 342.453214 -58.270394)
					)
				)
			)
		)
		(zone
			(layer "F.Cu")
			(hatch none 0.5)
			(connect_pads
				(clearance 0)
			)
			(min_thickness 0.25)
			(keepout
				(tracks not_allowed)
				(vias allowed)
				(pads allowed)
				(copperpour not_allowed)
				(footprints allowed)
			)
			(placement
				(enabled no)
				(sheetname "")
			)
			(fill
				(thermal_gap 0.5)
				(thermal_bridge_width 0.5)
				(island_removal_mode 0)
			)
			(polygon
				(pts
					(arc
						(start 342.453214 -39.025322)
						(mid 342.511077 -38.988951)
						(end 342.547448 -38.931088)
					)
					(arc
						(start 342.652604 -38.931088)
						(mid 342.582935 -39.060809)
						(end 342.453214 -39.130478)
					)
				)
			)
		)
		(zone
			(layer "F.Cu")
			(hatch none 0.5)
			(connect_pads
				(clearance 0)
			)
			(min_thickness 0.25)
			(keepout
				(tracks not_allowed)
				(vias allowed)
				(pads allowed)
				(copperpour not_allowed)
				(footprints allowed)
			)
			(placement
				(enabled no)
				(sheetname "")
			)
			(fill
				(thermal_gap 0.5)
				(thermal_bridge_width 0.5)
				(island_removal_mode 0)
			)
			(polygon
				(pts
					(arc
						(start 342.453214 -38.19525)
						(mid 342.511077 -38.158879)
						(end 342.547448 -38.101016)
					)
					(arc
						(start 342.652604 -38.101016)
						(mid 342.582935 -38.230737)
						(end 342.453214 -38.300406)
					)
				)
			)
		)
		(zone
			(layer "F.Cu")
			(hatch none 0.5)
			(connect_pads
				(clearance 0)
			)
			(min_thickness 0.25)
			(keepout
				(tracks not_allowed)
				(vias allowed)
				(pads allowed)
				(copperpour not_allowed)
				(footprints allowed)
			)
			(placement
				(enabled no)
				(sheetname "")
			)
			(fill
				(thermal_gap 0.5)
				(thermal_bridge_width 0.5)
				(island_removal_mode 0)
			)
			(polygon
				(pts
					(arc
						(start 342.547448 -58.799476)
						(mid 342.511077 -58.741613)
						(end 342.453214 -58.705242)
					)
					(arc
						(start 342.453214 -58.600086)
						(mid 342.582935 -58.669755)
						(end 342.652604 -58.799476)
					)
				)
			)
		)
		(zone
			(layer "F.Cu")
			(hatch none 0.5)
			(connect_pads
				(clearance 0)
			)
			(min_thickness 0.25)
			(keepout
				(tracks not_allowed)
				(vias allowed)
				(pads allowed)
				(copperpour not_allowed)
				(footprints allowed)
			)
			(placement
				(enabled no)
				(sheetname "")
			)
			(fill
				(thermal_gap 0.5)
				(thermal_bridge_width 0.5)
				(island_removal_mode 0)
			)
			(polygon
				(pts
					(arc
						(start 342.547448 -57.969404)
						(mid 342.511077 -57.911541)
						(end 342.453214 -57.87517)
					)
					(arc
						(start 342.453214 -57.770014)
						(mid 342.582935 -57.839683)
						(end 342.652604 -57.969404)
					)
				)
			)
		)
		(zone
			(layer "F.Cu")
			(hatch none 0.5)
			(connect_pads
				(clearance 0)
			)
			(min_thickness 0.25)
			(keepout
				(tracks not_allowed)
				(vias allowed)
				(pads allowed)
				(copperpour not_allowed)
				(footprints allowed)
			)
			(placement
				(enabled no)
				(sheetname "")
			)
			(fill
				(thermal_gap 0.5)
				(thermal_bridge_width 0.5)
				(island_removal_mode 0)
			)
			(polygon
				(pts
					(arc
						(start 342.547448 -38.829488)
						(mid 342.511077 -38.771625)
						(end 342.453214 -38.735254)
					)
					(arc
						(start 342.453214 -38.630098)
						(mid 342.582935 -38.699767)
						(end 342.652604 -38.829488)
					)
				)
			)
		)
		(zone
			(layer "F.Cu")
			(hatch none 0.5)
			(connect_pads
				(clearance 0)
			)
			(min_thickness 0.25)
			(keepout
				(tracks not_allowed)
				(vias allowed)
				(pads allowed)
				(copperpour not_allowed)
				(footprints allowed)
			)
			(placement
				(enabled no)
				(sheetname "")
			)
			(fill
				(thermal_gap 0.5)
				(thermal_bridge_width 0.5)
				(island_removal_mode 0)
			)
			(polygon
				(pts
					(arc
						(start 342.547448 -37.999416)
						(mid 342.511077 -37.941553)
						(end 342.453214 -37.905182)
					)
					(arc
						(start 342.453214 -37.800026)
						(mid 342.582935 -37.869695)
						(end 342.652604 -37.999416)
					)
				)
			)
		)
		(zone
			(layer "F.Cu")
			(hatch none 0.5)
			(connect_pads
				(clearance 0)
			)
			(min_thickness 0.25)
			(keepout
				(tracks not_allowed)
				(vias allowed)
				(pads allowed)
				(copperpour not_allowed)
				(footprints allowed)
			)
			(placement
				(enabled no)
				(sheetname "")
			)
			(fill
				(thermal_gap 0.5)
				(thermal_bridge_width 0.5)
				(island_removal_mode 0)
			)
			(polygon
				(pts
					(arc
						(start 342.75776 -58.48604)
						(mid 342.794046 -58.543734)
						(end 342.85174 -58.58002)
					)
					(arc
						(start 342.85174 -58.68543)
						(mid 342.722019 -58.615761)
						(end 342.65235 -58.48604)
					)
				)
			)
		)
		(zone
			(layer "F.Cu")
			(hatch none 0.5)
			(connect_pads
				(clearance 0)
			)
			(min_thickness 0.25)
			(keepout
				(tracks not_allowed)
				(vias allowed)
				(pads allowed)
				(copperpour not_allowed)
				(footprints allowed)
			)
			(placement
				(enabled no)
				(sheetname "")
			)
			(fill
				(thermal_gap 0.5)
				(thermal_bridge_width 0.5)
				(island_removal_mode 0)
			)
			(polygon
				(pts
					(arc
						(start 342.75776 -57.655968)
						(mid 342.794046 -57.713747)
						(end 342.85174 -57.750202)
					)
					(arc
						(start 342.85174 -57.855358)
						(mid 342.722019 -57.785689)
						(end 342.65235 -57.655968)
					)
				)
			)
		)
		(zone
			(layer "F.Cu")
			(hatch none 0.5)
			(connect_pads
				(clearance 0)
			)
			(min_thickness 0.25)
			(keepout
				(tracks not_allowed)
				(vias allowed)
				(pads allowed)
				(copperpour not_allowed)
				(footprints allowed)
			)
			(placement
				(enabled no)
				(sheetname "")
			)
			(fill
				(thermal_gap 0.5)
				(thermal_bridge_width 0.5)
				(island_removal_mode 0)
			)
			(polygon
				(pts
					(arc
						(start 342.75776 -39.346124)
						(mid 342.793991 -39.403983)
						(end 342.85174 -39.440358)
					)
					(arc
						(start 342.85174 -39.545514)
						(mid 342.722019 -39.475845)
						(end 342.65235 -39.346124)
					)
				)
			)
		)
		(zone
			(layer "F.Cu")
			(hatch none 0.5)
			(connect_pads
				(clearance 0)
			)
			(min_thickness 0.25)
			(keepout
				(tracks not_allowed)
				(vias allowed)
				(pads allowed)
				(copperpour not_allowed)
				(footprints allowed)
			)
			(placement
				(enabled no)
				(sheetname "")
			)
			(fill
				(thermal_gap 0.5)
				(thermal_bridge_width 0.5)
				(island_removal_mode 0)
			)
			(polygon
				(pts
					(arc
						(start 342.75776 -38.516052)
						(mid 342.793991 -38.573911)
						(end 342.85174 -38.610286)
					)
					(arc
						(start 342.85174 -38.715442)
						(mid 342.722019 -38.645773)
						(end 342.65235 -38.516052)
					)
				)
			)
		)
		(zone
			(layer "F.Cu")
			(hatch none 0.5)
			(connect_pads
				(clearance 0)
			)
			(min_thickness 0.25)
			(keepout
				(tracks not_allowed)
				(vias allowed)
				(pads allowed)
				(copperpour not_allowed)
				(footprints allowed)
			)
			(placement
				(enabled no)
				(sheetname "")
			)
			(fill
				(thermal_gap 0.5)
				(thermal_bridge_width 0.5)
				(island_removal_mode 0)
			)
			(polygon
				(pts
					(arc
						(start 342.85174 -58.290206)
						(mid 342.794041 -58.326632)
						(end 342.75776 -58.38444)
					)
					(arc
						(start 342.65235 -58.38444)
						(mid 342.722019 -58.254719)
						(end 342.85174 -58.18505)
					)
				)
			)
		)
		(zone
			(layer "F.Cu")
			(hatch none 0.5)
			(connect_pads
				(clearance 0)
			)
			(min_thickness 0.25)
			(keepout
				(tracks not_allowed)
				(vias allowed)
				(pads allowed)
				(copperpour not_allowed)
				(footprints allowed)
			)
			(placement
				(enabled no)
				(sheetname "")
			)
			(fill
				(thermal_gap 0.5)
				(thermal_bridge_width 0.5)
				(island_removal_mode 0)
			)
			(polygon
				(pts
					(arc
						(start 342.85174 -57.460134)
						(mid 342.794041 -57.49656)
						(end 342.75776 -57.554368)
					)
					(arc
						(start 342.65235 -57.554368)
						(mid 342.722019 -57.424647)
						(end 342.85174 -57.354978)
					)
				)
			)
		)
		(zone
			(layer "F.Cu")
			(hatch none 0.5)
			(connect_pads
				(clearance 0)
			)
			(min_thickness 0.25)
			(keepout
				(tracks not_allowed)
				(vias allowed)
				(pads allowed)
				(copperpour not_allowed)
				(footprints allowed)
			)
			(placement
				(enabled no)
				(sheetname "")
			)
			(fill
				(thermal_gap 0.5)
				(thermal_bridge_width 0.5)
				(island_removal_mode 0)
			)
			(polygon
				(pts
					(arc
						(start 342.85174 -39.15029)
						(mid 342.793986 -39.186686)
						(end 342.75776 -39.244524)
					)
					(arc
						(start 342.65235 -39.244524)
						(mid 342.722019 -39.114803)
						(end 342.85174 -39.045134)
					)
				)
			)
		)
		(zone
			(layer "F.Cu")
			(hatch none 0.5)
			(connect_pads
				(clearance 0)
			)
			(min_thickness 0.25)
			(keepout
				(tracks not_allowed)
				(vias allowed)
				(pads allowed)
				(copperpour not_allowed)
				(footprints allowed)
			)
			(placement
				(enabled no)
				(sheetname "")
			)
			(fill
				(thermal_gap 0.5)
				(thermal_bridge_width 0.5)
				(island_removal_mode 0)
			)
			(polygon
				(pts
					(arc
						(start 342.85174 -38.320218)
						(mid 342.794041 -38.356644)
						(end 342.75776 -38.414452)
					)
					(arc
						(start 342.65235 -38.414452)
						(mid 342.722019 -38.284731)
						(end 342.85174 -38.215062)
					)
				)
			)
		)
		(zone
			(layer "F.Cu")
			(hatch none 0.5)
			(connect_pads
				(clearance 0)
			)
			(min_thickness 0.25)
			(keepout
				(tracks not_allowed)
				(vias allowed)
				(pads allowed)
				(copperpour not_allowed)
				(footprints allowed)
			)
			(placement
				(enabled no)
				(sheetname "")
			)
			(fill
				(thermal_gap 0.5)
				(thermal_bridge_width 0.5)
				(island_removal_mode 0)
			)
			(polygon
				(pts
					(arc
						(start 342.95334 -58.58002)
						(mid 343.011199 -58.543789)
						(end 343.047574 -58.48604)
					)
					(arc
						(start 343.152984 -58.48604)
						(mid 343.083227 -58.615849)
						(end 342.95334 -58.68543)
					)
				)
			)
		)
		(zone
			(layer "F.Cu")
			(hatch none 0.5)
			(connect_pads
				(clearance 0)
			)
			(min_thickness 0.25)
			(keepout
				(tracks not_allowed)
				(vias allowed)
				(pads allowed)
				(copperpour not_allowed)
				(footprints allowed)
			)
			(placement
				(enabled no)
				(sheetname "")
			)
			(fill
				(thermal_gap 0.5)
				(thermal_bridge_width 0.5)
				(island_removal_mode 0)
			)
			(polygon
				(pts
					(arc
						(start 342.95334 -57.750202)
						(mid 343.011203 -57.713831)
						(end 343.047574 -57.655968)
					)
					(arc
						(start 343.152984 -57.655968)
						(mid 343.083227 -57.785777)
						(end 342.95334 -57.855358)
					)
				)
			)
		)
		(zone
			(layer "F.Cu")
			(hatch none 0.5)
			(connect_pads
				(clearance 0)
			)
			(min_thickness 0.25)
			(keepout
				(tracks not_allowed)
				(vias allowed)
				(pads allowed)
				(copperpour not_allowed)
				(footprints allowed)
			)
			(placement
				(enabled no)
				(sheetname "")
			)
			(fill
				(thermal_gap 0.5)
				(thermal_bridge_width 0.5)
				(island_removal_mode 0)
			)
			(polygon
				(pts
					(arc
						(start 342.95334 -39.440358)
						(mid 343.011203 -39.403987)
						(end 343.047574 -39.346124)
					)
					(arc
						(start 343.152984 -39.346124)
						(mid 343.083227 -39.475933)
						(end 342.95334 -39.545514)
					)
				)
			)
		)
		(zone
			(layer "F.Cu")
			(hatch none 0.5)
			(connect_pads
				(clearance 0)
			)
			(min_thickness 0.25)
			(keepout
				(tracks not_allowed)
				(vias allowed)
				(pads allowed)
				(copperpour not_allowed)
				(footprints allowed)
			)
			(placement
				(enabled no)
				(sheetname "")
			)
			(fill
				(thermal_gap 0.5)
				(thermal_bridge_width 0.5)
				(island_removal_mode 0)
			)
			(polygon
				(pts
					(arc
						(start 342.95334 -38.610286)
						(mid 343.011203 -38.573915)
						(end 343.047574 -38.516052)
					)
					(arc
						(start 343.152984 -38.516052)
						(mid 343.083227 -38.645861)
						(end 342.95334 -38.715442)
					)
				)
			)
		)
		(zone
			(layer "F.Cu")
			(hatch none 0.5)
			(connect_pads
				(clearance 0)
			)
			(min_thickness 0.25)
			(keepout
				(tracks not_allowed)
				(vias allowed)
				(pads allowed)
				(copperpour not_allowed)
				(footprints allowed)
			)
			(placement
				(enabled no)
				(sheetname "")
			)
			(fill
				(thermal_gap 0.5)
				(thermal_bridge_width 0.5)
				(island_removal_mode 0)
			)
			(polygon
				(pts
					(arc
						(start 343.047574 -58.38444)
						(mid 343.011203 -58.326577)
						(end 342.95334 -58.290206)
					)
					(arc
						(start 342.95334 -58.18505)
						(mid 343.083191 -58.254667)
						(end 343.152984 -58.38444)
					)
				)
			)
		)
		(zone
			(layer "F.Cu")
			(hatch none 0.5)
			(connect_pads
				(clearance 0)
			)
			(min_thickness 0.25)
			(keepout
				(tracks not_allowed)
				(vias allowed)
				(pads allowed)
				(copperpour not_allowed)
				(footprints allowed)
			)
			(placement
				(enabled no)
				(sheetname "")
			)
			(fill
				(thermal_gap 0.5)
				(thermal_bridge_width 0.5)
				(island_removal_mode 0)
			)
			(polygon
				(pts
					(arc
						(start 343.047574 -57.554368)
						(mid 343.011203 -57.496505)
						(end 342.95334 -57.460134)
					)
					(arc
						(start 342.95334 -57.354978)
						(mid 343.083191 -57.424595)
						(end 343.152984 -57.554368)
					)
				)
			)
		)
		(zone
			(layer "F.Cu")
			(hatch none 0.5)
			(connect_pads
				(clearance 0)
			)
			(min_thickness 0.25)
			(keepout
				(tracks not_allowed)
				(vias allowed)
				(pads allowed)
				(copperpour not_allowed)
				(footprints allowed)
			)
			(placement
				(enabled no)
				(sheetname "")
			)
			(fill
				(thermal_gap 0.5)
				(thermal_bridge_width 0.5)
				(island_removal_mode 0)
			)
			(polygon
				(pts
					(arc
						(start 343.047574 -39.244524)
						(mid 343.011203 -39.186661)
						(end 342.95334 -39.15029)
					)
					(arc
						(start 342.95334 -39.045134)
						(mid 343.083191 -39.114751)
						(end 343.152984 -39.244524)
					)
				)
			)
		)
		(zone
			(layer "F.Cu")
			(hatch none 0.5)
			(connect_pads
				(clearance 0)
			)
			(min_thickness 0.25)
			(keepout
				(tracks not_allowed)
				(vias allowed)
				(pads allowed)
				(copperpour not_allowed)
				(footprints allowed)
			)
			(placement
				(enabled no)
				(sheetname "")
			)
			(fill
				(thermal_gap 0.5)
				(thermal_bridge_width 0.5)
				(island_removal_mode 0)
			)
			(polygon
				(pts
					(arc
						(start 343.047574 -38.414452)
						(mid 343.011203 -38.356589)
						(end 342.95334 -38.320218)
					)
					(arc
						(start 342.95334 -38.215062)
						(mid 343.083191 -38.284679)
						(end 343.152984 -38.414452)
					)
				)
			)
		)
		(zone
			(layer "F.Cu")
			(hatch none 0.5)
			(connect_pads
				(clearance 0)
			)
			(min_thickness 0.25)
			(keepout
				(tracks not_allowed)
				(vias allowed)
				(pads allowed)
				(copperpour not_allowed)
				(footprints allowed)
			)
			(placement
				(enabled no)
				(sheetname "")
			)
			(fill
				(thermal_gap 0.5)
				(thermal_bridge_width 0.5)
				(island_removal_mode 0)
			)
			(polygon
				(pts
					(arc
						(start 343.257886 -58.901076)
						(mid 343.294257 -58.958939)
						(end 343.35212 -58.99531)
					)
					(arc
						(start 343.35212 -59.100466)
						(mid 343.222399 -59.030797)
						(end 343.15273 -58.901076)
					)
				)
			)
		)
		(zone
			(layer "F.Cu")
			(hatch none 0.5)
			(connect_pads
				(clearance 0)
			)
			(min_thickness 0.25)
			(keepout
				(tracks not_allowed)
				(vias allowed)
				(pads allowed)
				(copperpour not_allowed)
				(footprints allowed)
			)
			(placement
				(enabled no)
				(sheetname "")
			)
			(fill
				(thermal_gap 0.5)
				(thermal_bridge_width 0.5)
				(island_removal_mode 0)
			)
			(polygon
				(pts
					(arc
						(start 343.257886 -58.071004)
						(mid 343.294257 -58.128867)
						(end 343.35212 -58.165238)
					)
					(arc
						(start 343.35212 -58.270394)
						(mid 343.222399 -58.200725)
						(end 343.15273 -58.071004)
					)
				)
			)
		)
		(zone
			(layer "F.Cu")
			(hatch none 0.5)
			(connect_pads
				(clearance 0)
			)
			(min_thickness 0.25)
			(keepout
				(tracks not_allowed)
				(vias allowed)
				(pads allowed)
				(copperpour not_allowed)
				(footprints allowed)
			)
			(placement
				(enabled no)
				(sheetname "")
			)
			(fill
				(thermal_gap 0.5)
				(thermal_bridge_width 0.5)
				(island_removal_mode 0)
			)
			(polygon
				(pts
					(arc
						(start 343.257886 -38.931088)
						(mid 343.294257 -38.988951)
						(end 343.35212 -39.025322)
					)
					(arc
						(start 343.35212 -39.130478)
						(mid 343.222399 -39.060809)
						(end 343.15273 -38.931088)
					)
				)
			)
		)
		(zone
			(layer "F.Cu")
			(hatch none 0.5)
			(connect_pads
				(clearance 0)
			)
			(min_thickness 0.25)
			(keepout
				(tracks not_allowed)
				(vias allowed)
				(pads allowed)
				(copperpour not_allowed)
				(footprints allowed)
			)
			(placement
				(enabled no)
				(sheetname "")
			)
			(fill
				(thermal_gap 0.5)
				(thermal_bridge_width 0.5)
				(island_removal_mode 0)
			)
			(polygon
				(pts
					(arc
						(start 343.257886 -38.101016)
						(mid 343.294257 -38.158879)
						(end 343.35212 -38.19525)
					)
					(arc
						(start 343.35212 -38.300406)
						(mid 343.222399 -38.230737)
						(end 343.15273 -38.101016)
					)
				)
			)
		)
		(zone
			(layer "F.Cu")
			(hatch none 0.5)
			(connect_pads
				(clearance 0)
			)
			(min_thickness 0.25)
			(keepout
				(tracks not_allowed)
				(vias allowed)
				(pads allowed)
				(copperpour not_allowed)
				(footprints allowed)
			)
			(placement
				(enabled no)
				(sheetname "")
			)
			(fill
				(thermal_gap 0.5)
				(thermal_bridge_width 0.5)
				(island_removal_mode 0)
			)
			(polygon
				(pts
					(arc
						(start 343.35212 -58.705242)
						(mid 343.294257 -58.741613)
						(end 343.257886 -58.799476)
					)
					(arc
						(start 343.15273 -58.799476)
						(mid 343.222399 -58.669755)
						(end 343.35212 -58.600086)
					)
				)
			)
		)
		(zone
			(layer "F.Cu")
			(hatch none 0.5)
			(connect_pads
				(clearance 0)
			)
			(min_thickness 0.25)
			(keepout
				(tracks not_allowed)
				(vias allowed)
				(pads allowed)
				(copperpour not_allowed)
				(footprints allowed)
			)
			(placement
				(enabled no)
				(sheetname "")
			)
			(fill
				(thermal_gap 0.5)
				(thermal_bridge_width 0.5)
				(island_removal_mode 0)
			)
			(polygon
				(pts
					(arc
						(start 343.35212 -57.87517)
						(mid 343.294257 -57.911541)
						(end 343.257886 -57.969404)
					)
					(arc
						(start 343.15273 -57.969404)
						(mid 343.222399 -57.839683)
						(end 343.35212 -57.770014)
					)
				)
			)
		)
		(zone
			(layer "F.Cu")
			(hatch none 0.5)
			(connect_pads
				(clearance 0)
			)
			(min_thickness 0.25)
			(keepout
				(tracks not_allowed)
				(vias allowed)
				(pads allowed)
				(copperpour not_allowed)
				(footprints allowed)
			)
			(placement
				(enabled no)
				(sheetname "")
			)
			(fill
				(thermal_gap 0.5)
				(thermal_bridge_width 0.5)
				(island_removal_mode 0)
			)
			(polygon
				(pts
					(arc
						(start 343.35212 -38.735254)
						(mid 343.294257 -38.771625)
						(end 343.257886 -38.829488)
					)
					(arc
						(start 343.15273 -38.829488)
						(mid 343.222399 -38.699767)
						(end 343.35212 -38.630098)
					)
				)
			)
		)
		(zone
			(layer "F.Cu")
			(hatch none 0.5)
			(connect_pads
				(clearance 0)
			)
			(min_thickness 0.25)
			(keepout
				(tracks not_allowed)
				(vias allowed)
				(pads allowed)
				(copperpour not_allowed)
				(footprints allowed)
			)
			(placement
				(enabled no)
				(sheetname "")
			)
			(fill
				(thermal_gap 0.5)
				(thermal_bridge_width 0.5)
				(island_removal_mode 0)
			)
			(polygon
				(pts
					(arc
						(start 343.35212 -37.905182)
						(mid 343.294257 -37.941553)
						(end 343.257886 -37.999416)
					)
					(arc
						(start 343.15273 -37.999416)
						(mid 343.222399 -37.869695)
						(end 343.35212 -37.800026)
					)
				)
			)
		)
		(zone
			(layer "F.Cu")
			(hatch none 0.5)
			(connect_pads
				(clearance 0)
			)
			(min_thickness 0.25)
			(keepout
				(tracks not_allowed)
				(vias allowed)
				(pads allowed)
				(copperpour not_allowed)
				(footprints allowed)
			)
			(placement
				(enabled no)
				(sheetname "")
			)
			(fill
				(thermal_gap 0.5)
				(thermal_bridge_width 0.5)
				(island_removal_mode 0)
			)
			(polygon
				(pts
					(arc
						(start 343.45372 -58.99531)
						(mid 343.511583 -58.958939)
						(end 343.547954 -58.901076)
					)
					(arc
						(start 343.65311 -58.901076)
						(mid 343.583441 -59.030797)
						(end 343.45372 -59.100466)
					)
				)
			)
		)
		(zone
			(layer "F.Cu")
			(hatch none 0.5)
			(connect_pads
				(clearance 0)
			)
			(min_thickness 0.25)
			(keepout
				(tracks not_allowed)
				(vias allowed)
				(pads allowed)
				(copperpour not_allowed)
				(footprints allowed)
			)
			(placement
				(enabled no)
				(sheetname "")
			)
			(fill
				(thermal_gap 0.5)
				(thermal_bridge_width 0.5)
				(island_removal_mode 0)
			)
			(polygon
				(pts
					(arc
						(start 343.45372 -58.165238)
						(mid 343.511583 -58.128867)
						(end 343.547954 -58.071004)
					)
					(arc
						(start 343.65311 -58.071004)
						(mid 343.583441 -58.200725)
						(end 343.45372 -58.270394)
					)
				)
			)
		)
		(zone
			(layer "F.Cu")
			(hatch none 0.5)
			(connect_pads
				(clearance 0)
			)
			(min_thickness 0.25)
			(keepout
				(tracks not_allowed)
				(vias allowed)
				(pads allowed)
				(copperpour not_allowed)
				(footprints allowed)
			)
			(placement
				(enabled no)
				(sheetname "")
			)
			(fill
				(thermal_gap 0.5)
				(thermal_bridge_width 0.5)
				(island_removal_mode 0)
			)
			(polygon
				(pts
					(arc
						(start 343.45372 -39.025322)
						(mid 343.511583 -38.988951)
						(end 343.547954 -38.931088)
					)
					(arc
						(start 343.65311 -38.931088)
						(mid 343.583441 -39.060809)
						(end 343.45372 -39.130478)
					)
				)
			)
		)
		(zone
			(layer "F.Cu")
			(hatch none 0.5)
			(connect_pads
				(clearance 0)
			)
			(min_thickness 0.25)
			(keepout
				(tracks not_allowed)
				(vias allowed)
				(pads allowed)
				(copperpour not_allowed)
				(footprints allowed)
			)
			(placement
				(enabled no)
				(sheetname "")
			)
			(fill
				(thermal_gap 0.5)
				(thermal_bridge_width 0.5)
				(island_removal_mode 0)
			)
			(polygon
				(pts
					(arc
						(start 343.45372 -38.19525)
						(mid 343.511583 -38.158879)
						(end 343.547954 -38.101016)
					)
					(arc
						(start 343.65311 -38.101016)
						(mid 343.583441 -38.230737)
						(end 343.45372 -38.300406)
					)
				)
			)
		)
		(zone
			(layer "F.Cu")
			(hatch none 0.5)
			(connect_pads
				(clearance 0)
			)
			(min_thickness 0.25)
			(keepout
				(tracks not_allowed)
				(vias allowed)
				(pads allowed)
				(copperpour not_allowed)
				(footprints allowed)
			)
			(placement
				(enabled no)
				(sheetname "")
			)
			(fill
				(thermal_gap 0.5)
				(thermal_bridge_width 0.5)
				(island_removal_mode 0)
			)
			(polygon
				(pts
					(arc
						(start 343.547954 -58.799476)
						(mid 343.511583 -58.741613)
						(end 343.45372 -58.705242)
					)
					(arc
						(start 343.45372 -58.600086)
						(mid 343.583441 -58.669755)
						(end 343.65311 -58.799476)
					)
				)
			)
		)
		(zone
			(layer "F.Cu")
			(hatch none 0.5)
			(connect_pads
				(clearance 0)
			)
			(min_thickness 0.25)
			(keepout
				(tracks not_allowed)
				(vias allowed)
				(pads allowed)
				(copperpour not_allowed)
				(footprints allowed)
			)
			(placement
				(enabled no)
				(sheetname "")
			)
			(fill
				(thermal_gap 0.5)
				(thermal_bridge_width 0.5)
				(island_removal_mode 0)
			)
			(polygon
				(pts
					(arc
						(start 343.547954 -57.969404)
						(mid 343.511583 -57.911541)
						(end 343.45372 -57.87517)
					)
					(arc
						(start 343.45372 -57.770014)
						(mid 343.583441 -57.839683)
						(end 343.65311 -57.969404)
					)
				)
			)
		)
		(zone
			(layer "F.Cu")
			(hatch none 0.5)
			(connect_pads
				(clearance 0)
			)
			(min_thickness 0.25)
			(keepout
				(tracks not_allowed)
				(vias allowed)
				(pads allowed)
				(copperpour not_allowed)
				(footprints allowed)
			)
			(placement
				(enabled no)
				(sheetname "")
			)
			(fill
				(thermal_gap 0.5)
				(thermal_bridge_width 0.5)
				(island_removal_mode 0)
			)
			(polygon
				(pts
					(arc
						(start 343.547954 -38.829488)
						(mid 343.511583 -38.771625)
						(end 343.45372 -38.735254)
					)
					(arc
						(start 343.45372 -38.630098)
						(mid 343.583441 -38.699767)
						(end 343.65311 -38.829488)
					)
				)
			)
		)
		(zone
			(layer "F.Cu")
			(hatch none 0.5)
			(connect_pads
				(clearance 0)
			)
			(min_thickness 0.25)
			(keepout
				(tracks not_allowed)
				(vias allowed)
				(pads allowed)
				(copperpour not_allowed)
				(footprints allowed)
			)
			(placement
				(enabled no)
				(sheetname "")
			)
			(fill
				(thermal_gap 0.5)
				(thermal_bridge_width 0.5)
				(island_removal_mode 0)
			)
			(polygon
				(pts
					(arc
						(start 343.547954 -37.999416)
						(mid 343.511583 -37.941553)
						(end 343.45372 -37.905182)
					)
					(arc
						(start 343.45372 -37.800026)
						(mid 343.583441 -37.869695)
						(end 343.65311 -37.999416)
					)
				)
			)
		)
		(zone
			(layer "F.Cu")
			(hatch none 0.5)
			(connect_pads
				(clearance 0)
			)
			(min_thickness 0.25)
			(keepout
				(tracks not_allowed)
				(vias allowed)
				(pads allowed)
				(copperpour not_allowed)
				(footprints allowed)
			)
			(placement
				(enabled no)
				(sheetname "")
			)
			(fill
				(thermal_gap 0.5)
				(thermal_bridge_width 0.5)
				(island_removal_mode 0)
			)
			(polygon
				(pts
					(arc
						(start 343.758266 -58.48604)
						(mid 343.794552 -58.543734)
						(end 343.852246 -58.58002)
					)
					(arc
						(start 343.852246 -58.68543)
						(mid 343.722525 -58.615761)
						(end 343.652856 -58.48604)
					)
				)
			)
		)
		(zone
			(layer "F.Cu")
			(hatch none 0.5)
			(connect_pads
				(clearance 0)
			)
			(min_thickness 0.25)
			(keepout
				(tracks not_allowed)
				(vias allowed)
				(pads allowed)
				(copperpour not_allowed)
				(footprints allowed)
			)
			(placement
				(enabled no)
				(sheetname "")
			)
			(fill
				(thermal_gap 0.5)
				(thermal_bridge_width 0.5)
				(island_removal_mode 0)
			)
			(polygon
				(pts
					(arc
						(start 343.758266 -57.655968)
						(mid 343.794497 -57.713827)
						(end 343.852246 -57.750202)
					)
					(arc
						(start 343.852246 -57.855358)
						(mid 343.722525 -57.785689)
						(end 343.652856 -57.655968)
					)
				)
			)
		)
		(zone
			(layer "F.Cu")
			(hatch none 0.5)
			(connect_pads
				(clearance 0)
			)
			(min_thickness 0.25)
			(keepout
				(tracks not_allowed)
				(vias allowed)
				(pads allowed)
				(copperpour not_allowed)
				(footprints allowed)
			)
			(placement
				(enabled no)
				(sheetname "")
			)
			(fill
				(thermal_gap 0.5)
				(thermal_bridge_width 0.5)
				(island_removal_mode 0)
			)
			(polygon
				(pts
					(arc
						(start 343.758266 -39.346124)
						(mid 343.794497 -39.403983)
						(end 343.852246 -39.440358)
					)
					(arc
						(start 343.852246 -39.545514)
						(mid 343.722525 -39.475845)
						(end 343.652856 -39.346124)
					)
				)
			)
		)
		(zone
			(layer "F.Cu")
			(hatch none 0.5)
			(connect_pads
				(clearance 0)
			)
			(min_thickness 0.25)
			(keepout
				(tracks not_allowed)
				(vias allowed)
				(pads allowed)
				(copperpour not_allowed)
				(footprints allowed)
			)
			(placement
				(enabled no)
				(sheetname "")
			)
			(fill
				(thermal_gap 0.5)
				(thermal_bridge_width 0.5)
				(island_removal_mode 0)
			)
			(polygon
				(pts
					(arc
						(start 343.758266 -38.516052)
						(mid 343.794497 -38.573911)
						(end 343.852246 -38.610286)
					)
					(arc
						(start 343.852246 -38.715442)
						(mid 343.722525 -38.645773)
						(end 343.652856 -38.516052)
					)
				)
			)
		)
		(zone
			(layer "F.Cu")
			(hatch none 0.5)
			(connect_pads
				(clearance 0)
			)
			(min_thickness 0.25)
			(keepout
				(tracks not_allowed)
				(vias allowed)
				(pads allowed)
				(copperpour not_allowed)
				(footprints allowed)
			)
			(placement
				(enabled no)
				(sheetname "")
			)
			(fill
				(thermal_gap 0.5)
				(thermal_bridge_width 0.5)
				(island_removal_mode 0)
			)
			(polygon
				(pts
					(arc
						(start 343.852246 -58.290206)
						(mid 343.794547 -58.326632)
						(end 343.758266 -58.38444)
					)
					(arc
						(start 343.652856 -58.38444)
						(mid 343.722525 -58.254719)
						(end 343.852246 -58.18505)
					)
				)
			)
		)
		(zone
			(layer "F.Cu")
			(hatch none 0.5)
			(connect_pads
				(clearance 0)
			)
			(min_thickness 0.25)
			(keepout
				(tracks not_allowed)
				(vias allowed)
				(pads allowed)
				(copperpour not_allowed)
				(footprints allowed)
			)
			(placement
				(enabled no)
				(sheetname "")
			)
			(fill
				(thermal_gap 0.5)
				(thermal_bridge_width 0.5)
				(island_removal_mode 0)
			)
			(polygon
				(pts
					(arc
						(start 343.852246 -57.460134)
						(mid 343.794547 -57.49656)
						(end 343.758266 -57.554368)
					)
					(arc
						(start 343.652856 -57.554368)
						(mid 343.722525 -57.424647)
						(end 343.852246 -57.354978)
					)
				)
			)
		)
		(zone
			(layer "F.Cu")
			(hatch none 0.5)
			(connect_pads
				(clearance 0)
			)
			(min_thickness 0.25)
			(keepout
				(tracks not_allowed)
				(vias allowed)
				(pads allowed)
				(copperpour not_allowed)
				(footprints allowed)
			)
			(placement
				(enabled no)
				(sheetname "")
			)
			(fill
				(thermal_gap 0.5)
				(thermal_bridge_width 0.5)
				(island_removal_mode 0)
			)
			(polygon
				(pts
					(arc
						(start 343.852246 -39.15029)
						(mid 343.794547 -39.186716)
						(end 343.758266 -39.244524)
					)
					(arc
						(start 343.652856 -39.244524)
						(mid 343.722525 -39.114803)
						(end 343.852246 -39.045134)
					)
				)
			)
		)
		(zone
			(layer "F.Cu")
			(hatch none 0.5)
			(connect_pads
				(clearance 0)
			)
			(min_thickness 0.25)
			(keepout
				(tracks not_allowed)
				(vias allowed)
				(pads allowed)
				(copperpour not_allowed)
				(footprints allowed)
			)
			(placement
				(enabled no)
				(sheetname "")
			)
			(fill
				(thermal_gap 0.5)
				(thermal_bridge_width 0.5)
				(island_removal_mode 0)
			)
			(polygon
				(pts
					(arc
						(start 343.852246 -38.320218)
						(mid 343.794547 -38.356644)
						(end 343.758266 -38.414452)
					)
					(arc
						(start 343.652856 -38.414452)
						(mid 343.722525 -38.284731)
						(end 343.852246 -38.215062)
					)
				)
			)
		)
		(zone
			(layer "F.Cu")
			(hatch none 0.5)
			(connect_pads
				(clearance 0)
			)
			(min_thickness 0.25)
			(keepout
				(tracks not_allowed)
				(vias allowed)
				(pads allowed)
				(copperpour not_allowed)
				(footprints allowed)
			)
			(placement
				(enabled no)
				(sheetname "")
			)
			(fill
				(thermal_gap 0.5)
				(thermal_bridge_width 0.5)
				(island_removal_mode 0)
			)
			(polygon
				(pts
					(arc
						(start 343.953846 -58.58002)
						(mid 344.011705 -58.543789)
						(end 344.04808 -58.48604)
					)
					(arc
						(start 344.153236 -58.48604)
						(mid 344.083567 -58.615761)
						(end 343.953846 -58.68543)
					)
				)
			)
		)
		(zone
			(layer "F.Cu")
			(hatch none 0.5)
			(connect_pads
				(clearance 0)
			)
			(min_thickness 0.25)
			(keepout
				(tracks not_allowed)
				(vias allowed)
				(pads allowed)
				(copperpour not_allowed)
				(footprints allowed)
			)
			(placement
				(enabled no)
				(sheetname "")
			)
			(fill
				(thermal_gap 0.5)
				(thermal_bridge_width 0.5)
				(island_removal_mode 0)
			)
			(polygon
				(pts
					(arc
						(start 343.953846 -57.750202)
						(mid 344.011709 -57.713831)
						(end 344.04808 -57.655968)
					)
					(arc
						(start 344.153236 -57.655968)
						(mid 344.083567 -57.785689)
						(end 343.953846 -57.855358)
					)
				)
			)
		)
		(zone
			(layer "F.Cu")
			(hatch none 0.5)
			(connect_pads
				(clearance 0)
			)
			(min_thickness 0.25)
			(keepout
				(tracks not_allowed)
				(vias allowed)
				(pads allowed)
				(copperpour not_allowed)
				(footprints allowed)
			)
			(placement
				(enabled no)
				(sheetname "")
			)
			(fill
				(thermal_gap 0.5)
				(thermal_bridge_width 0.5)
				(island_removal_mode 0)
			)
			(polygon
				(pts
					(arc
						(start 343.953846 -39.440358)
						(mid 344.011709 -39.403987)
						(end 344.04808 -39.346124)
					)
					(arc
						(start 344.153236 -39.346124)
						(mid 344.083567 -39.475845)
						(end 343.953846 -39.545514)
					)
				)
			)
		)
		(zone
			(layer "F.Cu")
			(hatch none 0.5)
			(connect_pads
				(clearance 0)
			)
			(min_thickness 0.25)
			(keepout
				(tracks not_allowed)
				(vias allowed)
				(pads allowed)
				(copperpour not_allowed)
				(footprints allowed)
			)
			(placement
				(enabled no)
				(sheetname "")
			)
			(fill
				(thermal_gap 0.5)
				(thermal_bridge_width 0.5)
				(island_removal_mode 0)
			)
			(polygon
				(pts
					(arc
						(start 343.953846 -38.610286)
						(mid 344.011709 -38.573915)
						(end 344.04808 -38.516052)
					)
					(arc
						(start 344.153236 -38.516052)
						(mid 344.083567 -38.645773)
						(end 343.953846 -38.715442)
					)
				)
			)
		)
		(zone
			(layer "F.Cu")
			(hatch none 0.5)
			(connect_pads
				(clearance 0)
			)
			(min_thickness 0.25)
			(keepout
				(tracks not_allowed)
				(vias allowed)
				(pads allowed)
				(copperpour not_allowed)
				(footprints allowed)
			)
			(placement
				(enabled no)
				(sheetname "")
			)
			(fill
				(thermal_gap 0.5)
				(thermal_bridge_width 0.5)
				(island_removal_mode 0)
			)
			(polygon
				(pts
					(arc
						(start 344.04808 -58.38444)
						(mid 344.011709 -58.326577)
						(end 343.953846 -58.290206)
					)
					(arc
						(start 343.953846 -58.18505)
						(mid 344.083567 -58.254719)
						(end 344.153236 -58.38444)
					)
				)
			)
		)
		(zone
			(layer "F.Cu")
			(hatch none 0.5)
			(connect_pads
				(clearance 0)
			)
			(min_thickness 0.25)
			(keepout
				(tracks not_allowed)
				(vias allowed)
				(pads allowed)
				(copperpour not_allowed)
				(footprints allowed)
			)
			(placement
				(enabled no)
				(sheetname "")
			)
			(fill
				(thermal_gap 0.5)
				(thermal_bridge_width 0.5)
				(island_removal_mode 0)
			)
			(polygon
				(pts
					(arc
						(start 344.04808 -57.554368)
						(mid 344.011709 -57.496505)
						(end 343.953846 -57.460134)
					)
					(arc
						(start 343.953846 -57.354978)
						(mid 344.083567 -57.424647)
						(end 344.153236 -57.554368)
					)
				)
			)
		)
		(zone
			(layer "F.Cu")
			(hatch none 0.5)
			(connect_pads
				(clearance 0)
			)
			(min_thickness 0.25)
			(keepout
				(tracks not_allowed)
				(vias allowed)
				(pads allowed)
				(copperpour not_allowed)
				(footprints allowed)
			)
			(placement
				(enabled no)
				(sheetname "")
			)
			(fill
				(thermal_gap 0.5)
				(thermal_bridge_width 0.5)
				(island_removal_mode 0)
			)
			(polygon
				(pts
					(arc
						(start 344.04808 -39.244524)
						(mid 344.011709 -39.186661)
						(end 343.953846 -39.15029)
					)
					(arc
						(start 343.953846 -39.045134)
						(mid 344.083567 -39.114803)
						(end 344.153236 -39.244524)
					)
				)
			)
		)
		(zone
			(layer "F.Cu")
			(hatch none 0.5)
			(connect_pads
				(clearance 0)
			)
			(min_thickness 0.25)
			(keepout
				(tracks not_allowed)
				(vias allowed)
				(pads allowed)
				(copperpour not_allowed)
				(footprints allowed)
			)
			(placement
				(enabled no)
				(sheetname "")
			)
			(fill
				(thermal_gap 0.5)
				(thermal_bridge_width 0.5)
				(island_removal_mode 0)
			)
			(polygon
				(pts
					(arc
						(start 344.04808 -38.414452)
						(mid 344.011709 -38.356589)
						(end 343.953846 -38.320218)
					)
					(arc
						(start 343.953846 -38.215062)
						(mid 344.083567 -38.284731)
						(end 344.153236 -38.414452)
					)
				)
			)
		)
		(zone
			(layer "F.Cu")
			(hatch none 0.5)
			(connect_pads
				(clearance 0)
			)
			(min_thickness 0.25)
			(keepout
				(tracks not_allowed)
				(vias allowed)
				(pads allowed)
				(copperpour not_allowed)
				(footprints allowed)
			)
			(placement
				(enabled no)
				(sheetname "")
			)
			(fill
				(thermal_gap 0.5)
				(thermal_bridge_width 0.5)
				(island_removal_mode 0)
			)
			(polygon
				(pts
					(arc
						(start 344.258392 -58.901076)
						(mid 344.294763 -58.958939)
						(end 344.352626 -58.99531)
					)
					(arc
						(start 344.352626 -59.100466)
						(mid 344.222905 -59.030797)
						(end 344.153236 -58.901076)
					)
				)
			)
		)
		(zone
			(layer "F.Cu")
			(hatch none 0.5)
			(connect_pads
				(clearance 0)
			)
			(min_thickness 0.25)
			(keepout
				(tracks not_allowed)
				(vias allowed)
				(pads allowed)
				(copperpour not_allowed)
				(footprints allowed)
			)
			(placement
				(enabled no)
				(sheetname "")
			)
			(fill
				(thermal_gap 0.5)
				(thermal_bridge_width 0.5)
				(island_removal_mode 0)
			)
			(polygon
				(pts
					(arc
						(start 344.258392 -58.071004)
						(mid 344.294763 -58.128867)
						(end 344.352626 -58.165238)
					)
					(arc
						(start 344.352626 -58.270394)
						(mid 344.222905 -58.200725)
						(end 344.153236 -58.071004)
					)
				)
			)
		)
		(zone
			(layer "F.Cu")
			(hatch none 0.5)
			(connect_pads
				(clearance 0)
			)
			(min_thickness 0.25)
			(keepout
				(tracks not_allowed)
				(vias allowed)
				(pads allowed)
				(copperpour not_allowed)
				(footprints allowed)
			)
			(placement
				(enabled no)
				(sheetname "")
			)
			(fill
				(thermal_gap 0.5)
				(thermal_bridge_width 0.5)
				(island_removal_mode 0)
			)
			(polygon
				(pts
					(arc
						(start 344.258392 -38.931088)
						(mid 344.294763 -38.988951)
						(end 344.352626 -39.025322)
					)
					(arc
						(start 344.352626 -39.130478)
						(mid 344.222905 -39.060809)
						(end 344.153236 -38.931088)
					)
				)
			)
		)
		(zone
			(layer "F.Cu")
			(hatch none 0.5)
			(connect_pads
				(clearance 0)
			)
			(min_thickness 0.25)
			(keepout
				(tracks not_allowed)
				(vias allowed)
				(pads allowed)
				(copperpour not_allowed)
				(footprints allowed)
			)
			(placement
				(enabled no)
				(sheetname "")
			)
			(fill
				(thermal_gap 0.5)
				(thermal_bridge_width 0.5)
				(island_removal_mode 0)
			)
			(polygon
				(pts
					(arc
						(start 344.258392 -38.101016)
						(mid 344.294763 -38.158879)
						(end 344.352626 -38.19525)
					)
					(arc
						(start 344.352626 -38.300406)
						(mid 344.222905 -38.230737)
						(end 344.153236 -38.101016)
					)
				)
			)
		)
		(zone
			(layer "F.Cu")
			(hatch none 0.5)
			(connect_pads
				(clearance 0)
			)
			(min_thickness 0.25)
			(keepout
				(tracks not_allowed)
				(vias allowed)
				(pads allowed)
				(copperpour not_allowed)
				(footprints allowed)
			)
			(placement
				(enabled no)
				(sheetname "")
			)
			(fill
				(thermal_gap 0.5)
				(thermal_bridge_width 0.5)
				(island_removal_mode 0)
			)
			(polygon
				(pts
					(arc
						(start 344.352626 -58.705242)
						(mid 344.294763 -58.741613)
						(end 344.258392 -58.799476)
					)
					(arc
						(start 344.153236 -58.799476)
						(mid 344.222905 -58.669755)
						(end 344.352626 -58.600086)
					)
				)
			)
		)
		(zone
			(layer "F.Cu")
			(hatch none 0.5)
			(connect_pads
				(clearance 0)
			)
			(min_thickness 0.25)
			(keepout
				(tracks not_allowed)
				(vias allowed)
				(pads allowed)
				(copperpour not_allowed)
				(footprints allowed)
			)
			(placement
				(enabled no)
				(sheetname "")
			)
			(fill
				(thermal_gap 0.5)
				(thermal_bridge_width 0.5)
				(island_removal_mode 0)
			)
			(polygon
				(pts
					(arc
						(start 344.352626 -57.87517)
						(mid 344.294763 -57.911541)
						(end 344.258392 -57.969404)
					)
					(arc
						(start 344.153236 -57.969404)
						(mid 344.222905 -57.839683)
						(end 344.352626 -57.770014)
					)
				)
			)
		)
		(zone
			(layer "F.Cu")
			(hatch none 0.5)
			(connect_pads
				(clearance 0)
			)
			(min_thickness 0.25)
			(keepout
				(tracks not_allowed)
				(vias allowed)
				(pads allowed)
				(copperpour not_allowed)
				(footprints allowed)
			)
			(placement
				(enabled no)
				(sheetname "")
			)
			(fill
				(thermal_gap 0.5)
				(thermal_bridge_width 0.5)
				(island_removal_mode 0)
			)
			(polygon
				(pts
					(arc
						(start 344.352626 -38.735254)
						(mid 344.294763 -38.771625)
						(end 344.258392 -38.829488)
					)
					(arc
						(start 344.153236 -38.829488)
						(mid 344.222905 -38.699767)
						(end 344.352626 -38.630098)
					)
				)
			)
		)
		(zone
			(layer "F.Cu")
			(hatch none 0.5)
			(connect_pads
				(clearance 0)
			)
			(min_thickness 0.25)
			(keepout
				(tracks not_allowed)
				(vias allowed)
				(pads allowed)
				(copperpour not_allowed)
				(footprints allowed)
			)
			(placement
				(enabled no)
				(sheetname "")
			)
			(fill
				(thermal_gap 0.5)
				(thermal_bridge_width 0.5)
				(island_removal_mode 0)
			)
			(polygon
				(pts
					(arc
						(start 344.352626 -37.905182)
						(mid 344.294763 -37.941553)
						(end 344.258392 -37.999416)
					)
					(arc
						(start 344.153236 -37.999416)
						(mid 344.222905 -37.869695)
						(end 344.352626 -37.800026)
					)
				)
			)
		)
		(zone
			(layer "F.Cu")
			(hatch none 0.5)
			(connect_pads
				(clearance 0)
			)
			(min_thickness 0.25)
			(keepout
				(tracks not_allowed)
				(vias allowed)
				(pads allowed)
				(copperpour not_allowed)
				(footprints allowed)
			)
			(placement
				(enabled no)
				(sheetname "")
			)
			(fill
				(thermal_gap 0.5)
				(thermal_bridge_width 0.5)
				(island_removal_mode 0)
			)
			(polygon
				(pts
					(arc
						(start 344.454226 -58.99531)
						(mid 344.512089 -58.958939)
						(end 344.54846 -58.901076)
					)
					(arc
						(start 344.653616 -58.901076)
						(mid 344.583947 -59.030797)
						(end 344.454226 -59.100466)
					)
				)
			)
		)
		(zone
			(layer "F.Cu")
			(hatch none 0.5)
			(connect_pads
				(clearance 0)
			)
			(min_thickness 0.25)
			(keepout
				(tracks not_allowed)
				(vias allowed)
				(pads allowed)
				(copperpour not_allowed)
				(footprints allowed)
			)
			(placement
				(enabled no)
				(sheetname "")
			)
			(fill
				(thermal_gap 0.5)
				(thermal_bridge_width 0.5)
				(island_removal_mode 0)
			)
			(polygon
				(pts
					(arc
						(start 344.454226 -58.165238)
						(mid 344.512089 -58.128867)
						(end 344.54846 -58.071004)
					)
					(arc
						(start 344.653616 -58.071004)
						(mid 344.583947 -58.200725)
						(end 344.454226 -58.270394)
					)
				)
			)
		)
		(zone
			(layer "F.Cu")
			(hatch none 0.5)
			(connect_pads
				(clearance 0)
			)
			(min_thickness 0.25)
			(keepout
				(tracks not_allowed)
				(vias allowed)
				(pads allowed)
				(copperpour not_allowed)
				(footprints allowed)
			)
			(placement
				(enabled no)
				(sheetname "")
			)
			(fill
				(thermal_gap 0.5)
				(thermal_bridge_width 0.5)
				(island_removal_mode 0)
			)
			(polygon
				(pts
					(arc
						(start 344.454226 -39.025322)
						(mid 344.512089 -38.988951)
						(end 344.54846 -38.931088)
					)
					(arc
						(start 344.653616 -38.931088)
						(mid 344.583947 -39.060809)
						(end 344.454226 -39.130478)
					)
				)
			)
		)
		(zone
			(layer "F.Cu")
			(hatch none 0.5)
			(connect_pads
				(clearance 0)
			)
			(min_thickness 0.25)
			(keepout
				(tracks not_allowed)
				(vias allowed)
				(pads allowed)
				(copperpour not_allowed)
				(footprints allowed)
			)
			(placement
				(enabled no)
				(sheetname "")
			)
			(fill
				(thermal_gap 0.5)
				(thermal_bridge_width 0.5)
				(island_removal_mode 0)
			)
			(polygon
				(pts
					(arc
						(start 344.454226 -38.19525)
						(mid 344.512089 -38.158879)
						(end 344.54846 -38.101016)
					)
					(arc
						(start 344.653616 -38.101016)
						(mid 344.583947 -38.230737)
						(end 344.454226 -38.300406)
					)
				)
			)
		)
		(zone
			(layer "F.Cu")
			(hatch none 0.5)
			(connect_pads
				(clearance 0)
			)
			(min_thickness 0.25)
			(keepout
				(tracks not_allowed)
				(vias allowed)
				(pads allowed)
				(copperpour not_allowed)
				(footprints allowed)
			)
			(placement
				(enabled no)
				(sheetname "")
			)
			(fill
				(thermal_gap 0.5)
				(thermal_bridge_width 0.5)
				(island_removal_mode 0)
			)
			(polygon
				(pts
					(arc
						(start 344.54846 -58.799476)
						(mid 344.512089 -58.741613)
						(end 344.454226 -58.705242)
					)
					(arc
						(start 344.454226 -58.600086)
						(mid 344.583947 -58.669755)
						(end 344.653616 -58.799476)
					)
				)
			)
		)
		(zone
			(layer "F.Cu")
			(hatch none 0.5)
			(connect_pads
				(clearance 0)
			)
			(min_thickness 0.25)
			(keepout
				(tracks not_allowed)
				(vias allowed)
				(pads allowed)
				(copperpour not_allowed)
				(footprints allowed)
			)
			(placement
				(enabled no)
				(sheetname "")
			)
			(fill
				(thermal_gap 0.5)
				(thermal_bridge_width 0.5)
				(island_removal_mode 0)
			)
			(polygon
				(pts
					(arc
						(start 344.54846 -57.969404)
						(mid 344.512089 -57.911541)
						(end 344.454226 -57.87517)
					)
					(arc
						(start 344.454226 -57.770014)
						(mid 344.583947 -57.839683)
						(end 344.653616 -57.969404)
					)
				)
			)
		)
		(zone
			(layer "F.Cu")
			(hatch none 0.5)
			(connect_pads
				(clearance 0)
			)
			(min_thickness 0.25)
			(keepout
				(tracks not_allowed)
				(vias allowed)
				(pads allowed)
				(copperpour not_allowed)
				(footprints allowed)
			)
			(placement
				(enabled no)
				(sheetname "")
			)
			(fill
				(thermal_gap 0.5)
				(thermal_bridge_width 0.5)
				(island_removal_mode 0)
			)
			(polygon
				(pts
					(arc
						(start 344.54846 -38.829488)
						(mid 344.512089 -38.771625)
						(end 344.454226 -38.735254)
					)
					(arc
						(start 344.454226 -38.630098)
						(mid 344.583947 -38.699767)
						(end 344.653616 -38.829488)
					)
				)
			)
		)
		(zone
			(layer "F.Cu")
			(hatch none 0.5)
			(connect_pads
				(clearance 0)
			)
			(min_thickness 0.25)
			(keepout
				(tracks not_allowed)
				(vias allowed)
				(pads allowed)
				(copperpour not_allowed)
				(footprints allowed)
			)
			(placement
				(enabled no)
				(sheetname "")
			)
			(fill
				(thermal_gap 0.5)
				(thermal_bridge_width 0.5)
				(island_removal_mode 0)
			)
			(polygon
				(pts
					(arc
						(start 344.54846 -37.999416)
						(mid 344.512089 -37.941553)
						(end 344.454226 -37.905182)
					)
					(arc
						(start 344.454226 -37.800026)
						(mid 344.583947 -37.869695)
						(end 344.653616 -37.999416)
					)
				)
			)
		)
		(zone
			(layer "F.Cu")
			(hatch none 0.5)
			(connect_pads
				(clearance 0)
			)
			(min_thickness 0.25)
			(keepout
				(tracks not_allowed)
				(vias allowed)
				(pads allowed)
				(copperpour not_allowed)
				(footprints allowed)
			)
			(placement
				(enabled no)
				(sheetname "")
			)
			(fill
				(thermal_gap 0.5)
				(thermal_bridge_width 0.5)
				(island_removal_mode 0)
			)
			(polygon
				(pts
					(arc
						(start 344.758518 -58.48604)
						(mid 344.794944 -58.543739)
						(end 344.852752 -58.58002)
					)
					(arc
						(start 344.852752 -58.68543)
						(mid 344.723031 -58.615761)
						(end 344.653362 -58.48604)
					)
				)
			)
		)
		(zone
			(layer "F.Cu")
			(hatch none 0.5)
			(connect_pads
				(clearance 0)
			)
			(min_thickness 0.25)
			(keepout
				(tracks not_allowed)
				(vias allowed)
				(pads allowed)
				(copperpour not_allowed)
				(footprints allowed)
			)
			(placement
				(enabled no)
				(sheetname "")
			)
			(fill
				(thermal_gap 0.5)
				(thermal_bridge_width 0.5)
				(island_removal_mode 0)
			)
			(polygon
				(pts
					(arc
						(start 344.758518 -39.346124)
						(mid 344.794889 -39.403987)
						(end 344.852752 -39.440358)
					)
					(arc
						(start 344.852752 -39.545514)
						(mid 344.723031 -39.475845)
						(end 344.653362 -39.346124)
					)
				)
			)
		)
		(zone
			(layer "F.Cu")
			(hatch none 0.5)
			(connect_pads
				(clearance 0)
			)
			(min_thickness 0.25)
			(keepout
				(tracks not_allowed)
				(vias allowed)
				(pads allowed)
				(copperpour not_allowed)
				(footprints allowed)
			)
			(placement
				(enabled no)
				(sheetname "")
			)
			(fill
				(thermal_gap 0.5)
				(thermal_bridge_width 0.5)
				(island_removal_mode 0)
			)
			(polygon
				(pts
					(arc
						(start 344.758772 -57.655968)
						(mid 344.795003 -57.713827)
						(end 344.852752 -57.750202)
					)
					(arc
						(start 344.852752 -57.855358)
						(mid 344.723031 -57.785689)
						(end 344.653362 -57.655968)
					)
				)
			)
		)
		(zone
			(layer "F.Cu")
			(hatch none 0.5)
			(connect_pads
				(clearance 0)
			)
			(min_thickness 0.25)
			(keepout
				(tracks not_allowed)
				(vias allowed)
				(pads allowed)
				(copperpour not_allowed)
				(footprints allowed)
			)
			(placement
				(enabled no)
				(sheetname "")
			)
			(fill
				(thermal_gap 0.5)
				(thermal_bridge_width 0.5)
				(island_removal_mode 0)
			)
			(polygon
				(pts
					(arc
						(start 344.758772 -38.516052)
						(mid 344.795003 -38.573911)
						(end 344.852752 -38.610286)
					)
					(arc
						(start 344.852752 -38.715442)
						(mid 344.723031 -38.645773)
						(end 344.653362 -38.516052)
					)
				)
			)
		)
		(zone
			(layer "F.Cu")
			(hatch none 0.5)
			(connect_pads
				(clearance 0)
			)
			(min_thickness 0.25)
			(keepout
				(tracks not_allowed)
				(vias allowed)
				(pads allowed)
				(copperpour not_allowed)
				(footprints allowed)
			)
			(placement
				(enabled no)
				(sheetname "")
			)
			(fill
				(thermal_gap 0.5)
				(thermal_bridge_width 0.5)
				(island_removal_mode 0)
			)
			(polygon
				(pts
					(arc
						(start 344.852752 -58.290206)
						(mid 344.794889 -58.326577)
						(end 344.758518 -58.38444)
					)
					(arc
						(start 344.653362 -58.38444)
						(mid 344.723031 -58.254719)
						(end 344.852752 -58.18505)
					)
				)
			)
		)
		(zone
			(layer "F.Cu")
			(hatch none 0.5)
			(connect_pads
				(clearance 0)
			)
			(min_thickness 0.25)
			(keepout
				(tracks not_allowed)
				(vias allowed)
				(pads allowed)
				(copperpour not_allowed)
				(footprints allowed)
			)
			(placement
				(enabled no)
				(sheetname "")
			)
			(fill
				(thermal_gap 0.5)
				(thermal_bridge_width 0.5)
				(island_removal_mode 0)
			)
			(polygon
				(pts
					(arc
						(start 344.852752 -57.460134)
						(mid 344.795053 -57.49656)
						(end 344.758772 -57.554368)
					)
					(arc
						(start 344.653362 -57.554368)
						(mid 344.723031 -57.424647)
						(end 344.852752 -57.354978)
					)
				)
			)
		)
		(zone
			(layer "F.Cu")
			(hatch none 0.5)
			(connect_pads
				(clearance 0)
			)
			(min_thickness 0.25)
			(keepout
				(tracks not_allowed)
				(vias allowed)
				(pads allowed)
				(copperpour not_allowed)
				(footprints allowed)
			)
			(placement
				(enabled no)
				(sheetname "")
			)
			(fill
				(thermal_gap 0.5)
				(thermal_bridge_width 0.5)
				(island_removal_mode 0)
			)
			(polygon
				(pts
					(arc
						(start 344.852752 -39.15029)
						(mid 344.794889 -39.186661)
						(end 344.758518 -39.244524)
					)
					(arc
						(start 344.653362 -39.244524)
						(mid 344.723031 -39.114803)
						(end 344.852752 -39.045134)
					)
				)
			)
		)
		(zone
			(layer "F.Cu")
			(hatch none 0.5)
			(connect_pads
				(clearance 0)
			)
			(min_thickness 0.25)
			(keepout
				(tracks not_allowed)
				(vias allowed)
				(pads allowed)
				(copperpour not_allowed)
				(footprints allowed)
			)
			(placement
				(enabled no)
				(sheetname "")
			)
			(fill
				(thermal_gap 0.5)
				(thermal_bridge_width 0.5)
				(island_removal_mode 0)
			)
			(polygon
				(pts
					(arc
						(start 344.852752 -38.320218)
						(mid 344.795053 -38.356644)
						(end 344.758772 -38.414452)
					)
					(arc
						(start 344.653362 -38.414452)
						(mid 344.723031 -38.284731)
						(end 344.852752 -38.215062)
					)
				)
			)
		)
		(zone
			(layer "F.Cu")
			(hatch none 0.5)
			(connect_pads
				(clearance 0)
			)
			(min_thickness 0.25)
			(keepout
				(tracks not_allowed)
				(vias allowed)
				(pads allowed)
				(copperpour not_allowed)
				(footprints allowed)
			)
			(placement
				(enabled no)
				(sheetname "")
			)
			(fill
				(thermal_gap 0.5)
				(thermal_bridge_width 0.5)
				(island_removal_mode 0)
			)
			(polygon
				(pts
					(arc
						(start 344.954352 -58.58002)
						(mid 345.012211 -58.543789)
						(end 345.048586 -58.48604)
					)
					(arc
						(start 345.153742 -58.48604)
						(mid 345.084073 -58.615761)
						(end 344.954352 -58.68543)
					)
				)
			)
		)
		(zone
			(layer "F.Cu")
			(hatch none 0.5)
			(connect_pads
				(clearance 0)
			)
			(min_thickness 0.25)
			(keepout
				(tracks not_allowed)
				(vias allowed)
				(pads allowed)
				(copperpour not_allowed)
				(footprints allowed)
			)
			(placement
				(enabled no)
				(sheetname "")
			)
			(fill
				(thermal_gap 0.5)
				(thermal_bridge_width 0.5)
				(island_removal_mode 0)
			)
			(polygon
				(pts
					(arc
						(start 344.954352 -57.750202)
						(mid 345.012215 -57.713831)
						(end 345.048586 -57.655968)
					)
					(arc
						(start 345.153742 -57.655968)
						(mid 345.084073 -57.785689)
						(end 344.954352 -57.855358)
					)
				)
			)
		)
		(zone
			(layer "F.Cu")
			(hatch none 0.5)
			(connect_pads
				(clearance 0)
			)
			(min_thickness 0.25)
			(keepout
				(tracks not_allowed)
				(vias allowed)
				(pads allowed)
				(copperpour not_allowed)
				(footprints allowed)
			)
			(placement
				(enabled no)
				(sheetname "")
			)
			(fill
				(thermal_gap 0.5)
				(thermal_bridge_width 0.5)
				(island_removal_mode 0)
			)
			(polygon
				(pts
					(arc
						(start 344.954352 -39.440358)
						(mid 345.012215 -39.403987)
						(end 345.048586 -39.346124)
					)
					(arc
						(start 345.153742 -39.346124)
						(mid 345.084073 -39.475845)
						(end 344.954352 -39.545514)
					)
				)
			)
		)
		(zone
			(layer "F.Cu")
			(hatch none 0.5)
			(connect_pads
				(clearance 0)
			)
			(min_thickness 0.25)
			(keepout
				(tracks not_allowed)
				(vias allowed)
				(pads allowed)
				(copperpour not_allowed)
				(footprints allowed)
			)
			(placement
				(enabled no)
				(sheetname "")
			)
			(fill
				(thermal_gap 0.5)
				(thermal_bridge_width 0.5)
				(island_removal_mode 0)
			)
			(polygon
				(pts
					(arc
						(start 344.954352 -38.610286)
						(mid 345.012215 -38.573915)
						(end 345.048586 -38.516052)
					)
					(arc
						(start 345.153742 -38.516052)
						(mid 345.084073 -38.645773)
						(end 344.954352 -38.715442)
					)
				)
			)
		)
		(zone
			(layer "F.Cu")
			(hatch none 0.5)
			(connect_pads
				(clearance 0)
			)
			(min_thickness 0.25)
			(keepout
				(tracks not_allowed)
				(vias allowed)
				(pads allowed)
				(copperpour not_allowed)
				(footprints allowed)
			)
			(placement
				(enabled no)
				(sheetname "")
			)
			(fill
				(thermal_gap 0.5)
				(thermal_bridge_width 0.5)
				(island_removal_mode 0)
			)
			(polygon
				(pts
					(arc
						(start 345.048586 -58.38444)
						(mid 345.012215 -58.326577)
						(end 344.954352 -58.290206)
					)
					(arc
						(start 344.954352 -58.18505)
						(mid 345.084073 -58.254719)
						(end 345.153742 -58.38444)
					)
				)
			)
		)
		(zone
			(layer "F.Cu")
			(hatch none 0.5)
			(connect_pads
				(clearance 0)
			)
			(min_thickness 0.25)
			(keepout
				(tracks not_allowed)
				(vias allowed)
				(pads allowed)
				(copperpour not_allowed)
				(footprints allowed)
			)
			(placement
				(enabled no)
				(sheetname "")
			)
			(fill
				(thermal_gap 0.5)
				(thermal_bridge_width 0.5)
				(island_removal_mode 0)
			)
			(polygon
				(pts
					(arc
						(start 345.048586 -57.554368)
						(mid 345.012215 -57.496505)
						(end 344.954352 -57.460134)
					)
					(arc
						(start 344.954352 -57.354978)
						(mid 345.084073 -57.424647)
						(end 345.153742 -57.554368)
					)
				)
			)
		)
		(zone
			(layer "F.Cu")
			(hatch none 0.5)
			(connect_pads
				(clearance 0)
			)
			(min_thickness 0.25)
			(keepout
				(tracks not_allowed)
				(vias allowed)
				(pads allowed)
				(copperpour not_allowed)
				(footprints allowed)
			)
			(placement
				(enabled no)
				(sheetname "")
			)
			(fill
				(thermal_gap 0.5)
				(thermal_bridge_width 0.5)
				(island_removal_mode 0)
			)
			(polygon
				(pts
					(arc
						(start 345.048586 -39.244524)
						(mid 345.012215 -39.186661)
						(end 344.954352 -39.15029)
					)
					(arc
						(start 344.954352 -39.045134)
						(mid 345.084073 -39.114803)
						(end 345.153742 -39.244524)
					)
				)
			)
		)
		(zone
			(layer "F.Cu")
			(hatch none 0.5)
			(connect_pads
				(clearance 0)
			)
			(min_thickness 0.25)
			(keepout
				(tracks not_allowed)
				(vias allowed)
				(pads allowed)
				(copperpour not_allowed)
				(footprints allowed)
			)
			(placement
				(enabled no)
				(sheetname "")
			)
			(fill
				(thermal_gap 0.5)
				(thermal_bridge_width 0.5)
				(island_removal_mode 0)
			)
			(polygon
				(pts
					(arc
						(start 345.048586 -38.414452)
						(mid 345.012215 -38.356589)
						(end 344.954352 -38.320218)
					)
					(arc
						(start 344.954352 -38.215062)
						(mid 345.084073 -38.284731)
						(end 345.153742 -38.414452)
					)
				)
			)
		)
		(zone
			(layer "F.Cu")
			(hatch none 0.5)
			(connect_pads
				(clearance 0)
			)
			(min_thickness 0.25)
			(keepout
				(tracks not_allowed)
				(vias allowed)
				(pads allowed)
				(copperpour not_allowed)
				(footprints allowed)
			)
			(placement
				(enabled no)
				(sheetname "")
			)
			(fill
				(thermal_gap 0.5)
				(thermal_bridge_width 0.5)
				(island_removal_mode 0)
			)
			(polygon
				(pts
					(arc
						(start 345.258898 -58.901076)
						(mid 345.295269 -58.958939)
						(end 345.353132 -58.99531)
					)
					(arc
						(start 345.353132 -59.100466)
						(mid 345.223411 -59.030797)
						(end 345.153742 -58.901076)
					)
				)
			)
		)
		(zone
			(layer "F.Cu")
			(hatch none 0.5)
			(connect_pads
				(clearance 0)
			)
			(min_thickness 0.25)
			(keepout
				(tracks not_allowed)
				(vias allowed)
				(pads allowed)
				(copperpour not_allowed)
				(footprints allowed)
			)
			(placement
				(enabled no)
				(sheetname "")
			)
			(fill
				(thermal_gap 0.5)
				(thermal_bridge_width 0.5)
				(island_removal_mode 0)
			)
			(polygon
				(pts
					(arc
						(start 345.258898 -58.071004)
						(mid 345.295269 -58.128867)
						(end 345.353132 -58.165238)
					)
					(arc
						(start 345.353132 -58.270394)
						(mid 345.223411 -58.200725)
						(end 345.153742 -58.071004)
					)
				)
			)
		)
		(zone
			(layer "F.Cu")
			(hatch none 0.5)
			(connect_pads
				(clearance 0)
			)
			(min_thickness 0.25)
			(keepout
				(tracks not_allowed)
				(vias allowed)
				(pads allowed)
				(copperpour not_allowed)
				(footprints allowed)
			)
			(placement
				(enabled no)
				(sheetname "")
			)
			(fill
				(thermal_gap 0.5)
				(thermal_bridge_width 0.5)
				(island_removal_mode 0)
			)
			(polygon
				(pts
					(arc
						(start 345.258898 -38.931088)
						(mid 345.295269 -38.988951)
						(end 345.353132 -39.025322)
					)
					(arc
						(start 345.353132 -39.130478)
						(mid 345.223411 -39.060809)
						(end 345.153742 -38.931088)
					)
				)
			)
		)
		(zone
			(layer "F.Cu")
			(hatch none 0.5)
			(connect_pads
				(clearance 0)
			)
			(min_thickness 0.25)
			(keepout
				(tracks not_allowed)
				(vias allowed)
				(pads allowed)
				(copperpour not_allowed)
				(footprints allowed)
			)
			(placement
				(enabled no)
				(sheetname "")
			)
			(fill
				(thermal_gap 0.5)
				(thermal_bridge_width 0.5)
				(island_removal_mode 0)
			)
			(polygon
				(pts
					(arc
						(start 345.258898 -38.101016)
						(mid 345.295269 -38.158879)
						(end 345.353132 -38.19525)
					)
					(arc
						(start 345.353132 -38.300406)
						(mid 345.223411 -38.230737)
						(end 345.153742 -38.101016)
					)
				)
			)
		)
		(zone
			(layer "F.Cu")
			(hatch none 0.5)
			(connect_pads
				(clearance 0)
			)
			(min_thickness 0.25)
			(keepout
				(tracks not_allowed)
				(vias allowed)
				(pads allowed)
				(copperpour not_allowed)
				(footprints allowed)
			)
			(placement
				(enabled no)
				(sheetname "")
			)
			(fill
				(thermal_gap 0.5)
				(thermal_bridge_width 0.5)
				(island_removal_mode 0)
			)
			(polygon
				(pts
					(arc
						(start 345.353132 -58.705242)
						(mid 345.295269 -58.741613)
						(end 345.258898 -58.799476)
					)
					(arc
						(start 345.153742 -58.799476)
						(mid 345.223411 -58.669755)
						(end 345.353132 -58.600086)
					)
				)
			)
		)
		(zone
			(layer "F.Cu")
			(hatch none 0.5)
			(connect_pads
				(clearance 0)
			)
			(min_thickness 0.25)
			(keepout
				(tracks not_allowed)
				(vias allowed)
				(pads allowed)
				(copperpour not_allowed)
				(footprints allowed)
			)
			(placement
				(enabled no)
				(sheetname "")
			)
			(fill
				(thermal_gap 0.5)
				(thermal_bridge_width 0.5)
				(island_removal_mode 0)
			)
			(polygon
				(pts
					(arc
						(start 345.353132 -57.87517)
						(mid 345.295269 -57.911541)
						(end 345.258898 -57.969404)
					)
					(arc
						(start 345.153742 -57.969404)
						(mid 345.223411 -57.839683)
						(end 345.353132 -57.770014)
					)
				)
			)
		)
		(zone
			(layer "F.Cu")
			(hatch none 0.5)
			(connect_pads
				(clearance 0)
			)
			(min_thickness 0.25)
			(keepout
				(tracks not_allowed)
				(vias allowed)
				(pads allowed)
				(copperpour not_allowed)
				(footprints allowed)
			)
			(placement
				(enabled no)
				(sheetname "")
			)
			(fill
				(thermal_gap 0.5)
				(thermal_bridge_width 0.5)
				(island_removal_mode 0)
			)
			(polygon
				(pts
					(arc
						(start 345.353132 -38.735254)
						(mid 345.295269 -38.771625)
						(end 345.258898 -38.829488)
					)
					(arc
						(start 345.153742 -38.829488)
						(mid 345.223411 -38.699767)
						(end 345.353132 -38.630098)
					)
				)
			)
		)
		(zone
			(layer "F.Cu")
			(hatch none 0.5)
			(connect_pads
				(clearance 0)
			)
			(min_thickness 0.25)
			(keepout
				(tracks not_allowed)
				(vias allowed)
				(pads allowed)
				(copperpour not_allowed)
				(footprints allowed)
			)
			(placement
				(enabled no)
				(sheetname "")
			)
			(fill
				(thermal_gap 0.5)
				(thermal_bridge_width 0.5)
				(island_removal_mode 0)
			)
			(polygon
				(pts
					(arc
						(start 345.353132 -37.905182)
						(mid 345.295269 -37.941553)
						(end 345.258898 -37.999416)
					)
					(arc
						(start 345.153742 -37.999416)
						(mid 345.223411 -37.869695)
						(end 345.353132 -37.800026)
					)
				)
			)
		)
		(zone
			(layer "F.Cu")
			(hatch none 0.5)
			(connect_pads
				(clearance 0)
			)
			(min_thickness 0.25)
			(keepout
				(tracks not_allowed)
				(vias allowed)
				(pads allowed)
				(copperpour not_allowed)
				(footprints allowed)
			)
			(placement
				(enabled no)
				(sheetname "")
			)
			(fill
				(thermal_gap 0.5)
				(thermal_bridge_width 0.5)
				(island_removal_mode 0)
			)
			(polygon
				(pts
					(arc
						(start 345.40952 -57.00522)
						(mid 345.445891 -57.063083)
						(end 345.503754 -57.099454)
					)
					(arc
						(start 345.503754 -57.20461)
						(mid 345.374033 -57.134941)
						(end 345.304364 -57.00522)
					)
				)
			)
		)
		(zone
			(layer "F.Cu")
			(hatch none 0.5)
			(connect_pads
				(clearance 0)
			)
			(min_thickness 0.25)
			(keepout
				(tracks not_allowed)
				(vias allowed)
				(pads allowed)
				(copperpour not_allowed)
				(footprints allowed)
			)
			(placement
				(enabled no)
				(sheetname "")
			)
			(fill
				(thermal_gap 0.5)
				(thermal_bridge_width 0.5)
				(island_removal_mode 0)
			)
			(polygon
				(pts
					(arc
						(start 345.40952 -56.004714)
						(mid 345.445891 -56.062577)
						(end 345.503754 -56.098948)
					)
					(arc
						(start 345.503754 -56.204104)
						(mid 345.374033 -56.134435)
						(end 345.304364 -56.004714)
					)
				)
			)
		)
		(zone
			(layer "F.Cu")
			(hatch none 0.5)
			(connect_pads
				(clearance 0)
			)
			(min_thickness 0.25)
			(keepout
				(tracks not_allowed)
				(vias allowed)
				(pads allowed)
				(copperpour not_allowed)
				(footprints allowed)
			)
			(placement
				(enabled no)
				(sheetname "")
			)
			(fill
				(thermal_gap 0.5)
				(thermal_bridge_width 0.5)
				(island_removal_mode 0)
			)
			(polygon
				(pts
					(arc
						(start 345.40952 -55.004208)
						(mid 345.445891 -55.062071)
						(end 345.503754 -55.098442)
					)
					(arc
						(start 345.503754 -55.203598)
						(mid 345.374033 -55.133929)
						(end 345.304364 -55.004208)
					)
				)
			)
		)
		(zone
			(layer "F.Cu")
			(hatch none 0.5)
			(connect_pads
				(clearance 0)
			)
			(min_thickness 0.25)
			(keepout
				(tracks not_allowed)
				(vias allowed)
				(pads allowed)
				(copperpour not_allowed)
				(footprints allowed)
			)
			(placement
				(enabled no)
				(sheetname "")
			)
			(fill
				(thermal_gap 0.5)
				(thermal_bridge_width 0.5)
				(island_removal_mode 0)
			)
			(polygon
				(pts
					(arc
						(start 345.40952 -54.003702)
						(mid 345.445891 -54.061565)
						(end 345.503754 -54.097936)
					)
					(arc
						(start 345.503754 -54.203092)
						(mid 345.374033 -54.133423)
						(end 345.304364 -54.003702)
					)
				)
			)
		)
		(zone
			(layer "F.Cu")
			(hatch none 0.5)
			(connect_pads
				(clearance 0)
			)
			(min_thickness 0.25)
			(keepout
				(tracks not_allowed)
				(vias allowed)
				(pads allowed)
				(copperpour not_allowed)
				(footprints allowed)
			)
			(placement
				(enabled no)
				(sheetname "")
			)
			(fill
				(thermal_gap 0.5)
				(thermal_bridge_width 0.5)
				(island_removal_mode 0)
			)
			(polygon
				(pts
					(arc
						(start 345.40952 -53.003196)
						(mid 345.445891 -53.061059)
						(end 345.503754 -53.09743)
					)
					(arc
						(start 345.503754 -53.202586)
						(mid 345.374033 -53.132917)
						(end 345.304364 -53.003196)
					)
				)
			)
		)
		(zone
			(layer "F.Cu")
			(hatch none 0.5)
			(connect_pads
				(clearance 0)
			)
			(min_thickness 0.25)
			(keepout
				(tracks not_allowed)
				(vias allowed)
				(pads allowed)
				(copperpour not_allowed)
				(footprints allowed)
			)
			(placement
				(enabled no)
				(sheetname "")
			)
			(fill
				(thermal_gap 0.5)
				(thermal_bridge_width 0.5)
				(island_removal_mode 0)
			)
			(polygon
				(pts
					(arc
						(start 345.40952 -52.00269)
						(mid 345.445891 -52.060553)
						(end 345.503754 -52.096924)
					)
					(arc
						(start 345.503754 -52.20208)
						(mid 345.374033 -52.132411)
						(end 345.304364 -52.00269)
					)
				)
			)
		)
		(zone
			(layer "F.Cu")
			(hatch none 0.5)
			(connect_pads
				(clearance 0)
			)
			(min_thickness 0.25)
			(keepout
				(tracks not_allowed)
				(vias allowed)
				(pads allowed)
				(copperpour not_allowed)
				(footprints allowed)
			)
			(placement
				(enabled no)
				(sheetname "")
			)
			(fill
				(thermal_gap 0.5)
				(thermal_bridge_width 0.5)
				(island_removal_mode 0)
			)
			(polygon
				(pts
					(arc
						(start 345.40952 -51.002184)
						(mid 345.445891 -51.060047)
						(end 345.503754 -51.096418)
					)
					(arc
						(start 345.503754 -51.201574)
						(mid 345.374033 -51.131905)
						(end 345.304364 -51.002184)
					)
				)
			)
		)
		(zone
			(layer "F.Cu")
			(hatch none 0.5)
			(connect_pads
				(clearance 0)
			)
			(min_thickness 0.25)
			(keepout
				(tracks not_allowed)
				(vias allowed)
				(pads allowed)
				(copperpour not_allowed)
				(footprints allowed)
			)
			(placement
				(enabled no)
				(sheetname "")
			)
			(fill
				(thermal_gap 0.5)
				(thermal_bridge_width 0.5)
				(island_removal_mode 0)
			)
			(polygon
				(pts
					(arc
						(start 345.40952 -50.001678)
						(mid 345.445891 -50.059541)
						(end 345.503754 -50.095912)
					)
					(arc
						(start 345.503754 -50.201068)
						(mid 345.374033 -50.131399)
						(end 345.304364 -50.001678)
					)
				)
			)
		)
		(zone
			(layer "F.Cu")
			(hatch none 0.5)
			(connect_pads
				(clearance 0)
			)
			(min_thickness 0.25)
			(keepout
				(tracks not_allowed)
				(vias allowed)
				(pads allowed)
				(copperpour not_allowed)
				(footprints allowed)
			)
			(placement
				(enabled no)
				(sheetname "")
			)
			(fill
				(thermal_gap 0.5)
				(thermal_bridge_width 0.5)
				(island_removal_mode 0)
			)
			(polygon
				(pts
					(arc
						(start 345.40952 -49.001172)
						(mid 345.445891 -49.059035)
						(end 345.503754 -49.095406)
					)
					(arc
						(start 345.503754 -49.200562)
						(mid 345.374033 -49.130893)
						(end 345.304364 -49.001172)
					)
				)
			)
		)
		(zone
			(layer "F.Cu")
			(hatch none 0.5)
			(connect_pads
				(clearance 0)
			)
			(min_thickness 0.25)
			(keepout
				(tracks not_allowed)
				(vias allowed)
				(pads allowed)
				(copperpour not_allowed)
				(footprints allowed)
			)
			(placement
				(enabled no)
				(sheetname "")
			)
			(fill
				(thermal_gap 0.5)
				(thermal_bridge_width 0.5)
				(island_removal_mode 0)
			)
			(polygon
				(pts
					(arc
						(start 345.40952 -48.00092)
						(mid 345.445891 -48.058783)
						(end 345.503754 -48.095154)
					)
					(arc
						(start 345.503754 -48.20031)
						(mid 345.374033 -48.130641)
						(end 345.304364 -48.00092)
					)
				)
			)
		)
		(zone
			(layer "F.Cu")
			(hatch none 0.5)
			(connect_pads
				(clearance 0)
			)
			(min_thickness 0.25)
			(keepout
				(tracks not_allowed)
				(vias allowed)
				(pads allowed)
				(copperpour not_allowed)
				(footprints allowed)
			)
			(placement
				(enabled no)
				(sheetname "")
			)
			(fill
				(thermal_gap 0.5)
				(thermal_bridge_width 0.5)
				(island_removal_mode 0)
			)
			(polygon
				(pts
					(arc
						(start 345.40952 -47.000414)
						(mid 345.445891 -47.058277)
						(end 345.503754 -47.094648)
					)
					(arc
						(start 345.503754 -47.199804)
						(mid 345.374033 -47.130135)
						(end 345.304364 -47.000414)
					)
				)
			)
		)
		(zone
			(layer "F.Cu")
			(hatch none 0.5)
			(connect_pads
				(clearance 0)
			)
			(min_thickness 0.25)
			(keepout
				(tracks not_allowed)
				(vias allowed)
				(pads allowed)
				(copperpour not_allowed)
				(footprints allowed)
			)
			(placement
				(enabled no)
				(sheetname "")
			)
			(fill
				(thermal_gap 0.5)
				(thermal_bridge_width 0.5)
				(island_removal_mode 0)
			)
			(polygon
				(pts
					(arc
						(start 345.40952 -45.999908)
						(mid 345.445891 -46.057771)
						(end 345.503754 -46.094142)
					)
					(arc
						(start 345.503754 -46.199298)
						(mid 345.374033 -46.129629)
						(end 345.304364 -45.999908)
					)
				)
			)
		)
		(zone
			(layer "F.Cu")
			(hatch none 0.5)
			(connect_pads
				(clearance 0)
			)
			(min_thickness 0.25)
			(keepout
				(tracks not_allowed)
				(vias allowed)
				(pads allowed)
				(copperpour not_allowed)
				(footprints allowed)
			)
			(placement
				(enabled no)
				(sheetname "")
			)
			(fill
				(thermal_gap 0.5)
				(thermal_bridge_width 0.5)
				(island_removal_mode 0)
			)
			(polygon
				(pts
					(arc
						(start 345.40952 -44.999402)
						(mid 345.445891 -45.057265)
						(end 345.503754 -45.093636)
					)
					(arc
						(start 345.503754 -45.198792)
						(mid 345.374033 -45.129123)
						(end 345.304364 -44.999402)
					)
				)
			)
		)
		(zone
			(layer "F.Cu")
			(hatch none 0.5)
			(connect_pads
				(clearance 0)
			)
			(min_thickness 0.25)
			(keepout
				(tracks not_allowed)
				(vias allowed)
				(pads allowed)
				(copperpour not_allowed)
				(footprints allowed)
			)
			(placement
				(enabled no)
				(sheetname "")
			)
			(fill
				(thermal_gap 0.5)
				(thermal_bridge_width 0.5)
				(island_removal_mode 0)
			)
			(polygon
				(pts
					(arc
						(start 345.40952 -43.998896)
						(mid 345.445891 -44.056759)
						(end 345.503754 -44.09313)
					)
					(arc
						(start 345.503754 -44.198286)
						(mid 345.374033 -44.128617)
						(end 345.304364 -43.998896)
					)
				)
			)
		)
		(zone
			(layer "F.Cu")
			(hatch none 0.5)
			(connect_pads
				(clearance 0)
			)
			(min_thickness 0.25)
			(keepout
				(tracks not_allowed)
				(vias allowed)
				(pads allowed)
				(copperpour not_allowed)
				(footprints allowed)
			)
			(placement
				(enabled no)
				(sheetname "")
			)
			(fill
				(thermal_gap 0.5)
				(thermal_bridge_width 0.5)
				(island_removal_mode 0)
			)
			(polygon
				(pts
					(arc
						(start 345.40952 -42.99839)
						(mid 345.445891 -43.056253)
						(end 345.503754 -43.092624)
					)
					(arc
						(start 345.503754 -43.19778)
						(mid 345.374033 -43.128111)
						(end 345.304364 -42.99839)
					)
				)
			)
		)
		(zone
			(layer "F.Cu")
			(hatch none 0.5)
			(connect_pads
				(clearance 0)
			)
			(min_thickness 0.25)
			(keepout
				(tracks not_allowed)
				(vias allowed)
				(pads allowed)
				(copperpour not_allowed)
				(footprints allowed)
			)
			(placement
				(enabled no)
				(sheetname "")
			)
			(fill
				(thermal_gap 0.5)
				(thermal_bridge_width 0.5)
				(island_removal_mode 0)
			)
			(polygon
				(pts
					(arc
						(start 345.40952 -41.997884)
						(mid 345.445891 -42.055747)
						(end 345.503754 -42.092118)
					)
					(arc
						(start 345.503754 -42.197274)
						(mid 345.374033 -42.127605)
						(end 345.304364 -41.997884)
					)
				)
			)
		)
		(zone
			(layer "F.Cu")
			(hatch none 0.5)
			(connect_pads
				(clearance 0)
			)
			(min_thickness 0.25)
			(keepout
				(tracks not_allowed)
				(vias allowed)
				(pads allowed)
				(copperpour not_allowed)
				(footprints allowed)
			)
			(placement
				(enabled no)
				(sheetname "")
			)
			(fill
				(thermal_gap 0.5)
				(thermal_bridge_width 0.5)
				(island_removal_mode 0)
			)
			(polygon
				(pts
					(arc
						(start 345.40952 -40.997378)
						(mid 345.445891 -41.055241)
						(end 345.503754 -41.091612)
					)
					(arc
						(start 345.503754 -41.196768)
						(mid 345.374033 -41.127099)
						(end 345.304364 -40.997378)
					)
				)
			)
		)
		(zone
			(layer "F.Cu")
			(hatch none 0.5)
			(connect_pads
				(clearance 0)
			)
			(min_thickness 0.25)
			(keepout
				(tracks not_allowed)
				(vias allowed)
				(pads allowed)
				(copperpour not_allowed)
				(footprints allowed)
			)
			(placement
				(enabled no)
				(sheetname "")
			)
			(fill
				(thermal_gap 0.5)
				(thermal_bridge_width 0.5)
				(island_removal_mode 0)
			)
			(polygon
				(pts
					(arc
						(start 345.40952 -39.996872)
						(mid 345.445891 -40.054735)
						(end 345.503754 -40.091106)
					)
					(arc
						(start 345.503754 -40.196262)
						(mid 345.374033 -40.126593)
						(end 345.304364 -39.996872)
					)
				)
			)
		)
		(zone
			(layer "F.Cu")
			(hatch none 0.5)
			(connect_pads
				(clearance 0)
			)
			(min_thickness 0.25)
			(keepout
				(tracks not_allowed)
				(vias allowed)
				(pads allowed)
				(copperpour not_allowed)
				(footprints allowed)
			)
			(placement
				(enabled no)
				(sheetname "")
			)
			(fill
				(thermal_gap 0.5)
				(thermal_bridge_width 0.5)
				(island_removal_mode 0)
			)
			(polygon
				(pts
					(arc
						(start 345.454732 -58.99531)
						(mid 345.512595 -58.958939)
						(end 345.548966 -58.901076)
					)
					(arc
						(start 345.654122 -58.901076)
						(mid 345.584453 -59.030797)
						(end 345.454732 -59.100466)
					)
				)
			)
		)
		(zone
			(layer "F.Cu")
			(hatch none 0.5)
			(connect_pads
				(clearance 0)
			)
			(min_thickness 0.25)
			(keepout
				(tracks not_allowed)
				(vias allowed)
				(pads allowed)
				(copperpour not_allowed)
				(footprints allowed)
			)
			(placement
				(enabled no)
				(sheetname "")
			)
			(fill
				(thermal_gap 0.5)
				(thermal_bridge_width 0.5)
				(island_removal_mode 0)
			)
			(polygon
				(pts
					(arc
						(start 345.454732 -58.165238)
						(mid 345.512595 -58.128867)
						(end 345.548966 -58.071004)
					)
					(arc
						(start 345.654122 -58.071004)
						(mid 345.584453 -58.200725)
						(end 345.454732 -58.270394)
					)
				)
			)
		)
		(zone
			(layer "F.Cu")
			(hatch none 0.5)
			(connect_pads
				(clearance 0)
			)
			(min_thickness 0.25)
			(keepout
				(tracks not_allowed)
				(vias allowed)
				(pads allowed)
				(copperpour not_allowed)
				(footprints allowed)
			)
			(placement
				(enabled no)
				(sheetname "")
			)
			(fill
				(thermal_gap 0.5)
				(thermal_bridge_width 0.5)
				(island_removal_mode 0)
			)
			(polygon
				(pts
					(arc
						(start 345.454732 -39.025322)
						(mid 345.512595 -38.988951)
						(end 345.548966 -38.931088)
					)
					(arc
						(start 345.654122 -38.931088)
						(mid 345.584453 -39.060809)
						(end 345.454732 -39.130478)
					)
				)
			)
		)
		(zone
			(layer "F.Cu")
			(hatch none 0.5)
			(connect_pads
				(clearance 0)
			)
			(min_thickness 0.25)
			(keepout
				(tracks not_allowed)
				(vias allowed)
				(pads allowed)
				(copperpour not_allowed)
				(footprints allowed)
			)
			(placement
				(enabled no)
				(sheetname "")
			)
			(fill
				(thermal_gap 0.5)
				(thermal_bridge_width 0.5)
				(island_removal_mode 0)
			)
			(polygon
				(pts
					(arc
						(start 345.454732 -38.19525)
						(mid 345.512595 -38.158879)
						(end 345.548966 -38.101016)
					)
					(arc
						(start 345.654122 -38.101016)
						(mid 345.584453 -38.230737)
						(end 345.454732 -38.300406)
					)
				)
			)
		)
		(zone
			(layer "F.Cu")
			(hatch none 0.5)
			(connect_pads
				(clearance 0)
			)
			(min_thickness 0.25)
			(keepout
				(tracks not_allowed)
				(vias allowed)
				(pads allowed)
				(copperpour not_allowed)
				(footprints allowed)
			)
			(placement
				(enabled no)
				(sheetname "")
			)
			(fill
				(thermal_gap 0.5)
				(thermal_bridge_width 0.5)
				(island_removal_mode 0)
			)
			(polygon
				(pts
					(arc
						(start 345.503754 -56.809386)
						(mid 345.445891 -56.845757)
						(end 345.40952 -56.90362)
					)
					(arc
						(start 345.304364 -56.90362)
						(mid 345.374033 -56.773899)
						(end 345.503754 -56.70423)
					)
				)
			)
		)
		(zone
			(layer "F.Cu")
			(hatch none 0.5)
			(connect_pads
				(clearance 0)
			)
			(min_thickness 0.25)
			(keepout
				(tracks not_allowed)
				(vias allowed)
				(pads allowed)
				(copperpour not_allowed)
				(footprints allowed)
			)
			(placement
				(enabled no)
				(sheetname "")
			)
			(fill
				(thermal_gap 0.5)
				(thermal_bridge_width 0.5)
				(island_removal_mode 0)
			)
			(polygon
				(pts
					(arc
						(start 345.503754 -55.80888)
						(mid 345.445891 -55.845251)
						(end 345.40952 -55.903114)
					)
					(arc
						(start 345.304364 -55.903114)
						(mid 345.374033 -55.773393)
						(end 345.503754 -55.703724)
					)
				)
			)
		)
		(zone
			(layer "F.Cu")
			(hatch none 0.5)
			(connect_pads
				(clearance 0)
			)
			(min_thickness 0.25)
			(keepout
				(tracks not_allowed)
				(vias allowed)
				(pads allowed)
				(copperpour not_allowed)
				(footprints allowed)
			)
			(placement
				(enabled no)
				(sheetname "")
			)
			(fill
				(thermal_gap 0.5)
				(thermal_bridge_width 0.5)
				(island_removal_mode 0)
			)
			(polygon
				(pts
					(arc
						(start 345.503754 -54.808374)
						(mid 345.445891 -54.844745)
						(end 345.40952 -54.902608)
					)
					(arc
						(start 345.304364 -54.902608)
						(mid 345.374033 -54.772887)
						(end 345.503754 -54.703218)
					)
				)
			)
		)
		(zone
			(layer "F.Cu")
			(hatch none 0.5)
			(connect_pads
				(clearance 0)
			)
			(min_thickness 0.25)
			(keepout
				(tracks not_allowed)
				(vias allowed)
				(pads allowed)
				(copperpour not_allowed)
				(footprints allowed)
			)
			(placement
				(enabled no)
				(sheetname "")
			)
			(fill
				(thermal_gap 0.5)
				(thermal_bridge_width 0.5)
				(island_removal_mode 0)
			)
			(polygon
				(pts
					(arc
						(start 345.503754 -53.807868)
						(mid 345.445891 -53.844239)
						(end 345.40952 -53.902102)
					)
					(arc
						(start 345.304364 -53.902102)
						(mid 345.374033 -53.772381)
						(end 345.503754 -53.702712)
					)
				)
			)
		)
		(zone
			(layer "F.Cu")
			(hatch none 0.5)
			(connect_pads
				(clearance 0)
			)
			(min_thickness 0.25)
			(keepout
				(tracks not_allowed)
				(vias allowed)
				(pads allowed)
				(copperpour not_allowed)
				(footprints allowed)
			)
			(placement
				(enabled no)
				(sheetname "")
			)
			(fill
				(thermal_gap 0.5)
				(thermal_bridge_width 0.5)
				(island_removal_mode 0)
			)
			(polygon
				(pts
					(arc
						(start 345.503754 -52.807362)
						(mid 345.445891 -52.843733)
						(end 345.40952 -52.901596)
					)
					(arc
						(start 345.304364 -52.901596)
						(mid 345.374033 -52.771875)
						(end 345.503754 -52.702206)
					)
				)
			)
		)
		(zone
			(layer "F.Cu")
			(hatch none 0.5)
			(connect_pads
				(clearance 0)
			)
			(min_thickness 0.25)
			(keepout
				(tracks not_allowed)
				(vias allowed)
				(pads allowed)
				(copperpour not_allowed)
				(footprints allowed)
			)
			(placement
				(enabled no)
				(sheetname "")
			)
			(fill
				(thermal_gap 0.5)
				(thermal_bridge_width 0.5)
				(island_removal_mode 0)
			)
			(polygon
				(pts
					(arc
						(start 345.503754 -51.806856)
						(mid 345.445891 -51.843227)
						(end 345.40952 -51.90109)
					)
					(arc
						(start 345.304364 -51.90109)
						(mid 345.374033 -51.771369)
						(end 345.503754 -51.7017)
					)
				)
			)
		)
		(zone
			(layer "F.Cu")
			(hatch none 0.5)
			(connect_pads
				(clearance 0)
			)
			(min_thickness 0.25)
			(keepout
				(tracks not_allowed)
				(vias allowed)
				(pads allowed)
				(copperpour not_allowed)
				(footprints allowed)
			)
			(placement
				(enabled no)
				(sheetname "")
			)
			(fill
				(thermal_gap 0.5)
				(thermal_bridge_width 0.5)
				(island_removal_mode 0)
			)
			(polygon
				(pts
					(arc
						(start 345.503754 -50.80635)
						(mid 345.445891 -50.842721)
						(end 345.40952 -50.900584)
					)
					(arc
						(start 345.304364 -50.900584)
						(mid 345.374033 -50.770863)
						(end 345.503754 -50.701194)
					)
				)
			)
		)
		(zone
			(layer "F.Cu")
			(hatch none 0.5)
			(connect_pads
				(clearance 0)
			)
			(min_thickness 0.25)
			(keepout
				(tracks not_allowed)
				(vias allowed)
				(pads allowed)
				(copperpour not_allowed)
				(footprints allowed)
			)
			(placement
				(enabled no)
				(sheetname "")
			)
			(fill
				(thermal_gap 0.5)
				(thermal_bridge_width 0.5)
				(island_removal_mode 0)
			)
			(polygon
				(pts
					(arc
						(start 345.503754 -49.805844)
						(mid 345.445891 -49.842215)
						(end 345.40952 -49.900078)
					)
					(arc
						(start 345.304364 -49.900078)
						(mid 345.374033 -49.770357)
						(end 345.503754 -49.700688)
					)
				)
			)
		)
		(zone
			(layer "F.Cu")
			(hatch none 0.5)
			(connect_pads
				(clearance 0)
			)
			(min_thickness 0.25)
			(keepout
				(tracks not_allowed)
				(vias allowed)
				(pads allowed)
				(copperpour not_allowed)
				(footprints allowed)
			)
			(placement
				(enabled no)
				(sheetname "")
			)
			(fill
				(thermal_gap 0.5)
				(thermal_bridge_width 0.5)
				(island_removal_mode 0)
			)
			(polygon
				(pts
					(arc
						(start 345.503754 -48.805338)
						(mid 345.445891 -48.841709)
						(end 345.40952 -48.899572)
					)
					(arc
						(start 345.304364 -48.899572)
						(mid 345.374033 -48.769851)
						(end 345.503754 -48.700182)
					)
				)
			)
		)
		(zone
			(layer "F.Cu")
			(hatch none 0.5)
			(connect_pads
				(clearance 0)
			)
			(min_thickness 0.25)
			(keepout
				(tracks not_allowed)
				(vias allowed)
				(pads allowed)
				(copperpour not_allowed)
				(footprints allowed)
			)
			(placement
				(enabled no)
				(sheetname "")
			)
			(fill
				(thermal_gap 0.5)
				(thermal_bridge_width 0.5)
				(island_removal_mode 0)
			)
			(polygon
				(pts
					(arc
						(start 345.503754 -47.805086)
						(mid 345.445891 -47.841457)
						(end 345.40952 -47.89932)
					)
					(arc
						(start 345.304364 -47.89932)
						(mid 345.374033 -47.769599)
						(end 345.503754 -47.69993)
					)
				)
			)
		)
		(zone
			(layer "F.Cu")
			(hatch none 0.5)
			(connect_pads
				(clearance 0)
			)
			(min_thickness 0.25)
			(keepout
				(tracks not_allowed)
				(vias allowed)
				(pads allowed)
				(copperpour not_allowed)
				(footprints allowed)
			)
			(placement
				(enabled no)
				(sheetname "")
			)
			(fill
				(thermal_gap 0.5)
				(thermal_bridge_width 0.5)
				(island_removal_mode 0)
			)
			(polygon
				(pts
					(arc
						(start 345.503754 -46.80458)
						(mid 345.445891 -46.840951)
						(end 345.40952 -46.898814)
					)
					(arc
						(start 345.304364 -46.898814)
						(mid 345.374033 -46.769093)
						(end 345.503754 -46.699424)
					)
				)
			)
		)
		(zone
			(layer "F.Cu")
			(hatch none 0.5)
			(connect_pads
				(clearance 0)
			)
			(min_thickness 0.25)
			(keepout
				(tracks not_allowed)
				(vias allowed)
				(pads allowed)
				(copperpour not_allowed)
				(footprints allowed)
			)
			(placement
				(enabled no)
				(sheetname "")
			)
			(fill
				(thermal_gap 0.5)
				(thermal_bridge_width 0.5)
				(island_removal_mode 0)
			)
			(polygon
				(pts
					(arc
						(start 345.503754 -45.804074)
						(mid 345.445891 -45.840445)
						(end 345.40952 -45.898308)
					)
					(arc
						(start 345.304364 -45.898308)
						(mid 345.374033 -45.768587)
						(end 345.503754 -45.698918)
					)
				)
			)
		)
		(zone
			(layer "F.Cu")
			(hatch none 0.5)
			(connect_pads
				(clearance 0)
			)
			(min_thickness 0.25)
			(keepout
				(tracks not_allowed)
				(vias allowed)
				(pads allowed)
				(copperpour not_allowed)
				(footprints allowed)
			)
			(placement
				(enabled no)
				(sheetname "")
			)
			(fill
				(thermal_gap 0.5)
				(thermal_bridge_width 0.5)
				(island_removal_mode 0)
			)
			(polygon
				(pts
					(arc
						(start 345.503754 -44.803568)
						(mid 345.445891 -44.839939)
						(end 345.40952 -44.897802)
					)
					(arc
						(start 345.304364 -44.897802)
						(mid 345.374033 -44.768081)
						(end 345.503754 -44.698412)
					)
				)
			)
		)
		(zone
			(layer "F.Cu")
			(hatch none 0.5)
			(connect_pads
				(clearance 0)
			)
			(min_thickness 0.25)
			(keepout
				(tracks not_allowed)
				(vias allowed)
				(pads allowed)
				(copperpour not_allowed)
				(footprints allowed)
			)
			(placement
				(enabled no)
				(sheetname "")
			)
			(fill
				(thermal_gap 0.5)
				(thermal_bridge_width 0.5)
				(island_removal_mode 0)
			)
			(polygon
				(pts
					(arc
						(start 345.503754 -43.803062)
						(mid 345.445891 -43.839433)
						(end 345.40952 -43.897296)
					)
					(arc
						(start 345.304364 -43.897296)
						(mid 345.374033 -43.767575)
						(end 345.503754 -43.697906)
					)
				)
			)
		)
		(zone
			(layer "F.Cu")
			(hatch none 0.5)
			(connect_pads
				(clearance 0)
			)
			(min_thickness 0.25)
			(keepout
				(tracks not_allowed)
				(vias allowed)
				(pads allowed)
				(copperpour not_allowed)
				(footprints allowed)
			)
			(placement
				(enabled no)
				(sheetname "")
			)
			(fill
				(thermal_gap 0.5)
				(thermal_bridge_width 0.5)
				(island_removal_mode 0)
			)
			(polygon
				(pts
					(arc
						(start 345.503754 -42.802556)
						(mid 345.445891 -42.838927)
						(end 345.40952 -42.89679)
					)
					(arc
						(start 345.304364 -42.89679)
						(mid 345.374033 -42.767069)
						(end 345.503754 -42.6974)
					)
				)
			)
		)
		(zone
			(layer "F.Cu")
			(hatch none 0.5)
			(connect_pads
				(clearance 0)
			)
			(min_thickness 0.25)
			(keepout
				(tracks not_allowed)
				(vias allowed)
				(pads allowed)
				(copperpour not_allowed)
				(footprints allowed)
			)
			(placement
				(enabled no)
				(sheetname "")
			)
			(fill
				(thermal_gap 0.5)
				(thermal_bridge_width 0.5)
				(island_removal_mode 0)
			)
			(polygon
				(pts
					(arc
						(start 345.503754 -41.80205)
						(mid 345.445891 -41.838421)
						(end 345.40952 -41.896284)
					)
					(arc
						(start 345.304364 -41.896284)
						(mid 345.374033 -41.766563)
						(end 345.503754 -41.696894)
					)
				)
			)
		)
		(zone
			(layer "F.Cu")
			(hatch none 0.5)
			(connect_pads
				(clearance 0)
			)
			(min_thickness 0.25)
			(keepout
				(tracks not_allowed)
				(vias allowed)
				(pads allowed)
				(copperpour not_allowed)
				(footprints allowed)
			)
			(placement
				(enabled no)
				(sheetname "")
			)
			(fill
				(thermal_gap 0.5)
				(thermal_bridge_width 0.5)
				(island_removal_mode 0)
			)
			(polygon
				(pts
					(arc
						(start 345.503754 -40.801544)
						(mid 345.445891 -40.837915)
						(end 345.40952 -40.895778)
					)
					(arc
						(start 345.304364 -40.895778)
						(mid 345.374033 -40.766057)
						(end 345.503754 -40.696388)
					)
				)
			)
		)
		(zone
			(layer "F.Cu")
			(hatch none 0.5)
			(connect_pads
				(clearance 0)
			)
			(min_thickness 0.25)
			(keepout
				(tracks not_allowed)
				(vias allowed)
				(pads allowed)
				(copperpour not_allowed)
				(footprints allowed)
			)
			(placement
				(enabled no)
				(sheetname "")
			)
			(fill
				(thermal_gap 0.5)
				(thermal_bridge_width 0.5)
				(island_removal_mode 0)
			)
			(polygon
				(pts
					(arc
						(start 345.503754 -39.801038)
						(mid 345.445891 -39.837409)
						(end 345.40952 -39.895272)
					)
					(arc
						(start 345.304364 -39.895272)
						(mid 345.374033 -39.765551)
						(end 345.503754 -39.695882)
					)
				)
			)
		)
		(zone
			(layer "F.Cu")
			(hatch none 0.5)
			(connect_pads
				(clearance 0)
			)
			(min_thickness 0.25)
			(keepout
				(tracks not_allowed)
				(vias allowed)
				(pads allowed)
				(copperpour not_allowed)
				(footprints allowed)
			)
			(placement
				(enabled no)
				(sheetname "")
			)
			(fill
				(thermal_gap 0.5)
				(thermal_bridge_width 0.5)
				(island_removal_mode 0)
			)
			(polygon
				(pts
					(arc
						(start 345.548966 -58.799476)
						(mid 345.512595 -58.741613)
						(end 345.454732 -58.705242)
					)
					(arc
						(start 345.454732 -58.600086)
						(mid 345.584453 -58.669755)
						(end 345.654122 -58.799476)
					)
				)
			)
		)
		(zone
			(layer "F.Cu")
			(hatch none 0.5)
			(connect_pads
				(clearance 0)
			)
			(min_thickness 0.25)
			(keepout
				(tracks not_allowed)
				(vias allowed)
				(pads allowed)
				(copperpour not_allowed)
				(footprints allowed)
			)
			(placement
				(enabled no)
				(sheetname "")
			)
			(fill
				(thermal_gap 0.5)
				(thermal_bridge_width 0.5)
				(island_removal_mode 0)
			)
			(polygon
				(pts
					(arc
						(start 345.548966 -57.969404)
						(mid 345.512595 -57.911541)
						(end 345.454732 -57.87517)
					)
					(arc
						(start 345.454732 -57.770014)
						(mid 345.584453 -57.839683)
						(end 345.654122 -57.969404)
					)
				)
			)
		)
		(zone
			(layer "F.Cu")
			(hatch none 0.5)
			(connect_pads
				(clearance 0)
			)
			(min_thickness 0.25)
			(keepout
				(tracks not_allowed)
				(vias allowed)
				(pads allowed)
				(copperpour not_allowed)
				(footprints allowed)
			)
			(placement
				(enabled no)
				(sheetname "")
			)
			(fill
				(thermal_gap 0.5)
				(thermal_bridge_width 0.5)
				(island_removal_mode 0)
			)
			(polygon
				(pts
					(arc
						(start 345.548966 -38.829488)
						(mid 345.512595 -38.771625)
						(end 345.454732 -38.735254)
					)
					(arc
						(start 345.454732 -38.630098)
						(mid 345.584453 -38.699767)
						(end 345.654122 -38.829488)
					)
				)
			)
		)
		(zone
			(layer "F.Cu")
			(hatch none 0.5)
			(connect_pads
				(clearance 0)
			)
			(min_thickness 0.25)
			(keepout
				(tracks not_allowed)
				(vias allowed)
				(pads allowed)
				(copperpour not_allowed)
				(footprints allowed)
			)
			(placement
				(enabled no)
				(sheetname "")
			)
			(fill
				(thermal_gap 0.5)
				(thermal_bridge_width 0.5)
				(island_removal_mode 0)
			)
			(polygon
				(pts
					(arc
						(start 345.548966 -37.999416)
						(mid 345.512595 -37.941553)
						(end 345.454732 -37.905182)
					)
					(arc
						(start 345.454732 -37.800026)
						(mid 345.584453 -37.869695)
						(end 345.654122 -37.999416)
					)
				)
			)
		)
		(zone
			(layer "F.Cu")
			(hatch none 0.5)
			(connect_pads
				(clearance 0)
			)
			(min_thickness 0.25)
			(keepout
				(tracks not_allowed)
				(vias allowed)
				(pads allowed)
				(copperpour not_allowed)
				(footprints allowed)
			)
			(placement
				(enabled no)
				(sheetname "")
			)
			(fill
				(thermal_gap 0.5)
				(thermal_bridge_width 0.5)
				(island_removal_mode 0)
			)
			(polygon
				(pts
					(arc
						(start 345.605354 -57.099454)
						(mid 345.663217 -57.063083)
						(end 345.699588 -57.00522)
					)
					(arc
						(start 345.804744 -57.00522)
						(mid 345.735075 -57.134941)
						(end 345.605354 -57.20461)
					)
				)
			)
		)
		(zone
			(layer "F.Cu")
			(hatch none 0.5)
			(connect_pads
				(clearance 0)
			)
			(min_thickness 0.25)
			(keepout
				(tracks not_allowed)
				(vias allowed)
				(pads allowed)
				(copperpour not_allowed)
				(footprints allowed)
			)
			(placement
				(enabled no)
				(sheetname "")
			)
			(fill
				(thermal_gap 0.5)
				(thermal_bridge_width 0.5)
				(island_removal_mode 0)
			)
			(polygon
				(pts
					(arc
						(start 345.605354 -56.098948)
						(mid 345.663217 -56.062577)
						(end 345.699588 -56.004714)
					)
					(arc
						(start 345.804744 -56.004714)
						(mid 345.735075 -56.134435)
						(end 345.605354 -56.204104)
					)
				)
			)
		)
		(zone
			(layer "F.Cu")
			(hatch none 0.5)
			(connect_pads
				(clearance 0)
			)
			(min_thickness 0.25)
			(keepout
				(tracks not_allowed)
				(vias allowed)
				(pads allowed)
				(copperpour not_allowed)
				(footprints allowed)
			)
			(placement
				(enabled no)
				(sheetname "")
			)
			(fill
				(thermal_gap 0.5)
				(thermal_bridge_width 0.5)
				(island_removal_mode 0)
			)
			(polygon
				(pts
					(arc
						(start 345.605354 -55.098442)
						(mid 345.663217 -55.062071)
						(end 345.699588 -55.004208)
					)
					(arc
						(start 345.804744 -55.004208)
						(mid 345.735075 -55.133929)
						(end 345.605354 -55.203598)
					)
				)
			)
		)
		(zone
			(layer "F.Cu")
			(hatch none 0.5)
			(connect_pads
				(clearance 0)
			)
			(min_thickness 0.25)
			(keepout
				(tracks not_allowed)
				(vias allowed)
				(pads allowed)
				(copperpour not_allowed)
				(footprints allowed)
			)
			(placement
				(enabled no)
				(sheetname "")
			)
			(fill
				(thermal_gap 0.5)
				(thermal_bridge_width 0.5)
				(island_removal_mode 0)
			)
			(polygon
				(pts
					(arc
						(start 345.605354 -54.097936)
						(mid 345.663217 -54.061565)
						(end 345.699588 -54.003702)
					)
					(arc
						(start 345.804744 -54.003702)
						(mid 345.735075 -54.133423)
						(end 345.605354 -54.203092)
					)
				)
			)
		)
		(zone
			(layer "F.Cu")
			(hatch none 0.5)
			(connect_pads
				(clearance 0)
			)
			(min_thickness 0.25)
			(keepout
				(tracks not_allowed)
				(vias allowed)
				(pads allowed)
				(copperpour not_allowed)
				(footprints allowed)
			)
			(placement
				(enabled no)
				(sheetname "")
			)
			(fill
				(thermal_gap 0.5)
				(thermal_bridge_width 0.5)
				(island_removal_mode 0)
			)
			(polygon
				(pts
					(arc
						(start 345.605354 -53.09743)
						(mid 345.663217 -53.061059)
						(end 345.699588 -53.003196)
					)
					(arc
						(start 345.804744 -53.003196)
						(mid 345.735075 -53.132917)
						(end 345.605354 -53.202586)
					)
				)
			)
		)
		(zone
			(layer "F.Cu")
			(hatch none 0.5)
			(connect_pads
				(clearance 0)
			)
			(min_thickness 0.25)
			(keepout
				(tracks not_allowed)
				(vias allowed)
				(pads allowed)
				(copperpour not_allowed)
				(footprints allowed)
			)
			(placement
				(enabled no)
				(sheetname "")
			)
			(fill
				(thermal_gap 0.5)
				(thermal_bridge_width 0.5)
				(island_removal_mode 0)
			)
			(polygon
				(pts
					(arc
						(start 345.605354 -52.096924)
						(mid 345.663217 -52.060553)
						(end 345.699588 -52.00269)
					)
					(arc
						(start 345.804744 -52.00269)
						(mid 345.735075 -52.132411)
						(end 345.605354 -52.20208)
					)
				)
			)
		)
		(zone
			(layer "F.Cu")
			(hatch none 0.5)
			(connect_pads
				(clearance 0)
			)
			(min_thickness 0.25)
			(keepout
				(tracks not_allowed)
				(vias allowed)
				(pads allowed)
				(copperpour not_allowed)
				(footprints allowed)
			)
			(placement
				(enabled no)
				(sheetname "")
			)
			(fill
				(thermal_gap 0.5)
				(thermal_bridge_width 0.5)
				(island_removal_mode 0)
			)
			(polygon
				(pts
					(arc
						(start 345.605354 -51.096418)
						(mid 345.663217 -51.060047)
						(end 345.699588 -51.002184)
					)
					(arc
						(start 345.804744 -51.002184)
						(mid 345.735075 -51.131905)
						(end 345.605354 -51.201574)
					)
				)
			)
		)
		(zone
			(layer "F.Cu")
			(hatch none 0.5)
			(connect_pads
				(clearance 0)
			)
			(min_thickness 0.25)
			(keepout
				(tracks not_allowed)
				(vias allowed)
				(pads allowed)
				(copperpour not_allowed)
				(footprints allowed)
			)
			(placement
				(enabled no)
				(sheetname "")
			)
			(fill
				(thermal_gap 0.5)
				(thermal_bridge_width 0.5)
				(island_removal_mode 0)
			)
			(polygon
				(pts
					(arc
						(start 345.605354 -50.095912)
						(mid 345.663217 -50.059541)
						(end 345.699588 -50.001678)
					)
					(arc
						(start 345.804744 -50.001678)
						(mid 345.735075 -50.131399)
						(end 345.605354 -50.201068)
					)
				)
			)
		)
		(zone
			(layer "F.Cu")
			(hatch none 0.5)
			(connect_pads
				(clearance 0)
			)
			(min_thickness 0.25)
			(keepout
				(tracks not_allowed)
				(vias allowed)
				(pads allowed)
				(copperpour not_allowed)
				(footprints allowed)
			)
			(placement
				(enabled no)
				(sheetname "")
			)
			(fill
				(thermal_gap 0.5)
				(thermal_bridge_width 0.5)
				(island_removal_mode 0)
			)
			(polygon
				(pts
					(arc
						(start 345.605354 -49.095406)
						(mid 345.663217 -49.059035)
						(end 345.699588 -49.001172)
					)
					(arc
						(start 345.804744 -49.001172)
						(mid 345.735075 -49.130893)
						(end 345.605354 -49.200562)
					)
				)
			)
		)
		(zone
			(layer "F.Cu")
			(hatch none 0.5)
			(connect_pads
				(clearance 0)
			)
			(min_thickness 0.25)
			(keepout
				(tracks not_allowed)
				(vias allowed)
				(pads allowed)
				(copperpour not_allowed)
				(footprints allowed)
			)
			(placement
				(enabled no)
				(sheetname "")
			)
			(fill
				(thermal_gap 0.5)
				(thermal_bridge_width 0.5)
				(island_removal_mode 0)
			)
			(polygon
				(pts
					(arc
						(start 345.605354 -48.095154)
						(mid 345.663217 -48.058783)
						(end 345.699588 -48.00092)
					)
					(arc
						(start 345.804744 -48.00092)
						(mid 345.735075 -48.130641)
						(end 345.605354 -48.20031)
					)
				)
			)
		)
		(zone
			(layer "F.Cu")
			(hatch none 0.5)
			(connect_pads
				(clearance 0)
			)
			(min_thickness 0.25)
			(keepout
				(tracks not_allowed)
				(vias allowed)
				(pads allowed)
				(copperpour not_allowed)
				(footprints allowed)
			)
			(placement
				(enabled no)
				(sheetname "")
			)
			(fill
				(thermal_gap 0.5)
				(thermal_bridge_width 0.5)
				(island_removal_mode 0)
			)
			(polygon
				(pts
					(arc
						(start 345.605354 -47.094648)
						(mid 345.663217 -47.058277)
						(end 345.699588 -47.000414)
					)
					(arc
						(start 345.804744 -47.000414)
						(mid 345.735075 -47.130135)
						(end 345.605354 -47.199804)
					)
				)
			)
		)
		(zone
			(layer "F.Cu")
			(hatch none 0.5)
			(connect_pads
				(clearance 0)
			)
			(min_thickness 0.25)
			(keepout
				(tracks not_allowed)
				(vias allowed)
				(pads allowed)
				(copperpour not_allowed)
				(footprints allowed)
			)
			(placement
				(enabled no)
				(sheetname "")
			)
			(fill
				(thermal_gap 0.5)
				(thermal_bridge_width 0.5)
				(island_removal_mode 0)
			)
			(polygon
				(pts
					(arc
						(start 345.605354 -46.094142)
						(mid 345.663217 -46.057771)
						(end 345.699588 -45.999908)
					)
					(arc
						(start 345.804744 -45.999908)
						(mid 345.735075 -46.129629)
						(end 345.605354 -46.199298)
					)
				)
			)
		)
		(zone
			(layer "F.Cu")
			(hatch none 0.5)
			(connect_pads
				(clearance 0)
			)
			(min_thickness 0.25)
			(keepout
				(tracks not_allowed)
				(vias allowed)
				(pads allowed)
				(copperpour not_allowed)
				(footprints allowed)
			)
			(placement
				(enabled no)
				(sheetname "")
			)
			(fill
				(thermal_gap 0.5)
				(thermal_bridge_width 0.5)
				(island_removal_mode 0)
			)
			(polygon
				(pts
					(arc
						(start 345.605354 -45.093636)
						(mid 345.663217 -45.057265)
						(end 345.699588 -44.999402)
					)
					(arc
						(start 345.804744 -44.999402)
						(mid 345.735075 -45.129123)
						(end 345.605354 -45.198792)
					)
				)
			)
		)
		(zone
			(layer "F.Cu")
			(hatch none 0.5)
			(connect_pads
				(clearance 0)
			)
			(min_thickness 0.25)
			(keepout
				(tracks not_allowed)
				(vias allowed)
				(pads allowed)
				(copperpour not_allowed)
				(footprints allowed)
			)
			(placement
				(enabled no)
				(sheetname "")
			)
			(fill
				(thermal_gap 0.5)
				(thermal_bridge_width 0.5)
				(island_removal_mode 0)
			)
			(polygon
				(pts
					(arc
						(start 345.605354 -44.09313)
						(mid 345.663217 -44.056759)
						(end 345.699588 -43.998896)
					)
					(arc
						(start 345.804744 -43.998896)
						(mid 345.735075 -44.128617)
						(end 345.605354 -44.198286)
					)
				)
			)
		)
		(zone
			(layer "F.Cu")
			(hatch none 0.5)
			(connect_pads
				(clearance 0)
			)
			(min_thickness 0.25)
			(keepout
				(tracks not_allowed)
				(vias allowed)
				(pads allowed)
				(copperpour not_allowed)
				(footprints allowed)
			)
			(placement
				(enabled no)
				(sheetname "")
			)
			(fill
				(thermal_gap 0.5)
				(thermal_bridge_width 0.5)
				(island_removal_mode 0)
			)
			(polygon
				(pts
					(arc
						(start 345.605354 -43.092624)
						(mid 345.663217 -43.056253)
						(end 345.699588 -42.99839)
					)
					(arc
						(start 345.804744 -42.99839)
						(mid 345.735075 -43.128111)
						(end 345.605354 -43.19778)
					)
				)
			)
		)
		(zone
			(layer "F.Cu")
			(hatch none 0.5)
			(connect_pads
				(clearance 0)
			)
			(min_thickness 0.25)
			(keepout
				(tracks not_allowed)
				(vias allowed)
				(pads allowed)
				(copperpour not_allowed)
				(footprints allowed)
			)
			(placement
				(enabled no)
				(sheetname "")
			)
			(fill
				(thermal_gap 0.5)
				(thermal_bridge_width 0.5)
				(island_removal_mode 0)
			)
			(polygon
				(pts
					(arc
						(start 345.605354 -42.092118)
						(mid 345.663217 -42.055747)
						(end 345.699588 -41.997884)
					)
					(arc
						(start 345.804744 -41.997884)
						(mid 345.735075 -42.127605)
						(end 345.605354 -42.197274)
					)
				)
			)
		)
		(zone
			(layer "F.Cu")
			(hatch none 0.5)
			(connect_pads
				(clearance 0)
			)
			(min_thickness 0.25)
			(keepout
				(tracks not_allowed)
				(vias allowed)
				(pads allowed)
				(copperpour not_allowed)
				(footprints allowed)
			)
			(placement
				(enabled no)
				(sheetname "")
			)
			(fill
				(thermal_gap 0.5)
				(thermal_bridge_width 0.5)
				(island_removal_mode 0)
			)
			(polygon
				(pts
					(arc
						(start 345.605354 -41.091612)
						(mid 345.663217 -41.055241)
						(end 345.699588 -40.997378)
					)
					(arc
						(start 345.804744 -40.997378)
						(mid 345.735075 -41.127099)
						(end 345.605354 -41.196768)
					)
				)
			)
		)
		(zone
			(layer "F.Cu")
			(hatch none 0.5)
			(connect_pads
				(clearance 0)
			)
			(min_thickness 0.25)
			(keepout
				(tracks not_allowed)
				(vias allowed)
				(pads allowed)
				(copperpour not_allowed)
				(footprints allowed)
			)
			(placement
				(enabled no)
				(sheetname "")
			)
			(fill
				(thermal_gap 0.5)
				(thermal_bridge_width 0.5)
				(island_removal_mode 0)
			)
			(polygon
				(pts
					(arc
						(start 345.605354 -40.091106)
						(mid 345.663217 -40.054735)
						(end 345.699588 -39.996872)
					)
					(arc
						(start 345.804744 -39.996872)
						(mid 345.735075 -40.126593)
						(end 345.605354 -40.196262)
					)
				)
			)
		)
		(zone
			(layer "F.Cu")
			(hatch none 0.5)
			(connect_pads
				(clearance 0)
			)
			(min_thickness 0.25)
			(keepout
				(tracks not_allowed)
				(vias allowed)
				(pads allowed)
				(copperpour not_allowed)
				(footprints allowed)
			)
			(placement
				(enabled no)
				(sheetname "")
			)
			(fill
				(thermal_gap 0.5)
				(thermal_bridge_width 0.5)
				(island_removal_mode 0)
			)
			(polygon
				(pts
					(arc
						(start 345.699588 -56.90362)
						(mid 345.663217 -56.845757)
						(end 345.605354 -56.809386)
					)
					(arc
						(start 345.605354 -56.70423)
						(mid 345.735075 -56.773899)
						(end 345.804744 -56.90362)
					)
				)
			)
		)
		(zone
			(layer "F.Cu")
			(hatch none 0.5)
			(connect_pads
				(clearance 0)
			)
			(min_thickness 0.25)
			(keepout
				(tracks not_allowed)
				(vias allowed)
				(pads allowed)
				(copperpour not_allowed)
				(footprints allowed)
			)
			(placement
				(enabled no)
				(sheetname "")
			)
			(fill
				(thermal_gap 0.5)
				(thermal_bridge_width 0.5)
				(island_removal_mode 0)
			)
			(polygon
				(pts
					(arc
						(start 345.699588 -55.903114)
						(mid 345.663217 -55.845251)
						(end 345.605354 -55.80888)
					)
					(arc
						(start 345.605354 -55.703724)
						(mid 345.735075 -55.773393)
						(end 345.804744 -55.903114)
					)
				)
			)
		)
		(zone
			(layer "F.Cu")
			(hatch none 0.5)
			(connect_pads
				(clearance 0)
			)
			(min_thickness 0.25)
			(keepout
				(tracks not_allowed)
				(vias allowed)
				(pads allowed)
				(copperpour not_allowed)
				(footprints allowed)
			)
			(placement
				(enabled no)
				(sheetname "")
			)
			(fill
				(thermal_gap 0.5)
				(thermal_bridge_width 0.5)
				(island_removal_mode 0)
			)
			(polygon
				(pts
					(arc
						(start 345.699588 -54.902608)
						(mid 345.663217 -54.844745)
						(end 345.605354 -54.808374)
					)
					(arc
						(start 345.605354 -54.703218)
						(mid 345.735075 -54.772887)
						(end 345.804744 -54.902608)
					)
				)
			)
		)
		(zone
			(layer "F.Cu")
			(hatch none 0.5)
			(connect_pads
				(clearance 0)
			)
			(min_thickness 0.25)
			(keepout
				(tracks not_allowed)
				(vias allowed)
				(pads allowed)
				(copperpour not_allowed)
				(footprints allowed)
			)
			(placement
				(enabled no)
				(sheetname "")
			)
			(fill
				(thermal_gap 0.5)
				(thermal_bridge_width 0.5)
				(island_removal_mode 0)
			)
			(polygon
				(pts
					(arc
						(start 345.699588 -53.902102)
						(mid 345.663217 -53.844239)
						(end 345.605354 -53.807868)
					)
					(arc
						(start 345.605354 -53.702712)
						(mid 345.735075 -53.772381)
						(end 345.804744 -53.902102)
					)
				)
			)
		)
		(zone
			(layer "F.Cu")
			(hatch none 0.5)
			(connect_pads
				(clearance 0)
			)
			(min_thickness 0.25)
			(keepout
				(tracks not_allowed)
				(vias allowed)
				(pads allowed)
				(copperpour not_allowed)
				(footprints allowed)
			)
			(placement
				(enabled no)
				(sheetname "")
			)
			(fill
				(thermal_gap 0.5)
				(thermal_bridge_width 0.5)
				(island_removal_mode 0)
			)
			(polygon
				(pts
					(arc
						(start 345.699588 -52.901596)
						(mid 345.663217 -52.843733)
						(end 345.605354 -52.807362)
					)
					(arc
						(start 345.605354 -52.702206)
						(mid 345.735075 -52.771875)
						(end 345.804744 -52.901596)
					)
				)
			)
		)
		(zone
			(layer "F.Cu")
			(hatch none 0.5)
			(connect_pads
				(clearance 0)
			)
			(min_thickness 0.25)
			(keepout
				(tracks not_allowed)
				(vias allowed)
				(pads allowed)
				(copperpour not_allowed)
				(footprints allowed)
			)
			(placement
				(enabled no)
				(sheetname "")
			)
			(fill
				(thermal_gap 0.5)
				(thermal_bridge_width 0.5)
				(island_removal_mode 0)
			)
			(polygon
				(pts
					(arc
						(start 345.699588 -51.90109)
						(mid 345.663217 -51.843227)
						(end 345.605354 -51.806856)
					)
					(arc
						(start 345.605354 -51.7017)
						(mid 345.735075 -51.771369)
						(end 345.804744 -51.90109)
					)
				)
			)
		)
		(zone
			(layer "F.Cu")
			(hatch none 0.5)
			(connect_pads
				(clearance 0)
			)
			(min_thickness 0.25)
			(keepout
				(tracks not_allowed)
				(vias allowed)
				(pads allowed)
				(copperpour not_allowed)
				(footprints allowed)
			)
			(placement
				(enabled no)
				(sheetname "")
			)
			(fill
				(thermal_gap 0.5)
				(thermal_bridge_width 0.5)
				(island_removal_mode 0)
			)
			(polygon
				(pts
					(arc
						(start 345.699588 -50.900584)
						(mid 345.663217 -50.842721)
						(end 345.605354 -50.80635)
					)
					(arc
						(start 345.605354 -50.701194)
						(mid 345.735075 -50.770863)
						(end 345.804744 -50.900584)
					)
				)
			)
		)
		(zone
			(layer "F.Cu")
			(hatch none 0.5)
			(connect_pads
				(clearance 0)
			)
			(min_thickness 0.25)
			(keepout
				(tracks not_allowed)
				(vias allowed)
				(pads allowed)
				(copperpour not_allowed)
				(footprints allowed)
			)
			(placement
				(enabled no)
				(sheetname "")
			)
			(fill
				(thermal_gap 0.5)
				(thermal_bridge_width 0.5)
				(island_removal_mode 0)
			)
			(polygon
				(pts
					(arc
						(start 345.699588 -49.900078)
						(mid 345.663217 -49.842215)
						(end 345.605354 -49.805844)
					)
					(arc
						(start 345.605354 -49.700688)
						(mid 345.735075 -49.770357)
						(end 345.804744 -49.900078)
					)
				)
			)
		)
		(zone
			(layer "F.Cu")
			(hatch none 0.5)
			(connect_pads
				(clearance 0)
			)
			(min_thickness 0.25)
			(keepout
				(tracks not_allowed)
				(vias allowed)
				(pads allowed)
				(copperpour not_allowed)
				(footprints allowed)
			)
			(placement
				(enabled no)
				(sheetname "")
			)
			(fill
				(thermal_gap 0.5)
				(thermal_bridge_width 0.5)
				(island_removal_mode 0)
			)
			(polygon
				(pts
					(arc
						(start 345.699588 -48.899572)
						(mid 345.663217 -48.841709)
						(end 345.605354 -48.805338)
					)
					(arc
						(start 345.605354 -48.700182)
						(mid 345.735075 -48.769851)
						(end 345.804744 -48.899572)
					)
				)
			)
		)
		(zone
			(layer "F.Cu")
			(hatch none 0.5)
			(connect_pads
				(clearance 0)
			)
			(min_thickness 0.25)
			(keepout
				(tracks not_allowed)
				(vias allowed)
				(pads allowed)
				(copperpour not_allowed)
				(footprints allowed)
			)
			(placement
				(enabled no)
				(sheetname "")
			)
			(fill
				(thermal_gap 0.5)
				(thermal_bridge_width 0.5)
				(island_removal_mode 0)
			)
			(polygon
				(pts
					(arc
						(start 345.699588 -47.89932)
						(mid 345.663217 -47.841457)
						(end 345.605354 -47.805086)
					)
					(arc
						(start 345.605354 -47.69993)
						(mid 345.735075 -47.769599)
						(end 345.804744 -47.89932)
					)
				)
			)
		)
		(zone
			(layer "F.Cu")
			(hatch none 0.5)
			(connect_pads
				(clearance 0)
			)
			(min_thickness 0.25)
			(keepout
				(tracks not_allowed)
				(vias allowed)
				(pads allowed)
				(copperpour not_allowed)
				(footprints allowed)
			)
			(placement
				(enabled no)
				(sheetname "")
			)
			(fill
				(thermal_gap 0.5)
				(thermal_bridge_width 0.5)
				(island_removal_mode 0)
			)
			(polygon
				(pts
					(arc
						(start 345.699588 -46.898814)
						(mid 345.663217 -46.840951)
						(end 345.605354 -46.80458)
					)
					(arc
						(start 345.605354 -46.699424)
						(mid 345.735075 -46.769093)
						(end 345.804744 -46.898814)
					)
				)
			)
		)
		(zone
			(layer "F.Cu")
			(hatch none 0.5)
			(connect_pads
				(clearance 0)
			)
			(min_thickness 0.25)
			(keepout
				(tracks not_allowed)
				(vias allowed)
				(pads allowed)
				(copperpour not_allowed)
				(footprints allowed)
			)
			(placement
				(enabled no)
				(sheetname "")
			)
			(fill
				(thermal_gap 0.5)
				(thermal_bridge_width 0.5)
				(island_removal_mode 0)
			)
			(polygon
				(pts
					(arc
						(start 345.699588 -45.898308)
						(mid 345.663217 -45.840445)
						(end 345.605354 -45.804074)
					)
					(arc
						(start 345.605354 -45.698918)
						(mid 345.735075 -45.768587)
						(end 345.804744 -45.898308)
					)
				)
			)
		)
		(zone
			(layer "F.Cu")
			(hatch none 0.5)
			(connect_pads
				(clearance 0)
			)
			(min_thickness 0.25)
			(keepout
				(tracks not_allowed)
				(vias allowed)
				(pads allowed)
				(copperpour not_allowed)
				(footprints allowed)
			)
			(placement
				(enabled no)
				(sheetname "")
			)
			(fill
				(thermal_gap 0.5)
				(thermal_bridge_width 0.5)
				(island_removal_mode 0)
			)
			(polygon
				(pts
					(arc
						(start 345.699588 -44.897802)
						(mid 345.663217 -44.839939)
						(end 345.605354 -44.803568)
					)
					(arc
						(start 345.605354 -44.698412)
						(mid 345.735075 -44.768081)
						(end 345.804744 -44.897802)
					)
				)
			)
		)
		(zone
			(layer "F.Cu")
			(hatch none 0.5)
			(connect_pads
				(clearance 0)
			)
			(min_thickness 0.25)
			(keepout
				(tracks not_allowed)
				(vias allowed)
				(pads allowed)
				(copperpour not_allowed)
				(footprints allowed)
			)
			(placement
				(enabled no)
				(sheetname "")
			)
			(fill
				(thermal_gap 0.5)
				(thermal_bridge_width 0.5)
				(island_removal_mode 0)
			)
			(polygon
				(pts
					(arc
						(start 345.699588 -43.897296)
						(mid 345.663217 -43.839433)
						(end 345.605354 -43.803062)
					)
					(arc
						(start 345.605354 -43.697906)
						(mid 345.735075 -43.767575)
						(end 345.804744 -43.897296)
					)
				)
			)
		)
		(zone
			(layer "F.Cu")
			(hatch none 0.5)
			(connect_pads
				(clearance 0)
			)
			(min_thickness 0.25)
			(keepout
				(tracks not_allowed)
				(vias allowed)
				(pads allowed)
				(copperpour not_allowed)
				(footprints allowed)
			)
			(placement
				(enabled no)
				(sheetname "")
			)
			(fill
				(thermal_gap 0.5)
				(thermal_bridge_width 0.5)
				(island_removal_mode 0)
			)
			(polygon
				(pts
					(arc
						(start 345.699588 -42.89679)
						(mid 345.663217 -42.838927)
						(end 345.605354 -42.802556)
					)
					(arc
						(start 345.605354 -42.6974)
						(mid 345.735075 -42.767069)
						(end 345.804744 -42.89679)
					)
				)
			)
		)
		(zone
			(layer "F.Cu")
			(hatch none 0.5)
			(connect_pads
				(clearance 0)
			)
			(min_thickness 0.25)
			(keepout
				(tracks not_allowed)
				(vias allowed)
				(pads allowed)
				(copperpour not_allowed)
				(footprints allowed)
			)
			(placement
				(enabled no)
				(sheetname "")
			)
			(fill
				(thermal_gap 0.5)
				(thermal_bridge_width 0.5)
				(island_removal_mode 0)
			)
			(polygon
				(pts
					(arc
						(start 345.699588 -41.896284)
						(mid 345.663217 -41.838421)
						(end 345.605354 -41.80205)
					)
					(arc
						(start 345.605354 -41.696894)
						(mid 345.735075 -41.766563)
						(end 345.804744 -41.896284)
					)
				)
			)
		)
		(zone
			(layer "F.Cu")
			(hatch none 0.5)
			(connect_pads
				(clearance 0)
			)
			(min_thickness 0.25)
			(keepout
				(tracks not_allowed)
				(vias allowed)
				(pads allowed)
				(copperpour not_allowed)
				(footprints allowed)
			)
			(placement
				(enabled no)
				(sheetname "")
			)
			(fill
				(thermal_gap 0.5)
				(thermal_bridge_width 0.5)
				(island_removal_mode 0)
			)
			(polygon
				(pts
					(arc
						(start 345.699588 -40.895778)
						(mid 345.663217 -40.837915)
						(end 345.605354 -40.801544)
					)
					(arc
						(start 345.605354 -40.696388)
						(mid 345.735075 -40.766057)
						(end 345.804744 -40.895778)
					)
				)
			)
		)
		(zone
			(layer "F.Cu")
			(hatch none 0.5)
			(connect_pads
				(clearance 0)
			)
			(min_thickness 0.25)
			(keepout
				(tracks not_allowed)
				(vias allowed)
				(pads allowed)
				(copperpour not_allowed)
				(footprints allowed)
			)
			(placement
				(enabled no)
				(sheetname "")
			)
			(fill
				(thermal_gap 0.5)
				(thermal_bridge_width 0.5)
				(island_removal_mode 0)
			)
			(polygon
				(pts
					(arc
						(start 345.699588 -39.895272)
						(mid 345.663217 -39.837409)
						(end 345.605354 -39.801038)
					)
					(arc
						(start 345.605354 -39.695882)
						(mid 345.735075 -39.765551)
						(end 345.804744 -39.895272)
					)
				)
			)
		)
		(zone
			(layer "F.Cu")
			(hatch none 0.5)
			(connect_pads
				(clearance 0)
			)
			(min_thickness 0.25)
			(keepout
				(tracks not_allowed)
				(vias allowed)
				(pads allowed)
				(copperpour not_allowed)
				(footprints allowed)
			)
			(placement
				(enabled no)
				(sheetname "")
			)
			(fill
				(thermal_gap 0.5)
				(thermal_bridge_width 0.5)
				(island_removal_mode 0)
			)
			(polygon
				(pts
					(arc
						(start 345.759024 -58.48604)
						(mid 345.79545 -58.543739)
						(end 345.853258 -58.58002)
					)
					(arc
						(start 345.853258 -58.68543)
						(mid 345.723537 -58.615761)
						(end 345.653868 -58.48604)
					)
				)
			)
		)
		(zone
			(layer "F.Cu")
			(hatch none 0.5)
			(connect_pads
				(clearance 0)
			)
			(min_thickness 0.25)
			(keepout
				(tracks not_allowed)
				(vias allowed)
				(pads allowed)
				(copperpour not_allowed)
				(footprints allowed)
			)
			(placement
				(enabled no)
				(sheetname "")
			)
			(fill
				(thermal_gap 0.5)
				(thermal_bridge_width 0.5)
				(island_removal_mode 0)
			)
			(polygon
				(pts
					(arc
						(start 345.759024 -38.516052)
						(mid 345.795395 -38.573915)
						(end 345.853258 -38.610286)
					)
					(arc
						(start 345.853258 -38.715442)
						(mid 345.723537 -38.645773)
						(end 345.653868 -38.516052)
					)
				)
			)
		)
		(zone
			(layer "F.Cu")
			(hatch none 0.5)
			(connect_pads
				(clearance 0)
			)
			(min_thickness 0.25)
			(keepout
				(tracks not_allowed)
				(vias allowed)
				(pads allowed)
				(copperpour not_allowed)
				(footprints allowed)
			)
			(placement
				(enabled no)
				(sheetname "")
			)
			(fill
				(thermal_gap 0.5)
				(thermal_bridge_width 0.5)
				(island_removal_mode 0)
			)
			(polygon
				(pts
					(arc
						(start 345.824556 -57.505346)
						(mid 345.860927 -57.563209)
						(end 345.91879 -57.59958)
					)
					(arc
						(start 345.91879 -57.704736)
						(mid 345.789069 -57.635067)
						(end 345.7194 -57.505346)
					)
				)
			)
		)
		(zone
			(layer "F.Cu")
			(hatch none 0.5)
			(connect_pads
				(clearance 0)
			)
			(min_thickness 0.25)
			(keepout
				(tracks not_allowed)
				(vias allowed)
				(pads allowed)
				(copperpour not_allowed)
				(footprints allowed)
			)
			(placement
				(enabled no)
				(sheetname "")
			)
			(fill
				(thermal_gap 0.5)
				(thermal_bridge_width 0.5)
				(island_removal_mode 0)
			)
			(polygon
				(pts
					(arc
						(start 345.824556 -56.505094)
						(mid 345.860927 -56.562957)
						(end 345.91879 -56.599328)
					)
					(arc
						(start 345.91879 -56.704484)
						(mid 345.789069 -56.634815)
						(end 345.7194 -56.505094)
					)
				)
			)
		)
		(zone
			(layer "F.Cu")
			(hatch none 0.5)
			(connect_pads
				(clearance 0)
			)
			(min_thickness 0.25)
			(keepout
				(tracks not_allowed)
				(vias allowed)
				(pads allowed)
				(copperpour not_allowed)
				(footprints allowed)
			)
			(placement
				(enabled no)
				(sheetname "")
			)
			(fill
				(thermal_gap 0.5)
				(thermal_bridge_width 0.5)
				(island_removal_mode 0)
			)
			(polygon
				(pts
					(arc
						(start 345.824556 -55.504588)
						(mid 345.860927 -55.562451)
						(end 345.91879 -55.598822)
					)
					(arc
						(start 345.91879 -55.703978)
						(mid 345.789069 -55.634309)
						(end 345.7194 -55.504588)
					)
				)
			)
		)
		(zone
			(layer "F.Cu")
			(hatch none 0.5)
			(connect_pads
				(clearance 0)
			)
			(min_thickness 0.25)
			(keepout
				(tracks not_allowed)
				(vias allowed)
				(pads allowed)
				(copperpour not_allowed)
				(footprints allowed)
			)
			(placement
				(enabled no)
				(sheetname "")
			)
			(fill
				(thermal_gap 0.5)
				(thermal_bridge_width 0.5)
				(island_removal_mode 0)
			)
			(polygon
				(pts
					(arc
						(start 345.824556 -54.504082)
						(mid 345.860927 -54.561945)
						(end 345.91879 -54.598316)
					)
					(arc
						(start 345.91879 -54.703472)
						(mid 345.789069 -54.633803)
						(end 345.7194 -54.504082)
					)
				)
			)
		)
		(zone
			(layer "F.Cu")
			(hatch none 0.5)
			(connect_pads
				(clearance 0)
			)
			(min_thickness 0.25)
			(keepout
				(tracks not_allowed)
				(vias allowed)
				(pads allowed)
				(copperpour not_allowed)
				(footprints allowed)
			)
			(placement
				(enabled no)
				(sheetname "")
			)
			(fill
				(thermal_gap 0.5)
				(thermal_bridge_width 0.5)
				(island_removal_mode 0)
			)
			(polygon
				(pts
					(arc
						(start 345.824556 -53.503576)
						(mid 345.860927 -53.561439)
						(end 345.91879 -53.59781)
					)
					(arc
						(start 345.91879 -53.702966)
						(mid 345.789069 -53.633297)
						(end 345.7194 -53.503576)
					)
				)
			)
		)
		(zone
			(layer "F.Cu")
			(hatch none 0.5)
			(connect_pads
				(clearance 0)
			)
			(min_thickness 0.25)
			(keepout
				(tracks not_allowed)
				(vias allowed)
				(pads allowed)
				(copperpour not_allowed)
				(footprints allowed)
			)
			(placement
				(enabled no)
				(sheetname "")
			)
			(fill
				(thermal_gap 0.5)
				(thermal_bridge_width 0.5)
				(island_removal_mode 0)
			)
			(polygon
				(pts
					(arc
						(start 345.824556 -52.50307)
						(mid 345.860927 -52.560933)
						(end 345.91879 -52.597304)
					)
					(arc
						(start 345.91879 -52.70246)
						(mid 345.789069 -52.632791)
						(end 345.7194 -52.50307)
					)
				)
			)
		)
		(zone
			(layer "F.Cu")
			(hatch none 0.5)
			(connect_pads
				(clearance 0)
			)
			(min_thickness 0.25)
			(keepout
				(tracks not_allowed)
				(vias allowed)
				(pads allowed)
				(copperpour not_allowed)
				(footprints allowed)
			)
			(placement
				(enabled no)
				(sheetname "")
			)
			(fill
				(thermal_gap 0.5)
				(thermal_bridge_width 0.5)
				(island_removal_mode 0)
			)
			(polygon
				(pts
					(arc
						(start 345.824556 -51.502564)
						(mid 345.860927 -51.560427)
						(end 345.91879 -51.596798)
					)
					(arc
						(start 345.91879 -51.701954)
						(mid 345.789069 -51.632285)
						(end 345.7194 -51.502564)
					)
				)
			)
		)
		(zone
			(layer "F.Cu")
			(hatch none 0.5)
			(connect_pads
				(clearance 0)
			)
			(min_thickness 0.25)
			(keepout
				(tracks not_allowed)
				(vias allowed)
				(pads allowed)
				(copperpour not_allowed)
				(footprints allowed)
			)
			(placement
				(enabled no)
				(sheetname "")
			)
			(fill
				(thermal_gap 0.5)
				(thermal_bridge_width 0.5)
				(island_removal_mode 0)
			)
			(polygon
				(pts
					(arc
						(start 345.824556 -50.502058)
						(mid 345.860927 -50.559921)
						(end 345.91879 -50.596292)
					)
					(arc
						(start 345.91879 -50.701448)
						(mid 345.789069 -50.631779)
						(end 345.7194 -50.502058)
					)
				)
			)
		)
		(zone
			(layer "F.Cu")
			(hatch none 0.5)
			(connect_pads
				(clearance 0)
			)
			(min_thickness 0.25)
			(keepout
				(tracks not_allowed)
				(vias allowed)
				(pads allowed)
				(copperpour not_allowed)
				(footprints allowed)
			)
			(placement
				(enabled no)
				(sheetname "")
			)
			(fill
				(thermal_gap 0.5)
				(thermal_bridge_width 0.5)
				(island_removal_mode 0)
			)
			(polygon
				(pts
					(arc
						(start 345.824556 -49.501552)
						(mid 345.860927 -49.559415)
						(end 345.91879 -49.595786)
					)
					(arc
						(start 345.91879 -49.700942)
						(mid 345.789069 -49.631273)
						(end 345.7194 -49.501552)
					)
				)
			)
		)
		(zone
			(layer "F.Cu")
			(hatch none 0.5)
			(connect_pads
				(clearance 0)
			)
			(min_thickness 0.25)
			(keepout
				(tracks not_allowed)
				(vias allowed)
				(pads allowed)
				(copperpour not_allowed)
				(footprints allowed)
			)
			(placement
				(enabled no)
				(sheetname "")
			)
			(fill
				(thermal_gap 0.5)
				(thermal_bridge_width 0.5)
				(island_removal_mode 0)
			)
			(polygon
				(pts
					(arc
						(start 345.824556 -48.501046)
						(mid 345.860927 -48.558909)
						(end 345.91879 -48.59528)
					)
					(arc
						(start 345.91879 -48.700436)
						(mid 345.789069 -48.630767)
						(end 345.7194 -48.501046)
					)
				)
			)
		)
		(zone
			(layer "F.Cu")
			(hatch none 0.5)
			(connect_pads
				(clearance 0)
			)
			(min_thickness 0.25)
			(keepout
				(tracks not_allowed)
				(vias allowed)
				(pads allowed)
				(copperpour not_allowed)
				(footprints allowed)
			)
			(placement
				(enabled no)
				(sheetname "")
			)
			(fill
				(thermal_gap 0.5)
				(thermal_bridge_width 0.5)
				(island_removal_mode 0)
			)
			(polygon
				(pts
					(arc
						(start 345.824556 -47.50054)
						(mid 345.860927 -47.558403)
						(end 345.91879 -47.594774)
					)
					(arc
						(start 345.91879 -47.69993)
						(mid 345.789069 -47.630261)
						(end 345.7194 -47.50054)
					)
				)
			)
		)
		(zone
			(layer "F.Cu")
			(hatch none 0.5)
			(connect_pads
				(clearance 0)
			)
			(min_thickness 0.25)
			(keepout
				(tracks not_allowed)
				(vias allowed)
				(pads allowed)
				(copperpour not_allowed)
				(footprints allowed)
			)
			(placement
				(enabled no)
				(sheetname "")
			)
			(fill
				(thermal_gap 0.5)
				(thermal_bridge_width 0.5)
				(island_removal_mode 0)
			)
			(polygon
				(pts
					(arc
						(start 345.824556 -46.500034)
						(mid 345.860927 -46.557897)
						(end 345.91879 -46.594268)
					)
					(arc
						(start 345.91879 -46.699424)
						(mid 345.789069 -46.629755)
						(end 345.7194 -46.500034)
					)
				)
			)
		)
		(zone
			(layer "F.Cu")
			(hatch none 0.5)
			(connect_pads
				(clearance 0)
			)
			(min_thickness 0.25)
			(keepout
				(tracks not_allowed)
				(vias allowed)
				(pads allowed)
				(copperpour not_allowed)
				(footprints allowed)
			)
			(placement
				(enabled no)
				(sheetname "")
			)
			(fill
				(thermal_gap 0.5)
				(thermal_bridge_width 0.5)
				(island_removal_mode 0)
			)
			(polygon
				(pts
					(arc
						(start 345.824556 -45.499528)
						(mid 345.860927 -45.557391)
						(end 345.91879 -45.593762)
					)
					(arc
						(start 345.91879 -45.699172)
						(mid 345.788981 -45.629415)
						(end 345.7194 -45.499528)
					)
				)
			)
		)
		(zone
			(layer "F.Cu")
			(hatch none 0.5)
			(connect_pads
				(clearance 0)
			)
			(min_thickness 0.25)
			(keepout
				(tracks not_allowed)
				(vias allowed)
				(pads allowed)
				(copperpour not_allowed)
				(footprints allowed)
			)
			(placement
				(enabled no)
				(sheetname "")
			)
			(fill
				(thermal_gap 0.5)
				(thermal_bridge_width 0.5)
				(island_removal_mode 0)
			)
			(polygon
				(pts
					(arc
						(start 345.824556 -44.499022)
						(mid 345.860927 -44.556885)
						(end 345.91879 -44.593256)
					)
					(arc
						(start 345.91879 -44.698666)
						(mid 345.788981 -44.628909)
						(end 345.7194 -44.499022)
					)
				)
			)
		)
		(zone
			(layer "F.Cu")
			(hatch none 0.5)
			(connect_pads
				(clearance 0)
			)
			(min_thickness 0.25)
			(keepout
				(tracks not_allowed)
				(vias allowed)
				(pads allowed)
				(copperpour not_allowed)
				(footprints allowed)
			)
			(placement
				(enabled no)
				(sheetname "")
			)
			(fill
				(thermal_gap 0.5)
				(thermal_bridge_width 0.5)
				(island_removal_mode 0)
			)
			(polygon
				(pts
					(arc
						(start 345.824556 -43.49877)
						(mid 345.860952 -43.556524)
						(end 345.91879 -43.59275)
					)
					(arc
						(start 345.91879 -43.69816)
						(mid 345.789069 -43.628491)
						(end 345.7194 -43.49877)
					)
				)
			)
		)
		(zone
			(layer "F.Cu")
			(hatch none 0.5)
			(connect_pads
				(clearance 0)
			)
			(min_thickness 0.25)
			(keepout
				(tracks not_allowed)
				(vias allowed)
				(pads allowed)
				(copperpour not_allowed)
				(footprints allowed)
			)
			(placement
				(enabled no)
				(sheetname "")
			)
			(fill
				(thermal_gap 0.5)
				(thermal_bridge_width 0.5)
				(island_removal_mode 0)
			)
			(polygon
				(pts
					(arc
						(start 345.824556 -42.498264)
						(mid 345.860952 -42.556018)
						(end 345.91879 -42.592244)
					)
					(arc
						(start 345.91879 -42.697654)
						(mid 345.789069 -42.627985)
						(end 345.7194 -42.498264)
					)
				)
			)
		)
		(zone
			(layer "F.Cu")
			(hatch none 0.5)
			(connect_pads
				(clearance 0)
			)
			(min_thickness 0.25)
			(keepout
				(tracks not_allowed)
				(vias allowed)
				(pads allowed)
				(copperpour not_allowed)
				(footprints allowed)
			)
			(placement
				(enabled no)
				(sheetname "")
			)
			(fill
				(thermal_gap 0.5)
				(thermal_bridge_width 0.5)
				(island_removal_mode 0)
			)
			(polygon
				(pts
					(arc
						(start 345.824556 -41.497758)
						(mid 345.860952 -41.555512)
						(end 345.91879 -41.591738)
					)
					(arc
						(start 345.91879 -41.697148)
						(mid 345.789069 -41.627479)
						(end 345.7194 -41.497758)
					)
				)
			)
		)
		(zone
			(layer "F.Cu")
			(hatch none 0.5)
			(connect_pads
				(clearance 0)
			)
			(min_thickness 0.25)
			(keepout
				(tracks not_allowed)
				(vias allowed)
				(pads allowed)
				(copperpour not_allowed)
				(footprints allowed)
			)
			(placement
				(enabled no)
				(sheetname "")
			)
			(fill
				(thermal_gap 0.5)
				(thermal_bridge_width 0.5)
				(island_removal_mode 0)
			)
			(polygon
				(pts
					(arc
						(start 345.824556 -40.497252)
						(mid 345.860952 -40.555006)
						(end 345.91879 -40.591232)
					)
					(arc
						(start 345.91879 -40.696642)
						(mid 345.789069 -40.626973)
						(end 345.7194 -40.497252)
					)
				)
			)
		)
		(zone
			(layer "F.Cu")
			(hatch none 0.5)
			(connect_pads
				(clearance 0)
			)
			(min_thickness 0.25)
			(keepout
				(tracks not_allowed)
				(vias allowed)
				(pads allowed)
				(copperpour not_allowed)
				(footprints allowed)
			)
			(placement
				(enabled no)
				(sheetname "")
			)
			(fill
				(thermal_gap 0.5)
				(thermal_bridge_width 0.5)
				(island_removal_mode 0)
			)
			(polygon
				(pts
					(arc
						(start 345.824556 -39.496746)
						(mid 345.860982 -39.554445)
						(end 345.91879 -39.590726)
					)
					(arc
						(start 345.91879 -39.696136)
						(mid 345.789069 -39.626467)
						(end 345.7194 -39.496746)
					)
				)
			)
		)
		(zone
			(layer "F.Cu")
			(hatch none 0.5)
			(connect_pads
				(clearance 0)
			)
			(min_thickness 0.25)
			(keepout
				(tracks not_allowed)
				(vias allowed)
				(pads allowed)
				(copperpour not_allowed)
				(footprints allowed)
			)
			(placement
				(enabled no)
				(sheetname "")
			)
			(fill
				(thermal_gap 0.5)
				(thermal_bridge_width 0.5)
				(island_removal_mode 0)
			)
			(polygon
				(pts
					(arc
						(start 345.853258 -58.290206)
						(mid 345.795395 -58.326577)
						(end 345.759024 -58.38444)
					)
					(arc
						(start 345.653868 -58.38444)
						(mid 345.723537 -58.254719)
						(end 345.853258 -58.18505)
					)
				)
			)
		)
		(zone
			(layer "F.Cu")
			(hatch none 0.5)
			(connect_pads
				(clearance 0)
			)
			(min_thickness 0.25)
			(keepout
				(tracks not_allowed)
				(vias allowed)
				(pads allowed)
				(copperpour not_allowed)
				(footprints allowed)
			)
			(placement
				(enabled no)
				(sheetname "")
			)
			(fill
				(thermal_gap 0.5)
				(thermal_bridge_width 0.5)
				(island_removal_mode 0)
			)
			(polygon
				(pts
					(arc
						(start 345.853258 -38.320472)
						(mid 345.795399 -38.356703)
						(end 345.759024 -38.414452)
					)
					(arc
						(start 345.653868 -38.414452)
						(mid 345.723537 -38.284731)
						(end 345.853258 -38.215062)
					)
				)
			)
		)
		(zone
			(layer "F.Cu")
			(hatch none 0.5)
			(connect_pads
				(clearance 0)
			)
			(min_thickness 0.25)
			(keepout
				(tracks not_allowed)
				(vias allowed)
				(pads allowed)
				(copperpour not_allowed)
				(footprints allowed)
			)
			(placement
				(enabled no)
				(sheetname "")
			)
			(fill
				(thermal_gap 0.5)
				(thermal_bridge_width 0.5)
				(island_removal_mode 0)
			)
			(polygon
				(pts
					(arc
						(start 345.91879 -57.309766)
						(mid 345.860931 -57.345997)
						(end 345.824556 -57.403746)
					)
					(arc
						(start 345.7194 -57.403746)
						(mid 345.789069 -57.274025)
						(end 345.91879 -57.204356)
					)
				)
			)
		)
		(zone
			(layer "F.Cu")
			(hatch none 0.5)
			(connect_pads
				(clearance 0)
			)
			(min_thickness 0.25)
			(keepout
				(tracks not_allowed)
				(vias allowed)
				(pads allowed)
				(copperpour not_allowed)
				(footprints allowed)
			)
			(placement
				(enabled no)
				(sheetname "")
			)
			(fill
				(thermal_gap 0.5)
				(thermal_bridge_width 0.5)
				(island_removal_mode 0)
			)
			(polygon
				(pts
					(arc
						(start 345.91879 -56.30926)
						(mid 345.860927 -56.345631)
						(end 345.824556 -56.403494)
					)
					(arc
						(start 345.7194 -56.403494)
						(mid 345.789069 -56.273773)
						(end 345.91879 -56.204104)
					)
				)
			)
		)
		(zone
			(layer "F.Cu")
			(hatch none 0.5)
			(connect_pads
				(clearance 0)
			)
			(min_thickness 0.25)
			(keepout
				(tracks not_allowed)
				(vias allowed)
				(pads allowed)
				(copperpour not_allowed)
				(footprints allowed)
			)
			(placement
				(enabled no)
				(sheetname "")
			)
			(fill
				(thermal_gap 0.5)
				(thermal_bridge_width 0.5)
				(island_removal_mode 0)
			)
			(polygon
				(pts
					(arc
						(start 345.91879 -55.308754)
						(mid 345.860927 -55.345125)
						(end 345.824556 -55.402988)
					)
					(arc
						(start 345.7194 -55.402988)
						(mid 345.789069 -55.273267)
						(end 345.91879 -55.203598)
					)
				)
			)
		)
		(zone
			(layer "F.Cu")
			(hatch none 0.5)
			(connect_pads
				(clearance 0)
			)
			(min_thickness 0.25)
			(keepout
				(tracks not_allowed)
				(vias allowed)
				(pads allowed)
				(copperpour not_allowed)
				(footprints allowed)
			)
			(placement
				(enabled no)
				(sheetname "")
			)
			(fill
				(thermal_gap 0.5)
				(thermal_bridge_width 0.5)
				(island_removal_mode 0)
			)
			(polygon
				(pts
					(arc
						(start 345.91879 -54.308248)
						(mid 345.860927 -54.344619)
						(end 345.824556 -54.402482)
					)
					(arc
						(start 345.7194 -54.402482)
						(mid 345.789069 -54.272761)
						(end 345.91879 -54.203092)
					)
				)
			)
		)
		(zone
			(layer "F.Cu")
			(hatch none 0.5)
			(connect_pads
				(clearance 0)
			)
			(min_thickness 0.25)
			(keepout
				(tracks not_allowed)
				(vias allowed)
				(pads allowed)
				(copperpour not_allowed)
				(footprints allowed)
			)
			(placement
				(enabled no)
				(sheetname "")
			)
			(fill
				(thermal_gap 0.5)
				(thermal_bridge_width 0.5)
				(island_removal_mode 0)
			)
			(polygon
				(pts
					(arc
						(start 345.91879 -53.307742)
						(mid 345.860927 -53.344113)
						(end 345.824556 -53.401976)
					)
					(arc
						(start 345.7194 -53.401976)
						(mid 345.789069 -53.272255)
						(end 345.91879 -53.202586)
					)
				)
			)
		)
		(zone
			(layer "F.Cu")
			(hatch none 0.5)
			(connect_pads
				(clearance 0)
			)
			(min_thickness 0.25)
			(keepout
				(tracks not_allowed)
				(vias allowed)
				(pads allowed)
				(copperpour not_allowed)
				(footprints allowed)
			)
			(placement
				(enabled no)
				(sheetname "")
			)
			(fill
				(thermal_gap 0.5)
				(thermal_bridge_width 0.5)
				(island_removal_mode 0)
			)
			(polygon
				(pts
					(arc
						(start 345.91879 -52.307236)
						(mid 345.860927 -52.343607)
						(end 345.824556 -52.40147)
					)
					(arc
						(start 345.7194 -52.40147)
						(mid 345.789069 -52.271749)
						(end 345.91879 -52.20208)
					)
				)
			)
		)
		(zone
			(layer "F.Cu")
			(hatch none 0.5)
			(connect_pads
				(clearance 0)
			)
			(min_thickness 0.25)
			(keepout
				(tracks not_allowed)
				(vias allowed)
				(pads allowed)
				(copperpour not_allowed)
				(footprints allowed)
			)
			(placement
				(enabled no)
				(sheetname "")
			)
			(fill
				(thermal_gap 0.5)
				(thermal_bridge_width 0.5)
				(island_removal_mode 0)
			)
			(polygon
				(pts
					(arc
						(start 345.91879 -51.30673)
						(mid 345.860927 -51.343101)
						(end 345.824556 -51.400964)
					)
					(arc
						(start 345.7194 -51.400964)
						(mid 345.789069 -51.271243)
						(end 345.91879 -51.201574)
					)
				)
			)
		)
		(zone
			(layer "F.Cu")
			(hatch none 0.5)
			(connect_pads
				(clearance 0)
			)
			(min_thickness 0.25)
			(keepout
				(tracks not_allowed)
				(vias allowed)
				(pads allowed)
				(copperpour not_allowed)
				(footprints allowed)
			)
			(placement
				(enabled no)
				(sheetname "")
			)
			(fill
				(thermal_gap 0.5)
				(thermal_bridge_width 0.5)
				(island_removal_mode 0)
			)
			(polygon
				(pts
					(arc
						(start 345.91879 -50.306224)
						(mid 345.860927 -50.342595)
						(end 345.824556 -50.400458)
					)
					(arc
						(start 345.7194 -50.400458)
						(mid 345.789069 -50.270737)
						(end 345.91879 -50.201068)
					)
				)
			)
		)
		(zone
			(layer "F.Cu")
			(hatch none 0.5)
			(connect_pads
				(clearance 0)
			)
			(min_thickness 0.25)
			(keepout
				(tracks not_allowed)
				(vias allowed)
				(pads allowed)
				(copperpour not_allowed)
				(footprints allowed)
			)
			(placement
				(enabled no)
				(sheetname "")
			)
			(fill
				(thermal_gap 0.5)
				(thermal_bridge_width 0.5)
				(island_removal_mode 0)
			)
			(polygon
				(pts
					(arc
						(start 345.91879 -49.305718)
						(mid 345.860927 -49.342089)
						(end 345.824556 -49.399952)
					)
					(arc
						(start 345.7194 -49.399952)
						(mid 345.789069 -49.270231)
						(end 345.91879 -49.200562)
					)
				)
			)
		)
		(zone
			(layer "F.Cu")
			(hatch none 0.5)
			(connect_pads
				(clearance 0)
			)
			(min_thickness 0.25)
			(keepout
				(tracks not_allowed)
				(vias allowed)
				(pads allowed)
				(copperpour not_allowed)
				(footprints allowed)
			)
			(placement
				(enabled no)
				(sheetname "")
			)
			(fill
				(thermal_gap 0.5)
				(thermal_bridge_width 0.5)
				(island_removal_mode 0)
			)
			(polygon
				(pts
					(arc
						(start 345.91879 -48.305212)
						(mid 345.860927 -48.341583)
						(end 345.824556 -48.399446)
					)
					(arc
						(start 345.7194 -48.399446)
						(mid 345.789069 -48.269725)
						(end 345.91879 -48.200056)
					)
				)
			)
		)
		(zone
			(layer "F.Cu")
			(hatch none 0.5)
			(connect_pads
				(clearance 0)
			)
			(min_thickness 0.25)
			(keepout
				(tracks not_allowed)
				(vias allowed)
				(pads allowed)
				(copperpour not_allowed)
				(footprints allowed)
			)
			(placement
				(enabled no)
				(sheetname "")
			)
			(fill
				(thermal_gap 0.5)
				(thermal_bridge_width 0.5)
				(island_removal_mode 0)
			)
			(polygon
				(pts
					(arc
						(start 345.91879 -47.30496)
						(mid 345.861011 -47.341246)
						(end 345.824556 -47.39894)
					)
					(arc
						(start 345.7194 -47.39894)
						(mid 345.789069 -47.269219)
						(end 345.91879 -47.19955)
					)
				)
			)
		)
		(zone
			(layer "F.Cu")
			(hatch none 0.5)
			(connect_pads
				(clearance 0)
			)
			(min_thickness 0.25)
			(keepout
				(tracks not_allowed)
				(vias allowed)
				(pads allowed)
				(copperpour not_allowed)
				(footprints allowed)
			)
			(placement
				(enabled no)
				(sheetname "")
			)
			(fill
				(thermal_gap 0.5)
				(thermal_bridge_width 0.5)
				(island_removal_mode 0)
			)
			(polygon
				(pts
					(arc
						(start 345.91879 -46.304454)
						(mid 345.861011 -46.34074)
						(end 345.824556 -46.398434)
					)
					(arc
						(start 345.7194 -46.398434)
						(mid 345.789069 -46.268713)
						(end 345.91879 -46.199044)
					)
				)
			)
		)
		(zone
			(layer "F.Cu")
			(hatch none 0.5)
			(connect_pads
				(clearance 0)
			)
			(min_thickness 0.25)
			(keepout
				(tracks not_allowed)
				(vias allowed)
				(pads allowed)
				(copperpour not_allowed)
				(footprints allowed)
			)
			(placement
				(enabled no)
				(sheetname "")
			)
			(fill
				(thermal_gap 0.5)
				(thermal_bridge_width 0.5)
				(island_removal_mode 0)
			)
			(polygon
				(pts
					(arc
						(start 345.91879 -45.303948)
						(mid 345.861011 -45.340234)
						(end 345.824556 -45.397928)
					)
					(arc
						(start 345.7194 -45.397928)
						(mid 345.789069 -45.268207)
						(end 345.91879 -45.198538)
					)
				)
			)
		)
		(zone
			(layer "F.Cu")
			(hatch none 0.5)
			(connect_pads
				(clearance 0)
			)
			(min_thickness 0.25)
			(keepout
				(tracks not_allowed)
				(vias allowed)
				(pads allowed)
				(copperpour not_allowed)
				(footprints allowed)
			)
			(placement
				(enabled no)
				(sheetname "")
			)
			(fill
				(thermal_gap 0.5)
				(thermal_bridge_width 0.5)
				(island_removal_mode 0)
			)
			(polygon
				(pts
					(arc
						(start 345.91879 -44.303442)
						(mid 345.861011 -44.339728)
						(end 345.824556 -44.397422)
					)
					(arc
						(start 345.7194 -44.397422)
						(mid 345.789069 -44.267701)
						(end 345.91879 -44.198032)
					)
				)
			)
		)
		(zone
			(layer "F.Cu")
			(hatch none 0.5)
			(connect_pads
				(clearance 0)
			)
			(min_thickness 0.25)
			(keepout
				(tracks not_allowed)
				(vias allowed)
				(pads allowed)
				(copperpour not_allowed)
				(footprints allowed)
			)
			(placement
				(enabled no)
				(sheetname "")
			)
			(fill
				(thermal_gap 0.5)
				(thermal_bridge_width 0.5)
				(island_removal_mode 0)
			)
			(polygon
				(pts
					(arc
						(start 345.91879 -43.302936)
						(mid 345.860927 -43.339307)
						(end 345.824556 -43.39717)
					)
					(arc
						(start 345.7194 -43.39717)
						(mid 345.789017 -43.267319)
						(end 345.91879 -43.197526)
					)
				)
			)
		)
		(zone
			(layer "F.Cu")
			(hatch none 0.5)
			(connect_pads
				(clearance 0)
			)
			(min_thickness 0.25)
			(keepout
				(tracks not_allowed)
				(vias allowed)
				(pads allowed)
				(copperpour not_allowed)
				(footprints allowed)
			)
			(placement
				(enabled no)
				(sheetname "")
			)
			(fill
				(thermal_gap 0.5)
				(thermal_bridge_width 0.5)
				(island_removal_mode 0)
			)
			(polygon
				(pts
					(arc
						(start 345.91879 -42.30243)
						(mid 345.860927 -42.338801)
						(end 345.824556 -42.396664)
					)
					(arc
						(start 345.7194 -42.396664)
						(mid 345.789017 -42.266813)
						(end 345.91879 -42.19702)
					)
				)
			)
		)
		(zone
			(layer "F.Cu")
			(hatch none 0.5)
			(connect_pads
				(clearance 0)
			)
			(min_thickness 0.25)
			(keepout
				(tracks not_allowed)
				(vias allowed)
				(pads allowed)
				(copperpour not_allowed)
				(footprints allowed)
			)
			(placement
				(enabled no)
				(sheetname "")
			)
			(fill
				(thermal_gap 0.5)
				(thermal_bridge_width 0.5)
				(island_removal_mode 0)
			)
			(polygon
				(pts
					(arc
						(start 345.91879 -41.301924)
						(mid 345.860927 -41.338295)
						(end 345.824556 -41.396158)
					)
					(arc
						(start 345.7194 -41.396158)
						(mid 345.789069 -41.266437)
						(end 345.91879 -41.196768)
					)
				)
			)
		)
		(zone
			(layer "F.Cu")
			(hatch none 0.5)
			(connect_pads
				(clearance 0)
			)
			(min_thickness 0.25)
			(keepout
				(tracks not_allowed)
				(vias allowed)
				(pads allowed)
				(copperpour not_allowed)
				(footprints allowed)
			)
			(placement
				(enabled no)
				(sheetname "")
			)
			(fill
				(thermal_gap 0.5)
				(thermal_bridge_width 0.5)
				(island_removal_mode 0)
			)
			(polygon
				(pts
					(arc
						(start 345.91879 -40.301418)
						(mid 345.860927 -40.337789)
						(end 345.824556 -40.395652)
					)
					(arc
						(start 345.7194 -40.395652)
						(mid 345.789069 -40.265931)
						(end 345.91879 -40.196262)
					)
				)
			)
		)
		(zone
			(layer "F.Cu")
			(hatch none 0.5)
			(connect_pads
				(clearance 0)
			)
			(min_thickness 0.25)
			(keepout
				(tracks not_allowed)
				(vias allowed)
				(pads allowed)
				(copperpour not_allowed)
				(footprints allowed)
			)
			(placement
				(enabled no)
				(sheetname "")
			)
			(fill
				(thermal_gap 0.5)
				(thermal_bridge_width 0.5)
				(island_removal_mode 0)
			)
			(polygon
				(pts
					(arc
						(start 345.91879 -39.300912)
						(mid 345.860927 -39.337283)
						(end 345.824556 -39.395146)
					)
					(arc
						(start 345.7194 -39.395146)
						(mid 345.789069 -39.265425)
						(end 345.91879 -39.195756)
					)
				)
			)
		)
		(zone
			(layer "F.Cu")
			(hatch none 0.5)
			(connect_pads
				(clearance 0)
			)
			(min_thickness 0.25)
			(keepout
				(tracks not_allowed)
				(vias allowed)
				(pads allowed)
				(copperpour not_allowed)
				(footprints allowed)
			)
			(placement
				(enabled no)
				(sheetname "")
			)
			(fill
				(thermal_gap 0.5)
				(thermal_bridge_width 0.5)
				(island_removal_mode 0)
			)
			(polygon
				(pts
					(arc
						(start 345.954858 -58.58002)
						(mid 346.012717 -58.543789)
						(end 346.049092 -58.48604)
					)
					(arc
						(start 346.154248 -58.48604)
						(mid 346.084579 -58.615761)
						(end 345.954858 -58.68543)
					)
				)
			)
		)
		(zone
			(layer "F.Cu")
			(hatch none 0.5)
			(connect_pads
				(clearance 0)
			)
			(min_thickness 0.25)
			(keepout
				(tracks not_allowed)
				(vias allowed)
				(pads allowed)
				(copperpour not_allowed)
				(footprints allowed)
			)
			(placement
				(enabled no)
				(sheetname "")
			)
			(fill
				(thermal_gap 0.5)
				(thermal_bridge_width 0.5)
				(island_removal_mode 0)
			)
			(polygon
				(pts
					(arc
						(start 345.954858 -38.610286)
						(mid 346.012721 -38.573915)
						(end 346.049092 -38.516052)
					)
					(arc
						(start 346.154248 -38.516052)
						(mid 346.084579 -38.645773)
						(end 345.954858 -38.715442)
					)
				)
			)
		)
		(zone
			(layer "F.Cu")
			(hatch none 0.5)
			(connect_pads
				(clearance 0)
			)
			(min_thickness 0.25)
			(keepout
				(tracks not_allowed)
				(vias allowed)
				(pads allowed)
				(copperpour not_allowed)
				(footprints allowed)
			)
			(placement
				(enabled no)
				(sheetname "")
			)
			(fill
				(thermal_gap 0.5)
				(thermal_bridge_width 0.5)
				(island_removal_mode 0)
			)
			(polygon
				(pts
					(arc
						(start 346.02039 -57.59958)
						(mid 346.078253 -57.563209)
						(end 346.114624 -57.505346)
					)
					(arc
						(start 346.21978 -57.505346)
						(mid 346.150111 -57.635067)
						(end 346.02039 -57.704736)
					)
				)
			)
		)
		(zone
			(layer "F.Cu")
			(hatch none 0.5)
			(connect_pads
				(clearance 0)
			)
			(min_thickness 0.25)
			(keepout
				(tracks not_allowed)
				(vias allowed)
				(pads allowed)
				(copperpour not_allowed)
				(footprints allowed)
			)
			(placement
				(enabled no)
				(sheetname "")
			)
			(fill
				(thermal_gap 0.5)
				(thermal_bridge_width 0.5)
				(island_removal_mode 0)
			)
			(polygon
				(pts
					(arc
						(start 346.02039 -56.599328)
						(mid 346.078253 -56.562957)
						(end 346.114624 -56.505094)
					)
					(arc
						(start 346.21978 -56.505094)
						(mid 346.150111 -56.634815)
						(end 346.02039 -56.704484)
					)
				)
			)
		)
		(zone
			(layer "F.Cu")
			(hatch none 0.5)
			(connect_pads
				(clearance 0)
			)
			(min_thickness 0.25)
			(keepout
				(tracks not_allowed)
				(vias allowed)
				(pads allowed)
				(copperpour not_allowed)
				(footprints allowed)
			)
			(placement
				(enabled no)
				(sheetname "")
			)
			(fill
				(thermal_gap 0.5)
				(thermal_bridge_width 0.5)
				(island_removal_mode 0)
			)
			(polygon
				(pts
					(arc
						(start 346.02039 -55.598822)
						(mid 346.078253 -55.562451)
						(end 346.114624 -55.504588)
					)
					(arc
						(start 346.21978 -55.504588)
						(mid 346.150111 -55.634309)
						(end 346.02039 -55.703978)
					)
				)
			)
		)
		(zone
			(layer "F.Cu")
			(hatch none 0.5)
			(connect_pads
				(clearance 0)
			)
			(min_thickness 0.25)
			(keepout
				(tracks not_allowed)
				(vias allowed)
				(pads allowed)
				(copperpour not_allowed)
				(footprints allowed)
			)
			(placement
				(enabled no)
				(sheetname "")
			)
			(fill
				(thermal_gap 0.5)
				(thermal_bridge_width 0.5)
				(island_removal_mode 0)
			)
			(polygon
				(pts
					(arc
						(start 346.02039 -54.598316)
						(mid 346.078253 -54.561945)
						(end 346.114624 -54.504082)
					)
					(arc
						(start 346.21978 -54.504082)
						(mid 346.150111 -54.633803)
						(end 346.02039 -54.703472)
					)
				)
			)
		)
		(zone
			(layer "F.Cu")
			(hatch none 0.5)
			(connect_pads
				(clearance 0)
			)
			(min_thickness 0.25)
			(keepout
				(tracks not_allowed)
				(vias allowed)
				(pads allowed)
				(copperpour not_allowed)
				(footprints allowed)
			)
			(placement
				(enabled no)
				(sheetname "")
			)
			(fill
				(thermal_gap 0.5)
				(thermal_bridge_width 0.5)
				(island_removal_mode 0)
			)
			(polygon
				(pts
					(arc
						(start 346.02039 -53.59781)
						(mid 346.078253 -53.561439)
						(end 346.114624 -53.503576)
					)
					(arc
						(start 346.21978 -53.503576)
						(mid 346.150111 -53.633297)
						(end 346.02039 -53.702966)
					)
				)
			)
		)
		(zone
			(layer "F.Cu")
			(hatch none 0.5)
			(connect_pads
				(clearance 0)
			)
			(min_thickness 0.25)
			(keepout
				(tracks not_allowed)
				(vias allowed)
				(pads allowed)
				(copperpour not_allowed)
				(footprints allowed)
			)
			(placement
				(enabled no)
				(sheetname "")
			)
			(fill
				(thermal_gap 0.5)
				(thermal_bridge_width 0.5)
				(island_removal_mode 0)
			)
			(polygon
				(pts
					(arc
						(start 346.02039 -52.597304)
						(mid 346.078253 -52.560933)
						(end 346.114624 -52.50307)
					)
					(arc
						(start 346.21978 -52.50307)
						(mid 346.150111 -52.632791)
						(end 346.02039 -52.70246)
					)
				)
			)
		)
		(zone
			(layer "F.Cu")
			(hatch none 0.5)
			(connect_pads
				(clearance 0)
			)
			(min_thickness 0.25)
			(keepout
				(tracks not_allowed)
				(vias allowed)
				(pads allowed)
				(copperpour not_allowed)
				(footprints allowed)
			)
			(placement
				(enabled no)
				(sheetname "")
			)
			(fill
				(thermal_gap 0.5)
				(thermal_bridge_width 0.5)
				(island_removal_mode 0)
			)
			(polygon
				(pts
					(arc
						(start 346.02039 -51.596798)
						(mid 346.078253 -51.560427)
						(end 346.114624 -51.502564)
					)
					(arc
						(start 346.21978 -51.502564)
						(mid 346.150111 -51.632285)
						(end 346.02039 -51.701954)
					)
				)
			)
		)
		(zone
			(layer "F.Cu")
			(hatch none 0.5)
			(connect_pads
				(clearance 0)
			)
			(min_thickness 0.25)
			(keepout
				(tracks not_allowed)
				(vias allowed)
				(pads allowed)
				(copperpour not_allowed)
				(footprints allowed)
			)
			(placement
				(enabled no)
				(sheetname "")
			)
			(fill
				(thermal_gap 0.5)
				(thermal_bridge_width 0.5)
				(island_removal_mode 0)
			)
			(polygon
				(pts
					(arc
						(start 346.02039 -50.596292)
						(mid 346.078253 -50.559921)
						(end 346.114624 -50.502058)
					)
					(arc
						(start 346.21978 -50.502058)
						(mid 346.150111 -50.631779)
						(end 346.02039 -50.701448)
					)
				)
			)
		)
		(zone
			(layer "F.Cu")
			(hatch none 0.5)
			(connect_pads
				(clearance 0)
			)
			(min_thickness 0.25)
			(keepout
				(tracks not_allowed)
				(vias allowed)
				(pads allowed)
				(copperpour not_allowed)
				(footprints allowed)
			)
			(placement
				(enabled no)
				(sheetname "")
			)
			(fill
				(thermal_gap 0.5)
				(thermal_bridge_width 0.5)
				(island_removal_mode 0)
			)
			(polygon
				(pts
					(arc
						(start 346.02039 -49.595786)
						(mid 346.078253 -49.559415)
						(end 346.114624 -49.501552)
					)
					(arc
						(start 346.21978 -49.501552)
						(mid 346.150111 -49.631273)
						(end 346.02039 -49.700942)
					)
				)
			)
		)
		(zone
			(layer "F.Cu")
			(hatch none 0.5)
			(connect_pads
				(clearance 0)
			)
			(min_thickness 0.25)
			(keepout
				(tracks not_allowed)
				(vias allowed)
				(pads allowed)
				(copperpour not_allowed)
				(footprints allowed)
			)
			(placement
				(enabled no)
				(sheetname "")
			)
			(fill
				(thermal_gap 0.5)
				(thermal_bridge_width 0.5)
				(island_removal_mode 0)
			)
			(polygon
				(pts
					(arc
						(start 346.02039 -48.59528)
						(mid 346.078253 -48.558909)
						(end 346.114624 -48.501046)
					)
					(arc
						(start 346.21978 -48.501046)
						(mid 346.150111 -48.630767)
						(end 346.02039 -48.700436)
					)
				)
			)
		)
		(zone
			(layer "F.Cu")
			(hatch none 0.5)
			(connect_pads
				(clearance 0)
			)
			(min_thickness 0.25)
			(keepout
				(tracks not_allowed)
				(vias allowed)
				(pads allowed)
				(copperpour not_allowed)
				(footprints allowed)
			)
			(placement
				(enabled no)
				(sheetname "")
			)
			(fill
				(thermal_gap 0.5)
				(thermal_bridge_width 0.5)
				(island_removal_mode 0)
			)
			(polygon
				(pts
					(arc
						(start 346.02039 -47.594774)
						(mid 346.078253 -47.558403)
						(end 346.114624 -47.50054)
					)
					(arc
						(start 346.21978 -47.50054)
						(mid 346.150111 -47.630261)
						(end 346.02039 -47.69993)
					)
				)
			)
		)
		(zone
			(layer "F.Cu")
			(hatch none 0.5)
			(connect_pads
				(clearance 0)
			)
			(min_thickness 0.25)
			(keepout
				(tracks not_allowed)
				(vias allowed)
				(pads allowed)
				(copperpour not_allowed)
				(footprints allowed)
			)
			(placement
				(enabled no)
				(sheetname "")
			)
			(fill
				(thermal_gap 0.5)
				(thermal_bridge_width 0.5)
				(island_removal_mode 0)
			)
			(polygon
				(pts
					(arc
						(start 346.02039 -46.594268)
						(mid 346.078253 -46.557897)
						(end 346.114624 -46.500034)
					)
					(arc
						(start 346.21978 -46.500034)
						(mid 346.150111 -46.629755)
						(end 346.02039 -46.699424)
					)
				)
			)
		)
		(zone
			(layer "F.Cu")
			(hatch none 0.5)
			(connect_pads
				(clearance 0)
			)
			(min_thickness 0.25)
			(keepout
				(tracks not_allowed)
				(vias allowed)
				(pads allowed)
				(copperpour not_allowed)
				(footprints allowed)
			)
			(placement
				(enabled no)
				(sheetname "")
			)
			(fill
				(thermal_gap 0.5)
				(thermal_bridge_width 0.5)
				(island_removal_mode 0)
			)
			(polygon
				(pts
					(arc
						(start 346.02039 -45.593762)
						(mid 346.078253 -45.557391)
						(end 346.114624 -45.499528)
					)
					(arc
						(start 346.21978 -45.499528)
						(mid 346.150163 -45.629379)
						(end 346.02039 -45.699172)
					)
				)
			)
		)
		(zone
			(layer "F.Cu")
			(hatch none 0.5)
			(connect_pads
				(clearance 0)
			)
			(min_thickness 0.25)
			(keepout
				(tracks not_allowed)
				(vias allowed)
				(pads allowed)
				(copperpour not_allowed)
				(footprints allowed)
			)
			(placement
				(enabled no)
				(sheetname "")
			)
			(fill
				(thermal_gap 0.5)
				(thermal_bridge_width 0.5)
				(island_removal_mode 0)
			)
			(polygon
				(pts
					(arc
						(start 346.02039 -44.593256)
						(mid 346.078253 -44.556885)
						(end 346.114624 -44.499022)
					)
					(arc
						(start 346.21978 -44.499022)
						(mid 346.150163 -44.628873)
						(end 346.02039 -44.698666)
					)
				)
			)
		)
		(zone
			(layer "F.Cu")
			(hatch none 0.5)
			(connect_pads
				(clearance 0)
			)
			(min_thickness 0.25)
			(keepout
				(tracks not_allowed)
				(vias allowed)
				(pads allowed)
				(copperpour not_allowed)
				(footprints allowed)
			)
			(placement
				(enabled no)
				(sheetname "")
			)
			(fill
				(thermal_gap 0.5)
				(thermal_bridge_width 0.5)
				(island_removal_mode 0)
			)
			(polygon
				(pts
					(arc
						(start 346.02039 -43.59275)
						(mid 346.078249 -43.556519)
						(end 346.114624 -43.49877)
					)
					(arc
						(start 346.21978 -43.49877)
						(mid 346.150111 -43.628491)
						(end 346.02039 -43.69816)
					)
				)
			)
		)
		(zone
			(layer "F.Cu")
			(hatch none 0.5)
			(connect_pads
				(clearance 0)
			)
			(min_thickness 0.25)
			(keepout
				(tracks not_allowed)
				(vias allowed)
				(pads allowed)
				(copperpour not_allowed)
				(footprints allowed)
			)
			(placement
				(enabled no)
				(sheetname "")
			)
			(fill
				(thermal_gap 0.5)
				(thermal_bridge_width 0.5)
				(island_removal_mode 0)
			)
			(polygon
				(pts
					(arc
						(start 346.02039 -42.592244)
						(mid 346.078249 -42.556013)
						(end 346.114624 -42.498264)
					)
					(arc
						(start 346.21978 -42.498264)
						(mid 346.150111 -42.627985)
						(end 346.02039 -42.697654)
					)
				)
			)
		)
		(zone
			(layer "F.Cu")
			(hatch none 0.5)
			(connect_pads
				(clearance 0)
			)
			(min_thickness 0.25)
			(keepout
				(tracks not_allowed)
				(vias allowed)
				(pads allowed)
				(copperpour not_allowed)
				(footprints allowed)
			)
			(placement
				(enabled no)
				(sheetname "")
			)
			(fill
				(thermal_gap 0.5)
				(thermal_bridge_width 0.5)
				(island_removal_mode 0)
			)
			(polygon
				(pts
					(arc
						(start 346.02039 -41.591738)
						(mid 346.078249 -41.555507)
						(end 346.114624 -41.497758)
					)
					(arc
						(start 346.21978 -41.497758)
						(mid 346.150111 -41.627479)
						(end 346.02039 -41.697148)
					)
				)
			)
		)
		(zone
			(layer "F.Cu")
			(hatch none 0.5)
			(connect_pads
				(clearance 0)
			)
			(min_thickness 0.25)
			(keepout
				(tracks not_allowed)
				(vias allowed)
				(pads allowed)
				(copperpour not_allowed)
				(footprints allowed)
			)
			(placement
				(enabled no)
				(sheetname "")
			)
			(fill
				(thermal_gap 0.5)
				(thermal_bridge_width 0.5)
				(island_removal_mode 0)
			)
			(polygon
				(pts
					(arc
						(start 346.02039 -40.591232)
						(mid 346.078249 -40.555001)
						(end 346.114624 -40.497252)
					)
					(arc
						(start 346.21978 -40.497252)
						(mid 346.150111 -40.626973)
						(end 346.02039 -40.696642)
					)
				)
			)
		)
		(zone
			(layer "F.Cu")
			(hatch none 0.5)
			(connect_pads
				(clearance 0)
			)
			(min_thickness 0.25)
			(keepout
				(tracks not_allowed)
				(vias allowed)
				(pads allowed)
				(copperpour not_allowed)
				(footprints allowed)
			)
			(placement
				(enabled no)
				(sheetname "")
			)
			(fill
				(thermal_gap 0.5)
				(thermal_bridge_width 0.5)
				(island_removal_mode 0)
			)
			(polygon
				(pts
					(arc
						(start 346.02039 -39.590726)
						(mid 346.078249 -39.554495)
						(end 346.114624 -39.496746)
					)
					(arc
						(start 346.21978 -39.496746)
						(mid 346.150111 -39.626467)
						(end 346.02039 -39.696136)
					)
				)
			)
		)
		(zone
			(layer "F.Cu")
			(hatch none 0.5)
			(connect_pads
				(clearance 0)
			)
			(min_thickness 0.25)
			(keepout
				(tracks not_allowed)
				(vias allowed)
				(pads allowed)
				(copperpour not_allowed)
				(footprints allowed)
			)
			(placement
				(enabled no)
				(sheetname "")
			)
			(fill
				(thermal_gap 0.5)
				(thermal_bridge_width 0.5)
				(island_removal_mode 0)
			)
			(polygon
				(pts
					(arc
						(start 346.049092 -58.38444)
						(mid 346.012721 -58.326577)
						(end 345.954858 -58.290206)
					)
					(arc
						(start 345.954858 -58.18505)
						(mid 346.084579 -58.254719)
						(end 346.154248 -58.38444)
					)
				)
			)
		)
		(zone
			(layer "F.Cu")
			(hatch none 0.5)
			(connect_pads
				(clearance 0)
			)
			(min_thickness 0.25)
			(keepout
				(tracks not_allowed)
				(vias allowed)
				(pads allowed)
				(copperpour not_allowed)
				(footprints allowed)
			)
			(placement
				(enabled no)
				(sheetname "")
			)
			(fill
				(thermal_gap 0.5)
				(thermal_bridge_width 0.5)
				(island_removal_mode 0)
			)
			(polygon
				(pts
					(arc
						(start 346.049092 -38.414452)
						(mid 346.012666 -38.356753)
						(end 345.954858 -38.320472)
					)
					(arc
						(start 345.954858 -38.215062)
						(mid 346.084579 -38.284731)
						(end 346.154248 -38.414452)
					)
				)
			)
		)
		(zone
			(layer "F.Cu")
			(hatch none 0.5)
			(connect_pads
				(clearance 0)
			)
			(min_thickness 0.25)
			(keepout
				(tracks not_allowed)
				(vias allowed)
				(pads allowed)
				(copperpour not_allowed)
				(footprints allowed)
			)
			(placement
				(enabled no)
				(sheetname "")
			)
			(fill
				(thermal_gap 0.5)
				(thermal_bridge_width 0.5)
				(island_removal_mode 0)
			)
			(polygon
				(pts
					(arc
						(start 346.114624 -57.403746)
						(mid 346.078198 -57.346047)
						(end 346.02039 -57.309766)
					)
					(arc
						(start 346.02039 -57.204356)
						(mid 346.150111 -57.274025)
						(end 346.21978 -57.403746)
					)
				)
			)
		)
		(zone
			(layer "F.Cu")
			(hatch none 0.5)
			(connect_pads
				(clearance 0)
			)
			(min_thickness 0.25)
			(keepout
				(tracks not_allowed)
				(vias allowed)
				(pads allowed)
				(copperpour not_allowed)
				(footprints allowed)
			)
			(placement
				(enabled no)
				(sheetname "")
			)
			(fill
				(thermal_gap 0.5)
				(thermal_bridge_width 0.5)
				(island_removal_mode 0)
			)
			(polygon
				(pts
					(arc
						(start 346.114624 -56.403494)
						(mid 346.078253 -56.345631)
						(end 346.02039 -56.30926)
					)
					(arc
						(start 346.02039 -56.204104)
						(mid 346.150111 -56.273773)
						(end 346.21978 -56.403494)
					)
				)
			)
		)
		(zone
			(layer "F.Cu")
			(hatch none 0.5)
			(connect_pads
				(clearance 0)
			)
			(min_thickness 0.25)
			(keepout
				(tracks not_allowed)
				(vias allowed)
				(pads allowed)
				(copperpour not_allowed)
				(footprints allowed)
			)
			(placement
				(enabled no)
				(sheetname "")
			)
			(fill
				(thermal_gap 0.5)
				(thermal_bridge_width 0.5)
				(island_removal_mode 0)
			)
			(polygon
				(pts
					(arc
						(start 346.114624 -55.402988)
						(mid 346.078253 -55.345125)
						(end 346.02039 -55.308754)
					)
					(arc
						(start 346.02039 -55.203598)
						(mid 346.150111 -55.273267)
						(end 346.21978 -55.402988)
					)
				)
			)
		)
		(zone
			(layer "F.Cu")
			(hatch none 0.5)
			(connect_pads
				(clearance 0)
			)
			(min_thickness 0.25)
			(keepout
				(tracks not_allowed)
				(vias allowed)
				(pads allowed)
				(copperpour not_allowed)
				(footprints allowed)
			)
			(placement
				(enabled no)
				(sheetname "")
			)
			(fill
				(thermal_gap 0.5)
				(thermal_bridge_width 0.5)
				(island_removal_mode 0)
			)
			(polygon
				(pts
					(arc
						(start 346.114624 -54.402482)
						(mid 346.078253 -54.344619)
						(end 346.02039 -54.308248)
					)
					(arc
						(start 346.02039 -54.203092)
						(mid 346.150111 -54.272761)
						(end 346.21978 -54.402482)
					)
				)
			)
		)
		(zone
			(layer "F.Cu")
			(hatch none 0.5)
			(connect_pads
				(clearance 0)
			)
			(min_thickness 0.25)
			(keepout
				(tracks not_allowed)
				(vias allowed)
				(pads allowed)
				(copperpour not_allowed)
				(footprints allowed)
			)
			(placement
				(enabled no)
				(sheetname "")
			)
			(fill
				(thermal_gap 0.5)
				(thermal_bridge_width 0.5)
				(island_removal_mode 0)
			)
			(polygon
				(pts
					(arc
						(start 346.114624 -53.401976)
						(mid 346.078253 -53.344113)
						(end 346.02039 -53.307742)
					)
					(arc
						(start 346.02039 -53.202586)
						(mid 346.150111 -53.272255)
						(end 346.21978 -53.401976)
					)
				)
			)
		)
		(zone
			(layer "F.Cu")
			(hatch none 0.5)
			(connect_pads
				(clearance 0)
			)
			(min_thickness 0.25)
			(keepout
				(tracks not_allowed)
				(vias allowed)
				(pads allowed)
				(copperpour not_allowed)
				(footprints allowed)
			)
			(placement
				(enabled no)
				(sheetname "")
			)
			(fill
				(thermal_gap 0.5)
				(thermal_bridge_width 0.5)
				(island_removal_mode 0)
			)
			(polygon
				(pts
					(arc
						(start 346.114624 -52.40147)
						(mid 346.078253 -52.343607)
						(end 346.02039 -52.307236)
					)
					(arc
						(start 346.02039 -52.20208)
						(mid 346.150111 -52.271749)
						(end 346.21978 -52.40147)
					)
				)
			)
		)
		(zone
			(layer "F.Cu")
			(hatch none 0.5)
			(connect_pads
				(clearance 0)
			)
			(min_thickness 0.25)
			(keepout
				(tracks not_allowed)
				(vias allowed)
				(pads allowed)
				(copperpour not_allowed)
				(footprints allowed)
			)
			(placement
				(enabled no)
				(sheetname "")
			)
			(fill
				(thermal_gap 0.5)
				(thermal_bridge_width 0.5)
				(island_removal_mode 0)
			)
			(polygon
				(pts
					(arc
						(start 346.114624 -51.400964)
						(mid 346.078253 -51.343101)
						(end 346.02039 -51.30673)
					)
					(arc
						(start 346.02039 -51.201574)
						(mid 346.150111 -51.271243)
						(end 346.21978 -51.400964)
					)
				)
			)
		)
		(zone
			(layer "F.Cu")
			(hatch none 0.5)
			(connect_pads
				(clearance 0)
			)
			(min_thickness 0.25)
			(keepout
				(tracks not_allowed)
				(vias allowed)
				(pads allowed)
				(copperpour not_allowed)
				(footprints allowed)
			)
			(placement
				(enabled no)
				(sheetname "")
			)
			(fill
				(thermal_gap 0.5)
				(thermal_bridge_width 0.5)
				(island_removal_mode 0)
			)
			(polygon
				(pts
					(arc
						(start 346.114624 -50.400458)
						(mid 346.078253 -50.342595)
						(end 346.02039 -50.306224)
					)
					(arc
						(start 346.02039 -50.201068)
						(mid 346.150111 -50.270737)
						(end 346.21978 -50.400458)
					)
				)
			)
		)
		(zone
			(layer "F.Cu")
			(hatch none 0.5)
			(connect_pads
				(clearance 0)
			)
			(min_thickness 0.25)
			(keepout
				(tracks not_allowed)
				(vias allowed)
				(pads allowed)
				(copperpour not_allowed)
				(footprints allowed)
			)
			(placement
				(enabled no)
				(sheetname "")
			)
			(fill
				(thermal_gap 0.5)
				(thermal_bridge_width 0.5)
				(island_removal_mode 0)
			)
			(polygon
				(pts
					(arc
						(start 346.114624 -49.399952)
						(mid 346.078253 -49.342089)
						(end 346.02039 -49.305718)
					)
					(arc
						(start 346.02039 -49.200562)
						(mid 346.150111 -49.270231)
						(end 346.21978 -49.399952)
					)
				)
			)
		)
		(zone
			(layer "F.Cu")
			(hatch none 0.5)
			(connect_pads
				(clearance 0)
			)
			(min_thickness 0.25)
			(keepout
				(tracks not_allowed)
				(vias allowed)
				(pads allowed)
				(copperpour not_allowed)
				(footprints allowed)
			)
			(placement
				(enabled no)
				(sheetname "")
			)
			(fill
				(thermal_gap 0.5)
				(thermal_bridge_width 0.5)
				(island_removal_mode 0)
			)
			(polygon
				(pts
					(arc
						(start 346.114624 -48.399446)
						(mid 346.078253 -48.341583)
						(end 346.02039 -48.305212)
					)
					(arc
						(start 346.02039 -48.200056)
						(mid 346.150111 -48.269725)
						(end 346.21978 -48.399446)
					)
				)
			)
		)
		(zone
			(layer "F.Cu")
			(hatch none 0.5)
			(connect_pads
				(clearance 0)
			)
			(min_thickness 0.25)
			(keepout
				(tracks not_allowed)
				(vias allowed)
				(pads allowed)
				(copperpour not_allowed)
				(footprints allowed)
			)
			(placement
				(enabled no)
				(sheetname "")
			)
			(fill
				(thermal_gap 0.5)
				(thermal_bridge_width 0.5)
				(island_removal_mode 0)
			)
			(polygon
				(pts
					(arc
						(start 346.114624 -47.39894)
						(mid 346.078198 -47.341241)
						(end 346.02039 -47.30496)
					)
					(arc
						(start 346.02039 -47.19955)
						(mid 346.150111 -47.269219)
						(end 346.21978 -47.39894)
					)
				)
			)
		)
		(zone
			(layer "F.Cu")
			(hatch none 0.5)
			(connect_pads
				(clearance 0)
			)
			(min_thickness 0.25)
			(keepout
				(tracks not_allowed)
				(vias allowed)
				(pads allowed)
				(copperpour not_allowed)
				(footprints allowed)
			)
			(placement
				(enabled no)
				(sheetname "")
			)
			(fill
				(thermal_gap 0.5)
				(thermal_bridge_width 0.5)
				(island_removal_mode 0)
			)
			(polygon
				(pts
					(arc
						(start 346.114624 -46.398434)
						(mid 346.078198 -46.340735)
						(end 346.02039 -46.304454)
					)
					(arc
						(start 346.02039 -46.199044)
						(mid 346.150111 -46.268713)
						(end 346.21978 -46.398434)
					)
				)
			)
		)
		(zone
			(layer "F.Cu")
			(hatch none 0.5)
			(connect_pads
				(clearance 0)
			)
			(min_thickness 0.25)
			(keepout
				(tracks not_allowed)
				(vias allowed)
				(pads allowed)
				(copperpour not_allowed)
				(footprints allowed)
			)
			(placement
				(enabled no)
				(sheetname "")
			)
			(fill
				(thermal_gap 0.5)
				(thermal_bridge_width 0.5)
				(island_removal_mode 0)
			)
			(polygon
				(pts
					(arc
						(start 346.114624 -45.397928)
						(mid 346.078198 -45.340229)
						(end 346.02039 -45.303948)
					)
					(arc
						(start 346.02039 -45.198538)
						(mid 346.150111 -45.268207)
						(end 346.21978 -45.397928)
					)
				)
			)
		)
		(zone
			(layer "F.Cu")
			(hatch none 0.5)
			(connect_pads
				(clearance 0)
			)
			(min_thickness 0.25)
			(keepout
				(tracks not_allowed)
				(vias allowed)
				(pads allowed)
				(copperpour not_allowed)
				(footprints allowed)
			)
			(placement
				(enabled no)
				(sheetname "")
			)
			(fill
				(thermal_gap 0.5)
				(thermal_bridge_width 0.5)
				(island_removal_mode 0)
			)
			(polygon
				(pts
					(arc
						(start 346.114624 -44.397422)
						(mid 346.078198 -44.339723)
						(end 346.02039 -44.303442)
					)
					(arc
						(start 346.02039 -44.198032)
						(mid 346.150111 -44.267701)
						(end 346.21978 -44.397422)
					)
				)
			)
		)
		(zone
			(layer "F.Cu")
			(hatch none 0.5)
			(connect_pads
				(clearance 0)
			)
			(min_thickness 0.25)
			(keepout
				(tracks not_allowed)
				(vias allowed)
				(pads allowed)
				(copperpour not_allowed)
				(footprints allowed)
			)
			(placement
				(enabled no)
				(sheetname "")
			)
			(fill
				(thermal_gap 0.5)
				(thermal_bridge_width 0.5)
				(island_removal_mode 0)
			)
			(polygon
				(pts
					(arc
						(start 346.114624 -43.39717)
						(mid 346.078253 -43.339307)
						(end 346.02039 -43.302936)
					)
					(arc
						(start 346.02039 -43.197526)
						(mid 346.150199 -43.267283)
						(end 346.21978 -43.39717)
					)
				)
			)
		)
		(zone
			(layer "F.Cu")
			(hatch none 0.5)
			(connect_pads
				(clearance 0)
			)
			(min_thickness 0.25)
			(keepout
				(tracks not_allowed)
				(vias allowed)
				(pads allowed)
				(copperpour not_allowed)
				(footprints allowed)
			)
			(placement
				(enabled no)
				(sheetname "")
			)
			(fill
				(thermal_gap 0.5)
				(thermal_bridge_width 0.5)
				(island_removal_mode 0)
			)
			(polygon
				(pts
					(arc
						(start 346.114624 -42.396664)
						(mid 346.078253 -42.338801)
						(end 346.02039 -42.30243)
					)
					(arc
						(start 346.02039 -42.19702)
						(mid 346.150199 -42.266777)
						(end 346.21978 -42.396664)
					)
				)
			)
		)
		(zone
			(layer "F.Cu")
			(hatch none 0.5)
			(connect_pads
				(clearance 0)
			)
			(min_thickness 0.25)
			(keepout
				(tracks not_allowed)
				(vias allowed)
				(pads allowed)
				(copperpour not_allowed)
				(footprints allowed)
			)
			(placement
				(enabled no)
				(sheetname "")
			)
			(fill
				(thermal_gap 0.5)
				(thermal_bridge_width 0.5)
				(island_removal_mode 0)
			)
			(polygon
				(pts
					(arc
						(start 346.114624 -41.396158)
						(mid 346.078253 -41.338295)
						(end 346.02039 -41.301924)
					)
					(arc
						(start 346.02039 -41.196768)
						(mid 346.150111 -41.266437)
						(end 346.21978 -41.396158)
					)
				)
			)
		)
		(zone
			(layer "F.Cu")
			(hatch none 0.5)
			(connect_pads
				(clearance 0)
			)
			(min_thickness 0.25)
			(keepout
				(tracks not_allowed)
				(vias allowed)
				(pads allowed)
				(copperpour not_allowed)
				(footprints allowed)
			)
			(placement
				(enabled no)
				(sheetname "")
			)
			(fill
				(thermal_gap 0.5)
				(thermal_bridge_width 0.5)
				(island_removal_mode 0)
			)
			(polygon
				(pts
					(arc
						(start 346.114624 -40.395652)
						(mid 346.078253 -40.337789)
						(end 346.02039 -40.301418)
					)
					(arc
						(start 346.02039 -40.196262)
						(mid 346.150111 -40.265931)
						(end 346.21978 -40.395652)
					)
				)
			)
		)
		(zone
			(layer "F.Cu")
			(hatch none 0.5)
			(connect_pads
				(clearance 0)
			)
			(min_thickness 0.25)
			(keepout
				(tracks not_allowed)
				(vias allowed)
				(pads allowed)
				(copperpour not_allowed)
				(footprints allowed)
			)
			(placement
				(enabled no)
				(sheetname "")
			)
			(fill
				(thermal_gap 0.5)
				(thermal_bridge_width 0.5)
				(island_removal_mode 0)
			)
			(polygon
				(pts
					(arc
						(start 346.114624 -39.395146)
						(mid 346.078253 -39.337283)
						(end 346.02039 -39.300912)
					)
					(arc
						(start 346.02039 -39.195756)
						(mid 346.150111 -39.265425)
						(end 346.21978 -39.395146)
					)
				)
			)
		)
		(zone
			(layer "F.Cu")
			(hatch none 0.5)
			(connect_pads
				(clearance 0)
			)
			(min_thickness 0.25)
			(keepout
				(tracks not_allowed)
				(vias allowed)
				(pads allowed)
				(copperpour not_allowed)
				(footprints allowed)
			)
			(placement
				(enabled no)
				(sheetname "")
			)
			(fill
				(thermal_gap 0.5)
				(thermal_bridge_width 0.5)
				(island_removal_mode 0)
			)
			(polygon
				(pts
					(arc
						(start 346.239592 -58.005726)
						(mid 346.275963 -58.063589)
						(end 346.333826 -58.09996)
					)
					(arc
						(start 346.333826 -58.205116)
						(mid 346.204105 -58.135447)
						(end 346.134436 -58.005726)
					)
				)
			)
		)
		(zone
			(layer "F.Cu")
			(hatch none 0.5)
			(connect_pads
				(clearance 0)
			)
			(min_thickness 0.25)
			(keepout
				(tracks not_allowed)
				(vias allowed)
				(pads allowed)
				(copperpour not_allowed)
				(footprints allowed)
			)
			(placement
				(enabled no)
				(sheetname "")
			)
			(fill
				(thermal_gap 0.5)
				(thermal_bridge_width 0.5)
				(island_removal_mode 0)
			)
			(polygon
				(pts
					(arc
						(start 346.239592 -57.00522)
						(mid 346.275963 -57.063083)
						(end 346.333826 -57.099454)
					)
					(arc
						(start 346.333826 -57.20461)
						(mid 346.204105 -57.134941)
						(end 346.134436 -57.00522)
					)
				)
			)
		)
		(zone
			(layer "F.Cu")
			(hatch none 0.5)
			(connect_pads
				(clearance 0)
			)
			(min_thickness 0.25)
			(keepout
				(tracks not_allowed)
				(vias allowed)
				(pads allowed)
				(copperpour not_allowed)
				(footprints allowed)
			)
			(placement
				(enabled no)
				(sheetname "")
			)
			(fill
				(thermal_gap 0.5)
				(thermal_bridge_width 0.5)
				(island_removal_mode 0)
			)
			(polygon
				(pts
					(arc
						(start 346.239592 -56.004714)
						(mid 346.275963 -56.062577)
						(end 346.333826 -56.098948)
					)
					(arc
						(start 346.333826 -56.204104)
						(mid 346.204105 -56.134435)
						(end 346.134436 -56.004714)
					)
				)
			)
		)
		(zone
			(layer "F.Cu")
			(hatch none 0.5)
			(connect_pads
				(clearance 0)
			)
			(min_thickness 0.25)
			(keepout
				(tracks not_allowed)
				(vias allowed)
				(pads allowed)
				(copperpour not_allowed)
				(footprints allowed)
			)
			(placement
				(enabled no)
				(sheetname "")
			)
			(fill
				(thermal_gap 0.5)
				(thermal_bridge_width 0.5)
				(island_removal_mode 0)
			)
			(polygon
				(pts
					(arc
						(start 346.239592 -55.004208)
						(mid 346.275963 -55.062071)
						(end 346.333826 -55.098442)
					)
					(arc
						(start 346.333826 -55.203598)
						(mid 346.204105 -55.133929)
						(end 346.134436 -55.004208)
					)
				)
			)
		)
		(zone
			(layer "F.Cu")
			(hatch none 0.5)
			(connect_pads
				(clearance 0)
			)
			(min_thickness 0.25)
			(keepout
				(tracks not_allowed)
				(vias allowed)
				(pads allowed)
				(copperpour not_allowed)
				(footprints allowed)
			)
			(placement
				(enabled no)
				(sheetname "")
			)
			(fill
				(thermal_gap 0.5)
				(thermal_bridge_width 0.5)
				(island_removal_mode 0)
			)
			(polygon
				(pts
					(arc
						(start 346.239592 -54.003702)
						(mid 346.275963 -54.061565)
						(end 346.333826 -54.097936)
					)
					(arc
						(start 346.333826 -54.203092)
						(mid 346.204105 -54.133423)
						(end 346.134436 -54.003702)
					)
				)
			)
		)
		(zone
			(layer "F.Cu")
			(hatch none 0.5)
			(connect_pads
				(clearance 0)
			)
			(min_thickness 0.25)
			(keepout
				(tracks not_allowed)
				(vias allowed)
				(pads allowed)
				(copperpour not_allowed)
				(footprints allowed)
			)
			(placement
				(enabled no)
				(sheetname "")
			)
			(fill
				(thermal_gap 0.5)
				(thermal_bridge_width 0.5)
				(island_removal_mode 0)
			)
			(polygon
				(pts
					(arc
						(start 346.239592 -53.003196)
						(mid 346.275963 -53.061059)
						(end 346.333826 -53.09743)
					)
					(arc
						(start 346.333826 -53.202586)
						(mid 346.204105 -53.132917)
						(end 346.134436 -53.003196)
					)
				)
			)
		)
		(zone
			(layer "F.Cu")
			(hatch none 0.5)
			(connect_pads
				(clearance 0)
			)
			(min_thickness 0.25)
			(keepout
				(tracks not_allowed)
				(vias allowed)
				(pads allowed)
				(copperpour not_allowed)
				(footprints allowed)
			)
			(placement
				(enabled no)
				(sheetname "")
			)
			(fill
				(thermal_gap 0.5)
				(thermal_bridge_width 0.5)
				(island_removal_mode 0)
			)
			(polygon
				(pts
					(arc
						(start 346.239592 -52.00269)
						(mid 346.275963 -52.060553)
						(end 346.333826 -52.096924)
					)
					(arc
						(start 346.333826 -52.20208)
						(mid 346.204105 -52.132411)
						(end 346.134436 -52.00269)
					)
				)
			)
		)
		(zone
			(layer "F.Cu")
			(hatch none 0.5)
			(connect_pads
				(clearance 0)
			)
			(min_thickness 0.25)
			(keepout
				(tracks not_allowed)
				(vias allowed)
				(pads allowed)
				(copperpour not_allowed)
				(footprints allowed)
			)
			(placement
				(enabled no)
				(sheetname "")
			)
			(fill
				(thermal_gap 0.5)
				(thermal_bridge_width 0.5)
				(island_removal_mode 0)
			)
			(polygon
				(pts
					(arc
						(start 346.239592 -51.002184)
						(mid 346.275963 -51.060047)
						(end 346.333826 -51.096418)
					)
					(arc
						(start 346.333826 -51.201574)
						(mid 346.204105 -51.131905)
						(end 346.134436 -51.002184)
					)
				)
			)
		)
		(zone
			(layer "F.Cu")
			(hatch none 0.5)
			(connect_pads
				(clearance 0)
			)
			(min_thickness 0.25)
			(keepout
				(tracks not_allowed)
				(vias allowed)
				(pads allowed)
				(copperpour not_allowed)
				(footprints allowed)
			)
			(placement
				(enabled no)
				(sheetname "")
			)
			(fill
				(thermal_gap 0.5)
				(thermal_bridge_width 0.5)
				(island_removal_mode 0)
			)
			(polygon
				(pts
					(arc
						(start 346.239592 -50.001678)
						(mid 346.275963 -50.059541)
						(end 346.333826 -50.095912)
					)
					(arc
						(start 346.333826 -50.201068)
						(mid 346.204105 -50.131399)
						(end 346.134436 -50.001678)
					)
				)
			)
		)
		(zone
			(layer "F.Cu")
			(hatch none 0.5)
			(connect_pads
				(clearance 0)
			)
			(min_thickness 0.25)
			(keepout
				(tracks not_allowed)
				(vias allowed)
				(pads allowed)
				(copperpour not_allowed)
				(footprints allowed)
			)
			(placement
				(enabled no)
				(sheetname "")
			)
			(fill
				(thermal_gap 0.5)
				(thermal_bridge_width 0.5)
				(island_removal_mode 0)
			)
			(polygon
				(pts
					(arc
						(start 346.239592 -49.001172)
						(mid 346.275963 -49.059035)
						(end 346.333826 -49.095406)
					)
					(arc
						(start 346.333826 -49.200562)
						(mid 346.204105 -49.130893)
						(end 346.134436 -49.001172)
					)
				)
			)
		)
		(zone
			(layer "F.Cu")
			(hatch none 0.5)
			(connect_pads
				(clearance 0)
			)
			(min_thickness 0.25)
			(keepout
				(tracks not_allowed)
				(vias allowed)
				(pads allowed)
				(copperpour not_allowed)
				(footprints allowed)
			)
			(placement
				(enabled no)
				(sheetname "")
			)
			(fill
				(thermal_gap 0.5)
				(thermal_bridge_width 0.5)
				(island_removal_mode 0)
			)
			(polygon
				(pts
					(arc
						(start 346.239592 -48.000666)
						(mid 346.275963 -48.058529)
						(end 346.333826 -48.0949)
					)
					(arc
						(start 346.333826 -48.200056)
						(mid 346.204105 -48.130387)
						(end 346.134436 -48.000666)
					)
				)
			)
		)
		(zone
			(layer "F.Cu")
			(hatch none 0.5)
			(connect_pads
				(clearance 0)
			)
			(min_thickness 0.25)
			(keepout
				(tracks not_allowed)
				(vias allowed)
				(pads allowed)
				(copperpour not_allowed)
				(footprints allowed)
			)
			(placement
				(enabled no)
				(sheetname "")
			)
			(fill
				(thermal_gap 0.5)
				(thermal_bridge_width 0.5)
				(island_removal_mode 0)
			)
			(polygon
				(pts
					(arc
						(start 346.239592 -47.000414)
						(mid 346.275963 -47.058277)
						(end 346.333826 -47.094648)
					)
					(arc
						(start 346.333826 -47.199804)
						(mid 346.204105 -47.130135)
						(end 346.134436 -47.000414)
					)
				)
			)
		)
		(zone
			(layer "F.Cu")
			(hatch none 0.5)
			(connect_pads
				(clearance 0)
			)
			(min_thickness 0.25)
			(keepout
				(tracks not_allowed)
				(vias allowed)
				(pads allowed)
				(copperpour not_allowed)
				(footprints allowed)
			)
			(placement
				(enabled no)
				(sheetname "")
			)
			(fill
				(thermal_gap 0.5)
				(thermal_bridge_width 0.5)
				(island_removal_mode 0)
			)
			(polygon
				(pts
					(arc
						(start 346.239592 -45.999908)
						(mid 346.275963 -46.057771)
						(end 346.333826 -46.094142)
					)
					(arc
						(start 346.333826 -46.199298)
						(mid 346.204105 -46.129629)
						(end 346.134436 -45.999908)
					)
				)
			)
		)
		(zone
			(layer "F.Cu")
			(hatch none 0.5)
			(connect_pads
				(clearance 0)
			)
			(min_thickness 0.25)
			(keepout
				(tracks not_allowed)
				(vias allowed)
				(pads allowed)
				(copperpour not_allowed)
				(footprints allowed)
			)
			(placement
				(enabled no)
				(sheetname "")
			)
			(fill
				(thermal_gap 0.5)
				(thermal_bridge_width 0.5)
				(island_removal_mode 0)
			)
			(polygon
				(pts
					(arc
						(start 346.239592 -44.999402)
						(mid 346.275963 -45.057265)
						(end 346.333826 -45.093636)
					)
					(arc
						(start 346.333826 -45.198792)
						(mid 346.204105 -45.129123)
						(end 346.134436 -44.999402)
					)
				)
			)
		)
		(zone
			(layer "F.Cu")
			(hatch none 0.5)
			(connect_pads
				(clearance 0)
			)
			(min_thickness 0.25)
			(keepout
				(tracks not_allowed)
				(vias allowed)
				(pads allowed)
				(copperpour not_allowed)
				(footprints allowed)
			)
			(placement
				(enabled no)
				(sheetname "")
			)
			(fill
				(thermal_gap 0.5)
				(thermal_bridge_width 0.5)
				(island_removal_mode 0)
			)
			(polygon
				(pts
					(arc
						(start 346.239592 -43.998896)
						(mid 346.275963 -44.056759)
						(end 346.333826 -44.09313)
					)
					(arc
						(start 346.333826 -44.198286)
						(mid 346.204105 -44.128617)
						(end 346.134436 -43.998896)
					)
				)
			)
		)
		(zone
			(layer "F.Cu")
			(hatch none 0.5)
			(connect_pads
				(clearance 0)
			)
			(min_thickness 0.25)
			(keepout
				(tracks not_allowed)
				(vias allowed)
				(pads allowed)
				(copperpour not_allowed)
				(footprints allowed)
			)
			(placement
				(enabled no)
				(sheetname "")
			)
			(fill
				(thermal_gap 0.5)
				(thermal_bridge_width 0.5)
				(island_removal_mode 0)
			)
			(polygon
				(pts
					(arc
						(start 346.239592 -42.99839)
						(mid 346.275963 -43.056253)
						(end 346.333826 -43.092624)
					)
					(arc
						(start 346.333826 -43.19778)
						(mid 346.204105 -43.128111)
						(end 346.134436 -42.99839)
					)
				)
			)
		)
		(zone
			(layer "F.Cu")
			(hatch none 0.5)
			(connect_pads
				(clearance 0)
			)
			(min_thickness 0.25)
			(keepout
				(tracks not_allowed)
				(vias allowed)
				(pads allowed)
				(copperpour not_allowed)
				(footprints allowed)
			)
			(placement
				(enabled no)
				(sheetname "")
			)
			(fill
				(thermal_gap 0.5)
				(thermal_bridge_width 0.5)
				(island_removal_mode 0)
			)
			(polygon
				(pts
					(arc
						(start 346.239592 -41.997884)
						(mid 346.275963 -42.055747)
						(end 346.333826 -42.092118)
					)
					(arc
						(start 346.333826 -42.197274)
						(mid 346.204105 -42.127605)
						(end 346.134436 -41.997884)
					)
				)
			)
		)
		(zone
			(layer "F.Cu")
			(hatch none 0.5)
			(connect_pads
				(clearance 0)
			)
			(min_thickness 0.25)
			(keepout
				(tracks not_allowed)
				(vias allowed)
				(pads allowed)
				(copperpour not_allowed)
				(footprints allowed)
			)
			(placement
				(enabled no)
				(sheetname "")
			)
			(fill
				(thermal_gap 0.5)
				(thermal_bridge_width 0.5)
				(island_removal_mode 0)
			)
			(polygon
				(pts
					(arc
						(start 346.239592 -40.997378)
						(mid 346.275963 -41.055241)
						(end 346.333826 -41.091612)
					)
					(arc
						(start 346.333826 -41.196768)
						(mid 346.204105 -41.127099)
						(end 346.134436 -40.997378)
					)
				)
			)
		)
		(zone
			(layer "F.Cu")
			(hatch none 0.5)
			(connect_pads
				(clearance 0)
			)
			(min_thickness 0.25)
			(keepout
				(tracks not_allowed)
				(vias allowed)
				(pads allowed)
				(copperpour not_allowed)
				(footprints allowed)
			)
			(placement
				(enabled no)
				(sheetname "")
			)
			(fill
				(thermal_gap 0.5)
				(thermal_bridge_width 0.5)
				(island_removal_mode 0)
			)
			(polygon
				(pts
					(arc
						(start 346.239592 -39.996872)
						(mid 346.275963 -40.054735)
						(end 346.333826 -40.091106)
					)
					(arc
						(start 346.333826 -40.196262)
						(mid 346.204105 -40.126593)
						(end 346.134436 -39.996872)
					)
				)
			)
		)
		(zone
			(layer "F.Cu")
			(hatch none 0.5)
			(connect_pads
				(clearance 0)
			)
			(min_thickness 0.25)
			(keepout
				(tracks not_allowed)
				(vias allowed)
				(pads allowed)
				(copperpour not_allowed)
				(footprints allowed)
			)
			(placement
				(enabled no)
				(sheetname "")
			)
			(fill
				(thermal_gap 0.5)
				(thermal_bridge_width 0.5)
				(island_removal_mode 0)
			)
			(polygon
				(pts
					(arc
						(start 346.239592 -38.996366)
						(mid 346.275963 -39.054229)
						(end 346.333826 -39.0906)
					)
					(arc
						(start 346.333826 -39.195756)
						(mid 346.204105 -39.126087)
						(end 346.134436 -38.996366)
					)
				)
			)
		)
		(zone
			(layer "F.Cu")
			(hatch none 0.5)
			(connect_pads
				(clearance 0)
			)
			(min_thickness 0.25)
			(keepout
				(tracks not_allowed)
				(vias allowed)
				(pads allowed)
				(copperpour not_allowed)
				(footprints allowed)
			)
			(placement
				(enabled no)
				(sheetname "")
			)
			(fill
				(thermal_gap 0.5)
				(thermal_bridge_width 0.5)
				(island_removal_mode 0)
			)
			(polygon
				(pts
					(arc
						(start 346.333826 -57.809892)
						(mid 346.275963 -57.846263)
						(end 346.239592 -57.904126)
					)
					(arc
						(start 346.134436 -57.904126)
						(mid 346.204105 -57.774405)
						(end 346.333826 -57.704736)
					)
				)
			)
		)
		(zone
			(layer "F.Cu")
			(hatch none 0.5)
			(connect_pads
				(clearance 0)
			)
			(min_thickness 0.25)
			(keepout
				(tracks not_allowed)
				(vias allowed)
				(pads allowed)
				(copperpour not_allowed)
				(footprints allowed)
			)
			(placement
				(enabled no)
				(sheetname "")
			)
			(fill
				(thermal_gap 0.5)
				(thermal_bridge_width 0.5)
				(island_removal_mode 0)
			)
			(polygon
				(pts
					(arc
						(start 346.333826 -56.809386)
						(mid 346.275963 -56.845757)
						(end 346.239592 -56.90362)
					)
					(arc
						(start 346.134436 -56.90362)
						(mid 346.204105 -56.773899)
						(end 346.333826 -56.70423)
					)
				)
			)
		)
		(zone
			(layer "F.Cu")
			(hatch none 0.5)
			(connect_pads
				(clearance 0)
			)
			(min_thickness 0.25)
			(keepout
				(tracks not_allowed)
				(vias allowed)
				(pads allowed)
				(copperpour not_allowed)
				(footprints allowed)
			)
			(placement
				(enabled no)
				(sheetname "")
			)
			(fill
				(thermal_gap 0.5)
				(thermal_bridge_width 0.5)
				(island_removal_mode 0)
			)
			(polygon
				(pts
					(arc
						(start 346.333826 -55.80888)
						(mid 346.275963 -55.845251)
						(end 346.239592 -55.903114)
					)
					(arc
						(start 346.134436 -55.903114)
						(mid 346.204105 -55.773393)
						(end 346.333826 -55.703724)
					)
				)
			)
		)
		(zone
			(layer "F.Cu")
			(hatch none 0.5)
			(connect_pads
				(clearance 0)
			)
			(min_thickness 0.25)
			(keepout
				(tracks not_allowed)
				(vias allowed)
				(pads allowed)
				(copperpour not_allowed)
				(footprints allowed)
			)
			(placement
				(enabled no)
				(sheetname "")
			)
			(fill
				(thermal_gap 0.5)
				(thermal_bridge_width 0.5)
				(island_removal_mode 0)
			)
			(polygon
				(pts
					(arc
						(start 346.333826 -54.808374)
						(mid 346.275963 -54.844745)
						(end 346.239592 -54.902608)
					)
					(arc
						(start 346.134436 -54.902608)
						(mid 346.204105 -54.772887)
						(end 346.333826 -54.703218)
					)
				)
			)
		)
		(zone
			(layer "F.Cu")
			(hatch none 0.5)
			(connect_pads
				(clearance 0)
			)
			(min_thickness 0.25)
			(keepout
				(tracks not_allowed)
				(vias allowed)
				(pads allowed)
				(copperpour not_allowed)
				(footprints allowed)
			)
			(placement
				(enabled no)
				(sheetname "")
			)
			(fill
				(thermal_gap 0.5)
				(thermal_bridge_width 0.5)
				(island_removal_mode 0)
			)
			(polygon
				(pts
					(arc
						(start 346.333826 -53.807868)
						(mid 346.275963 -53.844239)
						(end 346.239592 -53.902102)
					)
					(arc
						(start 346.134436 -53.902102)
						(mid 346.204105 -53.772381)
						(end 346.333826 -53.702712)
					)
				)
			)
		)
		(zone
			(layer "F.Cu")
			(hatch none 0.5)
			(connect_pads
				(clearance 0)
			)
			(min_thickness 0.25)
			(keepout
				(tracks not_allowed)
				(vias allowed)
				(pads allowed)
				(copperpour not_allowed)
				(footprints allowed)
			)
			(placement
				(enabled no)
				(sheetname "")
			)
			(fill
				(thermal_gap 0.5)
				(thermal_bridge_width 0.5)
				(island_removal_mode 0)
			)
			(polygon
				(pts
					(arc
						(start 346.333826 -52.807362)
						(mid 346.275963 -52.843733)
						(end 346.239592 -52.901596)
					)
					(arc
						(start 346.134436 -52.901596)
						(mid 346.204105 -52.771875)
						(end 346.333826 -52.702206)
					)
				)
			)
		)
		(zone
			(layer "F.Cu")
			(hatch none 0.5)
			(connect_pads
				(clearance 0)
			)
			(min_thickness 0.25)
			(keepout
				(tracks not_allowed)
				(vias allowed)
				(pads allowed)
				(copperpour not_allowed)
				(footprints allowed)
			)
			(placement
				(enabled no)
				(sheetname "")
			)
			(fill
				(thermal_gap 0.5)
				(thermal_bridge_width 0.5)
				(island_removal_mode 0)
			)
			(polygon
				(pts
					(arc
						(start 346.333826 -51.806856)
						(mid 346.275963 -51.843227)
						(end 346.239592 -51.90109)
					)
					(arc
						(start 346.134436 -51.90109)
						(mid 346.204105 -51.771369)
						(end 346.333826 -51.7017)
					)
				)
			)
		)
		(zone
			(layer "F.Cu")
			(hatch none 0.5)
			(connect_pads
				(clearance 0)
			)
			(min_thickness 0.25)
			(keepout
				(tracks not_allowed)
				(vias allowed)
				(pads allowed)
				(copperpour not_allowed)
				(footprints allowed)
			)
			(placement
				(enabled no)
				(sheetname "")
			)
			(fill
				(thermal_gap 0.5)
				(thermal_bridge_width 0.5)
				(island_removal_mode 0)
			)
			(polygon
				(pts
					(arc
						(start 346.333826 -50.80635)
						(mid 346.275963 -50.842721)
						(end 346.239592 -50.900584)
					)
					(arc
						(start 346.134436 -50.900584)
						(mid 346.204105 -50.770863)
						(end 346.333826 -50.701194)
					)
				)
			)
		)
		(zone
			(layer "F.Cu")
			(hatch none 0.5)
			(connect_pads
				(clearance 0)
			)
			(min_thickness 0.25)
			(keepout
				(tracks not_allowed)
				(vias allowed)
				(pads allowed)
				(copperpour not_allowed)
				(footprints allowed)
			)
			(placement
				(enabled no)
				(sheetname "")
			)
			(fill
				(thermal_gap 0.5)
				(thermal_bridge_width 0.5)
				(island_removal_mode 0)
			)
			(polygon
				(pts
					(arc
						(start 346.333826 -49.805844)
						(mid 346.275963 -49.842215)
						(end 346.239592 -49.900078)
					)
					(arc
						(start 346.134436 -49.900078)
						(mid 346.204105 -49.770357)
						(end 346.333826 -49.700688)
					)
				)
			)
		)
		(zone
			(layer "F.Cu")
			(hatch none 0.5)
			(connect_pads
				(clearance 0)
			)
			(min_thickness 0.25)
			(keepout
				(tracks not_allowed)
				(vias allowed)
				(pads allowed)
				(copperpour not_allowed)
				(footprints allowed)
			)
			(placement
				(enabled no)
				(sheetname "")
			)
			(fill
				(thermal_gap 0.5)
				(thermal_bridge_width 0.5)
				(island_removal_mode 0)
			)
			(polygon
				(pts
					(arc
						(start 346.333826 -48.805338)
						(mid 346.275963 -48.841709)
						(end 346.239592 -48.899572)
					)
					(arc
						(start 346.134436 -48.899572)
						(mid 346.204105 -48.769851)
						(end 346.333826 -48.700182)
					)
				)
			)
		)
		(zone
			(layer "F.Cu")
			(hatch none 0.5)
			(connect_pads
				(clearance 0)
			)
			(min_thickness 0.25)
			(keepout
				(tracks not_allowed)
				(vias allowed)
				(pads allowed)
				(copperpour not_allowed)
				(footprints allowed)
			)
			(placement
				(enabled no)
				(sheetname "")
			)
			(fill
				(thermal_gap 0.5)
				(thermal_bridge_width 0.5)
				(island_removal_mode 0)
			)
			(polygon
				(pts
					(arc
						(start 346.333826 -47.804832)
						(mid 346.275963 -47.841203)
						(end 346.239592 -47.899066)
					)
					(arc
						(start 346.134436 -47.899066)
						(mid 346.204105 -47.769345)
						(end 346.333826 -47.699676)
					)
				)
			)
		)
		(zone
			(layer "F.Cu")
			(hatch none 0.5)
			(connect_pads
				(clearance 0)
			)
			(min_thickness 0.25)
			(keepout
				(tracks not_allowed)
				(vias allowed)
				(pads allowed)
				(copperpour not_allowed)
				(footprints allowed)
			)
			(placement
				(enabled no)
				(sheetname "")
			)
			(fill
				(thermal_gap 0.5)
				(thermal_bridge_width 0.5)
				(island_removal_mode 0)
			)
			(polygon
				(pts
					(arc
						(start 346.333826 -46.80458)
						(mid 346.275963 -46.840951)
						(end 346.239592 -46.898814)
					)
					(arc
						(start 346.134436 -46.898814)
						(mid 346.204105 -46.769093)
						(end 346.333826 -46.699424)
					)
				)
			)
		)
		(zone
			(layer "F.Cu")
			(hatch none 0.5)
			(connect_pads
				(clearance 0)
			)
			(min_thickness 0.25)
			(keepout
				(tracks not_allowed)
				(vias allowed)
				(pads allowed)
				(copperpour not_allowed)
				(footprints allowed)
			)
			(placement
				(enabled no)
				(sheetname "")
			)
			(fill
				(thermal_gap 0.5)
				(thermal_bridge_width 0.5)
				(island_removal_mode 0)
			)
			(polygon
				(pts
					(arc
						(start 346.333826 -45.804074)
						(mid 346.275963 -45.840445)
						(end 346.239592 -45.898308)
					)
					(arc
						(start 346.134436 -45.898308)
						(mid 346.204105 -45.768587)
						(end 346.333826 -45.698918)
					)
				)
			)
		)
		(zone
			(layer "F.Cu")
			(hatch none 0.5)
			(connect_pads
				(clearance 0)
			)
			(min_thickness 0.25)
			(keepout
				(tracks not_allowed)
				(vias allowed)
				(pads allowed)
				(copperpour not_allowed)
				(footprints allowed)
			)
			(placement
				(enabled no)
				(sheetname "")
			)
			(fill
				(thermal_gap 0.5)
				(thermal_bridge_width 0.5)
				(island_removal_mode 0)
			)
			(polygon
				(pts
					(arc
						(start 346.333826 -44.803568)
						(mid 346.275963 -44.839939)
						(end 346.239592 -44.897802)
					)
					(arc
						(start 346.134436 -44.897802)
						(mid 346.204105 -44.768081)
						(end 346.333826 -44.698412)
					)
				)
			)
		)
		(zone
			(layer "F.Cu")
			(hatch none 0.5)
			(connect_pads
				(clearance 0)
			)
			(min_thickness 0.25)
			(keepout
				(tracks not_allowed)
				(vias allowed)
				(pads allowed)
				(copperpour not_allowed)
				(footprints allowed)
			)
			(placement
				(enabled no)
				(sheetname "")
			)
			(fill
				(thermal_gap 0.5)
				(thermal_bridge_width 0.5)
				(island_removal_mode 0)
			)
			(polygon
				(pts
					(arc
						(start 346.333826 -43.803062)
						(mid 346.275963 -43.839433)
						(end 346.239592 -43.897296)
					)
					(arc
						(start 346.134436 -43.897296)
						(mid 346.204105 -43.767575)
						(end 346.333826 -43.697906)
					)
				)
			)
		)
		(zone
			(layer "F.Cu")
			(hatch none 0.5)
			(connect_pads
				(clearance 0)
			)
			(min_thickness 0.25)
			(keepout
				(tracks not_allowed)
				(vias allowed)
				(pads allowed)
				(copperpour not_allowed)
				(footprints allowed)
			)
			(placement
				(enabled no)
				(sheetname "")
			)
			(fill
				(thermal_gap 0.5)
				(thermal_bridge_width 0.5)
				(island_removal_mode 0)
			)
			(polygon
				(pts
					(arc
						(start 346.333826 -42.802556)
						(mid 346.275963 -42.838927)
						(end 346.239592 -42.89679)
					)
					(arc
						(start 346.134436 -42.89679)
						(mid 346.204105 -42.767069)
						(end 346.333826 -42.6974)
					)
				)
			)
		)
		(zone
			(layer "F.Cu")
			(hatch none 0.5)
			(connect_pads
				(clearance 0)
			)
			(min_thickness 0.25)
			(keepout
				(tracks not_allowed)
				(vias allowed)
				(pads allowed)
				(copperpour not_allowed)
				(footprints allowed)
			)
			(placement
				(enabled no)
				(sheetname "")
			)
			(fill
				(thermal_gap 0.5)
				(thermal_bridge_width 0.5)
				(island_removal_mode 0)
			)
			(polygon
				(pts
					(arc
						(start 346.333826 -41.80205)
						(mid 346.275963 -41.838421)
						(end 346.239592 -41.896284)
					)
					(arc
						(start 346.134436 -41.896284)
						(mid 346.204105 -41.766563)
						(end 346.333826 -41.696894)
					)
				)
			)
		)
		(zone
			(layer "F.Cu")
			(hatch none 0.5)
			(connect_pads
				(clearance 0)
			)
			(min_thickness 0.25)
			(keepout
				(tracks not_allowed)
				(vias allowed)
				(pads allowed)
				(copperpour not_allowed)
				(footprints allowed)
			)
			(placement
				(enabled no)
				(sheetname "")
			)
			(fill
				(thermal_gap 0.5)
				(thermal_bridge_width 0.5)
				(island_removal_mode 0)
			)
			(polygon
				(pts
					(arc
						(start 346.333826 -40.801544)
						(mid 346.275963 -40.837915)
						(end 346.239592 -40.895778)
					)
					(arc
						(start 346.134436 -40.895778)
						(mid 346.204105 -40.766057)
						(end 346.333826 -40.696388)
					)
				)
			)
		)
		(zone
			(layer "F.Cu")
			(hatch none 0.5)
			(connect_pads
				(clearance 0)
			)
			(min_thickness 0.25)
			(keepout
				(tracks not_allowed)
				(vias allowed)
				(pads allowed)
				(copperpour not_allowed)
				(footprints allowed)
			)
			(placement
				(enabled no)
				(sheetname "")
			)
			(fill
				(thermal_gap 0.5)
				(thermal_bridge_width 0.5)
				(island_removal_mode 0)
			)
			(polygon
				(pts
					(arc
						(start 346.333826 -39.801038)
						(mid 346.275963 -39.837409)
						(end 346.239592 -39.895272)
					)
					(arc
						(start 346.134436 -39.895272)
						(mid 346.204105 -39.765551)
						(end 346.333826 -39.695882)
					)
				)
			)
		)
		(zone
			(layer "F.Cu")
			(hatch none 0.5)
			(connect_pads
				(clearance 0)
			)
			(min_thickness 0.25)
			(keepout
				(tracks not_allowed)
				(vias allowed)
				(pads allowed)
				(copperpour not_allowed)
				(footprints allowed)
			)
			(placement
				(enabled no)
				(sheetname "")
			)
			(fill
				(thermal_gap 0.5)
				(thermal_bridge_width 0.5)
				(island_removal_mode 0)
			)
			(polygon
				(pts
					(arc
						(start 346.333826 -38.800532)
						(mid 346.275963 -38.836903)
						(end 346.239592 -38.894766)
					)
					(arc
						(start 346.134436 -38.894766)
						(mid 346.204105 -38.765045)
						(end 346.333826 -38.695376)
					)
				)
			)
		)
		(zone
			(layer "F.Cu")
			(hatch none 0.5)
			(connect_pads
				(clearance 0)
			)
			(min_thickness 0.25)
			(keepout
				(tracks not_allowed)
				(vias allowed)
				(pads allowed)
				(copperpour not_allowed)
				(footprints allowed)
			)
			(placement
				(enabled no)
				(sheetname "")
			)
			(fill
				(thermal_gap 0.5)
				(thermal_bridge_width 0.5)
				(island_removal_mode 0)
			)
			(polygon
				(pts
					(arc
						(start 346.414344 -58.660792)
						(mid 346.450715 -58.718655)
						(end 346.508578 -58.755026)
					)
					(arc
						(start 346.508578 -58.860182)
						(mid 346.378857 -58.790513)
						(end 346.309188 -58.660792)
					)
				)
			)
		)
		(zone
			(layer "F.Cu")
			(hatch none 0.5)
			(connect_pads
				(clearance 0)
			)
			(min_thickness 0.25)
			(keepout
				(tracks not_allowed)
				(vias allowed)
				(pads allowed)
				(copperpour not_allowed)
				(footprints allowed)
			)
			(placement
				(enabled no)
				(sheetname "")
			)
			(fill
				(thermal_gap 0.5)
				(thermal_bridge_width 0.5)
				(island_removal_mode 0)
			)
			(polygon
				(pts
					(arc
						(start 346.414344 -38.3413)
						(mid 346.450715 -38.399163)
						(end 346.508578 -38.435534)
					)
					(arc
						(start 346.508578 -38.54069)
						(mid 346.378857 -38.471021)
						(end 346.309188 -38.3413)
					)
				)
			)
		)
		(zone
			(layer "F.Cu")
			(hatch none 0.5)
			(connect_pads
				(clearance 0)
			)
			(min_thickness 0.25)
			(keepout
				(tracks not_allowed)
				(vias allowed)
				(pads allowed)
				(copperpour not_allowed)
				(footprints allowed)
			)
			(placement
				(enabled no)
				(sheetname "")
			)
			(fill
				(thermal_gap 0.5)
				(thermal_bridge_width 0.5)
				(island_removal_mode 0)
			)
			(polygon
				(pts
					(arc
						(start 346.435426 -58.09996)
						(mid 346.493289 -58.063589)
						(end 346.52966 -58.005726)
					)
					(arc
						(start 346.634816 -58.005726)
						(mid 346.565147 -58.135447)
						(end 346.435426 -58.205116)
					)
				)
			)
		)
		(zone
			(layer "F.Cu")
			(hatch none 0.5)
			(connect_pads
				(clearance 0)
			)
			(min_thickness 0.25)
			(keepout
				(tracks not_allowed)
				(vias allowed)
				(pads allowed)
				(copperpour not_allowed)
				(footprints allowed)
			)
			(placement
				(enabled no)
				(sheetname "")
			)
			(fill
				(thermal_gap 0.5)
				(thermal_bridge_width 0.5)
				(island_removal_mode 0)
			)
			(polygon
				(pts
					(arc
						(start 346.435426 -57.099454)
						(mid 346.493289 -57.063083)
						(end 346.52966 -57.00522)
					)
					(arc
						(start 346.634816 -57.00522)
						(mid 346.565147 -57.134941)
						(end 346.435426 -57.20461)
					)
				)
			)
		)
		(zone
			(layer "F.Cu")
			(hatch none 0.5)
			(connect_pads
				(clearance 0)
			)
			(min_thickness 0.25)
			(keepout
				(tracks not_allowed)
				(vias allowed)
				(pads allowed)
				(copperpour not_allowed)
				(footprints allowed)
			)
			(placement
				(enabled no)
				(sheetname "")
			)
			(fill
				(thermal_gap 0.5)
				(thermal_bridge_width 0.5)
				(island_removal_mode 0)
			)
			(polygon
				(pts
					(arc
						(start 346.435426 -56.098948)
						(mid 346.493289 -56.062577)
						(end 346.52966 -56.004714)
					)
					(arc
						(start 346.634816 -56.004714)
						(mid 346.565147 -56.134435)
						(end 346.435426 -56.204104)
					)
				)
			)
		)
		(zone
			(layer "F.Cu")
			(hatch none 0.5)
			(connect_pads
				(clearance 0)
			)
			(min_thickness 0.25)
			(keepout
				(tracks not_allowed)
				(vias allowed)
				(pads allowed)
				(copperpour not_allowed)
				(footprints allowed)
			)
			(placement
				(enabled no)
				(sheetname "")
			)
			(fill
				(thermal_gap 0.5)
				(thermal_bridge_width 0.5)
				(island_removal_mode 0)
			)
			(polygon
				(pts
					(arc
						(start 346.435426 -55.098442)
						(mid 346.493289 -55.062071)
						(end 346.52966 -55.004208)
					)
					(arc
						(start 346.634816 -55.004208)
						(mid 346.565147 -55.133929)
						(end 346.435426 -55.203598)
					)
				)
			)
		)
		(zone
			(layer "F.Cu")
			(hatch none 0.5)
			(connect_pads
				(clearance 0)
			)
			(min_thickness 0.25)
			(keepout
				(tracks not_allowed)
				(vias allowed)
				(pads allowed)
				(copperpour not_allowed)
				(footprints allowed)
			)
			(placement
				(enabled no)
				(sheetname "")
			)
			(fill
				(thermal_gap 0.5)
				(thermal_bridge_width 0.5)
				(island_removal_mode 0)
			)
			(polygon
				(pts
					(arc
						(start 346.435426 -54.097936)
						(mid 346.493289 -54.061565)
						(end 346.52966 -54.003702)
					)
					(arc
						(start 346.634816 -54.003702)
						(mid 346.565147 -54.133423)
						(end 346.435426 -54.203092)
					)
				)
			)
		)
		(zone
			(layer "F.Cu")
			(hatch none 0.5)
			(connect_pads
				(clearance 0)
			)
			(min_thickness 0.25)
			(keepout
				(tracks not_allowed)
				(vias allowed)
				(pads allowed)
				(copperpour not_allowed)
				(footprints allowed)
			)
			(placement
				(enabled no)
				(sheetname "")
			)
			(fill
				(thermal_gap 0.5)
				(thermal_bridge_width 0.5)
				(island_removal_mode 0)
			)
			(polygon
				(pts
					(arc
						(start 346.435426 -53.09743)
						(mid 346.493289 -53.061059)
						(end 346.52966 -53.003196)
					)
					(arc
						(start 346.634816 -53.003196)
						(mid 346.565147 -53.132917)
						(end 346.435426 -53.202586)
					)
				)
			)
		)
		(zone
			(layer "F.Cu")
			(hatch none 0.5)
			(connect_pads
				(clearance 0)
			)
			(min_thickness 0.25)
			(keepout
				(tracks not_allowed)
				(vias allowed)
				(pads allowed)
				(copperpour not_allowed)
				(footprints allowed)
			)
			(placement
				(enabled no)
				(sheetname "")
			)
			(fill
				(thermal_gap 0.5)
				(thermal_bridge_width 0.5)
				(island_removal_mode 0)
			)
			(polygon
				(pts
					(arc
						(start 346.435426 -52.096924)
						(mid 346.493289 -52.060553)
						(end 346.52966 -52.00269)
					)
					(arc
						(start 346.634816 -52.00269)
						(mid 346.565147 -52.132411)
						(end 346.435426 -52.20208)
					)
				)
			)
		)
		(zone
			(layer "F.Cu")
			(hatch none 0.5)
			(connect_pads
				(clearance 0)
			)
			(min_thickness 0.25)
			(keepout
				(tracks not_allowed)
				(vias allowed)
				(pads allowed)
				(copperpour not_allowed)
				(footprints allowed)
			)
			(placement
				(enabled no)
				(sheetname "")
			)
			(fill
				(thermal_gap 0.5)
				(thermal_bridge_width 0.5)
				(island_removal_mode 0)
			)
			(polygon
				(pts
					(arc
						(start 346.435426 -51.096418)
						(mid 346.493289 -51.060047)
						(end 346.52966 -51.002184)
					)
					(arc
						(start 346.634816 -51.002184)
						(mid 346.565147 -51.131905)
						(end 346.435426 -51.201574)
					)
				)
			)
		)
		(zone
			(layer "F.Cu")
			(hatch none 0.5)
			(connect_pads
				(clearance 0)
			)
			(min_thickness 0.25)
			(keepout
				(tracks not_allowed)
				(vias allowed)
				(pads allowed)
				(copperpour not_allowed)
				(footprints allowed)
			)
			(placement
				(enabled no)
				(sheetname "")
			)
			(fill
				(thermal_gap 0.5)
				(thermal_bridge_width 0.5)
				(island_removal_mode 0)
			)
			(polygon
				(pts
					(arc
						(start 346.435426 -50.095912)
						(mid 346.493289 -50.059541)
						(end 346.52966 -50.001678)
					)
					(arc
						(start 346.634816 -50.001678)
						(mid 346.565147 -50.131399)
						(end 346.435426 -50.201068)
					)
				)
			)
		)
		(zone
			(layer "F.Cu")
			(hatch none 0.5)
			(connect_pads
				(clearance 0)
			)
			(min_thickness 0.25)
			(keepout
				(tracks not_allowed)
				(vias allowed)
				(pads allowed)
				(copperpour not_allowed)
				(footprints allowed)
			)
			(placement
				(enabled no)
				(sheetname "")
			)
			(fill
				(thermal_gap 0.5)
				(thermal_bridge_width 0.5)
				(island_removal_mode 0)
			)
			(polygon
				(pts
					(arc
						(start 346.435426 -49.095406)
						(mid 346.493289 -49.059035)
						(end 346.52966 -49.001172)
					)
					(arc
						(start 346.634816 -49.001172)
						(mid 346.565147 -49.130893)
						(end 346.435426 -49.200562)
					)
				)
			)
		)
		(zone
			(layer "F.Cu")
			(hatch none 0.5)
			(connect_pads
				(clearance 0)
			)
			(min_thickness 0.25)
			(keepout
				(tracks not_allowed)
				(vias allowed)
				(pads allowed)
				(copperpour not_allowed)
				(footprints allowed)
			)
			(placement
				(enabled no)
				(sheetname "")
			)
			(fill
				(thermal_gap 0.5)
				(thermal_bridge_width 0.5)
				(island_removal_mode 0)
			)
			(polygon
				(pts
					(arc
						(start 346.435426 -48.0949)
						(mid 346.493289 -48.058529)
						(end 346.52966 -48.000666)
					)
					(arc
						(start 346.634816 -48.000666)
						(mid 346.565147 -48.130387)
						(end 346.435426 -48.200056)
					)
				)
			)
		)
		(zone
			(layer "F.Cu")
			(hatch none 0.5)
			(connect_pads
				(clearance 0)
			)
			(min_thickness 0.25)
			(keepout
				(tracks not_allowed)
				(vias allowed)
				(pads allowed)
				(copperpour not_allowed)
				(footprints allowed)
			)
			(placement
				(enabled no)
				(sheetname "")
			)
			(fill
				(thermal_gap 0.5)
				(thermal_bridge_width 0.5)
				(island_removal_mode 0)
			)
			(polygon
				(pts
					(arc
						(start 346.435426 -47.094648)
						(mid 346.493289 -47.058277)
						(end 346.52966 -47.000414)
					)
					(arc
						(start 346.634816 -47.000414)
						(mid 346.565147 -47.130135)
						(end 346.435426 -47.199804)
					)
				)
			)
		)
		(zone
			(layer "F.Cu")
			(hatch none 0.5)
			(connect_pads
				(clearance 0)
			)
			(min_thickness 0.25)
			(keepout
				(tracks not_allowed)
				(vias allowed)
				(pads allowed)
				(copperpour not_allowed)
				(footprints allowed)
			)
			(placement
				(enabled no)
				(sheetname "")
			)
			(fill
				(thermal_gap 0.5)
				(thermal_bridge_width 0.5)
				(island_removal_mode 0)
			)
			(polygon
				(pts
					(arc
						(start 346.435426 -46.094142)
						(mid 346.493289 -46.057771)
						(end 346.52966 -45.999908)
					)
					(arc
						(start 346.634816 -45.999908)
						(mid 346.565147 -46.129629)
						(end 346.435426 -46.199298)
					)
				)
			)
		)
		(zone
			(layer "F.Cu")
			(hatch none 0.5)
			(connect_pads
				(clearance 0)
			)
			(min_thickness 0.25)
			(keepout
				(tracks not_allowed)
				(vias allowed)
				(pads allowed)
				(copperpour not_allowed)
				(footprints allowed)
			)
			(placement
				(enabled no)
				(sheetname "")
			)
			(fill
				(thermal_gap 0.5)
				(thermal_bridge_width 0.5)
				(island_removal_mode 0)
			)
			(polygon
				(pts
					(arc
						(start 346.435426 -45.093636)
						(mid 346.493289 -45.057265)
						(end 346.52966 -44.999402)
					)
					(arc
						(start 346.634816 -44.999402)
						(mid 346.565147 -45.129123)
						(end 346.435426 -45.198792)
					)
				)
			)
		)
		(zone
			(layer "F.Cu")
			(hatch none 0.5)
			(connect_pads
				(clearance 0)
			)
			(min_thickness 0.25)
			(keepout
				(tracks not_allowed)
				(vias allowed)
				(pads allowed)
				(copperpour not_allowed)
				(footprints allowed)
			)
			(placement
				(enabled no)
				(sheetname "")
			)
			(fill
				(thermal_gap 0.5)
				(thermal_bridge_width 0.5)
				(island_removal_mode 0)
			)
			(polygon
				(pts
					(arc
						(start 346.435426 -44.09313)
						(mid 346.493289 -44.056759)
						(end 346.52966 -43.998896)
					)
					(arc
						(start 346.634816 -43.998896)
						(mid 346.565147 -44.128617)
						(end 346.435426 -44.198286)
					)
				)
			)
		)
		(zone
			(layer "F.Cu")
			(hatch none 0.5)
			(connect_pads
				(clearance 0)
			)
			(min_thickness 0.25)
			(keepout
				(tracks not_allowed)
				(vias allowed)
				(pads allowed)
				(copperpour not_allowed)
				(footprints allowed)
			)
			(placement
				(enabled no)
				(sheetname "")
			)
			(fill
				(thermal_gap 0.5)
				(thermal_bridge_width 0.5)
				(island_removal_mode 0)
			)
			(polygon
				(pts
					(arc
						(start 346.435426 -43.092624)
						(mid 346.493289 -43.056253)
						(end 346.52966 -42.99839)
					)
					(arc
						(start 346.634816 -42.99839)
						(mid 346.565147 -43.128111)
						(end 346.435426 -43.19778)
					)
				)
			)
		)
		(zone
			(layer "F.Cu")
			(hatch none 0.5)
			(connect_pads
				(clearance 0)
			)
			(min_thickness 0.25)
			(keepout
				(tracks not_allowed)
				(vias allowed)
				(pads allowed)
				(copperpour not_allowed)
				(footprints allowed)
			)
			(placement
				(enabled no)
				(sheetname "")
			)
			(fill
				(thermal_gap 0.5)
				(thermal_bridge_width 0.5)
				(island_removal_mode 0)
			)
			(polygon
				(pts
					(arc
						(start 346.435426 -42.092118)
						(mid 346.493289 -42.055747)
						(end 346.52966 -41.997884)
					)
					(arc
						(start 346.634816 -41.997884)
						(mid 346.565147 -42.127605)
						(end 346.435426 -42.197274)
					)
				)
			)
		)
		(zone
			(layer "F.Cu")
			(hatch none 0.5)
			(connect_pads
				(clearance 0)
			)
			(min_thickness 0.25)
			(keepout
				(tracks not_allowed)
				(vias allowed)
				(pads allowed)
				(copperpour not_allowed)
				(footprints allowed)
			)
			(placement
				(enabled no)
				(sheetname "")
			)
			(fill
				(thermal_gap 0.5)
				(thermal_bridge_width 0.5)
				(island_removal_mode 0)
			)
			(polygon
				(pts
					(arc
						(start 346.435426 -41.091612)
						(mid 346.493289 -41.055241)
						(end 346.52966 -40.997378)
					)
					(arc
						(start 346.634816 -40.997378)
						(mid 346.565147 -41.127099)
						(end 346.435426 -41.196768)
					)
				)
			)
		)
		(zone
			(layer "F.Cu")
			(hatch none 0.5)
			(connect_pads
				(clearance 0)
			)
			(min_thickness 0.25)
			(keepout
				(tracks not_allowed)
				(vias allowed)
				(pads allowed)
				(copperpour not_allowed)
				(footprints allowed)
			)
			(placement
				(enabled no)
				(sheetname "")
			)
			(fill
				(thermal_gap 0.5)
				(thermal_bridge_width 0.5)
				(island_removal_mode 0)
			)
			(polygon
				(pts
					(arc
						(start 346.435426 -40.091106)
						(mid 346.493289 -40.054735)
						(end 346.52966 -39.996872)
					)
					(arc
						(start 346.634816 -39.996872)
						(mid 346.565147 -40.126593)
						(end 346.435426 -40.196262)
					)
				)
			)
		)
		(zone
			(layer "F.Cu")
			(hatch none 0.5)
			(connect_pads
				(clearance 0)
			)
			(min_thickness 0.25)
			(keepout
				(tracks not_allowed)
				(vias allowed)
				(pads allowed)
				(copperpour not_allowed)
				(footprints allowed)
			)
			(placement
				(enabled no)
				(sheetname "")
			)
			(fill
				(thermal_gap 0.5)
				(thermal_bridge_width 0.5)
				(island_removal_mode 0)
			)
			(polygon
				(pts
					(arc
						(start 346.435426 -39.0906)
						(mid 346.493289 -39.054229)
						(end 346.52966 -38.996366)
					)
					(arc
						(start 346.634816 -38.996366)
						(mid 346.565147 -39.126087)
						(end 346.435426 -39.195756)
					)
				)
			)
		)
		(zone
			(layer "F.Cu")
			(hatch none 0.5)
			(connect_pads
				(clearance 0)
			)
			(min_thickness 0.25)
			(keepout
				(tracks not_allowed)
				(vias allowed)
				(pads allowed)
				(copperpour not_allowed)
				(footprints allowed)
			)
			(placement
				(enabled no)
				(sheetname "")
			)
			(fill
				(thermal_gap 0.5)
				(thermal_bridge_width 0.5)
				(island_removal_mode 0)
			)
			(polygon
				(pts
					(arc
						(start 346.508578 -58.464958)
						(mid 346.450715 -58.501329)
						(end 346.414344 -58.559192)
					)
					(arc
						(start 346.309188 -58.559192)
						(mid 346.378857 -58.429471)
						(end 346.508578 -58.359802)
					)
				)
			)
		)
		(zone
			(layer "F.Cu")
			(hatch none 0.5)
			(connect_pads
				(clearance 0)
			)
			(min_thickness 0.25)
			(keepout
				(tracks not_allowed)
				(vias allowed)
				(pads allowed)
				(copperpour not_allowed)
				(footprints allowed)
			)
			(placement
				(enabled no)
				(sheetname "")
			)
			(fill
				(thermal_gap 0.5)
				(thermal_bridge_width 0.5)
				(island_removal_mode 0)
			)
			(polygon
				(pts
					(arc
						(start 346.508578 -38.145466)
						(mid 346.450715 -38.181837)
						(end 346.414344 -38.2397)
					)
					(arc
						(start 346.309188 -38.2397)
						(mid 346.378857 -38.109979)
						(end 346.508578 -38.04031)
					)
				)
			)
		)
		(zone
			(layer "F.Cu")
			(hatch none 0.5)
			(connect_pads
				(clearance 0)
			)
			(min_thickness 0.25)
			(keepout
				(tracks not_allowed)
				(vias allowed)
				(pads allowed)
				(copperpour not_allowed)
				(footprints allowed)
			)
			(placement
				(enabled no)
				(sheetname "")
			)
			(fill
				(thermal_gap 0.5)
				(thermal_bridge_width 0.5)
				(island_removal_mode 0)
			)
			(polygon
				(pts
					(arc
						(start 346.52966 -57.904126)
						(mid 346.493289 -57.846263)
						(end 346.435426 -57.809892)
					)
					(arc
						(start 346.435426 -57.704736)
						(mid 346.565147 -57.774405)
						(end 346.634816 -57.904126)
					)
				)
			)
		)
		(zone
			(layer "F.Cu")
			(hatch none 0.5)
			(connect_pads
				(clearance 0)
			)
			(min_thickness 0.25)
			(keepout
				(tracks not_allowed)
				(vias allowed)
				(pads allowed)
				(copperpour not_allowed)
				(footprints allowed)
			)
			(placement
				(enabled no)
				(sheetname "")
			)
			(fill
				(thermal_gap 0.5)
				(thermal_bridge_width 0.5)
				(island_removal_mode 0)
			)
			(polygon
				(pts
					(arc
						(start 346.52966 -56.90362)
						(mid 346.493289 -56.845757)
						(end 346.435426 -56.809386)
					)
					(arc
						(start 346.435426 -56.70423)
						(mid 346.565147 -56.773899)
						(end 346.634816 -56.90362)
					)
				)
			)
		)
		(zone
			(layer "F.Cu")
			(hatch none 0.5)
			(connect_pads
				(clearance 0)
			)
			(min_thickness 0.25)
			(keepout
				(tracks not_allowed)
				(vias allowed)
				(pads allowed)
				(copperpour not_allowed)
				(footprints allowed)
			)
			(placement
				(enabled no)
				(sheetname "")
			)
			(fill
				(thermal_gap 0.5)
				(thermal_bridge_width 0.5)
				(island_removal_mode 0)
			)
			(polygon
				(pts
					(arc
						(start 346.52966 -55.903114)
						(mid 346.493289 -55.845251)
						(end 346.435426 -55.80888)
					)
					(arc
						(start 346.435426 -55.703724)
						(mid 346.565147 -55.773393)
						(end 346.634816 -55.903114)
					)
				)
			)
		)
		(zone
			(layer "F.Cu")
			(hatch none 0.5)
			(connect_pads
				(clearance 0)
			)
			(min_thickness 0.25)
			(keepout
				(tracks not_allowed)
				(vias allowed)
				(pads allowed)
				(copperpour not_allowed)
				(footprints allowed)
			)
			(placement
				(enabled no)
				(sheetname "")
			)
			(fill
				(thermal_gap 0.5)
				(thermal_bridge_width 0.5)
				(island_removal_mode 0)
			)
			(polygon
				(pts
					(arc
						(start 346.52966 -54.902608)
						(mid 346.493289 -54.844745)
						(end 346.435426 -54.808374)
					)
					(arc
						(start 346.435426 -54.703218)
						(mid 346.565147 -54.772887)
						(end 346.634816 -54.902608)
					)
				)
			)
		)
		(zone
			(layer "F.Cu")
			(hatch none 0.5)
			(connect_pads
				(clearance 0)
			)
			(min_thickness 0.25)
			(keepout
				(tracks not_allowed)
				(vias allowed)
				(pads allowed)
				(copperpour not_allowed)
				(footprints allowed)
			)
			(placement
				(enabled no)
				(sheetname "")
			)
			(fill
				(thermal_gap 0.5)
				(thermal_bridge_width 0.5)
				(island_removal_mode 0)
			)
			(polygon
				(pts
					(arc
						(start 346.52966 -53.902102)
						(mid 346.493289 -53.844239)
						(end 346.435426 -53.807868)
					)
					(arc
						(start 346.435426 -53.702712)
						(mid 346.565147 -53.772381)
						(end 346.634816 -53.902102)
					)
				)
			)
		)
		(zone
			(layer "F.Cu")
			(hatch none 0.5)
			(connect_pads
				(clearance 0)
			)
			(min_thickness 0.25)
			(keepout
				(tracks not_allowed)
				(vias allowed)
				(pads allowed)
				(copperpour not_allowed)
				(footprints allowed)
			)
			(placement
				(enabled no)
				(sheetname "")
			)
			(fill
				(thermal_gap 0.5)
				(thermal_bridge_width 0.5)
				(island_removal_mode 0)
			)
			(polygon
				(pts
					(arc
						(start 346.52966 -52.901596)
						(mid 346.493289 -52.843733)
						(end 346.435426 -52.807362)
					)
					(arc
						(start 346.435426 -52.702206)
						(mid 346.565147 -52.771875)
						(end 346.634816 -52.901596)
					)
				)
			)
		)
		(zone
			(layer "F.Cu")
			(hatch none 0.5)
			(connect_pads
				(clearance 0)
			)
			(min_thickness 0.25)
			(keepout
				(tracks not_allowed)
				(vias allowed)
				(pads allowed)
				(copperpour not_allowed)
				(footprints allowed)
			)
			(placement
				(enabled no)
				(sheetname "")
			)
			(fill
				(thermal_gap 0.5)
				(thermal_bridge_width 0.5)
				(island_removal_mode 0)
			)
			(polygon
				(pts
					(arc
						(start 346.52966 -51.90109)
						(mid 346.493289 -51.843227)
						(end 346.435426 -51.806856)
					)
					(arc
						(start 346.435426 -51.7017)
						(mid 346.565147 -51.771369)
						(end 346.634816 -51.90109)
					)
				)
			)
		)
		(zone
			(layer "F.Cu")
			(hatch none 0.5)
			(connect_pads
				(clearance 0)
			)
			(min_thickness 0.25)
			(keepout
				(tracks not_allowed)
				(vias allowed)
				(pads allowed)
				(copperpour not_allowed)
				(footprints allowed)
			)
			(placement
				(enabled no)
				(sheetname "")
			)
			(fill
				(thermal_gap 0.5)
				(thermal_bridge_width 0.5)
				(island_removal_mode 0)
			)
			(polygon
				(pts
					(arc
						(start 346.52966 -50.900584)
						(mid 346.493289 -50.842721)
						(end 346.435426 -50.80635)
					)
					(arc
						(start 346.435426 -50.701194)
						(mid 346.565147 -50.770863)
						(end 346.634816 -50.900584)
					)
				)
			)
		)
		(zone
			(layer "F.Cu")
			(hatch none 0.5)
			(connect_pads
				(clearance 0)
			)
			(min_thickness 0.25)
			(keepout
				(tracks not_allowed)
				(vias allowed)
				(pads allowed)
				(copperpour not_allowed)
				(footprints allowed)
			)
			(placement
				(enabled no)
				(sheetname "")
			)
			(fill
				(thermal_gap 0.5)
				(thermal_bridge_width 0.5)
				(island_removal_mode 0)
			)
			(polygon
				(pts
					(arc
						(start 346.52966 -49.900078)
						(mid 346.493289 -49.842215)
						(end 346.435426 -49.805844)
					)
					(arc
						(start 346.435426 -49.700688)
						(mid 346.565147 -49.770357)
						(end 346.634816 -49.900078)
					)
				)
			)
		)
		(zone
			(layer "F.Cu")
			(hatch none 0.5)
			(connect_pads
				(clearance 0)
			)
			(min_thickness 0.25)
			(keepout
				(tracks not_allowed)
				(vias allowed)
				(pads allowed)
				(copperpour not_allowed)
				(footprints allowed)
			)
			(placement
				(enabled no)
				(sheetname "")
			)
			(fill
				(thermal_gap 0.5)
				(thermal_bridge_width 0.5)
				(island_removal_mode 0)
			)
			(polygon
				(pts
					(arc
						(start 346.52966 -48.899572)
						(mid 346.493289 -48.841709)
						(end 346.435426 -48.805338)
					)
					(arc
						(start 346.435426 -48.700182)
						(mid 346.565147 -48.769851)
						(end 346.634816 -48.899572)
					)
				)
			)
		)
		(zone
			(layer "F.Cu")
			(hatch none 0.5)
			(connect_pads
				(clearance 0)
			)
			(min_thickness 0.25)
			(keepout
				(tracks not_allowed)
				(vias allowed)
				(pads allowed)
				(copperpour not_allowed)
				(footprints allowed)
			)
			(placement
				(enabled no)
				(sheetname "")
			)
			(fill
				(thermal_gap 0.5)
				(thermal_bridge_width 0.5)
				(island_removal_mode 0)
			)
			(polygon
				(pts
					(arc
						(start 346.52966 -47.899066)
						(mid 346.493289 -47.841203)
						(end 346.435426 -47.804832)
					)
					(arc
						(start 346.435426 -47.699676)
						(mid 346.565147 -47.769345)
						(end 346.634816 -47.899066)
					)
				)
			)
		)
		(zone
			(layer "F.Cu")
			(hatch none 0.5)
			(connect_pads
				(clearance 0)
			)
			(min_thickness 0.25)
			(keepout
				(tracks not_allowed)
				(vias allowed)
				(pads allowed)
				(copperpour not_allowed)
				(footprints allowed)
			)
			(placement
				(enabled no)
				(sheetname "")
			)
			(fill
				(thermal_gap 0.5)
				(thermal_bridge_width 0.5)
				(island_removal_mode 0)
			)
			(polygon
				(pts
					(arc
						(start 346.52966 -46.898814)
						(mid 346.493289 -46.840951)
						(end 346.435426 -46.80458)
					)
					(arc
						(start 346.435426 -46.699424)
						(mid 346.565147 -46.769093)
						(end 346.634816 -46.898814)
					)
				)
			)
		)
		(zone
			(layer "F.Cu")
			(hatch none 0.5)
			(connect_pads
				(clearance 0)
			)
			(min_thickness 0.25)
			(keepout
				(tracks not_allowed)
				(vias allowed)
				(pads allowed)
				(copperpour not_allowed)
				(footprints allowed)
			)
			(placement
				(enabled no)
				(sheetname "")
			)
			(fill
				(thermal_gap 0.5)
				(thermal_bridge_width 0.5)
				(island_removal_mode 0)
			)
			(polygon
				(pts
					(arc
						(start 346.52966 -45.898308)
						(mid 346.493289 -45.840445)
						(end 346.435426 -45.804074)
					)
					(arc
						(start 346.435426 -45.698918)
						(mid 346.565147 -45.768587)
						(end 346.634816 -45.898308)
					)
				)
			)
		)
		(zone
			(layer "F.Cu")
			(hatch none 0.5)
			(connect_pads
				(clearance 0)
			)
			(min_thickness 0.25)
			(keepout
				(tracks not_allowed)
				(vias allowed)
				(pads allowed)
				(copperpour not_allowed)
				(footprints allowed)
			)
			(placement
				(enabled no)
				(sheetname "")
			)
			(fill
				(thermal_gap 0.5)
				(thermal_bridge_width 0.5)
				(island_removal_mode 0)
			)
			(polygon
				(pts
					(arc
						(start 346.52966 -44.897802)
						(mid 346.493289 -44.839939)
						(end 346.435426 -44.803568)
					)
					(arc
						(start 346.435426 -44.698412)
						(mid 346.565147 -44.768081)
						(end 346.634816 -44.897802)
					)
				)
			)
		)
		(zone
			(layer "F.Cu")
			(hatch none 0.5)
			(connect_pads
				(clearance 0)
			)
			(min_thickness 0.25)
			(keepout
				(tracks not_allowed)
				(vias allowed)
				(pads allowed)
				(copperpour not_allowed)
				(footprints allowed)
			)
			(placement
				(enabled no)
				(sheetname "")
			)
			(fill
				(thermal_gap 0.5)
				(thermal_bridge_width 0.5)
				(island_removal_mode 0)
			)
			(polygon
				(pts
					(arc
						(start 346.52966 -43.897296)
						(mid 346.493289 -43.839433)
						(end 346.435426 -43.803062)
					)
					(arc
						(start 346.435426 -43.697906)
						(mid 346.565147 -43.767575)
						(end 346.634816 -43.897296)
					)
				)
			)
		)
		(zone
			(layer "F.Cu")
			(hatch none 0.5)
			(connect_pads
				(clearance 0)
			)
			(min_thickness 0.25)
			(keepout
				(tracks not_allowed)
				(vias allowed)
				(pads allowed)
				(copperpour not_allowed)
				(footprints allowed)
			)
			(placement
				(enabled no)
				(sheetname "")
			)
			(fill
				(thermal_gap 0.5)
				(thermal_bridge_width 0.5)
				(island_removal_mode 0)
			)
			(polygon
				(pts
					(arc
						(start 346.52966 -42.89679)
						(mid 346.493289 -42.838927)
						(end 346.435426 -42.802556)
					)
					(arc
						(start 346.435426 -42.6974)
						(mid 346.565147 -42.767069)
						(end 346.634816 -42.89679)
					)
				)
			)
		)
		(zone
			(layer "F.Cu")
			(hatch none 0.5)
			(connect_pads
				(clearance 0)
			)
			(min_thickness 0.25)
			(keepout
				(tracks not_allowed)
				(vias allowed)
				(pads allowed)
				(copperpour not_allowed)
				(footprints allowed)
			)
			(placement
				(enabled no)
				(sheetname "")
			)
			(fill
				(thermal_gap 0.5)
				(thermal_bridge_width 0.5)
				(island_removal_mode 0)
			)
			(polygon
				(pts
					(arc
						(start 346.52966 -41.896284)
						(mid 346.493289 -41.838421)
						(end 346.435426 -41.80205)
					)
					(arc
						(start 346.435426 -41.696894)
						(mid 346.565147 -41.766563)
						(end 346.634816 -41.896284)
					)
				)
			)
		)
		(zone
			(layer "F.Cu")
			(hatch none 0.5)
			(connect_pads
				(clearance 0)
			)
			(min_thickness 0.25)
			(keepout
				(tracks not_allowed)
				(vias allowed)
				(pads allowed)
				(copperpour not_allowed)
				(footprints allowed)
			)
			(placement
				(enabled no)
				(sheetname "")
			)
			(fill
				(thermal_gap 0.5)
				(thermal_bridge_width 0.5)
				(island_removal_mode 0)
			)
			(polygon
				(pts
					(arc
						(start 346.52966 -40.895778)
						(mid 346.493289 -40.837915)
						(end 346.435426 -40.801544)
					)
					(arc
						(start 346.435426 -40.696388)
						(mid 346.565147 -40.766057)
						(end 346.634816 -40.895778)
					)
				)
			)
		)
		(zone
			(layer "F.Cu")
			(hatch none 0.5)
			(connect_pads
				(clearance 0)
			)
			(min_thickness 0.25)
			(keepout
				(tracks not_allowed)
				(vias allowed)
				(pads allowed)
				(copperpour not_allowed)
				(footprints allowed)
			)
			(placement
				(enabled no)
				(sheetname "")
			)
			(fill
				(thermal_gap 0.5)
				(thermal_bridge_width 0.5)
				(island_removal_mode 0)
			)
			(polygon
				(pts
					(arc
						(start 346.52966 -39.895272)
						(mid 346.493289 -39.837409)
						(end 346.435426 -39.801038)
					)
					(arc
						(start 346.435426 -39.695882)
						(mid 346.565147 -39.765551)
						(end 346.634816 -39.895272)
					)
				)
			)
		)
		(zone
			(layer "F.Cu")
			(hatch none 0.5)
			(connect_pads
				(clearance 0)
			)
			(min_thickness 0.25)
			(keepout
				(tracks not_allowed)
				(vias allowed)
				(pads allowed)
				(copperpour not_allowed)
				(footprints allowed)
			)
			(placement
				(enabled no)
				(sheetname "")
			)
			(fill
				(thermal_gap 0.5)
				(thermal_bridge_width 0.5)
				(island_removal_mode 0)
			)
			(polygon
				(pts
					(arc
						(start 346.52966 -38.894766)
						(mid 346.493289 -38.836903)
						(end 346.435426 -38.800532)
					)
					(arc
						(start 346.435426 -38.695376)
						(mid 346.565147 -38.765045)
						(end 346.634816 -38.894766)
					)
				)
			)
		)
		(zone
			(layer "F.Cu")
			(hatch none 0.5)
			(connect_pads
				(clearance 0)
			)
			(min_thickness 0.25)
			(keepout
				(tracks not_allowed)
				(vias allowed)
				(pads allowed)
				(copperpour not_allowed)
				(footprints allowed)
			)
			(placement
				(enabled no)
				(sheetname "")
			)
			(fill
				(thermal_gap 0.5)
				(thermal_bridge_width 0.5)
				(island_removal_mode 0)
			)
			(polygon
				(pts
					(arc
						(start 346.610178 -58.755026)
						(mid 346.668041 -58.718655)
						(end 346.704412 -58.660792)
					)
					(arc
						(start 346.809568 -58.660792)
						(mid 346.739899 -58.790513)
						(end 346.610178 -58.860182)
					)
				)
			)
		)
		(zone
			(layer "F.Cu")
			(hatch none 0.5)
			(connect_pads
				(clearance 0)
			)
			(min_thickness 0.25)
			(keepout
				(tracks not_allowed)
				(vias allowed)
				(pads allowed)
				(copperpour not_allowed)
				(footprints allowed)
			)
			(placement
				(enabled no)
				(sheetname "")
			)
			(fill
				(thermal_gap 0.5)
				(thermal_bridge_width 0.5)
				(island_removal_mode 0)
			)
			(polygon
				(pts
					(arc
						(start 346.610178 -38.435534)
						(mid 346.668041 -38.399163)
						(end 346.704412 -38.3413)
					)
					(arc
						(start 346.809568 -38.3413)
						(mid 346.739899 -38.471021)
						(end 346.610178 -38.54069)
					)
				)
			)
		)
		(zone
			(layer "F.Cu")
			(hatch none 0.5)
			(connect_pads
				(clearance 0)
			)
			(min_thickness 0.25)
			(keepout
				(tracks not_allowed)
				(vias allowed)
				(pads allowed)
				(copperpour not_allowed)
				(footprints allowed)
			)
			(placement
				(enabled no)
				(sheetname "")
			)
			(fill
				(thermal_gap 0.5)
				(thermal_bridge_width 0.5)
				(island_removal_mode 0)
			)
			(polygon
				(pts
					(arc
						(start 346.654628 -57.505346)
						(mid 346.690999 -57.563209)
						(end 346.748862 -57.59958)
					)
					(arc
						(start 346.748862 -57.704736)
						(mid 346.619141 -57.635067)
						(end 346.549472 -57.505346)
					)
				)
			)
		)
		(zone
			(layer "F.Cu")
			(hatch none 0.5)
			(connect_pads
				(clearance 0)
			)
			(min_thickness 0.25)
			(keepout
				(tracks not_allowed)
				(vias allowed)
				(pads allowed)
				(copperpour not_allowed)
				(footprints allowed)
			)
			(placement
				(enabled no)
				(sheetname "")
			)
			(fill
				(thermal_gap 0.5)
				(thermal_bridge_width 0.5)
				(island_removal_mode 0)
			)
			(polygon
				(pts
					(arc
						(start 346.654628 -56.50484)
						(mid 346.690999 -56.562703)
						(end 346.748862 -56.599074)
					)
					(arc
						(start 346.748862 -56.70423)
						(mid 346.619141 -56.634561)
						(end 346.549472 -56.50484)
					)
				)
			)
		)
		(zone
			(layer "F.Cu")
			(hatch none 0.5)
			(connect_pads
				(clearance 0)
			)
			(min_thickness 0.25)
			(keepout
				(tracks not_allowed)
				(vias allowed)
				(pads allowed)
				(copperpour not_allowed)
				(footprints allowed)
			)
			(placement
				(enabled no)
				(sheetname "")
			)
			(fill
				(thermal_gap 0.5)
				(thermal_bridge_width 0.5)
				(island_removal_mode 0)
			)
			(polygon
				(pts
					(arc
						(start 346.654628 -55.504588)
						(mid 346.690999 -55.562451)
						(end 346.748862 -55.598822)
					)
					(arc
						(start 346.748862 -55.703978)
						(mid 346.619141 -55.634309)
						(end 346.549472 -55.504588)
					)
				)
			)
		)
		(zone
			(layer "F.Cu")
			(hatch none 0.5)
			(connect_pads
				(clearance 0)
			)
			(min_thickness 0.25)
			(keepout
				(tracks not_allowed)
				(vias allowed)
				(pads allowed)
				(copperpour not_allowed)
				(footprints allowed)
			)
			(placement
				(enabled no)
				(sheetname "")
			)
			(fill
				(thermal_gap 0.5)
				(thermal_bridge_width 0.5)
				(island_removal_mode 0)
			)
			(polygon
				(pts
					(arc
						(start 346.654628 -54.504082)
						(mid 346.690999 -54.561945)
						(end 346.748862 -54.598316)
					)
					(arc
						(start 346.748862 -54.703472)
						(mid 346.619141 -54.633803)
						(end 346.549472 -54.504082)
					)
				)
			)
		)
		(zone
			(layer "F.Cu")
			(hatch none 0.5)
			(connect_pads
				(clearance 0)
			)
			(min_thickness 0.25)
			(keepout
				(tracks not_allowed)
				(vias allowed)
				(pads allowed)
				(copperpour not_allowed)
				(footprints allowed)
			)
			(placement
				(enabled no)
				(sheetname "")
			)
			(fill
				(thermal_gap 0.5)
				(thermal_bridge_width 0.5)
				(island_removal_mode 0)
			)
			(polygon
				(pts
					(arc
						(start 346.654628 -53.503576)
						(mid 346.690999 -53.561439)
						(end 346.748862 -53.59781)
					)
					(arc
						(start 346.748862 -53.702966)
						(mid 346.619141 -53.633297)
						(end 346.549472 -53.503576)
					)
				)
			)
		)
		(zone
			(layer "F.Cu")
			(hatch none 0.5)
			(connect_pads
				(clearance 0)
			)
			(min_thickness 0.25)
			(keepout
				(tracks not_allowed)
				(vias allowed)
				(pads allowed)
				(copperpour not_allowed)
				(footprints allowed)
			)
			(placement
				(enabled no)
				(sheetname "")
			)
			(fill
				(thermal_gap 0.5)
				(thermal_bridge_width 0.5)
				(island_removal_mode 0)
			)
			(polygon
				(pts
					(arc
						(start 346.654628 -52.50307)
						(mid 346.690999 -52.560933)
						(end 346.748862 -52.597304)
					)
					(arc
						(start 346.748862 -52.70246)
						(mid 346.619141 -52.632791)
						(end 346.549472 -52.50307)
					)
				)
			)
		)
		(zone
			(layer "F.Cu")
			(hatch none 0.5)
			(connect_pads
				(clearance 0)
			)
			(min_thickness 0.25)
			(keepout
				(tracks not_allowed)
				(vias allowed)
				(pads allowed)
				(copperpour not_allowed)
				(footprints allowed)
			)
			(placement
				(enabled no)
				(sheetname "")
			)
			(fill
				(thermal_gap 0.5)
				(thermal_bridge_width 0.5)
				(island_removal_mode 0)
			)
			(polygon
				(pts
					(arc
						(start 346.654628 -51.502564)
						(mid 346.690999 -51.560427)
						(end 346.748862 -51.596798)
					)
					(arc
						(start 346.748862 -51.701954)
						(mid 346.619141 -51.632285)
						(end 346.549472 -51.502564)
					)
				)
			)
		)
		(zone
			(layer "F.Cu")
			(hatch none 0.5)
			(connect_pads
				(clearance 0)
			)
			(min_thickness 0.25)
			(keepout
				(tracks not_allowed)
				(vias allowed)
				(pads allowed)
				(copperpour not_allowed)
				(footprints allowed)
			)
			(placement
				(enabled no)
				(sheetname "")
			)
			(fill
				(thermal_gap 0.5)
				(thermal_bridge_width 0.5)
				(island_removal_mode 0)
			)
			(polygon
				(pts
					(arc
						(start 346.654628 -50.502058)
						(mid 346.690999 -50.559921)
						(end 346.748862 -50.596292)
					)
					(arc
						(start 346.748862 -50.701448)
						(mid 346.619141 -50.631779)
						(end 346.549472 -50.502058)
					)
				)
			)
		)
		(zone
			(layer "F.Cu")
			(hatch none 0.5)
			(connect_pads
				(clearance 0)
			)
			(min_thickness 0.25)
			(keepout
				(tracks not_allowed)
				(vias allowed)
				(pads allowed)
				(copperpour not_allowed)
				(footprints allowed)
			)
			(placement
				(enabled no)
				(sheetname "")
			)
			(fill
				(thermal_gap 0.5)
				(thermal_bridge_width 0.5)
				(island_removal_mode 0)
			)
			(polygon
				(pts
					(arc
						(start 346.654628 -49.501552)
						(mid 346.690999 -49.559415)
						(end 346.748862 -49.595786)
					)
					(arc
						(start 346.748862 -49.700942)
						(mid 346.619141 -49.631273)
						(end 346.549472 -49.501552)
					)
				)
			)
		)
		(zone
			(layer "F.Cu")
			(hatch none 0.5)
			(connect_pads
				(clearance 0)
			)
			(min_thickness 0.25)
			(keepout
				(tracks not_allowed)
				(vias allowed)
				(pads allowed)
				(copperpour not_allowed)
				(footprints allowed)
			)
			(placement
				(enabled no)
				(sheetname "")
			)
			(fill
				(thermal_gap 0.5)
				(thermal_bridge_width 0.5)
				(island_removal_mode 0)
			)
			(polygon
				(pts
					(arc
						(start 346.654628 -48.501046)
						(mid 346.690999 -48.558909)
						(end 346.748862 -48.59528)
					)
					(arc
						(start 346.748862 -48.700436)
						(mid 346.619141 -48.630767)
						(end 346.549472 -48.501046)
					)
				)
			)
		)
		(zone
			(layer "F.Cu")
			(hatch none 0.5)
			(connect_pads
				(clearance 0)
			)
			(min_thickness 0.25)
			(keepout
				(tracks not_allowed)
				(vias allowed)
				(pads allowed)
				(copperpour not_allowed)
				(footprints allowed)
			)
			(placement
				(enabled no)
				(sheetname "")
			)
			(fill
				(thermal_gap 0.5)
				(thermal_bridge_width 0.5)
				(island_removal_mode 0)
			)
			(polygon
				(pts
					(arc
						(start 346.654628 -47.50054)
						(mid 346.690999 -47.558403)
						(end 346.748862 -47.594774)
					)
					(arc
						(start 346.748862 -47.69993)
						(mid 346.619141 -47.630261)
						(end 346.549472 -47.50054)
					)
				)
			)
		)
		(zone
			(layer "F.Cu")
			(hatch none 0.5)
			(connect_pads
				(clearance 0)
			)
			(min_thickness 0.25)
			(keepout
				(tracks not_allowed)
				(vias allowed)
				(pads allowed)
				(copperpour not_allowed)
				(footprints allowed)
			)
			(placement
				(enabled no)
				(sheetname "")
			)
			(fill
				(thermal_gap 0.5)
				(thermal_bridge_width 0.5)
				(island_removal_mode 0)
			)
			(polygon
				(pts
					(arc
						(start 346.654628 -46.500034)
						(mid 346.690999 -46.557897)
						(end 346.748862 -46.594268)
					)
					(arc
						(start 346.748862 -46.699424)
						(mid 346.619141 -46.629755)
						(end 346.549472 -46.500034)
					)
				)
			)
		)
		(zone
			(layer "F.Cu")
			(hatch none 0.5)
			(connect_pads
				(clearance 0)
			)
			(min_thickness 0.25)
			(keepout
				(tracks not_allowed)
				(vias allowed)
				(pads allowed)
				(copperpour not_allowed)
				(footprints allowed)
			)
			(placement
				(enabled no)
				(sheetname "")
			)
			(fill
				(thermal_gap 0.5)
				(thermal_bridge_width 0.5)
				(island_removal_mode 0)
			)
			(polygon
				(pts
					(arc
						(start 346.654628 -45.499528)
						(mid 346.690999 -45.557391)
						(end 346.748862 -45.593762)
					)
					(arc
						(start 346.748862 -45.699172)
						(mid 346.619053 -45.629415)
						(end 346.549472 -45.499528)
					)
				)
			)
		)
		(zone
			(layer "F.Cu")
			(hatch none 0.5)
			(connect_pads
				(clearance 0)
			)
			(min_thickness 0.25)
			(keepout
				(tracks not_allowed)
				(vias allowed)
				(pads allowed)
				(copperpour not_allowed)
				(footprints allowed)
			)
			(placement
				(enabled no)
				(sheetname "")
			)
			(fill
				(thermal_gap 0.5)
				(thermal_bridge_width 0.5)
				(island_removal_mode 0)
			)
			(polygon
				(pts
					(arc
						(start 346.654628 -44.499022)
						(mid 346.690999 -44.556885)
						(end 346.748862 -44.593256)
					)
					(arc
						(start 346.748862 -44.698666)
						(mid 346.619053 -44.628909)
						(end 346.549472 -44.499022)
					)
				)
			)
		)
		(zone
			(layer "F.Cu")
			(hatch none 0.5)
			(connect_pads
				(clearance 0)
			)
			(min_thickness 0.25)
			(keepout
				(tracks not_allowed)
				(vias allowed)
				(pads allowed)
				(copperpour not_allowed)
				(footprints allowed)
			)
			(placement
				(enabled no)
				(sheetname "")
			)
			(fill
				(thermal_gap 0.5)
				(thermal_bridge_width 0.5)
				(island_removal_mode 0)
			)
			(polygon
				(pts
					(arc
						(start 346.654628 -43.49877)
						(mid 346.691054 -43.556469)
						(end 346.748862 -43.59275)
					)
					(arc
						(start 346.748862 -43.69816)
						(mid 346.619141 -43.628491)
						(end 346.549472 -43.49877)
					)
				)
			)
		)
		(zone
			(layer "F.Cu")
			(hatch none 0.5)
			(connect_pads
				(clearance 0)
			)
			(min_thickness 0.25)
			(keepout
				(tracks not_allowed)
				(vias allowed)
				(pads allowed)
				(copperpour not_allowed)
				(footprints allowed)
			)
			(placement
				(enabled no)
				(sheetname "")
			)
			(fill
				(thermal_gap 0.5)
				(thermal_bridge_width 0.5)
				(island_removal_mode 0)
			)
			(polygon
				(pts
					(arc
						(start 346.654628 -42.498264)
						(mid 346.691054 -42.555963)
						(end 346.748862 -42.592244)
					)
					(arc
						(start 346.748862 -42.697654)
						(mid 346.619141 -42.627985)
						(end 346.549472 -42.498264)
					)
				)
			)
		)
		(zone
			(layer "F.Cu")
			(hatch none 0.5)
			(connect_pads
				(clearance 0)
			)
			(min_thickness 0.25)
			(keepout
				(tracks not_allowed)
				(vias allowed)
				(pads allowed)
				(copperpour not_allowed)
				(footprints allowed)
			)
			(placement
				(enabled no)
				(sheetname "")
			)
			(fill
				(thermal_gap 0.5)
				(thermal_bridge_width 0.5)
				(island_removal_mode 0)
			)
			(polygon
				(pts
					(arc
						(start 346.654628 -41.497758)
						(mid 346.691054 -41.555457)
						(end 346.748862 -41.591738)
					)
					(arc
						(start 346.748862 -41.697148)
						(mid 346.619141 -41.627479)
						(end 346.549472 -41.497758)
					)
				)
			)
		)
		(zone
			(layer "F.Cu")
			(hatch none 0.5)
			(connect_pads
				(clearance 0)
			)
			(min_thickness 0.25)
			(keepout
				(tracks not_allowed)
				(vias allowed)
				(pads allowed)
				(copperpour not_allowed)
				(footprints allowed)
			)
			(placement
				(enabled no)
				(sheetname "")
			)
			(fill
				(thermal_gap 0.5)
				(thermal_bridge_width 0.5)
				(island_removal_mode 0)
			)
			(polygon
				(pts
					(arc
						(start 346.654628 -40.497252)
						(mid 346.691054 -40.554951)
						(end 346.748862 -40.591232)
					)
					(arc
						(start 346.748862 -40.696642)
						(mid 346.619141 -40.626973)
						(end 346.549472 -40.497252)
					)
				)
			)
		)
		(zone
			(layer "F.Cu")
			(hatch none 0.5)
			(connect_pads
				(clearance 0)
			)
			(min_thickness 0.25)
			(keepout
				(tracks not_allowed)
				(vias allowed)
				(pads allowed)
				(copperpour not_allowed)
				(footprints allowed)
			)
			(placement
				(enabled no)
				(sheetname "")
			)
			(fill
				(thermal_gap 0.5)
				(thermal_bridge_width 0.5)
				(island_removal_mode 0)
			)
			(polygon
				(pts
					(arc
						(start 346.654628 -39.496746)
						(mid 346.691054 -39.554445)
						(end 346.748862 -39.590726)
					)
					(arc
						(start 346.748862 -39.696136)
						(mid 346.619141 -39.626467)
						(end 346.549472 -39.496746)
					)
				)
			)
		)
		(zone
			(layer "F.Cu")
			(hatch none 0.5)
			(connect_pads
				(clearance 0)
			)
			(min_thickness 0.25)
			(keepout
				(tracks not_allowed)
				(vias allowed)
				(pads allowed)
				(copperpour not_allowed)
				(footprints allowed)
			)
			(placement
				(enabled no)
				(sheetname "")
			)
			(fill
				(thermal_gap 0.5)
				(thermal_bridge_width 0.5)
				(island_removal_mode 0)
			)
			(polygon
				(pts
					(arc
						(start 346.704412 -58.559192)
						(mid 346.668041 -58.501329)
						(end 346.610178 -58.464958)
					)
					(arc
						(start 346.610178 -58.359802)
						(mid 346.739899 -58.429471)
						(end 346.809568 -58.559192)
					)
				)
			)
		)
		(zone
			(layer "F.Cu")
			(hatch none 0.5)
			(connect_pads
				(clearance 0)
			)
			(min_thickness 0.25)
			(keepout
				(tracks not_allowed)
				(vias allowed)
				(pads allowed)
				(copperpour not_allowed)
				(footprints allowed)
			)
			(placement
				(enabled no)
				(sheetname "")
			)
			(fill
				(thermal_gap 0.5)
				(thermal_bridge_width 0.5)
				(island_removal_mode 0)
			)
			(polygon
				(pts
					(arc
						(start 346.704412 -38.2397)
						(mid 346.668041 -38.181837)
						(end 346.610178 -38.145466)
					)
					(arc
						(start 346.610178 -38.04031)
						(mid 346.739899 -38.109979)
						(end 346.809568 -38.2397)
					)
				)
			)
		)
		(zone
			(layer "F.Cu")
			(hatch none 0.5)
			(connect_pads
				(clearance 0)
			)
			(min_thickness 0.25)
			(keepout
				(tracks not_allowed)
				(vias allowed)
				(pads allowed)
				(copperpour not_allowed)
				(footprints allowed)
			)
			(placement
				(enabled no)
				(sheetname "")
			)
			(fill
				(thermal_gap 0.5)
				(thermal_bridge_width 0.5)
				(island_removal_mode 0)
			)
			(polygon
				(pts
					(arc
						(start 346.748862 -57.309766)
						(mid 346.691003 -57.345997)
						(end 346.654628 -57.403746)
					)
					(arc
						(start 346.549472 -57.403746)
						(mid 346.619141 -57.274025)
						(end 346.748862 -57.204356)
					)
				)
			)
		)
		(zone
			(layer "F.Cu")
			(hatch none 0.5)
			(connect_pads
				(clearance 0)
			)
			(min_thickness 0.25)
			(keepout
				(tracks not_allowed)
				(vias allowed)
				(pads allowed)
				(copperpour not_allowed)
				(footprints allowed)
			)
			(placement
				(enabled no)
				(sheetname "")
			)
			(fill
				(thermal_gap 0.5)
				(thermal_bridge_width 0.5)
				(island_removal_mode 0)
			)
			(polygon
				(pts
					(arc
						(start 346.748862 -56.30926)
						(mid 346.691003 -56.345491)
						(end 346.654628 -56.40324)
					)
					(arc
						(start 346.549472 -56.40324)
						(mid 346.619141 -56.273519)
						(end 346.748862 -56.20385)
					)
				)
			)
		)
		(zone
			(layer "F.Cu")
			(hatch none 0.5)
			(connect_pads
				(clearance 0)
			)
			(min_thickness 0.25)
			(keepout
				(tracks not_allowed)
				(vias allowed)
				(pads allowed)
				(copperpour not_allowed)
				(footprints allowed)
			)
			(placement
				(enabled no)
				(sheetname "")
			)
			(fill
				(thermal_gap 0.5)
				(thermal_bridge_width 0.5)
				(island_removal_mode 0)
			)
			(polygon
				(pts
					(arc
						(start 346.748862 -55.308754)
						(mid 346.690999 -55.345125)
						(end 346.654628 -55.402988)
					)
					(arc
						(start 346.549472 -55.402988)
						(mid 346.619141 -55.273267)
						(end 346.748862 -55.203598)
					)
				)
			)
		)
		(zone
			(layer "F.Cu")
			(hatch none 0.5)
			(connect_pads
				(clearance 0)
			)
			(min_thickness 0.25)
			(keepout
				(tracks not_allowed)
				(vias allowed)
				(pads allowed)
				(copperpour not_allowed)
				(footprints allowed)
			)
			(placement
				(enabled no)
				(sheetname "")
			)
			(fill
				(thermal_gap 0.5)
				(thermal_bridge_width 0.5)
				(island_removal_mode 0)
			)
			(polygon
				(pts
					(arc
						(start 346.748862 -54.308248)
						(mid 346.690999 -54.344619)
						(end 346.654628 -54.402482)
					)
					(arc
						(start 346.549472 -54.402482)
						(mid 346.619141 -54.272761)
						(end 346.748862 -54.203092)
					)
				)
			)
		)
		(zone
			(layer "F.Cu")
			(hatch none 0.5)
			(connect_pads
				(clearance 0)
			)
			(min_thickness 0.25)
			(keepout
				(tracks not_allowed)
				(vias allowed)
				(pads allowed)
				(copperpour not_allowed)
				(footprints allowed)
			)
			(placement
				(enabled no)
				(sheetname "")
			)
			(fill
				(thermal_gap 0.5)
				(thermal_bridge_width 0.5)
				(island_removal_mode 0)
			)
			(polygon
				(pts
					(arc
						(start 346.748862 -53.307742)
						(mid 346.690999 -53.344113)
						(end 346.654628 -53.401976)
					)
					(arc
						(start 346.549472 -53.401976)
						(mid 346.619141 -53.272255)
						(end 346.748862 -53.202586)
					)
				)
			)
		)
		(zone
			(layer "F.Cu")
			(hatch none 0.5)
			(connect_pads
				(clearance 0)
			)
			(min_thickness 0.25)
			(keepout
				(tracks not_allowed)
				(vias allowed)
				(pads allowed)
				(copperpour not_allowed)
				(footprints allowed)
			)
			(placement
				(enabled no)
				(sheetname "")
			)
			(fill
				(thermal_gap 0.5)
				(thermal_bridge_width 0.5)
				(island_removal_mode 0)
			)
			(polygon
				(pts
					(arc
						(start 346.748862 -52.307236)
						(mid 346.690999 -52.343607)
						(end 346.654628 -52.40147)
					)
					(arc
						(start 346.549472 -52.40147)
						(mid 346.619141 -52.271749)
						(end 346.748862 -52.20208)
					)
				)
			)
		)
		(zone
			(layer "F.Cu")
			(hatch none 0.5)
			(connect_pads
				(clearance 0)
			)
			(min_thickness 0.25)
			(keepout
				(tracks not_allowed)
				(vias allowed)
				(pads allowed)
				(copperpour not_allowed)
				(footprints allowed)
			)
			(placement
				(enabled no)
				(sheetname "")
			)
			(fill
				(thermal_gap 0.5)
				(thermal_bridge_width 0.5)
				(island_removal_mode 0)
			)
			(polygon
				(pts
					(arc
						(start 346.748862 -51.30673)
						(mid 346.690999 -51.343101)
						(end 346.654628 -51.400964)
					)
					(arc
						(start 346.549472 -51.400964)
						(mid 346.619141 -51.271243)
						(end 346.748862 -51.201574)
					)
				)
			)
		)
		(zone
			(layer "F.Cu")
			(hatch none 0.5)
			(connect_pads
				(clearance 0)
			)
			(min_thickness 0.25)
			(keepout
				(tracks not_allowed)
				(vias allowed)
				(pads allowed)
				(copperpour not_allowed)
				(footprints allowed)
			)
			(placement
				(enabled no)
				(sheetname "")
			)
			(fill
				(thermal_gap 0.5)
				(thermal_bridge_width 0.5)
				(island_removal_mode 0)
			)
			(polygon
				(pts
					(arc
						(start 346.748862 -50.306224)
						(mid 346.690999 -50.342595)
						(end 346.654628 -50.400458)
					)
					(arc
						(start 346.549472 -50.400458)
						(mid 346.619141 -50.270737)
						(end 346.748862 -50.201068)
					)
				)
			)
		)
		(zone
			(layer "F.Cu")
			(hatch none 0.5)
			(connect_pads
				(clearance 0)
			)
			(min_thickness 0.25)
			(keepout
				(tracks not_allowed)
				(vias allowed)
				(pads allowed)
				(copperpour not_allowed)
				(footprints allowed)
			)
			(placement
				(enabled no)
				(sheetname "")
			)
			(fill
				(thermal_gap 0.5)
				(thermal_bridge_width 0.5)
				(island_removal_mode 0)
			)
			(polygon
				(pts
					(arc
						(start 346.748862 -49.305718)
						(mid 346.690999 -49.342089)
						(end 346.654628 -49.399952)
					)
					(arc
						(start 346.549472 -49.399952)
						(mid 346.619141 -49.270231)
						(end 346.748862 -49.200562)
					)
				)
			)
		)
		(zone
			(layer "F.Cu")
			(hatch none 0.5)
			(connect_pads
				(clearance 0)
			)
			(min_thickness 0.25)
			(keepout
				(tracks not_allowed)
				(vias allowed)
				(pads allowed)
				(copperpour not_allowed)
				(footprints allowed)
			)
			(placement
				(enabled no)
				(sheetname "")
			)
			(fill
				(thermal_gap 0.5)
				(thermal_bridge_width 0.5)
				(island_removal_mode 0)
			)
			(polygon
				(pts
					(arc
						(start 346.748862 -48.305212)
						(mid 346.690999 -48.341583)
						(end 346.654628 -48.399446)
					)
					(arc
						(start 346.549472 -48.399446)
						(mid 346.619141 -48.269725)
						(end 346.748862 -48.200056)
					)
				)
			)
		)
		(zone
			(layer "F.Cu")
			(hatch none 0.5)
			(connect_pads
				(clearance 0)
			)
			(min_thickness 0.25)
			(keepout
				(tracks not_allowed)
				(vias allowed)
				(pads allowed)
				(copperpour not_allowed)
				(footprints allowed)
			)
			(placement
				(enabled no)
				(sheetname "")
			)
			(fill
				(thermal_gap 0.5)
				(thermal_bridge_width 0.5)
				(island_removal_mode 0)
			)
			(polygon
				(pts
					(arc
						(start 346.748862 -47.304706)
						(mid 346.690999 -47.341077)
						(end 346.654628 -47.39894)
					)
					(arc
						(start 346.549472 -47.39894)
						(mid 346.619141 -47.269219)
						(end 346.748862 -47.19955)
					)
				)
			)
		)
		(zone
			(layer "F.Cu")
			(hatch none 0.5)
			(connect_pads
				(clearance 0)
			)
			(min_thickness 0.25)
			(keepout
				(tracks not_allowed)
				(vias allowed)
				(pads allowed)
				(copperpour not_allowed)
				(footprints allowed)
			)
			(placement
				(enabled no)
				(sheetname "")
			)
			(fill
				(thermal_gap 0.5)
				(thermal_bridge_width 0.5)
				(island_removal_mode 0)
			)
			(polygon
				(pts
					(arc
						(start 346.748862 -46.304454)
						(mid 346.691003 -46.340685)
						(end 346.654628 -46.398434)
					)
					(arc
						(start 346.549472 -46.398434)
						(mid 346.619141 -46.268713)
						(end 346.748862 -46.199044)
					)
				)
			)
		)
		(zone
			(layer "F.Cu")
			(hatch none 0.5)
			(connect_pads
				(clearance 0)
			)
			(min_thickness 0.25)
			(keepout
				(tracks not_allowed)
				(vias allowed)
				(pads allowed)
				(copperpour not_allowed)
				(footprints allowed)
			)
			(placement
				(enabled no)
				(sheetname "")
			)
			(fill
				(thermal_gap 0.5)
				(thermal_bridge_width 0.5)
				(island_removal_mode 0)
			)
			(polygon
				(pts
					(arc
						(start 346.748862 -45.303948)
						(mid 346.691003 -45.340179)
						(end 346.654628 -45.397928)
					)
					(arc
						(start 346.549472 -45.397928)
						(mid 346.619141 -45.268207)
						(end 346.748862 -45.198538)
					)
				)
			)
		)
		(zone
			(layer "F.Cu")
			(hatch none 0.5)
			(connect_pads
				(clearance 0)
			)
			(min_thickness 0.25)
			(keepout
				(tracks not_allowed)
				(vias allowed)
				(pads allowed)
				(copperpour not_allowed)
				(footprints allowed)
			)
			(placement
				(enabled no)
				(sheetname "")
			)
			(fill
				(thermal_gap 0.5)
				(thermal_bridge_width 0.5)
				(island_removal_mode 0)
			)
			(polygon
				(pts
					(arc
						(start 346.748862 -44.303442)
						(mid 346.691003 -44.339673)
						(end 346.654628 -44.397422)
					)
					(arc
						(start 346.549472 -44.397422)
						(mid 346.619141 -44.267701)
						(end 346.748862 -44.198032)
					)
				)
			)
		)
		(zone
			(layer "F.Cu")
			(hatch none 0.5)
			(connect_pads
				(clearance 0)
			)
			(min_thickness 0.25)
			(keepout
				(tracks not_allowed)
				(vias allowed)
				(pads allowed)
				(copperpour not_allowed)
				(footprints allowed)
			)
			(placement
				(enabled no)
				(sheetname "")
			)
			(fill
				(thermal_gap 0.5)
				(thermal_bridge_width 0.5)
				(island_removal_mode 0)
			)
			(polygon
				(pts
					(arc
						(start 346.748862 -43.302936)
						(mid 346.690999 -43.339307)
						(end 346.654628 -43.39717)
					)
					(arc
						(start 346.549472 -43.39717)
						(mid 346.619089 -43.267319)
						(end 346.748862 -43.197526)
					)
				)
			)
		)
		(zone
			(layer "F.Cu")
			(hatch none 0.5)
			(connect_pads
				(clearance 0)
			)
			(min_thickness 0.25)
			(keepout
				(tracks not_allowed)
				(vias allowed)
				(pads allowed)
				(copperpour not_allowed)
				(footprints allowed)
			)
			(placement
				(enabled no)
				(sheetname "")
			)
			(fill
				(thermal_gap 0.5)
				(thermal_bridge_width 0.5)
				(island_removal_mode 0)
			)
			(polygon
				(pts
					(arc
						(start 346.748862 -42.30243)
						(mid 346.690999 -42.338801)
						(end 346.654628 -42.396664)
					)
					(arc
						(start 346.549472 -42.396664)
						(mid 346.619089 -42.266813)
						(end 346.748862 -42.19702)
					)
				)
			)
		)
		(zone
			(layer "F.Cu")
			(hatch none 0.5)
			(connect_pads
				(clearance 0)
			)
			(min_thickness 0.25)
			(keepout
				(tracks not_allowed)
				(vias allowed)
				(pads allowed)
				(copperpour not_allowed)
				(footprints allowed)
			)
			(placement
				(enabled no)
				(sheetname "")
			)
			(fill
				(thermal_gap 0.5)
				(thermal_bridge_width 0.5)
				(island_removal_mode 0)
			)
			(polygon
				(pts
					(arc
						(start 346.748862 -41.301924)
						(mid 346.690999 -41.338295)
						(end 346.654628 -41.396158)
					)
					(arc
						(start 346.549472 -41.396158)
						(mid 346.619141 -41.266437)
						(end 346.748862 -41.196768)
					)
				)
			)
		)
		(zone
			(layer "F.Cu")
			(hatch none 0.5)
			(connect_pads
				(clearance 0)
			)
			(min_thickness 0.25)
			(keepout
				(tracks not_allowed)
				(vias allowed)
				(pads allowed)
				(copperpour not_allowed)
				(footprints allowed)
			)
			(placement
				(enabled no)
				(sheetname "")
			)
			(fill
				(thermal_gap 0.5)
				(thermal_bridge_width 0.5)
				(island_removal_mode 0)
			)
			(polygon
				(pts
					(arc
						(start 346.748862 -40.301418)
						(mid 346.690999 -40.337789)
						(end 346.654628 -40.395652)
					)
					(arc
						(start 346.549472 -40.395652)
						(mid 346.619141 -40.265931)
						(end 346.748862 -40.196262)
					)
				)
			)
		)
		(zone
			(layer "F.Cu")
			(hatch none 0.5)
			(connect_pads
				(clearance 0)
			)
			(min_thickness 0.25)
			(keepout
				(tracks not_allowed)
				(vias allowed)
				(pads allowed)
				(copperpour not_allowed)
				(footprints allowed)
			)
			(placement
				(enabled no)
				(sheetname "")
			)
			(fill
				(thermal_gap 0.5)
				(thermal_bridge_width 0.5)
				(island_removal_mode 0)
			)
			(polygon
				(pts
					(arc
						(start 346.748862 -39.300912)
						(mid 346.690999 -39.337283)
						(end 346.654628 -39.395146)
					)
					(arc
						(start 346.549472 -39.395146)
						(mid 346.619141 -39.265425)
						(end 346.748862 -39.195756)
					)
				)
			)
		)
		(zone
			(layer "F.Cu")
			(hatch none 0.5)
			(connect_pads
				(clearance 0)
			)
			(min_thickness 0.25)
			(keepout
				(tracks not_allowed)
				(vias allowed)
				(pads allowed)
				(copperpour not_allowed)
				(footprints allowed)
			)
			(placement
				(enabled no)
				(sheetname "")
			)
			(fill
				(thermal_gap 0.5)
				(thermal_bridge_width 0.5)
				(island_removal_mode 0)
			)
			(polygon
				(pts
					(arc
						(start 346.850462 -57.59958)
						(mid 346.908325 -57.563209)
						(end 346.944696 -57.505346)
					)
					(arc
						(start 347.049852 -57.505346)
						(mid 346.980183 -57.635067)
						(end 346.850462 -57.704736)
					)
				)
			)
		)
		(zone
			(layer "F.Cu")
			(hatch none 0.5)
			(connect_pads
				(clearance 0)
			)
			(min_thickness 0.25)
			(keepout
				(tracks not_allowed)
				(vias allowed)
				(pads allowed)
				(copperpour not_allowed)
				(footprints allowed)
			)
			(placement
				(enabled no)
				(sheetname "")
			)
			(fill
				(thermal_gap 0.5)
				(thermal_bridge_width 0.5)
				(island_removal_mode 0)
			)
			(polygon
				(pts
					(arc
						(start 346.850462 -56.599074)
						(mid 346.908325 -56.562703)
						(end 346.944696 -56.50484)
					)
					(arc
						(start 347.049852 -56.50484)
						(mid 346.980183 -56.634561)
						(end 346.850462 -56.70423)
					)
				)
			)
		)
		(zone
			(layer "F.Cu")
			(hatch none 0.5)
			(connect_pads
				(clearance 0)
			)
			(min_thickness 0.25)
			(keepout
				(tracks not_allowed)
				(vias allowed)
				(pads allowed)
				(copperpour not_allowed)
				(footprints allowed)
			)
			(placement
				(enabled no)
				(sheetname "")
			)
			(fill
				(thermal_gap 0.5)
				(thermal_bridge_width 0.5)
				(island_removal_mode 0)
			)
			(polygon
				(pts
					(arc
						(start 346.850462 -55.598822)
						(mid 346.908325 -55.562451)
						(end 346.944696 -55.504588)
					)
					(arc
						(start 347.049852 -55.504588)
						(mid 346.980183 -55.634309)
						(end 346.850462 -55.703978)
					)
				)
			)
		)
		(zone
			(layer "F.Cu")
			(hatch none 0.5)
			(connect_pads
				(clearance 0)
			)
			(min_thickness 0.25)
			(keepout
				(tracks not_allowed)
				(vias allowed)
				(pads allowed)
				(copperpour not_allowed)
				(footprints allowed)
			)
			(placement
				(enabled no)
				(sheetname "")
			)
			(fill
				(thermal_gap 0.5)
				(thermal_bridge_width 0.5)
				(island_removal_mode 0)
			)
			(polygon
				(pts
					(arc
						(start 346.850462 -54.598316)
						(mid 346.908325 -54.561945)
						(end 346.944696 -54.504082)
					)
					(arc
						(start 347.049852 -54.504082)
						(mid 346.980183 -54.633803)
						(end 346.850462 -54.703472)
					)
				)
			)
		)
		(zone
			(layer "F.Cu")
			(hatch none 0.5)
			(connect_pads
				(clearance 0)
			)
			(min_thickness 0.25)
			(keepout
				(tracks not_allowed)
				(vias allowed)
				(pads allowed)
				(copperpour not_allowed)
				(footprints allowed)
			)
			(placement
				(enabled no)
				(sheetname "")
			)
			(fill
				(thermal_gap 0.5)
				(thermal_bridge_width 0.5)
				(island_removal_mode 0)
			)
			(polygon
				(pts
					(arc
						(start 346.850462 -53.59781)
						(mid 346.908325 -53.561439)
						(end 346.944696 -53.503576)
					)
					(arc
						(start 347.049852 -53.503576)
						(mid 346.980183 -53.633297)
						(end 346.850462 -53.702966)
					)
				)
			)
		)
		(zone
			(layer "F.Cu")
			(hatch none 0.5)
			(connect_pads
				(clearance 0)
			)
			(min_thickness 0.25)
			(keepout
				(tracks not_allowed)
				(vias allowed)
				(pads allowed)
				(copperpour not_allowed)
				(footprints allowed)
			)
			(placement
				(enabled no)
				(sheetname "")
			)
			(fill
				(thermal_gap 0.5)
				(thermal_bridge_width 0.5)
				(island_removal_mode 0)
			)
			(polygon
				(pts
					(arc
						(start 346.850462 -52.597304)
						(mid 346.908325 -52.560933)
						(end 346.944696 -52.50307)
					)
					(arc
						(start 347.049852 -52.50307)
						(mid 346.980183 -52.632791)
						(end 346.850462 -52.70246)
					)
				)
			)
		)
		(zone
			(layer "F.Cu")
			(hatch none 0.5)
			(connect_pads
				(clearance 0)
			)
			(min_thickness 0.25)
			(keepout
				(tracks not_allowed)
				(vias allowed)
				(pads allowed)
				(copperpour not_allowed)
				(footprints allowed)
			)
			(placement
				(enabled no)
				(sheetname "")
			)
			(fill
				(thermal_gap 0.5)
				(thermal_bridge_width 0.5)
				(island_removal_mode 0)
			)
			(polygon
				(pts
					(arc
						(start 346.850462 -51.596798)
						(mid 346.908325 -51.560427)
						(end 346.944696 -51.502564)
					)
					(arc
						(start 347.049852 -51.502564)
						(mid 346.980183 -51.632285)
						(end 346.850462 -51.701954)
					)
				)
			)
		)
		(zone
			(layer "F.Cu")
			(hatch none 0.5)
			(connect_pads
				(clearance 0)
			)
			(min_thickness 0.25)
			(keepout
				(tracks not_allowed)
				(vias allowed)
				(pads allowed)
				(copperpour not_allowed)
				(footprints allowed)
			)
			(placement
				(enabled no)
				(sheetname "")
			)
			(fill
				(thermal_gap 0.5)
				(thermal_bridge_width 0.5)
				(island_removal_mode 0)
			)
			(polygon
				(pts
					(arc
						(start 346.850462 -50.596292)
						(mid 346.908325 -50.559921)
						(end 346.944696 -50.502058)
					)
					(arc
						(start 347.049852 -50.502058)
						(mid 346.980183 -50.631779)
						(end 346.850462 -50.701448)
					)
				)
			)
		)
		(zone
			(layer "F.Cu")
			(hatch none 0.5)
			(connect_pads
				(clearance 0)
			)
			(min_thickness 0.25)
			(keepout
				(tracks not_allowed)
				(vias allowed)
				(pads allowed)
				(copperpour not_allowed)
				(footprints allowed)
			)
			(placement
				(enabled no)
				(sheetname "")
			)
			(fill
				(thermal_gap 0.5)
				(thermal_bridge_width 0.5)
				(island_removal_mode 0)
			)
			(polygon
				(pts
					(arc
						(start 346.850462 -49.595786)
						(mid 346.908325 -49.559415)
						(end 346.944696 -49.501552)
					)
					(arc
						(start 347.049852 -49.501552)
						(mid 346.980183 -49.631273)
						(end 346.850462 -49.700942)
					)
				)
			)
		)
		(zone
			(layer "F.Cu")
			(hatch none 0.5)
			(connect_pads
				(clearance 0)
			)
			(min_thickness 0.25)
			(keepout
				(tracks not_allowed)
				(vias allowed)
				(pads allowed)
				(copperpour not_allowed)
				(footprints allowed)
			)
			(placement
				(enabled no)
				(sheetname "")
			)
			(fill
				(thermal_gap 0.5)
				(thermal_bridge_width 0.5)
				(island_removal_mode 0)
			)
			(polygon
				(pts
					(arc
						(start 346.850462 -48.59528)
						(mid 346.908325 -48.558909)
						(end 346.944696 -48.501046)
					)
					(arc
						(start 347.049852 -48.501046)
						(mid 346.980183 -48.630767)
						(end 346.850462 -48.700436)
					)
				)
			)
		)
		(zone
			(layer "F.Cu")
			(hatch none 0.5)
			(connect_pads
				(clearance 0)
			)
			(min_thickness 0.25)
			(keepout
				(tracks not_allowed)
				(vias allowed)
				(pads allowed)
				(copperpour not_allowed)
				(footprints allowed)
			)
			(placement
				(enabled no)
				(sheetname "")
			)
			(fill
				(thermal_gap 0.5)
				(thermal_bridge_width 0.5)
				(island_removal_mode 0)
			)
			(polygon
				(pts
					(arc
						(start 346.850462 -47.594774)
						(mid 346.908325 -47.558403)
						(end 346.944696 -47.50054)
					)
					(arc
						(start 347.049852 -47.50054)
						(mid 346.980183 -47.630261)
						(end 346.850462 -47.69993)
					)
				)
			)
		)
		(zone
			(layer "F.Cu")
			(hatch none 0.5)
			(connect_pads
				(clearance 0)
			)
			(min_thickness 0.25)
			(keepout
				(tracks not_allowed)
				(vias allowed)
				(pads allowed)
				(copperpour not_allowed)
				(footprints allowed)
			)
			(placement
				(enabled no)
				(sheetname "")
			)
			(fill
				(thermal_gap 0.5)
				(thermal_bridge_width 0.5)
				(island_removal_mode 0)
			)
			(polygon
				(pts
					(arc
						(start 346.850462 -46.594268)
						(mid 346.908325 -46.557897)
						(end 346.944696 -46.500034)
					)
					(arc
						(start 347.049852 -46.500034)
						(mid 346.980183 -46.629755)
						(end 346.850462 -46.699424)
					)
				)
			)
		)
		(zone
			(layer "F.Cu")
			(hatch none 0.5)
			(connect_pads
				(clearance 0)
			)
			(min_thickness 0.25)
			(keepout
				(tracks not_allowed)
				(vias allowed)
				(pads allowed)
				(copperpour not_allowed)
				(footprints allowed)
			)
			(placement
				(enabled no)
				(sheetname "")
			)
			(fill
				(thermal_gap 0.5)
				(thermal_bridge_width 0.5)
				(island_removal_mode 0)
			)
			(polygon
				(pts
					(arc
						(start 346.850462 -45.593762)
						(mid 346.908325 -45.557391)
						(end 346.944696 -45.499528)
					)
					(arc
						(start 347.049852 -45.499528)
						(mid 346.980235 -45.629379)
						(end 346.850462 -45.699172)
					)
				)
			)
		)
		(zone
			(layer "F.Cu")
			(hatch none 0.5)
			(connect_pads
				(clearance 0)
			)
			(min_thickness 0.25)
			(keepout
				(tracks not_allowed)
				(vias allowed)
				(pads allowed)
				(copperpour not_allowed)
				(footprints allowed)
			)
			(placement
				(enabled no)
				(sheetname "")
			)
			(fill
				(thermal_gap 0.5)
				(thermal_bridge_width 0.5)
				(island_removal_mode 0)
			)
			(polygon
				(pts
					(arc
						(start 346.850462 -44.593256)
						(mid 346.908325 -44.556885)
						(end 346.944696 -44.499022)
					)
					(arc
						(start 347.049852 -44.499022)
						(mid 346.980235 -44.628873)
						(end 346.850462 -44.698666)
					)
				)
			)
		)
		(zone
			(layer "F.Cu")
			(hatch none 0.5)
			(connect_pads
				(clearance 0)
			)
			(min_thickness 0.25)
			(keepout
				(tracks not_allowed)
				(vias allowed)
				(pads allowed)
				(copperpour not_allowed)
				(footprints allowed)
			)
			(placement
				(enabled no)
				(sheetname "")
			)
			(fill
				(thermal_gap 0.5)
				(thermal_bridge_width 0.5)
				(island_removal_mode 0)
			)
			(polygon
				(pts
					(arc
						(start 346.850462 -43.59275)
						(mid 346.908321 -43.556519)
						(end 346.944696 -43.49877)
					)
					(arc
						(start 347.049852 -43.49877)
						(mid 346.980183 -43.628491)
						(end 346.850462 -43.69816)
					)
				)
			)
		)
		(zone
			(layer "F.Cu")
			(hatch none 0.5)
			(connect_pads
				(clearance 0)
			)
			(min_thickness 0.25)
			(keepout
				(tracks not_allowed)
				(vias allowed)
				(pads allowed)
				(copperpour not_allowed)
				(footprints allowed)
			)
			(placement
				(enabled no)
				(sheetname "")
			)
			(fill
				(thermal_gap 0.5)
				(thermal_bridge_width 0.5)
				(island_removal_mode 0)
			)
			(polygon
				(pts
					(arc
						(start 346.850462 -42.592244)
						(mid 346.908321 -42.556013)
						(end 346.944696 -42.498264)
					)
					(arc
						(start 347.049852 -42.498264)
						(mid 346.980183 -42.627985)
						(end 346.850462 -42.697654)
					)
				)
			)
		)
		(zone
			(layer "F.Cu")
			(hatch none 0.5)
			(connect_pads
				(clearance 0)
			)
			(min_thickness 0.25)
			(keepout
				(tracks not_allowed)
				(vias allowed)
				(pads allowed)
				(copperpour not_allowed)
				(footprints allowed)
			)
			(placement
				(enabled no)
				(sheetname "")
			)
			(fill
				(thermal_gap 0.5)
				(thermal_bridge_width 0.5)
				(island_removal_mode 0)
			)
			(polygon
				(pts
					(arc
						(start 346.850462 -41.591738)
						(mid 346.908321 -41.555507)
						(end 346.944696 -41.497758)
					)
					(arc
						(start 347.049852 -41.497758)
						(mid 346.980183 -41.627479)
						(end 346.850462 -41.697148)
					)
				)
			)
		)
		(zone
			(layer "F.Cu")
			(hatch none 0.5)
			(connect_pads
				(clearance 0)
			)
			(min_thickness 0.25)
			(keepout
				(tracks not_allowed)
				(vias allowed)
				(pads allowed)
				(copperpour not_allowed)
				(footprints allowed)
			)
			(placement
				(enabled no)
				(sheetname "")
			)
			(fill
				(thermal_gap 0.5)
				(thermal_bridge_width 0.5)
				(island_removal_mode 0)
			)
			(polygon
				(pts
					(arc
						(start 346.850462 -40.591232)
						(mid 346.908321 -40.555001)
						(end 346.944696 -40.497252)
					)
					(arc
						(start 347.049852 -40.497252)
						(mid 346.980183 -40.626973)
						(end 346.850462 -40.696642)
					)
				)
			)
		)
		(zone
			(layer "F.Cu")
			(hatch none 0.5)
			(connect_pads
				(clearance 0)
			)
			(min_thickness 0.25)
			(keepout
				(tracks not_allowed)
				(vias allowed)
				(pads allowed)
				(copperpour not_allowed)
				(footprints allowed)
			)
			(placement
				(enabled no)
				(sheetname "")
			)
			(fill
				(thermal_gap 0.5)
				(thermal_bridge_width 0.5)
				(island_removal_mode 0)
			)
			(polygon
				(pts
					(arc
						(start 346.850462 -39.590726)
						(mid 346.908321 -39.554495)
						(end 346.944696 -39.496746)
					)
					(arc
						(start 347.049852 -39.496746)
						(mid 346.980183 -39.626467)
						(end 346.850462 -39.696136)
					)
				)
			)
		)
		(zone
			(layer "F.Cu")
			(hatch none 0.5)
			(connect_pads
				(clearance 0)
			)
			(min_thickness 0.25)
			(keepout
				(tracks not_allowed)
				(vias allowed)
				(pads allowed)
				(copperpour not_allowed)
				(footprints allowed)
			)
			(placement
				(enabled no)
				(sheetname "")
			)
			(fill
				(thermal_gap 0.5)
				(thermal_bridge_width 0.5)
				(island_removal_mode 0)
			)
			(polygon
				(pts
					(arc
						(start 346.944696 -57.403746)
						(mid 346.90827 -57.346047)
						(end 346.850462 -57.309766)
					)
					(arc
						(start 346.850462 -57.204356)
						(mid 346.980183 -57.274025)
						(end 347.049852 -57.403746)
					)
				)
			)
		)
		(zone
			(layer "F.Cu")
			(hatch none 0.5)
			(connect_pads
				(clearance 0)
			)
			(min_thickness 0.25)
			(keepout
				(tracks not_allowed)
				(vias allowed)
				(pads allowed)
				(copperpour not_allowed)
				(footprints allowed)
			)
			(placement
				(enabled no)
				(sheetname "")
			)
			(fill
				(thermal_gap 0.5)
				(thermal_bridge_width 0.5)
				(island_removal_mode 0)
			)
			(polygon
				(pts
					(arc
						(start 346.944696 -56.40324)
						(mid 346.90827 -56.345541)
						(end 346.850462 -56.30926)
					)
					(arc
						(start 346.850462 -56.20385)
						(mid 346.980183 -56.273519)
						(end 347.049852 -56.40324)
					)
				)
			)
		)
		(zone
			(layer "F.Cu")
			(hatch none 0.5)
			(connect_pads
				(clearance 0)
			)
			(min_thickness 0.25)
			(keepout
				(tracks not_allowed)
				(vias allowed)
				(pads allowed)
				(copperpour not_allowed)
				(footprints allowed)
			)
			(placement
				(enabled no)
				(sheetname "")
			)
			(fill
				(thermal_gap 0.5)
				(thermal_bridge_width 0.5)
				(island_removal_mode 0)
			)
			(polygon
				(pts
					(arc
						(start 346.944696 -55.402988)
						(mid 346.908325 -55.345125)
						(end 346.850462 -55.308754)
					)
					(arc
						(start 346.850462 -55.203598)
						(mid 346.980183 -55.273267)
						(end 347.049852 -55.402988)
					)
				)
			)
		)
		(zone
			(layer "F.Cu")
			(hatch none 0.5)
			(connect_pads
				(clearance 0)
			)
			(min_thickness 0.25)
			(keepout
				(tracks not_allowed)
				(vias allowed)
				(pads allowed)
				(copperpour not_allowed)
				(footprints allowed)
			)
			(placement
				(enabled no)
				(sheetname "")
			)
			(fill
				(thermal_gap 0.5)
				(thermal_bridge_width 0.5)
				(island_removal_mode 0)
			)
			(polygon
				(pts
					(arc
						(start 346.944696 -54.402482)
						(mid 346.908325 -54.344619)
						(end 346.850462 -54.308248)
					)
					(arc
						(start 346.850462 -54.203092)
						(mid 346.980183 -54.272761)
						(end 347.049852 -54.402482)
					)
				)
			)
		)
		(zone
			(layer "F.Cu")
			(hatch none 0.5)
			(connect_pads
				(clearance 0)
			)
			(min_thickness 0.25)
			(keepout
				(tracks not_allowed)
				(vias allowed)
				(pads allowed)
				(copperpour not_allowed)
				(footprints allowed)
			)
			(placement
				(enabled no)
				(sheetname "")
			)
			(fill
				(thermal_gap 0.5)
				(thermal_bridge_width 0.5)
				(island_removal_mode 0)
			)
			(polygon
				(pts
					(arc
						(start 346.944696 -53.401976)
						(mid 346.908325 -53.344113)
						(end 346.850462 -53.307742)
					)
					(arc
						(start 346.850462 -53.202586)
						(mid 346.980183 -53.272255)
						(end 347.049852 -53.401976)
					)
				)
			)
		)
		(zone
			(layer "F.Cu")
			(hatch none 0.5)
			(connect_pads
				(clearance 0)
			)
			(min_thickness 0.25)
			(keepout
				(tracks not_allowed)
				(vias allowed)
				(pads allowed)
				(copperpour not_allowed)
				(footprints allowed)
			)
			(placement
				(enabled no)
				(sheetname "")
			)
			(fill
				(thermal_gap 0.5)
				(thermal_bridge_width 0.5)
				(island_removal_mode 0)
			)
			(polygon
				(pts
					(arc
						(start 346.944696 -52.40147)
						(mid 346.908325 -52.343607)
						(end 346.850462 -52.307236)
					)
					(arc
						(start 346.850462 -52.20208)
						(mid 346.980183 -52.271749)
						(end 347.049852 -52.40147)
					)
				)
			)
		)
		(zone
			(layer "F.Cu")
			(hatch none 0.5)
			(connect_pads
				(clearance 0)
			)
			(min_thickness 0.25)
			(keepout
				(tracks not_allowed)
				(vias allowed)
				(pads allowed)
				(copperpour not_allowed)
				(footprints allowed)
			)
			(placement
				(enabled no)
				(sheetname "")
			)
			(fill
				(thermal_gap 0.5)
				(thermal_bridge_width 0.5)
				(island_removal_mode 0)
			)
			(polygon
				(pts
					(arc
						(start 346.944696 -51.400964)
						(mid 346.908325 -51.343101)
						(end 346.850462 -51.30673)
					)
					(arc
						(start 346.850462 -51.201574)
						(mid 346.980183 -51.271243)
						(end 347.049852 -51.400964)
					)
				)
			)
		)
		(zone
			(layer "F.Cu")
			(hatch none 0.5)
			(connect_pads
				(clearance 0)
			)
			(min_thickness 0.25)
			(keepout
				(tracks not_allowed)
				(vias allowed)
				(pads allowed)
				(copperpour not_allowed)
				(footprints allowed)
			)
			(placement
				(enabled no)
				(sheetname "")
			)
			(fill
				(thermal_gap 0.5)
				(thermal_bridge_width 0.5)
				(island_removal_mode 0)
			)
			(polygon
				(pts
					(arc
						(start 346.944696 -50.400458)
						(mid 346.908325 -50.342595)
						(end 346.850462 -50.306224)
					)
					(arc
						(start 346.850462 -50.201068)
						(mid 346.980183 -50.270737)
						(end 347.049852 -50.400458)
					)
				)
			)
		)
		(zone
			(layer "F.Cu")
			(hatch none 0.5)
			(connect_pads
				(clearance 0)
			)
			(min_thickness 0.25)
			(keepout
				(tracks not_allowed)
				(vias allowed)
				(pads allowed)
				(copperpour not_allowed)
				(footprints allowed)
			)
			(placement
				(enabled no)
				(sheetname "")
			)
			(fill
				(thermal_gap 0.5)
				(thermal_bridge_width 0.5)
				(island_removal_mode 0)
			)
			(polygon
				(pts
					(arc
						(start 346.944696 -49.399952)
						(mid 346.908325 -49.342089)
						(end 346.850462 -49.305718)
					)
					(arc
						(start 346.850462 -49.200562)
						(mid 346.980183 -49.270231)
						(end 347.049852 -49.399952)
					)
				)
			)
		)
		(zone
			(layer "F.Cu")
			(hatch none 0.5)
			(connect_pads
				(clearance 0)
			)
			(min_thickness 0.25)
			(keepout
				(tracks not_allowed)
				(vias allowed)
				(pads allowed)
				(copperpour not_allowed)
				(footprints allowed)
			)
			(placement
				(enabled no)
				(sheetname "")
			)
			(fill
				(thermal_gap 0.5)
				(thermal_bridge_width 0.5)
				(island_removal_mode 0)
			)
			(polygon
				(pts
					(arc
						(start 346.944696 -48.399446)
						(mid 346.908325 -48.341583)
						(end 346.850462 -48.305212)
					)
					(arc
						(start 346.850462 -48.200056)
						(mid 346.980183 -48.269725)
						(end 347.049852 -48.399446)
					)
				)
			)
		)
		(zone
			(layer "F.Cu")
			(hatch none 0.5)
			(connect_pads
				(clearance 0)
			)
			(min_thickness 0.25)
			(keepout
				(tracks not_allowed)
				(vias allowed)
				(pads allowed)
				(copperpour not_allowed)
				(footprints allowed)
			)
			(placement
				(enabled no)
				(sheetname "")
			)
			(fill
				(thermal_gap 0.5)
				(thermal_bridge_width 0.5)
				(island_removal_mode 0)
			)
			(polygon
				(pts
					(arc
						(start 346.944696 -47.39894)
						(mid 346.908325 -47.341077)
						(end 346.850462 -47.304706)
					)
					(arc
						(start 346.850462 -47.19955)
						(mid 346.980183 -47.269219)
						(end 347.049852 -47.39894)
					)
				)
			)
		)
		(zone
			(layer "F.Cu")
			(hatch none 0.5)
			(connect_pads
				(clearance 0)
			)
			(min_thickness 0.25)
			(keepout
				(tracks not_allowed)
				(vias allowed)
				(pads allowed)
				(copperpour not_allowed)
				(footprints allowed)
			)
			(placement
				(enabled no)
				(sheetname "")
			)
			(fill
				(thermal_gap 0.5)
				(thermal_bridge_width 0.5)
				(island_removal_mode 0)
			)
			(polygon
				(pts
					(arc
						(start 346.944696 -46.398434)
						(mid 346.90827 -46.340735)
						(end 346.850462 -46.304454)
					)
					(arc
						(start 346.850462 -46.199044)
						(mid 346.980183 -46.268713)
						(end 347.049852 -46.398434)
					)
				)
			)
		)
		(zone
			(layer "F.Cu")
			(hatch none 0.5)
			(connect_pads
				(clearance 0)
			)
			(min_thickness 0.25)
			(keepout
				(tracks not_allowed)
				(vias allowed)
				(pads allowed)
				(copperpour not_allowed)
				(footprints allowed)
			)
			(placement
				(enabled no)
				(sheetname "")
			)
			(fill
				(thermal_gap 0.5)
				(thermal_bridge_width 0.5)
				(island_removal_mode 0)
			)
			(polygon
				(pts
					(arc
						(start 346.944696 -45.397928)
						(mid 346.90827 -45.340229)
						(end 346.850462 -45.303948)
					)
					(arc
						(start 346.850462 -45.198538)
						(mid 346.980183 -45.268207)
						(end 347.049852 -45.397928)
					)
				)
			)
		)
		(zone
			(layer "F.Cu")
			(hatch none 0.5)
			(connect_pads
				(clearance 0)
			)
			(min_thickness 0.25)
			(keepout
				(tracks not_allowed)
				(vias allowed)
				(pads allowed)
				(copperpour not_allowed)
				(footprints allowed)
			)
			(placement
				(enabled no)
				(sheetname "")
			)
			(fill
				(thermal_gap 0.5)
				(thermal_bridge_width 0.5)
				(island_removal_mode 0)
			)
			(polygon
				(pts
					(arc
						(start 346.944696 -44.397422)
						(mid 346.90827 -44.339723)
						(end 346.850462 -44.303442)
					)
					(arc
						(start 346.850462 -44.198032)
						(mid 346.980183 -44.267701)
						(end 347.049852 -44.397422)
					)
				)
			)
		)
		(zone
			(layer "F.Cu")
			(hatch none 0.5)
			(connect_pads
				(clearance 0)
			)
			(min_thickness 0.25)
			(keepout
				(tracks not_allowed)
				(vias allowed)
				(pads allowed)
				(copperpour not_allowed)
				(footprints allowed)
			)
			(placement
				(enabled no)
				(sheetname "")
			)
			(fill
				(thermal_gap 0.5)
				(thermal_bridge_width 0.5)
				(island_removal_mode 0)
			)
			(polygon
				(pts
					(arc
						(start 346.944696 -43.39717)
						(mid 346.908325 -43.339307)
						(end 346.850462 -43.302936)
					)
					(arc
						(start 346.850462 -43.197526)
						(mid 346.980271 -43.267283)
						(end 347.049852 -43.39717)
					)
				)
			)
		)
		(zone
			(layer "F.Cu")
			(hatch none 0.5)
			(connect_pads
				(clearance 0)
			)
			(min_thickness 0.25)
			(keepout
				(tracks not_allowed)
				(vias allowed)
				(pads allowed)
				(copperpour not_allowed)
				(footprints allowed)
			)
			(placement
				(enabled no)
				(sheetname "")
			)
			(fill
				(thermal_gap 0.5)
				(thermal_bridge_width 0.5)
				(island_removal_mode 0)
			)
			(polygon
				(pts
					(arc
						(start 346.944696 -42.396664)
						(mid 346.908325 -42.338801)
						(end 346.850462 -42.30243)
					)
					(arc
						(start 346.850462 -42.19702)
						(mid 346.980271 -42.266777)
						(end 347.049852 -42.396664)
					)
				)
			)
		)
		(zone
			(layer "F.Cu")
			(hatch none 0.5)
			(connect_pads
				(clearance 0)
			)
			(min_thickness 0.25)
			(keepout
				(tracks not_allowed)
				(vias allowed)
				(pads allowed)
				(copperpour not_allowed)
				(footprints allowed)
			)
			(placement
				(enabled no)
				(sheetname "")
			)
			(fill
				(thermal_gap 0.5)
				(thermal_bridge_width 0.5)
				(island_removal_mode 0)
			)
			(polygon
				(pts
					(arc
						(start 346.944696 -41.396158)
						(mid 346.908325 -41.338295)
						(end 346.850462 -41.301924)
					)
					(arc
						(start 346.850462 -41.196768)
						(mid 346.980183 -41.266437)
						(end 347.049852 -41.396158)
					)
				)
			)
		)
		(zone
			(layer "F.Cu")
			(hatch none 0.5)
			(connect_pads
				(clearance 0)
			)
			(min_thickness 0.25)
			(keepout
				(tracks not_allowed)
				(vias allowed)
				(pads allowed)
				(copperpour not_allowed)
				(footprints allowed)
			)
			(placement
				(enabled no)
				(sheetname "")
			)
			(fill
				(thermal_gap 0.5)
				(thermal_bridge_width 0.5)
				(island_removal_mode 0)
			)
			(polygon
				(pts
					(arc
						(start 346.944696 -40.395652)
						(mid 346.908325 -40.337789)
						(end 346.850462 -40.301418)
					)
					(arc
						(start 346.850462 -40.196262)
						(mid 346.980183 -40.265931)
						(end 347.049852 -40.395652)
					)
				)
			)
		)
		(zone
			(layer "F.Cu")
			(hatch none 0.5)
			(connect_pads
				(clearance 0)
			)
			(min_thickness 0.25)
			(keepout
				(tracks not_allowed)
				(vias allowed)
				(pads allowed)
				(copperpour not_allowed)
				(footprints allowed)
			)
			(placement
				(enabled no)
				(sheetname "")
			)
			(fill
				(thermal_gap 0.5)
				(thermal_bridge_width 0.5)
				(island_removal_mode 0)
			)
			(polygon
				(pts
					(arc
						(start 346.944696 -39.395146)
						(mid 346.908325 -39.337283)
						(end 346.850462 -39.300912)
					)
					(arc
						(start 346.850462 -39.195756)
						(mid 346.980183 -39.265425)
						(end 347.049852 -39.395146)
					)
				)
			)
		)
		(zone
			(layer "F.Cu")
			(hatch none 0.5)
			(connect_pads
				(clearance 0)
			)
			(min_thickness 0.25)
			(keepout
				(tracks not_allowed)
				(vias allowed)
				(pads allowed)
				(copperpour not_allowed)
				(footprints allowed)
			)
			(placement
				(enabled no)
				(sheetname "")
			)
			(fill
				(thermal_gap 0.5)
				(thermal_bridge_width 0.5)
				(island_removal_mode 0)
			)
			(polygon
				(pts
					(arc
						(start 326.402446 -57.86247)
						(mid 326.380349 -57.954926)
						(end 326.402446 -58.047382)
					)
					(arc
						(start 326.328278 -58.121804)
						(mid 326.278777 -57.954926)
						(end 326.328278 -57.788048)
					)
				)
			)
		)
		(zone
			(layer "F.Cu")
			(hatch none 0.5)
			(connect_pads
				(clearance 0)
			)
			(min_thickness 0.25)
			(keepout
				(tracks not_allowed)
				(vias allowed)
				(pads allowed)
				(copperpour not_allowed)
				(footprints allowed)
			)
			(placement
				(enabled no)
				(sheetname "")
			)
			(fill
				(thermal_gap 0.5)
				(thermal_bridge_width 0.5)
				(island_removal_mode 0)
			)
			(polygon
				(pts
					(arc
						(start 326.402446 -56.861964)
						(mid 326.380349 -56.95442)
						(end 326.402446 -57.046876)
					)
					(arc
						(start 326.328278 -57.121298)
						(mid 326.278777 -56.95442)
						(end 326.328278 -56.787542)
					)
				)
			)
		)
		(zone
			(layer "F.Cu")
			(hatch none 0.5)
			(connect_pads
				(clearance 0)
			)
			(min_thickness 0.25)
			(keepout
				(tracks not_allowed)
				(vias allowed)
				(pads allowed)
				(copperpour not_allowed)
				(footprints allowed)
			)
			(placement
				(enabled no)
				(sheetname "")
			)
			(fill
				(thermal_gap 0.5)
				(thermal_bridge_width 0.5)
				(island_removal_mode 0)
			)
			(polygon
				(pts
					(arc
						(start 326.402446 -38.85311)
						(mid 326.380349 -38.945566)
						(end 326.402446 -39.038022)
					)
					(arc
						(start 326.328278 -39.112444)
						(mid 326.278777 -38.945566)
						(end 326.328278 -38.778688)
					)
				)
			)
		)
		(zone
			(layer "F.Cu")
			(hatch none 0.5)
			(connect_pads
				(clearance 0)
			)
			(min_thickness 0.25)
			(keepout
				(tracks not_allowed)
				(vias allowed)
				(pads allowed)
				(copperpour not_allowed)
				(footprints allowed)
			)
			(placement
				(enabled no)
				(sheetname "")
			)
			(fill
				(thermal_gap 0.5)
				(thermal_bridge_width 0.5)
				(island_removal_mode 0)
			)
			(polygon
				(pts
					(arc
						(start 326.402446 -38.198044)
						(mid 326.380349 -38.2905)
						(end 326.402446 -38.382956)
					)
					(arc
						(start 326.328278 -38.457378)
						(mid 326.278777 -38.2905)
						(end 326.328278 -38.123622)
					)
				)
			)
		)
		(zone
			(layer "F.Cu")
			(hatch none 0.5)
			(connect_pads
				(clearance 0)
			)
			(min_thickness 0.25)
			(keepout
				(tracks not_allowed)
				(vias allowed)
				(pads allowed)
				(copperpour not_allowed)
				(footprints allowed)
			)
			(placement
				(enabled no)
				(sheetname "")
			)
			(fill
				(thermal_gap 0.5)
				(thermal_bridge_width 0.5)
				(island_removal_mode 0)
			)
			(polygon
				(pts
					(arc
						(start 326.492362 -58.137298)
						(mid 326.584818 -58.159395)
						(end 326.677274 -58.137298)
					)
					(arc
						(start 326.751696 -58.211466)
						(mid 326.584818 -58.260967)
						(end 326.41794 -58.211466)
					)
				)
			)
		)
		(zone
			(layer "F.Cu")
			(hatch none 0.5)
			(connect_pads
				(clearance 0)
			)
			(min_thickness 0.25)
			(keepout
				(tracks not_allowed)
				(vias allowed)
				(pads allowed)
				(copperpour not_allowed)
				(footprints allowed)
			)
			(placement
				(enabled no)
				(sheetname "")
			)
			(fill
				(thermal_gap 0.5)
				(thermal_bridge_width 0.5)
				(island_removal_mode 0)
			)
			(polygon
				(pts
					(arc
						(start 326.492362 -57.136792)
						(mid 326.584818 -57.158889)
						(end 326.677274 -57.136792)
					)
					(arc
						(start 326.751696 -57.21096)
						(mid 326.584818 -57.260461)
						(end 326.41794 -57.21096)
					)
				)
			)
		)
		(zone
			(layer "F.Cu")
			(hatch none 0.5)
			(connect_pads
				(clearance 0)
			)
			(min_thickness 0.25)
			(keepout
				(tracks not_allowed)
				(vias allowed)
				(pads allowed)
				(copperpour not_allowed)
				(footprints allowed)
			)
			(placement
				(enabled no)
				(sheetname "")
			)
			(fill
				(thermal_gap 0.5)
				(thermal_bridge_width 0.5)
				(island_removal_mode 0)
			)
			(polygon
				(pts
					(arc
						(start 326.492362 -39.127938)
						(mid 326.584818 -39.150035)
						(end 326.677274 -39.127938)
					)
					(arc
						(start 326.751696 -39.202106)
						(mid 326.584818 -39.251607)
						(end 326.41794 -39.202106)
					)
				)
			)
		)
		(zone
			(layer "F.Cu")
			(hatch none 0.5)
			(connect_pads
				(clearance 0)
			)
			(min_thickness 0.25)
			(keepout
				(tracks not_allowed)
				(vias allowed)
				(pads allowed)
				(copperpour not_allowed)
				(footprints allowed)
			)
			(placement
				(enabled no)
				(sheetname "")
			)
			(fill
				(thermal_gap 0.5)
				(thermal_bridge_width 0.5)
				(island_removal_mode 0)
			)
			(polygon
				(pts
					(arc
						(start 326.492362 -38.472872)
						(mid 326.584818 -38.494969)
						(end 326.677274 -38.472872)
					)
					(arc
						(start 326.751696 -38.54704)
						(mid 326.584818 -38.596541)
						(end 326.41794 -38.54704)
					)
				)
			)
		)
		(zone
			(layer "F.Cu")
			(hatch none 0.5)
			(connect_pads
				(clearance 0)
			)
			(min_thickness 0.25)
			(keepout
				(tracks not_allowed)
				(vias allowed)
				(pads allowed)
				(copperpour not_allowed)
				(footprints allowed)
			)
			(placement
				(enabled no)
				(sheetname "")
			)
			(fill
				(thermal_gap 0.5)
				(thermal_bridge_width 0.5)
				(island_removal_mode 0)
			)
			(polygon
				(pts
					(arc
						(start 326.677274 -57.772554)
						(mid 326.584818 -57.750457)
						(end 326.492362 -57.772554)
					)
					(arc
						(start 326.41794 -57.698386)
						(mid 326.584818 -57.648885)
						(end 326.751696 -57.698386)
					)
				)
			)
		)
		(zone
			(layer "F.Cu")
			(hatch none 0.5)
			(connect_pads
				(clearance 0)
			)
			(min_thickness 0.25)
			(keepout
				(tracks not_allowed)
				(vias allowed)
				(pads allowed)
				(copperpour not_allowed)
				(footprints allowed)
			)
			(placement
				(enabled no)
				(sheetname "")
			)
			(fill
				(thermal_gap 0.5)
				(thermal_bridge_width 0.5)
				(island_removal_mode 0)
			)
			(polygon
				(pts
					(arc
						(start 326.677274 -56.772048)
						(mid 326.584818 -56.749951)
						(end 326.492362 -56.772048)
					)
					(arc
						(start 326.41794 -56.69788)
						(mid 326.584818 -56.648379)
						(end 326.751696 -56.69788)
					)
				)
			)
		)
		(zone
			(layer "F.Cu")
			(hatch none 0.5)
			(connect_pads
				(clearance 0)
			)
			(min_thickness 0.25)
			(keepout
				(tracks not_allowed)
				(vias allowed)
				(pads allowed)
				(copperpour not_allowed)
				(footprints allowed)
			)
			(placement
				(enabled no)
				(sheetname "")
			)
			(fill
				(thermal_gap 0.5)
				(thermal_bridge_width 0.5)
				(island_removal_mode 0)
			)
			(polygon
				(pts
					(arc
						(start 326.677274 -38.763194)
						(mid 326.584818 -38.741097)
						(end 326.492362 -38.763194)
					)
					(arc
						(start 326.41794 -38.689026)
						(mid 326.584818 -38.639525)
						(end 326.751696 -38.689026)
					)
				)
			)
		)
		(zone
			(layer "F.Cu")
			(hatch none 0.5)
			(connect_pads
				(clearance 0)
			)
			(min_thickness 0.25)
			(keepout
				(tracks not_allowed)
				(vias allowed)
				(pads allowed)
				(copperpour not_allowed)
				(footprints allowed)
			)
			(placement
				(enabled no)
				(sheetname "")
			)
			(fill
				(thermal_gap 0.5)
				(thermal_bridge_width 0.5)
				(island_removal_mode 0)
			)
			(polygon
				(pts
					(arc
						(start 326.677274 -38.108128)
						(mid 326.584818 -38.086031)
						(end 326.492362 -38.108128)
					)
					(arc
						(start 326.41794 -38.03396)
						(mid 326.584818 -37.984459)
						(end 326.751696 -38.03396)
					)
				)
			)
		)
		(zone
			(layer "F.Cu")
			(hatch none 0.5)
			(connect_pads
				(clearance 0)
			)
			(min_thickness 0.25)
			(keepout
				(tracks not_allowed)
				(vias allowed)
				(pads allowed)
				(copperpour not_allowed)
				(footprints allowed)
			)
			(placement
				(enabled no)
				(sheetname "")
			)
			(fill
				(thermal_gap 0.5)
				(thermal_bridge_width 0.5)
				(island_removal_mode 0)
			)
			(polygon
				(pts
					(arc
						(start 326.76719 -58.047382)
						(mid 326.789287 -57.954926)
						(end 326.76719 -57.86247)
					)
					(arc
						(start 326.841358 -57.788048)
						(mid 326.890859 -57.954926)
						(end 326.841358 -58.121804)
					)
				)
			)
		)
		(zone
			(layer "F.Cu")
			(hatch none 0.5)
			(connect_pads
				(clearance 0)
			)
			(min_thickness 0.25)
			(keepout
				(tracks not_allowed)
				(vias allowed)
				(pads allowed)
				(copperpour not_allowed)
				(footprints allowed)
			)
			(placement
				(enabled no)
				(sheetname "")
			)
			(fill
				(thermal_gap 0.5)
				(thermal_bridge_width 0.5)
				(island_removal_mode 0)
			)
			(polygon
				(pts
					(arc
						(start 326.76719 -57.046876)
						(mid 326.789287 -56.95442)
						(end 326.76719 -56.861964)
					)
					(arc
						(start 326.841358 -56.787542)
						(mid 326.890859 -56.95442)
						(end 326.841358 -57.121298)
					)
				)
			)
		)
		(zone
			(layer "F.Cu")
			(hatch none 0.5)
			(connect_pads
				(clearance 0)
			)
			(min_thickness 0.25)
			(keepout
				(tracks not_allowed)
				(vias allowed)
				(pads allowed)
				(copperpour not_allowed)
				(footprints allowed)
			)
			(placement
				(enabled no)
				(sheetname "")
			)
			(fill
				(thermal_gap 0.5)
				(thermal_bridge_width 0.5)
				(island_removal_mode 0)
			)
			(polygon
				(pts
					(arc
						(start 326.76719 -39.038022)
						(mid 326.789287 -38.945566)
						(end 326.76719 -38.85311)
					)
					(arc
						(start 326.841358 -38.778688)
						(mid 326.890859 -38.945566)
						(end 326.841358 -39.112444)
					)
				)
			)
		)
		(zone
			(layer "F.Cu")
			(hatch none 0.5)
			(connect_pads
				(clearance 0)
			)
			(min_thickness 0.25)
			(keepout
				(tracks not_allowed)
				(vias allowed)
				(pads allowed)
				(copperpour not_allowed)
				(footprints allowed)
			)
			(placement
				(enabled no)
				(sheetname "")
			)
			(fill
				(thermal_gap 0.5)
				(thermal_bridge_width 0.5)
				(island_removal_mode 0)
			)
			(polygon
				(pts
					(arc
						(start 326.76719 -38.382956)
						(mid 326.789287 -38.2905)
						(end 326.76719 -38.198044)
					)
					(arc
						(start 326.841358 -38.123622)
						(mid 326.890859 -38.2905)
						(end 326.841358 -38.457378)
					)
				)
			)
		)
		(zone
			(layer "F.Cu")
			(hatch none 0.5)
			(connect_pads
				(clearance 0)
			)
			(min_thickness 0.25)
			(keepout
				(tracks not_allowed)
				(vias allowed)
				(pads allowed)
				(copperpour not_allowed)
				(footprints allowed)
			)
			(placement
				(enabled no)
				(sheetname "")
			)
			(fill
				(thermal_gap 0.5)
				(thermal_bridge_width 0.5)
				(island_removal_mode 0)
			)
			(polygon
				(pts
					(arc
						(start 327.057766 -58.517536)
						(mid 327.035669 -58.609992)
						(end 327.057766 -58.702448)
					)
					(arc
						(start 326.983598 -58.77687)
						(mid 326.934097 -58.609992)
						(end 326.983598 -58.443114)
					)
				)
			)
		)
		(zone
			(layer "F.Cu")
			(hatch none 0.5)
			(connect_pads
				(clearance 0)
			)
			(min_thickness 0.25)
			(keepout
				(tracks not_allowed)
				(vias allowed)
				(pads allowed)
				(copperpour not_allowed)
				(footprints allowed)
			)
			(placement
				(enabled no)
				(sheetname "")
			)
			(fill
				(thermal_gap 0.5)
				(thermal_bridge_width 0.5)
				(island_removal_mode 0)
			)
			(polygon
				(pts
					(arc
						(start 327.057766 -37.542724)
						(mid 327.035669 -37.63518)
						(end 327.057766 -37.727636)
					)
					(arc
						(start 326.983598 -37.802058)
						(mid 326.934097 -37.63518)
						(end 326.983598 -37.468302)
					)
				)
			)
		)
		(zone
			(layer "F.Cu")
			(hatch none 0.5)
			(connect_pads
				(clearance 0)
			)
			(min_thickness 0.25)
			(keepout
				(tracks not_allowed)
				(vias allowed)
				(pads allowed)
				(copperpour not_allowed)
				(footprints allowed)
			)
			(placement
				(enabled no)
				(sheetname "")
			)
			(fill
				(thermal_gap 0.5)
				(thermal_bridge_width 0.5)
				(island_removal_mode 0)
			)
			(polygon
				(pts
					(arc
						(start 327.147682 -58.792364)
						(mid 327.240138 -58.814461)
						(end 327.332594 -58.792364)
					)
					(arc
						(start 327.407016 -58.866532)
						(mid 327.240138 -58.916033)
						(end 327.07326 -58.866532)
					)
				)
			)
		)
		(zone
			(layer "F.Cu")
			(hatch none 0.5)
			(connect_pads
				(clearance 0)
			)
			(min_thickness 0.25)
			(keepout
				(tracks not_allowed)
				(vias allowed)
				(pads allowed)
				(copperpour not_allowed)
				(footprints allowed)
			)
			(placement
				(enabled no)
				(sheetname "")
			)
			(fill
				(thermal_gap 0.5)
				(thermal_bridge_width 0.5)
				(island_removal_mode 0)
			)
			(polygon
				(pts
					(arc
						(start 327.147682 -37.817552)
						(mid 327.240138 -37.839649)
						(end 327.332594 -37.817552)
					)
					(arc
						(start 327.407016 -37.89172)
						(mid 327.240138 -37.941221)
						(end 327.07326 -37.89172)
					)
				)
			)
		)
		(zone
			(layer "F.Cu")
			(hatch none 0.5)
			(connect_pads
				(clearance 0)
			)
			(min_thickness 0.25)
			(keepout
				(tracks not_allowed)
				(vias allowed)
				(pads allowed)
				(copperpour not_allowed)
				(footprints allowed)
			)
			(placement
				(enabled no)
				(sheetname "")
			)
			(fill
				(thermal_gap 0.5)
				(thermal_bridge_width 0.5)
				(island_removal_mode 0)
			)
			(polygon
				(pts
					(arc
						(start 327.332594 -58.42762)
						(mid 327.240138 -58.405523)
						(end 327.147682 -58.42762)
					)
					(arc
						(start 327.07326 -58.353452)
						(mid 327.240138 -58.303951)
						(end 327.407016 -58.353452)
					)
				)
			)
		)
		(zone
			(layer "F.Cu")
			(hatch none 0.5)
			(connect_pads
				(clearance 0)
			)
			(min_thickness 0.25)
			(keepout
				(tracks not_allowed)
				(vias allowed)
				(pads allowed)
				(copperpour not_allowed)
				(footprints allowed)
			)
			(placement
				(enabled no)
				(sheetname "")
			)
			(fill
				(thermal_gap 0.5)
				(thermal_bridge_width 0.5)
				(island_removal_mode 0)
			)
			(polygon
				(pts
					(arc
						(start 327.332594 -37.452808)
						(mid 327.240138 -37.430711)
						(end 327.147682 -37.452808)
					)
					(arc
						(start 327.07326 -37.37864)
						(mid 327.240138 -37.329139)
						(end 327.407016 -37.37864)
					)
				)
			)
		)
		(zone
			(layer "F.Cu")
			(hatch none 0.5)
			(connect_pads
				(clearance 0)
			)
			(min_thickness 0.25)
			(keepout
				(tracks not_allowed)
				(vias allowed)
				(pads allowed)
				(copperpour not_allowed)
				(footprints allowed)
			)
			(placement
				(enabled no)
				(sheetname "")
			)
			(fill
				(thermal_gap 0.5)
				(thermal_bridge_width 0.5)
				(island_removal_mode 0)
			)
			(polygon
				(pts
					(arc
						(start 327.42251 -58.702448)
						(mid 327.444607 -58.609992)
						(end 327.42251 -58.517536)
					)
					(arc
						(start 327.496678 -58.443114)
						(mid 327.546179 -58.609992)
						(end 327.496678 -58.77687)
					)
				)
			)
		)
		(zone
			(layer "F.Cu")
			(hatch none 0.5)
			(connect_pads
				(clearance 0)
			)
			(min_thickness 0.25)
			(keepout
				(tracks not_allowed)
				(vias allowed)
				(pads allowed)
				(copperpour not_allowed)
				(footprints allowed)
			)
			(placement
				(enabled no)
				(sheetname "")
			)
			(fill
				(thermal_gap 0.5)
				(thermal_bridge_width 0.5)
				(island_removal_mode 0)
			)
			(polygon
				(pts
					(arc
						(start 327.42251 -37.727636)
						(mid 327.444607 -37.63518)
						(end 327.42251 -37.542724)
					)
					(arc
						(start 327.496678 -37.468302)
						(mid 327.546179 -37.63518)
						(end 327.496678 -37.802058)
					)
				)
			)
		)
		(zone
			(layer "F.Cu")
			(hatch none 0.5)
			(connect_pads
				(clearance 0)
			)
			(min_thickness 0.25)
			(keepout
				(tracks not_allowed)
				(vias allowed)
				(pads allowed)
				(copperpour not_allowed)
				(footprints allowed)
			)
			(placement
				(enabled no)
				(sheetname "")
			)
			(fill
				(thermal_gap 0.5)
				(thermal_bridge_width 0.5)
				(island_removal_mode 0)
			)
			(polygon
				(pts
					(arc
						(start 327.712832 -59.172856)
						(mid 327.690735 -59.265312)
						(end 327.712832 -59.357768)
					)
					(arc
						(start 327.638918 -59.43219)
						(mid 327.589417 -59.265312)
						(end 327.638918 -59.098434)
					)
				)
			)
		)
		(zone
			(layer "F.Cu")
			(hatch none 0.5)
			(connect_pads
				(clearance 0)
			)
			(min_thickness 0.25)
			(keepout
				(tracks not_allowed)
				(vias allowed)
				(pads allowed)
				(copperpour not_allowed)
				(footprints allowed)
			)
			(placement
				(enabled no)
				(sheetname "")
			)
			(fill
				(thermal_gap 0.5)
				(thermal_bridge_width 0.5)
				(island_removal_mode 0)
			)
			(polygon
				(pts
					(arc
						(start 327.712832 -37.542724)
						(mid 327.690735 -37.63518)
						(end 327.712832 -37.727636)
					)
					(arc
						(start 327.638918 -37.802058)
						(mid 327.589417 -37.63518)
						(end 327.638918 -37.468302)
					)
				)
			)
		)
		(zone
			(layer "F.Cu")
			(hatch none 0.5)
			(connect_pads
				(clearance 0)
			)
			(min_thickness 0.25)
			(keepout
				(tracks not_allowed)
				(vias allowed)
				(pads allowed)
				(copperpour not_allowed)
				(footprints allowed)
			)
			(placement
				(enabled no)
				(sheetname "")
			)
			(fill
				(thermal_gap 0.5)
				(thermal_bridge_width 0.5)
				(island_removal_mode 0)
			)
			(polygon
				(pts
					(arc
						(start 327.802748 -59.447684)
						(mid 327.895345 -59.469896)
						(end 327.987914 -59.447684)
					)
					(arc
						(start 328.062336 -59.521852)
						(mid 327.895458 -59.571353)
						(end 327.72858 -59.521852)
					)
				)
			)
		)
		(zone
			(layer "F.Cu")
			(hatch none 0.5)
			(connect_pads
				(clearance 0)
			)
			(min_thickness 0.25)
			(keepout
				(tracks not_allowed)
				(vias allowed)
				(pads allowed)
				(copperpour not_allowed)
				(footprints allowed)
			)
			(placement
				(enabled no)
				(sheetname "")
			)
			(fill
				(thermal_gap 0.5)
				(thermal_bridge_width 0.5)
				(island_removal_mode 0)
			)
			(polygon
				(pts
					(arc
						(start 327.802748 -37.817552)
						(mid 327.895345 -37.839764)
						(end 327.987914 -37.817552)
					)
					(arc
						(start 328.062336 -37.89172)
						(mid 327.895458 -37.941221)
						(end 327.72858 -37.89172)
					)
				)
			)
		)
		(zone
			(layer "F.Cu")
			(hatch none 0.5)
			(connect_pads
				(clearance 0)
			)
			(min_thickness 0.25)
			(keepout
				(tracks not_allowed)
				(vias allowed)
				(pads allowed)
				(copperpour not_allowed)
				(footprints allowed)
			)
			(placement
				(enabled no)
				(sheetname "")
			)
			(fill
				(thermal_gap 0.5)
				(thermal_bridge_width 0.5)
				(island_removal_mode 0)
			)
			(polygon
				(pts
					(arc
						(start 327.987914 -59.08294)
						(mid 327.895345 -59.060843)
						(end 327.802748 -59.08294)
					)
					(arc
						(start 327.72858 -59.008772)
						(mid 327.895458 -58.959271)
						(end 328.062336 -59.008772)
					)
				)
			)
		)
		(zone
			(layer "F.Cu")
			(hatch none 0.5)
			(connect_pads
				(clearance 0)
			)
			(min_thickness 0.25)
			(keepout
				(tracks not_allowed)
				(vias allowed)
				(pads allowed)
				(copperpour not_allowed)
				(footprints allowed)
			)
			(placement
				(enabled no)
				(sheetname "")
			)
			(fill
				(thermal_gap 0.5)
				(thermal_bridge_width 0.5)
				(island_removal_mode 0)
			)
			(polygon
				(pts
					(arc
						(start 327.987914 -37.452808)
						(mid 327.895345 -37.430711)
						(end 327.802748 -37.452808)
					)
					(arc
						(start 327.72858 -37.37864)
						(mid 327.895458 -37.329139)
						(end 328.062336 -37.37864)
					)
				)
			)
		)
		(zone
			(layer "F.Cu")
			(hatch none 0.5)
			(connect_pads
				(clearance 0)
			)
			(min_thickness 0.25)
			(keepout
				(tracks not_allowed)
				(vias allowed)
				(pads allowed)
				(copperpour not_allowed)
				(footprints allowed)
			)
			(placement
				(enabled no)
				(sheetname "")
			)
			(fill
				(thermal_gap 0.5)
				(thermal_bridge_width 0.5)
				(island_removal_mode 0)
			)
			(polygon
				(pts
					(arc
						(start 328.07783 -59.357768)
						(mid 328.099927 -59.265312)
						(end 328.07783 -59.172856)
					)
					(arc
						(start 328.151744 -59.098434)
						(mid 328.201245 -59.265312)
						(end 328.151744 -59.43219)
					)
				)
			)
		)
		(zone
			(layer "F.Cu")
			(hatch none 0.5)
			(connect_pads
				(clearance 0)
			)
			(min_thickness 0.25)
			(keepout
				(tracks not_allowed)
				(vias allowed)
				(pads allowed)
				(copperpour not_allowed)
				(footprints allowed)
			)
			(placement
				(enabled no)
				(sheetname "")
			)
			(fill
				(thermal_gap 0.5)
				(thermal_bridge_width 0.5)
				(island_removal_mode 0)
			)
			(polygon
				(pts
					(arc
						(start 328.07783 -37.727636)
						(mid 328.099927 -37.63518)
						(end 328.07783 -37.542724)
					)
					(arc
						(start 328.151744 -37.468302)
						(mid 328.201245 -37.63518)
						(end 328.151744 -37.802058)
					)
				)
			)
		)
		(zone
			(layer "F.Cu")
			(hatch none 0.5)
			(connect_pads
				(clearance 0)
			)
			(min_thickness 0.25)
			(keepout
				(tracks not_allowed)
				(vias allowed)
				(pads allowed)
				(copperpour not_allowed)
				(footprints allowed)
			)
			(placement
				(enabled no)
				(sheetname "")
			)
			(fill
				(thermal_gap 0.5)
				(thermal_bridge_width 0.5)
				(island_removal_mode 0)
			)
			(polygon
				(pts
					(arc
						(start 328.713338 -59.172856)
						(mid 328.691241 -59.265312)
						(end 328.713338 -59.357768)
					)
					(arc
						(start 328.639424 -59.43219)
						(mid 328.589923 -59.265312)
						(end 328.639424 -59.098434)
					)
				)
			)
		)
		(zone
			(layer "F.Cu")
			(hatch none 0.5)
			(connect_pads
				(clearance 0)
			)
			(min_thickness 0.25)
			(keepout
				(tracks not_allowed)
				(vias allowed)
				(pads allowed)
				(copperpour not_allowed)
				(footprints allowed)
			)
			(placement
				(enabled no)
				(sheetname "")
			)
			(fill
				(thermal_gap 0.5)
				(thermal_bridge_width 0.5)
				(island_removal_mode 0)
			)
			(polygon
				(pts
					(arc
						(start 328.803254 -59.447684)
						(mid 328.895851 -59.469896)
						(end 328.98842 -59.447684)
					)
					(arc
						(start 329.062842 -59.521852)
						(mid 328.895858 -59.571353)
						(end 328.728832 -59.521852)
					)
				)
			)
		)
		(zone
			(layer "F.Cu")
			(hatch none 0.5)
			(connect_pads
				(clearance 0)
			)
			(min_thickness 0.25)
			(keepout
				(tracks not_allowed)
				(vias allowed)
				(pads allowed)
				(copperpour not_allowed)
				(footprints allowed)
			)
			(placement
				(enabled no)
				(sheetname "")
			)
			(fill
				(thermal_gap 0.5)
				(thermal_bridge_width 0.5)
				(island_removal_mode 0)
			)
			(polygon
				(pts
					(arc
						(start 328.983848 -56.498236)
						(mid 329.030449 -56.574063)
						(end 329.106276 -56.620664)
					)
					(arc
						(start 329.106276 -56.72582)
						(mid 328.958494 -56.646018)
						(end 328.878692 -56.498236)
					)
				)
			)
		)
		(zone
			(layer "F.Cu")
			(hatch none 0.5)
			(connect_pads
				(clearance 0)
			)
			(min_thickness 0.25)
			(keepout
				(tracks not_allowed)
				(vias allowed)
				(pads allowed)
				(copperpour not_allowed)
				(footprints allowed)
			)
			(placement
				(enabled no)
				(sheetname "")
			)
			(fill
				(thermal_gap 0.5)
				(thermal_bridge_width 0.5)
				(island_removal_mode 0)
			)
			(polygon
				(pts
					(arc
						(start 328.983848 -55.558436)
						(mid 329.030449 -55.634263)
						(end 329.106276 -55.680864)
					)
					(arc
						(start 329.106276 -55.78602)
						(mid 328.958494 -55.706218)
						(end 328.878692 -55.558436)
					)
				)
			)
		)
		(zone
			(layer "F.Cu")
			(hatch none 0.5)
			(connect_pads
				(clearance 0)
			)
			(min_thickness 0.25)
			(keepout
				(tracks not_allowed)
				(vias allowed)
				(pads allowed)
				(copperpour not_allowed)
				(footprints allowed)
			)
			(placement
				(enabled no)
				(sheetname "")
			)
			(fill
				(thermal_gap 0.5)
				(thermal_bridge_width 0.5)
				(island_removal_mode 0)
			)
			(polygon
				(pts
					(arc
						(start 328.983848 -54.618636)
						(mid 329.030449 -54.694463)
						(end 329.106276 -54.741064)
					)
					(arc
						(start 329.106276 -54.84622)
						(mid 328.958494 -54.766418)
						(end 328.878692 -54.618636)
					)
				)
			)
		)
		(zone
			(layer "F.Cu")
			(hatch none 0.5)
			(connect_pads
				(clearance 0)
			)
			(min_thickness 0.25)
			(keepout
				(tracks not_allowed)
				(vias allowed)
				(pads allowed)
				(copperpour not_allowed)
				(footprints allowed)
			)
			(placement
				(enabled no)
				(sheetname "")
			)
			(fill
				(thermal_gap 0.5)
				(thermal_bridge_width 0.5)
				(island_removal_mode 0)
			)
			(polygon
				(pts
					(arc
						(start 328.983848 -53.678836)
						(mid 329.030449 -53.754663)
						(end 329.106276 -53.801264)
					)
					(arc
						(start 329.106276 -53.90642)
						(mid 328.958494 -53.826618)
						(end 328.878692 -53.678836)
					)
				)
			)
		)
		(zone
			(layer "F.Cu")
			(hatch none 0.5)
			(connect_pads
				(clearance 0)
			)
			(min_thickness 0.25)
			(keepout
				(tracks not_allowed)
				(vias allowed)
				(pads allowed)
				(copperpour not_allowed)
				(footprints allowed)
			)
			(placement
				(enabled no)
				(sheetname "")
			)
			(fill
				(thermal_gap 0.5)
				(thermal_bridge_width 0.5)
				(island_removal_mode 0)
			)
			(polygon
				(pts
					(arc
						(start 328.983848 -52.739036)
						(mid 329.030449 -52.814863)
						(end 329.106276 -52.861464)
					)
					(arc
						(start 329.106276 -52.96662)
						(mid 328.958494 -52.886818)
						(end 328.878692 -52.739036)
					)
				)
			)
		)
		(zone
			(layer "F.Cu")
			(hatch none 0.5)
			(connect_pads
				(clearance 0)
			)
			(min_thickness 0.25)
			(keepout
				(tracks not_allowed)
				(vias allowed)
				(pads allowed)
				(copperpour not_allowed)
				(footprints allowed)
			)
			(placement
				(enabled no)
				(sheetname "")
			)
			(fill
				(thermal_gap 0.5)
				(thermal_bridge_width 0.5)
				(island_removal_mode 0)
			)
			(polygon
				(pts
					(arc
						(start 328.983848 -51.799236)
						(mid 329.030449 -51.875063)
						(end 329.106276 -51.921664)
					)
					(arc
						(start 329.106276 -52.02682)
						(mid 328.958494 -51.947018)
						(end 328.878692 -51.799236)
					)
				)
			)
		)
		(zone
			(layer "F.Cu")
			(hatch none 0.5)
			(connect_pads
				(clearance 0)
			)
			(min_thickness 0.25)
			(keepout
				(tracks not_allowed)
				(vias allowed)
				(pads allowed)
				(copperpour not_allowed)
				(footprints allowed)
			)
			(placement
				(enabled no)
				(sheetname "")
			)
			(fill
				(thermal_gap 0.5)
				(thermal_bridge_width 0.5)
				(island_removal_mode 0)
			)
			(polygon
				(pts
					(arc
						(start 328.983848 -50.859436)
						(mid 329.030449 -50.935263)
						(end 329.106276 -50.981864)
					)
					(arc
						(start 329.106276 -51.08702)
						(mid 328.958494 -51.007218)
						(end 328.878692 -50.859436)
					)
				)
			)
		)
		(zone
			(layer "F.Cu")
			(hatch none 0.5)
			(connect_pads
				(clearance 0)
			)
			(min_thickness 0.25)
			(keepout
				(tracks not_allowed)
				(vias allowed)
				(pads allowed)
				(copperpour not_allowed)
				(footprints allowed)
			)
			(placement
				(enabled no)
				(sheetname "")
			)
			(fill
				(thermal_gap 0.5)
				(thermal_bridge_width 0.5)
				(island_removal_mode 0)
			)
			(polygon
				(pts
					(arc
						(start 328.983848 -49.919636)
						(mid 329.030449 -49.995463)
						(end 329.106276 -50.042064)
					)
					(arc
						(start 329.106276 -50.14722)
						(mid 328.958494 -50.067418)
						(end 328.878692 -49.919636)
					)
				)
			)
		)
		(zone
			(layer "F.Cu")
			(hatch none 0.5)
			(connect_pads
				(clearance 0)
			)
			(min_thickness 0.25)
			(keepout
				(tracks not_allowed)
				(vias allowed)
				(pads allowed)
				(copperpour not_allowed)
				(footprints allowed)
			)
			(placement
				(enabled no)
				(sheetname "")
			)
			(fill
				(thermal_gap 0.5)
				(thermal_bridge_width 0.5)
				(island_removal_mode 0)
			)
			(polygon
				(pts
					(arc
						(start 328.983848 -48.979836)
						(mid 329.030449 -49.055663)
						(end 329.106276 -49.102264)
					)
					(arc
						(start 329.106276 -49.20742)
						(mid 328.958494 -49.127618)
						(end 328.878692 -48.979836)
					)
				)
			)
		)
		(zone
			(layer "F.Cu")
			(hatch none 0.5)
			(connect_pads
				(clearance 0)
			)
			(min_thickness 0.25)
			(keepout
				(tracks not_allowed)
				(vias allowed)
				(pads allowed)
				(copperpour not_allowed)
				(footprints allowed)
			)
			(placement
				(enabled no)
				(sheetname "")
			)
			(fill
				(thermal_gap 0.5)
				(thermal_bridge_width 0.5)
				(island_removal_mode 0)
			)
			(polygon
				(pts
					(arc
						(start 328.983848 -48.040036)
						(mid 329.030449 -48.115863)
						(end 329.106276 -48.162464)
					)
					(arc
						(start 329.106276 -48.26762)
						(mid 328.958494 -48.187818)
						(end 328.878692 -48.040036)
					)
				)
			)
		)
		(zone
			(layer "F.Cu")
			(hatch none 0.5)
			(connect_pads
				(clearance 0)
			)
			(min_thickness 0.25)
			(keepout
				(tracks not_allowed)
				(vias allowed)
				(pads allowed)
				(copperpour not_allowed)
				(footprints allowed)
			)
			(placement
				(enabled no)
				(sheetname "")
			)
			(fill
				(thermal_gap 0.5)
				(thermal_bridge_width 0.5)
				(island_removal_mode 0)
			)
			(polygon
				(pts
					(arc
						(start 328.983848 -47.100236)
						(mid 329.030449 -47.176063)
						(end 329.106276 -47.222664)
					)
					(arc
						(start 329.106276 -47.32782)
						(mid 328.958494 -47.248018)
						(end 328.878692 -47.100236)
					)
				)
			)
		)
		(zone
			(layer "F.Cu")
			(hatch none 0.5)
			(connect_pads
				(clearance 0)
			)
			(min_thickness 0.25)
			(keepout
				(tracks not_allowed)
				(vias allowed)
				(pads allowed)
				(copperpour not_allowed)
				(footprints allowed)
			)
			(placement
				(enabled no)
				(sheetname "")
			)
			(fill
				(thermal_gap 0.5)
				(thermal_bridge_width 0.5)
				(island_removal_mode 0)
			)
			(polygon
				(pts
					(arc
						(start 328.983848 -46.160436)
						(mid 329.030449 -46.236263)
						(end 329.106276 -46.282864)
					)
					(arc
						(start 329.106276 -46.38802)
						(mid 328.958494 -46.308218)
						(end 328.878692 -46.160436)
					)
				)
			)
		)
		(zone
			(layer "F.Cu")
			(hatch none 0.5)
			(connect_pads
				(clearance 0)
			)
			(min_thickness 0.25)
			(keepout
				(tracks not_allowed)
				(vias allowed)
				(pads allowed)
				(copperpour not_allowed)
				(footprints allowed)
			)
			(placement
				(enabled no)
				(sheetname "")
			)
			(fill
				(thermal_gap 0.5)
				(thermal_bridge_width 0.5)
				(island_removal_mode 0)
			)
			(polygon
				(pts
					(arc
						(start 328.983848 -45.220636)
						(mid 329.030449 -45.296463)
						(end 329.106276 -45.343064)
					)
					(arc
						(start 329.106276 -45.44822)
						(mid 328.958494 -45.368418)
						(end 328.878692 -45.220636)
					)
				)
			)
		)
		(zone
			(layer "F.Cu")
			(hatch none 0.5)
			(connect_pads
				(clearance 0)
			)
			(min_thickness 0.25)
			(keepout
				(tracks not_allowed)
				(vias allowed)
				(pads allowed)
				(copperpour not_allowed)
				(footprints allowed)
			)
			(placement
				(enabled no)
				(sheetname "")
			)
			(fill
				(thermal_gap 0.5)
				(thermal_bridge_width 0.5)
				(island_removal_mode 0)
			)
			(polygon
				(pts
					(arc
						(start 328.983848 -44.280836)
						(mid 329.030449 -44.356663)
						(end 329.106276 -44.403264)
					)
					(arc
						(start 329.106276 -44.50842)
						(mid 328.958494 -44.428618)
						(end 328.878692 -44.280836)
					)
				)
			)
		)
		(zone
			(layer "F.Cu")
			(hatch none 0.5)
			(connect_pads
				(clearance 0)
			)
			(min_thickness 0.25)
			(keepout
				(tracks not_allowed)
				(vias allowed)
				(pads allowed)
				(copperpour not_allowed)
				(footprints allowed)
			)
			(placement
				(enabled no)
				(sheetname "")
			)
			(fill
				(thermal_gap 0.5)
				(thermal_bridge_width 0.5)
				(island_removal_mode 0)
			)
			(polygon
				(pts
					(arc
						(start 328.983848 -43.341036)
						(mid 329.030449 -43.416863)
						(end 329.106276 -43.463464)
					)
					(arc
						(start 329.106276 -43.56862)
						(mid 328.958494 -43.488818)
						(end 328.878692 -43.341036)
					)
				)
			)
		)
		(zone
			(layer "F.Cu")
			(hatch none 0.5)
			(connect_pads
				(clearance 0)
			)
			(min_thickness 0.25)
			(keepout
				(tracks not_allowed)
				(vias allowed)
				(pads allowed)
				(copperpour not_allowed)
				(footprints allowed)
			)
			(placement
				(enabled no)
				(sheetname "")
			)
			(fill
				(thermal_gap 0.5)
				(thermal_bridge_width 0.5)
				(island_removal_mode 0)
			)
			(polygon
				(pts
					(arc
						(start 328.983848 -42.401236)
						(mid 329.030449 -42.477063)
						(end 329.106276 -42.523664)
					)
					(arc
						(start 329.106276 -42.62882)
						(mid 328.958494 -42.549018)
						(end 328.878692 -42.401236)
					)
				)
			)
		)
		(zone
			(layer "F.Cu")
			(hatch none 0.5)
			(connect_pads
				(clearance 0)
			)
			(min_thickness 0.25)
			(keepout
				(tracks not_allowed)
				(vias allowed)
				(pads allowed)
				(copperpour not_allowed)
				(footprints allowed)
			)
			(placement
				(enabled no)
				(sheetname "")
			)
			(fill
				(thermal_gap 0.5)
				(thermal_bridge_width 0.5)
				(island_removal_mode 0)
			)
			(polygon
				(pts
					(arc
						(start 328.983848 -41.461436)
						(mid 329.030449 -41.537263)
						(end 329.106276 -41.583864)
					)
					(arc
						(start 329.106276 -41.68902)
						(mid 328.958494 -41.609218)
						(end 328.878692 -41.461436)
					)
				)
			)
		)
		(zone
			(layer "F.Cu")
			(hatch none 0.5)
			(connect_pads
				(clearance 0)
			)
			(min_thickness 0.25)
			(keepout
				(tracks not_allowed)
				(vias allowed)
				(pads allowed)
				(copperpour not_allowed)
				(footprints allowed)
			)
			(placement
				(enabled no)
				(sheetname "")
			)
			(fill
				(thermal_gap 0.5)
				(thermal_bridge_width 0.5)
				(island_removal_mode 0)
			)
			(polygon
				(pts
					(arc
						(start 328.983848 -40.521636)
						(mid 329.030449 -40.597463)
						(end 329.106276 -40.644064)
					)
					(arc
						(start 329.106276 -40.74922)
						(mid 328.958494 -40.669418)
						(end 328.878692 -40.521636)
					)
				)
			)
		)
		(zone
			(layer "F.Cu")
			(hatch none 0.5)
			(connect_pads
				(clearance 0)
			)
			(min_thickness 0.25)
			(keepout
				(tracks not_allowed)
				(vias allowed)
				(pads allowed)
				(copperpour not_allowed)
				(footprints allowed)
			)
			(placement
				(enabled no)
				(sheetname "")
			)
			(fill
				(thermal_gap 0.5)
				(thermal_bridge_width 0.5)
				(island_removal_mode 0)
			)
			(polygon
				(pts
					(arc
						(start 328.98842 -59.08294)
						(mid 328.895851 -59.060843)
						(end 328.803254 -59.08294)
					)
					(arc
						(start 328.728832 -59.008772)
						(mid 328.895858 -58.959133)
						(end 329.062842 -59.008772)
					)
				)
			)
		)
		(zone
			(layer "F.Cu")
			(hatch none 0.5)
			(connect_pads
				(clearance 0)
			)
			(min_thickness 0.25)
			(keepout
				(tracks not_allowed)
				(vias allowed)
				(pads allowed)
				(copperpour not_allowed)
				(footprints allowed)
			)
			(placement
				(enabled no)
				(sheetname "")
			)
			(fill
				(thermal_gap 0.5)
				(thermal_bridge_width 0.5)
				(island_removal_mode 0)
			)
			(polygon
				(pts
					(arc
						(start 329.078336 -59.357768)
						(mid 329.100433 -59.265312)
						(end 329.078336 -59.172856)
					)
					(arc
						(start 329.15225 -59.098434)
						(mid 329.201751 -59.265312)
						(end 329.15225 -59.43219)
					)
				)
			)
		)
		(zone
			(layer "F.Cu")
			(hatch none 0.5)
			(connect_pads
				(clearance 0)
			)
			(min_thickness 0.25)
			(keepout
				(tracks not_allowed)
				(vias allowed)
				(pads allowed)
				(copperpour not_allowed)
				(footprints allowed)
			)
			(placement
				(enabled no)
				(sheetname "")
			)
			(fill
				(thermal_gap 0.5)
				(thermal_bridge_width 0.5)
				(island_removal_mode 0)
			)
			(polygon
				(pts
					(arc
						(start 329.106276 -56.256428)
						(mid 329.030449 -56.303029)
						(end 328.983848 -56.378856)
					)
					(arc
						(start 328.878692 -56.378856)
						(mid 328.958494 -56.231074)
						(end 329.106276 -56.151272)
					)
				)
			)
		)
		(zone
			(layer "F.Cu")
			(hatch none 0.5)
			(connect_pads
				(clearance 0)
			)
			(min_thickness 0.25)
			(keepout
				(tracks not_allowed)
				(vias allowed)
				(pads allowed)
				(copperpour not_allowed)
				(footprints allowed)
			)
			(placement
				(enabled no)
				(sheetname "")
			)
			(fill
				(thermal_gap 0.5)
				(thermal_bridge_width 0.5)
				(island_removal_mode 0)
			)
			(polygon
				(pts
					(arc
						(start 329.106276 -55.316628)
						(mid 329.030449 -55.363229)
						(end 328.983848 -55.439056)
					)
					(arc
						(start 328.878692 -55.439056)
						(mid 328.958494 -55.291274)
						(end 329.106276 -55.211472)
					)
				)
			)
		)
		(zone
			(layer "F.Cu")
			(hatch none 0.5)
			(connect_pads
				(clearance 0)
			)
			(min_thickness 0.25)
			(keepout
				(tracks not_allowed)
				(vias allowed)
				(pads allowed)
				(copperpour not_allowed)
				(footprints allowed)
			)
			(placement
				(enabled no)
				(sheetname "")
			)
			(fill
				(thermal_gap 0.5)
				(thermal_bridge_width 0.5)
				(island_removal_mode 0)
			)
			(polygon
				(pts
					(arc
						(start 329.106276 -54.376828)
						(mid 329.030449 -54.423429)
						(end 328.983848 -54.499256)
					)
					(arc
						(start 328.878692 -54.499256)
						(mid 328.958494 -54.351474)
						(end 329.106276 -54.271672)
					)
				)
			)
		)
		(zone
			(layer "F.Cu")
			(hatch none 0.5)
			(connect_pads
				(clearance 0)
			)
			(min_thickness 0.25)
			(keepout
				(tracks not_allowed)
				(vias allowed)
				(pads allowed)
				(copperpour not_allowed)
				(footprints allowed)
			)
			(placement
				(enabled no)
				(sheetname "")
			)
			(fill
				(thermal_gap 0.5)
				(thermal_bridge_width 0.5)
				(island_removal_mode 0)
			)
			(polygon
				(pts
					(arc
						(start 329.106276 -53.437028)
						(mid 329.030449 -53.483629)
						(end 328.983848 -53.559456)
					)
					(arc
						(start 328.878692 -53.559456)
						(mid 328.958494 -53.411674)
						(end 329.106276 -53.331872)
					)
				)
			)
		)
		(zone
			(layer "F.Cu")
			(hatch none 0.5)
			(connect_pads
				(clearance 0)
			)
			(min_thickness 0.25)
			(keepout
				(tracks not_allowed)
				(vias allowed)
				(pads allowed)
				(copperpour not_allowed)
				(footprints allowed)
			)
			(placement
				(enabled no)
				(sheetname "")
			)
			(fill
				(thermal_gap 0.5)
				(thermal_bridge_width 0.5)
				(island_removal_mode 0)
			)
			(polygon
				(pts
					(arc
						(start 329.106276 -52.497228)
						(mid 329.030449 -52.543829)
						(end 328.983848 -52.619656)
					)
					(arc
						(start 328.878692 -52.619656)
						(mid 328.958494 -52.471874)
						(end 329.106276 -52.392072)
					)
				)
			)
		)
		(zone
			(layer "F.Cu")
			(hatch none 0.5)
			(connect_pads
				(clearance 0)
			)
			(min_thickness 0.25)
			(keepout
				(tracks not_allowed)
				(vias allowed)
				(pads allowed)
				(copperpour not_allowed)
				(footprints allowed)
			)
			(placement
				(enabled no)
				(sheetname "")
			)
			(fill
				(thermal_gap 0.5)
				(thermal_bridge_width 0.5)
				(island_removal_mode 0)
			)
			(polygon
				(pts
					(arc
						(start 329.106276 -51.557428)
						(mid 329.030449 -51.604029)
						(end 328.983848 -51.679856)
					)
					(arc
						(start 328.878692 -51.679856)
						(mid 328.958494 -51.532074)
						(end 329.106276 -51.452272)
					)
				)
			)
		)
		(zone
			(layer "F.Cu")
			(hatch none 0.5)
			(connect_pads
				(clearance 0)
			)
			(min_thickness 0.25)
			(keepout
				(tracks not_allowed)
				(vias allowed)
				(pads allowed)
				(copperpour not_allowed)
				(footprints allowed)
			)
			(placement
				(enabled no)
				(sheetname "")
			)
			(fill
				(thermal_gap 0.5)
				(thermal_bridge_width 0.5)
				(island_removal_mode 0)
			)
			(polygon
				(pts
					(arc
						(start 329.106276 -50.617628)
						(mid 329.030449 -50.664229)
						(end 328.983848 -50.740056)
					)
					(arc
						(start 328.878692 -50.740056)
						(mid 328.958494 -50.592274)
						(end 329.106276 -50.512472)
					)
				)
			)
		)
		(zone
			(layer "F.Cu")
			(hatch none 0.5)
			(connect_pads
				(clearance 0)
			)
			(min_thickness 0.25)
			(keepout
				(tracks not_allowed)
				(vias allowed)
				(pads allowed)
				(copperpour not_allowed)
				(footprints allowed)
			)
			(placement
				(enabled no)
				(sheetname "")
			)
			(fill
				(thermal_gap 0.5)
				(thermal_bridge_width 0.5)
				(island_removal_mode 0)
			)
			(polygon
				(pts
					(arc
						(start 329.106276 -49.677828)
						(mid 329.030449 -49.724429)
						(end 328.983848 -49.800256)
					)
					(arc
						(start 328.878692 -49.800256)
						(mid 328.958494 -49.652474)
						(end 329.106276 -49.572672)
					)
				)
			)
		)
		(zone
			(layer "F.Cu")
			(hatch none 0.5)
			(connect_pads
				(clearance 0)
			)
			(min_thickness 0.25)
			(keepout
				(tracks not_allowed)
				(vias allowed)
				(pads allowed)
				(copperpour not_allowed)
				(footprints allowed)
			)
			(placement
				(enabled no)
				(sheetname "")
			)
			(fill
				(thermal_gap 0.5)
				(thermal_bridge_width 0.5)
				(island_removal_mode 0)
			)
			(polygon
				(pts
					(arc
						(start 329.106276 -48.738028)
						(mid 329.030449 -48.784629)
						(end 328.983848 -48.860456)
					)
					(arc
						(start 328.878692 -48.860456)
						(mid 328.958494 -48.712674)
						(end 329.106276 -48.632872)
					)
				)
			)
		)
		(zone
			(layer "F.Cu")
			(hatch none 0.5)
			(connect_pads
				(clearance 0)
			)
			(min_thickness 0.25)
			(keepout
				(tracks not_allowed)
				(vias allowed)
				(pads allowed)
				(copperpour not_allowed)
				(footprints allowed)
			)
			(placement
				(enabled no)
				(sheetname "")
			)
			(fill
				(thermal_gap 0.5)
				(thermal_bridge_width 0.5)
				(island_removal_mode 0)
			)
			(polygon
				(pts
					(arc
						(start 329.106276 -47.798228)
						(mid 329.030449 -47.844829)
						(end 328.983848 -47.920656)
					)
					(arc
						(start 328.878692 -47.920656)
						(mid 328.958494 -47.772874)
						(end 329.106276 -47.693072)
					)
				)
			)
		)
		(zone
			(layer "F.Cu")
			(hatch none 0.5)
			(connect_pads
				(clearance 0)
			)
			(min_thickness 0.25)
			(keepout
				(tracks not_allowed)
				(vias allowed)
				(pads allowed)
				(copperpour not_allowed)
				(footprints allowed)
			)
			(placement
				(enabled no)
				(sheetname "")
			)
			(fill
				(thermal_gap 0.5)
				(thermal_bridge_width 0.5)
				(island_removal_mode 0)
			)
			(polygon
				(pts
					(arc
						(start 329.106276 -46.858428)
						(mid 329.030449 -46.905029)
						(end 328.983848 -46.980856)
					)
					(arc
						(start 328.878692 -46.980856)
						(mid 328.958494 -46.833074)
						(end 329.106276 -46.753272)
					)
				)
			)
		)
		(zone
			(layer "F.Cu")
			(hatch none 0.5)
			(connect_pads
				(clearance 0)
			)
			(min_thickness 0.25)
			(keepout
				(tracks not_allowed)
				(vias allowed)
				(pads allowed)
				(copperpour not_allowed)
				(footprints allowed)
			)
			(placement
				(enabled no)
				(sheetname "")
			)
			(fill
				(thermal_gap 0.5)
				(thermal_bridge_width 0.5)
				(island_removal_mode 0)
			)
			(polygon
				(pts
					(arc
						(start 329.106276 -45.918628)
						(mid 329.030449 -45.965229)
						(end 328.983848 -46.041056)
					)
					(arc
						(start 328.878692 -46.041056)
						(mid 328.958494 -45.893274)
						(end 329.106276 -45.813472)
					)
				)
			)
		)
		(zone
			(layer "F.Cu")
			(hatch none 0.5)
			(connect_pads
				(clearance 0)
			)
			(min_thickness 0.25)
			(keepout
				(tracks not_allowed)
				(vias allowed)
				(pads allowed)
				(copperpour not_allowed)
				(footprints allowed)
			)
			(placement
				(enabled no)
				(sheetname "")
			)
			(fill
				(thermal_gap 0.5)
				(thermal_bridge_width 0.5)
				(island_removal_mode 0)
			)
			(polygon
				(pts
					(arc
						(start 329.106276 -44.978828)
						(mid 329.030449 -45.025429)
						(end 328.983848 -45.101256)
					)
					(arc
						(start 328.878692 -45.101256)
						(mid 328.958494 -44.953474)
						(end 329.106276 -44.873672)
					)
				)
			)
		)
		(zone
			(layer "F.Cu")
			(hatch none 0.5)
			(connect_pads
				(clearance 0)
			)
			(min_thickness 0.25)
			(keepout
				(tracks not_allowed)
				(vias allowed)
				(pads allowed)
				(copperpour not_allowed)
				(footprints allowed)
			)
			(placement
				(enabled no)
				(sheetname "")
			)
			(fill
				(thermal_gap 0.5)
				(thermal_bridge_width 0.5)
				(island_removal_mode 0)
			)
			(polygon
				(pts
					(arc
						(start 329.106276 -44.039028)
						(mid 329.030449 -44.085629)
						(end 328.983848 -44.161456)
					)
					(arc
						(start 328.878692 -44.161456)
						(mid 328.958494 -44.013674)
						(end 329.106276 -43.933872)
					)
				)
			)
		)
		(zone
			(layer "F.Cu")
			(hatch none 0.5)
			(connect_pads
				(clearance 0)
			)
			(min_thickness 0.25)
			(keepout
				(tracks not_allowed)
				(vias allowed)
				(pads allowed)
				(copperpour not_allowed)
				(footprints allowed)
			)
			(placement
				(enabled no)
				(sheetname "")
			)
			(fill
				(thermal_gap 0.5)
				(thermal_bridge_width 0.5)
				(island_removal_mode 0)
			)
			(polygon
				(pts
					(arc
						(start 329.106276 -43.099228)
						(mid 329.030449 -43.145829)
						(end 328.983848 -43.221656)
					)
					(arc
						(start 328.878692 -43.221656)
						(mid 328.958494 -43.073874)
						(end 329.106276 -42.994072)
					)
				)
			)
		)
		(zone
			(layer "F.Cu")
			(hatch none 0.5)
			(connect_pads
				(clearance 0)
			)
			(min_thickness 0.25)
			(keepout
				(tracks not_allowed)
				(vias allowed)
				(pads allowed)
				(copperpour not_allowed)
				(footprints allowed)
			)
			(placement
				(enabled no)
				(sheetname "")
			)
			(fill
				(thermal_gap 0.5)
				(thermal_bridge_width 0.5)
				(island_removal_mode 0)
			)
			(polygon
				(pts
					(arc
						(start 329.106276 -42.159428)
						(mid 329.030449 -42.206029)
						(end 328.983848 -42.281856)
					)
					(arc
						(start 328.878692 -42.281856)
						(mid 328.958494 -42.134074)
						(end 329.106276 -42.054272)
					)
				)
			)
		)
		(zone
			(layer "F.Cu")
			(hatch none 0.5)
			(connect_pads
				(clearance 0)
			)
			(min_thickness 0.25)
			(keepout
				(tracks not_allowed)
				(vias allowed)
				(pads allowed)
				(copperpour not_allowed)
				(footprints allowed)
			)
			(placement
				(enabled no)
				(sheetname "")
			)
			(fill
				(thermal_gap 0.5)
				(thermal_bridge_width 0.5)
				(island_removal_mode 0)
			)
			(polygon
				(pts
					(arc
						(start 329.106276 -41.219628)
						(mid 329.030449 -41.266229)
						(end 328.983848 -41.342056)
					)
					(arc
						(start 328.878692 -41.342056)
						(mid 328.958494 -41.194274)
						(end 329.106276 -41.114472)
					)
				)
			)
		)
		(zone
			(layer "F.Cu")
			(hatch none 0.5)
			(connect_pads
				(clearance 0)
			)
			(min_thickness 0.25)
			(keepout
				(tracks not_allowed)
				(vias allowed)
				(pads allowed)
				(copperpour not_allowed)
				(footprints allowed)
			)
			(placement
				(enabled no)
				(sheetname "")
			)
			(fill
				(thermal_gap 0.5)
				(thermal_bridge_width 0.5)
				(island_removal_mode 0)
			)
			(polygon
				(pts
					(arc
						(start 329.106276 -40.279828)
						(mid 329.030449 -40.326429)
						(end 328.983848 -40.402256)
					)
					(arc
						(start 328.878692 -40.402256)
						(mid 328.958494 -40.254474)
						(end 329.106276 -40.174672)
					)
				)
			)
		)
		(zone
			(layer "F.Cu")
			(hatch none 0.5)
			(connect_pads
				(clearance 0)
			)
			(min_thickness 0.25)
			(keepout
				(tracks not_allowed)
				(vias allowed)
				(pads allowed)
				(copperpour not_allowed)
				(footprints allowed)
			)
			(placement
				(enabled no)
				(sheetname "")
			)
			(fill
				(thermal_gap 0.5)
				(thermal_bridge_width 0.5)
				(island_removal_mode 0)
			)
			(polygon
				(pts
					(arc
						(start 329.225656 -56.620664)
						(mid 329.301483 -56.574063)
						(end 329.348084 -56.498236)
					)
					(arc
						(start 329.45324 -56.498236)
						(mid 329.373438 -56.646018)
						(end 329.225656 -56.72582)
					)
				)
			)
		)
		(zone
			(layer "F.Cu")
			(hatch none 0.5)
			(connect_pads
				(clearance 0)
			)
			(min_thickness 0.25)
			(keepout
				(tracks not_allowed)
				(vias allowed)
				(pads allowed)
				(copperpour not_allowed)
				(footprints allowed)
			)
			(placement
				(enabled no)
				(sheetname "")
			)
			(fill
				(thermal_gap 0.5)
				(thermal_bridge_width 0.5)
				(island_removal_mode 0)
			)
			(polygon
				(pts
					(arc
						(start 329.225656 -55.680864)
						(mid 329.301483 -55.634263)
						(end 329.348084 -55.558436)
					)
					(arc
						(start 329.45324 -55.558436)
						(mid 329.373438 -55.706218)
						(end 329.225656 -55.78602)
					)
				)
			)
		)
		(zone
			(layer "F.Cu")
			(hatch none 0.5)
			(connect_pads
				(clearance 0)
			)
			(min_thickness 0.25)
			(keepout
				(tracks not_allowed)
				(vias allowed)
				(pads allowed)
				(copperpour not_allowed)
				(footprints allowed)
			)
			(placement
				(enabled no)
				(sheetname "")
			)
			(fill
				(thermal_gap 0.5)
				(thermal_bridge_width 0.5)
				(island_removal_mode 0)
			)
			(polygon
				(pts
					(arc
						(start 329.225656 -54.741064)
						(mid 329.301483 -54.694463)
						(end 329.348084 -54.618636)
					)
					(arc
						(start 329.45324 -54.618636)
						(mid 329.373438 -54.766418)
						(end 329.225656 -54.84622)
					)
				)
			)
		)
		(zone
			(layer "F.Cu")
			(hatch none 0.5)
			(connect_pads
				(clearance 0)
			)
			(min_thickness 0.25)
			(keepout
				(tracks not_allowed)
				(vias allowed)
				(pads allowed)
				(copperpour not_allowed)
				(footprints allowed)
			)
			(placement
				(enabled no)
				(sheetname "")
			)
			(fill
				(thermal_gap 0.5)
				(thermal_bridge_width 0.5)
				(island_removal_mode 0)
			)
			(polygon
				(pts
					(arc
						(start 329.225656 -53.801264)
						(mid 329.301483 -53.754663)
						(end 329.348084 -53.678836)
					)
					(arc
						(start 329.45324 -53.678836)
						(mid 329.373438 -53.826618)
						(end 329.225656 -53.90642)
					)
				)
			)
		)
		(zone
			(layer "F.Cu")
			(hatch none 0.5)
			(connect_pads
				(clearance 0)
			)
			(min_thickness 0.25)
			(keepout
				(tracks not_allowed)
				(vias allowed)
				(pads allowed)
				(copperpour not_allowed)
				(footprints allowed)
			)
			(placement
				(enabled no)
				(sheetname "")
			)
			(fill
				(thermal_gap 0.5)
				(thermal_bridge_width 0.5)
				(island_removal_mode 0)
			)
			(polygon
				(pts
					(arc
						(start 329.225656 -52.861464)
						(mid 329.301483 -52.814863)
						(end 329.348084 -52.739036)
					)
					(arc
						(start 329.45324 -52.739036)
						(mid 329.373438 -52.886818)
						(end 329.225656 -52.96662)
					)
				)
			)
		)
		(zone
			(layer "F.Cu")
			(hatch none 0.5)
			(connect_pads
				(clearance 0)
			)
			(min_thickness 0.25)
			(keepout
				(tracks not_allowed)
				(vias allowed)
				(pads allowed)
				(copperpour not_allowed)
				(footprints allowed)
			)
			(placement
				(enabled no)
				(sheetname "")
			)
			(fill
				(thermal_gap 0.5)
				(thermal_bridge_width 0.5)
				(island_removal_mode 0)
			)
			(polygon
				(pts
					(arc
						(start 329.225656 -51.921664)
						(mid 329.301483 -51.875063)
						(end 329.348084 -51.799236)
					)
					(arc
						(start 329.45324 -51.799236)
						(mid 329.373438 -51.947018)
						(end 329.225656 -52.02682)
					)
				)
			)
		)
		(zone
			(layer "F.Cu")
			(hatch none 0.5)
			(connect_pads
				(clearance 0)
			)
			(min_thickness 0.25)
			(keepout
				(tracks not_allowed)
				(vias allowed)
				(pads allowed)
				(copperpour not_allowed)
				(footprints allowed)
			)
			(placement
				(enabled no)
				(sheetname "")
			)
			(fill
				(thermal_gap 0.5)
				(thermal_bridge_width 0.5)
				(island_removal_mode 0)
			)
			(polygon
				(pts
					(arc
						(start 329.225656 -50.981864)
						(mid 329.301483 -50.935263)
						(end 329.348084 -50.859436)
					)
					(arc
						(start 329.45324 -50.859436)
						(mid 329.373438 -51.007218)
						(end 329.225656 -51.08702)
					)
				)
			)
		)
		(zone
			(layer "F.Cu")
			(hatch none 0.5)
			(connect_pads
				(clearance 0)
			)
			(min_thickness 0.25)
			(keepout
				(tracks not_allowed)
				(vias allowed)
				(pads allowed)
				(copperpour not_allowed)
				(footprints allowed)
			)
			(placement
				(enabled no)
				(sheetname "")
			)
			(fill
				(thermal_gap 0.5)
				(thermal_bridge_width 0.5)
				(island_removal_mode 0)
			)
			(polygon
				(pts
					(arc
						(start 329.225656 -50.042064)
						(mid 329.301483 -49.995463)
						(end 329.348084 -49.919636)
					)
					(arc
						(start 329.45324 -49.919636)
						(mid 329.373438 -50.067418)
						(end 329.225656 -50.14722)
					)
				)
			)
		)
		(zone
			(layer "F.Cu")
			(hatch none 0.5)
			(connect_pads
				(clearance 0)
			)
			(min_thickness 0.25)
			(keepout
				(tracks not_allowed)
				(vias allowed)
				(pads allowed)
				(copperpour not_allowed)
				(footprints allowed)
			)
			(placement
				(enabled no)
				(sheetname "")
			)
			(fill
				(thermal_gap 0.5)
				(thermal_bridge_width 0.5)
				(island_removal_mode 0)
			)
			(polygon
				(pts
					(arc
						(start 329.225656 -49.102264)
						(mid 329.301483 -49.055663)
						(end 329.348084 -48.979836)
					)
					(arc
						(start 329.45324 -48.979836)
						(mid 329.373438 -49.127618)
						(end 329.225656 -49.20742)
					)
				)
			)
		)
		(zone
			(layer "F.Cu")
			(hatch none 0.5)
			(connect_pads
				(clearance 0)
			)
			(min_thickness 0.25)
			(keepout
				(tracks not_allowed)
				(vias allowed)
				(pads allowed)
				(copperpour not_allowed)
				(footprints allowed)
			)
			(placement
				(enabled no)
				(sheetname "")
			)
			(fill
				(thermal_gap 0.5)
				(thermal_bridge_width 0.5)
				(island_removal_mode 0)
			)
			(polygon
				(pts
					(arc
						(start 329.225656 -48.162464)
						(mid 329.301483 -48.115863)
						(end 329.348084 -48.040036)
					)
					(arc
						(start 329.45324 -48.040036)
						(mid 329.373438 -48.187818)
						(end 329.225656 -48.26762)
					)
				)
			)
		)
		(zone
			(layer "F.Cu")
			(hatch none 0.5)
			(connect_pads
				(clearance 0)
			)
			(min_thickness 0.25)
			(keepout
				(tracks not_allowed)
				(vias allowed)
				(pads allowed)
				(copperpour not_allowed)
				(footprints allowed)
			)
			(placement
				(enabled no)
				(sheetname "")
			)
			(fill
				(thermal_gap 0.5)
				(thermal_bridge_width 0.5)
				(island_removal_mode 0)
			)
			(polygon
				(pts
					(arc
						(start 329.225656 -47.222664)
						(mid 329.301483 -47.176063)
						(end 329.348084 -47.100236)
					)
					(arc
						(start 329.45324 -47.100236)
						(mid 329.373438 -47.248018)
						(end 329.225656 -47.32782)
					)
				)
			)
		)
		(zone
			(layer "F.Cu")
			(hatch none 0.5)
			(connect_pads
				(clearance 0)
			)
			(min_thickness 0.25)
			(keepout
				(tracks not_allowed)
				(vias allowed)
				(pads allowed)
				(copperpour not_allowed)
				(footprints allowed)
			)
			(placement
				(enabled no)
				(sheetname "")
			)
			(fill
				(thermal_gap 0.5)
				(thermal_bridge_width 0.5)
				(island_removal_mode 0)
			)
			(polygon
				(pts
					(arc
						(start 329.225656 -46.282864)
						(mid 329.301483 -46.236263)
						(end 329.348084 -46.160436)
					)
					(arc
						(start 329.45324 -46.160436)
						(mid 329.373438 -46.308218)
						(end 329.225656 -46.38802)
					)
				)
			)
		)
		(zone
			(layer "F.Cu")
			(hatch none 0.5)
			(connect_pads
				(clearance 0)
			)
			(min_thickness 0.25)
			(keepout
				(tracks not_allowed)
				(vias allowed)
				(pads allowed)
				(copperpour not_allowed)
				(footprints allowed)
			)
			(placement
				(enabled no)
				(sheetname "")
			)
			(fill
				(thermal_gap 0.5)
				(thermal_bridge_width 0.5)
				(island_removal_mode 0)
			)
			(polygon
				(pts
					(arc
						(start 329.225656 -45.343064)
						(mid 329.301483 -45.296463)
						(end 329.348084 -45.220636)
					)
					(arc
						(start 329.45324 -45.220636)
						(mid 329.373438 -45.368418)
						(end 329.225656 -45.44822)
					)
				)
			)
		)
		(zone
			(layer "F.Cu")
			(hatch none 0.5)
			(connect_pads
				(clearance 0)
			)
			(min_thickness 0.25)
			(keepout
				(tracks not_allowed)
				(vias allowed)
				(pads allowed)
				(copperpour not_allowed)
				(footprints allowed)
			)
			(placement
				(enabled no)
				(sheetname "")
			)
			(fill
				(thermal_gap 0.5)
				(thermal_bridge_width 0.5)
				(island_removal_mode 0)
			)
			(polygon
				(pts
					(arc
						(start 329.225656 -44.403264)
						(mid 329.301483 -44.356663)
						(end 329.348084 -44.280836)
					)
					(arc
						(start 329.45324 -44.280836)
						(mid 329.373438 -44.428618)
						(end 329.225656 -44.50842)
					)
				)
			)
		)
		(zone
			(layer "F.Cu")
			(hatch none 0.5)
			(connect_pads
				(clearance 0)
			)
			(min_thickness 0.25)
			(keepout
				(tracks not_allowed)
				(vias allowed)
				(pads allowed)
				(copperpour not_allowed)
				(footprints allowed)
			)
			(placement
				(enabled no)
				(sheetname "")
			)
			(fill
				(thermal_gap 0.5)
				(thermal_bridge_width 0.5)
				(island_removal_mode 0)
			)
			(polygon
				(pts
					(arc
						(start 329.225656 -43.463464)
						(mid 329.301483 -43.416863)
						(end 329.348084 -43.341036)
					)
					(arc
						(start 329.45324 -43.341036)
						(mid 329.373438 -43.488818)
						(end 329.225656 -43.56862)
					)
				)
			)
		)
		(zone
			(layer "F.Cu")
			(hatch none 0.5)
			(connect_pads
				(clearance 0)
			)
			(min_thickness 0.25)
			(keepout
				(tracks not_allowed)
				(vias allowed)
				(pads allowed)
				(copperpour not_allowed)
				(footprints allowed)
			)
			(placement
				(enabled no)
				(sheetname "")
			)
			(fill
				(thermal_gap 0.5)
				(thermal_bridge_width 0.5)
				(island_removal_mode 0)
			)
			(polygon
				(pts
					(arc
						(start 329.225656 -42.523664)
						(mid 329.301483 -42.477063)
						(end 329.348084 -42.401236)
					)
					(arc
						(start 329.45324 -42.401236)
						(mid 329.373438 -42.549018)
						(end 329.225656 -42.62882)
					)
				)
			)
		)
		(zone
			(layer "F.Cu")
			(hatch none 0.5)
			(connect_pads
				(clearance 0)
			)
			(min_thickness 0.25)
			(keepout
				(tracks not_allowed)
				(vias allowed)
				(pads allowed)
				(copperpour not_allowed)
				(footprints allowed)
			)
			(placement
				(enabled no)
				(sheetname "")
			)
			(fill
				(thermal_gap 0.5)
				(thermal_bridge_width 0.5)
				(island_removal_mode 0)
			)
			(polygon
				(pts
					(arc
						(start 329.225656 -41.583864)
						(mid 329.301483 -41.537263)
						(end 329.348084 -41.461436)
					)
					(arc
						(start 329.45324 -41.461436)
						(mid 329.373438 -41.609218)
						(end 329.225656 -41.68902)
					)
				)
			)
		)
		(zone
			(layer "F.Cu")
			(hatch none 0.5)
			(connect_pads
				(clearance 0)
			)
			(min_thickness 0.25)
			(keepout
				(tracks not_allowed)
				(vias allowed)
				(pads allowed)
				(copperpour not_allowed)
				(footprints allowed)
			)
			(placement
				(enabled no)
				(sheetname "")
			)
			(fill
				(thermal_gap 0.5)
				(thermal_bridge_width 0.5)
				(island_removal_mode 0)
			)
			(polygon
				(pts
					(arc
						(start 329.225656 -40.644064)
						(mid 329.301483 -40.597463)
						(end 329.348084 -40.521636)
					)
					(arc
						(start 329.45324 -40.521636)
						(mid 329.373438 -40.669418)
						(end 329.225656 -40.74922)
					)
				)
			)
		)
		(zone
			(layer "F.Cu")
			(hatch none 0.5)
			(connect_pads
				(clearance 0)
			)
			(min_thickness 0.25)
			(keepout
				(tracks not_allowed)
				(vias allowed)
				(pads allowed)
				(copperpour not_allowed)
				(footprints allowed)
			)
			(placement
				(enabled no)
				(sheetname "")
			)
			(fill
				(thermal_gap 0.5)
				(thermal_bridge_width 0.5)
				(island_removal_mode 0)
			)
			(polygon
				(pts
					(arc
						(start 329.348084 -56.378856)
						(mid 329.301483 -56.303029)
						(end 329.225656 -56.256428)
					)
					(arc
						(start 329.225656 -56.151272)
						(mid 329.373438 -56.231074)
						(end 329.45324 -56.378856)
					)
				)
			)
		)
		(zone
			(layer "F.Cu")
			(hatch none 0.5)
			(connect_pads
				(clearance 0)
			)
			(min_thickness 0.25)
			(keepout
				(tracks not_allowed)
				(vias allowed)
				(pads allowed)
				(copperpour not_allowed)
				(footprints allowed)
			)
			(placement
				(enabled no)
				(sheetname "")
			)
			(fill
				(thermal_gap 0.5)
				(thermal_bridge_width 0.5)
				(island_removal_mode 0)
			)
			(polygon
				(pts
					(arc
						(start 329.348084 -55.439056)
						(mid 329.301483 -55.363229)
						(end 329.225656 -55.316628)
					)
					(arc
						(start 329.225656 -55.211472)
						(mid 329.373438 -55.291274)
						(end 329.45324 -55.439056)
					)
				)
			)
		)
		(zone
			(layer "F.Cu")
			(hatch none 0.5)
			(connect_pads
				(clearance 0)
			)
			(min_thickness 0.25)
			(keepout
				(tracks not_allowed)
				(vias allowed)
				(pads allowed)
				(copperpour not_allowed)
				(footprints allowed)
			)
			(placement
				(enabled no)
				(sheetname "")
			)
			(fill
				(thermal_gap 0.5)
				(thermal_bridge_width 0.5)
				(island_removal_mode 0)
			)
			(polygon
				(pts
					(arc
						(start 329.348084 -54.499256)
						(mid 329.301483 -54.423429)
						(end 329.225656 -54.376828)
					)
					(arc
						(start 329.225656 -54.271672)
						(mid 329.373438 -54.351474)
						(end 329.45324 -54.499256)
					)
				)
			)
		)
		(zone
			(layer "F.Cu")
			(hatch none 0.5)
			(connect_pads
				(clearance 0)
			)
			(min_thickness 0.25)
			(keepout
				(tracks not_allowed)
				(vias allowed)
				(pads allowed)
				(copperpour not_allowed)
				(footprints allowed)
			)
			(placement
				(enabled no)
				(sheetname "")
			)
			(fill
				(thermal_gap 0.5)
				(thermal_bridge_width 0.5)
				(island_removal_mode 0)
			)
			(polygon
				(pts
					(arc
						(start 329.348084 -53.559456)
						(mid 329.301483 -53.483629)
						(end 329.225656 -53.437028)
					)
					(arc
						(start 329.225656 -53.331872)
						(mid 329.373438 -53.411674)
						(end 329.45324 -53.559456)
					)
				)
			)
		)
		(zone
			(layer "F.Cu")
			(hatch none 0.5)
			(connect_pads
				(clearance 0)
			)
			(min_thickness 0.25)
			(keepout
				(tracks not_allowed)
				(vias allowed)
				(pads allowed)
				(copperpour not_allowed)
				(footprints allowed)
			)
			(placement
				(enabled no)
				(sheetname "")
			)
			(fill
				(thermal_gap 0.5)
				(thermal_bridge_width 0.5)
				(island_removal_mode 0)
			)
			(polygon
				(pts
					(arc
						(start 329.348084 -52.619656)
						(mid 329.301483 -52.543829)
						(end 329.225656 -52.497228)
					)
					(arc
						(start 329.225656 -52.392072)
						(mid 329.373438 -52.471874)
						(end 329.45324 -52.619656)
					)
				)
			)
		)
		(zone
			(layer "F.Cu")
			(hatch none 0.5)
			(connect_pads
				(clearance 0)
			)
			(min_thickness 0.25)
			(keepout
				(tracks not_allowed)
				(vias allowed)
				(pads allowed)
				(copperpour not_allowed)
				(footprints allowed)
			)
			(placement
				(enabled no)
				(sheetname "")
			)
			(fill
				(thermal_gap 0.5)
				(thermal_bridge_width 0.5)
				(island_removal_mode 0)
			)
			(polygon
				(pts
					(arc
						(start 329.348084 -51.679856)
						(mid 329.301483 -51.604029)
						(end 329.225656 -51.557428)
					)
					(arc
						(start 329.225656 -51.452272)
						(mid 329.373438 -51.532074)
						(end 329.45324 -51.679856)
					)
				)
			)
		)
		(zone
			(layer "F.Cu")
			(hatch none 0.5)
			(connect_pads
				(clearance 0)
			)
			(min_thickness 0.25)
			(keepout
				(tracks not_allowed)
				(vias allowed)
				(pads allowed)
				(copperpour not_allowed)
				(footprints allowed)
			)
			(placement
				(enabled no)
				(sheetname "")
			)
			(fill
				(thermal_gap 0.5)
				(thermal_bridge_width 0.5)
				(island_removal_mode 0)
			)
			(polygon
				(pts
					(arc
						(start 329.348084 -50.740056)
						(mid 329.301483 -50.664229)
						(end 329.225656 -50.617628)
					)
					(arc
						(start 329.225656 -50.512472)
						(mid 329.373438 -50.592274)
						(end 329.45324 -50.740056)
					)
				)
			)
		)
		(zone
			(layer "F.Cu")
			(hatch none 0.5)
			(connect_pads
				(clearance 0)
			)
			(min_thickness 0.25)
			(keepout
				(tracks not_allowed)
				(vias allowed)
				(pads allowed)
				(copperpour not_allowed)
				(footprints allowed)
			)
			(placement
				(enabled no)
				(sheetname "")
			)
			(fill
				(thermal_gap 0.5)
				(thermal_bridge_width 0.5)
				(island_removal_mode 0)
			)
			(polygon
				(pts
					(arc
						(start 329.348084 -49.800256)
						(mid 329.301483 -49.724429)
						(end 329.225656 -49.677828)
					)
					(arc
						(start 329.225656 -49.572672)
						(mid 329.373438 -49.652474)
						(end 329.45324 -49.800256)
					)
				)
			)
		)
		(zone
			(layer "F.Cu")
			(hatch none 0.5)
			(connect_pads
				(clearance 0)
			)
			(min_thickness 0.25)
			(keepout
				(tracks not_allowed)
				(vias allowed)
				(pads allowed)
				(copperpour not_allowed)
				(footprints allowed)
			)
			(placement
				(enabled no)
				(sheetname "")
			)
			(fill
				(thermal_gap 0.5)
				(thermal_bridge_width 0.5)
				(island_removal_mode 0)
			)
			(polygon
				(pts
					(arc
						(start 329.348084 -48.860456)
						(mid 329.301483 -48.784629)
						(end 329.225656 -48.738028)
					)
					(arc
						(start 329.225656 -48.632872)
						(mid 329.373438 -48.712674)
						(end 329.45324 -48.860456)
					)
				)
			)
		)
		(zone
			(layer "F.Cu")
			(hatch none 0.5)
			(connect_pads
				(clearance 0)
			)
			(min_thickness 0.25)
			(keepout
				(tracks not_allowed)
				(vias allowed)
				(pads allowed)
				(copperpour not_allowed)
				(footprints allowed)
			)
			(placement
				(enabled no)
				(sheetname "")
			)
			(fill
				(thermal_gap 0.5)
				(thermal_bridge_width 0.5)
				(island_removal_mode 0)
			)
			(polygon
				(pts
					(arc
						(start 329.348084 -47.920656)
						(mid 329.301483 -47.844829)
						(end 329.225656 -47.798228)
					)
					(arc
						(start 329.225656 -47.693072)
						(mid 329.373438 -47.772874)
						(end 329.45324 -47.920656)
					)
				)
			)
		)
		(zone
			(layer "F.Cu")
			(hatch none 0.5)
			(connect_pads
				(clearance 0)
			)
			(min_thickness 0.25)
			(keepout
				(tracks not_allowed)
				(vias allowed)
				(pads allowed)
				(copperpour not_allowed)
				(footprints allowed)
			)
			(placement
				(enabled no)
				(sheetname "")
			)
			(fill
				(thermal_gap 0.5)
				(thermal_bridge_width 0.5)
				(island_removal_mode 0)
			)
			(polygon
				(pts
					(arc
						(start 329.348084 -46.980856)
						(mid 329.301483 -46.905029)
						(end 329.225656 -46.858428)
					)
					(arc
						(start 329.225656 -46.753272)
						(mid 329.373438 -46.833074)
						(end 329.45324 -46.980856)
					)
				)
			)
		)
		(zone
			(layer "F.Cu")
			(hatch none 0.5)
			(connect_pads
				(clearance 0)
			)
			(min_thickness 0.25)
			(keepout
				(tracks not_allowed)
				(vias allowed)
				(pads allowed)
				(copperpour not_allowed)
				(footprints allowed)
			)
			(placement
				(enabled no)
				(sheetname "")
			)
			(fill
				(thermal_gap 0.5)
				(thermal_bridge_width 0.5)
				(island_removal_mode 0)
			)
			(polygon
				(pts
					(arc
						(start 329.348084 -46.041056)
						(mid 329.301483 -45.965229)
						(end 329.225656 -45.918628)
					)
					(arc
						(start 329.225656 -45.813472)
						(mid 329.373438 -45.893274)
						(end 329.45324 -46.041056)
					)
				)
			)
		)
		(zone
			(layer "F.Cu")
			(hatch none 0.5)
			(connect_pads
				(clearance 0)
			)
			(min_thickness 0.25)
			(keepout
				(tracks not_allowed)
				(vias allowed)
				(pads allowed)
				(copperpour not_allowed)
				(footprints allowed)
			)
			(placement
				(enabled no)
				(sheetname "")
			)
			(fill
				(thermal_gap 0.5)
				(thermal_bridge_width 0.5)
				(island_removal_mode 0)
			)
			(polygon
				(pts
					(arc
						(start 329.348084 -45.101256)
						(mid 329.301483 -45.025429)
						(end 329.225656 -44.978828)
					)
					(arc
						(start 329.225656 -44.873672)
						(mid 329.373438 -44.953474)
						(end 329.45324 -45.101256)
					)
				)
			)
		)
		(zone
			(layer "F.Cu")
			(hatch none 0.5)
			(connect_pads
				(clearance 0)
			)
			(min_thickness 0.25)
			(keepout
				(tracks not_allowed)
				(vias allowed)
				(pads allowed)
				(copperpour not_allowed)
				(footprints allowed)
			)
			(placement
				(enabled no)
				(sheetname "")
			)
			(fill
				(thermal_gap 0.5)
				(thermal_bridge_width 0.5)
				(island_removal_mode 0)
			)
			(polygon
				(pts
					(arc
						(start 329.348084 -44.161456)
						(mid 329.301483 -44.085629)
						(end 329.225656 -44.039028)
					)
					(arc
						(start 329.225656 -43.933872)
						(mid 329.373438 -44.013674)
						(end 329.45324 -44.161456)
					)
				)
			)
		)
		(zone
			(layer "F.Cu")
			(hatch none 0.5)
			(connect_pads
				(clearance 0)
			)
			(min_thickness 0.25)
			(keepout
				(tracks not_allowed)
				(vias allowed)
				(pads allowed)
				(copperpour not_allowed)
				(footprints allowed)
			)
			(placement
				(enabled no)
				(sheetname "")
			)
			(fill
				(thermal_gap 0.5)
				(thermal_bridge_width 0.5)
				(island_removal_mode 0)
			)
			(polygon
				(pts
					(arc
						(start 329.348084 -43.221656)
						(mid 329.301483 -43.145829)
						(end 329.225656 -43.099228)
					)
					(arc
						(start 329.225656 -42.994072)
						(mid 329.373438 -43.073874)
						(end 329.45324 -43.221656)
					)
				)
			)
		)
		(zone
			(layer "F.Cu")
			(hatch none 0.5)
			(connect_pads
				(clearance 0)
			)
			(min_thickness 0.25)
			(keepout
				(tracks not_allowed)
				(vias allowed)
				(pads allowed)
				(copperpour not_allowed)
				(footprints allowed)
			)
			(placement
				(enabled no)
				(sheetname "")
			)
			(fill
				(thermal_gap 0.5)
				(thermal_bridge_width 0.5)
				(island_removal_mode 0)
			)
			(polygon
				(pts
					(arc
						(start 329.348084 -42.281856)
						(mid 329.301483 -42.206029)
						(end 329.225656 -42.159428)
					)
					(arc
						(start 329.225656 -42.054272)
						(mid 329.373438 -42.134074)
						(end 329.45324 -42.281856)
					)
				)
			)
		)
		(zone
			(layer "F.Cu")
			(hatch none 0.5)
			(connect_pads
				(clearance 0)
			)
			(min_thickness 0.25)
			(keepout
				(tracks not_allowed)
				(vias allowed)
				(pads allowed)
				(copperpour not_allowed)
				(footprints allowed)
			)
			(placement
				(enabled no)
				(sheetname "")
			)
			(fill
				(thermal_gap 0.5)
				(thermal_bridge_width 0.5)
				(island_removal_mode 0)
			)
			(polygon
				(pts
					(arc
						(start 329.348084 -41.342056)
						(mid 329.301483 -41.266229)
						(end 329.225656 -41.219628)
					)
					(arc
						(start 329.225656 -41.114472)
						(mid 329.373438 -41.194274)
						(end 329.45324 -41.342056)
					)
				)
			)
		)
		(zone
			(layer "F.Cu")
			(hatch none 0.5)
			(connect_pads
				(clearance 0)
			)
			(min_thickness 0.25)
			(keepout
				(tracks not_allowed)
				(vias allowed)
				(pads allowed)
				(copperpour not_allowed)
				(footprints allowed)
			)
			(placement
				(enabled no)
				(sheetname "")
			)
			(fill
				(thermal_gap 0.5)
				(thermal_bridge_width 0.5)
				(island_removal_mode 0)
			)
			(polygon
				(pts
					(arc
						(start 329.348084 -40.402256)
						(mid 329.301483 -40.326429)
						(end 329.225656 -40.279828)
					)
					(arc
						(start 329.225656 -40.174672)
						(mid 329.373438 -40.254474)
						(end 329.45324 -40.402256)
					)
				)
			)
		)
		(zone
			(layer "F.Cu")
			(hatch none 0.5)
			(connect_pads
				(clearance 0)
			)
			(min_thickness 0.25)
			(keepout
				(tracks not_allowed)
				(vias allowed)
				(pads allowed)
				(copperpour not_allowed)
				(footprints allowed)
			)
			(placement
				(enabled no)
				(sheetname "")
			)
			(fill
				(thermal_gap 0.5)
				(thermal_bridge_width 0.5)
				(island_removal_mode 0)
			)
			(polygon
				(pts
					(arc
						(start 329.798172 -56.968136)
						(mid 329.844687 -57.043878)
						(end 329.920346 -57.090564)
					)
					(arc
						(start 329.920346 -57.19572)
						(mid 329.772564 -57.115918)
						(end 329.692762 -56.968136)
					)
				)
			)
		)
		(zone
			(layer "F.Cu")
			(hatch none 0.5)
			(connect_pads
				(clearance 0)
			)
			(min_thickness 0.25)
			(keepout
				(tracks not_allowed)
				(vias allowed)
				(pads allowed)
				(copperpour not_allowed)
				(footprints allowed)
			)
			(placement
				(enabled no)
				(sheetname "")
			)
			(fill
				(thermal_gap 0.5)
				(thermal_bridge_width 0.5)
				(island_removal_mode 0)
			)
			(polygon
				(pts
					(arc
						(start 329.798172 -56.028336)
						(mid 329.844687 -56.104078)
						(end 329.920346 -56.150764)
					)
					(arc
						(start 329.920346 -56.25592)
						(mid 329.772564 -56.176118)
						(end 329.692762 -56.028336)
					)
				)
			)
		)
		(zone
			(layer "F.Cu")
			(hatch none 0.5)
			(connect_pads
				(clearance 0)
			)
			(min_thickness 0.25)
			(keepout
				(tracks not_allowed)
				(vias allowed)
				(pads allowed)
				(copperpour not_allowed)
				(footprints allowed)
			)
			(placement
				(enabled no)
				(sheetname "")
			)
			(fill
				(thermal_gap 0.5)
				(thermal_bridge_width 0.5)
				(island_removal_mode 0)
			)
			(polygon
				(pts
					(arc
						(start 329.798172 -55.088536)
						(mid 329.844687 -55.164278)
						(end 329.920346 -55.210964)
					)
					(arc
						(start 329.920346 -55.31612)
						(mid 329.772564 -55.236318)
						(end 329.692762 -55.088536)
					)
				)
			)
		)
		(zone
			(layer "F.Cu")
			(hatch none 0.5)
			(connect_pads
				(clearance 0)
			)
			(min_thickness 0.25)
			(keepout
				(tracks not_allowed)
				(vias allowed)
				(pads allowed)
				(copperpour not_allowed)
				(footprints allowed)
			)
			(placement
				(enabled no)
				(sheetname "")
			)
			(fill
				(thermal_gap 0.5)
				(thermal_bridge_width 0.5)
				(island_removal_mode 0)
			)
			(polygon
				(pts
					(arc
						(start 329.798172 -54.148736)
						(mid 329.844687 -54.224478)
						(end 329.920346 -54.271164)
					)
					(arc
						(start 329.920346 -54.37632)
						(mid 329.772564 -54.296518)
						(end 329.692762 -54.148736)
					)
				)
			)
		)
		(zone
			(layer "F.Cu")
			(hatch none 0.5)
			(connect_pads
				(clearance 0)
			)
			(min_thickness 0.25)
			(keepout
				(tracks not_allowed)
				(vias allowed)
				(pads allowed)
				(copperpour not_allowed)
				(footprints allowed)
			)
			(placement
				(enabled no)
				(sheetname "")
			)
			(fill
				(thermal_gap 0.5)
				(thermal_bridge_width 0.5)
				(island_removal_mode 0)
			)
			(polygon
				(pts
					(arc
						(start 329.798172 -53.208936)
						(mid 329.844687 -53.284678)
						(end 329.920346 -53.331364)
					)
					(arc
						(start 329.920346 -53.43652)
						(mid 329.772564 -53.356718)
						(end 329.692762 -53.208936)
					)
				)
			)
		)
		(zone
			(layer "F.Cu")
			(hatch none 0.5)
			(connect_pads
				(clearance 0)
			)
			(min_thickness 0.25)
			(keepout
				(tracks not_allowed)
				(vias allowed)
				(pads allowed)
				(copperpour not_allowed)
				(footprints allowed)
			)
			(placement
				(enabled no)
				(sheetname "")
			)
			(fill
				(thermal_gap 0.5)
				(thermal_bridge_width 0.5)
				(island_removal_mode 0)
			)
			(polygon
				(pts
					(arc
						(start 329.798172 -52.269136)
						(mid 329.844687 -52.344878)
						(end 329.920346 -52.391564)
					)
					(arc
						(start 329.920346 -52.49672)
						(mid 329.772564 -52.416918)
						(end 329.692762 -52.269136)
					)
				)
			)
		)
		(zone
			(layer "F.Cu")
			(hatch none 0.5)
			(connect_pads
				(clearance 0)
			)
			(min_thickness 0.25)
			(keepout
				(tracks not_allowed)
				(vias allowed)
				(pads allowed)
				(copperpour not_allowed)
				(footprints allowed)
			)
			(placement
				(enabled no)
				(sheetname "")
			)
			(fill
				(thermal_gap 0.5)
				(thermal_bridge_width 0.5)
				(island_removal_mode 0)
			)
			(polygon
				(pts
					(arc
						(start 329.798172 -51.329336)
						(mid 329.844687 -51.405078)
						(end 329.920346 -51.451764)
					)
					(arc
						(start 329.920346 -51.55692)
						(mid 329.772564 -51.477118)
						(end 329.692762 -51.329336)
					)
				)
			)
		)
		(zone
			(layer "F.Cu")
			(hatch none 0.5)
			(connect_pads
				(clearance 0)
			)
			(min_thickness 0.25)
			(keepout
				(tracks not_allowed)
				(vias allowed)
				(pads allowed)
				(copperpour not_allowed)
				(footprints allowed)
			)
			(placement
				(enabled no)
				(sheetname "")
			)
			(fill
				(thermal_gap 0.5)
				(thermal_bridge_width 0.5)
				(island_removal_mode 0)
			)
			(polygon
				(pts
					(arc
						(start 329.798172 -50.389536)
						(mid 329.844687 -50.465278)
						(end 329.920346 -50.511964)
					)
					(arc
						(start 329.920346 -50.61712)
						(mid 329.772564 -50.537318)
						(end 329.692762 -50.389536)
					)
				)
			)
		)
		(zone
			(layer "F.Cu")
			(hatch none 0.5)
			(connect_pads
				(clearance 0)
			)
			(min_thickness 0.25)
			(keepout
				(tracks not_allowed)
				(vias allowed)
				(pads allowed)
				(copperpour not_allowed)
				(footprints allowed)
			)
			(placement
				(enabled no)
				(sheetname "")
			)
			(fill
				(thermal_gap 0.5)
				(thermal_bridge_width 0.5)
				(island_removal_mode 0)
			)
			(polygon
				(pts
					(arc
						(start 329.798172 -49.449736)
						(mid 329.844687 -49.525478)
						(end 329.920346 -49.572164)
					)
					(arc
						(start 329.920346 -49.67732)
						(mid 329.772564 -49.597518)
						(end 329.692762 -49.449736)
					)
				)
			)
		)
		(zone
			(layer "F.Cu")
			(hatch none 0.5)
			(connect_pads
				(clearance 0)
			)
			(min_thickness 0.25)
			(keepout
				(tracks not_allowed)
				(vias allowed)
				(pads allowed)
				(copperpour not_allowed)
				(footprints allowed)
			)
			(placement
				(enabled no)
				(sheetname "")
			)
			(fill
				(thermal_gap 0.5)
				(thermal_bridge_width 0.5)
				(island_removal_mode 0)
			)
			(polygon
				(pts
					(arc
						(start 329.798172 -48.509936)
						(mid 329.844687 -48.585678)
						(end 329.920346 -48.632364)
					)
					(arc
						(start 329.920346 -48.73752)
						(mid 329.772564 -48.657718)
						(end 329.692762 -48.509936)
					)
				)
			)
		)
		(zone
			(layer "F.Cu")
			(hatch none 0.5)
			(connect_pads
				(clearance 0)
			)
			(min_thickness 0.25)
			(keepout
				(tracks not_allowed)
				(vias allowed)
				(pads allowed)
				(copperpour not_allowed)
				(footprints allowed)
			)
			(placement
				(enabled no)
				(sheetname "")
			)
			(fill
				(thermal_gap 0.5)
				(thermal_bridge_width 0.5)
				(island_removal_mode 0)
			)
			(polygon
				(pts
					(arc
						(start 329.798172 -47.570136)
						(mid 329.844687 -47.645878)
						(end 329.920346 -47.692564)
					)
					(arc
						(start 329.920346 -47.79772)
						(mid 329.772564 -47.717918)
						(end 329.692762 -47.570136)
					)
				)
			)
		)
		(zone
			(layer "F.Cu")
			(hatch none 0.5)
			(connect_pads
				(clearance 0)
			)
			(min_thickness 0.25)
			(keepout
				(tracks not_allowed)
				(vias allowed)
				(pads allowed)
				(copperpour not_allowed)
				(footprints allowed)
			)
			(placement
				(enabled no)
				(sheetname "")
			)
			(fill
				(thermal_gap 0.5)
				(thermal_bridge_width 0.5)
				(island_removal_mode 0)
			)
			(polygon
				(pts
					(arc
						(start 329.798172 -46.630336)
						(mid 329.844687 -46.706078)
						(end 329.920346 -46.752764)
					)
					(arc
						(start 329.920346 -46.85792)
						(mid 329.772564 -46.778118)
						(end 329.692762 -46.630336)
					)
				)
			)
		)
		(zone
			(layer "F.Cu")
			(hatch none 0.5)
			(connect_pads
				(clearance 0)
			)
			(min_thickness 0.25)
			(keepout
				(tracks not_allowed)
				(vias allowed)
				(pads allowed)
				(copperpour not_allowed)
				(footprints allowed)
			)
			(placement
				(enabled no)
				(sheetname "")
			)
			(fill
				(thermal_gap 0.5)
				(thermal_bridge_width 0.5)
				(island_removal_mode 0)
			)
			(polygon
				(pts
					(arc
						(start 329.798172 -45.690536)
						(mid 329.844687 -45.766278)
						(end 329.920346 -45.812964)
					)
					(arc
						(start 329.920346 -45.91812)
						(mid 329.772564 -45.838318)
						(end 329.692762 -45.690536)
					)
				)
			)
		)
		(zone
			(layer "F.Cu")
			(hatch none 0.5)
			(connect_pads
				(clearance 0)
			)
			(min_thickness 0.25)
			(keepout
				(tracks not_allowed)
				(vias allowed)
				(pads allowed)
				(copperpour not_allowed)
				(footprints allowed)
			)
			(placement
				(enabled no)
				(sheetname "")
			)
			(fill
				(thermal_gap 0.5)
				(thermal_bridge_width 0.5)
				(island_removal_mode 0)
			)
			(polygon
				(pts
					(arc
						(start 329.798172 -44.750736)
						(mid 329.844687 -44.826478)
						(end 329.920346 -44.873164)
					)
					(arc
						(start 329.920346 -44.97832)
						(mid 329.772564 -44.898518)
						(end 329.692762 -44.750736)
					)
				)
			)
		)
		(zone
			(layer "F.Cu")
			(hatch none 0.5)
			(connect_pads
				(clearance 0)
			)
			(min_thickness 0.25)
			(keepout
				(tracks not_allowed)
				(vias allowed)
				(pads allowed)
				(copperpour not_allowed)
				(footprints allowed)
			)
			(placement
				(enabled no)
				(sheetname "")
			)
			(fill
				(thermal_gap 0.5)
				(thermal_bridge_width 0.5)
				(island_removal_mode 0)
			)
			(polygon
				(pts
					(arc
						(start 329.798172 -43.810936)
						(mid 329.844687 -43.886678)
						(end 329.920346 -43.933364)
					)
					(arc
						(start 329.920346 -44.03852)
						(mid 329.772564 -43.958718)
						(end 329.692762 -43.810936)
					)
				)
			)
		)
		(zone
			(layer "F.Cu")
			(hatch none 0.5)
			(connect_pads
				(clearance 0)
			)
			(min_thickness 0.25)
			(keepout
				(tracks not_allowed)
				(vias allowed)
				(pads allowed)
				(copperpour not_allowed)
				(footprints allowed)
			)
			(placement
				(enabled no)
				(sheetname "")
			)
			(fill
				(thermal_gap 0.5)
				(thermal_bridge_width 0.5)
				(island_removal_mode 0)
			)
			(polygon
				(pts
					(arc
						(start 329.798172 -42.871136)
						(mid 329.844687 -42.946878)
						(end 329.920346 -42.993564)
					)
					(arc
						(start 329.920346 -43.09872)
						(mid 329.772564 -43.018918)
						(end 329.692762 -42.871136)
					)
				)
			)
		)
		(zone
			(layer "F.Cu")
			(hatch none 0.5)
			(connect_pads
				(clearance 0)
			)
			(min_thickness 0.25)
			(keepout
				(tracks not_allowed)
				(vias allowed)
				(pads allowed)
				(copperpour not_allowed)
				(footprints allowed)
			)
			(placement
				(enabled no)
				(sheetname "")
			)
			(fill
				(thermal_gap 0.5)
				(thermal_bridge_width 0.5)
				(island_removal_mode 0)
			)
			(polygon
				(pts
					(arc
						(start 329.798172 -41.931336)
						(mid 329.844687 -42.007078)
						(end 329.920346 -42.053764)
					)
					(arc
						(start 329.920346 -42.15892)
						(mid 329.772564 -42.079118)
						(end 329.692762 -41.931336)
					)
				)
			)
		)
		(zone
			(layer "F.Cu")
			(hatch none 0.5)
			(connect_pads
				(clearance 0)
			)
			(min_thickness 0.25)
			(keepout
				(tracks not_allowed)
				(vias allowed)
				(pads allowed)
				(copperpour not_allowed)
				(footprints allowed)
			)
			(placement
				(enabled no)
				(sheetname "")
			)
			(fill
				(thermal_gap 0.5)
				(thermal_bridge_width 0.5)
				(island_removal_mode 0)
			)
			(polygon
				(pts
					(arc
						(start 329.798172 -40.991536)
						(mid 329.844687 -41.067278)
						(end 329.920346 -41.113964)
					)
					(arc
						(start 329.920346 -41.21912)
						(mid 329.772564 -41.139318)
						(end 329.692762 -40.991536)
					)
				)
			)
		)
		(zone
			(layer "F.Cu")
			(hatch none 0.5)
			(connect_pads
				(clearance 0)
			)
			(min_thickness 0.25)
			(keepout
				(tracks not_allowed)
				(vias allowed)
				(pads allowed)
				(copperpour not_allowed)
				(footprints allowed)
			)
			(placement
				(enabled no)
				(sheetname "")
			)
			(fill
				(thermal_gap 0.5)
				(thermal_bridge_width 0.5)
				(island_removal_mode 0)
			)
			(polygon
				(pts
					(arc
						(start 329.798172 -40.051736)
						(mid 329.844687 -40.127478)
						(end 329.920346 -40.174164)
					)
					(arc
						(start 329.920346 -40.27932)
						(mid 329.772564 -40.199518)
						(end 329.692762 -40.051736)
					)
				)
			)
		)
		(zone
			(layer "F.Cu")
			(hatch none 0.5)
			(connect_pads
				(clearance 0)
			)
			(min_thickness 0.25)
			(keepout
				(tracks not_allowed)
				(vias allowed)
				(pads allowed)
				(copperpour not_allowed)
				(footprints allowed)
			)
			(placement
				(enabled no)
				(sheetname "")
			)
			(fill
				(thermal_gap 0.5)
				(thermal_bridge_width 0.5)
				(island_removal_mode 0)
			)
			(polygon
				(pts
					(arc
						(start 329.920346 -56.726328)
						(mid 329.844631 -56.772958)
						(end 329.798172 -56.848756)
					)
					(arc
						(start 329.692762 -56.848756)
						(mid 329.772564 -56.700974)
						(end 329.920346 -56.621172)
					)
				)
			)
		)
		(zone
			(layer "F.Cu")
			(hatch none 0.5)
			(connect_pads
				(clearance 0)
			)
			(min_thickness 0.25)
			(keepout
				(tracks not_allowed)
				(vias allowed)
				(pads allowed)
				(copperpour not_allowed)
				(footprints allowed)
			)
			(placement
				(enabled no)
				(sheetname "")
			)
			(fill
				(thermal_gap 0.5)
				(thermal_bridge_width 0.5)
				(island_removal_mode 0)
			)
			(polygon
				(pts
					(arc
						(start 329.920346 -55.786528)
						(mid 329.844631 -55.833158)
						(end 329.798172 -55.908956)
					)
					(arc
						(start 329.692762 -55.908956)
						(mid 329.772564 -55.761174)
						(end 329.920346 -55.681372)
					)
				)
			)
		)
		(zone
			(layer "F.Cu")
			(hatch none 0.5)
			(connect_pads
				(clearance 0)
			)
			(min_thickness 0.25)
			(keepout
				(tracks not_allowed)
				(vias allowed)
				(pads allowed)
				(copperpour not_allowed)
				(footprints allowed)
			)
			(placement
				(enabled no)
				(sheetname "")
			)
			(fill
				(thermal_gap 0.5)
				(thermal_bridge_width 0.5)
				(island_removal_mode 0)
			)
			(polygon
				(pts
					(arc
						(start 329.920346 -54.846728)
						(mid 329.844631 -54.893358)
						(end 329.798172 -54.969156)
					)
					(arc
						(start 329.692762 -54.969156)
						(mid 329.772564 -54.821374)
						(end 329.920346 -54.741572)
					)
				)
			)
		)
		(zone
			(layer "F.Cu")
			(hatch none 0.5)
			(connect_pads
				(clearance 0)
			)
			(min_thickness 0.25)
			(keepout
				(tracks not_allowed)
				(vias allowed)
				(pads allowed)
				(copperpour not_allowed)
				(footprints allowed)
			)
			(placement
				(enabled no)
				(sheetname "")
			)
			(fill
				(thermal_gap 0.5)
				(thermal_bridge_width 0.5)
				(island_removal_mode 0)
			)
			(polygon
				(pts
					(arc
						(start 329.920346 -53.906928)
						(mid 329.844631 -53.953558)
						(end 329.798172 -54.029356)
					)
					(arc
						(start 329.692762 -54.029356)
						(mid 329.772564 -53.881574)
						(end 329.920346 -53.801772)
					)
				)
			)
		)
		(zone
			(layer "F.Cu")
			(hatch none 0.5)
			(connect_pads
				(clearance 0)
			)
			(min_thickness 0.25)
			(keepout
				(tracks not_allowed)
				(vias allowed)
				(pads allowed)
				(copperpour not_allowed)
				(footprints allowed)
			)
			(placement
				(enabled no)
				(sheetname "")
			)
			(fill
				(thermal_gap 0.5)
				(thermal_bridge_width 0.5)
				(island_removal_mode 0)
			)
			(polygon
				(pts
					(arc
						(start 329.920346 -52.967128)
						(mid 329.844631 -53.013758)
						(end 329.798172 -53.089556)
					)
					(arc
						(start 329.692762 -53.089556)
						(mid 329.772564 -52.941774)
						(end 329.920346 -52.861972)
					)
				)
			)
		)
		(zone
			(layer "F.Cu")
			(hatch none 0.5)
			(connect_pads
				(clearance 0)
			)
			(min_thickness 0.25)
			(keepout
				(tracks not_allowed)
				(vias allowed)
				(pads allowed)
				(copperpour not_allowed)
				(footprints allowed)
			)
			(placement
				(enabled no)
				(sheetname "")
			)
			(fill
				(thermal_gap 0.5)
				(thermal_bridge_width 0.5)
				(island_removal_mode 0)
			)
			(polygon
				(pts
					(arc
						(start 329.920346 -52.027328)
						(mid 329.844631 -52.073958)
						(end 329.798172 -52.149756)
					)
					(arc
						(start 329.692762 -52.149756)
						(mid 329.772564 -52.001974)
						(end 329.920346 -51.922172)
					)
				)
			)
		)
		(zone
			(layer "F.Cu")
			(hatch none 0.5)
			(connect_pads
				(clearance 0)
			)
			(min_thickness 0.25)
			(keepout
				(tracks not_allowed)
				(vias allowed)
				(pads allowed)
				(copperpour not_allowed)
				(footprints allowed)
			)
			(placement
				(enabled no)
				(sheetname "")
			)
			(fill
				(thermal_gap 0.5)
				(thermal_bridge_width 0.5)
				(island_removal_mode 0)
			)
			(polygon
				(pts
					(arc
						(start 329.920346 -51.087528)
						(mid 329.844631 -51.134158)
						(end 329.798172 -51.209956)
					)
					(arc
						(start 329.692762 -51.209956)
						(mid 329.772564 -51.062174)
						(end 329.920346 -50.982372)
					)
				)
			)
		)
		(zone
			(layer "F.Cu")
			(hatch none 0.5)
			(connect_pads
				(clearance 0)
			)
			(min_thickness 0.25)
			(keepout
				(tracks not_allowed)
				(vias allowed)
				(pads allowed)
				(copperpour not_allowed)
				(footprints allowed)
			)
			(placement
				(enabled no)
				(sheetname "")
			)
			(fill
				(thermal_gap 0.5)
				(thermal_bridge_width 0.5)
				(island_removal_mode 0)
			)
			(polygon
				(pts
					(arc
						(start 329.920346 -50.147728)
						(mid 329.844631 -50.194358)
						(end 329.798172 -50.270156)
					)
					(arc
						(start 329.692762 -50.270156)
						(mid 329.772564 -50.122374)
						(end 329.920346 -50.042572)
					)
				)
			)
		)
		(zone
			(layer "F.Cu")
			(hatch none 0.5)
			(connect_pads
				(clearance 0)
			)
			(min_thickness 0.25)
			(keepout
				(tracks not_allowed)
				(vias allowed)
				(pads allowed)
				(copperpour not_allowed)
				(footprints allowed)
			)
			(placement
				(enabled no)
				(sheetname "")
			)
			(fill
				(thermal_gap 0.5)
				(thermal_bridge_width 0.5)
				(island_removal_mode 0)
			)
			(polygon
				(pts
					(arc
						(start 329.920346 -49.207928)
						(mid 329.844631 -49.254558)
						(end 329.798172 -49.330356)
					)
					(arc
						(start 329.692762 -49.330356)
						(mid 329.772564 -49.182574)
						(end 329.920346 -49.102772)
					)
				)
			)
		)
		(zone
			(layer "F.Cu")
			(hatch none 0.5)
			(connect_pads
				(clearance 0)
			)
			(min_thickness 0.25)
			(keepout
				(tracks not_allowed)
				(vias allowed)
				(pads allowed)
				(copperpour not_allowed)
				(footprints allowed)
			)
			(placement
				(enabled no)
				(sheetname "")
			)
			(fill
				(thermal_gap 0.5)
				(thermal_bridge_width 0.5)
				(island_removal_mode 0)
			)
			(polygon
				(pts
					(arc
						(start 329.920346 -48.268128)
						(mid 329.844631 -48.314758)
						(end 329.798172 -48.390556)
					)
					(arc
						(start 329.692762 -48.390556)
						(mid 329.772564 -48.242774)
						(end 329.920346 -48.162972)
					)
				)
			)
		)
		(zone
			(layer "F.Cu")
			(hatch none 0.5)
			(connect_pads
				(clearance 0)
			)
			(min_thickness 0.25)
			(keepout
				(tracks not_allowed)
				(vias allowed)
				(pads allowed)
				(copperpour not_allowed)
				(footprints allowed)
			)
			(placement
				(enabled no)
				(sheetname "")
			)
			(fill
				(thermal_gap 0.5)
				(thermal_bridge_width 0.5)
				(island_removal_mode 0)
			)
			(polygon
				(pts
					(arc
						(start 329.920346 -47.328328)
						(mid 329.844631 -47.374958)
						(end 329.798172 -47.450756)
					)
					(arc
						(start 329.692762 -47.450756)
						(mid 329.772564 -47.302974)
						(end 329.920346 -47.223172)
					)
				)
			)
		)
		(zone
			(layer "F.Cu")
			(hatch none 0.5)
			(connect_pads
				(clearance 0)
			)
			(min_thickness 0.25)
			(keepout
				(tracks not_allowed)
				(vias allowed)
				(pads allowed)
				(copperpour not_allowed)
				(footprints allowed)
			)
			(placement
				(enabled no)
				(sheetname "")
			)
			(fill
				(thermal_gap 0.5)
				(thermal_bridge_width 0.5)
				(island_removal_mode 0)
			)
			(polygon
				(pts
					(arc
						(start 329.920346 -46.388528)
						(mid 329.844631 -46.435158)
						(end 329.798172 -46.510956)
					)
					(arc
						(start 329.692762 -46.510956)
						(mid 329.772564 -46.363174)
						(end 329.920346 -46.283372)
					)
				)
			)
		)
		(zone
			(layer "F.Cu")
			(hatch none 0.5)
			(connect_pads
				(clearance 0)
			)
			(min_thickness 0.25)
			(keepout
				(tracks not_allowed)
				(vias allowed)
				(pads allowed)
				(copperpour not_allowed)
				(footprints allowed)
			)
			(placement
				(enabled no)
				(sheetname "")
			)
			(fill
				(thermal_gap 0.5)
				(thermal_bridge_width 0.5)
				(island_removal_mode 0)
			)
			(polygon
				(pts
					(arc
						(start 329.920346 -45.448728)
						(mid 329.844631 -45.495358)
						(end 329.798172 -45.571156)
					)
					(arc
						(start 329.692762 -45.571156)
						(mid 329.772564 -45.423374)
						(end 329.920346 -45.343572)
					)
				)
			)
		)
		(zone
			(layer "F.Cu")
			(hatch none 0.5)
			(connect_pads
				(clearance 0)
			)
			(min_thickness 0.25)
			(keepout
				(tracks not_allowed)
				(vias allowed)
				(pads allowed)
				(copperpour not_allowed)
				(footprints allowed)
			)
			(placement
				(enabled no)
				(sheetname "")
			)
			(fill
				(thermal_gap 0.5)
				(thermal_bridge_width 0.5)
				(island_removal_mode 0)
			)
			(polygon
				(pts
					(arc
						(start 329.920346 -44.508928)
						(mid 329.844631 -44.555558)
						(end 329.798172 -44.631356)
					)
					(arc
						(start 329.692762 -44.631356)
						(mid 329.772564 -44.483574)
						(end 329.920346 -44.403772)
					)
				)
			)
		)
		(zone
			(layer "F.Cu")
			(hatch none 0.5)
			(connect_pads
				(clearance 0)
			)
			(min_thickness 0.25)
			(keepout
				(tracks not_allowed)
				(vias allowed)
				(pads allowed)
				(copperpour not_allowed)
				(footprints allowed)
			)
			(placement
				(enabled no)
				(sheetname "")
			)
			(fill
				(thermal_gap 0.5)
				(thermal_bridge_width 0.5)
				(island_removal_mode 0)
			)
			(polygon
				(pts
					(arc
						(start 329.920346 -43.569128)
						(mid 329.844631 -43.615758)
						(end 329.798172 -43.691556)
					)
					(arc
						(start 329.692762 -43.691556)
						(mid 329.772564 -43.543774)
						(end 329.920346 -43.463972)
					)
				)
			)
		)
		(zone
			(layer "F.Cu")
			(hatch none 0.5)
			(connect_pads
				(clearance 0)
			)
			(min_thickness 0.25)
			(keepout
				(tracks not_allowed)
				(vias allowed)
				(pads allowed)
				(copperpour not_allowed)
				(footprints allowed)
			)
			(placement
				(enabled no)
				(sheetname "")
			)
			(fill
				(thermal_gap 0.5)
				(thermal_bridge_width 0.5)
				(island_removal_mode 0)
			)
			(polygon
				(pts
					(arc
						(start 329.920346 -42.629328)
						(mid 329.844631 -42.675958)
						(end 329.798172 -42.751756)
					)
					(arc
						(start 329.692762 -42.751756)
						(mid 329.772564 -42.603974)
						(end 329.920346 -42.524172)
					)
				)
			)
		)
		(zone
			(layer "F.Cu")
			(hatch none 0.5)
			(connect_pads
				(clearance 0)
			)
			(min_thickness 0.25)
			(keepout
				(tracks not_allowed)
				(vias allowed)
				(pads allowed)
				(copperpour not_allowed)
				(footprints allowed)
			)
			(placement
				(enabled no)
				(sheetname "")
			)
			(fill
				(thermal_gap 0.5)
				(thermal_bridge_width 0.5)
				(island_removal_mode 0)
			)
			(polygon
				(pts
					(arc
						(start 329.920346 -41.689528)
						(mid 329.844631 -41.736158)
						(end 329.798172 -41.811956)
					)
					(arc
						(start 329.692762 -41.811956)
						(mid 329.772564 -41.664174)
						(end 329.920346 -41.584372)
					)
				)
			)
		)
		(zone
			(layer "F.Cu")
			(hatch none 0.5)
			(connect_pads
				(clearance 0)
			)
			(min_thickness 0.25)
			(keepout
				(tracks not_allowed)
				(vias allowed)
				(pads allowed)
				(copperpour not_allowed)
				(footprints allowed)
			)
			(placement
				(enabled no)
				(sheetname "")
			)
			(fill
				(thermal_gap 0.5)
				(thermal_bridge_width 0.5)
				(island_removal_mode 0)
			)
			(polygon
				(pts
					(arc
						(start 329.920346 -40.749728)
						(mid 329.844631 -40.796358)
						(end 329.798172 -40.872156)
					)
					(arc
						(start 329.692762 -40.872156)
						(mid 329.772564 -40.724374)
						(end 329.920346 -40.644572)
					)
				)
			)
		)
		(zone
			(layer "F.Cu")
			(hatch none 0.5)
			(connect_pads
				(clearance 0)
			)
			(min_thickness 0.25)
			(keepout
				(tracks not_allowed)
				(vias allowed)
				(pads allowed)
				(copperpour not_allowed)
				(footprints allowed)
			)
			(placement
				(enabled no)
				(sheetname "")
			)
			(fill
				(thermal_gap 0.5)
				(thermal_bridge_width 0.5)
				(island_removal_mode 0)
			)
			(polygon
				(pts
					(arc
						(start 329.920346 -39.809928)
						(mid 329.844631 -39.856558)
						(end 329.798172 -39.932356)
					)
					(arc
						(start 329.692762 -39.932356)
						(mid 329.772564 -39.784574)
						(end 329.920346 -39.704772)
					)
				)
			)
		)
		(zone
			(layer "F.Cu")
			(hatch none 0.5)
			(connect_pads
				(clearance 0)
			)
			(min_thickness 0.25)
			(keepout
				(tracks not_allowed)
				(vias allowed)
				(pads allowed)
				(copperpour not_allowed)
				(footprints allowed)
			)
			(placement
				(enabled no)
				(sheetname "")
			)
			(fill
				(thermal_gap 0.5)
				(thermal_bridge_width 0.5)
				(island_removal_mode 0)
			)
			(polygon
				(pts
					(arc
						(start 330.03998 -57.090564)
						(mid 330.115695 -57.043934)
						(end 330.162154 -56.968136)
					)
					(arc
						(start 330.267564 -56.968136)
						(mid 330.187762 -57.115918)
						(end 330.03998 -57.19572)
					)
				)
			)
		)
		(zone
			(layer "F.Cu")
			(hatch none 0.5)
			(connect_pads
				(clearance 0)
			)
			(min_thickness 0.25)
			(keepout
				(tracks not_allowed)
				(vias allowed)
				(pads allowed)
				(copperpour not_allowed)
				(footprints allowed)
			)
			(placement
				(enabled no)
				(sheetname "")
			)
			(fill
				(thermal_gap 0.5)
				(thermal_bridge_width 0.5)
				(island_removal_mode 0)
			)
			(polygon
				(pts
					(arc
						(start 330.03998 -56.150764)
						(mid 330.115695 -56.104134)
						(end 330.162154 -56.028336)
					)
					(arc
						(start 330.267564 -56.028336)
						(mid 330.187762 -56.176118)
						(end 330.03998 -56.25592)
					)
				)
			)
		)
		(zone
			(layer "F.Cu")
			(hatch none 0.5)
			(connect_pads
				(clearance 0)
			)
			(min_thickness 0.25)
			(keepout
				(tracks not_allowed)
				(vias allowed)
				(pads allowed)
				(copperpour not_allowed)
				(footprints allowed)
			)
			(placement
				(enabled no)
				(sheetname "")
			)
			(fill
				(thermal_gap 0.5)
				(thermal_bridge_width 0.5)
				(island_removal_mode 0)
			)
			(polygon
				(pts
					(arc
						(start 330.03998 -55.210964)
						(mid 330.115695 -55.164334)
						(end 330.162154 -55.088536)
					)
					(arc
						(start 330.267564 -55.088536)
						(mid 330.187762 -55.236318)
						(end 330.03998 -55.31612)
					)
				)
			)
		)
		(zone
			(layer "F.Cu")
			(hatch none 0.5)
			(connect_pads
				(clearance 0)
			)
			(min_thickness 0.25)
			(keepout
				(tracks not_allowed)
				(vias allowed)
				(pads allowed)
				(copperpour not_allowed)
				(footprints allowed)
			)
			(placement
				(enabled no)
				(sheetname "")
			)
			(fill
				(thermal_gap 0.5)
				(thermal_bridge_width 0.5)
				(island_removal_mode 0)
			)
			(polygon
				(pts
					(arc
						(start 330.03998 -54.271164)
						(mid 330.115695 -54.224534)
						(end 330.162154 -54.148736)
					)
					(arc
						(start 330.267564 -54.148736)
						(mid 330.187762 -54.296518)
						(end 330.03998 -54.37632)
					)
				)
			)
		)
		(zone
			(layer "F.Cu")
			(hatch none 0.5)
			(connect_pads
				(clearance 0)
			)
			(min_thickness 0.25)
			(keepout
				(tracks not_allowed)
				(vias allowed)
				(pads allowed)
				(copperpour not_allowed)
				(footprints allowed)
			)
			(placement
				(enabled no)
				(sheetname "")
			)
			(fill
				(thermal_gap 0.5)
				(thermal_bridge_width 0.5)
				(island_removal_mode 0)
			)
			(polygon
				(pts
					(arc
						(start 330.03998 -53.331364)
						(mid 330.115695 -53.284734)
						(end 330.162154 -53.208936)
					)
					(arc
						(start 330.267564 -53.208936)
						(mid 330.187762 -53.356718)
						(end 330.03998 -53.43652)
					)
				)
			)
		)
		(zone
			(layer "F.Cu")
			(hatch none 0.5)
			(connect_pads
				(clearance 0)
			)
			(min_thickness 0.25)
			(keepout
				(tracks not_allowed)
				(vias allowed)
				(pads allowed)
				(copperpour not_allowed)
				(footprints allowed)
			)
			(placement
				(enabled no)
				(sheetname "")
			)
			(fill
				(thermal_gap 0.5)
				(thermal_bridge_width 0.5)
				(island_removal_mode 0)
			)
			(polygon
				(pts
					(arc
						(start 330.03998 -52.391564)
						(mid 330.115695 -52.344934)
						(end 330.162154 -52.269136)
					)
					(arc
						(start 330.267564 -52.269136)
						(mid 330.187762 -52.416918)
						(end 330.03998 -52.49672)
					)
				)
			)
		)
		(zone
			(layer "F.Cu")
			(hatch none 0.5)
			(connect_pads
				(clearance 0)
			)
			(min_thickness 0.25)
			(keepout
				(tracks not_allowed)
				(vias allowed)
				(pads allowed)
				(copperpour not_allowed)
				(footprints allowed)
			)
			(placement
				(enabled no)
				(sheetname "")
			)
			(fill
				(thermal_gap 0.5)
				(thermal_bridge_width 0.5)
				(island_removal_mode 0)
			)
			(polygon
				(pts
					(arc
						(start 330.03998 -51.451764)
						(mid 330.115695 -51.405134)
						(end 330.162154 -51.329336)
					)
					(arc
						(start 330.267564 -51.329336)
						(mid 330.187762 -51.477118)
						(end 330.03998 -51.55692)
					)
				)
			)
		)
		(zone
			(layer "F.Cu")
			(hatch none 0.5)
			(connect_pads
				(clearance 0)
			)
			(min_thickness 0.25)
			(keepout
				(tracks not_allowed)
				(vias allowed)
				(pads allowed)
				(copperpour not_allowed)
				(footprints allowed)
			)
			(placement
				(enabled no)
				(sheetname "")
			)
			(fill
				(thermal_gap 0.5)
				(thermal_bridge_width 0.5)
				(island_removal_mode 0)
			)
			(polygon
				(pts
					(arc
						(start 330.03998 -50.511964)
						(mid 330.115695 -50.465334)
						(end 330.162154 -50.389536)
					)
					(arc
						(start 330.267564 -50.389536)
						(mid 330.187762 -50.537318)
						(end 330.03998 -50.61712)
					)
				)
			)
		)
		(zone
			(layer "F.Cu")
			(hatch none 0.5)
			(connect_pads
				(clearance 0)
			)
			(min_thickness 0.25)
			(keepout
				(tracks not_allowed)
				(vias allowed)
				(pads allowed)
				(copperpour not_allowed)
				(footprints allowed)
			)
			(placement
				(enabled no)
				(sheetname "")
			)
			(fill
				(thermal_gap 0.5)
				(thermal_bridge_width 0.5)
				(island_removal_mode 0)
			)
			(polygon
				(pts
					(arc
						(start 330.03998 -49.572164)
						(mid 330.115695 -49.525534)
						(end 330.162154 -49.449736)
					)
					(arc
						(start 330.267564 -49.449736)
						(mid 330.187762 -49.597518)
						(end 330.03998 -49.67732)
					)
				)
			)
		)
		(zone
			(layer "F.Cu")
			(hatch none 0.5)
			(connect_pads
				(clearance 0)
			)
			(min_thickness 0.25)
			(keepout
				(tracks not_allowed)
				(vias allowed)
				(pads allowed)
				(copperpour not_allowed)
				(footprints allowed)
			)
			(placement
				(enabled no)
				(sheetname "")
			)
			(fill
				(thermal_gap 0.5)
				(thermal_bridge_width 0.5)
				(island_removal_mode 0)
			)
			(polygon
				(pts
					(arc
						(start 330.03998 -48.632364)
						(mid 330.115695 -48.585734)
						(end 330.162154 -48.509936)
					)
					(arc
						(start 330.267564 -48.509936)
						(mid 330.187762 -48.657718)
						(end 330.03998 -48.73752)
					)
				)
			)
		)
		(zone
			(layer "F.Cu")
			(hatch none 0.5)
			(connect_pads
				(clearance 0)
			)
			(min_thickness 0.25)
			(keepout
				(tracks not_allowed)
				(vias allowed)
				(pads allowed)
				(copperpour not_allowed)
				(footprints allowed)
			)
			(placement
				(enabled no)
				(sheetname "")
			)
			(fill
				(thermal_gap 0.5)
				(thermal_bridge_width 0.5)
				(island_removal_mode 0)
			)
			(polygon
				(pts
					(arc
						(start 330.03998 -47.692564)
						(mid 330.115695 -47.645934)
						(end 330.162154 -47.570136)
					)
					(arc
						(start 330.267564 -47.570136)
						(mid 330.187762 -47.717918)
						(end 330.03998 -47.79772)
					)
				)
			)
		)
		(zone
			(layer "F.Cu")
			(hatch none 0.5)
			(connect_pads
				(clearance 0)
			)
			(min_thickness 0.25)
			(keepout
				(tracks not_allowed)
				(vias allowed)
				(pads allowed)
				(copperpour not_allowed)
				(footprints allowed)
			)
			(placement
				(enabled no)
				(sheetname "")
			)
			(fill
				(thermal_gap 0.5)
				(thermal_bridge_width 0.5)
				(island_removal_mode 0)
			)
			(polygon
				(pts
					(arc
						(start 330.03998 -46.752764)
						(mid 330.115695 -46.706134)
						(end 330.162154 -46.630336)
					)
					(arc
						(start 330.267564 -46.630336)
						(mid 330.187762 -46.778118)
						(end 330.03998 -46.85792)
					)
				)
			)
		)
		(zone
			(layer "F.Cu")
			(hatch none 0.5)
			(connect_pads
				(clearance 0)
			)
			(min_thickness 0.25)
			(keepout
				(tracks not_allowed)
				(vias allowed)
				(pads allowed)
				(copperpour not_allowed)
				(footprints allowed)
			)
			(placement
				(enabled no)
				(sheetname "")
			)
			(fill
				(thermal_gap 0.5)
				(thermal_bridge_width 0.5)
				(island_removal_mode 0)
			)
			(polygon
				(pts
					(arc
						(start 330.03998 -45.812964)
						(mid 330.115695 -45.766334)
						(end 330.162154 -45.690536)
					)
					(arc
						(start 330.267564 -45.690536)
						(mid 330.187762 -45.838318)
						(end 330.03998 -45.91812)
					)
				)
			)
		)
		(zone
			(layer "F.Cu")
			(hatch none 0.5)
			(connect_pads
				(clearance 0)
			)
			(min_thickness 0.25)
			(keepout
				(tracks not_allowed)
				(vias allowed)
				(pads allowed)
				(copperpour not_allowed)
				(footprints allowed)
			)
			(placement
				(enabled no)
				(sheetname "")
			)
			(fill
				(thermal_gap 0.5)
				(thermal_bridge_width 0.5)
				(island_removal_mode 0)
			)
			(polygon
				(pts
					(arc
						(start 330.03998 -44.873164)
						(mid 330.115695 -44.826534)
						(end 330.162154 -44.750736)
					)
					(arc
						(start 330.267564 -44.750736)
						(mid 330.187762 -44.898518)
						(end 330.03998 -44.97832)
					)
				)
			)
		)
		(zone
			(layer "F.Cu")
			(hatch none 0.5)
			(connect_pads
				(clearance 0)
			)
			(min_thickness 0.25)
			(keepout
				(tracks not_allowed)
				(vias allowed)
				(pads allowed)
				(copperpour not_allowed)
				(footprints allowed)
			)
			(placement
				(enabled no)
				(sheetname "")
			)
			(fill
				(thermal_gap 0.5)
				(thermal_bridge_width 0.5)
				(island_removal_mode 0)
			)
			(polygon
				(pts
					(arc
						(start 330.03998 -43.933364)
						(mid 330.115695 -43.886734)
						(end 330.162154 -43.810936)
					)
					(arc
						(start 330.267564 -43.810936)
						(mid 330.187762 -43.958718)
						(end 330.03998 -44.03852)
					)
				)
			)
		)
		(zone
			(layer "F.Cu")
			(hatch none 0.5)
			(connect_pads
				(clearance 0)
			)
			(min_thickness 0.25)
			(keepout
				(tracks not_allowed)
				(vias allowed)
				(pads allowed)
				(copperpour not_allowed)
				(footprints allowed)
			)
			(placement
				(enabled no)
				(sheetname "")
			)
			(fill
				(thermal_gap 0.5)
				(thermal_bridge_width 0.5)
				(island_removal_mode 0)
			)
			(polygon
				(pts
					(arc
						(start 330.03998 -42.993564)
						(mid 330.115695 -42.946934)
						(end 330.162154 -42.871136)
					)
					(arc
						(start 330.267564 -42.871136)
						(mid 330.187762 -43.018918)
						(end 330.03998 -43.09872)
					)
				)
			)
		)
		(zone
			(layer "F.Cu")
			(hatch none 0.5)
			(connect_pads
				(clearance 0)
			)
			(min_thickness 0.25)
			(keepout
				(tracks not_allowed)
				(vias allowed)
				(pads allowed)
				(copperpour not_allowed)
				(footprints allowed)
			)
			(placement
				(enabled no)
				(sheetname "")
			)
			(fill
				(thermal_gap 0.5)
				(thermal_bridge_width 0.5)
				(island_removal_mode 0)
			)
			(polygon
				(pts
					(arc
						(start 330.03998 -42.053764)
						(mid 330.115695 -42.007134)
						(end 330.162154 -41.931336)
					)
					(arc
						(start 330.267564 -41.931336)
						(mid 330.187762 -42.079118)
						(end 330.03998 -42.15892)
					)
				)
			)
		)
		(zone
			(layer "F.Cu")
			(hatch none 0.5)
			(connect_pads
				(clearance 0)
			)
			(min_thickness 0.25)
			(keepout
				(tracks not_allowed)
				(vias allowed)
				(pads allowed)
				(copperpour not_allowed)
				(footprints allowed)
			)
			(placement
				(enabled no)
				(sheetname "")
			)
			(fill
				(thermal_gap 0.5)
				(thermal_bridge_width 0.5)
				(island_removal_mode 0)
			)
			(polygon
				(pts
					(arc
						(start 330.03998 -41.113964)
						(mid 330.115695 -41.067334)
						(end 330.162154 -40.991536)
					)
					(arc
						(start 330.267564 -40.991536)
						(mid 330.187762 -41.139318)
						(end 330.03998 -41.21912)
					)
				)
			)
		)
		(zone
			(layer "F.Cu")
			(hatch none 0.5)
			(connect_pads
				(clearance 0)
			)
			(min_thickness 0.25)
			(keepout
				(tracks not_allowed)
				(vias allowed)
				(pads allowed)
				(copperpour not_allowed)
				(footprints allowed)
			)
			(placement
				(enabled no)
				(sheetname "")
			)
			(fill
				(thermal_gap 0.5)
				(thermal_bridge_width 0.5)
				(island_removal_mode 0)
			)
			(polygon
				(pts
					(arc
						(start 330.03998 -40.174164)
						(mid 330.115695 -40.127534)
						(end 330.162154 -40.051736)
					)
					(arc
						(start 330.267564 -40.051736)
						(mid 330.187762 -40.199518)
						(end 330.03998 -40.27932)
					)
				)
			)
		)
		(zone
			(layer "F.Cu")
			(hatch none 0.5)
			(connect_pads
				(clearance 0)
			)
			(min_thickness 0.25)
			(keepout
				(tracks not_allowed)
				(vias allowed)
				(pads allowed)
				(copperpour not_allowed)
				(footprints allowed)
			)
			(placement
				(enabled no)
				(sheetname "")
			)
			(fill
				(thermal_gap 0.5)
				(thermal_bridge_width 0.5)
				(island_removal_mode 0)
			)
			(polygon
				(pts
					(arc
						(start 330.162154 -56.848756)
						(mid 330.115639 -56.773014)
						(end 330.03998 -56.726328)
					)
					(arc
						(start 330.03998 -56.621172)
						(mid 330.187762 -56.700974)
						(end 330.267564 -56.848756)
					)
				)
			)
		)
		(zone
			(layer "F.Cu")
			(hatch none 0.5)
			(connect_pads
				(clearance 0)
			)
			(min_thickness 0.25)
			(keepout
				(tracks not_allowed)
				(vias allowed)
				(pads allowed)
				(copperpour not_allowed)
				(footprints allowed)
			)
			(placement
				(enabled no)
				(sheetname "")
			)
			(fill
				(thermal_gap 0.5)
				(thermal_bridge_width 0.5)
				(island_removal_mode 0)
			)
			(polygon
				(pts
					(arc
						(start 330.162154 -55.908956)
						(mid 330.115639 -55.833214)
						(end 330.03998 -55.786528)
					)
					(arc
						(start 330.03998 -55.681372)
						(mid 330.187762 -55.761174)
						(end 330.267564 -55.908956)
					)
				)
			)
		)
		(zone
			(layer "F.Cu")
			(hatch none 0.5)
			(connect_pads
				(clearance 0)
			)
			(min_thickness 0.25)
			(keepout
				(tracks not_allowed)
				(vias allowed)
				(pads allowed)
				(copperpour not_allowed)
				(footprints allowed)
			)
			(placement
				(enabled no)
				(sheetname "")
			)
			(fill
				(thermal_gap 0.5)
				(thermal_bridge_width 0.5)
				(island_removal_mode 0)
			)
			(polygon
				(pts
					(arc
						(start 330.162154 -54.969156)
						(mid 330.115639 -54.893414)
						(end 330.03998 -54.846728)
					)
					(arc
						(start 330.03998 -54.741572)
						(mid 330.187762 -54.821374)
						(end 330.267564 -54.969156)
					)
				)
			)
		)
		(zone
			(layer "F.Cu")
			(hatch none 0.5)
			(connect_pads
				(clearance 0)
			)
			(min_thickness 0.25)
			(keepout
				(tracks not_allowed)
				(vias allowed)
				(pads allowed)
				(copperpour not_allowed)
				(footprints allowed)
			)
			(placement
				(enabled no)
				(sheetname "")
			)
			(fill
				(thermal_gap 0.5)
				(thermal_bridge_width 0.5)
				(island_removal_mode 0)
			)
			(polygon
				(pts
					(arc
						(start 330.162154 -54.029356)
						(mid 330.115639 -53.953614)
						(end 330.03998 -53.906928)
					)
					(arc
						(start 330.03998 -53.801772)
						(mid 330.187762 -53.881574)
						(end 330.267564 -54.029356)
					)
				)
			)
		)
		(zone
			(layer "F.Cu")
			(hatch none 0.5)
			(connect_pads
				(clearance 0)
			)
			(min_thickness 0.25)
			(keepout
				(tracks not_allowed)
				(vias allowed)
				(pads allowed)
				(copperpour not_allowed)
				(footprints allowed)
			)
			(placement
				(enabled no)
				(sheetname "")
			)
			(fill
				(thermal_gap 0.5)
				(thermal_bridge_width 0.5)
				(island_removal_mode 0)
			)
			(polygon
				(pts
					(arc
						(start 330.162154 -53.089556)
						(mid 330.115639 -53.013814)
						(end 330.03998 -52.967128)
					)
					(arc
						(start 330.03998 -52.861972)
						(mid 330.187762 -52.941774)
						(end 330.267564 -53.089556)
					)
				)
			)
		)
		(zone
			(layer "F.Cu")
			(hatch none 0.5)
			(connect_pads
				(clearance 0)
			)
			(min_thickness 0.25)
			(keepout
				(tracks not_allowed)
				(vias allowed)
				(pads allowed)
				(copperpour not_allowed)
				(footprints allowed)
			)
			(placement
				(enabled no)
				(sheetname "")
			)
			(fill
				(thermal_gap 0.5)
				(thermal_bridge_width 0.5)
				(island_removal_mode 0)
			)
			(polygon
				(pts
					(arc
						(start 330.162154 -52.149756)
						(mid 330.115639 -52.074014)
						(end 330.03998 -52.027328)
					)
					(arc
						(start 330.03998 -51.922172)
						(mid 330.187762 -52.001974)
						(end 330.267564 -52.149756)
					)
				)
			)
		)
		(zone
			(layer "F.Cu")
			(hatch none 0.5)
			(connect_pads
				(clearance 0)
			)
			(min_thickness 0.25)
			(keepout
				(tracks not_allowed)
				(vias allowed)
				(pads allowed)
				(copperpour not_allowed)
				(footprints allowed)
			)
			(placement
				(enabled no)
				(sheetname "")
			)
			(fill
				(thermal_gap 0.5)
				(thermal_bridge_width 0.5)
				(island_removal_mode 0)
			)
			(polygon
				(pts
					(arc
						(start 330.162154 -51.209956)
						(mid 330.115639 -51.134214)
						(end 330.03998 -51.087528)
					)
					(arc
						(start 330.03998 -50.982372)
						(mid 330.187762 -51.062174)
						(end 330.267564 -51.209956)
					)
				)
			)
		)
		(zone
			(layer "F.Cu")
			(hatch none 0.5)
			(connect_pads
				(clearance 0)
			)
			(min_thickness 0.25)
			(keepout
				(tracks not_allowed)
				(vias allowed)
				(pads allowed)
				(copperpour not_allowed)
				(footprints allowed)
			)
			(placement
				(enabled no)
				(sheetname "")
			)
			(fill
				(thermal_gap 0.5)
				(thermal_bridge_width 0.5)
				(island_removal_mode 0)
			)
			(polygon
				(pts
					(arc
						(start 330.162154 -50.270156)
						(mid 330.115639 -50.194414)
						(end 330.03998 -50.147728)
					)
					(arc
						(start 330.03998 -50.042572)
						(mid 330.187762 -50.122374)
						(end 330.267564 -50.270156)
					)
				)
			)
		)
		(zone
			(layer "F.Cu")
			(hatch none 0.5)
			(connect_pads
				(clearance 0)
			)
			(min_thickness 0.25)
			(keepout
				(tracks not_allowed)
				(vias allowed)
				(pads allowed)
				(copperpour not_allowed)
				(footprints allowed)
			)
			(placement
				(enabled no)
				(sheetname "")
			)
			(fill
				(thermal_gap 0.5)
				(thermal_bridge_width 0.5)
				(island_removal_mode 0)
			)
			(polygon
				(pts
					(arc
						(start 330.162154 -49.330356)
						(mid 330.115639 -49.254614)
						(end 330.03998 -49.207928)
					)
					(arc
						(start 330.03998 -49.102772)
						(mid 330.187762 -49.182574)
						(end 330.267564 -49.330356)
					)
				)
			)
		)
		(zone
			(layer "F.Cu")
			(hatch none 0.5)
			(connect_pads
				(clearance 0)
			)
			(min_thickness 0.25)
			(keepout
				(tracks not_allowed)
				(vias allowed)
				(pads allowed)
				(copperpour not_allowed)
				(footprints allowed)
			)
			(placement
				(enabled no)
				(sheetname "")
			)
			(fill
				(thermal_gap 0.5)
				(thermal_bridge_width 0.5)
				(island_removal_mode 0)
			)
			(polygon
				(pts
					(arc
						(start 330.162154 -48.390556)
						(mid 330.115639 -48.314814)
						(end 330.03998 -48.268128)
					)
					(arc
						(start 330.03998 -48.162972)
						(mid 330.187762 -48.242774)
						(end 330.267564 -48.390556)
					)
				)
			)
		)
		(zone
			(layer "F.Cu")
			(hatch none 0.5)
			(connect_pads
				(clearance 0)
			)
			(min_thickness 0.25)
			(keepout
				(tracks not_allowed)
				(vias allowed)
				(pads allowed)
				(copperpour not_allowed)
				(footprints allowed)
			)
			(placement
				(enabled no)
				(sheetname "")
			)
			(fill
				(thermal_gap 0.5)
				(thermal_bridge_width 0.5)
				(island_removal_mode 0)
			)
			(polygon
				(pts
					(arc
						(start 330.162154 -47.450756)
						(mid 330.115639 -47.375014)
						(end 330.03998 -47.328328)
					)
					(arc
						(start 330.03998 -47.223172)
						(mid 330.187762 -47.302974)
						(end 330.267564 -47.450756)
					)
				)
			)
		)
		(zone
			(layer "F.Cu")
			(hatch none 0.5)
			(connect_pads
				(clearance 0)
			)
			(min_thickness 0.25)
			(keepout
				(tracks not_allowed)
				(vias allowed)
				(pads allowed)
				(copperpour not_allowed)
				(footprints allowed)
			)
			(placement
				(enabled no)
				(sheetname "")
			)
			(fill
				(thermal_gap 0.5)
				(thermal_bridge_width 0.5)
				(island_removal_mode 0)
			)
			(polygon
				(pts
					(arc
						(start 330.162154 -46.510956)
						(mid 330.115639 -46.435214)
						(end 330.03998 -46.388528)
					)
					(arc
						(start 330.03998 -46.283372)
						(mid 330.187762 -46.363174)
						(end 330.267564 -46.510956)
					)
				)
			)
		)
		(zone
			(layer "F.Cu")
			(hatch none 0.5)
			(connect_pads
				(clearance 0)
			)
			(min_thickness 0.25)
			(keepout
				(tracks not_allowed)
				(vias allowed)
				(pads allowed)
				(copperpour not_allowed)
				(footprints allowed)
			)
			(placement
				(enabled no)
				(sheetname "")
			)
			(fill
				(thermal_gap 0.5)
				(thermal_bridge_width 0.5)
				(island_removal_mode 0)
			)
			(polygon
				(pts
					(arc
						(start 330.162154 -45.571156)
						(mid 330.115639 -45.495414)
						(end 330.03998 -45.448728)
					)
					(arc
						(start 330.03998 -45.343572)
						(mid 330.187762 -45.423374)
						(end 330.267564 -45.571156)
					)
				)
			)
		)
		(zone
			(layer "F.Cu")
			(hatch none 0.5)
			(connect_pads
				(clearance 0)
			)
			(min_thickness 0.25)
			(keepout
				(tracks not_allowed)
				(vias allowed)
				(pads allowed)
				(copperpour not_allowed)
				(footprints allowed)
			)
			(placement
				(enabled no)
				(sheetname "")
			)
			(fill
				(thermal_gap 0.5)
				(thermal_bridge_width 0.5)
				(island_removal_mode 0)
			)
			(polygon
				(pts
					(arc
						(start 330.162154 -44.631356)
						(mid 330.115639 -44.555614)
						(end 330.03998 -44.508928)
					)
					(arc
						(start 330.03998 -44.403772)
						(mid 330.187762 -44.483574)
						(end 330.267564 -44.631356)
					)
				)
			)
		)
		(zone
			(layer "F.Cu")
			(hatch none 0.5)
			(connect_pads
				(clearance 0)
			)
			(min_thickness 0.25)
			(keepout
				(tracks not_allowed)
				(vias allowed)
				(pads allowed)
				(copperpour not_allowed)
				(footprints allowed)
			)
			(placement
				(enabled no)
				(sheetname "")
			)
			(fill
				(thermal_gap 0.5)
				(thermal_bridge_width 0.5)
				(island_removal_mode 0)
			)
			(polygon
				(pts
					(arc
						(start 330.162154 -43.691556)
						(mid 330.115639 -43.615814)
						(end 330.03998 -43.569128)
					)
					(arc
						(start 330.03998 -43.463972)
						(mid 330.187762 -43.543774)
						(end 330.267564 -43.691556)
					)
				)
			)
		)
		(zone
			(layer "F.Cu")
			(hatch none 0.5)
			(connect_pads
				(clearance 0)
			)
			(min_thickness 0.25)
			(keepout
				(tracks not_allowed)
				(vias allowed)
				(pads allowed)
				(copperpour not_allowed)
				(footprints allowed)
			)
			(placement
				(enabled no)
				(sheetname "")
			)
			(fill
				(thermal_gap 0.5)
				(thermal_bridge_width 0.5)
				(island_removal_mode 0)
			)
			(polygon
				(pts
					(arc
						(start 330.162154 -42.751756)
						(mid 330.115639 -42.676014)
						(end 330.03998 -42.629328)
					)
					(arc
						(start 330.03998 -42.524172)
						(mid 330.187762 -42.603974)
						(end 330.267564 -42.751756)
					)
				)
			)
		)
		(zone
			(layer "F.Cu")
			(hatch none 0.5)
			(connect_pads
				(clearance 0)
			)
			(min_thickness 0.25)
			(keepout
				(tracks not_allowed)
				(vias allowed)
				(pads allowed)
				(copperpour not_allowed)
				(footprints allowed)
			)
			(placement
				(enabled no)
				(sheetname "")
			)
			(fill
				(thermal_gap 0.5)
				(thermal_bridge_width 0.5)
				(island_removal_mode 0)
			)
			(polygon
				(pts
					(arc
						(start 330.162154 -41.811956)
						(mid 330.115639 -41.736214)
						(end 330.03998 -41.689528)
					)
					(arc
						(start 330.03998 -41.584372)
						(mid 330.187762 -41.664174)
						(end 330.267564 -41.811956)
					)
				)
			)
		)
		(zone
			(layer "F.Cu")
			(hatch none 0.5)
			(connect_pads
				(clearance 0)
			)
			(min_thickness 0.25)
			(keepout
				(tracks not_allowed)
				(vias allowed)
				(pads allowed)
				(copperpour not_allowed)
				(footprints allowed)
			)
			(placement
				(enabled no)
				(sheetname "")
			)
			(fill
				(thermal_gap 0.5)
				(thermal_bridge_width 0.5)
				(island_removal_mode 0)
			)
			(polygon
				(pts
					(arc
						(start 330.162154 -40.872156)
						(mid 330.115639 -40.796414)
						(end 330.03998 -40.749728)
					)
					(arc
						(start 330.03998 -40.644572)
						(mid 330.187762 -40.724374)
						(end 330.267564 -40.872156)
					)
				)
			)
		)
		(zone
			(layer "F.Cu")
			(hatch none 0.5)
			(connect_pads
				(clearance 0)
			)
			(min_thickness 0.25)
			(keepout
				(tracks not_allowed)
				(vias allowed)
				(pads allowed)
				(copperpour not_allowed)
				(footprints allowed)
			)
			(placement
				(enabled no)
				(sheetname "")
			)
			(fill
				(thermal_gap 0.5)
				(thermal_bridge_width 0.5)
				(island_removal_mode 0)
			)
			(polygon
				(pts
					(arc
						(start 330.162154 -39.932356)
						(mid 330.115639 -39.856614)
						(end 330.03998 -39.809928)
					)
					(arc
						(start 330.03998 -39.704772)
						(mid 330.187762 -39.784574)
						(end 330.267564 -39.932356)
					)
				)
			)
		)
		(zone
			(layer "F.Cu")
			(hatch none 0.5)
			(connect_pads
				(clearance 0)
			)
			(min_thickness 0.25)
			(keepout
				(tracks not_allowed)
				(vias allowed)
				(pads allowed)
				(copperpour not_allowed)
				(footprints allowed)
			)
			(placement
				(enabled no)
				(sheetname "")
			)
			(fill
				(thermal_gap 0.5)
				(thermal_bridge_width 0.5)
				(island_removal_mode 0)
			)
			(polygon
				(pts
					(arc
						(start 330.611988 -56.498236)
						(mid 330.658589 -56.574063)
						(end 330.734416 -56.620664)
					)
					(arc
						(start 330.734416 -56.72582)
						(mid 330.586634 -56.646018)
						(end 330.506832 -56.498236)
					)
				)
			)
		)
		(zone
			(layer "F.Cu")
			(hatch none 0.5)
			(connect_pads
				(clearance 0)
			)
			(min_thickness 0.25)
			(keepout
				(tracks not_allowed)
				(vias allowed)
				(pads allowed)
				(copperpour not_allowed)
				(footprints allowed)
			)
			(placement
				(enabled no)
				(sheetname "")
			)
			(fill
				(thermal_gap 0.5)
				(thermal_bridge_width 0.5)
				(island_removal_mode 0)
			)
			(polygon
				(pts
					(arc
						(start 330.611988 -55.558436)
						(mid 330.658589 -55.634263)
						(end 330.734416 -55.680864)
					)
					(arc
						(start 330.734416 -55.78602)
						(mid 330.586634 -55.706218)
						(end 330.506832 -55.558436)
					)
				)
			)
		)
		(zone
			(layer "F.Cu")
			(hatch none 0.5)
			(connect_pads
				(clearance 0)
			)
			(min_thickness 0.25)
			(keepout
				(tracks not_allowed)
				(vias allowed)
				(pads allowed)
				(copperpour not_allowed)
				(footprints allowed)
			)
			(placement
				(enabled no)
				(sheetname "")
			)
			(fill
				(thermal_gap 0.5)
				(thermal_bridge_width 0.5)
				(island_removal_mode 0)
			)
			(polygon
				(pts
					(arc
						(start 330.611988 -54.618636)
						(mid 330.658589 -54.694463)
						(end 330.734416 -54.741064)
					)
					(arc
						(start 330.734416 -54.84622)
						(mid 330.586634 -54.766418)
						(end 330.506832 -54.618636)
					)
				)
			)
		)
		(zone
			(layer "F.Cu")
			(hatch none 0.5)
			(connect_pads
				(clearance 0)
			)
			(min_thickness 0.25)
			(keepout
				(tracks not_allowed)
				(vias allowed)
				(pads allowed)
				(copperpour not_allowed)
				(footprints allowed)
			)
			(placement
				(enabled no)
				(sheetname "")
			)
			(fill
				(thermal_gap 0.5)
				(thermal_bridge_width 0.5)
				(island_removal_mode 0)
			)
			(polygon
				(pts
					(arc
						(start 330.611988 -53.678836)
						(mid 330.658589 -53.754663)
						(end 330.734416 -53.801264)
					)
					(arc
						(start 330.734416 -53.90642)
						(mid 330.586634 -53.826618)
						(end 330.506832 -53.678836)
					)
				)
			)
		)
		(zone
			(layer "F.Cu")
			(hatch none 0.5)
			(connect_pads
				(clearance 0)
			)
			(min_thickness 0.25)
			(keepout
				(tracks not_allowed)
				(vias allowed)
				(pads allowed)
				(copperpour not_allowed)
				(footprints allowed)
			)
			(placement
				(enabled no)
				(sheetname "")
			)
			(fill
				(thermal_gap 0.5)
				(thermal_bridge_width 0.5)
				(island_removal_mode 0)
			)
			(polygon
				(pts
					(arc
						(start 330.611988 -52.739036)
						(mid 330.658589 -52.814863)
						(end 330.734416 -52.861464)
					)
					(arc
						(start 330.734416 -52.96662)
						(mid 330.586634 -52.886818)
						(end 330.506832 -52.739036)
					)
				)
			)
		)
		(zone
			(layer "F.Cu")
			(hatch none 0.5)
			(connect_pads
				(clearance 0)
			)
			(min_thickness 0.25)
			(keepout
				(tracks not_allowed)
				(vias allowed)
				(pads allowed)
				(copperpour not_allowed)
				(footprints allowed)
			)
			(placement
				(enabled no)
				(sheetname "")
			)
			(fill
				(thermal_gap 0.5)
				(thermal_bridge_width 0.5)
				(island_removal_mode 0)
			)
			(polygon
				(pts
					(arc
						(start 330.611988 -51.799236)
						(mid 330.658589 -51.875063)
						(end 330.734416 -51.921664)
					)
					(arc
						(start 330.734416 -52.02682)
						(mid 330.586634 -51.947018)
						(end 330.506832 -51.799236)
					)
				)
			)
		)
		(zone
			(layer "F.Cu")
			(hatch none 0.5)
			(connect_pads
				(clearance 0)
			)
			(min_thickness 0.25)
			(keepout
				(tracks not_allowed)
				(vias allowed)
				(pads allowed)
				(copperpour not_allowed)
				(footprints allowed)
			)
			(placement
				(enabled no)
				(sheetname "")
			)
			(fill
				(thermal_gap 0.5)
				(thermal_bridge_width 0.5)
				(island_removal_mode 0)
			)
			(polygon
				(pts
					(arc
						(start 330.611988 -50.859436)
						(mid 330.658589 -50.935263)
						(end 330.734416 -50.981864)
					)
					(arc
						(start 330.734416 -51.08702)
						(mid 330.586634 -51.007218)
						(end 330.506832 -50.859436)
					)
				)
			)
		)
		(zone
			(layer "F.Cu")
			(hatch none 0.5)
			(connect_pads
				(clearance 0)
			)
			(min_thickness 0.25)
			(keepout
				(tracks not_allowed)
				(vias allowed)
				(pads allowed)
				(copperpour not_allowed)
				(footprints allowed)
			)
			(placement
				(enabled no)
				(sheetname "")
			)
			(fill
				(thermal_gap 0.5)
				(thermal_bridge_width 0.5)
				(island_removal_mode 0)
			)
			(polygon
				(pts
					(arc
						(start 330.611988 -49.919636)
						(mid 330.658589 -49.995463)
						(end 330.734416 -50.042064)
					)
					(arc
						(start 330.734416 -50.14722)
						(mid 330.586634 -50.067418)
						(end 330.506832 -49.919636)
					)
				)
			)
		)
		(zone
			(layer "F.Cu")
			(hatch none 0.5)
			(connect_pads
				(clearance 0)
			)
			(min_thickness 0.25)
			(keepout
				(tracks not_allowed)
				(vias allowed)
				(pads allowed)
				(copperpour not_allowed)
				(footprints allowed)
			)
			(placement
				(enabled no)
				(sheetname "")
			)
			(fill
				(thermal_gap 0.5)
				(thermal_bridge_width 0.5)
				(island_removal_mode 0)
			)
			(polygon
				(pts
					(arc
						(start 330.611988 -48.979836)
						(mid 330.658589 -49.055663)
						(end 330.734416 -49.102264)
					)
					(arc
						(start 330.734416 -49.20742)
						(mid 330.586634 -49.127618)
						(end 330.506832 -48.979836)
					)
				)
			)
		)
		(zone
			(layer "F.Cu")
			(hatch none 0.5)
			(connect_pads
				(clearance 0)
			)
			(min_thickness 0.25)
			(keepout
				(tracks not_allowed)
				(vias allowed)
				(pads allowed)
				(copperpour not_allowed)
				(footprints allowed)
			)
			(placement
				(enabled no)
				(sheetname "")
			)
			(fill
				(thermal_gap 0.5)
				(thermal_bridge_width 0.5)
				(island_removal_mode 0)
			)
			(polygon
				(pts
					(arc
						(start 330.611988 -48.040036)
						(mid 330.658589 -48.115863)
						(end 330.734416 -48.162464)
					)
					(arc
						(start 330.734416 -48.26762)
						(mid 330.586634 -48.187818)
						(end 330.506832 -48.040036)
					)
				)
			)
		)
		(zone
			(layer "F.Cu")
			(hatch none 0.5)
			(connect_pads
				(clearance 0)
			)
			(min_thickness 0.25)
			(keepout
				(tracks not_allowed)
				(vias allowed)
				(pads allowed)
				(copperpour not_allowed)
				(footprints allowed)
			)
			(placement
				(enabled no)
				(sheetname "")
			)
			(fill
				(thermal_gap 0.5)
				(thermal_bridge_width 0.5)
				(island_removal_mode 0)
			)
			(polygon
				(pts
					(arc
						(start 330.612242 -47.100236)
						(mid 330.658843 -47.176063)
						(end 330.73467 -47.222664)
					)
					(arc
						(start 330.73467 -47.32782)
						(mid 330.586758 -47.248069)
						(end 330.506832 -47.100236)
					)
				)
			)
		)
		(zone
			(layer "F.Cu")
			(hatch none 0.5)
			(connect_pads
				(clearance 0)
			)
			(min_thickness 0.25)
			(keepout
				(tracks not_allowed)
				(vias allowed)
				(pads allowed)
				(copperpour not_allowed)
				(footprints allowed)
			)
			(placement
				(enabled no)
				(sheetname "")
			)
			(fill
				(thermal_gap 0.5)
				(thermal_bridge_width 0.5)
				(island_removal_mode 0)
			)
			(polygon
				(pts
					(arc
						(start 330.612242 -46.160436)
						(mid 330.658843 -46.236263)
						(end 330.73467 -46.282864)
					)
					(arc
						(start 330.73467 -46.38802)
						(mid 330.586758 -46.308269)
						(end 330.506832 -46.160436)
					)
				)
			)
		)
		(zone
			(layer "F.Cu")
			(hatch none 0.5)
			(connect_pads
				(clearance 0)
			)
			(min_thickness 0.25)
			(keepout
				(tracks not_allowed)
				(vias allowed)
				(pads allowed)
				(copperpour not_allowed)
				(footprints allowed)
			)
			(placement
				(enabled no)
				(sheetname "")
			)
			(fill
				(thermal_gap 0.5)
				(thermal_bridge_width 0.5)
				(island_removal_mode 0)
			)
			(polygon
				(pts
					(arc
						(start 330.612242 -45.220636)
						(mid 330.658843 -45.296463)
						(end 330.73467 -45.343064)
					)
					(arc
						(start 330.73467 -45.44822)
						(mid 330.586758 -45.368469)
						(end 330.506832 -45.220636)
					)
				)
			)
		)
		(zone
			(layer "F.Cu")
			(hatch none 0.5)
			(connect_pads
				(clearance 0)
			)
			(min_thickness 0.25)
			(keepout
				(tracks not_allowed)
				(vias allowed)
				(pads allowed)
				(copperpour not_allowed)
				(footprints allowed)
			)
			(placement
				(enabled no)
				(sheetname "")
			)
			(fill
				(thermal_gap 0.5)
				(thermal_bridge_width 0.5)
				(island_removal_mode 0)
			)
			(polygon
				(pts
					(arc
						(start 330.612242 -44.280836)
						(mid 330.658843 -44.356663)
						(end 330.73467 -44.403264)
					)
					(arc
						(start 330.73467 -44.50842)
						(mid 330.586758 -44.428669)
						(end 330.506832 -44.280836)
					)
				)
			)
		)
		(zone
			(layer "F.Cu")
			(hatch none 0.5)
			(connect_pads
				(clearance 0)
			)
			(min_thickness 0.25)
			(keepout
				(tracks not_allowed)
				(vias allowed)
				(pads allowed)
				(copperpour not_allowed)
				(footprints allowed)
			)
			(placement
				(enabled no)
				(sheetname "")
			)
			(fill
				(thermal_gap 0.5)
				(thermal_bridge_width 0.5)
				(island_removal_mode 0)
			)
			(polygon
				(pts
					(arc
						(start 330.612242 -43.341036)
						(mid 330.658843 -43.416863)
						(end 330.73467 -43.463464)
					)
					(arc
						(start 330.73467 -43.56862)
						(mid 330.586758 -43.488869)
						(end 330.506832 -43.341036)
					)
				)
			)
		)
		(zone
			(layer "F.Cu")
			(hatch none 0.5)
			(connect_pads
				(clearance 0)
			)
			(min_thickness 0.25)
			(keepout
				(tracks not_allowed)
				(vias allowed)
				(pads allowed)
				(copperpour not_allowed)
				(footprints allowed)
			)
			(placement
				(enabled no)
				(sheetname "")
			)
			(fill
				(thermal_gap 0.5)
				(thermal_bridge_width 0.5)
				(island_removal_mode 0)
			)
			(polygon
				(pts
					(arc
						(start 330.612242 -42.401236)
						(mid 330.658843 -42.477063)
						(end 330.73467 -42.523664)
					)
					(arc
						(start 330.73467 -42.62882)
						(mid 330.586758 -42.549069)
						(end 330.506832 -42.401236)
					)
				)
			)
		)
		(zone
			(layer "F.Cu")
			(hatch none 0.5)
			(connect_pads
				(clearance 0)
			)
			(min_thickness 0.25)
			(keepout
				(tracks not_allowed)
				(vias allowed)
				(pads allowed)
				(copperpour not_allowed)
				(footprints allowed)
			)
			(placement
				(enabled no)
				(sheetname "")
			)
			(fill
				(thermal_gap 0.5)
				(thermal_bridge_width 0.5)
				(island_removal_mode 0)
			)
			(polygon
				(pts
					(arc
						(start 330.612242 -41.461436)
						(mid 330.658843 -41.537263)
						(end 330.73467 -41.583864)
					)
					(arc
						(start 330.73467 -41.68902)
						(mid 330.586758 -41.609269)
						(end 330.506832 -41.461436)
					)
				)
			)
		)
		(zone
			(layer "F.Cu")
			(hatch none 0.5)
			(connect_pads
				(clearance 0)
			)
			(min_thickness 0.25)
			(keepout
				(tracks not_allowed)
				(vias allowed)
				(pads allowed)
				(copperpour not_allowed)
				(footprints allowed)
			)
			(placement
				(enabled no)
				(sheetname "")
			)
			(fill
				(thermal_gap 0.5)
				(thermal_bridge_width 0.5)
				(island_removal_mode 0)
			)
			(polygon
				(pts
					(arc
						(start 330.612242 -40.521636)
						(mid 330.658843 -40.597463)
						(end 330.73467 -40.644064)
					)
					(arc
						(start 330.73467 -40.74922)
						(mid 330.586758 -40.669469)
						(end 330.506832 -40.521636)
					)
				)
			)
		)
		(zone
			(layer "F.Cu")
			(hatch none 0.5)
			(connect_pads
				(clearance 0)
			)
			(min_thickness 0.25)
			(keepout
				(tracks not_allowed)
				(vias allowed)
				(pads allowed)
				(copperpour not_allowed)
				(footprints allowed)
			)
			(placement
				(enabled no)
				(sheetname "")
			)
			(fill
				(thermal_gap 0.5)
				(thermal_bridge_width 0.5)
				(island_removal_mode 0)
			)
			(polygon
				(pts
					(arc
						(start 330.734416 -56.256428)
						(mid 330.658589 -56.303029)
						(end 330.611988 -56.378856)
					)
					(arc
						(start 330.506832 -56.378856)
						(mid 330.586634 -56.231074)
						(end 330.734416 -56.151272)
					)
				)
			)
		)
		(zone
			(layer "F.Cu")
			(hatch none 0.5)
			(connect_pads
				(clearance 0)
			)
			(min_thickness 0.25)
			(keepout
				(tracks not_allowed)
				(vias allowed)
				(pads allowed)
				(copperpour not_allowed)
				(footprints allowed)
			)
			(placement
				(enabled no)
				(sheetname "")
			)
			(fill
				(thermal_gap 0.5)
				(thermal_bridge_width 0.5)
				(island_removal_mode 0)
			)
			(polygon
				(pts
					(arc
						(start 330.734416 -55.316628)
						(mid 330.658589 -55.363229)
						(end 330.611988 -55.439056)
					)
					(arc
						(start 330.506832 -55.439056)
						(mid 330.586634 -55.291274)
						(end 330.734416 -55.211472)
					)
				)
			)
		)
		(zone
			(layer "F.Cu")
			(hatch none 0.5)
			(connect_pads
				(clearance 0)
			)
			(min_thickness 0.25)
			(keepout
				(tracks not_allowed)
				(vias allowed)
				(pads allowed)
				(copperpour not_allowed)
				(footprints allowed)
			)
			(placement
				(enabled no)
				(sheetname "")
			)
			(fill
				(thermal_gap 0.5)
				(thermal_bridge_width 0.5)
				(island_removal_mode 0)
			)
			(polygon
				(pts
					(arc
						(start 330.734416 -54.376828)
						(mid 330.658589 -54.423429)
						(end 330.611988 -54.499256)
					)
					(arc
						(start 330.506832 -54.499256)
						(mid 330.586634 -54.351474)
						(end 330.734416 -54.271672)
					)
				)
			)
		)
		(zone
			(layer "F.Cu")
			(hatch none 0.5)
			(connect_pads
				(clearance 0)
			)
			(min_thickness 0.25)
			(keepout
				(tracks not_allowed)
				(vias allowed)
				(pads allowed)
				(copperpour not_allowed)
				(footprints allowed)
			)
			(placement
				(enabled no)
				(sheetname "")
			)
			(fill
				(thermal_gap 0.5)
				(thermal_bridge_width 0.5)
				(island_removal_mode 0)
			)
			(polygon
				(pts
					(arc
						(start 330.734416 -53.437028)
						(mid 330.658589 -53.483629)
						(end 330.611988 -53.559456)
					)
					(arc
						(start 330.506832 -53.559456)
						(mid 330.586634 -53.411674)
						(end 330.734416 -53.331872)
					)
				)
			)
		)
		(zone
			(layer "F.Cu")
			(hatch none 0.5)
			(connect_pads
				(clearance 0)
			)
			(min_thickness 0.25)
			(keepout
				(tracks not_allowed)
				(vias allowed)
				(pads allowed)
				(copperpour not_allowed)
				(footprints allowed)
			)
			(placement
				(enabled no)
				(sheetname "")
			)
			(fill
				(thermal_gap 0.5)
				(thermal_bridge_width 0.5)
				(island_removal_mode 0)
			)
			(polygon
				(pts
					(arc
						(start 330.734416 -52.497228)
						(mid 330.658589 -52.543829)
						(end 330.611988 -52.619656)
					)
					(arc
						(start 330.506832 -52.619656)
						(mid 330.586634 -52.471874)
						(end 330.734416 -52.392072)
					)
				)
			)
		)
		(zone
			(layer "F.Cu")
			(hatch none 0.5)
			(connect_pads
				(clearance 0)
			)
			(min_thickness 0.25)
			(keepout
				(tracks not_allowed)
				(vias allowed)
				(pads allowed)
				(copperpour not_allowed)
				(footprints allowed)
			)
			(placement
				(enabled no)
				(sheetname "")
			)
			(fill
				(thermal_gap 0.5)
				(thermal_bridge_width 0.5)
				(island_removal_mode 0)
			)
			(polygon
				(pts
					(arc
						(start 330.734416 -51.557428)
						(mid 330.658589 -51.604029)
						(end 330.611988 -51.679856)
					)
					(arc
						(start 330.506832 -51.679856)
						(mid 330.586634 -51.532074)
						(end 330.734416 -51.452272)
					)
				)
			)
		)
		(zone
			(layer "F.Cu")
			(hatch none 0.5)
			(connect_pads
				(clearance 0)
			)
			(min_thickness 0.25)
			(keepout
				(tracks not_allowed)
				(vias allowed)
				(pads allowed)
				(copperpour not_allowed)
				(footprints allowed)
			)
			(placement
				(enabled no)
				(sheetname "")
			)
			(fill
				(thermal_gap 0.5)
				(thermal_bridge_width 0.5)
				(island_removal_mode 0)
			)
			(polygon
				(pts
					(arc
						(start 330.734416 -50.617628)
						(mid 330.658589 -50.664229)
						(end 330.611988 -50.740056)
					)
					(arc
						(start 330.506832 -50.740056)
						(mid 330.586634 -50.592274)
						(end 330.734416 -50.512472)
					)
				)
			)
		)
		(zone
			(layer "F.Cu")
			(hatch none 0.5)
			(connect_pads
				(clearance 0)
			)
			(min_thickness 0.25)
			(keepout
				(tracks not_allowed)
				(vias allowed)
				(pads allowed)
				(copperpour not_allowed)
				(footprints allowed)
			)
			(placement
				(enabled no)
				(sheetname "")
			)
			(fill
				(thermal_gap 0.5)
				(thermal_bridge_width 0.5)
				(island_removal_mode 0)
			)
			(polygon
				(pts
					(arc
						(start 330.734416 -49.677828)
						(mid 330.658589 -49.724429)
						(end 330.611988 -49.800256)
					)
					(arc
						(start 330.506832 -49.800256)
						(mid 330.586634 -49.652474)
						(end 330.734416 -49.572672)
					)
				)
			)
		)
		(zone
			(layer "F.Cu")
			(hatch none 0.5)
			(connect_pads
				(clearance 0)
			)
			(min_thickness 0.25)
			(keepout
				(tracks not_allowed)
				(vias allowed)
				(pads allowed)
				(copperpour not_allowed)
				(footprints allowed)
			)
			(placement
				(enabled no)
				(sheetname "")
			)
			(fill
				(thermal_gap 0.5)
				(thermal_bridge_width 0.5)
				(island_removal_mode 0)
			)
			(polygon
				(pts
					(arc
						(start 330.734416 -48.738028)
						(mid 330.658589 -48.784629)
						(end 330.611988 -48.860456)
					)
					(arc
						(start 330.506832 -48.860456)
						(mid 330.586634 -48.712674)
						(end 330.734416 -48.632872)
					)
				)
			)
		)
		(zone
			(layer "F.Cu")
			(hatch none 0.5)
			(connect_pads
				(clearance 0)
			)
			(min_thickness 0.25)
			(keepout
				(tracks not_allowed)
				(vias allowed)
				(pads allowed)
				(copperpour not_allowed)
				(footprints allowed)
			)
			(placement
				(enabled no)
				(sheetname "")
			)
			(fill
				(thermal_gap 0.5)
				(thermal_bridge_width 0.5)
				(island_removal_mode 0)
			)
			(polygon
				(pts
					(arc
						(start 330.734416 -47.798228)
						(mid 330.658589 -47.844829)
						(end 330.611988 -47.920656)
					)
					(arc
						(start 330.506832 -47.920656)
						(mid 330.586634 -47.772874)
						(end 330.734416 -47.693072)
					)
				)
			)
		)
		(zone
			(layer "F.Cu")
			(hatch none 0.5)
			(connect_pads
				(clearance 0)
			)
			(min_thickness 0.25)
			(keepout
				(tracks not_allowed)
				(vias allowed)
				(pads allowed)
				(copperpour not_allowed)
				(footprints allowed)
			)
			(placement
				(enabled no)
				(sheetname "")
			)
			(fill
				(thermal_gap 0.5)
				(thermal_bridge_width 0.5)
				(island_removal_mode 0)
			)
			(polygon
				(pts
					(arc
						(start 330.73467 -46.858428)
						(mid 330.658843 -46.905029)
						(end 330.612242 -46.980856)
					)
					(arc
						(start 330.506832 -46.980856)
						(mid 330.586722 -46.832986)
						(end 330.73467 -46.753272)
					)
				)
			)
		)
		(zone
			(layer "F.Cu")
			(hatch none 0.5)
			(connect_pads
				(clearance 0)
			)
			(min_thickness 0.25)
			(keepout
				(tracks not_allowed)
				(vias allowed)
				(pads allowed)
				(copperpour not_allowed)
				(footprints allowed)
			)
			(placement
				(enabled no)
				(sheetname "")
			)
			(fill
				(thermal_gap 0.5)
				(thermal_bridge_width 0.5)
				(island_removal_mode 0)
			)
			(polygon
				(pts
					(arc
						(start 330.73467 -45.918628)
						(mid 330.658843 -45.965229)
						(end 330.612242 -46.041056)
					)
					(arc
						(start 330.506832 -46.041056)
						(mid 330.586722 -45.893186)
						(end 330.73467 -45.813472)
					)
				)
			)
		)
		(zone
			(layer "F.Cu")
			(hatch none 0.5)
			(connect_pads
				(clearance 0)
			)
			(min_thickness 0.25)
			(keepout
				(tracks not_allowed)
				(vias allowed)
				(pads allowed)
				(copperpour not_allowed)
				(footprints allowed)
			)
			(placement
				(enabled no)
				(sheetname "")
			)
			(fill
				(thermal_gap 0.5)
				(thermal_bridge_width 0.5)
				(island_removal_mode 0)
			)
			(polygon
				(pts
					(arc
						(start 330.73467 -44.978828)
						(mid 330.658843 -45.025429)
						(end 330.612242 -45.101256)
					)
					(arc
						(start 330.506832 -45.101256)
						(mid 330.586722 -44.953386)
						(end 330.73467 -44.873672)
					)
				)
			)
		)
		(zone
			(layer "F.Cu")
			(hatch none 0.5)
			(connect_pads
				(clearance 0)
			)
			(min_thickness 0.25)
			(keepout
				(tracks not_allowed)
				(vias allowed)
				(pads allowed)
				(copperpour not_allowed)
				(footprints allowed)
			)
			(placement
				(enabled no)
				(sheetname "")
			)
			(fill
				(thermal_gap 0.5)
				(thermal_bridge_width 0.5)
				(island_removal_mode 0)
			)
			(polygon
				(pts
					(arc
						(start 330.73467 -44.039028)
						(mid 330.658843 -44.085629)
						(end 330.612242 -44.161456)
					)
					(arc
						(start 330.506832 -44.161456)
						(mid 330.586722 -44.013586)
						(end 330.73467 -43.933872)
					)
				)
			)
		)
		(zone
			(layer "F.Cu")
			(hatch none 0.5)
			(connect_pads
				(clearance 0)
			)
			(min_thickness 0.25)
			(keepout
				(tracks not_allowed)
				(vias allowed)
				(pads allowed)
				(copperpour not_allowed)
				(footprints allowed)
			)
			(placement
				(enabled no)
				(sheetname "")
			)
			(fill
				(thermal_gap 0.5)
				(thermal_bridge_width 0.5)
				(island_removal_mode 0)
			)
			(polygon
				(pts
					(arc
						(start 330.73467 -43.099228)
						(mid 330.658843 -43.145829)
						(end 330.612242 -43.221656)
					)
					(arc
						(start 330.506832 -43.221656)
						(mid 330.586722 -43.073786)
						(end 330.73467 -42.994072)
					)
				)
			)
		)
		(zone
			(layer "F.Cu")
			(hatch none 0.5)
			(connect_pads
				(clearance 0)
			)
			(min_thickness 0.25)
			(keepout
				(tracks not_allowed)
				(vias allowed)
				(pads allowed)
				(copperpour not_allowed)
				(footprints allowed)
			)
			(placement
				(enabled no)
				(sheetname "")
			)
			(fill
				(thermal_gap 0.5)
				(thermal_bridge_width 0.5)
				(island_removal_mode 0)
			)
			(polygon
				(pts
					(arc
						(start 330.73467 -42.159428)
						(mid 330.658843 -42.206029)
						(end 330.612242 -42.281856)
					)
					(arc
						(start 330.506832 -42.281856)
						(mid 330.586722 -42.133986)
						(end 330.73467 -42.054272)
					)
				)
			)
		)
		(zone
			(layer "F.Cu")
			(hatch none 0.5)
			(connect_pads
				(clearance 0)
			)
			(min_thickness 0.25)
			(keepout
				(tracks not_allowed)
				(vias allowed)
				(pads allowed)
				(copperpour not_allowed)
				(footprints allowed)
			)
			(placement
				(enabled no)
				(sheetname "")
			)
			(fill
				(thermal_gap 0.5)
				(thermal_bridge_width 0.5)
				(island_removal_mode 0)
			)
			(polygon
				(pts
					(arc
						(start 330.73467 -41.219628)
						(mid 330.658843 -41.266229)
						(end 330.612242 -41.342056)
					)
					(arc
						(start 330.506832 -41.342056)
						(mid 330.586722 -41.194186)
						(end 330.73467 -41.114472)
					)
				)
			)
		)
		(zone
			(layer "F.Cu")
			(hatch none 0.5)
			(connect_pads
				(clearance 0)
			)
			(min_thickness 0.25)
			(keepout
				(tracks not_allowed)
				(vias allowed)
				(pads allowed)
				(copperpour not_allowed)
				(footprints allowed)
			)
			(placement
				(enabled no)
				(sheetname "")
			)
			(fill
				(thermal_gap 0.5)
				(thermal_bridge_width 0.5)
				(island_removal_mode 0)
			)
			(polygon
				(pts
					(arc
						(start 330.73467 -40.279828)
						(mid 330.658843 -40.326429)
						(end 330.612242 -40.402256)
					)
					(arc
						(start 330.506832 -40.402256)
						(mid 330.586722 -40.254386)
						(end 330.73467 -40.174672)
					)
				)
			)
		)
		(zone
			(layer "F.Cu")
			(hatch none 0.5)
			(connect_pads
				(clearance 0)
			)
			(min_thickness 0.25)
			(keepout
				(tracks not_allowed)
				(vias allowed)
				(pads allowed)
				(copperpour not_allowed)
				(footprints allowed)
			)
			(placement
				(enabled no)
				(sheetname "")
			)
			(fill
				(thermal_gap 0.5)
				(thermal_bridge_width 0.5)
				(island_removal_mode 0)
			)
			(polygon
				(pts
					(arc
						(start 330.853796 -56.620664)
						(mid 330.929623 -56.574063)
						(end 330.976224 -56.498236)
					)
					(arc
						(start 331.08138 -56.498236)
						(mid 331.001578 -56.646018)
						(end 330.853796 -56.72582)
					)
				)
			)
		)
		(zone
			(layer "F.Cu")
			(hatch none 0.5)
			(connect_pads
				(clearance 0)
			)
			(min_thickness 0.25)
			(keepout
				(tracks not_allowed)
				(vias allowed)
				(pads allowed)
				(copperpour not_allowed)
				(footprints allowed)
			)
			(placement
				(enabled no)
				(sheetname "")
			)
			(fill
				(thermal_gap 0.5)
				(thermal_bridge_width 0.5)
				(island_removal_mode 0)
			)
			(polygon
				(pts
					(arc
						(start 330.853796 -55.680864)
						(mid 330.929623 -55.634263)
						(end 330.976224 -55.558436)
					)
					(arc
						(start 331.08138 -55.558436)
						(mid 331.001578 -55.706218)
						(end 330.853796 -55.78602)
					)
				)
			)
		)
		(zone
			(layer "F.Cu")
			(hatch none 0.5)
			(connect_pads
				(clearance 0)
			)
			(min_thickness 0.25)
			(keepout
				(tracks not_allowed)
				(vias allowed)
				(pads allowed)
				(copperpour not_allowed)
				(footprints allowed)
			)
			(placement
				(enabled no)
				(sheetname "")
			)
			(fill
				(thermal_gap 0.5)
				(thermal_bridge_width 0.5)
				(island_removal_mode 0)
			)
			(polygon
				(pts
					(arc
						(start 330.853796 -54.741064)
						(mid 330.929623 -54.694463)
						(end 330.976224 -54.618636)
					)
					(arc
						(start 331.08138 -54.618636)
						(mid 331.001578 -54.766418)
						(end 330.853796 -54.84622)
					)
				)
			)
		)
		(zone
			(layer "F.Cu")
			(hatch none 0.5)
			(connect_pads
				(clearance 0)
			)
			(min_thickness 0.25)
			(keepout
				(tracks not_allowed)
				(vias allowed)
				(pads allowed)
				(copperpour not_allowed)
				(footprints allowed)
			)
			(placement
				(enabled no)
				(sheetname "")
			)
			(fill
				(thermal_gap 0.5)
				(thermal_bridge_width 0.5)
				(island_removal_mode 0)
			)
			(polygon
				(pts
					(arc
						(start 330.853796 -53.801264)
						(mid 330.929623 -53.754663)
						(end 330.976224 -53.678836)
					)
					(arc
						(start 331.08138 -53.678836)
						(mid 331.001578 -53.826618)
						(end 330.853796 -53.90642)
					)
				)
			)
		)
		(zone
			(layer "F.Cu")
			(hatch none 0.5)
			(connect_pads
				(clearance 0)
			)
			(min_thickness 0.25)
			(keepout
				(tracks not_allowed)
				(vias allowed)
				(pads allowed)
				(copperpour not_allowed)
				(footprints allowed)
			)
			(placement
				(enabled no)
				(sheetname "")
			)
			(fill
				(thermal_gap 0.5)
				(thermal_bridge_width 0.5)
				(island_removal_mode 0)
			)
			(polygon
				(pts
					(arc
						(start 330.853796 -52.861464)
						(mid 330.929623 -52.814863)
						(end 330.976224 -52.739036)
					)
					(arc
						(start 331.08138 -52.739036)
						(mid 331.001578 -52.886818)
						(end 330.853796 -52.96662)
					)
				)
			)
		)
		(zone
			(layer "F.Cu")
			(hatch none 0.5)
			(connect_pads
				(clearance 0)
			)
			(min_thickness 0.25)
			(keepout
				(tracks not_allowed)
				(vias allowed)
				(pads allowed)
				(copperpour not_allowed)
				(footprints allowed)
			)
			(placement
				(enabled no)
				(sheetname "")
			)
			(fill
				(thermal_gap 0.5)
				(thermal_bridge_width 0.5)
				(island_removal_mode 0)
			)
			(polygon
				(pts
					(arc
						(start 330.853796 -51.921664)
						(mid 330.929623 -51.875063)
						(end 330.976224 -51.799236)
					)
					(arc
						(start 331.08138 -51.799236)
						(mid 331.001578 -51.947018)
						(end 330.853796 -52.02682)
					)
				)
			)
		)
		(zone
			(layer "F.Cu")
			(hatch none 0.5)
			(connect_pads
				(clearance 0)
			)
			(min_thickness 0.25)
			(keepout
				(tracks not_allowed)
				(vias allowed)
				(pads allowed)
				(copperpour not_allowed)
				(footprints allowed)
			)
			(placement
				(enabled no)
				(sheetname "")
			)
			(fill
				(thermal_gap 0.5)
				(thermal_bridge_width 0.5)
				(island_removal_mode 0)
			)
			(polygon
				(pts
					(arc
						(start 330.853796 -50.981864)
						(mid 330.929623 -50.935263)
						(end 330.976224 -50.859436)
					)
					(arc
						(start 331.08138 -50.859436)
						(mid 331.001578 -51.007218)
						(end 330.853796 -51.08702)
					)
				)
			)
		)
		(zone
			(layer "F.Cu")
			(hatch none 0.5)
			(connect_pads
				(clearance 0)
			)
			(min_thickness 0.25)
			(keepout
				(tracks not_allowed)
				(vias allowed)
				(pads allowed)
				(copperpour not_allowed)
				(footprints allowed)
			)
			(placement
				(enabled no)
				(sheetname "")
			)
			(fill
				(thermal_gap 0.5)
				(thermal_bridge_width 0.5)
				(island_removal_mode 0)
			)
			(polygon
				(pts
					(arc
						(start 330.853796 -50.042064)
						(mid 330.929623 -49.995463)
						(end 330.976224 -49.919636)
					)
					(arc
						(start 331.08138 -49.919636)
						(mid 331.001578 -50.067418)
						(end 330.853796 -50.14722)
					)
				)
			)
		)
		(zone
			(layer "F.Cu")
			(hatch none 0.5)
			(connect_pads
				(clearance 0)
			)
			(min_thickness 0.25)
			(keepout
				(tracks not_allowed)
				(vias allowed)
				(pads allowed)
				(copperpour not_allowed)
				(footprints allowed)
			)
			(placement
				(enabled no)
				(sheetname "")
			)
			(fill
				(thermal_gap 0.5)
				(thermal_bridge_width 0.5)
				(island_removal_mode 0)
			)
			(polygon
				(pts
					(arc
						(start 330.853796 -49.102264)
						(mid 330.929623 -49.055663)
						(end 330.976224 -48.979836)
					)
					(arc
						(start 331.08138 -48.979836)
						(mid 331.001578 -49.127618)
						(end 330.853796 -49.20742)
					)
				)
			)
		)
		(zone
			(layer "F.Cu")
			(hatch none 0.5)
			(connect_pads
				(clearance 0)
			)
			(min_thickness 0.25)
			(keepout
				(tracks not_allowed)
				(vias allowed)
				(pads allowed)
				(copperpour not_allowed)
				(footprints allowed)
			)
			(placement
				(enabled no)
				(sheetname "")
			)
			(fill
				(thermal_gap 0.5)
				(thermal_bridge_width 0.5)
				(island_removal_mode 0)
			)
			(polygon
				(pts
					(arc
						(start 330.853796 -48.162464)
						(mid 330.929623 -48.115863)
						(end 330.976224 -48.040036)
					)
					(arc
						(start 331.08138 -48.040036)
						(mid 331.001578 -48.187818)
						(end 330.853796 -48.26762)
					)
				)
			)
		)
		(zone
			(layer "F.Cu")
			(hatch none 0.5)
			(connect_pads
				(clearance 0)
			)
			(min_thickness 0.25)
			(keepout
				(tracks not_allowed)
				(vias allowed)
				(pads allowed)
				(copperpour not_allowed)
				(footprints allowed)
			)
			(placement
				(enabled no)
				(sheetname "")
			)
			(fill
				(thermal_gap 0.5)
				(thermal_bridge_width 0.5)
				(island_removal_mode 0)
			)
			(polygon
				(pts
					(arc
						(start 330.85405 -47.222664)
						(mid 330.929877 -47.176063)
						(end 330.976478 -47.100236)
					)
					(arc
						(start 331.081634 -47.100236)
						(mid 331.001832 -47.248018)
						(end 330.85405 -47.32782)
					)
				)
			)
		)
		(zone
			(layer "F.Cu")
			(hatch none 0.5)
			(connect_pads
				(clearance 0)
			)
			(min_thickness 0.25)
			(keepout
				(tracks not_allowed)
				(vias allowed)
				(pads allowed)
				(copperpour not_allowed)
				(footprints allowed)
			)
			(placement
				(enabled no)
				(sheetname "")
			)
			(fill
				(thermal_gap 0.5)
				(thermal_bridge_width 0.5)
				(island_removal_mode 0)
			)
			(polygon
				(pts
					(arc
						(start 330.85405 -46.282864)
						(mid 330.929877 -46.236263)
						(end 330.976478 -46.160436)
					)
					(arc
						(start 331.081634 -46.160436)
						(mid 331.001832 -46.308218)
						(end 330.85405 -46.38802)
					)
				)
			)
		)
		(zone
			(layer "F.Cu")
			(hatch none 0.5)
			(connect_pads
				(clearance 0)
			)
			(min_thickness 0.25)
			(keepout
				(tracks not_allowed)
				(vias allowed)
				(pads allowed)
				(copperpour not_allowed)
				(footprints allowed)
			)
			(placement
				(enabled no)
				(sheetname "")
			)
			(fill
				(thermal_gap 0.5)
				(thermal_bridge_width 0.5)
				(island_removal_mode 0)
			)
			(polygon
				(pts
					(arc
						(start 330.85405 -45.343064)
						(mid 330.929877 -45.296463)
						(end 330.976478 -45.220636)
					)
					(arc
						(start 331.081634 -45.220636)
						(mid 331.001832 -45.368418)
						(end 330.85405 -45.44822)
					)
				)
			)
		)
		(zone
			(layer "F.Cu")
			(hatch none 0.5)
			(connect_pads
				(clearance 0)
			)
			(min_thickness 0.25)
			(keepout
				(tracks not_allowed)
				(vias allowed)
				(pads allowed)
				(copperpour not_allowed)
				(footprints allowed)
			)
			(placement
				(enabled no)
				(sheetname "")
			)
			(fill
				(thermal_gap 0.5)
				(thermal_bridge_width 0.5)
				(island_removal_mode 0)
			)
			(polygon
				(pts
					(arc
						(start 330.85405 -44.403264)
						(mid 330.929877 -44.356663)
						(end 330.976478 -44.280836)
					)
					(arc
						(start 331.081634 -44.280836)
						(mid 331.001832 -44.428618)
						(end 330.85405 -44.50842)
					)
				)
			)
		)
		(zone
			(layer "F.Cu")
			(hatch none 0.5)
			(connect_pads
				(clearance 0)
			)
			(min_thickness 0.25)
			(keepout
				(tracks not_allowed)
				(vias allowed)
				(pads allowed)
				(copperpour not_allowed)
				(footprints allowed)
			)
			(placement
				(enabled no)
				(sheetname "")
			)
			(fill
				(thermal_gap 0.5)
				(thermal_bridge_width 0.5)
				(island_removal_mode 0)
			)
			(polygon
				(pts
					(arc
						(start 330.85405 -43.463464)
						(mid 330.929877 -43.416863)
						(end 330.976478 -43.341036)
					)
					(arc
						(start 331.081634 -43.341036)
						(mid 331.001832 -43.488818)
						(end 330.85405 -43.56862)
					)
				)
			)
		)
		(zone
			(layer "F.Cu")
			(hatch none 0.5)
			(connect_pads
				(clearance 0)
			)
			(min_thickness 0.25)
			(keepout
				(tracks not_allowed)
				(vias allowed)
				(pads allowed)
				(copperpour not_allowed)
				(footprints allowed)
			)
			(placement
				(enabled no)
				(sheetname "")
			)
			(fill
				(thermal_gap 0.5)
				(thermal_bridge_width 0.5)
				(island_removal_mode 0)
			)
			(polygon
				(pts
					(arc
						(start 330.85405 -42.523664)
						(mid 330.929877 -42.477063)
						(end 330.976478 -42.401236)
					)
					(arc
						(start 331.081634 -42.401236)
						(mid 331.001832 -42.549018)
						(end 330.85405 -42.62882)
					)
				)
			)
		)
		(zone
			(layer "F.Cu")
			(hatch none 0.5)
			(connect_pads
				(clearance 0)
			)
			(min_thickness 0.25)
			(keepout
				(tracks not_allowed)
				(vias allowed)
				(pads allowed)
				(copperpour not_allowed)
				(footprints allowed)
			)
			(placement
				(enabled no)
				(sheetname "")
			)
			(fill
				(thermal_gap 0.5)
				(thermal_bridge_width 0.5)
				(island_removal_mode 0)
			)
			(polygon
				(pts
					(arc
						(start 330.85405 -41.583864)
						(mid 330.929877 -41.537263)
						(end 330.976478 -41.461436)
					)
					(arc
						(start 331.081634 -41.461436)
						(mid 331.001832 -41.609218)
						(end 330.85405 -41.68902)
					)
				)
			)
		)
		(zone
			(layer "F.Cu")
			(hatch none 0.5)
			(connect_pads
				(clearance 0)
			)
			(min_thickness 0.25)
			(keepout
				(tracks not_allowed)
				(vias allowed)
				(pads allowed)
				(copperpour not_allowed)
				(footprints allowed)
			)
			(placement
				(enabled no)
				(sheetname "")
			)
			(fill
				(thermal_gap 0.5)
				(thermal_bridge_width 0.5)
				(island_removal_mode 0)
			)
			(polygon
				(pts
					(arc
						(start 330.85405 -40.644064)
						(mid 330.929877 -40.597463)
						(end 330.976478 -40.521636)
					)
					(arc
						(start 331.081634 -40.521636)
						(mid 331.001832 -40.669418)
						(end 330.85405 -40.74922)
					)
				)
			)
		)
		(zone
			(layer "F.Cu")
			(hatch none 0.5)
			(connect_pads
				(clearance 0)
			)
			(min_thickness 0.25)
			(keepout
				(tracks not_allowed)
				(vias allowed)
				(pads allowed)
				(copperpour not_allowed)
				(footprints allowed)
			)
			(placement
				(enabled no)
				(sheetname "")
			)
			(fill
				(thermal_gap 0.5)
				(thermal_bridge_width 0.5)
				(island_removal_mode 0)
			)
			(polygon
				(pts
					(arc
						(start 330.976224 -56.378856)
						(mid 330.929623 -56.303029)
						(end 330.853796 -56.256428)
					)
					(arc
						(start 330.853796 -56.151272)
						(mid 331.001578 -56.231074)
						(end 331.08138 -56.378856)
					)
				)
			)
		)
		(zone
			(layer "F.Cu")
			(hatch none 0.5)
			(connect_pads
				(clearance 0)
			)
			(min_thickness 0.25)
			(keepout
				(tracks not_allowed)
				(vias allowed)
				(pads allowed)
				(copperpour not_allowed)
				(footprints allowed)
			)
			(placement
				(enabled no)
				(sheetname "")
			)
			(fill
				(thermal_gap 0.5)
				(thermal_bridge_width 0.5)
				(island_removal_mode 0)
			)
			(polygon
				(pts
					(arc
						(start 330.976224 -55.439056)
						(mid 330.929623 -55.363229)
						(end 330.853796 -55.316628)
					)
					(arc
						(start 330.853796 -55.211472)
						(mid 331.001578 -55.291274)
						(end 331.08138 -55.439056)
					)
				)
			)
		)
		(zone
			(layer "F.Cu")
			(hatch none 0.5)
			(connect_pads
				(clearance 0)
			)
			(min_thickness 0.25)
			(keepout
				(tracks not_allowed)
				(vias allowed)
				(pads allowed)
				(copperpour not_allowed)
				(footprints allowed)
			)
			(placement
				(enabled no)
				(sheetname "")
			)
			(fill
				(thermal_gap 0.5)
				(thermal_bridge_width 0.5)
				(island_removal_mode 0)
			)
			(polygon
				(pts
					(arc
						(start 330.976224 -54.499256)
						(mid 330.929623 -54.423429)
						(end 330.853796 -54.376828)
					)
					(arc
						(start 330.853796 -54.271672)
						(mid 331.001578 -54.351474)
						(end 331.08138 -54.499256)
					)
				)
			)
		)
		(zone
			(layer "F.Cu")
			(hatch none 0.5)
			(connect_pads
				(clearance 0)
			)
			(min_thickness 0.25)
			(keepout
				(tracks not_allowed)
				(vias allowed)
				(pads allowed)
				(copperpour not_allowed)
				(footprints allowed)
			)
			(placement
				(enabled no)
				(sheetname "")
			)
			(fill
				(thermal_gap 0.5)
				(thermal_bridge_width 0.5)
				(island_removal_mode 0)
			)
			(polygon
				(pts
					(arc
						(start 330.976224 -53.559456)
						(mid 330.929623 -53.483629)
						(end 330.853796 -53.437028)
					)
					(arc
						(start 330.853796 -53.331872)
						(mid 331.001578 -53.411674)
						(end 331.08138 -53.559456)
					)
				)
			)
		)
		(zone
			(layer "F.Cu")
			(hatch none 0.5)
			(connect_pads
				(clearance 0)
			)
			(min_thickness 0.25)
			(keepout
				(tracks not_allowed)
				(vias allowed)
				(pads allowed)
				(copperpour not_allowed)
				(footprints allowed)
			)
			(placement
				(enabled no)
				(sheetname "")
			)
			(fill
				(thermal_gap 0.5)
				(thermal_bridge_width 0.5)
				(island_removal_mode 0)
			)
			(polygon
				(pts
					(arc
						(start 330.976224 -52.619656)
						(mid 330.929623 -52.543829)
						(end 330.853796 -52.497228)
					)
					(arc
						(start 330.853796 -52.392072)
						(mid 331.001578 -52.471874)
						(end 331.08138 -52.619656)
					)
				)
			)
		)
		(zone
			(layer "F.Cu")
			(hatch none 0.5)
			(connect_pads
				(clearance 0)
			)
			(min_thickness 0.25)
			(keepout
				(tracks not_allowed)
				(vias allowed)
				(pads allowed)
				(copperpour not_allowed)
				(footprints allowed)
			)
			(placement
				(enabled no)
				(sheetname "")
			)
			(fill
				(thermal_gap 0.5)
				(thermal_bridge_width 0.5)
				(island_removal_mode 0)
			)
			(polygon
				(pts
					(arc
						(start 330.976224 -51.679856)
						(mid 330.929623 -51.604029)
						(end 330.853796 -51.557428)
					)
					(arc
						(start 330.853796 -51.452272)
						(mid 331.001578 -51.532074)
						(end 331.08138 -51.679856)
					)
				)
			)
		)
		(zone
			(layer "F.Cu")
			(hatch none 0.5)
			(connect_pads
				(clearance 0)
			)
			(min_thickness 0.25)
			(keepout
				(tracks not_allowed)
				(vias allowed)
				(pads allowed)
				(copperpour not_allowed)
				(footprints allowed)
			)
			(placement
				(enabled no)
				(sheetname "")
			)
			(fill
				(thermal_gap 0.5)
				(thermal_bridge_width 0.5)
				(island_removal_mode 0)
			)
			(polygon
				(pts
					(arc
						(start 330.976224 -50.740056)
						(mid 330.929623 -50.664229)
						(end 330.853796 -50.617628)
					)
					(arc
						(start 330.853796 -50.512472)
						(mid 331.001578 -50.592274)
						(end 331.08138 -50.740056)
					)
				)
			)
		)
		(zone
			(layer "F.Cu")
			(hatch none 0.5)
			(connect_pads
				(clearance 0)
			)
			(min_thickness 0.25)
			(keepout
				(tracks not_allowed)
				(vias allowed)
				(pads allowed)
				(copperpour not_allowed)
				(footprints allowed)
			)
			(placement
				(enabled no)
				(sheetname "")
			)
			(fill
				(thermal_gap 0.5)
				(thermal_bridge_width 0.5)
				(island_removal_mode 0)
			)
			(polygon
				(pts
					(arc
						(start 330.976224 -49.800256)
						(mid 330.929623 -49.724429)
						(end 330.853796 -49.677828)
					)
					(arc
						(start 330.853796 -49.572672)
						(mid 331.001578 -49.652474)
						(end 331.08138 -49.800256)
					)
				)
			)
		)
		(zone
			(layer "F.Cu")
			(hatch none 0.5)
			(connect_pads
				(clearance 0)
			)
			(min_thickness 0.25)
			(keepout
				(tracks not_allowed)
				(vias allowed)
				(pads allowed)
				(copperpour not_allowed)
				(footprints allowed)
			)
			(placement
				(enabled no)
				(sheetname "")
			)
			(fill
				(thermal_gap 0.5)
				(thermal_bridge_width 0.5)
				(island_removal_mode 0)
			)
			(polygon
				(pts
					(arc
						(start 330.976224 -48.860456)
						(mid 330.929623 -48.784629)
						(end 330.853796 -48.738028)
					)
					(arc
						(start 330.853796 -48.632872)
						(mid 331.001578 -48.712674)
						(end 331.08138 -48.860456)
					)
				)
			)
		)
		(zone
			(layer "F.Cu")
			(hatch none 0.5)
			(connect_pads
				(clearance 0)
			)
			(min_thickness 0.25)
			(keepout
				(tracks not_allowed)
				(vias allowed)
				(pads allowed)
				(copperpour not_allowed)
				(footprints allowed)
			)
			(placement
				(enabled no)
				(sheetname "")
			)
			(fill
				(thermal_gap 0.5)
				(thermal_bridge_width 0.5)
				(island_removal_mode 0)
			)
			(polygon
				(pts
					(arc
						(start 330.976224 -47.920656)
						(mid 330.929623 -47.844829)
						(end 330.853796 -47.798228)
					)
					(arc
						(start 330.853796 -47.693072)
						(mid 331.001578 -47.772874)
						(end 331.08138 -47.920656)
					)
				)
			)
		)
		(zone
			(layer "F.Cu")
			(hatch none 0.5)
			(connect_pads
				(clearance 0)
			)
			(min_thickness 0.25)
			(keepout
				(tracks not_allowed)
				(vias allowed)
				(pads allowed)
				(copperpour not_allowed)
				(footprints allowed)
			)
			(placement
				(enabled no)
				(sheetname "")
			)
			(fill
				(thermal_gap 0.5)
				(thermal_bridge_width 0.5)
				(island_removal_mode 0)
			)
			(polygon
				(pts
					(arc
						(start 330.976478 -46.980856)
						(mid 330.929877 -46.905029)
						(end 330.85405 -46.858428)
					)
					(arc
						(start 330.85405 -46.753272)
						(mid 331.001832 -46.833074)
						(end 331.081634 -46.980856)
					)
				)
			)
		)
		(zone
			(layer "F.Cu")
			(hatch none 0.5)
			(connect_pads
				(clearance 0)
			)
			(min_thickness 0.25)
			(keepout
				(tracks not_allowed)
				(vias allowed)
				(pads allowed)
				(copperpour not_allowed)
				(footprints allowed)
			)
			(placement
				(enabled no)
				(sheetname "")
			)
			(fill
				(thermal_gap 0.5)
				(thermal_bridge_width 0.5)
				(island_removal_mode 0)
			)
			(polygon
				(pts
					(arc
						(start 330.976478 -46.041056)
						(mid 330.929877 -45.965229)
						(end 330.85405 -45.918628)
					)
					(arc
						(start 330.85405 -45.813472)
						(mid 331.001832 -45.893274)
						(end 331.081634 -46.041056)
					)
				)
			)
		)
		(zone
			(layer "F.Cu")
			(hatch none 0.5)
			(connect_pads
				(clearance 0)
			)
			(min_thickness 0.25)
			(keepout
				(tracks not_allowed)
				(vias allowed)
				(pads allowed)
				(copperpour not_allowed)
				(footprints allowed)
			)
			(placement
				(enabled no)
				(sheetname "")
			)
			(fill
				(thermal_gap 0.5)
				(thermal_bridge_width 0.5)
				(island_removal_mode 0)
			)
			(polygon
				(pts
					(arc
						(start 330.976478 -45.101256)
						(mid 330.929877 -45.025429)
						(end 330.85405 -44.978828)
					)
					(arc
						(start 330.85405 -44.873672)
						(mid 331.001832 -44.953474)
						(end 331.081634 -45.101256)
					)
				)
			)
		)
		(zone
			(layer "F.Cu")
			(hatch none 0.5)
			(connect_pads
				(clearance 0)
			)
			(min_thickness 0.25)
			(keepout
				(tracks not_allowed)
				(vias allowed)
				(pads allowed)
				(copperpour not_allowed)
				(footprints allowed)
			)
			(placement
				(enabled no)
				(sheetname "")
			)
			(fill
				(thermal_gap 0.5)
				(thermal_bridge_width 0.5)
				(island_removal_mode 0)
			)
			(polygon
				(pts
					(arc
						(start 330.976478 -44.161456)
						(mid 330.929877 -44.085629)
						(end 330.85405 -44.039028)
					)
					(arc
						(start 330.85405 -43.933872)
						(mid 331.001832 -44.013674)
						(end 331.081634 -44.161456)
					)
				)
			)
		)
		(zone
			(layer "F.Cu")
			(hatch none 0.5)
			(connect_pads
				(clearance 0)
			)
			(min_thickness 0.25)
			(keepout
				(tracks not_allowed)
				(vias allowed)
				(pads allowed)
				(copperpour not_allowed)
				(footprints allowed)
			)
			(placement
				(enabled no)
				(sheetname "")
			)
			(fill
				(thermal_gap 0.5)
				(thermal_bridge_width 0.5)
				(island_removal_mode 0)
			)
			(polygon
				(pts
					(arc
						(start 330.976478 -43.221656)
						(mid 330.929877 -43.145829)
						(end 330.85405 -43.099228)
					)
					(arc
						(start 330.85405 -42.994072)
						(mid 331.001832 -43.073874)
						(end 331.081634 -43.221656)
					)
				)
			)
		)
		(zone
			(layer "F.Cu")
			(hatch none 0.5)
			(connect_pads
				(clearance 0)
			)
			(min_thickness 0.25)
			(keepout
				(tracks not_allowed)
				(vias allowed)
				(pads allowed)
				(copperpour not_allowed)
				(footprints allowed)
			)
			(placement
				(enabled no)
				(sheetname "")
			)
			(fill
				(thermal_gap 0.5)
				(thermal_bridge_width 0.5)
				(island_removal_mode 0)
			)
			(polygon
				(pts
					(arc
						(start 330.976478 -42.281856)
						(mid 330.929877 -42.206029)
						(end 330.85405 -42.159428)
					)
					(arc
						(start 330.85405 -42.054272)
						(mid 331.001832 -42.134074)
						(end 331.081634 -42.281856)
					)
				)
			)
		)
		(zone
			(layer "F.Cu")
			(hatch none 0.5)
			(connect_pads
				(clearance 0)
			)
			(min_thickness 0.25)
			(keepout
				(tracks not_allowed)
				(vias allowed)
				(pads allowed)
				(copperpour not_allowed)
				(footprints allowed)
			)
			(placement
				(enabled no)
				(sheetname "")
			)
			(fill
				(thermal_gap 0.5)
				(thermal_bridge_width 0.5)
				(island_removal_mode 0)
			)
			(polygon
				(pts
					(arc
						(start 330.976478 -41.342056)
						(mid 330.929877 -41.266229)
						(end 330.85405 -41.219628)
					)
					(arc
						(start 330.85405 -41.114472)
						(mid 331.001832 -41.194274)
						(end 331.081634 -41.342056)
					)
				)
			)
		)
		(zone
			(layer "F.Cu")
			(hatch none 0.5)
			(connect_pads
				(clearance 0)
			)
			(min_thickness 0.25)
			(keepout
				(tracks not_allowed)
				(vias allowed)
				(pads allowed)
				(copperpour not_allowed)
				(footprints allowed)
			)
			(placement
				(enabled no)
				(sheetname "")
			)
			(fill
				(thermal_gap 0.5)
				(thermal_bridge_width 0.5)
				(island_removal_mode 0)
			)
			(polygon
				(pts
					(arc
						(start 330.976478 -40.402256)
						(mid 330.929877 -40.326429)
						(end 330.85405 -40.279828)
					)
					(arc
						(start 330.85405 -40.174672)
						(mid 331.001832 -40.254474)
						(end 331.081634 -40.402256)
					)
				)
			)
		)
		(zone
			(layer "F.Cu")
			(hatch none 0.5)
			(connect_pads
				(clearance 0)
			)
			(min_thickness 0.25)
			(keepout
				(tracks not_allowed)
				(vias allowed)
				(pads allowed)
				(copperpour not_allowed)
				(footprints allowed)
			)
			(placement
				(enabled no)
				(sheetname "")
			)
			(fill
				(thermal_gap 0.5)
				(thermal_bridge_width 0.5)
				(island_removal_mode 0)
			)
			(polygon
				(pts
					(arc
						(start 331.426058 -56.968136)
						(mid 331.472659 -57.043963)
						(end 331.548486 -57.090564)
					)
					(arc
						(start 331.548486 -57.19572)
						(mid 331.400704 -57.115918)
						(end 331.320902 -56.968136)
					)
				)
			)
		)
		(zone
			(layer "F.Cu")
			(hatch none 0.5)
			(connect_pads
				(clearance 0)
			)
			(min_thickness 0.25)
			(keepout
				(tracks not_allowed)
				(vias allowed)
				(pads allowed)
				(copperpour not_allowed)
				(footprints allowed)
			)
			(placement
				(enabled no)
				(sheetname "")
			)
			(fill
				(thermal_gap 0.5)
				(thermal_bridge_width 0.5)
				(island_removal_mode 0)
			)
			(polygon
				(pts
					(arc
						(start 331.426058 -56.028336)
						(mid 331.472659 -56.104163)
						(end 331.548486 -56.150764)
					)
					(arc
						(start 331.548486 -56.25592)
						(mid 331.400704 -56.176118)
						(end 331.320902 -56.028336)
					)
				)
			)
		)
		(zone
			(layer "F.Cu")
			(hatch none 0.5)
			(connect_pads
				(clearance 0)
			)
			(min_thickness 0.25)
			(keepout
				(tracks not_allowed)
				(vias allowed)
				(pads allowed)
				(copperpour not_allowed)
				(footprints allowed)
			)
			(placement
				(enabled no)
				(sheetname "")
			)
			(fill
				(thermal_gap 0.5)
				(thermal_bridge_width 0.5)
				(island_removal_mode 0)
			)
			(polygon
				(pts
					(arc
						(start 331.426058 -55.088536)
						(mid 331.472659 -55.164363)
						(end 331.548486 -55.210964)
					)
					(arc
						(start 331.548486 -55.31612)
						(mid 331.400704 -55.236318)
						(end 331.320902 -55.088536)
					)
				)
			)
		)
		(zone
			(layer "F.Cu")
			(hatch none 0.5)
			(connect_pads
				(clearance 0)
			)
			(min_thickness 0.25)
			(keepout
				(tracks not_allowed)
				(vias allowed)
				(pads allowed)
				(copperpour not_allowed)
				(footprints allowed)
			)
			(placement
				(enabled no)
				(sheetname "")
			)
			(fill
				(thermal_gap 0.5)
				(thermal_bridge_width 0.5)
				(island_removal_mode 0)
			)
			(polygon
				(pts
					(arc
						(start 331.426058 -54.148736)
						(mid 331.472659 -54.224563)
						(end 331.548486 -54.271164)
					)
					(arc
						(start 331.548486 -54.37632)
						(mid 331.400704 -54.296518)
						(end 331.320902 -54.148736)
					)
				)
			)
		)
		(zone
			(layer "F.Cu")
			(hatch none 0.5)
			(connect_pads
				(clearance 0)
			)
			(min_thickness 0.25)
			(keepout
				(tracks not_allowed)
				(vias allowed)
				(pads allowed)
				(copperpour not_allowed)
				(footprints allowed)
			)
			(placement
				(enabled no)
				(sheetname "")
			)
			(fill
				(thermal_gap 0.5)
				(thermal_bridge_width 0.5)
				(island_removal_mode 0)
			)
			(polygon
				(pts
					(arc
						(start 331.426058 -53.208936)
						(mid 331.472659 -53.284763)
						(end 331.548486 -53.331364)
					)
					(arc
						(start 331.548486 -53.43652)
						(mid 331.400704 -53.356718)
						(end 331.320902 -53.208936)
					)
				)
			)
		)
		(zone
			(layer "F.Cu")
			(hatch none 0.5)
			(connect_pads
				(clearance 0)
			)
			(min_thickness 0.25)
			(keepout
				(tracks not_allowed)
				(vias allowed)
				(pads allowed)
				(copperpour not_allowed)
				(footprints allowed)
			)
			(placement
				(enabled no)
				(sheetname "")
			)
			(fill
				(thermal_gap 0.5)
				(thermal_bridge_width 0.5)
				(island_removal_mode 0)
			)
			(polygon
				(pts
					(arc
						(start 331.426058 -52.269136)
						(mid 331.472659 -52.344963)
						(end 331.548486 -52.391564)
					)
					(arc
						(start 331.548486 -52.49672)
						(mid 331.400704 -52.416918)
						(end 331.320902 -52.269136)
					)
				)
			)
		)
		(zone
			(layer "F.Cu")
			(hatch none 0.5)
			(connect_pads
				(clearance 0)
			)
			(min_thickness 0.25)
			(keepout
				(tracks not_allowed)
				(vias allowed)
				(pads allowed)
				(copperpour not_allowed)
				(footprints allowed)
			)
			(placement
				(enabled no)
				(sheetname "")
			)
			(fill
				(thermal_gap 0.5)
				(thermal_bridge_width 0.5)
				(island_removal_mode 0)
			)
			(polygon
				(pts
					(arc
						(start 331.426058 -51.329336)
						(mid 331.472659 -51.405163)
						(end 331.548486 -51.451764)
					)
					(arc
						(start 331.548486 -51.55692)
						(mid 331.400704 -51.477118)
						(end 331.320902 -51.329336)
					)
				)
			)
		)
		(zone
			(layer "F.Cu")
			(hatch none 0.5)
			(connect_pads
				(clearance 0)
			)
			(min_thickness 0.25)
			(keepout
				(tracks not_allowed)
				(vias allowed)
				(pads allowed)
				(copperpour not_allowed)
				(footprints allowed)
			)
			(placement
				(enabled no)
				(sheetname "")
			)
			(fill
				(thermal_gap 0.5)
				(thermal_bridge_width 0.5)
				(island_removal_mode 0)
			)
			(polygon
				(pts
					(arc
						(start 331.426058 -50.389536)
						(mid 331.472659 -50.465363)
						(end 331.548486 -50.511964)
					)
					(arc
						(start 331.548486 -50.61712)
						(mid 331.400704 -50.537318)
						(end 331.320902 -50.389536)
					)
				)
			)
		)
		(zone
			(layer "F.Cu")
			(hatch none 0.5)
			(connect_pads
				(clearance 0)
			)
			(min_thickness 0.25)
			(keepout
				(tracks not_allowed)
				(vias allowed)
				(pads allowed)
				(copperpour not_allowed)
				(footprints allowed)
			)
			(placement
				(enabled no)
				(sheetname "")
			)
			(fill
				(thermal_gap 0.5)
				(thermal_bridge_width 0.5)
				(island_removal_mode 0)
			)
			(polygon
				(pts
					(arc
						(start 331.426058 -49.449736)
						(mid 331.472659 -49.525563)
						(end 331.548486 -49.572164)
					)
					(arc
						(start 331.548486 -49.67732)
						(mid 331.400704 -49.597518)
						(end 331.320902 -49.449736)
					)
				)
			)
		)
		(zone
			(layer "F.Cu")
			(hatch none 0.5)
			(connect_pads
				(clearance 0)
			)
			(min_thickness 0.25)
			(keepout
				(tracks not_allowed)
				(vias allowed)
				(pads allowed)
				(copperpour not_allowed)
				(footprints allowed)
			)
			(placement
				(enabled no)
				(sheetname "")
			)
			(fill
				(thermal_gap 0.5)
				(thermal_bridge_width 0.5)
				(island_removal_mode 0)
			)
			(polygon
				(pts
					(arc
						(start 331.426058 -48.509936)
						(mid 331.472659 -48.585763)
						(end 331.548486 -48.632364)
					)
					(arc
						(start 331.548486 -48.73752)
						(mid 331.400704 -48.657718)
						(end 331.320902 -48.509936)
					)
				)
			)
		)
		(zone
			(layer "F.Cu")
			(hatch none 0.5)
			(connect_pads
				(clearance 0)
			)
			(min_thickness 0.25)
			(keepout
				(tracks not_allowed)
				(vias allowed)
				(pads allowed)
				(copperpour not_allowed)
				(footprints allowed)
			)
			(placement
				(enabled no)
				(sheetname "")
			)
			(fill
				(thermal_gap 0.5)
				(thermal_bridge_width 0.5)
				(island_removal_mode 0)
			)
			(polygon
				(pts
					(arc
						(start 331.426058 -47.570136)
						(mid 331.472659 -47.645963)
						(end 331.548486 -47.692564)
					)
					(arc
						(start 331.548486 -47.79772)
						(mid 331.400704 -47.717918)
						(end 331.320902 -47.570136)
					)
				)
			)
		)
		(zone
			(layer "F.Cu")
			(hatch none 0.5)
			(connect_pads
				(clearance 0)
			)
			(min_thickness 0.25)
			(keepout
				(tracks not_allowed)
				(vias allowed)
				(pads allowed)
				(copperpour not_allowed)
				(footprints allowed)
			)
			(placement
				(enabled no)
				(sheetname "")
			)
			(fill
				(thermal_gap 0.5)
				(thermal_bridge_width 0.5)
				(island_removal_mode 0)
			)
			(polygon
				(pts
					(arc
						(start 331.426058 -46.630336)
						(mid 331.472659 -46.706163)
						(end 331.548486 -46.752764)
					)
					(arc
						(start 331.548486 -46.85792)
						(mid 331.400704 -46.778118)
						(end 331.320902 -46.630336)
					)
				)
			)
		)
		(zone
			(layer "F.Cu")
			(hatch none 0.5)
			(connect_pads
				(clearance 0)
			)
			(min_thickness 0.25)
			(keepout
				(tracks not_allowed)
				(vias allowed)
				(pads allowed)
				(copperpour not_allowed)
				(footprints allowed)
			)
			(placement
				(enabled no)
				(sheetname "")
			)
			(fill
				(thermal_gap 0.5)
				(thermal_bridge_width 0.5)
				(island_removal_mode 0)
			)
			(polygon
				(pts
					(arc
						(start 331.426058 -45.690536)
						(mid 331.472659 -45.766363)
						(end 331.548486 -45.812964)
					)
					(arc
						(start 331.548486 -45.91812)
						(mid 331.400704 -45.838318)
						(end 331.320902 -45.690536)
					)
				)
			)
		)
		(zone
			(layer "F.Cu")
			(hatch none 0.5)
			(connect_pads
				(clearance 0)
			)
			(min_thickness 0.25)
			(keepout
				(tracks not_allowed)
				(vias allowed)
				(pads allowed)
				(copperpour not_allowed)
				(footprints allowed)
			)
			(placement
				(enabled no)
				(sheetname "")
			)
			(fill
				(thermal_gap 0.5)
				(thermal_bridge_width 0.5)
				(island_removal_mode 0)
			)
			(polygon
				(pts
					(arc
						(start 331.426058 -44.750736)
						(mid 331.472659 -44.826563)
						(end 331.548486 -44.873164)
					)
					(arc
						(start 331.548486 -44.97832)
						(mid 331.400704 -44.898518)
						(end 331.320902 -44.750736)
					)
				)
			)
		)
		(zone
			(layer "F.Cu")
			(hatch none 0.5)
			(connect_pads
				(clearance 0)
			)
			(min_thickness 0.25)
			(keepout
				(tracks not_allowed)
				(vias allowed)
				(pads allowed)
				(copperpour not_allowed)
				(footprints allowed)
			)
			(placement
				(enabled no)
				(sheetname "")
			)
			(fill
				(thermal_gap 0.5)
				(thermal_bridge_width 0.5)
				(island_removal_mode 0)
			)
			(polygon
				(pts
					(arc
						(start 331.426058 -43.810936)
						(mid 331.472659 -43.886763)
						(end 331.548486 -43.933364)
					)
					(arc
						(start 331.548486 -44.03852)
						(mid 331.400704 -43.958718)
						(end 331.320902 -43.810936)
					)
				)
			)
		)
		(zone
			(layer "F.Cu")
			(hatch none 0.5)
			(connect_pads
				(clearance 0)
			)
			(min_thickness 0.25)
			(keepout
				(tracks not_allowed)
				(vias allowed)
				(pads allowed)
				(copperpour not_allowed)
				(footprints allowed)
			)
			(placement
				(enabled no)
				(sheetname "")
			)
			(fill
				(thermal_gap 0.5)
				(thermal_bridge_width 0.5)
				(island_removal_mode 0)
			)
			(polygon
				(pts
					(arc
						(start 331.426058 -42.871136)
						(mid 331.472659 -42.946963)
						(end 331.548486 -42.993564)
					)
					(arc
						(start 331.548486 -43.09872)
						(mid 331.400704 -43.018918)
						(end 331.320902 -42.871136)
					)
				)
			)
		)
		(zone
			(layer "F.Cu")
			(hatch none 0.5)
			(connect_pads
				(clearance 0)
			)
			(min_thickness 0.25)
			(keepout
				(tracks not_allowed)
				(vias allowed)
				(pads allowed)
				(copperpour not_allowed)
				(footprints allowed)
			)
			(placement
				(enabled no)
				(sheetname "")
			)
			(fill
				(thermal_gap 0.5)
				(thermal_bridge_width 0.5)
				(island_removal_mode 0)
			)
			(polygon
				(pts
					(arc
						(start 331.426058 -41.931336)
						(mid 331.472659 -42.007163)
						(end 331.548486 -42.053764)
					)
					(arc
						(start 331.548486 -42.15892)
						(mid 331.400704 -42.079118)
						(end 331.320902 -41.931336)
					)
				)
			)
		)
		(zone
			(layer "F.Cu")
			(hatch none 0.5)
			(connect_pads
				(clearance 0)
			)
			(min_thickness 0.25)
			(keepout
				(tracks not_allowed)
				(vias allowed)
				(pads allowed)
				(copperpour not_allowed)
				(footprints allowed)
			)
			(placement
				(enabled no)
				(sheetname "")
			)
			(fill
				(thermal_gap 0.5)
				(thermal_bridge_width 0.5)
				(island_removal_mode 0)
			)
			(polygon
				(pts
					(arc
						(start 331.426058 -40.991536)
						(mid 331.472659 -41.067363)
						(end 331.548486 -41.113964)
					)
					(arc
						(start 331.548486 -41.21912)
						(mid 331.400704 -41.139318)
						(end 331.320902 -40.991536)
					)
				)
			)
		)
		(zone
			(layer "F.Cu")
			(hatch none 0.5)
			(connect_pads
				(clearance 0)
			)
			(min_thickness 0.25)
			(keepout
				(tracks not_allowed)
				(vias allowed)
				(pads allowed)
				(copperpour not_allowed)
				(footprints allowed)
			)
			(placement
				(enabled no)
				(sheetname "")
			)
			(fill
				(thermal_gap 0.5)
				(thermal_bridge_width 0.5)
				(island_removal_mode 0)
			)
			(polygon
				(pts
					(arc
						(start 331.426058 -40.051736)
						(mid 331.472659 -40.127563)
						(end 331.548486 -40.174164)
					)
					(arc
						(start 331.548486 -40.27932)
						(mid 331.400704 -40.199518)
						(end 331.320902 -40.051736)
					)
				)
			)
		)
		(zone
			(layer "F.Cu")
			(hatch none 0.5)
			(connect_pads
				(clearance 0)
			)
			(min_thickness 0.25)
			(keepout
				(tracks not_allowed)
				(vias allowed)
				(pads allowed)
				(copperpour not_allowed)
				(footprints allowed)
			)
			(placement
				(enabled no)
				(sheetname "")
			)
			(fill
				(thermal_gap 0.5)
				(thermal_bridge_width 0.5)
				(island_removal_mode 0)
			)
			(polygon
				(pts
					(arc
						(start 331.548486 -56.726328)
						(mid 331.472659 -56.772929)
						(end 331.426058 -56.848756)
					)
					(arc
						(start 331.320902 -56.848756)
						(mid 331.400704 -56.700974)
						(end 331.548486 -56.621172)
					)
				)
			)
		)
		(zone
			(layer "F.Cu")
			(hatch none 0.5)
			(connect_pads
				(clearance 0)
			)
			(min_thickness 0.25)
			(keepout
				(tracks not_allowed)
				(vias allowed)
				(pads allowed)
				(copperpour not_allowed)
				(footprints allowed)
			)
			(placement
				(enabled no)
				(sheetname "")
			)
			(fill
				(thermal_gap 0.5)
				(thermal_bridge_width 0.5)
				(island_removal_mode 0)
			)
			(polygon
				(pts
					(arc
						(start 331.548486 -55.786528)
						(mid 331.472659 -55.833129)
						(end 331.426058 -55.908956)
					)
					(arc
						(start 331.320902 -55.908956)
						(mid 331.400704 -55.761174)
						(end 331.548486 -55.681372)
					)
				)
			)
		)
		(zone
			(layer "F.Cu")
			(hatch none 0.5)
			(connect_pads
				(clearance 0)
			)
			(min_thickness 0.25)
			(keepout
				(tracks not_allowed)
				(vias allowed)
				(pads allowed)
				(copperpour not_allowed)
				(footprints allowed)
			)
			(placement
				(enabled no)
				(sheetname "")
			)
			(fill
				(thermal_gap 0.5)
				(thermal_bridge_width 0.5)
				(island_removal_mode 0)
			)
			(polygon
				(pts
					(arc
						(start 331.548486 -54.846728)
						(mid 331.472659 -54.893329)
						(end 331.426058 -54.969156)
					)
					(arc
						(start 331.320902 -54.969156)
						(mid 331.400704 -54.821374)
						(end 331.548486 -54.741572)
					)
				)
			)
		)
		(zone
			(layer "F.Cu")
			(hatch none 0.5)
			(connect_pads
				(clearance 0)
			)
			(min_thickness 0.25)
			(keepout
				(tracks not_allowed)
				(vias allowed)
				(pads allowed)
				(copperpour not_allowed)
				(footprints allowed)
			)
			(placement
				(enabled no)
				(sheetname "")
			)
			(fill
				(thermal_gap 0.5)
				(thermal_bridge_width 0.5)
				(island_removal_mode 0)
			)
			(polygon
				(pts
					(arc
						(start 331.548486 -53.906928)
						(mid 331.472659 -53.953529)
						(end 331.426058 -54.029356)
					)
					(arc
						(start 331.320902 -54.029356)
						(mid 331.400704 -53.881574)
						(end 331.548486 -53.801772)
					)
				)
			)
		)
		(zone
			(layer "F.Cu")
			(hatch none 0.5)
			(connect_pads
				(clearance 0)
			)
			(min_thickness 0.25)
			(keepout
				(tracks not_allowed)
				(vias allowed)
				(pads allowed)
				(copperpour not_allowed)
				(footprints allowed)
			)
			(placement
				(enabled no)
				(sheetname "")
			)
			(fill
				(thermal_gap 0.5)
				(thermal_bridge_width 0.5)
				(island_removal_mode 0)
			)
			(polygon
				(pts
					(arc
						(start 331.548486 -52.967128)
						(mid 331.472659 -53.013729)
						(end 331.426058 -53.089556)
					)
					(arc
						(start 331.320902 -53.089556)
						(mid 331.400704 -52.941774)
						(end 331.548486 -52.861972)
					)
				)
			)
		)
		(zone
			(layer "F.Cu")
			(hatch none 0.5)
			(connect_pads
				(clearance 0)
			)
			(min_thickness 0.25)
			(keepout
				(tracks not_allowed)
				(vias allowed)
				(pads allowed)
				(copperpour not_allowed)
				(footprints allowed)
			)
			(placement
				(enabled no)
				(sheetname "")
			)
			(fill
				(thermal_gap 0.5)
				(thermal_bridge_width 0.5)
				(island_removal_mode 0)
			)
			(polygon
				(pts
					(arc
						(start 331.548486 -52.027328)
						(mid 331.472659 -52.073929)
						(end 331.426058 -52.149756)
					)
					(arc
						(start 331.320902 -52.149756)
						(mid 331.400704 -52.001974)
						(end 331.548486 -51.922172)
					)
				)
			)
		)
		(zone
			(layer "F.Cu")
			(hatch none 0.5)
			(connect_pads
				(clearance 0)
			)
			(min_thickness 0.25)
			(keepout
				(tracks not_allowed)
				(vias allowed)
				(pads allowed)
				(copperpour not_allowed)
				(footprints allowed)
			)
			(placement
				(enabled no)
				(sheetname "")
			)
			(fill
				(thermal_gap 0.5)
				(thermal_bridge_width 0.5)
				(island_removal_mode 0)
			)
			(polygon
				(pts
					(arc
						(start 331.548486 -51.087528)
						(mid 331.472659 -51.134129)
						(end 331.426058 -51.209956)
					)
					(arc
						(start 331.320902 -51.209956)
						(mid 331.400704 -51.062174)
						(end 331.548486 -50.982372)
					)
				)
			)
		)
		(zone
			(layer "F.Cu")
			(hatch none 0.5)
			(connect_pads
				(clearance 0)
			)
			(min_thickness 0.25)
			(keepout
				(tracks not_allowed)
				(vias allowed)
				(pads allowed)
				(copperpour not_allowed)
				(footprints allowed)
			)
			(placement
				(enabled no)
				(sheetname "")
			)
			(fill
				(thermal_gap 0.5)
				(thermal_bridge_width 0.5)
				(island_removal_mode 0)
			)
			(polygon
				(pts
					(arc
						(start 331.548486 -50.147728)
						(mid 331.472659 -50.194329)
						(end 331.426058 -50.270156)
					)
					(arc
						(start 331.320902 -50.270156)
						(mid 331.400704 -50.122374)
						(end 331.548486 -50.042572)
					)
				)
			)
		)
		(zone
			(layer "F.Cu")
			(hatch none 0.5)
			(connect_pads
				(clearance 0)
			)
			(min_thickness 0.25)
			(keepout
				(tracks not_allowed)
				(vias allowed)
				(pads allowed)
				(copperpour not_allowed)
				(footprints allowed)
			)
			(placement
				(enabled no)
				(sheetname "")
			)
			(fill
				(thermal_gap 0.5)
				(thermal_bridge_width 0.5)
				(island_removal_mode 0)
			)
			(polygon
				(pts
					(arc
						(start 331.548486 -49.207928)
						(mid 331.472659 -49.254529)
						(end 331.426058 -49.330356)
					)
					(arc
						(start 331.320902 -49.330356)
						(mid 331.400704 -49.182574)
						(end 331.548486 -49.102772)
					)
				)
			)
		)
		(zone
			(layer "F.Cu")
			(hatch none 0.5)
			(connect_pads
				(clearance 0)
			)
			(min_thickness 0.25)
			(keepout
				(tracks not_allowed)
				(vias allowed)
				(pads allowed)
				(copperpour not_allowed)
				(footprints allowed)
			)
			(placement
				(enabled no)
				(sheetname "")
			)
			(fill
				(thermal_gap 0.5)
				(thermal_bridge_width 0.5)
				(island_removal_mode 0)
			)
			(polygon
				(pts
					(arc
						(start 331.548486 -48.268128)
						(mid 331.472659 -48.314729)
						(end 331.426058 -48.390556)
					)
					(arc
						(start 331.320902 -48.390556)
						(mid 331.400704 -48.242774)
						(end 331.548486 -48.162972)
					)
				)
			)
		)
		(zone
			(layer "F.Cu")
			(hatch none 0.5)
			(connect_pads
				(clearance 0)
			)
			(min_thickness 0.25)
			(keepout
				(tracks not_allowed)
				(vias allowed)
				(pads allowed)
				(copperpour not_allowed)
				(footprints allowed)
			)
			(placement
				(enabled no)
				(sheetname "")
			)
			(fill
				(thermal_gap 0.5)
				(thermal_bridge_width 0.5)
				(island_removal_mode 0)
			)
			(polygon
				(pts
					(arc
						(start 331.548486 -47.328328)
						(mid 331.472659 -47.374929)
						(end 331.426058 -47.450756)
					)
					(arc
						(start 331.320902 -47.450756)
						(mid 331.400704 -47.302974)
						(end 331.548486 -47.223172)
					)
				)
			)
		)
		(zone
			(layer "F.Cu")
			(hatch none 0.5)
			(connect_pads
				(clearance 0)
			)
			(min_thickness 0.25)
			(keepout
				(tracks not_allowed)
				(vias allowed)
				(pads allowed)
				(copperpour not_allowed)
				(footprints allowed)
			)
			(placement
				(enabled no)
				(sheetname "")
			)
			(fill
				(thermal_gap 0.5)
				(thermal_bridge_width 0.5)
				(island_removal_mode 0)
			)
			(polygon
				(pts
					(arc
						(start 331.548486 -46.388528)
						(mid 331.472659 -46.435129)
						(end 331.426058 -46.510956)
					)
					(arc
						(start 331.320902 -46.510956)
						(mid 331.400704 -46.363174)
						(end 331.548486 -46.283372)
					)
				)
			)
		)
		(zone
			(layer "F.Cu")
			(hatch none 0.5)
			(connect_pads
				(clearance 0)
			)
			(min_thickness 0.25)
			(keepout
				(tracks not_allowed)
				(vias allowed)
				(pads allowed)
				(copperpour not_allowed)
				(footprints allowed)
			)
			(placement
				(enabled no)
				(sheetname "")
			)
			(fill
				(thermal_gap 0.5)
				(thermal_bridge_width 0.5)
				(island_removal_mode 0)
			)
			(polygon
				(pts
					(arc
						(start 331.548486 -45.448728)
						(mid 331.472659 -45.495329)
						(end 331.426058 -45.571156)
					)
					(arc
						(start 331.320902 -45.571156)
						(mid 331.400704 -45.423374)
						(end 331.548486 -45.343572)
					)
				)
			)
		)
		(zone
			(layer "F.Cu")
			(hatch none 0.5)
			(connect_pads
				(clearance 0)
			)
			(min_thickness 0.25)
			(keepout
				(tracks not_allowed)
				(vias allowed)
				(pads allowed)
				(copperpour not_allowed)
				(footprints allowed)
			)
			(placement
				(enabled no)
				(sheetname "")
			)
			(fill
				(thermal_gap 0.5)
				(thermal_bridge_width 0.5)
				(island_removal_mode 0)
			)
			(polygon
				(pts
					(arc
						(start 331.548486 -44.508928)
						(mid 331.472659 -44.555529)
						(end 331.426058 -44.631356)
					)
					(arc
						(start 331.320902 -44.631356)
						(mid 331.400704 -44.483574)
						(end 331.548486 -44.403772)
					)
				)
			)
		)
		(zone
			(layer "F.Cu")
			(hatch none 0.5)
			(connect_pads
				(clearance 0)
			)
			(min_thickness 0.25)
			(keepout
				(tracks not_allowed)
				(vias allowed)
				(pads allowed)
				(copperpour not_allowed)
				(footprints allowed)
			)
			(placement
				(enabled no)
				(sheetname "")
			)
			(fill
				(thermal_gap 0.5)
				(thermal_bridge_width 0.5)
				(island_removal_mode 0)
			)
			(polygon
				(pts
					(arc
						(start 331.548486 -43.569128)
						(mid 331.472659 -43.615729)
						(end 331.426058 -43.691556)
					)
					(arc
						(start 331.320902 -43.691556)
						(mid 331.400704 -43.543774)
						(end 331.548486 -43.463972)
					)
				)
			)
		)
		(zone
			(layer "F.Cu")
			(hatch none 0.5)
			(connect_pads
				(clearance 0)
			)
			(min_thickness 0.25)
			(keepout
				(tracks not_allowed)
				(vias allowed)
				(pads allowed)
				(copperpour not_allowed)
				(footprints allowed)
			)
			(placement
				(enabled no)
				(sheetname "")
			)
			(fill
				(thermal_gap 0.5)
				(thermal_bridge_width 0.5)
				(island_removal_mode 0)
			)
			(polygon
				(pts
					(arc
						(start 331.548486 -42.629328)
						(mid 331.472659 -42.675929)
						(end 331.426058 -42.751756)
					)
					(arc
						(start 331.320902 -42.751756)
						(mid 331.400704 -42.603974)
						(end 331.548486 -42.524172)
					)
				)
			)
		)
		(zone
			(layer "F.Cu")
			(hatch none 0.5)
			(connect_pads
				(clearance 0)
			)
			(min_thickness 0.25)
			(keepout
				(tracks not_allowed)
				(vias allowed)
				(pads allowed)
				(copperpour not_allowed)
				(footprints allowed)
			)
			(placement
				(enabled no)
				(sheetname "")
			)
			(fill
				(thermal_gap 0.5)
				(thermal_bridge_width 0.5)
				(island_removal_mode 0)
			)
			(polygon
				(pts
					(arc
						(start 331.548486 -41.689528)
						(mid 331.472659 -41.736129)
						(end 331.426058 -41.811956)
					)
					(arc
						(start 331.320902 -41.811956)
						(mid 331.400704 -41.664174)
						(end 331.548486 -41.584372)
					)
				)
			)
		)
		(zone
			(layer "F.Cu")
			(hatch none 0.5)
			(connect_pads
				(clearance 0)
			)
			(min_thickness 0.25)
			(keepout
				(tracks not_allowed)
				(vias allowed)
				(pads allowed)
				(copperpour not_allowed)
				(footprints allowed)
			)
			(placement
				(enabled no)
				(sheetname "")
			)
			(fill
				(thermal_gap 0.5)
				(thermal_bridge_width 0.5)
				(island_removal_mode 0)
			)
			(polygon
				(pts
					(arc
						(start 331.548486 -40.749728)
						(mid 331.472659 -40.796329)
						(end 331.426058 -40.872156)
					)
					(arc
						(start 331.320902 -40.872156)
						(mid 331.400704 -40.724374)
						(end 331.548486 -40.644572)
					)
				)
			)
		)
		(zone
			(layer "F.Cu")
			(hatch none 0.5)
			(connect_pads
				(clearance 0)
			)
			(min_thickness 0.25)
			(keepout
				(tracks not_allowed)
				(vias allowed)
				(pads allowed)
				(copperpour not_allowed)
				(footprints allowed)
			)
			(placement
				(enabled no)
				(sheetname "")
			)
			(fill
				(thermal_gap 0.5)
				(thermal_bridge_width 0.5)
				(island_removal_mode 0)
			)
			(polygon
				(pts
					(arc
						(start 331.548486 -39.809928)
						(mid 331.472659 -39.856529)
						(end 331.426058 -39.932356)
					)
					(arc
						(start 331.320902 -39.932356)
						(mid 331.400704 -39.784574)
						(end 331.548486 -39.704772)
					)
				)
			)
		)
		(zone
			(layer "F.Cu")
			(hatch none 0.5)
			(connect_pads
				(clearance 0)
			)
			(min_thickness 0.25)
			(keepout
				(tracks not_allowed)
				(vias allowed)
				(pads allowed)
				(copperpour not_allowed)
				(footprints allowed)
			)
			(placement
				(enabled no)
				(sheetname "")
			)
			(fill
				(thermal_gap 0.5)
				(thermal_bridge_width 0.5)
				(island_removal_mode 0)
			)
			(polygon
				(pts
					(arc
						(start 331.667866 -57.090564)
						(mid 331.743693 -57.043963)
						(end 331.790294 -56.968136)
					)
					(arc
						(start 331.89545 -56.968136)
						(mid 331.815648 -57.115918)
						(end 331.667866 -57.19572)
					)
				)
			)
		)
		(zone
			(layer "F.Cu")
			(hatch none 0.5)
			(connect_pads
				(clearance 0)
			)
			(min_thickness 0.25)
			(keepout
				(tracks not_allowed)
				(vias allowed)
				(pads allowed)
				(copperpour not_allowed)
				(footprints allowed)
			)
			(placement
				(enabled no)
				(sheetname "")
			)
			(fill
				(thermal_gap 0.5)
				(thermal_bridge_width 0.5)
				(island_removal_mode 0)
			)
			(polygon
				(pts
					(arc
						(start 331.667866 -56.150764)
						(mid 331.743693 -56.104163)
						(end 331.790294 -56.028336)
					)
					(arc
						(start 331.89545 -56.028336)
						(mid 331.815648 -56.176118)
						(end 331.667866 -56.25592)
					)
				)
			)
		)
		(zone
			(layer "F.Cu")
			(hatch none 0.5)
			(connect_pads
				(clearance 0)
			)
			(min_thickness 0.25)
			(keepout
				(tracks not_allowed)
				(vias allowed)
				(pads allowed)
				(copperpour not_allowed)
				(footprints allowed)
			)
			(placement
				(enabled no)
				(sheetname "")
			)
			(fill
				(thermal_gap 0.5)
				(thermal_bridge_width 0.5)
				(island_removal_mode 0)
			)
			(polygon
				(pts
					(arc
						(start 331.667866 -55.210964)
						(mid 331.743693 -55.164363)
						(end 331.790294 -55.088536)
					)
					(arc
						(start 331.89545 -55.088536)
						(mid 331.815648 -55.236318)
						(end 331.667866 -55.31612)
					)
				)
			)
		)
		(zone
			(layer "F.Cu")
			(hatch none 0.5)
			(connect_pads
				(clearance 0)
			)
			(min_thickness 0.25)
			(keepout
				(tracks not_allowed)
				(vias allowed)
				(pads allowed)
				(copperpour not_allowed)
				(footprints allowed)
			)
			(placement
				(enabled no)
				(sheetname "")
			)
			(fill
				(thermal_gap 0.5)
				(thermal_bridge_width 0.5)
				(island_removal_mode 0)
			)
			(polygon
				(pts
					(arc
						(start 331.667866 -54.271164)
						(mid 331.743693 -54.224563)
						(end 331.790294 -54.148736)
					)
					(arc
						(start 331.89545 -54.148736)
						(mid 331.815648 -54.296518)
						(end 331.667866 -54.37632)
					)
				)
			)
		)
		(zone
			(layer "F.Cu")
			(hatch none 0.5)
			(connect_pads
				(clearance 0)
			)
			(min_thickness 0.25)
			(keepout
				(tracks not_allowed)
				(vias allowed)
				(pads allowed)
				(copperpour not_allowed)
				(footprints allowed)
			)
			(placement
				(enabled no)
				(sheetname "")
			)
			(fill
				(thermal_gap 0.5)
				(thermal_bridge_width 0.5)
				(island_removal_mode 0)
			)
			(polygon
				(pts
					(arc
						(start 331.667866 -53.331364)
						(mid 331.743693 -53.284763)
						(end 331.790294 -53.208936)
					)
					(arc
						(start 331.89545 -53.208936)
						(mid 331.815648 -53.356718)
						(end 331.667866 -53.43652)
					)
				)
			)
		)
		(zone
			(layer "F.Cu")
			(hatch none 0.5)
			(connect_pads
				(clearance 0)
			)
			(min_thickness 0.25)
			(keepout
				(tracks not_allowed)
				(vias allowed)
				(pads allowed)
				(copperpour not_allowed)
				(footprints allowed)
			)
			(placement
				(enabled no)
				(sheetname "")
			)
			(fill
				(thermal_gap 0.5)
				(thermal_bridge_width 0.5)
				(island_removal_mode 0)
			)
			(polygon
				(pts
					(arc
						(start 331.667866 -52.391564)
						(mid 331.743693 -52.344963)
						(end 331.790294 -52.269136)
					)
					(arc
						(start 331.89545 -52.269136)
						(mid 331.815648 -52.416918)
						(end 331.667866 -52.49672)
					)
				)
			)
		)
		(zone
			(layer "F.Cu")
			(hatch none 0.5)
			(connect_pads
				(clearance 0)
			)
			(min_thickness 0.25)
			(keepout
				(tracks not_allowed)
				(vias allowed)
				(pads allowed)
				(copperpour not_allowed)
				(footprints allowed)
			)
			(placement
				(enabled no)
				(sheetname "")
			)
			(fill
				(thermal_gap 0.5)
				(thermal_bridge_width 0.5)
				(island_removal_mode 0)
			)
			(polygon
				(pts
					(arc
						(start 331.667866 -51.451764)
						(mid 331.743693 -51.405163)
						(end 331.790294 -51.329336)
					)
					(arc
						(start 331.89545 -51.329336)
						(mid 331.815648 -51.477118)
						(end 331.667866 -51.55692)
					)
				)
			)
		)
		(zone
			(layer "F.Cu")
			(hatch none 0.5)
			(connect_pads
				(clearance 0)
			)
			(min_thickness 0.25)
			(keepout
				(tracks not_allowed)
				(vias allowed)
				(pads allowed)
				(copperpour not_allowed)
				(footprints allowed)
			)
			(placement
				(enabled no)
				(sheetname "")
			)
			(fill
				(thermal_gap 0.5)
				(thermal_bridge_width 0.5)
				(island_removal_mode 0)
			)
			(polygon
				(pts
					(arc
						(start 331.667866 -50.511964)
						(mid 331.743693 -50.465363)
						(end 331.790294 -50.389536)
					)
					(arc
						(start 331.89545 -50.389536)
						(mid 331.815648 -50.537318)
						(end 331.667866 -50.61712)
					)
				)
			)
		)
		(zone
			(layer "F.Cu")
			(hatch none 0.5)
			(connect_pads
				(clearance 0)
			)
			(min_thickness 0.25)
			(keepout
				(tracks not_allowed)
				(vias allowed)
				(pads allowed)
				(copperpour not_allowed)
				(footprints allowed)
			)
			(placement
				(enabled no)
				(sheetname "")
			)
			(fill
				(thermal_gap 0.5)
				(thermal_bridge_width 0.5)
				(island_removal_mode 0)
			)
			(polygon
				(pts
					(arc
						(start 331.667866 -49.572164)
						(mid 331.743693 -49.525563)
						(end 331.790294 -49.449736)
					)
					(arc
						(start 331.89545 -49.449736)
						(mid 331.815648 -49.597518)
						(end 331.667866 -49.67732)
					)
				)
			)
		)
		(zone
			(layer "F.Cu")
			(hatch none 0.5)
			(connect_pads
				(clearance 0)
			)
			(min_thickness 0.25)
			(keepout
				(tracks not_allowed)
				(vias allowed)
				(pads allowed)
				(copperpour not_allowed)
				(footprints allowed)
			)
			(placement
				(enabled no)
				(sheetname "")
			)
			(fill
				(thermal_gap 0.5)
				(thermal_bridge_width 0.5)
				(island_removal_mode 0)
			)
			(polygon
				(pts
					(arc
						(start 331.667866 -48.632364)
						(mid 331.743693 -48.585763)
						(end 331.790294 -48.509936)
					)
					(arc
						(start 331.89545 -48.509936)
						(mid 331.815648 -48.657718)
						(end 331.667866 -48.73752)
					)
				)
			)
		)
		(zone
			(layer "F.Cu")
			(hatch none 0.5)
			(connect_pads
				(clearance 0)
			)
			(min_thickness 0.25)
			(keepout
				(tracks not_allowed)
				(vias allowed)
				(pads allowed)
				(copperpour not_allowed)
				(footprints allowed)
			)
			(placement
				(enabled no)
				(sheetname "")
			)
			(fill
				(thermal_gap 0.5)
				(thermal_bridge_width 0.5)
				(island_removal_mode 0)
			)
			(polygon
				(pts
					(arc
						(start 331.667866 -47.692564)
						(mid 331.743693 -47.645963)
						(end 331.790294 -47.570136)
					)
					(arc
						(start 331.89545 -47.570136)
						(mid 331.815648 -47.717918)
						(end 331.667866 -47.79772)
					)
				)
			)
		)
		(zone
			(layer "F.Cu")
			(hatch none 0.5)
			(connect_pads
				(clearance 0)
			)
			(min_thickness 0.25)
			(keepout
				(tracks not_allowed)
				(vias allowed)
				(pads allowed)
				(copperpour not_allowed)
				(footprints allowed)
			)
			(placement
				(enabled no)
				(sheetname "")
			)
			(fill
				(thermal_gap 0.5)
				(thermal_bridge_width 0.5)
				(island_removal_mode 0)
			)
			(polygon
				(pts
					(arc
						(start 331.667866 -46.752764)
						(mid 331.743693 -46.706163)
						(end 331.790294 -46.630336)
					)
					(arc
						(start 331.89545 -46.630336)
						(mid 331.815648 -46.778118)
						(end 331.667866 -46.85792)
					)
				)
			)
		)
		(zone
			(layer "F.Cu")
			(hatch none 0.5)
			(connect_pads
				(clearance 0)
			)
			(min_thickness 0.25)
			(keepout
				(tracks not_allowed)
				(vias allowed)
				(pads allowed)
				(copperpour not_allowed)
				(footprints allowed)
			)
			(placement
				(enabled no)
				(sheetname "")
			)
			(fill
				(thermal_gap 0.5)
				(thermal_bridge_width 0.5)
				(island_removal_mode 0)
			)
			(polygon
				(pts
					(arc
						(start 331.667866 -45.812964)
						(mid 331.743693 -45.766363)
						(end 331.790294 -45.690536)
					)
					(arc
						(start 331.89545 -45.690536)
						(mid 331.815648 -45.838318)
						(end 331.667866 -45.91812)
					)
				)
			)
		)
		(zone
			(layer "F.Cu")
			(hatch none 0.5)
			(connect_pads
				(clearance 0)
			)
			(min_thickness 0.25)
			(keepout
				(tracks not_allowed)
				(vias allowed)
				(pads allowed)
				(copperpour not_allowed)
				(footprints allowed)
			)
			(placement
				(enabled no)
				(sheetname "")
			)
			(fill
				(thermal_gap 0.5)
				(thermal_bridge_width 0.5)
				(island_removal_mode 0)
			)
			(polygon
				(pts
					(arc
						(start 331.667866 -44.873164)
						(mid 331.743693 -44.826563)
						(end 331.790294 -44.750736)
					)
					(arc
						(start 331.89545 -44.750736)
						(mid 331.815648 -44.898518)
						(end 331.667866 -44.97832)
					)
				)
			)
		)
		(zone
			(layer "F.Cu")
			(hatch none 0.5)
			(connect_pads
				(clearance 0)
			)
			(min_thickness 0.25)
			(keepout
				(tracks not_allowed)
				(vias allowed)
				(pads allowed)
				(copperpour not_allowed)
				(footprints allowed)
			)
			(placement
				(enabled no)
				(sheetname "")
			)
			(fill
				(thermal_gap 0.5)
				(thermal_bridge_width 0.5)
				(island_removal_mode 0)
			)
			(polygon
				(pts
					(arc
						(start 331.667866 -43.933364)
						(mid 331.743693 -43.886763)
						(end 331.790294 -43.810936)
					)
					(arc
						(start 331.89545 -43.810936)
						(mid 331.815648 -43.958718)
						(end 331.667866 -44.03852)
					)
				)
			)
		)
		(zone
			(layer "F.Cu")
			(hatch none 0.5)
			(connect_pads
				(clearance 0)
			)
			(min_thickness 0.25)
			(keepout
				(tracks not_allowed)
				(vias allowed)
				(pads allowed)
				(copperpour not_allowed)
				(footprints allowed)
			)
			(placement
				(enabled no)
				(sheetname "")
			)
			(fill
				(thermal_gap 0.5)
				(thermal_bridge_width 0.5)
				(island_removal_mode 0)
			)
			(polygon
				(pts
					(arc
						(start 331.667866 -42.993564)
						(mid 331.743693 -42.946963)
						(end 331.790294 -42.871136)
					)
					(arc
						(start 331.89545 -42.871136)
						(mid 331.815648 -43.018918)
						(end 331.667866 -43.09872)
					)
				)
			)
		)
		(zone
			(layer "F.Cu")
			(hatch none 0.5)
			(connect_pads
				(clearance 0)
			)
			(min_thickness 0.25)
			(keepout
				(tracks not_allowed)
				(vias allowed)
				(pads allowed)
				(copperpour not_allowed)
				(footprints allowed)
			)
			(placement
				(enabled no)
				(sheetname "")
			)
			(fill
				(thermal_gap 0.5)
				(thermal_bridge_width 0.5)
				(island_removal_mode 0)
			)
			(polygon
				(pts
					(arc
						(start 331.667866 -42.053764)
						(mid 331.743693 -42.007163)
						(end 331.790294 -41.931336)
					)
					(arc
						(start 331.89545 -41.931336)
						(mid 331.815648 -42.079118)
						(end 331.667866 -42.15892)
					)
				)
			)
		)
		(zone
			(layer "F.Cu")
			(hatch none 0.5)
			(connect_pads
				(clearance 0)
			)
			(min_thickness 0.25)
			(keepout
				(tracks not_allowed)
				(vias allowed)
				(pads allowed)
				(copperpour not_allowed)
				(footprints allowed)
			)
			(placement
				(enabled no)
				(sheetname "")
			)
			(fill
				(thermal_gap 0.5)
				(thermal_bridge_width 0.5)
				(island_removal_mode 0)
			)
			(polygon
				(pts
					(arc
						(start 331.667866 -41.113964)
						(mid 331.743693 -41.067363)
						(end 331.790294 -40.991536)
					)
					(arc
						(start 331.89545 -40.991536)
						(mid 331.815648 -41.139318)
						(end 331.667866 -41.21912)
					)
				)
			)
		)
		(zone
			(layer "F.Cu")
			(hatch none 0.5)
			(connect_pads
				(clearance 0)
			)
			(min_thickness 0.25)
			(keepout
				(tracks not_allowed)
				(vias allowed)
				(pads allowed)
				(copperpour not_allowed)
				(footprints allowed)
			)
			(placement
				(enabled no)
				(sheetname "")
			)
			(fill
				(thermal_gap 0.5)
				(thermal_bridge_width 0.5)
				(island_removal_mode 0)
			)
			(polygon
				(pts
					(arc
						(start 331.667866 -40.174164)
						(mid 331.743693 -40.127563)
						(end 331.790294 -40.051736)
					)
					(arc
						(start 331.89545 -40.051736)
						(mid 331.815648 -40.199518)
						(end 331.667866 -40.27932)
					)
				)
			)
		)
		(zone
			(layer "F.Cu")
			(hatch none 0.5)
			(connect_pads
				(clearance 0)
			)
			(min_thickness 0.25)
			(keepout
				(tracks not_allowed)
				(vias allowed)
				(pads allowed)
				(copperpour not_allowed)
				(footprints allowed)
			)
			(placement
				(enabled no)
				(sheetname "")
			)
			(fill
				(thermal_gap 0.5)
				(thermal_bridge_width 0.5)
				(island_removal_mode 0)
			)
			(polygon
				(pts
					(arc
						(start 331.790294 -56.848756)
						(mid 331.743693 -56.772929)
						(end 331.667866 -56.726328)
					)
					(arc
						(start 331.667866 -56.621172)
						(mid 331.815648 -56.700974)
						(end 331.89545 -56.848756)
					)
				)
			)
		)
		(zone
			(layer "F.Cu")
			(hatch none 0.5)
			(connect_pads
				(clearance 0)
			)
			(min_thickness 0.25)
			(keepout
				(tracks not_allowed)
				(vias allowed)
				(pads allowed)
				(copperpour not_allowed)
				(footprints allowed)
			)
			(placement
				(enabled no)
				(sheetname "")
			)
			(fill
				(thermal_gap 0.5)
				(thermal_bridge_width 0.5)
				(island_removal_mode 0)
			)
			(polygon
				(pts
					(arc
						(start 331.790294 -55.908956)
						(mid 331.743693 -55.833129)
						(end 331.667866 -55.786528)
					)
					(arc
						(start 331.667866 -55.681372)
						(mid 331.815648 -55.761174)
						(end 331.89545 -55.908956)
					)
				)
			)
		)
		(zone
			(layer "F.Cu")
			(hatch none 0.5)
			(connect_pads
				(clearance 0)
			)
			(min_thickness 0.25)
			(keepout
				(tracks not_allowed)
				(vias allowed)
				(pads allowed)
				(copperpour not_allowed)
				(footprints allowed)
			)
			(placement
				(enabled no)
				(sheetname "")
			)
			(fill
				(thermal_gap 0.5)
				(thermal_bridge_width 0.5)
				(island_removal_mode 0)
			)
			(polygon
				(pts
					(arc
						(start 331.790294 -54.969156)
						(mid 331.743693 -54.893329)
						(end 331.667866 -54.846728)
					)
					(arc
						(start 331.667866 -54.741572)
						(mid 331.815648 -54.821374)
						(end 331.89545 -54.969156)
					)
				)
			)
		)
		(zone
			(layer "F.Cu")
			(hatch none 0.5)
			(connect_pads
				(clearance 0)
			)
			(min_thickness 0.25)
			(keepout
				(tracks not_allowed)
				(vias allowed)
				(pads allowed)
				(copperpour not_allowed)
				(footprints allowed)
			)
			(placement
				(enabled no)
				(sheetname "")
			)
			(fill
				(thermal_gap 0.5)
				(thermal_bridge_width 0.5)
				(island_removal_mode 0)
			)
			(polygon
				(pts
					(arc
						(start 331.790294 -54.029356)
						(mid 331.743693 -53.953529)
						(end 331.667866 -53.906928)
					)
					(arc
						(start 331.667866 -53.801772)
						(mid 331.815648 -53.881574)
						(end 331.89545 -54.029356)
					)
				)
			)
		)
		(zone
			(layer "F.Cu")
			(hatch none 0.5)
			(connect_pads
				(clearance 0)
			)
			(min_thickness 0.25)
			(keepout
				(tracks not_allowed)
				(vias allowed)
				(pads allowed)
				(copperpour not_allowed)
				(footprints allowed)
			)
			(placement
				(enabled no)
				(sheetname "")
			)
			(fill
				(thermal_gap 0.5)
				(thermal_bridge_width 0.5)
				(island_removal_mode 0)
			)
			(polygon
				(pts
					(arc
						(start 331.790294 -53.089556)
						(mid 331.743693 -53.013729)
						(end 331.667866 -52.967128)
					)
					(arc
						(start 331.667866 -52.861972)
						(mid 331.815648 -52.941774)
						(end 331.89545 -53.089556)
					)
				)
			)
		)
		(zone
			(layer "F.Cu")
			(hatch none 0.5)
			(connect_pads
				(clearance 0)
			)
			(min_thickness 0.25)
			(keepout
				(tracks not_allowed)
				(vias allowed)
				(pads allowed)
				(copperpour not_allowed)
				(footprints allowed)
			)
			(placement
				(enabled no)
				(sheetname "")
			)
			(fill
				(thermal_gap 0.5)
				(thermal_bridge_width 0.5)
				(island_removal_mode 0)
			)
			(polygon
				(pts
					(arc
						(start 331.790294 -52.149756)
						(mid 331.743693 -52.073929)
						(end 331.667866 -52.027328)
					)
					(arc
						(start 331.667866 -51.922172)
						(mid 331.815648 -52.001974)
						(end 331.89545 -52.149756)
					)
				)
			)
		)
		(zone
			(layer "F.Cu")
			(hatch none 0.5)
			(connect_pads
				(clearance 0)
			)
			(min_thickness 0.25)
			(keepout
				(tracks not_allowed)
				(vias allowed)
				(pads allowed)
				(copperpour not_allowed)
				(footprints allowed)
			)
			(placement
				(enabled no)
				(sheetname "")
			)
			(fill
				(thermal_gap 0.5)
				(thermal_bridge_width 0.5)
				(island_removal_mode 0)
			)
			(polygon
				(pts
					(arc
						(start 331.790294 -51.209956)
						(mid 331.743693 -51.134129)
						(end 331.667866 -51.087528)
					)
					(arc
						(start 331.667866 -50.982372)
						(mid 331.815648 -51.062174)
						(end 331.89545 -51.209956)
					)
				)
			)
		)
		(zone
			(layer "F.Cu")
			(hatch none 0.5)
			(connect_pads
				(clearance 0)
			)
			(min_thickness 0.25)
			(keepout
				(tracks not_allowed)
				(vias allowed)
				(pads allowed)
				(copperpour not_allowed)
				(footprints allowed)
			)
			(placement
				(enabled no)
				(sheetname "")
			)
			(fill
				(thermal_gap 0.5)
				(thermal_bridge_width 0.5)
				(island_removal_mode 0)
			)
			(polygon
				(pts
					(arc
						(start 331.790294 -50.270156)
						(mid 331.743693 -50.194329)
						(end 331.667866 -50.147728)
					)
					(arc
						(start 331.667866 -50.042572)
						(mid 331.815648 -50.122374)
						(end 331.89545 -50.270156)
					)
				)
			)
		)
		(zone
			(layer "F.Cu")
			(hatch none 0.5)
			(connect_pads
				(clearance 0)
			)
			(min_thickness 0.25)
			(keepout
				(tracks not_allowed)
				(vias allowed)
				(pads allowed)
				(copperpour not_allowed)
				(footprints allowed)
			)
			(placement
				(enabled no)
				(sheetname "")
			)
			(fill
				(thermal_gap 0.5)
				(thermal_bridge_width 0.5)
				(island_removal_mode 0)
			)
			(polygon
				(pts
					(arc
						(start 331.790294 -49.330356)
						(mid 331.743693 -49.254529)
						(end 331.667866 -49.207928)
					)
					(arc
						(start 331.667866 -49.102772)
						(mid 331.815648 -49.182574)
						(end 331.89545 -49.330356)
					)
				)
			)
		)
		(zone
			(layer "F.Cu")
			(hatch none 0.5)
			(connect_pads
				(clearance 0)
			)
			(min_thickness 0.25)
			(keepout
				(tracks not_allowed)
				(vias allowed)
				(pads allowed)
				(copperpour not_allowed)
				(footprints allowed)
			)
			(placement
				(enabled no)
				(sheetname "")
			)
			(fill
				(thermal_gap 0.5)
				(thermal_bridge_width 0.5)
				(island_removal_mode 0)
			)
			(polygon
				(pts
					(arc
						(start 331.790294 -48.390556)
						(mid 331.743693 -48.314729)
						(end 331.667866 -48.268128)
					)
					(arc
						(start 331.667866 -48.162972)
						(mid 331.815648 -48.242774)
						(end 331.89545 -48.390556)
					)
				)
			)
		)
		(zone
			(layer "F.Cu")
			(hatch none 0.5)
			(connect_pads
				(clearance 0)
			)
			(min_thickness 0.25)
			(keepout
				(tracks not_allowed)
				(vias allowed)
				(pads allowed)
				(copperpour not_allowed)
				(footprints allowed)
			)
			(placement
				(enabled no)
				(sheetname "")
			)
			(fill
				(thermal_gap 0.5)
				(thermal_bridge_width 0.5)
				(island_removal_mode 0)
			)
			(polygon
				(pts
					(arc
						(start 331.790294 -47.450756)
						(mid 331.743693 -47.374929)
						(end 331.667866 -47.328328)
					)
					(arc
						(start 331.667866 -47.223172)
						(mid 331.815648 -47.302974)
						(end 331.89545 -47.450756)
					)
				)
			)
		)
		(zone
			(layer "F.Cu")
			(hatch none 0.5)
			(connect_pads
				(clearance 0)
			)
			(min_thickness 0.25)
			(keepout
				(tracks not_allowed)
				(vias allowed)
				(pads allowed)
				(copperpour not_allowed)
				(footprints allowed)
			)
			(placement
				(enabled no)
				(sheetname "")
			)
			(fill
				(thermal_gap 0.5)
				(thermal_bridge_width 0.5)
				(island_removal_mode 0)
			)
			(polygon
				(pts
					(arc
						(start 331.790294 -46.510956)
						(mid 331.743693 -46.435129)
						(end 331.667866 -46.388528)
					)
					(arc
						(start 331.667866 -46.283372)
						(mid 331.815648 -46.363174)
						(end 331.89545 -46.510956)
					)
				)
			)
		)
		(zone
			(layer "F.Cu")
			(hatch none 0.5)
			(connect_pads
				(clearance 0)
			)
			(min_thickness 0.25)
			(keepout
				(tracks not_allowed)
				(vias allowed)
				(pads allowed)
				(copperpour not_allowed)
				(footprints allowed)
			)
			(placement
				(enabled no)
				(sheetname "")
			)
			(fill
				(thermal_gap 0.5)
				(thermal_bridge_width 0.5)
				(island_removal_mode 0)
			)
			(polygon
				(pts
					(arc
						(start 331.790294 -45.571156)
						(mid 331.743693 -45.495329)
						(end 331.667866 -45.448728)
					)
					(arc
						(start 331.667866 -45.343572)
						(mid 331.815648 -45.423374)
						(end 331.89545 -45.571156)
					)
				)
			)
		)
		(zone
			(layer "F.Cu")
			(hatch none 0.5)
			(connect_pads
				(clearance 0)
			)
			(min_thickness 0.25)
			(keepout
				(tracks not_allowed)
				(vias allowed)
				(pads allowed)
				(copperpour not_allowed)
				(footprints allowed)
			)
			(placement
				(enabled no)
				(sheetname "")
			)
			(fill
				(thermal_gap 0.5)
				(thermal_bridge_width 0.5)
				(island_removal_mode 0)
			)
			(polygon
				(pts
					(arc
						(start 331.790294 -44.631356)
						(mid 331.743693 -44.555529)
						(end 331.667866 -44.508928)
					)
					(arc
						(start 331.667866 -44.403772)
						(mid 331.815648 -44.483574)
						(end 331.89545 -44.631356)
					)
				)
			)
		)
		(zone
			(layer "F.Cu")
			(hatch none 0.5)
			(connect_pads
				(clearance 0)
			)
			(min_thickness 0.25)
			(keepout
				(tracks not_allowed)
				(vias allowed)
				(pads allowed)
				(copperpour not_allowed)
				(footprints allowed)
			)
			(placement
				(enabled no)
				(sheetname "")
			)
			(fill
				(thermal_gap 0.5)
				(thermal_bridge_width 0.5)
				(island_removal_mode 0)
			)
			(polygon
				(pts
					(arc
						(start 331.790294 -43.691556)
						(mid 331.743693 -43.615729)
						(end 331.667866 -43.569128)
					)
					(arc
						(start 331.667866 -43.463972)
						(mid 331.815648 -43.543774)
						(end 331.89545 -43.691556)
					)
				)
			)
		)
		(zone
			(layer "F.Cu")
			(hatch none 0.5)
			(connect_pads
				(clearance 0)
			)
			(min_thickness 0.25)
			(keepout
				(tracks not_allowed)
				(vias allowed)
				(pads allowed)
				(copperpour not_allowed)
				(footprints allowed)
			)
			(placement
				(enabled no)
				(sheetname "")
			)
			(fill
				(thermal_gap 0.5)
				(thermal_bridge_width 0.5)
				(island_removal_mode 0)
			)
			(polygon
				(pts
					(arc
						(start 331.790294 -42.751756)
						(mid 331.743693 -42.675929)
						(end 331.667866 -42.629328)
					)
					(arc
						(start 331.667866 -42.524172)
						(mid 331.815648 -42.603974)
						(end 331.89545 -42.751756)
					)
				)
			)
		)
		(zone
			(layer "F.Cu")
			(hatch none 0.5)
			(connect_pads
				(clearance 0)
			)
			(min_thickness 0.25)
			(keepout
				(tracks not_allowed)
				(vias allowed)
				(pads allowed)
				(copperpour not_allowed)
				(footprints allowed)
			)
			(placement
				(enabled no)
				(sheetname "")
			)
			(fill
				(thermal_gap 0.5)
				(thermal_bridge_width 0.5)
				(island_removal_mode 0)
			)
			(polygon
				(pts
					(arc
						(start 331.790294 -41.811956)
						(mid 331.743693 -41.736129)
						(end 331.667866 -41.689528)
					)
					(arc
						(start 331.667866 -41.584372)
						(mid 331.815648 -41.664174)
						(end 331.89545 -41.811956)
					)
				)
			)
		)
		(zone
			(layer "F.Cu")
			(hatch none 0.5)
			(connect_pads
				(clearance 0)
			)
			(min_thickness 0.25)
			(keepout
				(tracks not_allowed)
				(vias allowed)
				(pads allowed)
				(copperpour not_allowed)
				(footprints allowed)
			)
			(placement
				(enabled no)
				(sheetname "")
			)
			(fill
				(thermal_gap 0.5)
				(thermal_bridge_width 0.5)
				(island_removal_mode 0)
			)
			(polygon
				(pts
					(arc
						(start 331.790294 -40.872156)
						(mid 331.743693 -40.796329)
						(end 331.667866 -40.749728)
					)
					(arc
						(start 331.667866 -40.644572)
						(mid 331.815648 -40.724374)
						(end 331.89545 -40.872156)
					)
				)
			)
		)
		(zone
			(layer "F.Cu")
			(hatch none 0.5)
			(connect_pads
				(clearance 0)
			)
			(min_thickness 0.25)
			(keepout
				(tracks not_allowed)
				(vias allowed)
				(pads allowed)
				(copperpour not_allowed)
				(footprints allowed)
			)
			(placement
				(enabled no)
				(sheetname "")
			)
			(fill
				(thermal_gap 0.5)
				(thermal_bridge_width 0.5)
				(island_removal_mode 0)
			)
			(polygon
				(pts
					(arc
						(start 331.790294 -39.932356)
						(mid 331.743693 -39.856529)
						(end 331.667866 -39.809928)
					)
					(arc
						(start 331.667866 -39.704772)
						(mid 331.815648 -39.784574)
						(end 331.89545 -39.932356)
					)
				)
			)
		)
		(zone
			(layer "F.Cu")
			(hatch none 0.5)
			(connect_pads
				(clearance 0)
			)
			(min_thickness 0.25)
			(keepout
				(tracks not_allowed)
				(vias allowed)
				(pads allowed)
				(copperpour not_allowed)
				(footprints allowed)
			)
			(placement
				(enabled no)
				(sheetname "")
			)
			(fill
				(thermal_gap 0.5)
				(thermal_bridge_width 0.5)
				(island_removal_mode 0)
			)
			(polygon
				(pts
					(arc
						(start 332.240382 -56.498236)
						(mid 332.286897 -56.573978)
						(end 332.362556 -56.620664)
					)
					(arc
						(start 332.362556 -56.72582)
						(mid 332.214774 -56.646018)
						(end 332.134972 -56.498236)
					)
				)
			)
		)
		(zone
			(layer "F.Cu")
			(hatch none 0.5)
			(connect_pads
				(clearance 0)
			)
			(min_thickness 0.25)
			(keepout
				(tracks not_allowed)
				(vias allowed)
				(pads allowed)
				(copperpour not_allowed)
				(footprints allowed)
			)
			(placement
				(enabled no)
				(sheetname "")
			)
			(fill
				(thermal_gap 0.5)
				(thermal_bridge_width 0.5)
				(island_removal_mode 0)
			)
			(polygon
				(pts
					(arc
						(start 332.240382 -55.558436)
						(mid 332.286897 -55.634178)
						(end 332.362556 -55.680864)
					)
					(arc
						(start 332.362556 -55.78602)
						(mid 332.214774 -55.706218)
						(end 332.134972 -55.558436)
					)
				)
			)
		)
		(zone
			(layer "F.Cu")
			(hatch none 0.5)
			(connect_pads
				(clearance 0)
			)
			(min_thickness 0.25)
			(keepout
				(tracks not_allowed)
				(vias allowed)
				(pads allowed)
				(copperpour not_allowed)
				(footprints allowed)
			)
			(placement
				(enabled no)
				(sheetname "")
			)
			(fill
				(thermal_gap 0.5)
				(thermal_bridge_width 0.5)
				(island_removal_mode 0)
			)
			(polygon
				(pts
					(arc
						(start 332.240382 -54.618636)
						(mid 332.286897 -54.694378)
						(end 332.362556 -54.741064)
					)
					(arc
						(start 332.362556 -54.84622)
						(mid 332.214774 -54.766418)
						(end 332.134972 -54.618636)
					)
				)
			)
		)
		(zone
			(layer "F.Cu")
			(hatch none 0.5)
			(connect_pads
				(clearance 0)
			)
			(min_thickness 0.25)
			(keepout
				(tracks not_allowed)
				(vias allowed)
				(pads allowed)
				(copperpour not_allowed)
				(footprints allowed)
			)
			(placement
				(enabled no)
				(sheetname "")
			)
			(fill
				(thermal_gap 0.5)
				(thermal_bridge_width 0.5)
				(island_removal_mode 0)
			)
			(polygon
				(pts
					(arc
						(start 332.240382 -53.678836)
						(mid 332.286897 -53.754578)
						(end 332.362556 -53.801264)
					)
					(arc
						(start 332.362556 -53.90642)
						(mid 332.214774 -53.826618)
						(end 332.134972 -53.678836)
					)
				)
			)
		)
		(zone
			(layer "F.Cu")
			(hatch none 0.5)
			(connect_pads
				(clearance 0)
			)
			(min_thickness 0.25)
			(keepout
				(tracks not_allowed)
				(vias allowed)
				(pads allowed)
				(copperpour not_allowed)
				(footprints allowed)
			)
			(placement
				(enabled no)
				(sheetname "")
			)
			(fill
				(thermal_gap 0.5)
				(thermal_bridge_width 0.5)
				(island_removal_mode 0)
			)
			(polygon
				(pts
					(arc
						(start 332.240382 -52.739036)
						(mid 332.286897 -52.814778)
						(end 332.362556 -52.861464)
					)
					(arc
						(start 332.362556 -52.96662)
						(mid 332.214774 -52.886818)
						(end 332.134972 -52.739036)
					)
				)
			)
		)
		(zone
			(layer "F.Cu")
			(hatch none 0.5)
			(connect_pads
				(clearance 0)
			)
			(min_thickness 0.25)
			(keepout
				(tracks not_allowed)
				(vias allowed)
				(pads allowed)
				(copperpour not_allowed)
				(footprints allowed)
			)
			(placement
				(enabled no)
				(sheetname "")
			)
			(fill
				(thermal_gap 0.5)
				(thermal_bridge_width 0.5)
				(island_removal_mode 0)
			)
			(polygon
				(pts
					(arc
						(start 332.240382 -51.799236)
						(mid 332.286897 -51.874978)
						(end 332.362556 -51.921664)
					)
					(arc
						(start 332.362556 -52.02682)
						(mid 332.214774 -51.947018)
						(end 332.134972 -51.799236)
					)
				)
			)
		)
		(zone
			(layer "F.Cu")
			(hatch none 0.5)
			(connect_pads
				(clearance 0)
			)
			(min_thickness 0.25)
			(keepout
				(tracks not_allowed)
				(vias allowed)
				(pads allowed)
				(copperpour not_allowed)
				(footprints allowed)
			)
			(placement
				(enabled no)
				(sheetname "")
			)
			(fill
				(thermal_gap 0.5)
				(thermal_bridge_width 0.5)
				(island_removal_mode 0)
			)
			(polygon
				(pts
					(arc
						(start 332.240382 -50.859436)
						(mid 332.286897 -50.935178)
						(end 332.362556 -50.981864)
					)
					(arc
						(start 332.362556 -51.08702)
						(mid 332.214774 -51.007218)
						(end 332.134972 -50.859436)
					)
				)
			)
		)
		(zone
			(layer "F.Cu")
			(hatch none 0.5)
			(connect_pads
				(clearance 0)
			)
			(min_thickness 0.25)
			(keepout
				(tracks not_allowed)
				(vias allowed)
				(pads allowed)
				(copperpour not_allowed)
				(footprints allowed)
			)
			(placement
				(enabled no)
				(sheetname "")
			)
			(fill
				(thermal_gap 0.5)
				(thermal_bridge_width 0.5)
				(island_removal_mode 0)
			)
			(polygon
				(pts
					(arc
						(start 332.240382 -49.919636)
						(mid 332.286897 -49.995378)
						(end 332.362556 -50.042064)
					)
					(arc
						(start 332.362556 -50.14722)
						(mid 332.214774 -50.067418)
						(end 332.134972 -49.919636)
					)
				)
			)
		)
		(zone
			(layer "F.Cu")
			(hatch none 0.5)
			(connect_pads
				(clearance 0)
			)
			(min_thickness 0.25)
			(keepout
				(tracks not_allowed)
				(vias allowed)
				(pads allowed)
				(copperpour not_allowed)
				(footprints allowed)
			)
			(placement
				(enabled no)
				(sheetname "")
			)
			(fill
				(thermal_gap 0.5)
				(thermal_bridge_width 0.5)
				(island_removal_mode 0)
			)
			(polygon
				(pts
					(arc
						(start 332.240382 -48.979836)
						(mid 332.286897 -49.055578)
						(end 332.362556 -49.102264)
					)
					(arc
						(start 332.362556 -49.20742)
						(mid 332.214774 -49.127618)
						(end 332.134972 -48.979836)
					)
				)
			)
		)
		(zone
			(layer "F.Cu")
			(hatch none 0.5)
			(connect_pads
				(clearance 0)
			)
			(min_thickness 0.25)
			(keepout
				(tracks not_allowed)
				(vias allowed)
				(pads allowed)
				(copperpour not_allowed)
				(footprints allowed)
			)
			(placement
				(enabled no)
				(sheetname "")
			)
			(fill
				(thermal_gap 0.5)
				(thermal_bridge_width 0.5)
				(island_removal_mode 0)
			)
			(polygon
				(pts
					(arc
						(start 332.240382 -48.040036)
						(mid 332.286897 -48.115778)
						(end 332.362556 -48.162464)
					)
					(arc
						(start 332.362556 -48.26762)
						(mid 332.214774 -48.187818)
						(end 332.134972 -48.040036)
					)
				)
			)
		)
		(zone
			(layer "F.Cu")
			(hatch none 0.5)
			(connect_pads
				(clearance 0)
			)
			(min_thickness 0.25)
			(keepout
				(tracks not_allowed)
				(vias allowed)
				(pads allowed)
				(copperpour not_allowed)
				(footprints allowed)
			)
			(placement
				(enabled no)
				(sheetname "")
			)
			(fill
				(thermal_gap 0.5)
				(thermal_bridge_width 0.5)
				(island_removal_mode 0)
			)
			(polygon
				(pts
					(arc
						(start 332.240382 -47.100236)
						(mid 332.286897 -47.175978)
						(end 332.362556 -47.222664)
					)
					(arc
						(start 332.362556 -47.32782)
						(mid 332.214774 -47.248018)
						(end 332.134972 -47.100236)
					)
				)
			)
		)
		(zone
			(layer "F.Cu")
			(hatch none 0.5)
			(connect_pads
				(clearance 0)
			)
			(min_thickness 0.25)
			(keepout
				(tracks not_allowed)
				(vias allowed)
				(pads allowed)
				(copperpour not_allowed)
				(footprints allowed)
			)
			(placement
				(enabled no)
				(sheetname "")
			)
			(fill
				(thermal_gap 0.5)
				(thermal_bridge_width 0.5)
				(island_removal_mode 0)
			)
			(polygon
				(pts
					(arc
						(start 332.240382 -46.160436)
						(mid 332.286897 -46.236178)
						(end 332.362556 -46.282864)
					)
					(arc
						(start 332.362556 -46.38802)
						(mid 332.214774 -46.308218)
						(end 332.134972 -46.160436)
					)
				)
			)
		)
		(zone
			(layer "F.Cu")
			(hatch none 0.5)
			(connect_pads
				(clearance 0)
			)
			(min_thickness 0.25)
			(keepout
				(tracks not_allowed)
				(vias allowed)
				(pads allowed)
				(copperpour not_allowed)
				(footprints allowed)
			)
			(placement
				(enabled no)
				(sheetname "")
			)
			(fill
				(thermal_gap 0.5)
				(thermal_bridge_width 0.5)
				(island_removal_mode 0)
			)
			(polygon
				(pts
					(arc
						(start 332.240382 -45.220636)
						(mid 332.286897 -45.296378)
						(end 332.362556 -45.343064)
					)
					(arc
						(start 332.362556 -45.44822)
						(mid 332.214774 -45.368418)
						(end 332.134972 -45.220636)
					)
				)
			)
		)
		(zone
			(layer "F.Cu")
			(hatch none 0.5)
			(connect_pads
				(clearance 0)
			)
			(min_thickness 0.25)
			(keepout
				(tracks not_allowed)
				(vias allowed)
				(pads allowed)
				(copperpour not_allowed)
				(footprints allowed)
			)
			(placement
				(enabled no)
				(sheetname "")
			)
			(fill
				(thermal_gap 0.5)
				(thermal_bridge_width 0.5)
				(island_removal_mode 0)
			)
			(polygon
				(pts
					(arc
						(start 332.240382 -44.280836)
						(mid 332.286897 -44.356578)
						(end 332.362556 -44.403264)
					)
					(arc
						(start 332.362556 -44.50842)
						(mid 332.214774 -44.428618)
						(end 332.134972 -44.280836)
					)
				)
			)
		)
		(zone
			(layer "F.Cu")
			(hatch none 0.5)
			(connect_pads
				(clearance 0)
			)
			(min_thickness 0.25)
			(keepout
				(tracks not_allowed)
				(vias allowed)
				(pads allowed)
				(copperpour not_allowed)
				(footprints allowed)
			)
			(placement
				(enabled no)
				(sheetname "")
			)
			(fill
				(thermal_gap 0.5)
				(thermal_bridge_width 0.5)
				(island_removal_mode 0)
			)
			(polygon
				(pts
					(arc
						(start 332.240382 -43.341036)
						(mid 332.286897 -43.416778)
						(end 332.362556 -43.463464)
					)
					(arc
						(start 332.362556 -43.56862)
						(mid 332.214774 -43.488818)
						(end 332.134972 -43.341036)
					)
				)
			)
		)
		(zone
			(layer "F.Cu")
			(hatch none 0.5)
			(connect_pads
				(clearance 0)
			)
			(min_thickness 0.25)
			(keepout
				(tracks not_allowed)
				(vias allowed)
				(pads allowed)
				(copperpour not_allowed)
				(footprints allowed)
			)
			(placement
				(enabled no)
				(sheetname "")
			)
			(fill
				(thermal_gap 0.5)
				(thermal_bridge_width 0.5)
				(island_removal_mode 0)
			)
			(polygon
				(pts
					(arc
						(start 332.240382 -42.401236)
						(mid 332.286897 -42.476978)
						(end 332.362556 -42.523664)
					)
					(arc
						(start 332.362556 -42.62882)
						(mid 332.214774 -42.549018)
						(end 332.134972 -42.401236)
					)
				)
			)
		)
		(zone
			(layer "F.Cu")
			(hatch none 0.5)
			(connect_pads
				(clearance 0)
			)
			(min_thickness 0.25)
			(keepout
				(tracks not_allowed)
				(vias allowed)
				(pads allowed)
				(copperpour not_allowed)
				(footprints allowed)
			)
			(placement
				(enabled no)
				(sheetname "")
			)
			(fill
				(thermal_gap 0.5)
				(thermal_bridge_width 0.5)
				(island_removal_mode 0)
			)
			(polygon
				(pts
					(arc
						(start 332.240382 -41.461436)
						(mid 332.286897 -41.537178)
						(end 332.362556 -41.583864)
					)
					(arc
						(start 332.362556 -41.68902)
						(mid 332.214774 -41.609218)
						(end 332.134972 -41.461436)
					)
				)
			)
		)
		(zone
			(layer "F.Cu")
			(hatch none 0.5)
			(connect_pads
				(clearance 0)
			)
			(min_thickness 0.25)
			(keepout
				(tracks not_allowed)
				(vias allowed)
				(pads allowed)
				(copperpour not_allowed)
				(footprints allowed)
			)
			(placement
				(enabled no)
				(sheetname "")
			)
			(fill
				(thermal_gap 0.5)
				(thermal_bridge_width 0.5)
				(island_removal_mode 0)
			)
			(polygon
				(pts
					(arc
						(start 332.240382 -40.521636)
						(mid 332.286897 -40.597378)
						(end 332.362556 -40.644064)
					)
					(arc
						(start 332.362556 -40.74922)
						(mid 332.214774 -40.669418)
						(end 332.134972 -40.521636)
					)
				)
			)
		)
		(zone
			(layer "F.Cu")
			(hatch none 0.5)
			(connect_pads
				(clearance 0)
			)
			(min_thickness 0.25)
			(keepout
				(tracks not_allowed)
				(vias allowed)
				(pads allowed)
				(copperpour not_allowed)
				(footprints allowed)
			)
			(placement
				(enabled no)
				(sheetname "")
			)
			(fill
				(thermal_gap 0.5)
				(thermal_bridge_width 0.5)
				(island_removal_mode 0)
			)
			(polygon
				(pts
					(arc
						(start 332.362556 -56.256428)
						(mid 332.286841 -56.303058)
						(end 332.240382 -56.378856)
					)
					(arc
						(start 332.134972 -56.378856)
						(mid 332.214774 -56.231074)
						(end 332.362556 -56.151272)
					)
				)
			)
		)
		(zone
			(layer "F.Cu")
			(hatch none 0.5)
			(connect_pads
				(clearance 0)
			)
			(min_thickness 0.25)
			(keepout
				(tracks not_allowed)
				(vias allowed)
				(pads allowed)
				(copperpour not_allowed)
				(footprints allowed)
			)
			(placement
				(enabled no)
				(sheetname "")
			)
			(fill
				(thermal_gap 0.5)
				(thermal_bridge_width 0.5)
				(island_removal_mode 0)
			)
			(polygon
				(pts
					(arc
						(start 332.362556 -55.316628)
						(mid 332.286841 -55.363258)
						(end 332.240382 -55.439056)
					)
					(arc
						(start 332.134972 -55.439056)
						(mid 332.214774 -55.291274)
						(end 332.362556 -55.211472)
					)
				)
			)
		)
		(zone
			(layer "F.Cu")
			(hatch none 0.5)
			(connect_pads
				(clearance 0)
			)
			(min_thickness 0.25)
			(keepout
				(tracks not_allowed)
				(vias allowed)
				(pads allowed)
				(copperpour not_allowed)
				(footprints allowed)
			)
			(placement
				(enabled no)
				(sheetname "")
			)
			(fill
				(thermal_gap 0.5)
				(thermal_bridge_width 0.5)
				(island_removal_mode 0)
			)
			(polygon
				(pts
					(arc
						(start 332.362556 -54.376828)
						(mid 332.286841 -54.423458)
						(end 332.240382 -54.499256)
					)
					(arc
						(start 332.134972 -54.499256)
						(mid 332.214774 -54.351474)
						(end 332.362556 -54.271672)
					)
				)
			)
		)
		(zone
			(layer "F.Cu")
			(hatch none 0.5)
			(connect_pads
				(clearance 0)
			)
			(min_thickness 0.25)
			(keepout
				(tracks not_allowed)
				(vias allowed)
				(pads allowed)
				(copperpour not_allowed)
				(footprints allowed)
			)
			(placement
				(enabled no)
				(sheetname "")
			)
			(fill
				(thermal_gap 0.5)
				(thermal_bridge_width 0.5)
				(island_removal_mode 0)
			)
			(polygon
				(pts
					(arc
						(start 332.362556 -53.437028)
						(mid 332.286841 -53.483658)
						(end 332.240382 -53.559456)
					)
					(arc
						(start 332.134972 -53.559456)
						(mid 332.214774 -53.411674)
						(end 332.362556 -53.331872)
					)
				)
			)
		)
		(zone
			(layer "F.Cu")
			(hatch none 0.5)
			(connect_pads
				(clearance 0)
			)
			(min_thickness 0.25)
			(keepout
				(tracks not_allowed)
				(vias allowed)
				(pads allowed)
				(copperpour not_allowed)
				(footprints allowed)
			)
			(placement
				(enabled no)
				(sheetname "")
			)
			(fill
				(thermal_gap 0.5)
				(thermal_bridge_width 0.5)
				(island_removal_mode 0)
			)
			(polygon
				(pts
					(arc
						(start 332.362556 -52.497228)
						(mid 332.286841 -52.543858)
						(end 332.240382 -52.619656)
					)
					(arc
						(start 332.134972 -52.619656)
						(mid 332.214774 -52.471874)
						(end 332.362556 -52.392072)
					)
				)
			)
		)
		(zone
			(layer "F.Cu")
			(hatch none 0.5)
			(connect_pads
				(clearance 0)
			)
			(min_thickness 0.25)
			(keepout
				(tracks not_allowed)
				(vias allowed)
				(pads allowed)
				(copperpour not_allowed)
				(footprints allowed)
			)
			(placement
				(enabled no)
				(sheetname "")
			)
			(fill
				(thermal_gap 0.5)
				(thermal_bridge_width 0.5)
				(island_removal_mode 0)
			)
			(polygon
				(pts
					(arc
						(start 332.362556 -51.557428)
						(mid 332.286841 -51.604058)
						(end 332.240382 -51.679856)
					)
					(arc
						(start 332.134972 -51.679856)
						(mid 332.214774 -51.532074)
						(end 332.362556 -51.452272)
					)
				)
			)
		)
		(zone
			(layer "F.Cu")
			(hatch none 0.5)
			(connect_pads
				(clearance 0)
			)
			(min_thickness 0.25)
			(keepout
				(tracks not_allowed)
				(vias allowed)
				(pads allowed)
				(copperpour not_allowed)
				(footprints allowed)
			)
			(placement
				(enabled no)
				(sheetname "")
			)
			(fill
				(thermal_gap 0.5)
				(thermal_bridge_width 0.5)
				(island_removal_mode 0)
			)
			(polygon
				(pts
					(arc
						(start 332.362556 -50.617628)
						(mid 332.286841 -50.664258)
						(end 332.240382 -50.740056)
					)
					(arc
						(start 332.134972 -50.740056)
						(mid 332.214774 -50.592274)
						(end 332.362556 -50.512472)
					)
				)
			)
		)
		(zone
			(layer "F.Cu")
			(hatch none 0.5)
			(connect_pads
				(clearance 0)
			)
			(min_thickness 0.25)
			(keepout
				(tracks not_allowed)
				(vias allowed)
				(pads allowed)
				(copperpour not_allowed)
				(footprints allowed)
			)
			(placement
				(enabled no)
				(sheetname "")
			)
			(fill
				(thermal_gap 0.5)
				(thermal_bridge_width 0.5)
				(island_removal_mode 0)
			)
			(polygon
				(pts
					(arc
						(start 332.362556 -49.677828)
						(mid 332.286841 -49.724458)
						(end 332.240382 -49.800256)
					)
					(arc
						(start 332.134972 -49.800256)
						(mid 332.214774 -49.652474)
						(end 332.362556 -49.572672)
					)
				)
			)
		)
		(zone
			(layer "F.Cu")
			(hatch none 0.5)
			(connect_pads
				(clearance 0)
			)
			(min_thickness 0.25)
			(keepout
				(tracks not_allowed)
				(vias allowed)
				(pads allowed)
				(copperpour not_allowed)
				(footprints allowed)
			)
			(placement
				(enabled no)
				(sheetname "")
			)
			(fill
				(thermal_gap 0.5)
				(thermal_bridge_width 0.5)
				(island_removal_mode 0)
			)
			(polygon
				(pts
					(arc
						(start 332.362556 -48.738028)
						(mid 332.286841 -48.784658)
						(end 332.240382 -48.860456)
					)
					(arc
						(start 332.134972 -48.860456)
						(mid 332.214774 -48.712674)
						(end 332.362556 -48.632872)
					)
				)
			)
		)
		(zone
			(layer "F.Cu")
			(hatch none 0.5)
			(connect_pads
				(clearance 0)
			)
			(min_thickness 0.25)
			(keepout
				(tracks not_allowed)
				(vias allowed)
				(pads allowed)
				(copperpour not_allowed)
				(footprints allowed)
			)
			(placement
				(enabled no)
				(sheetname "")
			)
			(fill
				(thermal_gap 0.5)
				(thermal_bridge_width 0.5)
				(island_removal_mode 0)
			)
			(polygon
				(pts
					(arc
						(start 332.362556 -47.798228)
						(mid 332.286841 -47.844858)
						(end 332.240382 -47.920656)
					)
					(arc
						(start 332.134972 -47.920656)
						(mid 332.214774 -47.772874)
						(end 332.362556 -47.693072)
					)
				)
			)
		)
		(zone
			(layer "F.Cu")
			(hatch none 0.5)
			(connect_pads
				(clearance 0)
			)
			(min_thickness 0.25)
			(keepout
				(tracks not_allowed)
				(vias allowed)
				(pads allowed)
				(copperpour not_allowed)
				(footprints allowed)
			)
			(placement
				(enabled no)
				(sheetname "")
			)
			(fill
				(thermal_gap 0.5)
				(thermal_bridge_width 0.5)
				(island_removal_mode 0)
			)
			(polygon
				(pts
					(arc
						(start 332.362556 -46.858428)
						(mid 332.286841 -46.905058)
						(end 332.240382 -46.980856)
					)
					(arc
						(start 332.134972 -46.980856)
						(mid 332.214774 -46.833074)
						(end 332.362556 -46.753272)
					)
				)
			)
		)
		(zone
			(layer "F.Cu")
			(hatch none 0.5)
			(connect_pads
				(clearance 0)
			)
			(min_thickness 0.25)
			(keepout
				(tracks not_allowed)
				(vias allowed)
				(pads allowed)
				(copperpour not_allowed)
				(footprints allowed)
			)
			(placement
				(enabled no)
				(sheetname "")
			)
			(fill
				(thermal_gap 0.5)
				(thermal_bridge_width 0.5)
				(island_removal_mode 0)
			)
			(polygon
				(pts
					(arc
						(start 332.362556 -45.918628)
						(mid 332.286841 -45.965258)
						(end 332.240382 -46.041056)
					)
					(arc
						(start 332.134972 -46.041056)
						(mid 332.214774 -45.893274)
						(end 332.362556 -45.813472)
					)
				)
			)
		)
		(zone
			(layer "F.Cu")
			(hatch none 0.5)
			(connect_pads
				(clearance 0)
			)
			(min_thickness 0.25)
			(keepout
				(tracks not_allowed)
				(vias allowed)
				(pads allowed)
				(copperpour not_allowed)
				(footprints allowed)
			)
			(placement
				(enabled no)
				(sheetname "")
			)
			(fill
				(thermal_gap 0.5)
				(thermal_bridge_width 0.5)
				(island_removal_mode 0)
			)
			(polygon
				(pts
					(arc
						(start 332.362556 -44.978828)
						(mid 332.286841 -45.025458)
						(end 332.240382 -45.101256)
					)
					(arc
						(start 332.134972 -45.101256)
						(mid 332.214774 -44.953474)
						(end 332.362556 -44.873672)
					)
				)
			)
		)
		(zone
			(layer "F.Cu")
			(hatch none 0.5)
			(connect_pads
				(clearance 0)
			)
			(min_thickness 0.25)
			(keepout
				(tracks not_allowed)
				(vias allowed)
				(pads allowed)
				(copperpour not_allowed)
				(footprints allowed)
			)
			(placement
				(enabled no)
				(sheetname "")
			)
			(fill
				(thermal_gap 0.5)
				(thermal_bridge_width 0.5)
				(island_removal_mode 0)
			)
			(polygon
				(pts
					(arc
						(start 332.362556 -44.039028)
						(mid 332.286841 -44.085658)
						(end 332.240382 -44.161456)
					)
					(arc
						(start 332.134972 -44.161456)
						(mid 332.214774 -44.013674)
						(end 332.362556 -43.933872)
					)
				)
			)
		)
		(zone
			(layer "F.Cu")
			(hatch none 0.5)
			(connect_pads
				(clearance 0)
			)
			(min_thickness 0.25)
			(keepout
				(tracks not_allowed)
				(vias allowed)
				(pads allowed)
				(copperpour not_allowed)
				(footprints allowed)
			)
			(placement
				(enabled no)
				(sheetname "")
			)
			(fill
				(thermal_gap 0.5)
				(thermal_bridge_width 0.5)
				(island_removal_mode 0)
			)
			(polygon
				(pts
					(arc
						(start 332.362556 -43.099228)
						(mid 332.286841 -43.145858)
						(end 332.240382 -43.221656)
					)
					(arc
						(start 332.134972 -43.221656)
						(mid 332.214774 -43.073874)
						(end 332.362556 -42.994072)
					)
				)
			)
		)
		(zone
			(layer "F.Cu")
			(hatch none 0.5)
			(connect_pads
				(clearance 0)
			)
			(min_thickness 0.25)
			(keepout
				(tracks not_allowed)
				(vias allowed)
				(pads allowed)
				(copperpour not_allowed)
				(footprints allowed)
			)
			(placement
				(enabled no)
				(sheetname "")
			)
			(fill
				(thermal_gap 0.5)
				(thermal_bridge_width 0.5)
				(island_removal_mode 0)
			)
			(polygon
				(pts
					(arc
						(start 332.362556 -42.159428)
						(mid 332.286841 -42.206058)
						(end 332.240382 -42.281856)
					)
					(arc
						(start 332.134972 -42.281856)
						(mid 332.214774 -42.134074)
						(end 332.362556 -42.054272)
					)
				)
			)
		)
		(zone
			(layer "F.Cu")
			(hatch none 0.5)
			(connect_pads
				(clearance 0)
			)
			(min_thickness 0.25)
			(keepout
				(tracks not_allowed)
				(vias allowed)
				(pads allowed)
				(copperpour not_allowed)
				(footprints allowed)
			)
			(placement
				(enabled no)
				(sheetname "")
			)
			(fill
				(thermal_gap 0.5)
				(thermal_bridge_width 0.5)
				(island_removal_mode 0)
			)
			(polygon
				(pts
					(arc
						(start 332.362556 -41.219628)
						(mid 332.286841 -41.266258)
						(end 332.240382 -41.342056)
					)
					(arc
						(start 332.134972 -41.342056)
						(mid 332.214774 -41.194274)
						(end 332.362556 -41.114472)
					)
				)
			)
		)
		(zone
			(layer "F.Cu")
			(hatch none 0.5)
			(connect_pads
				(clearance 0)
			)
			(min_thickness 0.25)
			(keepout
				(tracks not_allowed)
				(vias allowed)
				(pads allowed)
				(copperpour not_allowed)
				(footprints allowed)
			)
			(placement
				(enabled no)
				(sheetname "")
			)
			(fill
				(thermal_gap 0.5)
				(thermal_bridge_width 0.5)
				(island_removal_mode 0)
			)
			(polygon
				(pts
					(arc
						(start 332.362556 -40.279828)
						(mid 332.286841 -40.326458)
						(end 332.240382 -40.402256)
					)
					(arc
						(start 332.134972 -40.402256)
						(mid 332.214774 -40.254474)
						(end 332.362556 -40.174672)
					)
				)
			)
		)
		(zone
			(layer "F.Cu")
			(hatch none 0.5)
			(connect_pads
				(clearance 0)
			)
			(min_thickness 0.25)
			(keepout
				(tracks not_allowed)
				(vias allowed)
				(pads allowed)
				(copperpour not_allowed)
				(footprints allowed)
			)
			(placement
				(enabled no)
				(sheetname "")
			)
			(fill
				(thermal_gap 0.5)
				(thermal_bridge_width 0.5)
				(island_removal_mode 0)
			)
			(polygon
				(pts
					(arc
						(start 332.481936 -56.620664)
						(mid 332.557763 -56.574063)
						(end 332.604364 -56.498236)
					)
					(arc
						(start 332.709774 -56.498236)
						(mid 332.629884 -56.646106)
						(end 332.481936 -56.72582)
					)
				)
			)
		)
		(zone
			(layer "F.Cu")
			(hatch none 0.5)
			(connect_pads
				(clearance 0)
			)
			(min_thickness 0.25)
			(keepout
				(tracks not_allowed)
				(vias allowed)
				(pads allowed)
				(copperpour not_allowed)
				(footprints allowed)
			)
			(placement
				(enabled no)
				(sheetname "")
			)
			(fill
				(thermal_gap 0.5)
				(thermal_bridge_width 0.5)
				(island_removal_mode 0)
			)
			(polygon
				(pts
					(arc
						(start 332.481936 -55.680864)
						(mid 332.557763 -55.634263)
						(end 332.604364 -55.558436)
					)
					(arc
						(start 332.709774 -55.558436)
						(mid 332.629884 -55.706306)
						(end 332.481936 -55.78602)
					)
				)
			)
		)
		(zone
			(layer "F.Cu")
			(hatch none 0.5)
			(connect_pads
				(clearance 0)
			)
			(min_thickness 0.25)
			(keepout
				(tracks not_allowed)
				(vias allowed)
				(pads allowed)
				(copperpour not_allowed)
				(footprints allowed)
			)
			(placement
				(enabled no)
				(sheetname "")
			)
			(fill
				(thermal_gap 0.5)
				(thermal_bridge_width 0.5)
				(island_removal_mode 0)
			)
			(polygon
				(pts
					(arc
						(start 332.481936 -54.741064)
						(mid 332.557763 -54.694463)
						(end 332.604364 -54.618636)
					)
					(arc
						(start 332.709774 -54.618636)
						(mid 332.629884 -54.766506)
						(end 332.481936 -54.84622)
					)
				)
			)
		)
		(zone
			(layer "F.Cu")
			(hatch none 0.5)
			(connect_pads
				(clearance 0)
			)
			(min_thickness 0.25)
			(keepout
				(tracks not_allowed)
				(vias allowed)
				(pads allowed)
				(copperpour not_allowed)
				(footprints allowed)
			)
			(placement
				(enabled no)
				(sheetname "")
			)
			(fill
				(thermal_gap 0.5)
				(thermal_bridge_width 0.5)
				(island_removal_mode 0)
			)
			(polygon
				(pts
					(arc
						(start 332.481936 -53.801264)
						(mid 332.557763 -53.754663)
						(end 332.604364 -53.678836)
					)
					(arc
						(start 332.709774 -53.678836)
						(mid 332.629884 -53.826706)
						(end 332.481936 -53.90642)
					)
				)
			)
		)
		(zone
			(layer "F.Cu")
			(hatch none 0.5)
			(connect_pads
				(clearance 0)
			)
			(min_thickness 0.25)
			(keepout
				(tracks not_allowed)
				(vias allowed)
				(pads allowed)
				(copperpour not_allowed)
				(footprints allowed)
			)
			(placement
				(enabled no)
				(sheetname "")
			)
			(fill
				(thermal_gap 0.5)
				(thermal_bridge_width 0.5)
				(island_removal_mode 0)
			)
			(polygon
				(pts
					(arc
						(start 332.481936 -52.861464)
						(mid 332.557763 -52.814863)
						(end 332.604364 -52.739036)
					)
					(arc
						(start 332.709774 -52.739036)
						(mid 332.629884 -52.886906)
						(end 332.481936 -52.96662)
					)
				)
			)
		)
		(zone
			(layer "F.Cu")
			(hatch none 0.5)
			(connect_pads
				(clearance 0)
			)
			(min_thickness 0.25)
			(keepout
				(tracks not_allowed)
				(vias allowed)
				(pads allowed)
				(copperpour not_allowed)
				(footprints allowed)
			)
			(placement
				(enabled no)
				(sheetname "")
			)
			(fill
				(thermal_gap 0.5)
				(thermal_bridge_width 0.5)
				(island_removal_mode 0)
			)
			(polygon
				(pts
					(arc
						(start 332.481936 -51.921664)
						(mid 332.557763 -51.875063)
						(end 332.604364 -51.799236)
					)
					(arc
						(start 332.709774 -51.799236)
						(mid 332.629884 -51.947106)
						(end 332.481936 -52.02682)
					)
				)
			)
		)
		(zone
			(layer "F.Cu")
			(hatch none 0.5)
			(connect_pads
				(clearance 0)
			)
			(min_thickness 0.25)
			(keepout
				(tracks not_allowed)
				(vias allowed)
				(pads allowed)
				(copperpour not_allowed)
				(footprints allowed)
			)
			(placement
				(enabled no)
				(sheetname "")
			)
			(fill
				(thermal_gap 0.5)
				(thermal_bridge_width 0.5)
				(island_removal_mode 0)
			)
			(polygon
				(pts
					(arc
						(start 332.481936 -50.981864)
						(mid 332.557763 -50.935263)
						(end 332.604364 -50.859436)
					)
					(arc
						(start 332.709774 -50.859436)
						(mid 332.629884 -51.007306)
						(end 332.481936 -51.08702)
					)
				)
			)
		)
		(zone
			(layer "F.Cu")
			(hatch none 0.5)
			(connect_pads
				(clearance 0)
			)
			(min_thickness 0.25)
			(keepout
				(tracks not_allowed)
				(vias allowed)
				(pads allowed)
				(copperpour not_allowed)
				(footprints allowed)
			)
			(placement
				(enabled no)
				(sheetname "")
			)
			(fill
				(thermal_gap 0.5)
				(thermal_bridge_width 0.5)
				(island_removal_mode 0)
			)
			(polygon
				(pts
					(arc
						(start 332.481936 -50.042064)
						(mid 332.557763 -49.995463)
						(end 332.604364 -49.919636)
					)
					(arc
						(start 332.709774 -49.919636)
						(mid 332.629884 -50.067506)
						(end 332.481936 -50.14722)
					)
				)
			)
		)
		(zone
			(layer "F.Cu")
			(hatch none 0.5)
			(connect_pads
				(clearance 0)
			)
			(min_thickness 0.25)
			(keepout
				(tracks not_allowed)
				(vias allowed)
				(pads allowed)
				(copperpour not_allowed)
				(footprints allowed)
			)
			(placement
				(enabled no)
				(sheetname "")
			)
			(fill
				(thermal_gap 0.5)
				(thermal_bridge_width 0.5)
				(island_removal_mode 0)
			)
			(polygon
				(pts
					(arc
						(start 332.481936 -49.102264)
						(mid 332.557763 -49.055663)
						(end 332.604364 -48.979836)
					)
					(arc
						(start 332.709774 -48.979836)
						(mid 332.629884 -49.127706)
						(end 332.481936 -49.20742)
					)
				)
			)
		)
		(zone
			(layer "F.Cu")
			(hatch none 0.5)
			(connect_pads
				(clearance 0)
			)
			(min_thickness 0.25)
			(keepout
				(tracks not_allowed)
				(vias allowed)
				(pads allowed)
				(copperpour not_allowed)
				(footprints allowed)
			)
			(placement
				(enabled no)
				(sheetname "")
			)
			(fill
				(thermal_gap 0.5)
				(thermal_bridge_width 0.5)
				(island_removal_mode 0)
			)
			(polygon
				(pts
					(arc
						(start 332.481936 -48.162464)
						(mid 332.557763 -48.115863)
						(end 332.604364 -48.040036)
					)
					(arc
						(start 332.709774 -48.040036)
						(mid 332.629884 -48.187906)
						(end 332.481936 -48.26762)
					)
				)
			)
		)
		(zone
			(layer "F.Cu")
			(hatch none 0.5)
			(connect_pads
				(clearance 0)
			)
			(min_thickness 0.25)
			(keepout
				(tracks not_allowed)
				(vias allowed)
				(pads allowed)
				(copperpour not_allowed)
				(footprints allowed)
			)
			(placement
				(enabled no)
				(sheetname "")
			)
			(fill
				(thermal_gap 0.5)
				(thermal_bridge_width 0.5)
				(island_removal_mode 0)
			)
			(polygon
				(pts
					(arc
						(start 332.481936 -47.222664)
						(mid 332.557763 -47.176063)
						(end 332.604364 -47.100236)
					)
					(arc
						(start 332.709774 -47.100236)
						(mid 332.629884 -47.248106)
						(end 332.481936 -47.32782)
					)
				)
			)
		)
		(zone
			(layer "F.Cu")
			(hatch none 0.5)
			(connect_pads
				(clearance 0)
			)
			(min_thickness 0.25)
			(keepout
				(tracks not_allowed)
				(vias allowed)
				(pads allowed)
				(copperpour not_allowed)
				(footprints allowed)
			)
			(placement
				(enabled no)
				(sheetname "")
			)
			(fill
				(thermal_gap 0.5)
				(thermal_bridge_width 0.5)
				(island_removal_mode 0)
			)
			(polygon
				(pts
					(arc
						(start 332.481936 -46.282864)
						(mid 332.557763 -46.236263)
						(end 332.604364 -46.160436)
					)
					(arc
						(start 332.709774 -46.160436)
						(mid 332.629884 -46.308306)
						(end 332.481936 -46.38802)
					)
				)
			)
		)
		(zone
			(layer "F.Cu")
			(hatch none 0.5)
			(connect_pads
				(clearance 0)
			)
			(min_thickness 0.25)
			(keepout
				(tracks not_allowed)
				(vias allowed)
				(pads allowed)
				(copperpour not_allowed)
				(footprints allowed)
			)
			(placement
				(enabled no)
				(sheetname "")
			)
			(fill
				(thermal_gap 0.5)
				(thermal_bridge_width 0.5)
				(island_removal_mode 0)
			)
			(polygon
				(pts
					(arc
						(start 332.481936 -45.343064)
						(mid 332.557763 -45.296463)
						(end 332.604364 -45.220636)
					)
					(arc
						(start 332.709774 -45.220636)
						(mid 332.629884 -45.368506)
						(end 332.481936 -45.44822)
					)
				)
			)
		)
		(zone
			(layer "F.Cu")
			(hatch none 0.5)
			(connect_pads
				(clearance 0)
			)
			(min_thickness 0.25)
			(keepout
				(tracks not_allowed)
				(vias allowed)
				(pads allowed)
				(copperpour not_allowed)
				(footprints allowed)
			)
			(placement
				(enabled no)
				(sheetname "")
			)
			(fill
				(thermal_gap 0.5)
				(thermal_bridge_width 0.5)
				(island_removal_mode 0)
			)
			(polygon
				(pts
					(arc
						(start 332.481936 -44.403264)
						(mid 332.557763 -44.356663)
						(end 332.604364 -44.280836)
					)
					(arc
						(start 332.709774 -44.280836)
						(mid 332.629884 -44.428706)
						(end 332.481936 -44.50842)
					)
				)
			)
		)
		(zone
			(layer "F.Cu")
			(hatch none 0.5)
			(connect_pads
				(clearance 0)
			)
			(min_thickness 0.25)
			(keepout
				(tracks not_allowed)
				(vias allowed)
				(pads allowed)
				(copperpour not_allowed)
				(footprints allowed)
			)
			(placement
				(enabled no)
				(sheetname "")
			)
			(fill
				(thermal_gap 0.5)
				(thermal_bridge_width 0.5)
				(island_removal_mode 0)
			)
			(polygon
				(pts
					(arc
						(start 332.481936 -43.463464)
						(mid 332.557763 -43.416863)
						(end 332.604364 -43.341036)
					)
					(arc
						(start 332.709774 -43.341036)
						(mid 332.629884 -43.488906)
						(end 332.481936 -43.56862)
					)
				)
			)
		)
		(zone
			(layer "F.Cu")
			(hatch none 0.5)
			(connect_pads
				(clearance 0)
			)
			(min_thickness 0.25)
			(keepout
				(tracks not_allowed)
				(vias allowed)
				(pads allowed)
				(copperpour not_allowed)
				(footprints allowed)
			)
			(placement
				(enabled no)
				(sheetname "")
			)
			(fill
				(thermal_gap 0.5)
				(thermal_bridge_width 0.5)
				(island_removal_mode 0)
			)
			(polygon
				(pts
					(arc
						(start 332.481936 -42.523664)
						(mid 332.557763 -42.477063)
						(end 332.604364 -42.401236)
					)
					(arc
						(start 332.709774 -42.401236)
						(mid 332.629884 -42.549106)
						(end 332.481936 -42.62882)
					)
				)
			)
		)
		(zone
			(layer "F.Cu")
			(hatch none 0.5)
			(connect_pads
				(clearance 0)
			)
			(min_thickness 0.25)
			(keepout
				(tracks not_allowed)
				(vias allowed)
				(pads allowed)
				(copperpour not_allowed)
				(footprints allowed)
			)
			(placement
				(enabled no)
				(sheetname "")
			)
			(fill
				(thermal_gap 0.5)
				(thermal_bridge_width 0.5)
				(island_removal_mode 0)
			)
			(polygon
				(pts
					(arc
						(start 332.481936 -41.583864)
						(mid 332.557763 -41.537263)
						(end 332.604364 -41.461436)
					)
					(arc
						(start 332.709774 -41.461436)
						(mid 332.629884 -41.609306)
						(end 332.481936 -41.68902)
					)
				)
			)
		)
		(zone
			(layer "F.Cu")
			(hatch none 0.5)
			(connect_pads
				(clearance 0)
			)
			(min_thickness 0.25)
			(keepout
				(tracks not_allowed)
				(vias allowed)
				(pads allowed)
				(copperpour not_allowed)
				(footprints allowed)
			)
			(placement
				(enabled no)
				(sheetname "")
			)
			(fill
				(thermal_gap 0.5)
				(thermal_bridge_width 0.5)
				(island_removal_mode 0)
			)
			(polygon
				(pts
					(arc
						(start 332.481936 -40.644064)
						(mid 332.557763 -40.597463)
						(end 332.604364 -40.521636)
					)
					(arc
						(start 332.709774 -40.521636)
						(mid 332.629884 -40.669506)
						(end 332.481936 -40.74922)
					)
				)
			)
		)
		(zone
			(layer "F.Cu")
			(hatch none 0.5)
			(connect_pads
				(clearance 0)
			)
			(min_thickness 0.25)
			(keepout
				(tracks not_allowed)
				(vias allowed)
				(pads allowed)
				(copperpour not_allowed)
				(footprints allowed)
			)
			(placement
				(enabled no)
				(sheetname "")
			)
			(fill
				(thermal_gap 0.5)
				(thermal_bridge_width 0.5)
				(island_removal_mode 0)
			)
			(polygon
				(pts
					(arc
						(start 332.604364 -56.378856)
						(mid 332.557763 -56.303029)
						(end 332.481936 -56.256428)
					)
					(arc
						(start 332.481936 -56.151272)
						(mid 332.629848 -56.231023)
						(end 332.709774 -56.378856)
					)
				)
			)
		)
		(zone
			(layer "F.Cu")
			(hatch none 0.5)
			(connect_pads
				(clearance 0)
			)
			(min_thickness 0.25)
			(keepout
				(tracks not_allowed)
				(vias allowed)
				(pads allowed)
				(copperpour not_allowed)
				(footprints allowed)
			)
			(placement
				(enabled no)
				(sheetname "")
			)
			(fill
				(thermal_gap 0.5)
				(thermal_bridge_width 0.5)
				(island_removal_mode 0)
			)
			(polygon
				(pts
					(arc
						(start 332.604364 -55.439056)
						(mid 332.557763 -55.363229)
						(end 332.481936 -55.316628)
					)
					(arc
						(start 332.481936 -55.211472)
						(mid 332.629848 -55.291223)
						(end 332.709774 -55.439056)
					)
				)
			)
		)
		(zone
			(layer "F.Cu")
			(hatch none 0.5)
			(connect_pads
				(clearance 0)
			)
			(min_thickness 0.25)
			(keepout
				(tracks not_allowed)
				(vias allowed)
				(pads allowed)
				(copperpour not_allowed)
				(footprints allowed)
			)
			(placement
				(enabled no)
				(sheetname "")
			)
			(fill
				(thermal_gap 0.5)
				(thermal_bridge_width 0.5)
				(island_removal_mode 0)
			)
			(polygon
				(pts
					(arc
						(start 332.604364 -54.499256)
						(mid 332.557763 -54.423429)
						(end 332.481936 -54.376828)
					)
					(arc
						(start 332.481936 -54.271672)
						(mid 332.629848 -54.351423)
						(end 332.709774 -54.499256)
					)
				)
			)
		)
		(zone
			(layer "F.Cu")
			(hatch none 0.5)
			(connect_pads
				(clearance 0)
			)
			(min_thickness 0.25)
			(keepout
				(tracks not_allowed)
				(vias allowed)
				(pads allowed)
				(copperpour not_allowed)
				(footprints allowed)
			)
			(placement
				(enabled no)
				(sheetname "")
			)
			(fill
				(thermal_gap 0.5)
				(thermal_bridge_width 0.5)
				(island_removal_mode 0)
			)
			(polygon
				(pts
					(arc
						(start 332.604364 -53.559456)
						(mid 332.557763 -53.483629)
						(end 332.481936 -53.437028)
					)
					(arc
						(start 332.481936 -53.331872)
						(mid 332.629848 -53.411623)
						(end 332.709774 -53.559456)
					)
				)
			)
		)
		(zone
			(layer "F.Cu")
			(hatch none 0.5)
			(connect_pads
				(clearance 0)
			)
			(min_thickness 0.25)
			(keepout
				(tracks not_allowed)
				(vias allowed)
				(pads allowed)
				(copperpour not_allowed)
				(footprints allowed)
			)
			(placement
				(enabled no)
				(sheetname "")
			)
			(fill
				(thermal_gap 0.5)
				(thermal_bridge_width 0.5)
				(island_removal_mode 0)
			)
			(polygon
				(pts
					(arc
						(start 332.604364 -52.619656)
						(mid 332.557763 -52.543829)
						(end 332.481936 -52.497228)
					)
					(arc
						(start 332.481936 -52.392072)
						(mid 332.629848 -52.471823)
						(end 332.709774 -52.619656)
					)
				)
			)
		)
		(zone
			(layer "F.Cu")
			(hatch none 0.5)
			(connect_pads
				(clearance 0)
			)
			(min_thickness 0.25)
			(keepout
				(tracks not_allowed)
				(vias allowed)
				(pads allowed)
				(copperpour not_allowed)
				(footprints allowed)
			)
			(placement
				(enabled no)
				(sheetname "")
			)
			(fill
				(thermal_gap 0.5)
				(thermal_bridge_width 0.5)
				(island_removal_mode 0)
			)
			(polygon
				(pts
					(arc
						(start 332.604364 -51.679856)
						(mid 332.557763 -51.604029)
						(end 332.481936 -51.557428)
					)
					(arc
						(start 332.481936 -51.452272)
						(mid 332.629848 -51.532023)
						(end 332.709774 -51.679856)
					)
				)
			)
		)
		(zone
			(layer "F.Cu")
			(hatch none 0.5)
			(connect_pads
				(clearance 0)
			)
			(min_thickness 0.25)
			(keepout
				(tracks not_allowed)
				(vias allowed)
				(pads allowed)
				(copperpour not_allowed)
				(footprints allowed)
			)
			(placement
				(enabled no)
				(sheetname "")
			)
			(fill
				(thermal_gap 0.5)
				(thermal_bridge_width 0.5)
				(island_removal_mode 0)
			)
			(polygon
				(pts
					(arc
						(start 332.604364 -50.740056)
						(mid 332.557763 -50.664229)
						(end 332.481936 -50.617628)
					)
					(arc
						(start 332.481936 -50.512472)
						(mid 332.629848 -50.592223)
						(end 332.709774 -50.740056)
					)
				)
			)
		)
		(zone
			(layer "F.Cu")
			(hatch none 0.5)
			(connect_pads
				(clearance 0)
			)
			(min_thickness 0.25)
			(keepout
				(tracks not_allowed)
				(vias allowed)
				(pads allowed)
				(copperpour not_allowed)
				(footprints allowed)
			)
			(placement
				(enabled no)
				(sheetname "")
			)
			(fill
				(thermal_gap 0.5)
				(thermal_bridge_width 0.5)
				(island_removal_mode 0)
			)
			(polygon
				(pts
					(arc
						(start 332.604364 -49.800256)
						(mid 332.557763 -49.724429)
						(end 332.481936 -49.677828)
					)
					(arc
						(start 332.481936 -49.572672)
						(mid 332.629848 -49.652423)
						(end 332.709774 -49.800256)
					)
				)
			)
		)
		(zone
			(layer "F.Cu")
			(hatch none 0.5)
			(connect_pads
				(clearance 0)
			)
			(min_thickness 0.25)
			(keepout
				(tracks not_allowed)
				(vias allowed)
				(pads allowed)
				(copperpour not_allowed)
				(footprints allowed)
			)
			(placement
				(enabled no)
				(sheetname "")
			)
			(fill
				(thermal_gap 0.5)
				(thermal_bridge_width 0.5)
				(island_removal_mode 0)
			)
			(polygon
				(pts
					(arc
						(start 332.604364 -48.860456)
						(mid 332.557763 -48.784629)
						(end 332.481936 -48.738028)
					)
					(arc
						(start 332.481936 -48.632872)
						(mid 332.629848 -48.712623)
						(end 332.709774 -48.860456)
					)
				)
			)
		)
		(zone
			(layer "F.Cu")
			(hatch none 0.5)
			(connect_pads
				(clearance 0)
			)
			(min_thickness 0.25)
			(keepout
				(tracks not_allowed)
				(vias allowed)
				(pads allowed)
				(copperpour not_allowed)
				(footprints allowed)
			)
			(placement
				(enabled no)
				(sheetname "")
			)
			(fill
				(thermal_gap 0.5)
				(thermal_bridge_width 0.5)
				(island_removal_mode 0)
			)
			(polygon
				(pts
					(arc
						(start 332.604364 -47.920656)
						(mid 332.557763 -47.844829)
						(end 332.481936 -47.798228)
					)
					(arc
						(start 332.481936 -47.693072)
						(mid 332.629848 -47.772823)
						(end 332.709774 -47.920656)
					)
				)
			)
		)
		(zone
			(layer "F.Cu")
			(hatch none 0.5)
			(connect_pads
				(clearance 0)
			)
			(min_thickness 0.25)
			(keepout
				(tracks not_allowed)
				(vias allowed)
				(pads allowed)
				(copperpour not_allowed)
				(footprints allowed)
			)
			(placement
				(enabled no)
				(sheetname "")
			)
			(fill
				(thermal_gap 0.5)
				(thermal_bridge_width 0.5)
				(island_removal_mode 0)
			)
			(polygon
				(pts
					(arc
						(start 332.604364 -46.980856)
						(mid 332.557763 -46.905029)
						(end 332.481936 -46.858428)
					)
					(arc
						(start 332.481936 -46.753272)
						(mid 332.629848 -46.833023)
						(end 332.709774 -46.980856)
					)
				)
			)
		)
		(zone
			(layer "F.Cu")
			(hatch none 0.5)
			(connect_pads
				(clearance 0)
			)
			(min_thickness 0.25)
			(keepout
				(tracks not_allowed)
				(vias allowed)
				(pads allowed)
				(copperpour not_allowed)
				(footprints allowed)
			)
			(placement
				(enabled no)
				(sheetname "")
			)
			(fill
				(thermal_gap 0.5)
				(thermal_bridge_width 0.5)
				(island_removal_mode 0)
			)
			(polygon
				(pts
					(arc
						(start 332.604364 -46.041056)
						(mid 332.557763 -45.965229)
						(end 332.481936 -45.918628)
					)
					(arc
						(start 332.481936 -45.813472)
						(mid 332.629848 -45.893223)
						(end 332.709774 -46.041056)
					)
				)
			)
		)
		(zone
			(layer "F.Cu")
			(hatch none 0.5)
			(connect_pads
				(clearance 0)
			)
			(min_thickness 0.25)
			(keepout
				(tracks not_allowed)
				(vias allowed)
				(pads allowed)
				(copperpour not_allowed)
				(footprints allowed)
			)
			(placement
				(enabled no)
				(sheetname "")
			)
			(fill
				(thermal_gap 0.5)
				(thermal_bridge_width 0.5)
				(island_removal_mode 0)
			)
			(polygon
				(pts
					(arc
						(start 332.604364 -45.101256)
						(mid 332.557763 -45.025429)
						(end 332.481936 -44.978828)
					)
					(arc
						(start 332.481936 -44.873672)
						(mid 332.629848 -44.953423)
						(end 332.709774 -45.101256)
					)
				)
			)
		)
		(zone
			(layer "F.Cu")
			(hatch none 0.5)
			(connect_pads
				(clearance 0)
			)
			(min_thickness 0.25)
			(keepout
				(tracks not_allowed)
				(vias allowed)
				(pads allowed)
				(copperpour not_allowed)
				(footprints allowed)
			)
			(placement
				(enabled no)
				(sheetname "")
			)
			(fill
				(thermal_gap 0.5)
				(thermal_bridge_width 0.5)
				(island_removal_mode 0)
			)
			(polygon
				(pts
					(arc
						(start 332.604364 -44.161456)
						(mid 332.557763 -44.085629)
						(end 332.481936 -44.039028)
					)
					(arc
						(start 332.481936 -43.933872)
						(mid 332.629848 -44.013623)
						(end 332.709774 -44.161456)
					)
				)
			)
		)
		(zone
			(layer "F.Cu")
			(hatch none 0.5)
			(connect_pads
				(clearance 0)
			)
			(min_thickness 0.25)
			(keepout
				(tracks not_allowed)
				(vias allowed)
				(pads allowed)
				(copperpour not_allowed)
				(footprints allowed)
			)
			(placement
				(enabled no)
				(sheetname "")
			)
			(fill
				(thermal_gap 0.5)
				(thermal_bridge_width 0.5)
				(island_removal_mode 0)
			)
			(polygon
				(pts
					(arc
						(start 332.604364 -43.221656)
						(mid 332.557763 -43.145829)
						(end 332.481936 -43.099228)
					)
					(arc
						(start 332.481936 -42.994072)
						(mid 332.629848 -43.073823)
						(end 332.709774 -43.221656)
					)
				)
			)
		)
		(zone
			(layer "F.Cu")
			(hatch none 0.5)
			(connect_pads
				(clearance 0)
			)
			(min_thickness 0.25)
			(keepout
				(tracks not_allowed)
				(vias allowed)
				(pads allowed)
				(copperpour not_allowed)
				(footprints allowed)
			)
			(placement
				(enabled no)
				(sheetname "")
			)
			(fill
				(thermal_gap 0.5)
				(thermal_bridge_width 0.5)
				(island_removal_mode 0)
			)
			(polygon
				(pts
					(arc
						(start 332.604364 -42.281856)
						(mid 332.557763 -42.206029)
						(end 332.481936 -42.159428)
					)
					(arc
						(start 332.481936 -42.054272)
						(mid 332.629848 -42.134023)
						(end 332.709774 -42.281856)
					)
				)
			)
		)
		(zone
			(layer "F.Cu")
			(hatch none 0.5)
			(connect_pads
				(clearance 0)
			)
			(min_thickness 0.25)
			(keepout
				(tracks not_allowed)
				(vias allowed)
				(pads allowed)
				(copperpour not_allowed)
				(footprints allowed)
			)
			(placement
				(enabled no)
				(sheetname "")
			)
			(fill
				(thermal_gap 0.5)
				(thermal_bridge_width 0.5)
				(island_removal_mode 0)
			)
			(polygon
				(pts
					(arc
						(start 332.604364 -41.342056)
						(mid 332.557763 -41.266229)
						(end 332.481936 -41.219628)
					)
					(arc
						(start 332.481936 -41.114472)
						(mid 332.629848 -41.194223)
						(end 332.709774 -41.342056)
					)
				)
			)
		)
		(zone
			(layer "F.Cu")
			(hatch none 0.5)
			(connect_pads
				(clearance 0)
			)
			(min_thickness 0.25)
			(keepout
				(tracks not_allowed)
				(vias allowed)
				(pads allowed)
				(copperpour not_allowed)
				(footprints allowed)
			)
			(placement
				(enabled no)
				(sheetname "")
			)
			(fill
				(thermal_gap 0.5)
				(thermal_bridge_width 0.5)
				(island_removal_mode 0)
			)
			(polygon
				(pts
					(arc
						(start 332.604364 -40.402256)
						(mid 332.557763 -40.326429)
						(end 332.481936 -40.279828)
					)
					(arc
						(start 332.481936 -40.174672)
						(mid 332.629848 -40.254423)
						(end 332.709774 -40.402256)
					)
				)
			)
		)
		(zone
			(layer "F.Cu")
			(hatch none 0.5)
			(connect_pads
				(clearance 0)
			)
			(min_thickness 0.25)
			(keepout
				(tracks not_allowed)
				(vias allowed)
				(pads allowed)
				(copperpour not_allowed)
				(footprints allowed)
			)
			(placement
				(enabled no)
				(sheetname "")
			)
			(fill
				(thermal_gap 0.5)
				(thermal_bridge_width 0.5)
				(island_removal_mode 0)
			)
			(polygon
				(pts
					(arc
						(start 333.054452 -56.968136)
						(mid 333.101053 -57.043963)
						(end 333.17688 -57.090564)
					)
					(arc
						(start 333.17688 -57.19572)
						(mid 333.028968 -57.115969)
						(end 332.949042 -56.968136)
					)
				)
			)
		)
		(zone
			(layer "F.Cu")
			(hatch none 0.5)
			(connect_pads
				(clearance 0)
			)
			(min_thickness 0.25)
			(keepout
				(tracks not_allowed)
				(vias allowed)
				(pads allowed)
				(copperpour not_allowed)
				(footprints allowed)
			)
			(placement
				(enabled no)
				(sheetname "")
			)
			(fill
				(thermal_gap 0.5)
				(thermal_bridge_width 0.5)
				(island_removal_mode 0)
			)
			(polygon
				(pts
					(arc
						(start 333.054452 -56.028336)
						(mid 333.101053 -56.104163)
						(end 333.17688 -56.150764)
					)
					(arc
						(start 333.17688 -56.25592)
						(mid 333.028968 -56.176169)
						(end 332.949042 -56.028336)
					)
				)
			)
		)
		(zone
			(layer "F.Cu")
			(hatch none 0.5)
			(connect_pads
				(clearance 0)
			)
			(min_thickness 0.25)
			(keepout
				(tracks not_allowed)
				(vias allowed)
				(pads allowed)
				(copperpour not_allowed)
				(footprints allowed)
			)
			(placement
				(enabled no)
				(sheetname "")
			)
			(fill
				(thermal_gap 0.5)
				(thermal_bridge_width 0.5)
				(island_removal_mode 0)
			)
			(polygon
				(pts
					(arc
						(start 333.054452 -55.088536)
						(mid 333.101053 -55.164363)
						(end 333.17688 -55.210964)
					)
					(arc
						(start 333.17688 -55.31612)
						(mid 333.028968 -55.236369)
						(end 332.949042 -55.088536)
					)
				)
			)
		)
		(zone
			(layer "F.Cu")
			(hatch none 0.5)
			(connect_pads
				(clearance 0)
			)
			(min_thickness 0.25)
			(keepout
				(tracks not_allowed)
				(vias allowed)
				(pads allowed)
				(copperpour not_allowed)
				(footprints allowed)
			)
			(placement
				(enabled no)
				(sheetname "")
			)
			(fill
				(thermal_gap 0.5)
				(thermal_bridge_width 0.5)
				(island_removal_mode 0)
			)
			(polygon
				(pts
					(arc
						(start 333.054452 -54.148736)
						(mid 333.101053 -54.224563)
						(end 333.17688 -54.271164)
					)
					(arc
						(start 333.17688 -54.37632)
						(mid 333.028968 -54.296569)
						(end 332.949042 -54.148736)
					)
				)
			)
		)
		(zone
			(layer "F.Cu")
			(hatch none 0.5)
			(connect_pads
				(clearance 0)
			)
			(min_thickness 0.25)
			(keepout
				(tracks not_allowed)
				(vias allowed)
				(pads allowed)
				(copperpour not_allowed)
				(footprints allowed)
			)
			(placement
				(enabled no)
				(sheetname "")
			)
			(fill
				(thermal_gap 0.5)
				(thermal_bridge_width 0.5)
				(island_removal_mode 0)
			)
			(polygon
				(pts
					(arc
						(start 333.054452 -53.208936)
						(mid 333.101053 -53.284763)
						(end 333.17688 -53.331364)
					)
					(arc
						(start 333.17688 -53.43652)
						(mid 333.028968 -53.356769)
						(end 332.949042 -53.208936)
					)
				)
			)
		)
		(zone
			(layer "F.Cu")
			(hatch none 0.5)
			(connect_pads
				(clearance 0)
			)
			(min_thickness 0.25)
			(keepout
				(tracks not_allowed)
				(vias allowed)
				(pads allowed)
				(copperpour not_allowed)
				(footprints allowed)
			)
			(placement
				(enabled no)
				(sheetname "")
			)
			(fill
				(thermal_gap 0.5)
				(thermal_bridge_width 0.5)
				(island_removal_mode 0)
			)
			(polygon
				(pts
					(arc
						(start 333.054452 -52.269136)
						(mid 333.101053 -52.344963)
						(end 333.17688 -52.391564)
					)
					(arc
						(start 333.17688 -52.49672)
						(mid 333.028968 -52.416969)
						(end 332.949042 -52.269136)
					)
				)
			)
		)
		(zone
			(layer "F.Cu")
			(hatch none 0.5)
			(connect_pads
				(clearance 0)
			)
			(min_thickness 0.25)
			(keepout
				(tracks not_allowed)
				(vias allowed)
				(pads allowed)
				(copperpour not_allowed)
				(footprints allowed)
			)
			(placement
				(enabled no)
				(sheetname "")
			)
			(fill
				(thermal_gap 0.5)
				(thermal_bridge_width 0.5)
				(island_removal_mode 0)
			)
			(polygon
				(pts
					(arc
						(start 333.054452 -51.329336)
						(mid 333.101053 -51.405163)
						(end 333.17688 -51.451764)
					)
					(arc
						(start 333.17688 -51.55692)
						(mid 333.028968 -51.477169)
						(end 332.949042 -51.329336)
					)
				)
			)
		)
		(zone
			(layer "F.Cu")
			(hatch none 0.5)
			(connect_pads
				(clearance 0)
			)
			(min_thickness 0.25)
			(keepout
				(tracks not_allowed)
				(vias allowed)
				(pads allowed)
				(copperpour not_allowed)
				(footprints allowed)
			)
			(placement
				(enabled no)
				(sheetname "")
			)
			(fill
				(thermal_gap 0.5)
				(thermal_bridge_width 0.5)
				(island_removal_mode 0)
			)
			(polygon
				(pts
					(arc
						(start 333.054452 -50.389536)
						(mid 333.101053 -50.465363)
						(end 333.17688 -50.511964)
					)
					(arc
						(start 333.17688 -50.61712)
						(mid 333.028968 -50.537369)
						(end 332.949042 -50.389536)
					)
				)
			)
		)
		(zone
			(layer "F.Cu")
			(hatch none 0.5)
			(connect_pads
				(clearance 0)
			)
			(min_thickness 0.25)
			(keepout
				(tracks not_allowed)
				(vias allowed)
				(pads allowed)
				(copperpour not_allowed)
				(footprints allowed)
			)
			(placement
				(enabled no)
				(sheetname "")
			)
			(fill
				(thermal_gap 0.5)
				(thermal_bridge_width 0.5)
				(island_removal_mode 0)
			)
			(polygon
				(pts
					(arc
						(start 333.054452 -49.449736)
						(mid 333.101053 -49.525563)
						(end 333.17688 -49.572164)
					)
					(arc
						(start 333.17688 -49.67732)
						(mid 333.028968 -49.597569)
						(end 332.949042 -49.449736)
					)
				)
			)
		)
		(zone
			(layer "F.Cu")
			(hatch none 0.5)
			(connect_pads
				(clearance 0)
			)
			(min_thickness 0.25)
			(keepout
				(tracks not_allowed)
				(vias allowed)
				(pads allowed)
				(copperpour not_allowed)
				(footprints allowed)
			)
			(placement
				(enabled no)
				(sheetname "")
			)
			(fill
				(thermal_gap 0.5)
				(thermal_bridge_width 0.5)
				(island_removal_mode 0)
			)
			(polygon
				(pts
					(arc
						(start 333.054452 -48.509936)
						(mid 333.101053 -48.585763)
						(end 333.17688 -48.632364)
					)
					(arc
						(start 333.17688 -48.73752)
						(mid 333.028968 -48.657769)
						(end 332.949042 -48.509936)
					)
				)
			)
		)
		(zone
			(layer "F.Cu")
			(hatch none 0.5)
			(connect_pads
				(clearance 0)
			)
			(min_thickness 0.25)
			(keepout
				(tracks not_allowed)
				(vias allowed)
				(pads allowed)
				(copperpour not_allowed)
				(footprints allowed)
			)
			(placement
				(enabled no)
				(sheetname "")
			)
			(fill
				(thermal_gap 0.5)
				(thermal_bridge_width 0.5)
				(island_removal_mode 0)
			)
			(polygon
				(pts
					(arc
						(start 333.054452 -47.570136)
						(mid 333.101053 -47.645963)
						(end 333.17688 -47.692564)
					)
					(arc
						(start 333.17688 -47.79772)
						(mid 333.028968 -47.717969)
						(end 332.949042 -47.570136)
					)
				)
			)
		)
		(zone
			(layer "F.Cu")
			(hatch none 0.5)
			(connect_pads
				(clearance 0)
			)
			(min_thickness 0.25)
			(keepout
				(tracks not_allowed)
				(vias allowed)
				(pads allowed)
				(copperpour not_allowed)
				(footprints allowed)
			)
			(placement
				(enabled no)
				(sheetname "")
			)
			(fill
				(thermal_gap 0.5)
				(thermal_bridge_width 0.5)
				(island_removal_mode 0)
			)
			(polygon
				(pts
					(arc
						(start 333.054452 -46.630336)
						(mid 333.101053 -46.706163)
						(end 333.17688 -46.752764)
					)
					(arc
						(start 333.17688 -46.85792)
						(mid 333.028968 -46.778169)
						(end 332.949042 -46.630336)
					)
				)
			)
		)
		(zone
			(layer "F.Cu")
			(hatch none 0.5)
			(connect_pads
				(clearance 0)
			)
			(min_thickness 0.25)
			(keepout
				(tracks not_allowed)
				(vias allowed)
				(pads allowed)
				(copperpour not_allowed)
				(footprints allowed)
			)
			(placement
				(enabled no)
				(sheetname "")
			)
			(fill
				(thermal_gap 0.5)
				(thermal_bridge_width 0.5)
				(island_removal_mode 0)
			)
			(polygon
				(pts
					(arc
						(start 333.054452 -45.690536)
						(mid 333.101053 -45.766363)
						(end 333.17688 -45.812964)
					)
					(arc
						(start 333.17688 -45.91812)
						(mid 333.028968 -45.838369)
						(end 332.949042 -45.690536)
					)
				)
			)
		)
		(zone
			(layer "F.Cu")
			(hatch none 0.5)
			(connect_pads
				(clearance 0)
			)
			(min_thickness 0.25)
			(keepout
				(tracks not_allowed)
				(vias allowed)
				(pads allowed)
				(copperpour not_allowed)
				(footprints allowed)
			)
			(placement
				(enabled no)
				(sheetname "")
			)
			(fill
				(thermal_gap 0.5)
				(thermal_bridge_width 0.5)
				(island_removal_mode 0)
			)
			(polygon
				(pts
					(arc
						(start 333.054452 -44.750736)
						(mid 333.101053 -44.826563)
						(end 333.17688 -44.873164)
					)
					(arc
						(start 333.17688 -44.97832)
						(mid 333.028968 -44.898569)
						(end 332.949042 -44.750736)
					)
				)
			)
		)
		(zone
			(layer "F.Cu")
			(hatch none 0.5)
			(connect_pads
				(clearance 0)
			)
			(min_thickness 0.25)
			(keepout
				(tracks not_allowed)
				(vias allowed)
				(pads allowed)
				(copperpour not_allowed)
				(footprints allowed)
			)
			(placement
				(enabled no)
				(sheetname "")
			)
			(fill
				(thermal_gap 0.5)
				(thermal_bridge_width 0.5)
				(island_removal_mode 0)
			)
			(polygon
				(pts
					(arc
						(start 333.054452 -43.810936)
						(mid 333.101053 -43.886763)
						(end 333.17688 -43.933364)
					)
					(arc
						(start 333.17688 -44.03852)
						(mid 333.028968 -43.958769)
						(end 332.949042 -43.810936)
					)
				)
			)
		)
		(zone
			(layer "F.Cu")
			(hatch none 0.5)
			(connect_pads
				(clearance 0)
			)
			(min_thickness 0.25)
			(keepout
				(tracks not_allowed)
				(vias allowed)
				(pads allowed)
				(copperpour not_allowed)
				(footprints allowed)
			)
			(placement
				(enabled no)
				(sheetname "")
			)
			(fill
				(thermal_gap 0.5)
				(thermal_bridge_width 0.5)
				(island_removal_mode 0)
			)
			(polygon
				(pts
					(arc
						(start 333.054452 -42.871136)
						(mid 333.101053 -42.946963)
						(end 333.17688 -42.993564)
					)
					(arc
						(start 333.17688 -43.09872)
						(mid 333.028968 -43.018969)
						(end 332.949042 -42.871136)
					)
				)
			)
		)
		(zone
			(layer "F.Cu")
			(hatch none 0.5)
			(connect_pads
				(clearance 0)
			)
			(min_thickness 0.25)
			(keepout
				(tracks not_allowed)
				(vias allowed)
				(pads allowed)
				(copperpour not_allowed)
				(footprints allowed)
			)
			(placement
				(enabled no)
				(sheetname "")
			)
			(fill
				(thermal_gap 0.5)
				(thermal_bridge_width 0.5)
				(island_removal_mode 0)
			)
			(polygon
				(pts
					(arc
						(start 333.054452 -41.931336)
						(mid 333.101053 -42.007163)
						(end 333.17688 -42.053764)
					)
					(arc
						(start 333.17688 -42.15892)
						(mid 333.028968 -42.079169)
						(end 332.949042 -41.931336)
					)
				)
			)
		)
		(zone
			(layer "F.Cu")
			(hatch none 0.5)
			(connect_pads
				(clearance 0)
			)
			(min_thickness 0.25)
			(keepout
				(tracks not_allowed)
				(vias allowed)
				(pads allowed)
				(copperpour not_allowed)
				(footprints allowed)
			)
			(placement
				(enabled no)
				(sheetname "")
			)
			(fill
				(thermal_gap 0.5)
				(thermal_bridge_width 0.5)
				(island_removal_mode 0)
			)
			(polygon
				(pts
					(arc
						(start 333.054452 -40.991536)
						(mid 333.101053 -41.067363)
						(end 333.17688 -41.113964)
					)
					(arc
						(start 333.17688 -41.21912)
						(mid 333.028968 -41.139369)
						(end 332.949042 -40.991536)
					)
				)
			)
		)
		(zone
			(layer "F.Cu")
			(hatch none 0.5)
			(connect_pads
				(clearance 0)
			)
			(min_thickness 0.25)
			(keepout
				(tracks not_allowed)
				(vias allowed)
				(pads allowed)
				(copperpour not_allowed)
				(footprints allowed)
			)
			(placement
				(enabled no)
				(sheetname "")
			)
			(fill
				(thermal_gap 0.5)
				(thermal_bridge_width 0.5)
				(island_removal_mode 0)
			)
			(polygon
				(pts
					(arc
						(start 333.054452 -40.051736)
						(mid 333.101053 -40.127563)
						(end 333.17688 -40.174164)
					)
					(arc
						(start 333.17688 -40.27932)
						(mid 333.028968 -40.199569)
						(end 332.949042 -40.051736)
					)
				)
			)
		)
		(zone
			(layer "F.Cu")
			(hatch none 0.5)
			(connect_pads
				(clearance 0)
			)
			(min_thickness 0.25)
			(keepout
				(tracks not_allowed)
				(vias allowed)
				(pads allowed)
				(copperpour not_allowed)
				(footprints allowed)
			)
			(placement
				(enabled no)
				(sheetname "")
			)
			(fill
				(thermal_gap 0.5)
				(thermal_bridge_width 0.5)
				(island_removal_mode 0)
			)
			(polygon
				(pts
					(arc
						(start 333.17688 -56.726328)
						(mid 333.101053 -56.772929)
						(end 333.054452 -56.848756)
					)
					(arc
						(start 332.949042 -56.848756)
						(mid 333.028932 -56.700886)
						(end 333.17688 -56.621172)
					)
				)
			)
		)
		(zone
			(layer "F.Cu")
			(hatch none 0.5)
			(connect_pads
				(clearance 0)
			)
			(min_thickness 0.25)
			(keepout
				(tracks not_allowed)
				(vias allowed)
				(pads allowed)
				(copperpour not_allowed)
				(footprints allowed)
			)
			(placement
				(enabled no)
				(sheetname "")
			)
			(fill
				(thermal_gap 0.5)
				(thermal_bridge_width 0.5)
				(island_removal_mode 0)
			)
			(polygon
				(pts
					(arc
						(start 333.17688 -55.786528)
						(mid 333.101053 -55.833129)
						(end 333.054452 -55.908956)
					)
					(arc
						(start 332.949042 -55.908956)
						(mid 333.028932 -55.761086)
						(end 333.17688 -55.681372)
					)
				)
			)
		)
		(zone
			(layer "F.Cu")
			(hatch none 0.5)
			(connect_pads
				(clearance 0)
			)
			(min_thickness 0.25)
			(keepout
				(tracks not_allowed)
				(vias allowed)
				(pads allowed)
				(copperpour not_allowed)
				(footprints allowed)
			)
			(placement
				(enabled no)
				(sheetname "")
			)
			(fill
				(thermal_gap 0.5)
				(thermal_bridge_width 0.5)
				(island_removal_mode 0)
			)
			(polygon
				(pts
					(arc
						(start 333.17688 -54.846728)
						(mid 333.101053 -54.893329)
						(end 333.054452 -54.969156)
					)
					(arc
						(start 332.949042 -54.969156)
						(mid 333.028932 -54.821286)
						(end 333.17688 -54.741572)
					)
				)
			)
		)
		(zone
			(layer "F.Cu")
			(hatch none 0.5)
			(connect_pads
				(clearance 0)
			)
			(min_thickness 0.25)
			(keepout
				(tracks not_allowed)
				(vias allowed)
				(pads allowed)
				(copperpour not_allowed)
				(footprints allowed)
			)
			(placement
				(enabled no)
				(sheetname "")
			)
			(fill
				(thermal_gap 0.5)
				(thermal_bridge_width 0.5)
				(island_removal_mode 0)
			)
			(polygon
				(pts
					(arc
						(start 333.17688 -53.906928)
						(mid 333.101053 -53.953529)
						(end 333.054452 -54.029356)
					)
					(arc
						(start 332.949042 -54.029356)
						(mid 333.028932 -53.881486)
						(end 333.17688 -53.801772)
					)
				)
			)
		)
		(zone
			(layer "F.Cu")
			(hatch none 0.5)
			(connect_pads
				(clearance 0)
			)
			(min_thickness 0.25)
			(keepout
				(tracks not_allowed)
				(vias allowed)
				(pads allowed)
				(copperpour not_allowed)
				(footprints allowed)
			)
			(placement
				(enabled no)
				(sheetname "")
			)
			(fill
				(thermal_gap 0.5)
				(thermal_bridge_width 0.5)
				(island_removal_mode 0)
			)
			(polygon
				(pts
					(arc
						(start 333.17688 -52.967128)
						(mid 333.101053 -53.013729)
						(end 333.054452 -53.089556)
					)
					(arc
						(start 332.949042 -53.089556)
						(mid 333.028932 -52.941686)
						(end 333.17688 -52.861972)
					)
				)
			)
		)
		(zone
			(layer "F.Cu")
			(hatch none 0.5)
			(connect_pads
				(clearance 0)
			)
			(min_thickness 0.25)
			(keepout
				(tracks not_allowed)
				(vias allowed)
				(pads allowed)
				(copperpour not_allowed)
				(footprints allowed)
			)
			(placement
				(enabled no)
				(sheetname "")
			)
			(fill
				(thermal_gap 0.5)
				(thermal_bridge_width 0.5)
				(island_removal_mode 0)
			)
			(polygon
				(pts
					(arc
						(start 333.17688 -52.027328)
						(mid 333.101053 -52.073929)
						(end 333.054452 -52.149756)
					)
					(arc
						(start 332.949042 -52.149756)
						(mid 333.028932 -52.001886)
						(end 333.17688 -51.922172)
					)
				)
			)
		)
		(zone
			(layer "F.Cu")
			(hatch none 0.5)
			(connect_pads
				(clearance 0)
			)
			(min_thickness 0.25)
			(keepout
				(tracks not_allowed)
				(vias allowed)
				(pads allowed)
				(copperpour not_allowed)
				(footprints allowed)
			)
			(placement
				(enabled no)
				(sheetname "")
			)
			(fill
				(thermal_gap 0.5)
				(thermal_bridge_width 0.5)
				(island_removal_mode 0)
			)
			(polygon
				(pts
					(arc
						(start 333.17688 -51.087528)
						(mid 333.101053 -51.134129)
						(end 333.054452 -51.209956)
					)
					(arc
						(start 332.949042 -51.209956)
						(mid 333.028932 -51.062086)
						(end 333.17688 -50.982372)
					)
				)
			)
		)
		(zone
			(layer "F.Cu")
			(hatch none 0.5)
			(connect_pads
				(clearance 0)
			)
			(min_thickness 0.25)
			(keepout
				(tracks not_allowed)
				(vias allowed)
				(pads allowed)
				(copperpour not_allowed)
				(footprints allowed)
			)
			(placement
				(enabled no)
				(sheetname "")
			)
			(fill
				(thermal_gap 0.5)
				(thermal_bridge_width 0.5)
				(island_removal_mode 0)
			)
			(polygon
				(pts
					(arc
						(start 333.17688 -50.147728)
						(mid 333.101053 -50.194329)
						(end 333.054452 -50.270156)
					)
					(arc
						(start 332.949042 -50.270156)
						(mid 333.028932 -50.122286)
						(end 333.17688 -50.042572)
					)
				)
			)
		)
		(zone
			(layer "F.Cu")
			(hatch none 0.5)
			(connect_pads
				(clearance 0)
			)
			(min_thickness 0.25)
			(keepout
				(tracks not_allowed)
				(vias allowed)
				(pads allowed)
				(copperpour not_allowed)
				(footprints allowed)
			)
			(placement
				(enabled no)
				(sheetname "")
			)
			(fill
				(thermal_gap 0.5)
				(thermal_bridge_width 0.5)
				(island_removal_mode 0)
			)
			(polygon
				(pts
					(arc
						(start 333.17688 -49.207928)
						(mid 333.101053 -49.254529)
						(end 333.054452 -49.330356)
					)
					(arc
						(start 332.949042 -49.330356)
						(mid 333.028932 -49.182486)
						(end 333.17688 -49.102772)
					)
				)
			)
		)
		(zone
			(layer "F.Cu")
			(hatch none 0.5)
			(connect_pads
				(clearance 0)
			)
			(min_thickness 0.25)
			(keepout
				(tracks not_allowed)
				(vias allowed)
				(pads allowed)
				(copperpour not_allowed)
				(footprints allowed)
			)
			(placement
				(enabled no)
				(sheetname "")
			)
			(fill
				(thermal_gap 0.5)
				(thermal_bridge_width 0.5)
				(island_removal_mode 0)
			)
			(polygon
				(pts
					(arc
						(start 333.17688 -48.268128)
						(mid 333.101053 -48.314729)
						(end 333.054452 -48.390556)
					)
					(arc
						(start 332.949042 -48.390556)
						(mid 333.028932 -48.242686)
						(end 333.17688 -48.162972)
					)
				)
			)
		)
		(zone
			(layer "F.Cu")
			(hatch none 0.5)
			(connect_pads
				(clearance 0)
			)
			(min_thickness 0.25)
			(keepout
				(tracks not_allowed)
				(vias allowed)
				(pads allowed)
				(copperpour not_allowed)
				(footprints allowed)
			)
			(placement
				(enabled no)
				(sheetname "")
			)
			(fill
				(thermal_gap 0.5)
				(thermal_bridge_width 0.5)
				(island_removal_mode 0)
			)
			(polygon
				(pts
					(arc
						(start 333.17688 -47.328328)
						(mid 333.101053 -47.374929)
						(end 333.054452 -47.450756)
					)
					(arc
						(start 332.949042 -47.450756)
						(mid 333.028932 -47.302886)
						(end 333.17688 -47.223172)
					)
				)
			)
		)
		(zone
			(layer "F.Cu")
			(hatch none 0.5)
			(connect_pads
				(clearance 0)
			)
			(min_thickness 0.25)
			(keepout
				(tracks not_allowed)
				(vias allowed)
				(pads allowed)
				(copperpour not_allowed)
				(footprints allowed)
			)
			(placement
				(enabled no)
				(sheetname "")
			)
			(fill
				(thermal_gap 0.5)
				(thermal_bridge_width 0.5)
				(island_removal_mode 0)
			)
			(polygon
				(pts
					(arc
						(start 333.17688 -46.388528)
						(mid 333.101053 -46.435129)
						(end 333.054452 -46.510956)
					)
					(arc
						(start 332.949042 -46.510956)
						(mid 333.028932 -46.363086)
						(end 333.17688 -46.283372)
					)
				)
			)
		)
		(zone
			(layer "F.Cu")
			(hatch none 0.5)
			(connect_pads
				(clearance 0)
			)
			(min_thickness 0.25)
			(keepout
				(tracks not_allowed)
				(vias allowed)
				(pads allowed)
				(copperpour not_allowed)
				(footprints allowed)
			)
			(placement
				(enabled no)
				(sheetname "")
			)
			(fill
				(thermal_gap 0.5)
				(thermal_bridge_width 0.5)
				(island_removal_mode 0)
			)
			(polygon
				(pts
					(arc
						(start 333.17688 -45.448728)
						(mid 333.101053 -45.495329)
						(end 333.054452 -45.571156)
					)
					(arc
						(start 332.949042 -45.571156)
						(mid 333.028932 -45.423286)
						(end 333.17688 -45.343572)
					)
				)
			)
		)
		(zone
			(layer "F.Cu")
			(hatch none 0.5)
			(connect_pads
				(clearance 0)
			)
			(min_thickness 0.25)
			(keepout
				(tracks not_allowed)
				(vias allowed)
				(pads allowed)
				(copperpour not_allowed)
				(footprints allowed)
			)
			(placement
				(enabled no)
				(sheetname "")
			)
			(fill
				(thermal_gap 0.5)
				(thermal_bridge_width 0.5)
				(island_removal_mode 0)
			)
			(polygon
				(pts
					(arc
						(start 333.17688 -44.508928)
						(mid 333.101053 -44.555529)
						(end 333.054452 -44.631356)
					)
					(arc
						(start 332.949042 -44.631356)
						(mid 333.028932 -44.483486)
						(end 333.17688 -44.403772)
					)
				)
			)
		)
		(zone
			(layer "F.Cu")
			(hatch none 0.5)
			(connect_pads
				(clearance 0)
			)
			(min_thickness 0.25)
			(keepout
				(tracks not_allowed)
				(vias allowed)
				(pads allowed)
				(copperpour not_allowed)
				(footprints allowed)
			)
			(placement
				(enabled no)
				(sheetname "")
			)
			(fill
				(thermal_gap 0.5)
				(thermal_bridge_width 0.5)
				(island_removal_mode 0)
			)
			(polygon
				(pts
					(arc
						(start 333.17688 -43.569128)
						(mid 333.101053 -43.615729)
						(end 333.054452 -43.691556)
					)
					(arc
						(start 332.949042 -43.691556)
						(mid 333.028932 -43.543686)
						(end 333.17688 -43.463972)
					)
				)
			)
		)
		(zone
			(layer "F.Cu")
			(hatch none 0.5)
			(connect_pads
				(clearance 0)
			)
			(min_thickness 0.25)
			(keepout
				(tracks not_allowed)
				(vias allowed)
				(pads allowed)
				(copperpour not_allowed)
				(footprints allowed)
			)
			(placement
				(enabled no)
				(sheetname "")
			)
			(fill
				(thermal_gap 0.5)
				(thermal_bridge_width 0.5)
				(island_removal_mode 0)
			)
			(polygon
				(pts
					(arc
						(start 333.17688 -42.629328)
						(mid 333.101053 -42.675929)
						(end 333.054452 -42.751756)
					)
					(arc
						(start 332.949042 -42.751756)
						(mid 333.028932 -42.603886)
						(end 333.17688 -42.524172)
					)
				)
			)
		)
		(zone
			(layer "F.Cu")
			(hatch none 0.5)
			(connect_pads
				(clearance 0)
			)
			(min_thickness 0.25)
			(keepout
				(tracks not_allowed)
				(vias allowed)
				(pads allowed)
				(copperpour not_allowed)
				(footprints allowed)
			)
			(placement
				(enabled no)
				(sheetname "")
			)
			(fill
				(thermal_gap 0.5)
				(thermal_bridge_width 0.5)
				(island_removal_mode 0)
			)
			(polygon
				(pts
					(arc
						(start 333.17688 -41.689528)
						(mid 333.101053 -41.736129)
						(end 333.054452 -41.811956)
					)
					(arc
						(start 332.949042 -41.811956)
						(mid 333.028932 -41.664086)
						(end 333.17688 -41.584372)
					)
				)
			)
		)
		(zone
			(layer "F.Cu")
			(hatch none 0.5)
			(connect_pads
				(clearance 0)
			)
			(min_thickness 0.25)
			(keepout
				(tracks not_allowed)
				(vias allowed)
				(pads allowed)
				(copperpour not_allowed)
				(footprints allowed)
			)
			(placement
				(enabled no)
				(sheetname "")
			)
			(fill
				(thermal_gap 0.5)
				(thermal_bridge_width 0.5)
				(island_removal_mode 0)
			)
			(polygon
				(pts
					(arc
						(start 333.17688 -40.749728)
						(mid 333.101053 -40.796329)
						(end 333.054452 -40.872156)
					)
					(arc
						(start 332.949042 -40.872156)
						(mid 333.028932 -40.724286)
						(end 333.17688 -40.644572)
					)
				)
			)
		)
		(zone
			(layer "F.Cu")
			(hatch none 0.5)
			(connect_pads
				(clearance 0)
			)
			(min_thickness 0.25)
			(keepout
				(tracks not_allowed)
				(vias allowed)
				(pads allowed)
				(copperpour not_allowed)
				(footprints allowed)
			)
			(placement
				(enabled no)
				(sheetname "")
			)
			(fill
				(thermal_gap 0.5)
				(thermal_bridge_width 0.5)
				(island_removal_mode 0)
			)
			(polygon
				(pts
					(arc
						(start 333.17688 -39.809928)
						(mid 333.101053 -39.856529)
						(end 333.054452 -39.932356)
					)
					(arc
						(start 332.949042 -39.932356)
						(mid 333.028932 -39.784486)
						(end 333.17688 -39.704772)
					)
				)
			)
		)
		(zone
			(layer "F.Cu")
			(hatch none 0.5)
			(connect_pads
				(clearance 0)
			)
			(min_thickness 0.25)
			(keepout
				(tracks not_allowed)
				(vias allowed)
				(pads allowed)
				(copperpour not_allowed)
				(footprints allowed)
			)
			(placement
				(enabled no)
				(sheetname "")
			)
			(fill
				(thermal_gap 0.5)
				(thermal_bridge_width 0.5)
				(island_removal_mode 0)
			)
			(polygon
				(pts
					(arc
						(start 333.29626 -57.090564)
						(mid 333.371975 -57.043934)
						(end 333.418434 -56.968136)
					)
					(arc
						(start 333.523844 -56.968136)
						(mid 333.444042 -57.115918)
						(end 333.29626 -57.19572)
					)
				)
			)
		)
		(zone
			(layer "F.Cu")
			(hatch none 0.5)
			(connect_pads
				(clearance 0)
			)
			(min_thickness 0.25)
			(keepout
				(tracks not_allowed)
				(vias allowed)
				(pads allowed)
				(copperpour not_allowed)
				(footprints allowed)
			)
			(placement
				(enabled no)
				(sheetname "")
			)
			(fill
				(thermal_gap 0.5)
				(thermal_bridge_width 0.5)
				(island_removal_mode 0)
			)
			(polygon
				(pts
					(arc
						(start 333.29626 -56.150764)
						(mid 333.371975 -56.104134)
						(end 333.418434 -56.028336)
					)
					(arc
						(start 333.523844 -56.028336)
						(mid 333.444042 -56.176118)
						(end 333.29626 -56.25592)
					)
				)
			)
		)
		(zone
			(layer "F.Cu")
			(hatch none 0.5)
			(connect_pads
				(clearance 0)
			)
			(min_thickness 0.25)
			(keepout
				(tracks not_allowed)
				(vias allowed)
				(pads allowed)
				(copperpour not_allowed)
				(footprints allowed)
			)
			(placement
				(enabled no)
				(sheetname "")
			)
			(fill
				(thermal_gap 0.5)
				(thermal_bridge_width 0.5)
				(island_removal_mode 0)
			)
			(polygon
				(pts
					(arc
						(start 333.29626 -55.210964)
						(mid 333.371975 -55.164334)
						(end 333.418434 -55.088536)
					)
					(arc
						(start 333.523844 -55.088536)
						(mid 333.444042 -55.236318)
						(end 333.29626 -55.31612)
					)
				)
			)
		)
		(zone
			(layer "F.Cu")
			(hatch none 0.5)
			(connect_pads
				(clearance 0)
			)
			(min_thickness 0.25)
			(keepout
				(tracks not_allowed)
				(vias allowed)
				(pads allowed)
				(copperpour not_allowed)
				(footprints allowed)
			)
			(placement
				(enabled no)
				(sheetname "")
			)
			(fill
				(thermal_gap 0.5)
				(thermal_bridge_width 0.5)
				(island_removal_mode 0)
			)
			(polygon
				(pts
					(arc
						(start 333.29626 -54.271164)
						(mid 333.371975 -54.224534)
						(end 333.418434 -54.148736)
					)
					(arc
						(start 333.523844 -54.148736)
						(mid 333.444042 -54.296518)
						(end 333.29626 -54.37632)
					)
				)
			)
		)
		(zone
			(layer "F.Cu")
			(hatch none 0.5)
			(connect_pads
				(clearance 0)
			)
			(min_thickness 0.25)
			(keepout
				(tracks not_allowed)
				(vias allowed)
				(pads allowed)
				(copperpour not_allowed)
				(footprints allowed)
			)
			(placement
				(enabled no)
				(sheetname "")
			)
			(fill
				(thermal_gap 0.5)
				(thermal_bridge_width 0.5)
				(island_removal_mode 0)
			)
			(polygon
				(pts
					(arc
						(start 333.29626 -53.331364)
						(mid 333.371975 -53.284734)
						(end 333.418434 -53.208936)
					)
					(arc
						(start 333.523844 -53.208936)
						(mid 333.444042 -53.356718)
						(end 333.29626 -53.43652)
					)
				)
			)
		)
		(zone
			(layer "F.Cu")
			(hatch none 0.5)
			(connect_pads
				(clearance 0)
			)
			(min_thickness 0.25)
			(keepout
				(tracks not_allowed)
				(vias allowed)
				(pads allowed)
				(copperpour not_allowed)
				(footprints allowed)
			)
			(placement
				(enabled no)
				(sheetname "")
			)
			(fill
				(thermal_gap 0.5)
				(thermal_bridge_width 0.5)
				(island_removal_mode 0)
			)
			(polygon
				(pts
					(arc
						(start 333.29626 -52.391564)
						(mid 333.371975 -52.344934)
						(end 333.418434 -52.269136)
					)
					(arc
						(start 333.523844 -52.269136)
						(mid 333.444042 -52.416918)
						(end 333.29626 -52.49672)
					)
				)
			)
		)
		(zone
			(layer "F.Cu")
			(hatch none 0.5)
			(connect_pads
				(clearance 0)
			)
			(min_thickness 0.25)
			(keepout
				(tracks not_allowed)
				(vias allowed)
				(pads allowed)
				(copperpour not_allowed)
				(footprints allowed)
			)
			(placement
				(enabled no)
				(sheetname "")
			)
			(fill
				(thermal_gap 0.5)
				(thermal_bridge_width 0.5)
				(island_removal_mode 0)
			)
			(polygon
				(pts
					(arc
						(start 333.29626 -51.451764)
						(mid 333.371975 -51.405134)
						(end 333.418434 -51.329336)
					)
					(arc
						(start 333.523844 -51.329336)
						(mid 333.444042 -51.477118)
						(end 333.29626 -51.55692)
					)
				)
			)
		)
		(zone
			(layer "F.Cu")
			(hatch none 0.5)
			(connect_pads
				(clearance 0)
			)
			(min_thickness 0.25)
			(keepout
				(tracks not_allowed)
				(vias allowed)
				(pads allowed)
				(copperpour not_allowed)
				(footprints allowed)
			)
			(placement
				(enabled no)
				(sheetname "")
			)
			(fill
				(thermal_gap 0.5)
				(thermal_bridge_width 0.5)
				(island_removal_mode 0)
			)
			(polygon
				(pts
					(arc
						(start 333.29626 -50.511964)
						(mid 333.371975 -50.465334)
						(end 333.418434 -50.389536)
					)
					(arc
						(start 333.523844 -50.389536)
						(mid 333.444042 -50.537318)
						(end 333.29626 -50.61712)
					)
				)
			)
		)
		(zone
			(layer "F.Cu")
			(hatch none 0.5)
			(connect_pads
				(clearance 0)
			)
			(min_thickness 0.25)
			(keepout
				(tracks not_allowed)
				(vias allowed)
				(pads allowed)
				(copperpour not_allowed)
				(footprints allowed)
			)
			(placement
				(enabled no)
				(sheetname "")
			)
			(fill
				(thermal_gap 0.5)
				(thermal_bridge_width 0.5)
				(island_removal_mode 0)
			)
			(polygon
				(pts
					(arc
						(start 333.29626 -49.572164)
						(mid 333.371975 -49.525534)
						(end 333.418434 -49.449736)
					)
					(arc
						(start 333.523844 -49.449736)
						(mid 333.444042 -49.597518)
						(end 333.29626 -49.67732)
					)
				)
			)
		)
		(zone
			(layer "F.Cu")
			(hatch none 0.5)
			(connect_pads
				(clearance 0)
			)
			(min_thickness 0.25)
			(keepout
				(tracks not_allowed)
				(vias allowed)
				(pads allowed)
				(copperpour not_allowed)
				(footprints allowed)
			)
			(placement
				(enabled no)
				(sheetname "")
			)
			(fill
				(thermal_gap 0.5)
				(thermal_bridge_width 0.5)
				(island_removal_mode 0)
			)
			(polygon
				(pts
					(arc
						(start 333.29626 -48.632364)
						(mid 333.371975 -48.585734)
						(end 333.418434 -48.509936)
					)
					(arc
						(start 333.523844 -48.509936)
						(mid 333.444042 -48.657718)
						(end 333.29626 -48.73752)
					)
				)
			)
		)
		(zone
			(layer "F.Cu")
			(hatch none 0.5)
			(connect_pads
				(clearance 0)
			)
			(min_thickness 0.25)
			(keepout
				(tracks not_allowed)
				(vias allowed)
				(pads allowed)
				(copperpour not_allowed)
				(footprints allowed)
			)
			(placement
				(enabled no)
				(sheetname "")
			)
			(fill
				(thermal_gap 0.5)
				(thermal_bridge_width 0.5)
				(island_removal_mode 0)
			)
			(polygon
				(pts
					(arc
						(start 333.29626 -47.692564)
						(mid 333.371975 -47.645934)
						(end 333.418434 -47.570136)
					)
					(arc
						(start 333.523844 -47.570136)
						(mid 333.444042 -47.717918)
						(end 333.29626 -47.79772)
					)
				)
			)
		)
		(zone
			(layer "F.Cu")
			(hatch none 0.5)
			(connect_pads
				(clearance 0)
			)
			(min_thickness 0.25)
			(keepout
				(tracks not_allowed)
				(vias allowed)
				(pads allowed)
				(copperpour not_allowed)
				(footprints allowed)
			)
			(placement
				(enabled no)
				(sheetname "")
			)
			(fill
				(thermal_gap 0.5)
				(thermal_bridge_width 0.5)
				(island_removal_mode 0)
			)
			(polygon
				(pts
					(arc
						(start 333.29626 -46.752764)
						(mid 333.371975 -46.706134)
						(end 333.418434 -46.630336)
					)
					(arc
						(start 333.523844 -46.630336)
						(mid 333.444042 -46.778118)
						(end 333.29626 -46.85792)
					)
				)
			)
		)
		(zone
			(layer "F.Cu")
			(hatch none 0.5)
			(connect_pads
				(clearance 0)
			)
			(min_thickness 0.25)
			(keepout
				(tracks not_allowed)
				(vias allowed)
				(pads allowed)
				(copperpour not_allowed)
				(footprints allowed)
			)
			(placement
				(enabled no)
				(sheetname "")
			)
			(fill
				(thermal_gap 0.5)
				(thermal_bridge_width 0.5)
				(island_removal_mode 0)
			)
			(polygon
				(pts
					(arc
						(start 333.29626 -45.812964)
						(mid 333.371975 -45.766334)
						(end 333.418434 -45.690536)
					)
					(arc
						(start 333.523844 -45.690536)
						(mid 333.444042 -45.838318)
						(end 333.29626 -45.91812)
					)
				)
			)
		)
		(zone
			(layer "F.Cu")
			(hatch none 0.5)
			(connect_pads
				(clearance 0)
			)
			(min_thickness 0.25)
			(keepout
				(tracks not_allowed)
				(vias allowed)
				(pads allowed)
				(copperpour not_allowed)
				(footprints allowed)
			)
			(placement
				(enabled no)
				(sheetname "")
			)
			(fill
				(thermal_gap 0.5)
				(thermal_bridge_width 0.5)
				(island_removal_mode 0)
			)
			(polygon
				(pts
					(arc
						(start 333.29626 -44.873164)
						(mid 333.371975 -44.826534)
						(end 333.418434 -44.750736)
					)
					(arc
						(start 333.523844 -44.750736)
						(mid 333.444042 -44.898518)
						(end 333.29626 -44.97832)
					)
				)
			)
		)
		(zone
			(layer "F.Cu")
			(hatch none 0.5)
			(connect_pads
				(clearance 0)
			)
			(min_thickness 0.25)
			(keepout
				(tracks not_allowed)
				(vias allowed)
				(pads allowed)
				(copperpour not_allowed)
				(footprints allowed)
			)
			(placement
				(enabled no)
				(sheetname "")
			)
			(fill
				(thermal_gap 0.5)
				(thermal_bridge_width 0.5)
				(island_removal_mode 0)
			)
			(polygon
				(pts
					(arc
						(start 333.29626 -43.933364)
						(mid 333.371975 -43.886734)
						(end 333.418434 -43.810936)
					)
					(arc
						(start 333.523844 -43.810936)
						(mid 333.444042 -43.958718)
						(end 333.29626 -44.03852)
					)
				)
			)
		)
		(zone
			(layer "F.Cu")
			(hatch none 0.5)
			(connect_pads
				(clearance 0)
			)
			(min_thickness 0.25)
			(keepout
				(tracks not_allowed)
				(vias allowed)
				(pads allowed)
				(copperpour not_allowed)
				(footprints allowed)
			)
			(placement
				(enabled no)
				(sheetname "")
			)
			(fill
				(thermal_gap 0.5)
				(thermal_bridge_width 0.5)
				(island_removal_mode 0)
			)
			(polygon
				(pts
					(arc
						(start 333.29626 -42.993564)
						(mid 333.371975 -42.946934)
						(end 333.418434 -42.871136)
					)
					(arc
						(start 333.523844 -42.871136)
						(mid 333.444042 -43.018918)
						(end 333.29626 -43.09872)
					)
				)
			)
		)
		(zone
			(layer "F.Cu")
			(hatch none 0.5)
			(connect_pads
				(clearance 0)
			)
			(min_thickness 0.25)
			(keepout
				(tracks not_allowed)
				(vias allowed)
				(pads allowed)
				(copperpour not_allowed)
				(footprints allowed)
			)
			(placement
				(enabled no)
				(sheetname "")
			)
			(fill
				(thermal_gap 0.5)
				(thermal_bridge_width 0.5)
				(island_removal_mode 0)
			)
			(polygon
				(pts
					(arc
						(start 333.29626 -42.053764)
						(mid 333.371975 -42.007134)
						(end 333.418434 -41.931336)
					)
					(arc
						(start 333.523844 -41.931336)
						(mid 333.444042 -42.079118)
						(end 333.29626 -42.15892)
					)
				)
			)
		)
		(zone
			(layer "F.Cu")
			(hatch none 0.5)
			(connect_pads
				(clearance 0)
			)
			(min_thickness 0.25)
			(keepout
				(tracks not_allowed)
				(vias allowed)
				(pads allowed)
				(copperpour not_allowed)
				(footprints allowed)
			)
			(placement
				(enabled no)
				(sheetname "")
			)
			(fill
				(thermal_gap 0.5)
				(thermal_bridge_width 0.5)
				(island_removal_mode 0)
			)
			(polygon
				(pts
					(arc
						(start 333.29626 -41.113964)
						(mid 333.371975 -41.067334)
						(end 333.418434 -40.991536)
					)
					(arc
						(start 333.523844 -40.991536)
						(mid 333.444042 -41.139318)
						(end 333.29626 -41.21912)
					)
				)
			)
		)
		(zone
			(layer "F.Cu")
			(hatch none 0.5)
			(connect_pads
				(clearance 0)
			)
			(min_thickness 0.25)
			(keepout
				(tracks not_allowed)
				(vias allowed)
				(pads allowed)
				(copperpour not_allowed)
				(footprints allowed)
			)
			(placement
				(enabled no)
				(sheetname "")
			)
			(fill
				(thermal_gap 0.5)
				(thermal_bridge_width 0.5)
				(island_removal_mode 0)
			)
			(polygon
				(pts
					(arc
						(start 333.29626 -40.174164)
						(mid 333.371975 -40.127534)
						(end 333.418434 -40.051736)
					)
					(arc
						(start 333.523844 -40.051736)
						(mid 333.444042 -40.199518)
						(end 333.29626 -40.27932)
					)
				)
			)
		)
		(zone
			(layer "F.Cu")
			(hatch none 0.5)
			(connect_pads
				(clearance 0)
			)
			(min_thickness 0.25)
			(keepout
				(tracks not_allowed)
				(vias allowed)
				(pads allowed)
				(copperpour not_allowed)
				(footprints allowed)
			)
			(placement
				(enabled no)
				(sheetname "")
			)
			(fill
				(thermal_gap 0.5)
				(thermal_bridge_width 0.5)
				(island_removal_mode 0)
			)
			(polygon
				(pts
					(arc
						(start 333.418434 -56.848756)
						(mid 333.371919 -56.773014)
						(end 333.29626 -56.726328)
					)
					(arc
						(start 333.29626 -56.621172)
						(mid 333.444042 -56.700974)
						(end 333.523844 -56.848756)
					)
				)
			)
		)
		(zone
			(layer "F.Cu")
			(hatch none 0.5)
			(connect_pads
				(clearance 0)
			)
			(min_thickness 0.25)
			(keepout
				(tracks not_allowed)
				(vias allowed)
				(pads allowed)
				(copperpour not_allowed)
				(footprints allowed)
			)
			(placement
				(enabled no)
				(sheetname "")
			)
			(fill
				(thermal_gap 0.5)
				(thermal_bridge_width 0.5)
				(island_removal_mode 0)
			)
			(polygon
				(pts
					(arc
						(start 333.418434 -55.908956)
						(mid 333.371919 -55.833214)
						(end 333.29626 -55.786528)
					)
					(arc
						(start 333.29626 -55.681372)
						(mid 333.444042 -55.761174)
						(end 333.523844 -55.908956)
					)
				)
			)
		)
		(zone
			(layer "F.Cu")
			(hatch none 0.5)
			(connect_pads
				(clearance 0)
			)
			(min_thickness 0.25)
			(keepout
				(tracks not_allowed)
				(vias allowed)
				(pads allowed)
				(copperpour not_allowed)
				(footprints allowed)
			)
			(placement
				(enabled no)
				(sheetname "")
			)
			(fill
				(thermal_gap 0.5)
				(thermal_bridge_width 0.5)
				(island_removal_mode 0)
			)
			(polygon
				(pts
					(arc
						(start 333.418434 -54.969156)
						(mid 333.371919 -54.893414)
						(end 333.29626 -54.846728)
					)
					(arc
						(start 333.29626 -54.741572)
						(mid 333.444042 -54.821374)
						(end 333.523844 -54.969156)
					)
				)
			)
		)
		(zone
			(layer "F.Cu")
			(hatch none 0.5)
			(connect_pads
				(clearance 0)
			)
			(min_thickness 0.25)
			(keepout
				(tracks not_allowed)
				(vias allowed)
				(pads allowed)
				(copperpour not_allowed)
				(footprints allowed)
			)
			(placement
				(enabled no)
				(sheetname "")
			)
			(fill
				(thermal_gap 0.5)
				(thermal_bridge_width 0.5)
				(island_removal_mode 0)
			)
			(polygon
				(pts
					(arc
						(start 333.418434 -54.029356)
						(mid 333.371919 -53.953614)
						(end 333.29626 -53.906928)
					)
					(arc
						(start 333.29626 -53.801772)
						(mid 333.444042 -53.881574)
						(end 333.523844 -54.029356)
					)
				)
			)
		)
		(zone
			(layer "F.Cu")
			(hatch none 0.5)
			(connect_pads
				(clearance 0)
			)
			(min_thickness 0.25)
			(keepout
				(tracks not_allowed)
				(vias allowed)
				(pads allowed)
				(copperpour not_allowed)
				(footprints allowed)
			)
			(placement
				(enabled no)
				(sheetname "")
			)
			(fill
				(thermal_gap 0.5)
				(thermal_bridge_width 0.5)
				(island_removal_mode 0)
			)
			(polygon
				(pts
					(arc
						(start 333.418434 -53.089556)
						(mid 333.371919 -53.013814)
						(end 333.29626 -52.967128)
					)
					(arc
						(start 333.29626 -52.861972)
						(mid 333.444042 -52.941774)
						(end 333.523844 -53.089556)
					)
				)
			)
		)
		(zone
			(layer "F.Cu")
			(hatch none 0.5)
			(connect_pads
				(clearance 0)
			)
			(min_thickness 0.25)
			(keepout
				(tracks not_allowed)
				(vias allowed)
				(pads allowed)
				(copperpour not_allowed)
				(footprints allowed)
			)
			(placement
				(enabled no)
				(sheetname "")
			)
			(fill
				(thermal_gap 0.5)
				(thermal_bridge_width 0.5)
				(island_removal_mode 0)
			)
			(polygon
				(pts
					(arc
						(start 333.418434 -52.149756)
						(mid 333.371919 -52.074014)
						(end 333.29626 -52.027328)
					)
					(arc
						(start 333.29626 -51.922172)
						(mid 333.444042 -52.001974)
						(end 333.523844 -52.149756)
					)
				)
			)
		)
		(zone
			(layer "F.Cu")
			(hatch none 0.5)
			(connect_pads
				(clearance 0)
			)
			(min_thickness 0.25)
			(keepout
				(tracks not_allowed)
				(vias allowed)
				(pads allowed)
				(copperpour not_allowed)
				(footprints allowed)
			)
			(placement
				(enabled no)
				(sheetname "")
			)
			(fill
				(thermal_gap 0.5)
				(thermal_bridge_width 0.5)
				(island_removal_mode 0)
			)
			(polygon
				(pts
					(arc
						(start 333.418434 -51.209956)
						(mid 333.371919 -51.134214)
						(end 333.29626 -51.087528)
					)
					(arc
						(start 333.29626 -50.982372)
						(mid 333.444042 -51.062174)
						(end 333.523844 -51.209956)
					)
				)
			)
		)
		(zone
			(layer "F.Cu")
			(hatch none 0.5)
			(connect_pads
				(clearance 0)
			)
			(min_thickness 0.25)
			(keepout
				(tracks not_allowed)
				(vias allowed)
				(pads allowed)
				(copperpour not_allowed)
				(footprints allowed)
			)
			(placement
				(enabled no)
				(sheetname "")
			)
			(fill
				(thermal_gap 0.5)
				(thermal_bridge_width 0.5)
				(island_removal_mode 0)
			)
			(polygon
				(pts
					(arc
						(start 333.418434 -50.270156)
						(mid 333.371919 -50.194414)
						(end 333.29626 -50.147728)
					)
					(arc
						(start 333.29626 -50.042572)
						(mid 333.444042 -50.122374)
						(end 333.523844 -50.270156)
					)
				)
			)
		)
		(zone
			(layer "F.Cu")
			(hatch none 0.5)
			(connect_pads
				(clearance 0)
			)
			(min_thickness 0.25)
			(keepout
				(tracks not_allowed)
				(vias allowed)
				(pads allowed)
				(copperpour not_allowed)
				(footprints allowed)
			)
			(placement
				(enabled no)
				(sheetname "")
			)
			(fill
				(thermal_gap 0.5)
				(thermal_bridge_width 0.5)
				(island_removal_mode 0)
			)
			(polygon
				(pts
					(arc
						(start 333.418434 -49.330356)
						(mid 333.371919 -49.254614)
						(end 333.29626 -49.207928)
					)
					(arc
						(start 333.29626 -49.102772)
						(mid 333.444042 -49.182574)
						(end 333.523844 -49.330356)
					)
				)
			)
		)
		(zone
			(layer "F.Cu")
			(hatch none 0.5)
			(connect_pads
				(clearance 0)
			)
			(min_thickness 0.25)
			(keepout
				(tracks not_allowed)
				(vias allowed)
				(pads allowed)
				(copperpour not_allowed)
				(footprints allowed)
			)
			(placement
				(enabled no)
				(sheetname "")
			)
			(fill
				(thermal_gap 0.5)
				(thermal_bridge_width 0.5)
				(island_removal_mode 0)
			)
			(polygon
				(pts
					(arc
						(start 333.418434 -48.390556)
						(mid 333.371919 -48.314814)
						(end 333.29626 -48.268128)
					)
					(arc
						(start 333.29626 -48.162972)
						(mid 333.444042 -48.242774)
						(end 333.523844 -48.390556)
					)
				)
			)
		)
		(zone
			(layer "F.Cu")
			(hatch none 0.5)
			(connect_pads
				(clearance 0)
			)
			(min_thickness 0.25)
			(keepout
				(tracks not_allowed)
				(vias allowed)
				(pads allowed)
				(copperpour not_allowed)
				(footprints allowed)
			)
			(placement
				(enabled no)
				(sheetname "")
			)
			(fill
				(thermal_gap 0.5)
				(thermal_bridge_width 0.5)
				(island_removal_mode 0)
			)
			(polygon
				(pts
					(arc
						(start 333.418434 -47.450756)
						(mid 333.371919 -47.375014)
						(end 333.29626 -47.328328)
					)
					(arc
						(start 333.29626 -47.223172)
						(mid 333.444042 -47.302974)
						(end 333.523844 -47.450756)
					)
				)
			)
		)
		(zone
			(layer "F.Cu")
			(hatch none 0.5)
			(connect_pads
				(clearance 0)
			)
			(min_thickness 0.25)
			(keepout
				(tracks not_allowed)
				(vias allowed)
				(pads allowed)
				(copperpour not_allowed)
				(footprints allowed)
			)
			(placement
				(enabled no)
				(sheetname "")
			)
			(fill
				(thermal_gap 0.5)
				(thermal_bridge_width 0.5)
				(island_removal_mode 0)
			)
			(polygon
				(pts
					(arc
						(start 333.418434 -46.510956)
						(mid 333.371919 -46.435214)
						(end 333.29626 -46.388528)
					)
					(arc
						(start 333.29626 -46.283372)
						(mid 333.444042 -46.363174)
						(end 333.523844 -46.510956)
					)
				)
			)
		)
		(zone
			(layer "F.Cu")
			(hatch none 0.5)
			(connect_pads
				(clearance 0)
			)
			(min_thickness 0.25)
			(keepout
				(tracks not_allowed)
				(vias allowed)
				(pads allowed)
				(copperpour not_allowed)
				(footprints allowed)
			)
			(placement
				(enabled no)
				(sheetname "")
			)
			(fill
				(thermal_gap 0.5)
				(thermal_bridge_width 0.5)
				(island_removal_mode 0)
			)
			(polygon
				(pts
					(arc
						(start 333.418434 -45.571156)
						(mid 333.371919 -45.495414)
						(end 333.29626 -45.448728)
					)
					(arc
						(start 333.29626 -45.343572)
						(mid 333.444042 -45.423374)
						(end 333.523844 -45.571156)
					)
				)
			)
		)
		(zone
			(layer "F.Cu")
			(hatch none 0.5)
			(connect_pads
				(clearance 0)
			)
			(min_thickness 0.25)
			(keepout
				(tracks not_allowed)
				(vias allowed)
				(pads allowed)
				(copperpour not_allowed)
				(footprints allowed)
			)
			(placement
				(enabled no)
				(sheetname "")
			)
			(fill
				(thermal_gap 0.5)
				(thermal_bridge_width 0.5)
				(island_removal_mode 0)
			)
			(polygon
				(pts
					(arc
						(start 333.418434 -44.631356)
						(mid 333.371919 -44.555614)
						(end 333.29626 -44.508928)
					)
					(arc
						(start 333.29626 -44.403772)
						(mid 333.444042 -44.483574)
						(end 333.523844 -44.631356)
					)
				)
			)
		)
		(zone
			(layer "F.Cu")
			(hatch none 0.5)
			(connect_pads
				(clearance 0)
			)
			(min_thickness 0.25)
			(keepout
				(tracks not_allowed)
				(vias allowed)
				(pads allowed)
				(copperpour not_allowed)
				(footprints allowed)
			)
			(placement
				(enabled no)
				(sheetname "")
			)
			(fill
				(thermal_gap 0.5)
				(thermal_bridge_width 0.5)
				(island_removal_mode 0)
			)
			(polygon
				(pts
					(arc
						(start 333.418434 -43.691556)
						(mid 333.371919 -43.615814)
						(end 333.29626 -43.569128)
					)
					(arc
						(start 333.29626 -43.463972)
						(mid 333.444042 -43.543774)
						(end 333.523844 -43.691556)
					)
				)
			)
		)
		(zone
			(layer "F.Cu")
			(hatch none 0.5)
			(connect_pads
				(clearance 0)
			)
			(min_thickness 0.25)
			(keepout
				(tracks not_allowed)
				(vias allowed)
				(pads allowed)
				(copperpour not_allowed)
				(footprints allowed)
			)
			(placement
				(enabled no)
				(sheetname "")
			)
			(fill
				(thermal_gap 0.5)
				(thermal_bridge_width 0.5)
				(island_removal_mode 0)
			)
			(polygon
				(pts
					(arc
						(start 333.418434 -42.751756)
						(mid 333.371919 -42.676014)
						(end 333.29626 -42.629328)
					)
					(arc
						(start 333.29626 -42.524172)
						(mid 333.444042 -42.603974)
						(end 333.523844 -42.751756)
					)
				)
			)
		)
		(zone
			(layer "F.Cu")
			(hatch none 0.5)
			(connect_pads
				(clearance 0)
			)
			(min_thickness 0.25)
			(keepout
				(tracks not_allowed)
				(vias allowed)
				(pads allowed)
				(copperpour not_allowed)
				(footprints allowed)
			)
			(placement
				(enabled no)
				(sheetname "")
			)
			(fill
				(thermal_gap 0.5)
				(thermal_bridge_width 0.5)
				(island_removal_mode 0)
			)
			(polygon
				(pts
					(arc
						(start 333.418434 -41.811956)
						(mid 333.371919 -41.736214)
						(end 333.29626 -41.689528)
					)
					(arc
						(start 333.29626 -41.584372)
						(mid 333.444042 -41.664174)
						(end 333.523844 -41.811956)
					)
				)
			)
		)
		(zone
			(layer "F.Cu")
			(hatch none 0.5)
			(connect_pads
				(clearance 0)
			)
			(min_thickness 0.25)
			(keepout
				(tracks not_allowed)
				(vias allowed)
				(pads allowed)
				(copperpour not_allowed)
				(footprints allowed)
			)
			(placement
				(enabled no)
				(sheetname "")
			)
			(fill
				(thermal_gap 0.5)
				(thermal_bridge_width 0.5)
				(island_removal_mode 0)
			)
			(polygon
				(pts
					(arc
						(start 333.418434 -40.872156)
						(mid 333.371919 -40.796414)
						(end 333.29626 -40.749728)
					)
					(arc
						(start 333.29626 -40.644572)
						(mid 333.444042 -40.724374)
						(end 333.523844 -40.872156)
					)
				)
			)
		)
		(zone
			(layer "F.Cu")
			(hatch none 0.5)
			(connect_pads
				(clearance 0)
			)
			(min_thickness 0.25)
			(keepout
				(tracks not_allowed)
				(vias allowed)
				(pads allowed)
				(copperpour not_allowed)
				(footprints allowed)
			)
			(placement
				(enabled no)
				(sheetname "")
			)
			(fill
				(thermal_gap 0.5)
				(thermal_bridge_width 0.5)
				(island_removal_mode 0)
			)
			(polygon
				(pts
					(arc
						(start 333.418434 -39.932356)
						(mid 333.371919 -39.856614)
						(end 333.29626 -39.809928)
					)
					(arc
						(start 333.29626 -39.704772)
						(mid 333.444042 -39.784574)
						(end 333.523844 -39.932356)
					)
				)
			)
		)
		(zone
			(layer "F.Cu")
			(hatch none 0.5)
			(connect_pads
				(clearance 0)
			)
			(min_thickness 0.25)
			(keepout
				(tracks not_allowed)
				(vias allowed)
				(pads allowed)
				(copperpour not_allowed)
				(footprints allowed)
			)
			(placement
				(enabled no)
				(sheetname "")
			)
			(fill
				(thermal_gap 0.5)
				(thermal_bridge_width 0.5)
				(island_removal_mode 0)
			)
			(polygon
				(pts
					(arc
						(start 333.868268 -56.498236)
						(mid 333.914869 -56.574063)
						(end 333.990696 -56.620664)
					)
					(arc
						(start 333.990696 -56.72582)
						(mid 333.842914 -56.646018)
						(end 333.763112 -56.498236)
					)
				)
			)
		)
		(zone
			(layer "F.Cu")
			(hatch none 0.5)
			(connect_pads
				(clearance 0)
			)
			(min_thickness 0.25)
			(keepout
				(tracks not_allowed)
				(vias allowed)
				(pads allowed)
				(copperpour not_allowed)
				(footprints allowed)
			)
			(placement
				(enabled no)
				(sheetname "")
			)
			(fill
				(thermal_gap 0.5)
				(thermal_bridge_width 0.5)
				(island_removal_mode 0)
			)
			(polygon
				(pts
					(arc
						(start 333.868268 -55.558436)
						(mid 333.914869 -55.634263)
						(end 333.990696 -55.680864)
					)
					(arc
						(start 333.990696 -55.78602)
						(mid 333.842914 -55.706218)
						(end 333.763112 -55.558436)
					)
				)
			)
		)
		(zone
			(layer "F.Cu")
			(hatch none 0.5)
			(connect_pads
				(clearance 0)
			)
			(min_thickness 0.25)
			(keepout
				(tracks not_allowed)
				(vias allowed)
				(pads allowed)
				(copperpour not_allowed)
				(footprints allowed)
			)
			(placement
				(enabled no)
				(sheetname "")
			)
			(fill
				(thermal_gap 0.5)
				(thermal_bridge_width 0.5)
				(island_removal_mode 0)
			)
			(polygon
				(pts
					(arc
						(start 333.868268 -54.618636)
						(mid 333.914869 -54.694463)
						(end 333.990696 -54.741064)
					)
					(arc
						(start 333.990696 -54.84622)
						(mid 333.842914 -54.766418)
						(end 333.763112 -54.618636)
					)
				)
			)
		)
		(zone
			(layer "F.Cu")
			(hatch none 0.5)
			(connect_pads
				(clearance 0)
			)
			(min_thickness 0.25)
			(keepout
				(tracks not_allowed)
				(vias allowed)
				(pads allowed)
				(copperpour not_allowed)
				(footprints allowed)
			)
			(placement
				(enabled no)
				(sheetname "")
			)
			(fill
				(thermal_gap 0.5)
				(thermal_bridge_width 0.5)
				(island_removal_mode 0)
			)
			(polygon
				(pts
					(arc
						(start 333.868268 -53.678836)
						(mid 333.914869 -53.754663)
						(end 333.990696 -53.801264)
					)
					(arc
						(start 333.990696 -53.90642)
						(mid 333.842914 -53.826618)
						(end 333.763112 -53.678836)
					)
				)
			)
		)
		(zone
			(layer "F.Cu")
			(hatch none 0.5)
			(connect_pads
				(clearance 0)
			)
			(min_thickness 0.25)
			(keepout
				(tracks not_allowed)
				(vias allowed)
				(pads allowed)
				(copperpour not_allowed)
				(footprints allowed)
			)
			(placement
				(enabled no)
				(sheetname "")
			)
			(fill
				(thermal_gap 0.5)
				(thermal_bridge_width 0.5)
				(island_removal_mode 0)
			)
			(polygon
				(pts
					(arc
						(start 333.868268 -52.739036)
						(mid 333.914869 -52.814863)
						(end 333.990696 -52.861464)
					)
					(arc
						(start 333.990696 -52.96662)
						(mid 333.842914 -52.886818)
						(end 333.763112 -52.739036)
					)
				)
			)
		)
		(zone
			(layer "F.Cu")
			(hatch none 0.5)
			(connect_pads
				(clearance 0)
			)
			(min_thickness 0.25)
			(keepout
				(tracks not_allowed)
				(vias allowed)
				(pads allowed)
				(copperpour not_allowed)
				(footprints allowed)
			)
			(placement
				(enabled no)
				(sheetname "")
			)
			(fill
				(thermal_gap 0.5)
				(thermal_bridge_width 0.5)
				(island_removal_mode 0)
			)
			(polygon
				(pts
					(arc
						(start 333.868522 -44.280836)
						(mid 333.915123 -44.356663)
						(end 333.99095 -44.403264)
					)
					(arc
						(start 333.99095 -44.50842)
						(mid 333.843168 -44.428618)
						(end 333.763366 -44.280836)
					)
				)
			)
		)
		(zone
			(layer "F.Cu")
			(hatch none 0.5)
			(connect_pads
				(clearance 0)
			)
			(min_thickness 0.25)
			(keepout
				(tracks not_allowed)
				(vias allowed)
				(pads allowed)
				(copperpour not_allowed)
				(footprints allowed)
			)
			(placement
				(enabled no)
				(sheetname "")
			)
			(fill
				(thermal_gap 0.5)
				(thermal_bridge_width 0.5)
				(island_removal_mode 0)
			)
			(polygon
				(pts
					(arc
						(start 333.868522 -43.341036)
						(mid 333.915123 -43.416863)
						(end 333.99095 -43.463464)
					)
					(arc
						(start 333.99095 -43.56862)
						(mid 333.843168 -43.488818)
						(end 333.763366 -43.341036)
					)
				)
			)
		)
		(zone
			(layer "F.Cu")
			(hatch none 0.5)
			(connect_pads
				(clearance 0)
			)
			(min_thickness 0.25)
			(keepout
				(tracks not_allowed)
				(vias allowed)
				(pads allowed)
				(copperpour not_allowed)
				(footprints allowed)
			)
			(placement
				(enabled no)
				(sheetname "")
			)
			(fill
				(thermal_gap 0.5)
				(thermal_bridge_width 0.5)
				(island_removal_mode 0)
			)
			(polygon
				(pts
					(arc
						(start 333.868522 -42.401236)
						(mid 333.915123 -42.477063)
						(end 333.99095 -42.523664)
					)
					(arc
						(start 333.99095 -42.62882)
						(mid 333.843168 -42.549018)
						(end 333.763366 -42.401236)
					)
				)
			)
		)
		(zone
			(layer "F.Cu")
			(hatch none 0.5)
			(connect_pads
				(clearance 0)
			)
			(min_thickness 0.25)
			(keepout
				(tracks not_allowed)
				(vias allowed)
				(pads allowed)
				(copperpour not_allowed)
				(footprints allowed)
			)
			(placement
				(enabled no)
				(sheetname "")
			)
			(fill
				(thermal_gap 0.5)
				(thermal_bridge_width 0.5)
				(island_removal_mode 0)
			)
			(polygon
				(pts
					(arc
						(start 333.868522 -41.461436)
						(mid 333.915123 -41.537263)
						(end 333.99095 -41.583864)
					)
					(arc
						(start 333.99095 -41.68902)
						(mid 333.843168 -41.609218)
						(end 333.763366 -41.461436)
					)
				)
			)
		)
		(zone
			(layer "F.Cu")
			(hatch none 0.5)
			(connect_pads
				(clearance 0)
			)
			(min_thickness 0.25)
			(keepout
				(tracks not_allowed)
				(vias allowed)
				(pads allowed)
				(copperpour not_allowed)
				(footprints allowed)
			)
			(placement
				(enabled no)
				(sheetname "")
			)
			(fill
				(thermal_gap 0.5)
				(thermal_bridge_width 0.5)
				(island_removal_mode 0)
			)
			(polygon
				(pts
					(arc
						(start 333.868522 -40.521636)
						(mid 333.915123 -40.597463)
						(end 333.99095 -40.644064)
					)
					(arc
						(start 333.99095 -40.74922)
						(mid 333.843168 -40.669418)
						(end 333.763366 -40.521636)
					)
				)
			)
		)
		(zone
			(layer "F.Cu")
			(hatch none 0.5)
			(connect_pads
				(clearance 0)
			)
			(min_thickness 0.25)
			(keepout
				(tracks not_allowed)
				(vias allowed)
				(pads allowed)
				(copperpour not_allowed)
				(footprints allowed)
			)
			(placement
				(enabled no)
				(sheetname "")
			)
			(fill
				(thermal_gap 0.5)
				(thermal_bridge_width 0.5)
				(island_removal_mode 0)
			)
			(polygon
				(pts
					(arc
						(start 333.990696 -56.256428)
						(mid 333.914869 -56.303029)
						(end 333.868268 -56.378856)
					)
					(arc
						(start 333.763112 -56.378856)
						(mid 333.842914 -56.231074)
						(end 333.990696 -56.151272)
					)
				)
			)
		)
		(zone
			(layer "F.Cu")
			(hatch none 0.5)
			(connect_pads
				(clearance 0)
			)
			(min_thickness 0.25)
			(keepout
				(tracks not_allowed)
				(vias allowed)
				(pads allowed)
				(copperpour not_allowed)
				(footprints allowed)
			)
			(placement
				(enabled no)
				(sheetname "")
			)
			(fill
				(thermal_gap 0.5)
				(thermal_bridge_width 0.5)
				(island_removal_mode 0)
			)
			(polygon
				(pts
					(arc
						(start 333.990696 -55.316628)
						(mid 333.914869 -55.363229)
						(end 333.868268 -55.439056)
					)
					(arc
						(start 333.763112 -55.439056)
						(mid 333.842914 -55.291274)
						(end 333.990696 -55.211472)
					)
				)
			)
		)
		(zone
			(layer "F.Cu")
			(hatch none 0.5)
			(connect_pads
				(clearance 0)
			)
			(min_thickness 0.25)
			(keepout
				(tracks not_allowed)
				(vias allowed)
				(pads allowed)
				(copperpour not_allowed)
				(footprints allowed)
			)
			(placement
				(enabled no)
				(sheetname "")
			)
			(fill
				(thermal_gap 0.5)
				(thermal_bridge_width 0.5)
				(island_removal_mode 0)
			)
			(polygon
				(pts
					(arc
						(start 333.990696 -54.376828)
						(mid 333.914869 -54.423429)
						(end 333.868268 -54.499256)
					)
					(arc
						(start 333.763112 -54.499256)
						(mid 333.842914 -54.351474)
						(end 333.990696 -54.271672)
					)
				)
			)
		)
		(zone
			(layer "F.Cu")
			(hatch none 0.5)
			(connect_pads
				(clearance 0)
			)
			(min_thickness 0.25)
			(keepout
				(tracks not_allowed)
				(vias allowed)
				(pads allowed)
				(copperpour not_allowed)
				(footprints allowed)
			)
			(placement
				(enabled no)
				(sheetname "")
			)
			(fill
				(thermal_gap 0.5)
				(thermal_bridge_width 0.5)
				(island_removal_mode 0)
			)
			(polygon
				(pts
					(arc
						(start 333.990696 -53.437028)
						(mid 333.914869 -53.483629)
						(end 333.868268 -53.559456)
					)
					(arc
						(start 333.763112 -53.559456)
						(mid 333.842914 -53.411674)
						(end 333.990696 -53.331872)
					)
				)
			)
		)
		(zone
			(layer "F.Cu")
			(hatch none 0.5)
			(connect_pads
				(clearance 0)
			)
			(min_thickness 0.25)
			(keepout
				(tracks not_allowed)
				(vias allowed)
				(pads allowed)
				(copperpour not_allowed)
				(footprints allowed)
			)
			(placement
				(enabled no)
				(sheetname "")
			)
			(fill
				(thermal_gap 0.5)
				(thermal_bridge_width 0.5)
				(island_removal_mode 0)
			)
			(polygon
				(pts
					(arc
						(start 333.990696 -52.497228)
						(mid 333.914869 -52.543829)
						(end 333.868268 -52.619656)
					)
					(arc
						(start 333.763112 -52.619656)
						(mid 333.842914 -52.471874)
						(end 333.990696 -52.392072)
					)
				)
			)
		)
		(zone
			(layer "F.Cu")
			(hatch none 0.5)
			(connect_pads
				(clearance 0)
			)
			(min_thickness 0.25)
			(keepout
				(tracks not_allowed)
				(vias allowed)
				(pads allowed)
				(copperpour not_allowed)
				(footprints allowed)
			)
			(placement
				(enabled no)
				(sheetname "")
			)
			(fill
				(thermal_gap 0.5)
				(thermal_bridge_width 0.5)
				(island_removal_mode 0)
			)
			(polygon
				(pts
					(arc
						(start 333.99095 -44.039028)
						(mid 333.915123 -44.085629)
						(end 333.868522 -44.161456)
					)
					(arc
						(start 333.763366 -44.161456)
						(mid 333.843168 -44.013674)
						(end 333.99095 -43.933872)
					)
				)
			)
		)
		(zone
			(layer "F.Cu")
			(hatch none 0.5)
			(connect_pads
				(clearance 0)
			)
			(min_thickness 0.25)
			(keepout
				(tracks not_allowed)
				(vias allowed)
				(pads allowed)
				(copperpour not_allowed)
				(footprints allowed)
			)
			(placement
				(enabled no)
				(sheetname "")
			)
			(fill
				(thermal_gap 0.5)
				(thermal_bridge_width 0.5)
				(island_removal_mode 0)
			)
			(polygon
				(pts
					(arc
						(start 333.99095 -43.099228)
						(mid 333.915123 -43.145829)
						(end 333.868522 -43.221656)
					)
					(arc
						(start 333.763366 -43.221656)
						(mid 333.843168 -43.073874)
						(end 333.99095 -42.994072)
					)
				)
			)
		)
		(zone
			(layer "F.Cu")
			(hatch none 0.5)
			(connect_pads
				(clearance 0)
			)
			(min_thickness 0.25)
			(keepout
				(tracks not_allowed)
				(vias allowed)
				(pads allowed)
				(copperpour not_allowed)
				(footprints allowed)
			)
			(placement
				(enabled no)
				(sheetname "")
			)
			(fill
				(thermal_gap 0.5)
				(thermal_bridge_width 0.5)
				(island_removal_mode 0)
			)
			(polygon
				(pts
					(arc
						(start 333.99095 -42.159428)
						(mid 333.915123 -42.206029)
						(end 333.868522 -42.281856)
					)
					(arc
						(start 333.763366 -42.281856)
						(mid 333.843168 -42.134074)
						(end 333.99095 -42.054272)
					)
				)
			)
		)
		(zone
			(layer "F.Cu")
			(hatch none 0.5)
			(connect_pads
				(clearance 0)
			)
			(min_thickness 0.25)
			(keepout
				(tracks not_allowed)
				(vias allowed)
				(pads allowed)
				(copperpour not_allowed)
				(footprints allowed)
			)
			(placement
				(enabled no)
				(sheetname "")
			)
			(fill
				(thermal_gap 0.5)
				(thermal_bridge_width 0.5)
				(island_removal_mode 0)
			)
			(polygon
				(pts
					(arc
						(start 333.99095 -41.219628)
						(mid 333.915123 -41.266229)
						(end 333.868522 -41.342056)
					)
					(arc
						(start 333.763366 -41.342056)
						(mid 333.843168 -41.194274)
						(end 333.99095 -41.114472)
					)
				)
			)
		)
		(zone
			(layer "F.Cu")
			(hatch none 0.5)
			(connect_pads
				(clearance 0)
			)
			(min_thickness 0.25)
			(keepout
				(tracks not_allowed)
				(vias allowed)
				(pads allowed)
				(copperpour not_allowed)
				(footprints allowed)
			)
			(placement
				(enabled no)
				(sheetname "")
			)
			(fill
				(thermal_gap 0.5)
				(thermal_bridge_width 0.5)
				(island_removal_mode 0)
			)
			(polygon
				(pts
					(arc
						(start 333.99095 -40.279828)
						(mid 333.915123 -40.326429)
						(end 333.868522 -40.402256)
					)
					(arc
						(start 333.763366 -40.402256)
						(mid 333.843168 -40.254474)
						(end 333.99095 -40.174672)
					)
				)
			)
		)
		(zone
			(layer "F.Cu")
			(hatch none 0.5)
			(connect_pads
				(clearance 0)
			)
			(min_thickness 0.25)
			(keepout
				(tracks not_allowed)
				(vias allowed)
				(pads allowed)
				(copperpour not_allowed)
				(footprints allowed)
			)
			(placement
				(enabled no)
				(sheetname "")
			)
			(fill
				(thermal_gap 0.5)
				(thermal_bridge_width 0.5)
				(island_removal_mode 0)
			)
			(polygon
				(pts
					(arc
						(start 334.110076 -56.620664)
						(mid 334.185903 -56.574063)
						(end 334.232504 -56.498236)
					)
					(arc
						(start 334.33766 -56.498236)
						(mid 334.257858 -56.646018)
						(end 334.110076 -56.72582)
					)
				)
			)
		)
		(zone
			(layer "F.Cu")
			(hatch none 0.5)
			(connect_pads
				(clearance 0)
			)
			(min_thickness 0.25)
			(keepout
				(tracks not_allowed)
				(vias allowed)
				(pads allowed)
				(copperpour not_allowed)
				(footprints allowed)
			)
			(placement
				(enabled no)
				(sheetname "")
			)
			(fill
				(thermal_gap 0.5)
				(thermal_bridge_width 0.5)
				(island_removal_mode 0)
			)
			(polygon
				(pts
					(arc
						(start 334.110076 -55.680864)
						(mid 334.185903 -55.634263)
						(end 334.232504 -55.558436)
					)
					(arc
						(start 334.33766 -55.558436)
						(mid 334.257858 -55.706218)
						(end 334.110076 -55.78602)
					)
				)
			)
		)
		(zone
			(layer "F.Cu")
			(hatch none 0.5)
			(connect_pads
				(clearance 0)
			)
			(min_thickness 0.25)
			(keepout
				(tracks not_allowed)
				(vias allowed)
				(pads allowed)
				(copperpour not_allowed)
				(footprints allowed)
			)
			(placement
				(enabled no)
				(sheetname "")
			)
			(fill
				(thermal_gap 0.5)
				(thermal_bridge_width 0.5)
				(island_removal_mode 0)
			)
			(polygon
				(pts
					(arc
						(start 334.110076 -54.741064)
						(mid 334.185903 -54.694463)
						(end 334.232504 -54.618636)
					)
					(arc
						(start 334.33766 -54.618636)
						(mid 334.257858 -54.766418)
						(end 334.110076 -54.84622)
					)
				)
			)
		)
		(zone
			(layer "F.Cu")
			(hatch none 0.5)
			(connect_pads
				(clearance 0)
			)
			(min_thickness 0.25)
			(keepout
				(tracks not_allowed)
				(vias allowed)
				(pads allowed)
				(copperpour not_allowed)
				(footprints allowed)
			)
			(placement
				(enabled no)
				(sheetname "")
			)
			(fill
				(thermal_gap 0.5)
				(thermal_bridge_width 0.5)
				(island_removal_mode 0)
			)
			(polygon
				(pts
					(arc
						(start 334.110076 -53.801264)
						(mid 334.185903 -53.754663)
						(end 334.232504 -53.678836)
					)
					(arc
						(start 334.33766 -53.678836)
						(mid 334.257858 -53.826618)
						(end 334.110076 -53.90642)
					)
				)
			)
		)
		(zone
			(layer "F.Cu")
			(hatch none 0.5)
			(connect_pads
				(clearance 0)
			)
			(min_thickness 0.25)
			(keepout
				(tracks not_allowed)
				(vias allowed)
				(pads allowed)
				(copperpour not_allowed)
				(footprints allowed)
			)
			(placement
				(enabled no)
				(sheetname "")
			)
			(fill
				(thermal_gap 0.5)
				(thermal_bridge_width 0.5)
				(island_removal_mode 0)
			)
			(polygon
				(pts
					(arc
						(start 334.110076 -52.861464)
						(mid 334.185903 -52.814863)
						(end 334.232504 -52.739036)
					)
					(arc
						(start 334.33766 -52.739036)
						(mid 334.257858 -52.886818)
						(end 334.110076 -52.96662)
					)
				)
			)
		)
		(zone
			(layer "F.Cu")
			(hatch none 0.5)
			(connect_pads
				(clearance 0)
			)
			(min_thickness 0.25)
			(keepout
				(tracks not_allowed)
				(vias allowed)
				(pads allowed)
				(copperpour not_allowed)
				(footprints allowed)
			)
			(placement
				(enabled no)
				(sheetname "")
			)
			(fill
				(thermal_gap 0.5)
				(thermal_bridge_width 0.5)
				(island_removal_mode 0)
			)
			(polygon
				(pts
					(arc
						(start 334.11033 -44.403264)
						(mid 334.186157 -44.356663)
						(end 334.232758 -44.280836)
					)
					(arc
						(start 334.337914 -44.280836)
						(mid 334.258112 -44.428618)
						(end 334.11033 -44.50842)
					)
				)
			)
		)
		(zone
			(layer "F.Cu")
			(hatch none 0.5)
			(connect_pads
				(clearance 0)
			)
			(min_thickness 0.25)
			(keepout
				(tracks not_allowed)
				(vias allowed)
				(pads allowed)
				(copperpour not_allowed)
				(footprints allowed)
			)
			(placement
				(enabled no)
				(sheetname "")
			)
			(fill
				(thermal_gap 0.5)
				(thermal_bridge_width 0.5)
				(island_removal_mode 0)
			)
			(polygon
				(pts
					(arc
						(start 334.11033 -43.463464)
						(mid 334.186157 -43.416863)
						(end 334.232758 -43.341036)
					)
					(arc
						(start 334.337914 -43.341036)
						(mid 334.258112 -43.488818)
						(end 334.11033 -43.56862)
					)
				)
			)
		)
		(zone
			(layer "F.Cu")
			(hatch none 0.5)
			(connect_pads
				(clearance 0)
			)
			(min_thickness 0.25)
			(keepout
				(tracks not_allowed)
				(vias allowed)
				(pads allowed)
				(copperpour not_allowed)
				(footprints allowed)
			)
			(placement
				(enabled no)
				(sheetname "")
			)
			(fill
				(thermal_gap 0.5)
				(thermal_bridge_width 0.5)
				(island_removal_mode 0)
			)
			(polygon
				(pts
					(arc
						(start 334.11033 -42.523664)
						(mid 334.186157 -42.477063)
						(end 334.232758 -42.401236)
					)
					(arc
						(start 334.337914 -42.401236)
						(mid 334.258112 -42.549018)
						(end 334.11033 -42.62882)
					)
				)
			)
		)
		(zone
			(layer "F.Cu")
			(hatch none 0.5)
			(connect_pads
				(clearance 0)
			)
			(min_thickness 0.25)
			(keepout
				(tracks not_allowed)
				(vias allowed)
				(pads allowed)
				(copperpour not_allowed)
				(footprints allowed)
			)
			(placement
				(enabled no)
				(sheetname "")
			)
			(fill
				(thermal_gap 0.5)
				(thermal_bridge_width 0.5)
				(island_removal_mode 0)
			)
			(polygon
				(pts
					(arc
						(start 334.11033 -41.583864)
						(mid 334.186157 -41.537263)
						(end 334.232758 -41.461436)
					)
					(arc
						(start 334.337914 -41.461436)
						(mid 334.258112 -41.609218)
						(end 334.11033 -41.68902)
					)
				)
			)
		)
		(zone
			(layer "F.Cu")
			(hatch none 0.5)
			(connect_pads
				(clearance 0)
			)
			(min_thickness 0.25)
			(keepout
				(tracks not_allowed)
				(vias allowed)
				(pads allowed)
				(copperpour not_allowed)
				(footprints allowed)
			)
			(placement
				(enabled no)
				(sheetname "")
			)
			(fill
				(thermal_gap 0.5)
				(thermal_bridge_width 0.5)
				(island_removal_mode 0)
			)
			(polygon
				(pts
					(arc
						(start 334.11033 -40.644064)
						(mid 334.186157 -40.597463)
						(end 334.232758 -40.521636)
					)
					(arc
						(start 334.337914 -40.521636)
						(mid 334.258112 -40.669418)
						(end 334.11033 -40.74922)
					)
				)
			)
		)
		(zone
			(layer "F.Cu")
			(hatch none 0.5)
			(connect_pads
				(clearance 0)
			)
			(min_thickness 0.25)
			(keepout
				(tracks not_allowed)
				(vias allowed)
				(pads allowed)
				(copperpour not_allowed)
				(footprints allowed)
			)
			(placement
				(enabled no)
				(sheetname "")
			)
			(fill
				(thermal_gap 0.5)
				(thermal_bridge_width 0.5)
				(island_removal_mode 0)
			)
			(polygon
				(pts
					(arc
						(start 334.232504 -56.378856)
						(mid 334.185903 -56.303029)
						(end 334.110076 -56.256428)
					)
					(arc
						(start 334.110076 -56.151272)
						(mid 334.257858 -56.231074)
						(end 334.33766 -56.378856)
					)
				)
			)
		)
		(zone
			(layer "F.Cu")
			(hatch none 0.5)
			(connect_pads
				(clearance 0)
			)
			(min_thickness 0.25)
			(keepout
				(tracks not_allowed)
				(vias allowed)
				(pads allowed)
				(copperpour not_allowed)
				(footprints allowed)
			)
			(placement
				(enabled no)
				(sheetname "")
			)
			(fill
				(thermal_gap 0.5)
				(thermal_bridge_width 0.5)
				(island_removal_mode 0)
			)
			(polygon
				(pts
					(arc
						(start 334.232504 -55.439056)
						(mid 334.185903 -55.363229)
						(end 334.110076 -55.316628)
					)
					(arc
						(start 334.110076 -55.211472)
						(mid 334.257858 -55.291274)
						(end 334.33766 -55.439056)
					)
				)
			)
		)
		(zone
			(layer "F.Cu")
			(hatch none 0.5)
			(connect_pads
				(clearance 0)
			)
			(min_thickness 0.25)
			(keepout
				(tracks not_allowed)
				(vias allowed)
				(pads allowed)
				(copperpour not_allowed)
				(footprints allowed)
			)
			(placement
				(enabled no)
				(sheetname "")
			)
			(fill
				(thermal_gap 0.5)
				(thermal_bridge_width 0.5)
				(island_removal_mode 0)
			)
			(polygon
				(pts
					(arc
						(start 334.232504 -54.499256)
						(mid 334.185903 -54.423429)
						(end 334.110076 -54.376828)
					)
					(arc
						(start 334.110076 -54.271672)
						(mid 334.257858 -54.351474)
						(end 334.33766 -54.499256)
					)
				)
			)
		)
		(zone
			(layer "F.Cu")
			(hatch none 0.5)
			(connect_pads
				(clearance 0)
			)
			(min_thickness 0.25)
			(keepout
				(tracks not_allowed)
				(vias allowed)
				(pads allowed)
				(copperpour not_allowed)
				(footprints allowed)
			)
			(placement
				(enabled no)
				(sheetname "")
			)
			(fill
				(thermal_gap 0.5)
				(thermal_bridge_width 0.5)
				(island_removal_mode 0)
			)
			(polygon
				(pts
					(arc
						(start 334.232504 -53.559456)
						(mid 334.185903 -53.483629)
						(end 334.110076 -53.437028)
					)
					(arc
						(start 334.110076 -53.331872)
						(mid 334.257858 -53.411674)
						(end 334.33766 -53.559456)
					)
				)
			)
		)
		(zone
			(layer "F.Cu")
			(hatch none 0.5)
			(connect_pads
				(clearance 0)
			)
			(min_thickness 0.25)
			(keepout
				(tracks not_allowed)
				(vias allowed)
				(pads allowed)
				(copperpour not_allowed)
				(footprints allowed)
			)
			(placement
				(enabled no)
				(sheetname "")
			)
			(fill
				(thermal_gap 0.5)
				(thermal_bridge_width 0.5)
				(island_removal_mode 0)
			)
			(polygon
				(pts
					(arc
						(start 334.232504 -52.619656)
						(mid 334.185903 -52.543829)
						(end 334.110076 -52.497228)
					)
					(arc
						(start 334.110076 -52.392072)
						(mid 334.257858 -52.471874)
						(end 334.33766 -52.619656)
					)
				)
			)
		)
		(zone
			(layer "F.Cu")
			(hatch none 0.5)
			(connect_pads
				(clearance 0)
			)
			(min_thickness 0.25)
			(keepout
				(tracks not_allowed)
				(vias allowed)
				(pads allowed)
				(copperpour not_allowed)
				(footprints allowed)
			)
			(placement
				(enabled no)
				(sheetname "")
			)
			(fill
				(thermal_gap 0.5)
				(thermal_bridge_width 0.5)
				(island_removal_mode 0)
			)
			(polygon
				(pts
					(arc
						(start 334.232758 -44.161456)
						(mid 334.186157 -44.085629)
						(end 334.11033 -44.039028)
					)
					(arc
						(start 334.11033 -43.933872)
						(mid 334.258112 -44.013674)
						(end 334.337914 -44.161456)
					)
				)
			)
		)
		(zone
			(layer "F.Cu")
			(hatch none 0.5)
			(connect_pads
				(clearance 0)
			)
			(min_thickness 0.25)
			(keepout
				(tracks not_allowed)
				(vias allowed)
				(pads allowed)
				(copperpour not_allowed)
				(footprints allowed)
			)
			(placement
				(enabled no)
				(sheetname "")
			)
			(fill
				(thermal_gap 0.5)
				(thermal_bridge_width 0.5)
				(island_removal_mode 0)
			)
			(polygon
				(pts
					(arc
						(start 334.232758 -43.221656)
						(mid 334.186157 -43.145829)
						(end 334.11033 -43.099228)
					)
					(arc
						(start 334.11033 -42.994072)
						(mid 334.258112 -43.073874)
						(end 334.337914 -43.221656)
					)
				)
			)
		)
		(zone
			(layer "F.Cu")
			(hatch none 0.5)
			(connect_pads
				(clearance 0)
			)
			(min_thickness 0.25)
			(keepout
				(tracks not_allowed)
				(vias allowed)
				(pads allowed)
				(copperpour not_allowed)
				(footprints allowed)
			)
			(placement
				(enabled no)
				(sheetname "")
			)
			(fill
				(thermal_gap 0.5)
				(thermal_bridge_width 0.5)
				(island_removal_mode 0)
			)
			(polygon
				(pts
					(arc
						(start 334.232758 -42.281856)
						(mid 334.186157 -42.206029)
						(end 334.11033 -42.159428)
					)
					(arc
						(start 334.11033 -42.054272)
						(mid 334.258112 -42.134074)
						(end 334.337914 -42.281856)
					)
				)
			)
		)
		(zone
			(layer "F.Cu")
			(hatch none 0.5)
			(connect_pads
				(clearance 0)
			)
			(min_thickness 0.25)
			(keepout
				(tracks not_allowed)
				(vias allowed)
				(pads allowed)
				(copperpour not_allowed)
				(footprints allowed)
			)
			(placement
				(enabled no)
				(sheetname "")
			)
			(fill
				(thermal_gap 0.5)
				(thermal_bridge_width 0.5)
				(island_removal_mode 0)
			)
			(polygon
				(pts
					(arc
						(start 334.232758 -41.342056)
						(mid 334.186157 -41.266229)
						(end 334.11033 -41.219628)
					)
					(arc
						(start 334.11033 -41.114472)
						(mid 334.258112 -41.194274)
						(end 334.337914 -41.342056)
					)
				)
			)
		)
		(zone
			(layer "F.Cu")
			(hatch none 0.5)
			(connect_pads
				(clearance 0)
			)
			(min_thickness 0.25)
			(keepout
				(tracks not_allowed)
				(vias allowed)
				(pads allowed)
				(copperpour not_allowed)
				(footprints allowed)
			)
			(placement
				(enabled no)
				(sheetname "")
			)
			(fill
				(thermal_gap 0.5)
				(thermal_bridge_width 0.5)
				(island_removal_mode 0)
			)
			(polygon
				(pts
					(arc
						(start 334.232758 -40.402256)
						(mid 334.186157 -40.326429)
						(end 334.11033 -40.279828)
					)
					(arc
						(start 334.11033 -40.174672)
						(mid 334.258112 -40.254474)
						(end 334.337914 -40.402256)
					)
				)
			)
		)
		(zone
			(layer "F.Cu")
			(hatch none 0.5)
			(connect_pads
				(clearance 0)
			)
			(min_thickness 0.25)
			(keepout
				(tracks not_allowed)
				(vias allowed)
				(pads allowed)
				(copperpour not_allowed)
				(footprints allowed)
			)
			(placement
				(enabled no)
				(sheetname "")
			)
			(fill
				(thermal_gap 0.5)
				(thermal_bridge_width 0.5)
				(island_removal_mode 0)
			)
			(polygon
				(pts
					(arc
						(start 334.31734 -51.710336)
						(mid 334.363941 -51.786163)
						(end 334.439768 -51.832764)
					)
					(arc
						(start 334.439768 -51.93792)
						(mid 334.291986 -51.858118)
						(end 334.212184 -51.710336)
					)
				)
			)
		)
		(zone
			(layer "F.Cu")
			(hatch none 0.5)
			(connect_pads
				(clearance 0)
			)
			(min_thickness 0.25)
			(keepout
				(tracks not_allowed)
				(vias allowed)
				(pads allowed)
				(copperpour not_allowed)
				(footprints allowed)
			)
			(placement
				(enabled no)
				(sheetname "")
			)
			(fill
				(thermal_gap 0.5)
				(thermal_bridge_width 0.5)
				(island_removal_mode 0)
			)
			(polygon
				(pts
					(arc
						(start 334.31734 -50.910236)
						(mid 334.363941 -50.986063)
						(end 334.439768 -51.032664)
					)
					(arc
						(start 334.439768 -51.13782)
						(mid 334.291986 -51.058018)
						(end 334.212184 -50.910236)
					)
				)
			)
		)
		(zone
			(layer "F.Cu")
			(hatch none 0.5)
			(connect_pads
				(clearance 0)
			)
			(min_thickness 0.25)
			(keepout
				(tracks not_allowed)
				(vias allowed)
				(pads allowed)
				(copperpour not_allowed)
				(footprints allowed)
			)
			(placement
				(enabled no)
				(sheetname "")
			)
			(fill
				(thermal_gap 0.5)
				(thermal_bridge_width 0.5)
				(island_removal_mode 0)
			)
			(polygon
				(pts
					(arc
						(start 334.31734 -50.110136)
						(mid 334.363941 -50.185963)
						(end 334.439768 -50.232564)
					)
					(arc
						(start 334.439768 -50.33772)
						(mid 334.291986 -50.257918)
						(end 334.212184 -50.110136)
					)
				)
			)
		)
		(zone
			(layer "F.Cu")
			(hatch none 0.5)
			(connect_pads
				(clearance 0)
			)
			(min_thickness 0.25)
			(keepout
				(tracks not_allowed)
				(vias allowed)
				(pads allowed)
				(copperpour not_allowed)
				(footprints allowed)
			)
			(placement
				(enabled no)
				(sheetname "")
			)
			(fill
				(thermal_gap 0.5)
				(thermal_bridge_width 0.5)
				(island_removal_mode 0)
			)
			(polygon
				(pts
					(arc
						(start 334.31734 -49.310036)
						(mid 334.363941 -49.385863)
						(end 334.439768 -49.432464)
					)
					(arc
						(start 334.439768 -49.53762)
						(mid 334.291986 -49.457818)
						(end 334.212184 -49.310036)
					)
				)
			)
		)
		(zone
			(layer "F.Cu")
			(hatch none 0.5)
			(connect_pads
				(clearance 0)
			)
			(min_thickness 0.25)
			(keepout
				(tracks not_allowed)
				(vias allowed)
				(pads allowed)
				(copperpour not_allowed)
				(footprints allowed)
			)
			(placement
				(enabled no)
				(sheetname "")
			)
			(fill
				(thermal_gap 0.5)
				(thermal_bridge_width 0.5)
				(island_removal_mode 0)
			)
			(polygon
				(pts
					(arc
						(start 334.31734 -48.509936)
						(mid 334.363941 -48.585763)
						(end 334.439768 -48.632364)
					)
					(arc
						(start 334.439768 -48.73752)
						(mid 334.291986 -48.657718)
						(end 334.212184 -48.509936)
					)
				)
			)
		)
		(zone
			(layer "F.Cu")
			(hatch none 0.5)
			(connect_pads
				(clearance 0)
			)
			(min_thickness 0.25)
			(keepout
				(tracks not_allowed)
				(vias allowed)
				(pads allowed)
				(copperpour not_allowed)
				(footprints allowed)
			)
			(placement
				(enabled no)
				(sheetname "")
			)
			(fill
				(thermal_gap 0.5)
				(thermal_bridge_width 0.5)
				(island_removal_mode 0)
			)
			(polygon
				(pts
					(arc
						(start 334.31734 -47.709836)
						(mid 334.363941 -47.785663)
						(end 334.439768 -47.832264)
					)
					(arc
						(start 334.439768 -47.93742)
						(mid 334.291986 -47.857618)
						(end 334.212184 -47.709836)
					)
				)
			)
		)
		(zone
			(layer "F.Cu")
			(hatch none 0.5)
			(connect_pads
				(clearance 0)
			)
			(min_thickness 0.25)
			(keepout
				(tracks not_allowed)
				(vias allowed)
				(pads allowed)
				(copperpour not_allowed)
				(footprints allowed)
			)
			(placement
				(enabled no)
				(sheetname "")
			)
			(fill
				(thermal_gap 0.5)
				(thermal_bridge_width 0.5)
				(island_removal_mode 0)
			)
			(polygon
				(pts
					(arc
						(start 334.31734 -46.909736)
						(mid 334.363941 -46.985563)
						(end 334.439768 -47.032164)
					)
					(arc
						(start 334.439768 -47.13732)
						(mid 334.291986 -47.057518)
						(end 334.212184 -46.909736)
					)
				)
			)
		)
		(zone
			(layer "F.Cu")
			(hatch none 0.5)
			(connect_pads
				(clearance 0)
			)
			(min_thickness 0.25)
			(keepout
				(tracks not_allowed)
				(vias allowed)
				(pads allowed)
				(copperpour not_allowed)
				(footprints allowed)
			)
			(placement
				(enabled no)
				(sheetname "")
			)
			(fill
				(thermal_gap 0.5)
				(thermal_bridge_width 0.5)
				(island_removal_mode 0)
			)
			(polygon
				(pts
					(arc
						(start 334.31734 -46.109636)
						(mid 334.363941 -46.185463)
						(end 334.439768 -46.232064)
					)
					(arc
						(start 334.439768 -46.33722)
						(mid 334.291986 -46.257418)
						(end 334.212184 -46.109636)
					)
				)
			)
		)
		(zone
			(layer "F.Cu")
			(hatch none 0.5)
			(connect_pads
				(clearance 0)
			)
			(min_thickness 0.25)
			(keepout
				(tracks not_allowed)
				(vias allowed)
				(pads allowed)
				(copperpour not_allowed)
				(footprints allowed)
			)
			(placement
				(enabled no)
				(sheetname "")
			)
			(fill
				(thermal_gap 0.5)
				(thermal_bridge_width 0.5)
				(island_removal_mode 0)
			)
			(polygon
				(pts
					(arc
						(start 334.31734 -45.309536)
						(mid 334.363941 -45.385363)
						(end 334.439768 -45.431964)
					)
					(arc
						(start 334.439768 -45.53712)
						(mid 334.291986 -45.457318)
						(end 334.212184 -45.309536)
					)
				)
			)
		)
		(zone
			(layer "F.Cu")
			(hatch none 0.5)
			(connect_pads
				(clearance 0)
			)
			(min_thickness 0.25)
			(keepout
				(tracks not_allowed)
				(vias allowed)
				(pads allowed)
				(copperpour not_allowed)
				(footprints allowed)
			)
			(placement
				(enabled no)
				(sheetname "")
			)
			(fill
				(thermal_gap 0.5)
				(thermal_bridge_width 0.5)
				(island_removal_mode 0)
			)
			(polygon
				(pts
					(arc
						(start 334.439768 -51.468528)
						(mid 334.363941 -51.515129)
						(end 334.31734 -51.590956)
					)
					(arc
						(start 334.212184 -51.590956)
						(mid 334.291986 -51.443174)
						(end 334.439768 -51.363372)
					)
				)
			)
		)
		(zone
			(layer "F.Cu")
			(hatch none 0.5)
			(connect_pads
				(clearance 0)
			)
			(min_thickness 0.25)
			(keepout
				(tracks not_allowed)
				(vias allowed)
				(pads allowed)
				(copperpour not_allowed)
				(footprints allowed)
			)
			(placement
				(enabled no)
				(sheetname "")
			)
			(fill
				(thermal_gap 0.5)
				(thermal_bridge_width 0.5)
				(island_removal_mode 0)
			)
			(polygon
				(pts
					(arc
						(start 334.439768 -50.668428)
						(mid 334.363941 -50.715029)
						(end 334.31734 -50.790856)
					)
					(arc
						(start 334.212184 -50.790856)
						(mid 334.291986 -50.643074)
						(end 334.439768 -50.563272)
					)
				)
			)
		)
		(zone
			(layer "F.Cu")
			(hatch none 0.5)
			(connect_pads
				(clearance 0)
			)
			(min_thickness 0.25)
			(keepout
				(tracks not_allowed)
				(vias allowed)
				(pads allowed)
				(copperpour not_allowed)
				(footprints allowed)
			)
			(placement
				(enabled no)
				(sheetname "")
			)
			(fill
				(thermal_gap 0.5)
				(thermal_bridge_width 0.5)
				(island_removal_mode 0)
			)
			(polygon
				(pts
					(arc
						(start 334.439768 -49.868328)
						(mid 334.363941 -49.914929)
						(end 334.31734 -49.990756)
					)
					(arc
						(start 334.212184 -49.990756)
						(mid 334.291986 -49.842974)
						(end 334.439768 -49.763172)
					)
				)
			)
		)
		(zone
			(layer "F.Cu")
			(hatch none 0.5)
			(connect_pads
				(clearance 0)
			)
			(min_thickness 0.25)
			(keepout
				(tracks not_allowed)
				(vias allowed)
				(pads allowed)
				(copperpour not_allowed)
				(footprints allowed)
			)
			(placement
				(enabled no)
				(sheetname "")
			)
			(fill
				(thermal_gap 0.5)
				(thermal_bridge_width 0.5)
				(island_removal_mode 0)
			)
			(polygon
				(pts
					(arc
						(start 334.439768 -49.068228)
						(mid 334.363941 -49.114829)
						(end 334.31734 -49.190656)
					)
					(arc
						(start 334.212184 -49.190656)
						(mid 334.291986 -49.042874)
						(end 334.439768 -48.963072)
					)
				)
			)
		)
		(zone
			(layer "F.Cu")
			(hatch none 0.5)
			(connect_pads
				(clearance 0)
			)
			(min_thickness 0.25)
			(keepout
				(tracks not_allowed)
				(vias allowed)
				(pads allowed)
				(copperpour not_allowed)
				(footprints allowed)
			)
			(placement
				(enabled no)
				(sheetname "")
			)
			(fill
				(thermal_gap 0.5)
				(thermal_bridge_width 0.5)
				(island_removal_mode 0)
			)
			(polygon
				(pts
					(arc
						(start 334.439768 -48.268128)
						(mid 334.363941 -48.314729)
						(end 334.31734 -48.390556)
					)
					(arc
						(start 334.212184 -48.390556)
						(mid 334.291986 -48.242774)
						(end 334.439768 -48.162972)
					)
				)
			)
		)
		(zone
			(layer "F.Cu")
			(hatch none 0.5)
			(connect_pads
				(clearance 0)
			)
			(min_thickness 0.25)
			(keepout
				(tracks not_allowed)
				(vias allowed)
				(pads allowed)
				(copperpour not_allowed)
				(footprints allowed)
			)
			(placement
				(enabled no)
				(sheetname "")
			)
			(fill
				(thermal_gap 0.5)
				(thermal_bridge_width 0.5)
				(island_removal_mode 0)
			)
			(polygon
				(pts
					(arc
						(start 334.439768 -47.468028)
						(mid 334.363941 -47.514629)
						(end 334.31734 -47.590456)
					)
					(arc
						(start 334.212184 -47.590456)
						(mid 334.291986 -47.442674)
						(end 334.439768 -47.362872)
					)
				)
			)
		)
		(zone
			(layer "F.Cu")
			(hatch none 0.5)
			(connect_pads
				(clearance 0)
			)
			(min_thickness 0.25)
			(keepout
				(tracks not_allowed)
				(vias allowed)
				(pads allowed)
				(copperpour not_allowed)
				(footprints allowed)
			)
			(placement
				(enabled no)
				(sheetname "")
			)
			(fill
				(thermal_gap 0.5)
				(thermal_bridge_width 0.5)
				(island_removal_mode 0)
			)
			(polygon
				(pts
					(arc
						(start 334.439768 -46.667928)
						(mid 334.363941 -46.714529)
						(end 334.31734 -46.790356)
					)
					(arc
						(start 334.212184 -46.790356)
						(mid 334.291986 -46.642574)
						(end 334.439768 -46.562772)
					)
				)
			)
		)
		(zone
			(layer "F.Cu")
			(hatch none 0.5)
			(connect_pads
				(clearance 0)
			)
			(min_thickness 0.25)
			(keepout
				(tracks not_allowed)
				(vias allowed)
				(pads allowed)
				(copperpour not_allowed)
				(footprints allowed)
			)
			(placement
				(enabled no)
				(sheetname "")
			)
			(fill
				(thermal_gap 0.5)
				(thermal_bridge_width 0.5)
				(island_removal_mode 0)
			)
			(polygon
				(pts
					(arc
						(start 334.439768 -45.867828)
						(mid 334.363941 -45.914429)
						(end 334.31734 -45.990256)
					)
					(arc
						(start 334.212184 -45.990256)
						(mid 334.291986 -45.842474)
						(end 334.439768 -45.762672)
					)
				)
			)
		)
		(zone
			(layer "F.Cu")
			(hatch none 0.5)
			(connect_pads
				(clearance 0)
			)
			(min_thickness 0.25)
			(keepout
				(tracks not_allowed)
				(vias allowed)
				(pads allowed)
				(copperpour not_allowed)
				(footprints allowed)
			)
			(placement
				(enabled no)
				(sheetname "")
			)
			(fill
				(thermal_gap 0.5)
				(thermal_bridge_width 0.5)
				(island_removal_mode 0)
			)
			(polygon
				(pts
					(arc
						(start 334.439768 -45.067728)
						(mid 334.363941 -45.114329)
						(end 334.31734 -45.190156)
					)
					(arc
						(start 334.212184 -45.190156)
						(mid 334.291986 -45.042374)
						(end 334.439768 -44.962572)
					)
				)
			)
		)
		(zone
			(layer "F.Cu")
			(hatch none 0.5)
			(connect_pads
				(clearance 0)
			)
			(min_thickness 0.25)
			(keepout
				(tracks not_allowed)
				(vias allowed)
				(pads allowed)
				(copperpour not_allowed)
				(footprints allowed)
			)
			(placement
				(enabled no)
				(sheetname "")
			)
			(fill
				(thermal_gap 0.5)
				(thermal_bridge_width 0.5)
				(island_removal_mode 0)
			)
			(polygon
				(pts
					(arc
						(start 334.559148 -51.832764)
						(mid 334.634975 -51.786163)
						(end 334.681576 -51.710336)
					)
					(arc
						(start 334.786732 -51.710336)
						(mid 334.70693 -51.858118)
						(end 334.559148 -51.93792)
					)
				)
			)
		)
		(zone
			(layer "F.Cu")
			(hatch none 0.5)
			(connect_pads
				(clearance 0)
			)
			(min_thickness 0.25)
			(keepout
				(tracks not_allowed)
				(vias allowed)
				(pads allowed)
				(copperpour not_allowed)
				(footprints allowed)
			)
			(placement
				(enabled no)
				(sheetname "")
			)
			(fill
				(thermal_gap 0.5)
				(thermal_bridge_width 0.5)
				(island_removal_mode 0)
			)
			(polygon
				(pts
					(arc
						(start 334.559148 -51.032664)
						(mid 334.634975 -50.986063)
						(end 334.681576 -50.910236)
					)
					(arc
						(start 334.786732 -50.910236)
						(mid 334.70693 -51.058018)
						(end 334.559148 -51.13782)
					)
				)
			)
		)
		(zone
			(layer "F.Cu")
			(hatch none 0.5)
			(connect_pads
				(clearance 0)
			)
			(min_thickness 0.25)
			(keepout
				(tracks not_allowed)
				(vias allowed)
				(pads allowed)
				(copperpour not_allowed)
				(footprints allowed)
			)
			(placement
				(enabled no)
				(sheetname "")
			)
			(fill
				(thermal_gap 0.5)
				(thermal_bridge_width 0.5)
				(island_removal_mode 0)
			)
			(polygon
				(pts
					(arc
						(start 334.559148 -50.232564)
						(mid 334.634975 -50.185963)
						(end 334.681576 -50.110136)
					)
					(arc
						(start 334.786732 -50.110136)
						(mid 334.70693 -50.257918)
						(end 334.559148 -50.33772)
					)
				)
			)
		)
		(zone
			(layer "F.Cu")
			(hatch none 0.5)
			(connect_pads
				(clearance 0)
			)
			(min_thickness 0.25)
			(keepout
				(tracks not_allowed)
				(vias allowed)
				(pads allowed)
				(copperpour not_allowed)
				(footprints allowed)
			)
			(placement
				(enabled no)
				(sheetname "")
			)
			(fill
				(thermal_gap 0.5)
				(thermal_bridge_width 0.5)
				(island_removal_mode 0)
			)
			(polygon
				(pts
					(arc
						(start 334.559148 -49.432464)
						(mid 334.634975 -49.385863)
						(end 334.681576 -49.310036)
					)
					(arc
						(start 334.786732 -49.310036)
						(mid 334.70693 -49.457818)
						(end 334.559148 -49.53762)
					)
				)
			)
		)
		(zone
			(layer "F.Cu")
			(hatch none 0.5)
			(connect_pads
				(clearance 0)
			)
			(min_thickness 0.25)
			(keepout
				(tracks not_allowed)
				(vias allowed)
				(pads allowed)
				(copperpour not_allowed)
				(footprints allowed)
			)
			(placement
				(enabled no)
				(sheetname "")
			)
			(fill
				(thermal_gap 0.5)
				(thermal_bridge_width 0.5)
				(island_removal_mode 0)
			)
			(polygon
				(pts
					(arc
						(start 334.559148 -48.632364)
						(mid 334.634975 -48.585763)
						(end 334.681576 -48.509936)
					)
					(arc
						(start 334.786732 -48.509936)
						(mid 334.70693 -48.657718)
						(end 334.559148 -48.73752)
					)
				)
			)
		)
		(zone
			(layer "F.Cu")
			(hatch none 0.5)
			(connect_pads
				(clearance 0)
			)
			(min_thickness 0.25)
			(keepout
				(tracks not_allowed)
				(vias allowed)
				(pads allowed)
				(copperpour not_allowed)
				(footprints allowed)
			)
			(placement
				(enabled no)
				(sheetname "")
			)
			(fill
				(thermal_gap 0.5)
				(thermal_bridge_width 0.5)
				(island_removal_mode 0)
			)
			(polygon
				(pts
					(arc
						(start 334.559148 -47.832264)
						(mid 334.634975 -47.785663)
						(end 334.681576 -47.709836)
					)
					(arc
						(start 334.786732 -47.709836)
						(mid 334.70693 -47.857618)
						(end 334.559148 -47.93742)
					)
				)
			)
		)
		(zone
			(layer "F.Cu")
			(hatch none 0.5)
			(connect_pads
				(clearance 0)
			)
			(min_thickness 0.25)
			(keepout
				(tracks not_allowed)
				(vias allowed)
				(pads allowed)
				(copperpour not_allowed)
				(footprints allowed)
			)
			(placement
				(enabled no)
				(sheetname "")
			)
			(fill
				(thermal_gap 0.5)
				(thermal_bridge_width 0.5)
				(island_removal_mode 0)
			)
			(polygon
				(pts
					(arc
						(start 334.559148 -47.032164)
						(mid 334.634975 -46.985563)
						(end 334.681576 -46.909736)
					)
					(arc
						(start 334.786732 -46.909736)
						(mid 334.70693 -47.057518)
						(end 334.559148 -47.13732)
					)
				)
			)
		)
		(zone
			(layer "F.Cu")
			(hatch none 0.5)
			(connect_pads
				(clearance 0)
			)
			(min_thickness 0.25)
			(keepout
				(tracks not_allowed)
				(vias allowed)
				(pads allowed)
				(copperpour not_allowed)
				(footprints allowed)
			)
			(placement
				(enabled no)
				(sheetname "")
			)
			(fill
				(thermal_gap 0.5)
				(thermal_bridge_width 0.5)
				(island_removal_mode 0)
			)
			(polygon
				(pts
					(arc
						(start 334.559148 -46.232064)
						(mid 334.634975 -46.185463)
						(end 334.681576 -46.109636)
					)
					(arc
						(start 334.786732 -46.109636)
						(mid 334.70693 -46.257418)
						(end 334.559148 -46.33722)
					)
				)
			)
		)
		(zone
			(layer "F.Cu")
			(hatch none 0.5)
			(connect_pads
				(clearance 0)
			)
			(min_thickness 0.25)
			(keepout
				(tracks not_allowed)
				(vias allowed)
				(pads allowed)
				(copperpour not_allowed)
				(footprints allowed)
			)
			(placement
				(enabled no)
				(sheetname "")
			)
			(fill
				(thermal_gap 0.5)
				(thermal_bridge_width 0.5)
				(island_removal_mode 0)
			)
			(polygon
				(pts
					(arc
						(start 334.559148 -45.431964)
						(mid 334.634975 -45.385363)
						(end 334.681576 -45.309536)
					)
					(arc
						(start 334.786732 -45.309536)
						(mid 334.70693 -45.457318)
						(end 334.559148 -45.53712)
					)
				)
			)
		)
		(zone
			(layer "F.Cu")
			(hatch none 0.5)
			(connect_pads
				(clearance 0)
			)
			(min_thickness 0.25)
			(keepout
				(tracks not_allowed)
				(vias allowed)
				(pads allowed)
				(copperpour not_allowed)
				(footprints allowed)
			)
			(placement
				(enabled no)
				(sheetname "")
			)
			(fill
				(thermal_gap 0.5)
				(thermal_bridge_width 0.5)
				(island_removal_mode 0)
			)
			(polygon
				(pts
					(arc
						(start 334.681576 -51.590956)
						(mid 334.634975 -51.515129)
						(end 334.559148 -51.468528)
					)
					(arc
						(start 334.559148 -51.363372)
						(mid 334.70693 -51.443174)
						(end 334.786732 -51.590956)
					)
				)
			)
		)
		(zone
			(layer "F.Cu")
			(hatch none 0.5)
			(connect_pads
				(clearance 0)
			)
			(min_thickness 0.25)
			(keepout
				(tracks not_allowed)
				(vias allowed)
				(pads allowed)
				(copperpour not_allowed)
				(footprints allowed)
			)
			(placement
				(enabled no)
				(sheetname "")
			)
			(fill
				(thermal_gap 0.5)
				(thermal_bridge_width 0.5)
				(island_removal_mode 0)
			)
			(polygon
				(pts
					(arc
						(start 334.681576 -50.790856)
						(mid 334.634975 -50.715029)
						(end 334.559148 -50.668428)
					)
					(arc
						(start 334.559148 -50.563272)
						(mid 334.70693 -50.643074)
						(end 334.786732 -50.790856)
					)
				)
			)
		)
		(zone
			(layer "F.Cu")
			(hatch none 0.5)
			(connect_pads
				(clearance 0)
			)
			(min_thickness 0.25)
			(keepout
				(tracks not_allowed)
				(vias allowed)
				(pads allowed)
				(copperpour not_allowed)
				(footprints allowed)
			)
			(placement
				(enabled no)
				(sheetname "")
			)
			(fill
				(thermal_gap 0.5)
				(thermal_bridge_width 0.5)
				(island_removal_mode 0)
			)
			(polygon
				(pts
					(arc
						(start 334.681576 -49.990756)
						(mid 334.634975 -49.914929)
						(end 334.559148 -49.868328)
					)
					(arc
						(start 334.559148 -49.763172)
						(mid 334.70693 -49.842974)
						(end 334.786732 -49.990756)
					)
				)
			)
		)
		(zone
			(layer "F.Cu")
			(hatch none 0.5)
			(connect_pads
				(clearance 0)
			)
			(min_thickness 0.25)
			(keepout
				(tracks not_allowed)
				(vias allowed)
				(pads allowed)
				(copperpour not_allowed)
				(footprints allowed)
			)
			(placement
				(enabled no)
				(sheetname "")
			)
			(fill
				(thermal_gap 0.5)
				(thermal_bridge_width 0.5)
				(island_removal_mode 0)
			)
			(polygon
				(pts
					(arc
						(start 334.681576 -49.190656)
						(mid 334.634975 -49.114829)
						(end 334.559148 -49.068228)
					)
					(arc
						(start 334.559148 -48.963072)
						(mid 334.70693 -49.042874)
						(end 334.786732 -49.190656)
					)
				)
			)
		)
		(zone
			(layer "F.Cu")
			(hatch none 0.5)
			(connect_pads
				(clearance 0)
			)
			(min_thickness 0.25)
			(keepout
				(tracks not_allowed)
				(vias allowed)
				(pads allowed)
				(copperpour not_allowed)
				(footprints allowed)
			)
			(placement
				(enabled no)
				(sheetname "")
			)
			(fill
				(thermal_gap 0.5)
				(thermal_bridge_width 0.5)
				(island_removal_mode 0)
			)
			(polygon
				(pts
					(arc
						(start 334.681576 -48.390556)
						(mid 334.634975 -48.314729)
						(end 334.559148 -48.268128)
					)
					(arc
						(start 334.559148 -48.162972)
						(mid 334.70693 -48.242774)
						(end 334.786732 -48.390556)
					)
				)
			)
		)
		(zone
			(layer "F.Cu")
			(hatch none 0.5)
			(connect_pads
				(clearance 0)
			)
			(min_thickness 0.25)
			(keepout
				(tracks not_allowed)
				(vias allowed)
				(pads allowed)
				(copperpour not_allowed)
				(footprints allowed)
			)
			(placement
				(enabled no)
				(sheetname "")
			)
			(fill
				(thermal_gap 0.5)
				(thermal_bridge_width 0.5)
				(island_removal_mode 0)
			)
			(polygon
				(pts
					(arc
						(start 334.681576 -47.590456)
						(mid 334.634975 -47.514629)
						(end 334.559148 -47.468028)
					)
					(arc
						(start 334.559148 -47.362872)
						(mid 334.70693 -47.442674)
						(end 334.786732 -47.590456)
					)
				)
			)
		)
		(zone
			(layer "F.Cu")
			(hatch none 0.5)
			(connect_pads
				(clearance 0)
			)
			(min_thickness 0.25)
			(keepout
				(tracks not_allowed)
				(vias allowed)
				(pads allowed)
				(copperpour not_allowed)
				(footprints allowed)
			)
			(placement
				(enabled no)
				(sheetname "")
			)
			(fill
				(thermal_gap 0.5)
				(thermal_bridge_width 0.5)
				(island_removal_mode 0)
			)
			(polygon
				(pts
					(arc
						(start 334.681576 -46.790356)
						(mid 334.634975 -46.714529)
						(end 334.559148 -46.667928)
					)
					(arc
						(start 334.559148 -46.562772)
						(mid 334.70693 -46.642574)
						(end 334.786732 -46.790356)
					)
				)
			)
		)
		(zone
			(layer "F.Cu")
			(hatch none 0.5)
			(connect_pads
				(clearance 0)
			)
			(min_thickness 0.25)
			(keepout
				(tracks not_allowed)
				(vias allowed)
				(pads allowed)
				(copperpour not_allowed)
				(footprints allowed)
			)
			(placement
				(enabled no)
				(sheetname "")
			)
			(fill
				(thermal_gap 0.5)
				(thermal_bridge_width 0.5)
				(island_removal_mode 0)
			)
			(polygon
				(pts
					(arc
						(start 334.681576 -45.990256)
						(mid 334.634975 -45.914429)
						(end 334.559148 -45.867828)
					)
					(arc
						(start 334.559148 -45.762672)
						(mid 334.70693 -45.842474)
						(end 334.786732 -45.990256)
					)
				)
			)
		)
		(zone
			(layer "F.Cu")
			(hatch none 0.5)
			(connect_pads
				(clearance 0)
			)
			(min_thickness 0.25)
			(keepout
				(tracks not_allowed)
				(vias allowed)
				(pads allowed)
				(copperpour not_allowed)
				(footprints allowed)
			)
			(placement
				(enabled no)
				(sheetname "")
			)
			(fill
				(thermal_gap 0.5)
				(thermal_bridge_width 0.5)
				(island_removal_mode 0)
			)
			(polygon
				(pts
					(arc
						(start 334.681576 -45.190156)
						(mid 334.634975 -45.114329)
						(end 334.559148 -45.067728)
					)
					(arc
						(start 334.559148 -44.962572)
						(mid 334.70693 -45.042374)
						(end 334.786732 -45.190156)
					)
				)
			)
		)
		(zone
			(layer "F.Cu")
			(hatch none 0.5)
			(connect_pads
				(clearance 0)
			)
			(min_thickness 0.25)
			(keepout
				(tracks not_allowed)
				(vias allowed)
				(pads allowed)
				(copperpour not_allowed)
				(footprints allowed)
			)
			(placement
				(enabled no)
				(sheetname "")
			)
			(fill
				(thermal_gap 0.5)
				(thermal_bridge_width 0.5)
				(island_removal_mode 0)
			)
			(polygon
				(pts
					(arc
						(start 334.682338 -56.968136)
						(mid 334.728939 -57.043963)
						(end 334.804766 -57.090564)
					)
					(arc
						(start 334.804766 -57.19572)
						(mid 334.656984 -57.115918)
						(end 334.577182 -56.968136)
					)
				)
			)
		)
		(zone
			(layer "F.Cu")
			(hatch none 0.5)
			(connect_pads
				(clearance 0)
			)
			(min_thickness 0.25)
			(keepout
				(tracks not_allowed)
				(vias allowed)
				(pads allowed)
				(copperpour not_allowed)
				(footprints allowed)
			)
			(placement
				(enabled no)
				(sheetname "")
			)
			(fill
				(thermal_gap 0.5)
				(thermal_bridge_width 0.5)
				(island_removal_mode 0)
			)
			(polygon
				(pts
					(arc
						(start 334.682338 -56.028336)
						(mid 334.728939 -56.104163)
						(end 334.804766 -56.150764)
					)
					(arc
						(start 334.804766 -56.25592)
						(mid 334.656984 -56.176118)
						(end 334.577182 -56.028336)
					)
				)
			)
		)
		(zone
			(layer "F.Cu")
			(hatch none 0.5)
			(connect_pads
				(clearance 0)
			)
			(min_thickness 0.25)
			(keepout
				(tracks not_allowed)
				(vias allowed)
				(pads allowed)
				(copperpour not_allowed)
				(footprints allowed)
			)
			(placement
				(enabled no)
				(sheetname "")
			)
			(fill
				(thermal_gap 0.5)
				(thermal_bridge_width 0.5)
				(island_removal_mode 0)
			)
			(polygon
				(pts
					(arc
						(start 334.682338 -55.088536)
						(mid 334.728939 -55.164363)
						(end 334.804766 -55.210964)
					)
					(arc
						(start 334.804766 -55.31612)
						(mid 334.656984 -55.236318)
						(end 334.577182 -55.088536)
					)
				)
			)
		)
		(zone
			(layer "F.Cu")
			(hatch none 0.5)
			(connect_pads
				(clearance 0)
			)
			(min_thickness 0.25)
			(keepout
				(tracks not_allowed)
				(vias allowed)
				(pads allowed)
				(copperpour not_allowed)
				(footprints allowed)
			)
			(placement
				(enabled no)
				(sheetname "")
			)
			(fill
				(thermal_gap 0.5)
				(thermal_bridge_width 0.5)
				(island_removal_mode 0)
			)
			(polygon
				(pts
					(arc
						(start 334.682338 -54.148736)
						(mid 334.728939 -54.224563)
						(end 334.804766 -54.271164)
					)
					(arc
						(start 334.804766 -54.37632)
						(mid 334.656984 -54.296518)
						(end 334.577182 -54.148736)
					)
				)
			)
		)
		(zone
			(layer "F.Cu")
			(hatch none 0.5)
			(connect_pads
				(clearance 0)
			)
			(min_thickness 0.25)
			(keepout
				(tracks not_allowed)
				(vias allowed)
				(pads allowed)
				(copperpour not_allowed)
				(footprints allowed)
			)
			(placement
				(enabled no)
				(sheetname "")
			)
			(fill
				(thermal_gap 0.5)
				(thermal_bridge_width 0.5)
				(island_removal_mode 0)
			)
			(polygon
				(pts
					(arc
						(start 334.682338 -53.208936)
						(mid 334.728939 -53.284763)
						(end 334.804766 -53.331364)
					)
					(arc
						(start 334.804766 -53.43652)
						(mid 334.656984 -53.356718)
						(end 334.577182 -53.208936)
					)
				)
			)
		)
		(zone
			(layer "F.Cu")
			(hatch none 0.5)
			(connect_pads
				(clearance 0)
			)
			(min_thickness 0.25)
			(keepout
				(tracks not_allowed)
				(vias allowed)
				(pads allowed)
				(copperpour not_allowed)
				(footprints allowed)
			)
			(placement
				(enabled no)
				(sheetname "")
			)
			(fill
				(thermal_gap 0.5)
				(thermal_bridge_width 0.5)
				(island_removal_mode 0)
			)
			(polygon
				(pts
					(arc
						(start 334.682338 -43.810936)
						(mid 334.728939 -43.886763)
						(end 334.804766 -43.933364)
					)
					(arc
						(start 334.804766 -44.03852)
						(mid 334.656984 -43.958718)
						(end 334.577182 -43.810936)
					)
				)
			)
		)
		(zone
			(layer "F.Cu")
			(hatch none 0.5)
			(connect_pads
				(clearance 0)
			)
			(min_thickness 0.25)
			(keepout
				(tracks not_allowed)
				(vias allowed)
				(pads allowed)
				(copperpour not_allowed)
				(footprints allowed)
			)
			(placement
				(enabled no)
				(sheetname "")
			)
			(fill
				(thermal_gap 0.5)
				(thermal_bridge_width 0.5)
				(island_removal_mode 0)
			)
			(polygon
				(pts
					(arc
						(start 334.682338 -42.871136)
						(mid 334.728939 -42.946963)
						(end 334.804766 -42.993564)
					)
					(arc
						(start 334.804766 -43.09872)
						(mid 334.656984 -43.018918)
						(end 334.577182 -42.871136)
					)
				)
			)
		)
		(zone
			(layer "F.Cu")
			(hatch none 0.5)
			(connect_pads
				(clearance 0)
			)
			(min_thickness 0.25)
			(keepout
				(tracks not_allowed)
				(vias allowed)
				(pads allowed)
				(copperpour not_allowed)
				(footprints allowed)
			)
			(placement
				(enabled no)
				(sheetname "")
			)
			(fill
				(thermal_gap 0.5)
				(thermal_bridge_width 0.5)
				(island_removal_mode 0)
			)
			(polygon
				(pts
					(arc
						(start 334.682338 -41.931336)
						(mid 334.728939 -42.007163)
						(end 334.804766 -42.053764)
					)
					(arc
						(start 334.804766 -42.15892)
						(mid 334.656984 -42.079118)
						(end 334.577182 -41.931336)
					)
				)
			)
		)
		(zone
			(layer "F.Cu")
			(hatch none 0.5)
			(connect_pads
				(clearance 0)
			)
			(min_thickness 0.25)
			(keepout
				(tracks not_allowed)
				(vias allowed)
				(pads allowed)
				(copperpour not_allowed)
				(footprints allowed)
			)
			(placement
				(enabled no)
				(sheetname "")
			)
			(fill
				(thermal_gap 0.5)
				(thermal_bridge_width 0.5)
				(island_removal_mode 0)
			)
			(polygon
				(pts
					(arc
						(start 334.682338 -40.991536)
						(mid 334.728939 -41.067363)
						(end 334.804766 -41.113964)
					)
					(arc
						(start 334.804766 -41.21912)
						(mid 334.656984 -41.139318)
						(end 334.577182 -40.991536)
					)
				)
			)
		)
		(zone
			(layer "F.Cu")
			(hatch none 0.5)
			(connect_pads
				(clearance 0)
			)
			(min_thickness 0.25)
			(keepout
				(tracks not_allowed)
				(vias allowed)
				(pads allowed)
				(copperpour not_allowed)
				(footprints allowed)
			)
			(placement
				(enabled no)
				(sheetname "")
			)
			(fill
				(thermal_gap 0.5)
				(thermal_bridge_width 0.5)
				(island_removal_mode 0)
			)
			(polygon
				(pts
					(arc
						(start 334.682338 -40.051736)
						(mid 334.728939 -40.127563)
						(end 334.804766 -40.174164)
					)
					(arc
						(start 334.804766 -40.27932)
						(mid 334.656984 -40.199518)
						(end 334.577182 -40.051736)
					)
				)
			)
		)
		(zone
			(layer "F.Cu")
			(hatch none 0.5)
			(connect_pads
				(clearance 0)
			)
			(min_thickness 0.25)
			(keepout
				(tracks not_allowed)
				(vias allowed)
				(pads allowed)
				(copperpour not_allowed)
				(footprints allowed)
			)
			(placement
				(enabled no)
				(sheetname "")
			)
			(fill
				(thermal_gap 0.5)
				(thermal_bridge_width 0.5)
				(island_removal_mode 0)
			)
			(polygon
				(pts
					(arc
						(start 334.804766 -56.726328)
						(mid 334.728939 -56.772929)
						(end 334.682338 -56.848756)
					)
					(arc
						(start 334.577182 -56.848756)
						(mid 334.656984 -56.700974)
						(end 334.804766 -56.621172)
					)
				)
			)
		)
		(zone
			(layer "F.Cu")
			(hatch none 0.5)
			(connect_pads
				(clearance 0)
			)
			(min_thickness 0.25)
			(keepout
				(tracks not_allowed)
				(vias allowed)
				(pads allowed)
				(copperpour not_allowed)
				(footprints allowed)
			)
			(placement
				(enabled no)
				(sheetname "")
			)
			(fill
				(thermal_gap 0.5)
				(thermal_bridge_width 0.5)
				(island_removal_mode 0)
			)
			(polygon
				(pts
					(arc
						(start 334.804766 -55.786528)
						(mid 334.728939 -55.833129)
						(end 334.682338 -55.908956)
					)
					(arc
						(start 334.577182 -55.908956)
						(mid 334.656984 -55.761174)
						(end 334.804766 -55.681372)
					)
				)
			)
		)
		(zone
			(layer "F.Cu")
			(hatch none 0.5)
			(connect_pads
				(clearance 0)
			)
			(min_thickness 0.25)
			(keepout
				(tracks not_allowed)
				(vias allowed)
				(pads allowed)
				(copperpour not_allowed)
				(footprints allowed)
			)
			(placement
				(enabled no)
				(sheetname "")
			)
			(fill
				(thermal_gap 0.5)
				(thermal_bridge_width 0.5)
				(island_removal_mode 0)
			)
			(polygon
				(pts
					(arc
						(start 334.804766 -54.846728)
						(mid 334.728939 -54.893329)
						(end 334.682338 -54.969156)
					)
					(arc
						(start 334.577182 -54.969156)
						(mid 334.656984 -54.821374)
						(end 334.804766 -54.741572)
					)
				)
			)
		)
		(zone
			(layer "F.Cu")
			(hatch none 0.5)
			(connect_pads
				(clearance 0)
			)
			(min_thickness 0.25)
			(keepout
				(tracks not_allowed)
				(vias allowed)
				(pads allowed)
				(copperpour not_allowed)
				(footprints allowed)
			)
			(placement
				(enabled no)
				(sheetname "")
			)
			(fill
				(thermal_gap 0.5)
				(thermal_bridge_width 0.5)
				(island_removal_mode 0)
			)
			(polygon
				(pts
					(arc
						(start 334.804766 -53.906928)
						(mid 334.728939 -53.953529)
						(end 334.682338 -54.029356)
					)
					(arc
						(start 334.577182 -54.029356)
						(mid 334.656984 -53.881574)
						(end 334.804766 -53.801772)
					)
				)
			)
		)
		(zone
			(layer "F.Cu")
			(hatch none 0.5)
			(connect_pads
				(clearance 0)
			)
			(min_thickness 0.25)
			(keepout
				(tracks not_allowed)
				(vias allowed)
				(pads allowed)
				(copperpour not_allowed)
				(footprints allowed)
			)
			(placement
				(enabled no)
				(sheetname "")
			)
			(fill
				(thermal_gap 0.5)
				(thermal_bridge_width 0.5)
				(island_removal_mode 0)
			)
			(polygon
				(pts
					(arc
						(start 334.804766 -52.967128)
						(mid 334.728939 -53.013729)
						(end 334.682338 -53.089556)
					)
					(arc
						(start 334.577182 -53.089556)
						(mid 334.656984 -52.941774)
						(end 334.804766 -52.861972)
					)
				)
			)
		)
		(zone
			(layer "F.Cu")
			(hatch none 0.5)
			(connect_pads
				(clearance 0)
			)
			(min_thickness 0.25)
			(keepout
				(tracks not_allowed)
				(vias allowed)
				(pads allowed)
				(copperpour not_allowed)
				(footprints allowed)
			)
			(placement
				(enabled no)
				(sheetname "")
			)
			(fill
				(thermal_gap 0.5)
				(thermal_bridge_width 0.5)
				(island_removal_mode 0)
			)
			(polygon
				(pts
					(arc
						(start 334.804766 -43.569128)
						(mid 334.728939 -43.615729)
						(end 334.682338 -43.691556)
					)
					(arc
						(start 334.577182 -43.691556)
						(mid 334.656984 -43.543774)
						(end 334.804766 -43.463972)
					)
				)
			)
		)
		(zone
			(layer "F.Cu")
			(hatch none 0.5)
			(connect_pads
				(clearance 0)
			)
			(min_thickness 0.25)
			(keepout
				(tracks not_allowed)
				(vias allowed)
				(pads allowed)
				(copperpour not_allowed)
				(footprints allowed)
			)
			(placement
				(enabled no)
				(sheetname "")
			)
			(fill
				(thermal_gap 0.5)
				(thermal_bridge_width 0.5)
				(island_removal_mode 0)
			)
			(polygon
				(pts
					(arc
						(start 334.804766 -42.629328)
						(mid 334.728939 -42.675929)
						(end 334.682338 -42.751756)
					)
					(arc
						(start 334.577182 -42.751756)
						(mid 334.656984 -42.603974)
						(end 334.804766 -42.524172)
					)
				)
			)
		)
		(zone
			(layer "F.Cu")
			(hatch none 0.5)
			(connect_pads
				(clearance 0)
			)
			(min_thickness 0.25)
			(keepout
				(tracks not_allowed)
				(vias allowed)
				(pads allowed)
				(copperpour not_allowed)
				(footprints allowed)
			)
			(placement
				(enabled no)
				(sheetname "")
			)
			(fill
				(thermal_gap 0.5)
				(thermal_bridge_width 0.5)
				(island_removal_mode 0)
			)
			(polygon
				(pts
					(arc
						(start 334.804766 -41.689528)
						(mid 334.728939 -41.736129)
						(end 334.682338 -41.811956)
					)
					(arc
						(start 334.577182 -41.811956)
						(mid 334.656984 -41.664174)
						(end 334.804766 -41.584372)
					)
				)
			)
		)
		(zone
			(layer "F.Cu")
			(hatch none 0.5)
			(connect_pads
				(clearance 0)
			)
			(min_thickness 0.25)
			(keepout
				(tracks not_allowed)
				(vias allowed)
				(pads allowed)
				(copperpour not_allowed)
				(footprints allowed)
			)
			(placement
				(enabled no)
				(sheetname "")
			)
			(fill
				(thermal_gap 0.5)
				(thermal_bridge_width 0.5)
				(island_removal_mode 0)
			)
			(polygon
				(pts
					(arc
						(start 334.804766 -40.749728)
						(mid 334.728939 -40.796329)
						(end 334.682338 -40.872156)
					)
					(arc
						(start 334.577182 -40.872156)
						(mid 334.656984 -40.724374)
						(end 334.804766 -40.644572)
					)
				)
			)
		)
		(zone
			(layer "F.Cu")
			(hatch none 0.5)
			(connect_pads
				(clearance 0)
			)
			(min_thickness 0.25)
			(keepout
				(tracks not_allowed)
				(vias allowed)
				(pads allowed)
				(copperpour not_allowed)
				(footprints allowed)
			)
			(placement
				(enabled no)
				(sheetname "")
			)
			(fill
				(thermal_gap 0.5)
				(thermal_bridge_width 0.5)
				(island_removal_mode 0)
			)
			(polygon
				(pts
					(arc
						(start 334.804766 -39.809928)
						(mid 334.728939 -39.856529)
						(end 334.682338 -39.932356)
					)
					(arc
						(start 334.577182 -39.932356)
						(mid 334.656984 -39.784574)
						(end 334.804766 -39.704772)
					)
				)
			)
		)
		(zone
			(layer "F.Cu")
			(hatch none 0.5)
			(connect_pads
				(clearance 0)
			)
			(min_thickness 0.25)
			(keepout
				(tracks not_allowed)
				(vias allowed)
				(pads allowed)
				(copperpour not_allowed)
				(footprints allowed)
			)
			(placement
				(enabled no)
				(sheetname "")
			)
			(fill
				(thermal_gap 0.5)
				(thermal_bridge_width 0.5)
				(island_removal_mode 0)
			)
			(polygon
				(pts
					(arc
						(start 334.924146 -57.090564)
						(mid 334.999973 -57.043963)
						(end 335.046574 -56.968136)
					)
					(arc
						(start 335.151984 -56.968136)
						(mid 335.072094 -57.116006)
						(end 334.924146 -57.19572)
					)
				)
			)
		)
		(zone
			(layer "F.Cu")
			(hatch none 0.5)
			(connect_pads
				(clearance 0)
			)
			(min_thickness 0.25)
			(keepout
				(tracks not_allowed)
				(vias allowed)
				(pads allowed)
				(copperpour not_allowed)
				(footprints allowed)
			)
			(placement
				(enabled no)
				(sheetname "")
			)
			(fill
				(thermal_gap 0.5)
				(thermal_bridge_width 0.5)
				(island_removal_mode 0)
			)
			(polygon
				(pts
					(arc
						(start 334.924146 -56.150764)
						(mid 334.999973 -56.104163)
						(end 335.046574 -56.028336)
					)
					(arc
						(start 335.151984 -56.028336)
						(mid 335.072094 -56.176206)
						(end 334.924146 -56.25592)
					)
				)
			)
		)
		(zone
			(layer "F.Cu")
			(hatch none 0.5)
			(connect_pads
				(clearance 0)
			)
			(min_thickness 0.25)
			(keepout
				(tracks not_allowed)
				(vias allowed)
				(pads allowed)
				(copperpour not_allowed)
				(footprints allowed)
			)
			(placement
				(enabled no)
				(sheetname "")
			)
			(fill
				(thermal_gap 0.5)
				(thermal_bridge_width 0.5)
				(island_removal_mode 0)
			)
			(polygon
				(pts
					(arc
						(start 334.924146 -55.210964)
						(mid 334.999973 -55.164363)
						(end 335.046574 -55.088536)
					)
					(arc
						(start 335.151984 -55.088536)
						(mid 335.072094 -55.236406)
						(end 334.924146 -55.31612)
					)
				)
			)
		)
		(zone
			(layer "F.Cu")
			(hatch none 0.5)
			(connect_pads
				(clearance 0)
			)
			(min_thickness 0.25)
			(keepout
				(tracks not_allowed)
				(vias allowed)
				(pads allowed)
				(copperpour not_allowed)
				(footprints allowed)
			)
			(placement
				(enabled no)
				(sheetname "")
			)
			(fill
				(thermal_gap 0.5)
				(thermal_bridge_width 0.5)
				(island_removal_mode 0)
			)
			(polygon
				(pts
					(arc
						(start 334.924146 -54.271164)
						(mid 334.999973 -54.224563)
						(end 335.046574 -54.148736)
					)
					(arc
						(start 335.151984 -54.148736)
						(mid 335.072094 -54.296606)
						(end 334.924146 -54.37632)
					)
				)
			)
		)
		(zone
			(layer "F.Cu")
			(hatch none 0.5)
			(connect_pads
				(clearance 0)
			)
			(min_thickness 0.25)
			(keepout
				(tracks not_allowed)
				(vias allowed)
				(pads allowed)
				(copperpour not_allowed)
				(footprints allowed)
			)
			(placement
				(enabled no)
				(sheetname "")
			)
			(fill
				(thermal_gap 0.5)
				(thermal_bridge_width 0.5)
				(island_removal_mode 0)
			)
			(polygon
				(pts
					(arc
						(start 334.924146 -53.331364)
						(mid 334.999973 -53.284763)
						(end 335.046574 -53.208936)
					)
					(arc
						(start 335.151984 -53.208936)
						(mid 335.072094 -53.356806)
						(end 334.924146 -53.43652)
					)
				)
			)
		)
		(zone
			(layer "F.Cu")
			(hatch none 0.5)
			(connect_pads
				(clearance 0)
			)
			(min_thickness 0.25)
			(keepout
				(tracks not_allowed)
				(vias allowed)
				(pads allowed)
				(copperpour not_allowed)
				(footprints allowed)
			)
			(placement
				(enabled no)
				(sheetname "")
			)
			(fill
				(thermal_gap 0.5)
				(thermal_bridge_width 0.5)
				(island_removal_mode 0)
			)
			(polygon
				(pts
					(arc
						(start 334.924146 -43.933364)
						(mid 334.999973 -43.886763)
						(end 335.046574 -43.810936)
					)
					(arc
						(start 335.151984 -43.810936)
						(mid 335.072094 -43.958806)
						(end 334.924146 -44.03852)
					)
				)
			)
		)
		(zone
			(layer "F.Cu")
			(hatch none 0.5)
			(connect_pads
				(clearance 0)
			)
			(min_thickness 0.25)
			(keepout
				(tracks not_allowed)
				(vias allowed)
				(pads allowed)
				(copperpour not_allowed)
				(footprints allowed)
			)
			(placement
				(enabled no)
				(sheetname "")
			)
			(fill
				(thermal_gap 0.5)
				(thermal_bridge_width 0.5)
				(island_removal_mode 0)
			)
			(polygon
				(pts
					(arc
						(start 334.924146 -42.993564)
						(mid 334.999973 -42.946963)
						(end 335.046574 -42.871136)
					)
					(arc
						(start 335.151984 -42.871136)
						(mid 335.072094 -43.019006)
						(end 334.924146 -43.09872)
					)
				)
			)
		)
		(zone
			(layer "F.Cu")
			(hatch none 0.5)
			(connect_pads
				(clearance 0)
			)
			(min_thickness 0.25)
			(keepout
				(tracks not_allowed)
				(vias allowed)
				(pads allowed)
				(copperpour not_allowed)
				(footprints allowed)
			)
			(placement
				(enabled no)
				(sheetname "")
			)
			(fill
				(thermal_gap 0.5)
				(thermal_bridge_width 0.5)
				(island_removal_mode 0)
			)
			(polygon
				(pts
					(arc
						(start 334.924146 -42.053764)
						(mid 334.999973 -42.007163)
						(end 335.046574 -41.931336)
					)
					(arc
						(start 335.151984 -41.931336)
						(mid 335.072094 -42.079206)
						(end 334.924146 -42.15892)
					)
				)
			)
		)
		(zone
			(layer "F.Cu")
			(hatch none 0.5)
			(connect_pads
				(clearance 0)
			)
			(min_thickness 0.25)
			(keepout
				(tracks not_allowed)
				(vias allowed)
				(pads allowed)
				(copperpour not_allowed)
				(footprints allowed)
			)
			(placement
				(enabled no)
				(sheetname "")
			)
			(fill
				(thermal_gap 0.5)
				(thermal_bridge_width 0.5)
				(island_removal_mode 0)
			)
			(polygon
				(pts
					(arc
						(start 334.924146 -41.113964)
						(mid 334.999973 -41.067363)
						(end 335.046574 -40.991536)
					)
					(arc
						(start 335.151984 -40.991536)
						(mid 335.072094 -41.139406)
						(end 334.924146 -41.21912)
					)
				)
			)
		)
		(zone
			(layer "F.Cu")
			(hatch none 0.5)
			(connect_pads
				(clearance 0)
			)
			(min_thickness 0.25)
			(keepout
				(tracks not_allowed)
				(vias allowed)
				(pads allowed)
				(copperpour not_allowed)
				(footprints allowed)
			)
			(placement
				(enabled no)
				(sheetname "")
			)
			(fill
				(thermal_gap 0.5)
				(thermal_bridge_width 0.5)
				(island_removal_mode 0)
			)
			(polygon
				(pts
					(arc
						(start 334.924146 -40.174164)
						(mid 334.999973 -40.127563)
						(end 335.046574 -40.051736)
					)
					(arc
						(start 335.151984 -40.051736)
						(mid 335.072094 -40.199606)
						(end 334.924146 -40.27932)
					)
				)
			)
		)
		(zone
			(layer "F.Cu")
			(hatch none 0.5)
			(connect_pads
				(clearance 0)
			)
			(min_thickness 0.25)
			(keepout
				(tracks not_allowed)
				(vias allowed)
				(pads allowed)
				(copperpour not_allowed)
				(footprints allowed)
			)
			(placement
				(enabled no)
				(sheetname "")
			)
			(fill
				(thermal_gap 0.5)
				(thermal_bridge_width 0.5)
				(island_removal_mode 0)
			)
			(polygon
				(pts
					(arc
						(start 335.046574 -56.848756)
						(mid 334.999973 -56.772929)
						(end 334.924146 -56.726328)
					)
					(arc
						(start 334.924146 -56.621172)
						(mid 335.072058 -56.700923)
						(end 335.151984 -56.848756)
					)
				)
			)
		)
		(zone
			(layer "F.Cu")
			(hatch none 0.5)
			(connect_pads
				(clearance 0)
			)
			(min_thickness 0.25)
			(keepout
				(tracks not_allowed)
				(vias allowed)
				(pads allowed)
				(copperpour not_allowed)
				(footprints allowed)
			)
			(placement
				(enabled no)
				(sheetname "")
			)
			(fill
				(thermal_gap 0.5)
				(thermal_bridge_width 0.5)
				(island_removal_mode 0)
			)
			(polygon
				(pts
					(arc
						(start 335.046574 -55.908956)
						(mid 334.999973 -55.833129)
						(end 334.924146 -55.786528)
					)
					(arc
						(start 334.924146 -55.681372)
						(mid 335.072058 -55.761123)
						(end 335.151984 -55.908956)
					)
				)
			)
		)
		(zone
			(layer "F.Cu")
			(hatch none 0.5)
			(connect_pads
				(clearance 0)
			)
			(min_thickness 0.25)
			(keepout
				(tracks not_allowed)
				(vias allowed)
				(pads allowed)
				(copperpour not_allowed)
				(footprints allowed)
			)
			(placement
				(enabled no)
				(sheetname "")
			)
			(fill
				(thermal_gap 0.5)
				(thermal_bridge_width 0.5)
				(island_removal_mode 0)
			)
			(polygon
				(pts
					(arc
						(start 335.046574 -54.969156)
						(mid 334.999973 -54.893329)
						(end 334.924146 -54.846728)
					)
					(arc
						(start 334.924146 -54.741572)
						(mid 335.072058 -54.821323)
						(end 335.151984 -54.969156)
					)
				)
			)
		)
		(zone
			(layer "F.Cu")
			(hatch none 0.5)
			(connect_pads
				(clearance 0)
			)
			(min_thickness 0.25)
			(keepout
				(tracks not_allowed)
				(vias allowed)
				(pads allowed)
				(copperpour not_allowed)
				(footprints allowed)
			)
			(placement
				(enabled no)
				(sheetname "")
			)
			(fill
				(thermal_gap 0.5)
				(thermal_bridge_width 0.5)
				(island_removal_mode 0)
			)
			(polygon
				(pts
					(arc
						(start 335.046574 -54.029356)
						(mid 334.999973 -53.953529)
						(end 334.924146 -53.906928)
					)
					(arc
						(start 334.924146 -53.801772)
						(mid 335.072058 -53.881523)
						(end 335.151984 -54.029356)
					)
				)
			)
		)
		(zone
			(layer "F.Cu")
			(hatch none 0.5)
			(connect_pads
				(clearance 0)
			)
			(min_thickness 0.25)
			(keepout
				(tracks not_allowed)
				(vias allowed)
				(pads allowed)
				(copperpour not_allowed)
				(footprints allowed)
			)
			(placement
				(enabled no)
				(sheetname "")
			)
			(fill
				(thermal_gap 0.5)
				(thermal_bridge_width 0.5)
				(island_removal_mode 0)
			)
			(polygon
				(pts
					(arc
						(start 335.046574 -53.089556)
						(mid 334.999973 -53.013729)
						(end 334.924146 -52.967128)
					)
					(arc
						(start 334.924146 -52.861972)
						(mid 335.072058 -52.941723)
						(end 335.151984 -53.089556)
					)
				)
			)
		)
		(zone
			(layer "F.Cu")
			(hatch none 0.5)
			(connect_pads
				(clearance 0)
			)
			(min_thickness 0.25)
			(keepout
				(tracks not_allowed)
				(vias allowed)
				(pads allowed)
				(copperpour not_allowed)
				(footprints allowed)
			)
			(placement
				(enabled no)
				(sheetname "")
			)
			(fill
				(thermal_gap 0.5)
				(thermal_bridge_width 0.5)
				(island_removal_mode 0)
			)
			(polygon
				(pts
					(arc
						(start 335.046574 -43.691556)
						(mid 334.999973 -43.615729)
						(end 334.924146 -43.569128)
					)
					(arc
						(start 334.924146 -43.463972)
						(mid 335.072058 -43.543723)
						(end 335.151984 -43.691556)
					)
				)
			)
		)
		(zone
			(layer "F.Cu")
			(hatch none 0.5)
			(connect_pads
				(clearance 0)
			)
			(min_thickness 0.25)
			(keepout
				(tracks not_allowed)
				(vias allowed)
				(pads allowed)
				(copperpour not_allowed)
				(footprints allowed)
			)
			(placement
				(enabled no)
				(sheetname "")
			)
			(fill
				(thermal_gap 0.5)
				(thermal_bridge_width 0.5)
				(island_removal_mode 0)
			)
			(polygon
				(pts
					(arc
						(start 335.046574 -42.751756)
						(mid 334.999973 -42.675929)
						(end 334.924146 -42.629328)
					)
					(arc
						(start 334.924146 -42.524172)
						(mid 335.072058 -42.603923)
						(end 335.151984 -42.751756)
					)
				)
			)
		)
		(zone
			(layer "F.Cu")
			(hatch none 0.5)
			(connect_pads
				(clearance 0)
			)
			(min_thickness 0.25)
			(keepout
				(tracks not_allowed)
				(vias allowed)
				(pads allowed)
				(copperpour not_allowed)
				(footprints allowed)
			)
			(placement
				(enabled no)
				(sheetname "")
			)
			(fill
				(thermal_gap 0.5)
				(thermal_bridge_width 0.5)
				(island_removal_mode 0)
			)
			(polygon
				(pts
					(arc
						(start 335.046574 -41.811956)
						(mid 334.999973 -41.736129)
						(end 334.924146 -41.689528)
					)
					(arc
						(start 334.924146 -41.584372)
						(mid 335.072058 -41.664123)
						(end 335.151984 -41.811956)
					)
				)
			)
		)
		(zone
			(layer "F.Cu")
			(hatch none 0.5)
			(connect_pads
				(clearance 0)
			)
			(min_thickness 0.25)
			(keepout
				(tracks not_allowed)
				(vias allowed)
				(pads allowed)
				(copperpour not_allowed)
				(footprints allowed)
			)
			(placement
				(enabled no)
				(sheetname "")
			)
			(fill
				(thermal_gap 0.5)
				(thermal_bridge_width 0.5)
				(island_removal_mode 0)
			)
			(polygon
				(pts
					(arc
						(start 335.046574 -40.872156)
						(mid 334.999973 -40.796329)
						(end 334.924146 -40.749728)
					)
					(arc
						(start 334.924146 -40.644572)
						(mid 335.072058 -40.724323)
						(end 335.151984 -40.872156)
					)
				)
			)
		)
		(zone
			(layer "F.Cu")
			(hatch none 0.5)
			(connect_pads
				(clearance 0)
			)
			(min_thickness 0.25)
			(keepout
				(tracks not_allowed)
				(vias allowed)
				(pads allowed)
				(copperpour not_allowed)
				(footprints allowed)
			)
			(placement
				(enabled no)
				(sheetname "")
			)
			(fill
				(thermal_gap 0.5)
				(thermal_bridge_width 0.5)
				(island_removal_mode 0)
			)
			(polygon
				(pts
					(arc
						(start 335.046574 -39.932356)
						(mid 334.999973 -39.856529)
						(end 334.924146 -39.809928)
					)
					(arc
						(start 334.924146 -39.704772)
						(mid 335.072058 -39.784523)
						(end 335.151984 -39.932356)
					)
				)
			)
		)
		(zone
			(layer "F.Cu")
			(hatch none 0.5)
			(connect_pads
				(clearance 0)
			)
			(min_thickness 0.25)
			(keepout
				(tracks not_allowed)
				(vias allowed)
				(pads allowed)
				(copperpour not_allowed)
				(footprints allowed)
			)
			(placement
				(enabled no)
				(sheetname "")
			)
			(fill
				(thermal_gap 0.5)
				(thermal_bridge_width 0.5)
				(island_removal_mode 0)
			)
			(polygon
				(pts
					(arc
						(start 335.11744 -51.710336)
						(mid 335.164041 -51.786163)
						(end 335.239868 -51.832764)
					)
					(arc
						(start 335.239868 -51.93792)
						(mid 335.092086 -51.858118)
						(end 335.012284 -51.710336)
					)
				)
			)
		)
		(zone
			(layer "F.Cu")
			(hatch none 0.5)
			(connect_pads
				(clearance 0)
			)
			(min_thickness 0.25)
			(keepout
				(tracks not_allowed)
				(vias allowed)
				(pads allowed)
				(copperpour not_allowed)
				(footprints allowed)
			)
			(placement
				(enabled no)
				(sheetname "")
			)
			(fill
				(thermal_gap 0.5)
				(thermal_bridge_width 0.5)
				(island_removal_mode 0)
			)
			(polygon
				(pts
					(arc
						(start 335.11744 -50.910236)
						(mid 335.164041 -50.986063)
						(end 335.239868 -51.032664)
					)
					(arc
						(start 335.239868 -51.13782)
						(mid 335.092086 -51.058018)
						(end 335.012284 -50.910236)
					)
				)
			)
		)
		(zone
			(layer "F.Cu")
			(hatch none 0.5)
			(connect_pads
				(clearance 0)
			)
			(min_thickness 0.25)
			(keepout
				(tracks not_allowed)
				(vias allowed)
				(pads allowed)
				(copperpour not_allowed)
				(footprints allowed)
			)
			(placement
				(enabled no)
				(sheetname "")
			)
			(fill
				(thermal_gap 0.5)
				(thermal_bridge_width 0.5)
				(island_removal_mode 0)
			)
			(polygon
				(pts
					(arc
						(start 335.11744 -50.110136)
						(mid 335.164041 -50.185963)
						(end 335.239868 -50.232564)
					)
					(arc
						(start 335.239868 -50.33772)
						(mid 335.092086 -50.257918)
						(end 335.012284 -50.110136)
					)
				)
			)
		)
		(zone
			(layer "F.Cu")
			(hatch none 0.5)
			(connect_pads
				(clearance 0)
			)
			(min_thickness 0.25)
			(keepout
				(tracks not_allowed)
				(vias allowed)
				(pads allowed)
				(copperpour not_allowed)
				(footprints allowed)
			)
			(placement
				(enabled no)
				(sheetname "")
			)
			(fill
				(thermal_gap 0.5)
				(thermal_bridge_width 0.5)
				(island_removal_mode 0)
			)
			(polygon
				(pts
					(arc
						(start 335.11744 -49.310036)
						(mid 335.164041 -49.385863)
						(end 335.239868 -49.432464)
					)
					(arc
						(start 335.239868 -49.53762)
						(mid 335.092086 -49.457818)
						(end 335.012284 -49.310036)
					)
				)
			)
		)
		(zone
			(layer "F.Cu")
			(hatch none 0.5)
			(connect_pads
				(clearance 0)
			)
			(min_thickness 0.25)
			(keepout
				(tracks not_allowed)
				(vias allowed)
				(pads allowed)
				(copperpour not_allowed)
				(footprints allowed)
			)
			(placement
				(enabled no)
				(sheetname "")
			)
			(fill
				(thermal_gap 0.5)
				(thermal_bridge_width 0.5)
				(island_removal_mode 0)
			)
			(polygon
				(pts
					(arc
						(start 335.11744 -48.509936)
						(mid 335.164041 -48.585763)
						(end 335.239868 -48.632364)
					)
					(arc
						(start 335.239868 -48.73752)
						(mid 335.092086 -48.657718)
						(end 335.012284 -48.509936)
					)
				)
			)
		)
		(zone
			(layer "F.Cu")
			(hatch none 0.5)
			(connect_pads
				(clearance 0)
			)
			(min_thickness 0.25)
			(keepout
				(tracks not_allowed)
				(vias allowed)
				(pads allowed)
				(copperpour not_allowed)
				(footprints allowed)
			)
			(placement
				(enabled no)
				(sheetname "")
			)
			(fill
				(thermal_gap 0.5)
				(thermal_bridge_width 0.5)
				(island_removal_mode 0)
			)
			(polygon
				(pts
					(arc
						(start 335.11744 -47.709836)
						(mid 335.164041 -47.785663)
						(end 335.239868 -47.832264)
					)
					(arc
						(start 335.239868 -47.93742)
						(mid 335.092086 -47.857618)
						(end 335.012284 -47.709836)
					)
				)
			)
		)
		(zone
			(layer "F.Cu")
			(hatch none 0.5)
			(connect_pads
				(clearance 0)
			)
			(min_thickness 0.25)
			(keepout
				(tracks not_allowed)
				(vias allowed)
				(pads allowed)
				(copperpour not_allowed)
				(footprints allowed)
			)
			(placement
				(enabled no)
				(sheetname "")
			)
			(fill
				(thermal_gap 0.5)
				(thermal_bridge_width 0.5)
				(island_removal_mode 0)
			)
			(polygon
				(pts
					(arc
						(start 335.11744 -46.909736)
						(mid 335.164041 -46.985563)
						(end 335.239868 -47.032164)
					)
					(arc
						(start 335.239868 -47.13732)
						(mid 335.092086 -47.057518)
						(end 335.012284 -46.909736)
					)
				)
			)
		)
		(zone
			(layer "F.Cu")
			(hatch none 0.5)
			(connect_pads
				(clearance 0)
			)
			(min_thickness 0.25)
			(keepout
				(tracks not_allowed)
				(vias allowed)
				(pads allowed)
				(copperpour not_allowed)
				(footprints allowed)
			)
			(placement
				(enabled no)
				(sheetname "")
			)
			(fill
				(thermal_gap 0.5)
				(thermal_bridge_width 0.5)
				(island_removal_mode 0)
			)
			(polygon
				(pts
					(arc
						(start 335.11744 -46.109636)
						(mid 335.164041 -46.185463)
						(end 335.239868 -46.232064)
					)
					(arc
						(start 335.239868 -46.33722)
						(mid 335.092086 -46.257418)
						(end 335.012284 -46.109636)
					)
				)
			)
		)
		(zone
			(layer "F.Cu")
			(hatch none 0.5)
			(connect_pads
				(clearance 0)
			)
			(min_thickness 0.25)
			(keepout
				(tracks not_allowed)
				(vias allowed)
				(pads allowed)
				(copperpour not_allowed)
				(footprints allowed)
			)
			(placement
				(enabled no)
				(sheetname "")
			)
			(fill
				(thermal_gap 0.5)
				(thermal_bridge_width 0.5)
				(island_removal_mode 0)
			)
			(polygon
				(pts
					(arc
						(start 335.11744 -45.309536)
						(mid 335.164041 -45.385363)
						(end 335.239868 -45.431964)
					)
					(arc
						(start 335.239868 -45.53712)
						(mid 335.092086 -45.457318)
						(end 335.012284 -45.309536)
					)
				)
			)
		)
		(zone
			(layer "F.Cu")
			(hatch none 0.5)
			(connect_pads
				(clearance 0)
			)
			(min_thickness 0.25)
			(keepout
				(tracks not_allowed)
				(vias allowed)
				(pads allowed)
				(copperpour not_allowed)
				(footprints allowed)
			)
			(placement
				(enabled no)
				(sheetname "")
			)
			(fill
				(thermal_gap 0.5)
				(thermal_bridge_width 0.5)
				(island_removal_mode 0)
			)
			(polygon
				(pts
					(arc
						(start 335.239868 -51.468528)
						(mid 335.164041 -51.515129)
						(end 335.11744 -51.590956)
					)
					(arc
						(start 335.012284 -51.590956)
						(mid 335.092086 -51.443174)
						(end 335.239868 -51.363372)
					)
				)
			)
		)
		(zone
			(layer "F.Cu")
			(hatch none 0.5)
			(connect_pads
				(clearance 0)
			)
			(min_thickness 0.25)
			(keepout
				(tracks not_allowed)
				(vias allowed)
				(pads allowed)
				(copperpour not_allowed)
				(footprints allowed)
			)
			(placement
				(enabled no)
				(sheetname "")
			)
			(fill
				(thermal_gap 0.5)
				(thermal_bridge_width 0.5)
				(island_removal_mode 0)
			)
			(polygon
				(pts
					(arc
						(start 335.239868 -50.668428)
						(mid 335.164041 -50.715029)
						(end 335.11744 -50.790856)
					)
					(arc
						(start 335.012284 -50.790856)
						(mid 335.092086 -50.643074)
						(end 335.239868 -50.563272)
					)
				)
			)
		)
		(zone
			(layer "F.Cu")
			(hatch none 0.5)
			(connect_pads
				(clearance 0)
			)
			(min_thickness 0.25)
			(keepout
				(tracks not_allowed)
				(vias allowed)
				(pads allowed)
				(copperpour not_allowed)
				(footprints allowed)
			)
			(placement
				(enabled no)
				(sheetname "")
			)
			(fill
				(thermal_gap 0.5)
				(thermal_bridge_width 0.5)
				(island_removal_mode 0)
			)
			(polygon
				(pts
					(arc
						(start 335.239868 -49.868328)
						(mid 335.164041 -49.914929)
						(end 335.11744 -49.990756)
					)
					(arc
						(start 335.012284 -49.990756)
						(mid 335.092086 -49.842974)
						(end 335.239868 -49.763172)
					)
				)
			)
		)
		(zone
			(layer "F.Cu")
			(hatch none 0.5)
			(connect_pads
				(clearance 0)
			)
			(min_thickness 0.25)
			(keepout
				(tracks not_allowed)
				(vias allowed)
				(pads allowed)
				(copperpour not_allowed)
				(footprints allowed)
			)
			(placement
				(enabled no)
				(sheetname "")
			)
			(fill
				(thermal_gap 0.5)
				(thermal_bridge_width 0.5)
				(island_removal_mode 0)
			)
			(polygon
				(pts
					(arc
						(start 335.239868 -49.068228)
						(mid 335.164041 -49.114829)
						(end 335.11744 -49.190656)
					)
					(arc
						(start 335.012284 -49.190656)
						(mid 335.092086 -49.042874)
						(end 335.239868 -48.963072)
					)
				)
			)
		)
		(zone
			(layer "F.Cu")
			(hatch none 0.5)
			(connect_pads
				(clearance 0)
			)
			(min_thickness 0.25)
			(keepout
				(tracks not_allowed)
				(vias allowed)
				(pads allowed)
				(copperpour not_allowed)
				(footprints allowed)
			)
			(placement
				(enabled no)
				(sheetname "")
			)
			(fill
				(thermal_gap 0.5)
				(thermal_bridge_width 0.5)
				(island_removal_mode 0)
			)
			(polygon
				(pts
					(arc
						(start 335.239868 -48.268128)
						(mid 335.164041 -48.314729)
						(end 335.11744 -48.390556)
					)
					(arc
						(start 335.012284 -48.390556)
						(mid 335.092086 -48.242774)
						(end 335.239868 -48.162972)
					)
				)
			)
		)
		(zone
			(layer "F.Cu")
			(hatch none 0.5)
			(connect_pads
				(clearance 0)
			)
			(min_thickness 0.25)
			(keepout
				(tracks not_allowed)
				(vias allowed)
				(pads allowed)
				(copperpour not_allowed)
				(footprints allowed)
			)
			(placement
				(enabled no)
				(sheetname "")
			)
			(fill
				(thermal_gap 0.5)
				(thermal_bridge_width 0.5)
				(island_removal_mode 0)
			)
			(polygon
				(pts
					(arc
						(start 335.239868 -47.468028)
						(mid 335.164041 -47.514629)
						(end 335.11744 -47.590456)
					)
					(arc
						(start 335.012284 -47.590456)
						(mid 335.092086 -47.442674)
						(end 335.239868 -47.362872)
					)
				)
			)
		)
		(zone
			(layer "F.Cu")
			(hatch none 0.5)
			(connect_pads
				(clearance 0)
			)
			(min_thickness 0.25)
			(keepout
				(tracks not_allowed)
				(vias allowed)
				(pads allowed)
				(copperpour not_allowed)
				(footprints allowed)
			)
			(placement
				(enabled no)
				(sheetname "")
			)
			(fill
				(thermal_gap 0.5)
				(thermal_bridge_width 0.5)
				(island_removal_mode 0)
			)
			(polygon
				(pts
					(arc
						(start 335.239868 -46.667928)
						(mid 335.164041 -46.714529)
						(end 335.11744 -46.790356)
					)
					(arc
						(start 335.012284 -46.790356)
						(mid 335.092086 -46.642574)
						(end 335.239868 -46.562772)
					)
				)
			)
		)
		(zone
			(layer "F.Cu")
			(hatch none 0.5)
			(connect_pads
				(clearance 0)
			)
			(min_thickness 0.25)
			(keepout
				(tracks not_allowed)
				(vias allowed)
				(pads allowed)
				(copperpour not_allowed)
				(footprints allowed)
			)
			(placement
				(enabled no)
				(sheetname "")
			)
			(fill
				(thermal_gap 0.5)
				(thermal_bridge_width 0.5)
				(island_removal_mode 0)
			)
			(polygon
				(pts
					(arc
						(start 335.239868 -45.867828)
						(mid 335.164041 -45.914429)
						(end 335.11744 -45.990256)
					)
					(arc
						(start 335.012284 -45.990256)
						(mid 335.092086 -45.842474)
						(end 335.239868 -45.762672)
					)
				)
			)
		)
		(zone
			(layer "F.Cu")
			(hatch none 0.5)
			(connect_pads
				(clearance 0)
			)
			(min_thickness 0.25)
			(keepout
				(tracks not_allowed)
				(vias allowed)
				(pads allowed)
				(copperpour not_allowed)
				(footprints allowed)
			)
			(placement
				(enabled no)
				(sheetname "")
			)
			(fill
				(thermal_gap 0.5)
				(thermal_bridge_width 0.5)
				(island_removal_mode 0)
			)
			(polygon
				(pts
					(arc
						(start 335.239868 -45.067728)
						(mid 335.164041 -45.114329)
						(end 335.11744 -45.190156)
					)
					(arc
						(start 335.012284 -45.190156)
						(mid 335.092086 -45.042374)
						(end 335.239868 -44.962572)
					)
				)
			)
		)
		(zone
			(layer "F.Cu")
			(hatch none 0.5)
			(connect_pads
				(clearance 0)
			)
			(min_thickness 0.25)
			(keepout
				(tracks not_allowed)
				(vias allowed)
				(pads allowed)
				(copperpour not_allowed)
				(footprints allowed)
			)
			(placement
				(enabled no)
				(sheetname "")
			)
			(fill
				(thermal_gap 0.5)
				(thermal_bridge_width 0.5)
				(island_removal_mode 0)
			)
			(polygon
				(pts
					(arc
						(start 335.359248 -51.832764)
						(mid 335.435075 -51.786163)
						(end 335.481676 -51.710336)
					)
					(arc
						(start 335.586832 -51.710336)
						(mid 335.50703 -51.858118)
						(end 335.359248 -51.93792)
					)
				)
			)
		)
		(zone
			(layer "F.Cu")
			(hatch none 0.5)
			(connect_pads
				(clearance 0)
			)
			(min_thickness 0.25)
			(keepout
				(tracks not_allowed)
				(vias allowed)
				(pads allowed)
				(copperpour not_allowed)
				(footprints allowed)
			)
			(placement
				(enabled no)
				(sheetname "")
			)
			(fill
				(thermal_gap 0.5)
				(thermal_bridge_width 0.5)
				(island_removal_mode 0)
			)
			(polygon
				(pts
					(arc
						(start 335.359248 -51.032664)
						(mid 335.435075 -50.986063)
						(end 335.481676 -50.910236)
					)
					(arc
						(start 335.586832 -50.910236)
						(mid 335.50703 -51.058018)
						(end 335.359248 -51.13782)
					)
				)
			)
		)
		(zone
			(layer "F.Cu")
			(hatch none 0.5)
			(connect_pads
				(clearance 0)
			)
			(min_thickness 0.25)
			(keepout
				(tracks not_allowed)
				(vias allowed)
				(pads allowed)
				(copperpour not_allowed)
				(footprints allowed)
			)
			(placement
				(enabled no)
				(sheetname "")
			)
			(fill
				(thermal_gap 0.5)
				(thermal_bridge_width 0.5)
				(island_removal_mode 0)
			)
			(polygon
				(pts
					(arc
						(start 335.359248 -50.232564)
						(mid 335.435075 -50.185963)
						(end 335.481676 -50.110136)
					)
					(arc
						(start 335.586832 -50.110136)
						(mid 335.50703 -50.257918)
						(end 335.359248 -50.33772)
					)
				)
			)
		)
		(zone
			(layer "F.Cu")
			(hatch none 0.5)
			(connect_pads
				(clearance 0)
			)
			(min_thickness 0.25)
			(keepout
				(tracks not_allowed)
				(vias allowed)
				(pads allowed)
				(copperpour not_allowed)
				(footprints allowed)
			)
			(placement
				(enabled no)
				(sheetname "")
			)
			(fill
				(thermal_gap 0.5)
				(thermal_bridge_width 0.5)
				(island_removal_mode 0)
			)
			(polygon
				(pts
					(arc
						(start 335.359248 -49.432464)
						(mid 335.435075 -49.385863)
						(end 335.481676 -49.310036)
					)
					(arc
						(start 335.586832 -49.310036)
						(mid 335.50703 -49.457818)
						(end 335.359248 -49.53762)
					)
				)
			)
		)
		(zone
			(layer "F.Cu")
			(hatch none 0.5)
			(connect_pads
				(clearance 0)
			)
			(min_thickness 0.25)
			(keepout
				(tracks not_allowed)
				(vias allowed)
				(pads allowed)
				(copperpour not_allowed)
				(footprints allowed)
			)
			(placement
				(enabled no)
				(sheetname "")
			)
			(fill
				(thermal_gap 0.5)
				(thermal_bridge_width 0.5)
				(island_removal_mode 0)
			)
			(polygon
				(pts
					(arc
						(start 335.359248 -48.632364)
						(mid 335.435075 -48.585763)
						(end 335.481676 -48.509936)
					)
					(arc
						(start 335.586832 -48.509936)
						(mid 335.50703 -48.657718)
						(end 335.359248 -48.73752)
					)
				)
			)
		)
		(zone
			(layer "F.Cu")
			(hatch none 0.5)
			(connect_pads
				(clearance 0)
			)
			(min_thickness 0.25)
			(keepout
				(tracks not_allowed)
				(vias allowed)
				(pads allowed)
				(copperpour not_allowed)
				(footprints allowed)
			)
			(placement
				(enabled no)
				(sheetname "")
			)
			(fill
				(thermal_gap 0.5)
				(thermal_bridge_width 0.5)
				(island_removal_mode 0)
			)
			(polygon
				(pts
					(arc
						(start 335.359248 -47.832264)
						(mid 335.435075 -47.785663)
						(end 335.481676 -47.709836)
					)
					(arc
						(start 335.586832 -47.709836)
						(mid 335.50703 -47.857618)
						(end 335.359248 -47.93742)
					)
				)
			)
		)
		(zone
			(layer "F.Cu")
			(hatch none 0.5)
			(connect_pads
				(clearance 0)
			)
			(min_thickness 0.25)
			(keepout
				(tracks not_allowed)
				(vias allowed)
				(pads allowed)
				(copperpour not_allowed)
				(footprints allowed)
			)
			(placement
				(enabled no)
				(sheetname "")
			)
			(fill
				(thermal_gap 0.5)
				(thermal_bridge_width 0.5)
				(island_removal_mode 0)
			)
			(polygon
				(pts
					(arc
						(start 335.359248 -47.032164)
						(mid 335.435075 -46.985563)
						(end 335.481676 -46.909736)
					)
					(arc
						(start 335.586832 -46.909736)
						(mid 335.50703 -47.057518)
						(end 335.359248 -47.13732)
					)
				)
			)
		)
		(zone
			(layer "F.Cu")
			(hatch none 0.5)
			(connect_pads
				(clearance 0)
			)
			(min_thickness 0.25)
			(keepout
				(tracks not_allowed)
				(vias allowed)
				(pads allowed)
				(copperpour not_allowed)
				(footprints allowed)
			)
			(placement
				(enabled no)
				(sheetname "")
			)
			(fill
				(thermal_gap 0.5)
				(thermal_bridge_width 0.5)
				(island_removal_mode 0)
			)
			(polygon
				(pts
					(arc
						(start 335.359248 -46.232064)
						(mid 335.435075 -46.185463)
						(end 335.481676 -46.109636)
					)
					(arc
						(start 335.586832 -46.109636)
						(mid 335.50703 -46.257418)
						(end 335.359248 -46.33722)
					)
				)
			)
		)
		(zone
			(layer "F.Cu")
			(hatch none 0.5)
			(connect_pads
				(clearance 0)
			)
			(min_thickness 0.25)
			(keepout
				(tracks not_allowed)
				(vias allowed)
				(pads allowed)
				(copperpour not_allowed)
				(footprints allowed)
			)
			(placement
				(enabled no)
				(sheetname "")
			)
			(fill
				(thermal_gap 0.5)
				(thermal_bridge_width 0.5)
				(island_removal_mode 0)
			)
			(polygon
				(pts
					(arc
						(start 335.359248 -45.431964)
						(mid 335.435075 -45.385363)
						(end 335.481676 -45.309536)
					)
					(arc
						(start 335.586832 -45.309536)
						(mid 335.50703 -45.457318)
						(end 335.359248 -45.53712)
					)
				)
			)
		)
		(zone
			(layer "F.Cu")
			(hatch none 0.5)
			(connect_pads
				(clearance 0)
			)
			(min_thickness 0.25)
			(keepout
				(tracks not_allowed)
				(vias allowed)
				(pads allowed)
				(copperpour not_allowed)
				(footprints allowed)
			)
			(placement
				(enabled no)
				(sheetname "")
			)
			(fill
				(thermal_gap 0.5)
				(thermal_bridge_width 0.5)
				(island_removal_mode 0)
			)
			(polygon
				(pts
					(arc
						(start 335.481676 -51.590956)
						(mid 335.435075 -51.515129)
						(end 335.359248 -51.468528)
					)
					(arc
						(start 335.359248 -51.363372)
						(mid 335.50703 -51.443174)
						(end 335.586832 -51.590956)
					)
				)
			)
		)
		(zone
			(layer "F.Cu")
			(hatch none 0.5)
			(connect_pads
				(clearance 0)
			)
			(min_thickness 0.25)
			(keepout
				(tracks not_allowed)
				(vias allowed)
				(pads allowed)
				(copperpour not_allowed)
				(footprints allowed)
			)
			(placement
				(enabled no)
				(sheetname "")
			)
			(fill
				(thermal_gap 0.5)
				(thermal_bridge_width 0.5)
				(island_removal_mode 0)
			)
			(polygon
				(pts
					(arc
						(start 335.481676 -50.790856)
						(mid 335.435075 -50.715029)
						(end 335.359248 -50.668428)
					)
					(arc
						(start 335.359248 -50.563272)
						(mid 335.50703 -50.643074)
						(end 335.586832 -50.790856)
					)
				)
			)
		)
		(zone
			(layer "F.Cu")
			(hatch none 0.5)
			(connect_pads
				(clearance 0)
			)
			(min_thickness 0.25)
			(keepout
				(tracks not_allowed)
				(vias allowed)
				(pads allowed)
				(copperpour not_allowed)
				(footprints allowed)
			)
			(placement
				(enabled no)
				(sheetname "")
			)
			(fill
				(thermal_gap 0.5)
				(thermal_bridge_width 0.5)
				(island_removal_mode 0)
			)
			(polygon
				(pts
					(arc
						(start 335.481676 -49.990756)
						(mid 335.435075 -49.914929)
						(end 335.359248 -49.868328)
					)
					(arc
						(start 335.359248 -49.763172)
						(mid 335.50703 -49.842974)
						(end 335.586832 -49.990756)
					)
				)
			)
		)
		(zone
			(layer "F.Cu")
			(hatch none 0.5)
			(connect_pads
				(clearance 0)
			)
			(min_thickness 0.25)
			(keepout
				(tracks not_allowed)
				(vias allowed)
				(pads allowed)
				(copperpour not_allowed)
				(footprints allowed)
			)
			(placement
				(enabled no)
				(sheetname "")
			)
			(fill
				(thermal_gap 0.5)
				(thermal_bridge_width 0.5)
				(island_removal_mode 0)
			)
			(polygon
				(pts
					(arc
						(start 335.481676 -49.190656)
						(mid 335.435075 -49.114829)
						(end 335.359248 -49.068228)
					)
					(arc
						(start 335.359248 -48.963072)
						(mid 335.50703 -49.042874)
						(end 335.586832 -49.190656)
					)
				)
			)
		)
		(zone
			(layer "F.Cu")
			(hatch none 0.5)
			(connect_pads
				(clearance 0)
			)
			(min_thickness 0.25)
			(keepout
				(tracks not_allowed)
				(vias allowed)
				(pads allowed)
				(copperpour not_allowed)
				(footprints allowed)
			)
			(placement
				(enabled no)
				(sheetname "")
			)
			(fill
				(thermal_gap 0.5)
				(thermal_bridge_width 0.5)
				(island_removal_mode 0)
			)
			(polygon
				(pts
					(arc
						(start 335.481676 -48.390556)
						(mid 335.435075 -48.314729)
						(end 335.359248 -48.268128)
					)
					(arc
						(start 335.359248 -48.162972)
						(mid 335.50703 -48.242774)
						(end 335.586832 -48.390556)
					)
				)
			)
		)
		(zone
			(layer "F.Cu")
			(hatch none 0.5)
			(connect_pads
				(clearance 0)
			)
			(min_thickness 0.25)
			(keepout
				(tracks not_allowed)
				(vias allowed)
				(pads allowed)
				(copperpour not_allowed)
				(footprints allowed)
			)
			(placement
				(enabled no)
				(sheetname "")
			)
			(fill
				(thermal_gap 0.5)
				(thermal_bridge_width 0.5)
				(island_removal_mode 0)
			)
			(polygon
				(pts
					(arc
						(start 335.481676 -47.590456)
						(mid 335.435075 -47.514629)
						(end 335.359248 -47.468028)
					)
					(arc
						(start 335.359248 -47.362872)
						(mid 335.50703 -47.442674)
						(end 335.586832 -47.590456)
					)
				)
			)
		)
		(zone
			(layer "F.Cu")
			(hatch none 0.5)
			(connect_pads
				(clearance 0)
			)
			(min_thickness 0.25)
			(keepout
				(tracks not_allowed)
				(vias allowed)
				(pads allowed)
				(copperpour not_allowed)
				(footprints allowed)
			)
			(placement
				(enabled no)
				(sheetname "")
			)
			(fill
				(thermal_gap 0.5)
				(thermal_bridge_width 0.5)
				(island_removal_mode 0)
			)
			(polygon
				(pts
					(arc
						(start 335.481676 -46.790356)
						(mid 335.435075 -46.714529)
						(end 335.359248 -46.667928)
					)
					(arc
						(start 335.359248 -46.562772)
						(mid 335.50703 -46.642574)
						(end 335.586832 -46.790356)
					)
				)
			)
		)
		(zone
			(layer "F.Cu")
			(hatch none 0.5)
			(connect_pads
				(clearance 0)
			)
			(min_thickness 0.25)
			(keepout
				(tracks not_allowed)
				(vias allowed)
				(pads allowed)
				(copperpour not_allowed)
				(footprints allowed)
			)
			(placement
				(enabled no)
				(sheetname "")
			)
			(fill
				(thermal_gap 0.5)
				(thermal_bridge_width 0.5)
				(island_removal_mode 0)
			)
			(polygon
				(pts
					(arc
						(start 335.481676 -45.990256)
						(mid 335.435075 -45.914429)
						(end 335.359248 -45.867828)
					)
					(arc
						(start 335.359248 -45.762672)
						(mid 335.50703 -45.842474)
						(end 335.586832 -45.990256)
					)
				)
			)
		)
		(zone
			(layer "F.Cu")
			(hatch none 0.5)
			(connect_pads
				(clearance 0)
			)
			(min_thickness 0.25)
			(keepout
				(tracks not_allowed)
				(vias allowed)
				(pads allowed)
				(copperpour not_allowed)
				(footprints allowed)
			)
			(placement
				(enabled no)
				(sheetname "")
			)
			(fill
				(thermal_gap 0.5)
				(thermal_bridge_width 0.5)
				(island_removal_mode 0)
			)
			(polygon
				(pts
					(arc
						(start 335.481676 -45.190156)
						(mid 335.435075 -45.114329)
						(end 335.359248 -45.067728)
					)
					(arc
						(start 335.359248 -44.962572)
						(mid 335.50703 -45.042374)
						(end 335.586832 -45.190156)
					)
				)
			)
		)
		(zone
			(layer "F.Cu")
			(hatch none 0.5)
			(connect_pads
				(clearance 0)
			)
			(min_thickness 0.25)
			(keepout
				(tracks not_allowed)
				(vias allowed)
				(pads allowed)
				(copperpour not_allowed)
				(footprints allowed)
			)
			(placement
				(enabled no)
				(sheetname "")
			)
			(fill
				(thermal_gap 0.5)
				(thermal_bridge_width 0.5)
				(island_removal_mode 0)
			)
			(polygon
				(pts
					(arc
						(start 335.496662 -56.498236)
						(mid 335.543177 -56.573978)
						(end 335.618836 -56.620664)
					)
					(arc
						(start 335.618836 -56.72582)
						(mid 335.471054 -56.646018)
						(end 335.391252 -56.498236)
					)
				)
			)
		)
		(zone
			(layer "F.Cu")
			(hatch none 0.5)
			(connect_pads
				(clearance 0)
			)
			(min_thickness 0.25)
			(keepout
				(tracks not_allowed)
				(vias allowed)
				(pads allowed)
				(copperpour not_allowed)
				(footprints allowed)
			)
			(placement
				(enabled no)
				(sheetname "")
			)
			(fill
				(thermal_gap 0.5)
				(thermal_bridge_width 0.5)
				(island_removal_mode 0)
			)
			(polygon
				(pts
					(arc
						(start 335.496662 -55.558436)
						(mid 335.543177 -55.634178)
						(end 335.618836 -55.680864)
					)
					(arc
						(start 335.618836 -55.78602)
						(mid 335.471054 -55.706218)
						(end 335.391252 -55.558436)
					)
				)
			)
		)
		(zone
			(layer "F.Cu")
			(hatch none 0.5)
			(connect_pads
				(clearance 0)
			)
			(min_thickness 0.25)
			(keepout
				(tracks not_allowed)
				(vias allowed)
				(pads allowed)
				(copperpour not_allowed)
				(footprints allowed)
			)
			(placement
				(enabled no)
				(sheetname "")
			)
			(fill
				(thermal_gap 0.5)
				(thermal_bridge_width 0.5)
				(island_removal_mode 0)
			)
			(polygon
				(pts
					(arc
						(start 335.496662 -54.618636)
						(mid 335.543177 -54.694378)
						(end 335.618836 -54.741064)
					)
					(arc
						(start 335.618836 -54.84622)
						(mid 335.471054 -54.766418)
						(end 335.391252 -54.618636)
					)
				)
			)
		)
		(zone
			(layer "F.Cu")
			(hatch none 0.5)
			(connect_pads
				(clearance 0)
			)
			(min_thickness 0.25)
			(keepout
				(tracks not_allowed)
				(vias allowed)
				(pads allowed)
				(copperpour not_allowed)
				(footprints allowed)
			)
			(placement
				(enabled no)
				(sheetname "")
			)
			(fill
				(thermal_gap 0.5)
				(thermal_bridge_width 0.5)
				(island_removal_mode 0)
			)
			(polygon
				(pts
					(arc
						(start 335.496662 -53.678836)
						(mid 335.543177 -53.754578)
						(end 335.618836 -53.801264)
					)
					(arc
						(start 335.618836 -53.90642)
						(mid 335.471054 -53.826618)
						(end 335.391252 -53.678836)
					)
				)
			)
		)
		(zone
			(layer "F.Cu")
			(hatch none 0.5)
			(connect_pads
				(clearance 0)
			)
			(min_thickness 0.25)
			(keepout
				(tracks not_allowed)
				(vias allowed)
				(pads allowed)
				(copperpour not_allowed)
				(footprints allowed)
			)
			(placement
				(enabled no)
				(sheetname "")
			)
			(fill
				(thermal_gap 0.5)
				(thermal_bridge_width 0.5)
				(island_removal_mode 0)
			)
			(polygon
				(pts
					(arc
						(start 335.496662 -52.739036)
						(mid 335.543177 -52.814778)
						(end 335.618836 -52.861464)
					)
					(arc
						(start 335.618836 -52.96662)
						(mid 335.471054 -52.886818)
						(end 335.391252 -52.739036)
					)
				)
			)
		)
		(zone
			(layer "F.Cu")
			(hatch none 0.5)
			(connect_pads
				(clearance 0)
			)
			(min_thickness 0.25)
			(keepout
				(tracks not_allowed)
				(vias allowed)
				(pads allowed)
				(copperpour not_allowed)
				(footprints allowed)
			)
			(placement
				(enabled no)
				(sheetname "")
			)
			(fill
				(thermal_gap 0.5)
				(thermal_bridge_width 0.5)
				(island_removal_mode 0)
			)
			(polygon
				(pts
					(arc
						(start 335.496662 -44.280836)
						(mid 335.543177 -44.356578)
						(end 335.618836 -44.403264)
					)
					(arc
						(start 335.618836 -44.50842)
						(mid 335.471054 -44.428618)
						(end 335.391252 -44.280836)
					)
				)
			)
		)
		(zone
			(layer "F.Cu")
			(hatch none 0.5)
			(connect_pads
				(clearance 0)
			)
			(min_thickness 0.25)
			(keepout
				(tracks not_allowed)
				(vias allowed)
				(pads allowed)
				(copperpour not_allowed)
				(footprints allowed)
			)
			(placement
				(enabled no)
				(sheetname "")
			)
			(fill
				(thermal_gap 0.5)
				(thermal_bridge_width 0.5)
				(island_removal_mode 0)
			)
			(polygon
				(pts
					(arc
						(start 335.496662 -43.341036)
						(mid 335.543177 -43.416778)
						(end 335.618836 -43.463464)
					)
					(arc
						(start 335.618836 -43.56862)
						(mid 335.471054 -43.488818)
						(end 335.391252 -43.341036)
					)
				)
			)
		)
		(zone
			(layer "F.Cu")
			(hatch none 0.5)
			(connect_pads
				(clearance 0)
			)
			(min_thickness 0.25)
			(keepout
				(tracks not_allowed)
				(vias allowed)
				(pads allowed)
				(copperpour not_allowed)
				(footprints allowed)
			)
			(placement
				(enabled no)
				(sheetname "")
			)
			(fill
				(thermal_gap 0.5)
				(thermal_bridge_width 0.5)
				(island_removal_mode 0)
			)
			(polygon
				(pts
					(arc
						(start 335.496662 -42.401236)
						(mid 335.543177 -42.476978)
						(end 335.618836 -42.523664)
					)
					(arc
						(start 335.618836 -42.62882)
						(mid 335.471054 -42.549018)
						(end 335.391252 -42.401236)
					)
				)
			)
		)
		(zone
			(layer "F.Cu")
			(hatch none 0.5)
			(connect_pads
				(clearance 0)
			)
			(min_thickness 0.25)
			(keepout
				(tracks not_allowed)
				(vias allowed)
				(pads allowed)
				(copperpour not_allowed)
				(footprints allowed)
			)
			(placement
				(enabled no)
				(sheetname "")
			)
			(fill
				(thermal_gap 0.5)
				(thermal_bridge_width 0.5)
				(island_removal_mode 0)
			)
			(polygon
				(pts
					(arc
						(start 335.496662 -41.461436)
						(mid 335.543177 -41.537178)
						(end 335.618836 -41.583864)
					)
					(arc
						(start 335.618836 -41.68902)
						(mid 335.471054 -41.609218)
						(end 335.391252 -41.461436)
					)
				)
			)
		)
		(zone
			(layer "F.Cu")
			(hatch none 0.5)
			(connect_pads
				(clearance 0)
			)
			(min_thickness 0.25)
			(keepout
				(tracks not_allowed)
				(vias allowed)
				(pads allowed)
				(copperpour not_allowed)
				(footprints allowed)
			)
			(placement
				(enabled no)
				(sheetname "")
			)
			(fill
				(thermal_gap 0.5)
				(thermal_bridge_width 0.5)
				(island_removal_mode 0)
			)
			(polygon
				(pts
					(arc
						(start 335.496662 -40.521636)
						(mid 335.543177 -40.597378)
						(end 335.618836 -40.644064)
					)
					(arc
						(start 335.618836 -40.74922)
						(mid 335.471054 -40.669418)
						(end 335.391252 -40.521636)
					)
				)
			)
		)
		(zone
			(layer "F.Cu")
			(hatch none 0.5)
			(connect_pads
				(clearance 0)
			)
			(min_thickness 0.25)
			(keepout
				(tracks not_allowed)
				(vias allowed)
				(pads allowed)
				(copperpour not_allowed)
				(footprints allowed)
			)
			(placement
				(enabled no)
				(sheetname "")
			)
			(fill
				(thermal_gap 0.5)
				(thermal_bridge_width 0.5)
				(island_removal_mode 0)
			)
			(polygon
				(pts
					(arc
						(start 335.618836 -56.256428)
						(mid 335.543121 -56.303058)
						(end 335.496662 -56.378856)
					)
					(arc
						(start 335.391252 -56.378856)
						(mid 335.471054 -56.231074)
						(end 335.618836 -56.151272)
					)
				)
			)
		)
		(zone
			(layer "F.Cu")
			(hatch none 0.5)
			(connect_pads
				(clearance 0)
			)
			(min_thickness 0.25)
			(keepout
				(tracks not_allowed)
				(vias allowed)
				(pads allowed)
				(copperpour not_allowed)
				(footprints allowed)
			)
			(placement
				(enabled no)
				(sheetname "")
			)
			(fill
				(thermal_gap 0.5)
				(thermal_bridge_width 0.5)
				(island_removal_mode 0)
			)
			(polygon
				(pts
					(arc
						(start 335.618836 -55.316628)
						(mid 335.543121 -55.363258)
						(end 335.496662 -55.439056)
					)
					(arc
						(start 335.391252 -55.439056)
						(mid 335.471054 -55.291274)
						(end 335.618836 -55.211472)
					)
				)
			)
		)
		(zone
			(layer "F.Cu")
			(hatch none 0.5)
			(connect_pads
				(clearance 0)
			)
			(min_thickness 0.25)
			(keepout
				(tracks not_allowed)
				(vias allowed)
				(pads allowed)
				(copperpour not_allowed)
				(footprints allowed)
			)
			(placement
				(enabled no)
				(sheetname "")
			)
			(fill
				(thermal_gap 0.5)
				(thermal_bridge_width 0.5)
				(island_removal_mode 0)
			)
			(polygon
				(pts
					(arc
						(start 335.618836 -54.376828)
						(mid 335.543121 -54.423458)
						(end 335.496662 -54.499256)
					)
					(arc
						(start 335.391252 -54.499256)
						(mid 335.471054 -54.351474)
						(end 335.618836 -54.271672)
					)
				)
			)
		)
		(zone
			(layer "F.Cu")
			(hatch none 0.5)
			(connect_pads
				(clearance 0)
			)
			(min_thickness 0.25)
			(keepout
				(tracks not_allowed)
				(vias allowed)
				(pads allowed)
				(copperpour not_allowed)
				(footprints allowed)
			)
			(placement
				(enabled no)
				(sheetname "")
			)
			(fill
				(thermal_gap 0.5)
				(thermal_bridge_width 0.5)
				(island_removal_mode 0)
			)
			(polygon
				(pts
					(arc
						(start 335.618836 -53.437028)
						(mid 335.543121 -53.483658)
						(end 335.496662 -53.559456)
					)
					(arc
						(start 335.391252 -53.559456)
						(mid 335.471054 -53.411674)
						(end 335.618836 -53.331872)
					)
				)
			)
		)
		(zone
			(layer "F.Cu")
			(hatch none 0.5)
			(connect_pads
				(clearance 0)
			)
			(min_thickness 0.25)
			(keepout
				(tracks not_allowed)
				(vias allowed)
				(pads allowed)
				(copperpour not_allowed)
				(footprints allowed)
			)
			(placement
				(enabled no)
				(sheetname "")
			)
			(fill
				(thermal_gap 0.5)
				(thermal_bridge_width 0.5)
				(island_removal_mode 0)
			)
			(polygon
				(pts
					(arc
						(start 335.618836 -52.497228)
						(mid 335.543121 -52.543858)
						(end 335.496662 -52.619656)
					)
					(arc
						(start 335.391252 -52.619656)
						(mid 335.471054 -52.471874)
						(end 335.618836 -52.392072)
					)
				)
			)
		)
		(zone
			(layer "F.Cu")
			(hatch none 0.5)
			(connect_pads
				(clearance 0)
			)
			(min_thickness 0.25)
			(keepout
				(tracks not_allowed)
				(vias allowed)
				(pads allowed)
				(copperpour not_allowed)
				(footprints allowed)
			)
			(placement
				(enabled no)
				(sheetname "")
			)
			(fill
				(thermal_gap 0.5)
				(thermal_bridge_width 0.5)
				(island_removal_mode 0)
			)
			(polygon
				(pts
					(arc
						(start 335.618836 -44.039028)
						(mid 335.543121 -44.085658)
						(end 335.496662 -44.161456)
					)
					(arc
						(start 335.391252 -44.161456)
						(mid 335.471054 -44.013674)
						(end 335.618836 -43.933872)
					)
				)
			)
		)
		(zone
			(layer "F.Cu")
			(hatch none 0.5)
			(connect_pads
				(clearance 0)
			)
			(min_thickness 0.25)
			(keepout
				(tracks not_allowed)
				(vias allowed)
				(pads allowed)
				(copperpour not_allowed)
				(footprints allowed)
			)
			(placement
				(enabled no)
				(sheetname "")
			)
			(fill
				(thermal_gap 0.5)
				(thermal_bridge_width 0.5)
				(island_removal_mode 0)
			)
			(polygon
				(pts
					(arc
						(start 335.618836 -43.099228)
						(mid 335.543121 -43.145858)
						(end 335.496662 -43.221656)
					)
					(arc
						(start 335.391252 -43.221656)
						(mid 335.471054 -43.073874)
						(end 335.618836 -42.994072)
					)
				)
			)
		)
		(zone
			(layer "F.Cu")
			(hatch none 0.5)
			(connect_pads
				(clearance 0)
			)
			(min_thickness 0.25)
			(keepout
				(tracks not_allowed)
				(vias allowed)
				(pads allowed)
				(copperpour not_allowed)
				(footprints allowed)
			)
			(placement
				(enabled no)
				(sheetname "")
			)
			(fill
				(thermal_gap 0.5)
				(thermal_bridge_width 0.5)
				(island_removal_mode 0)
			)
			(polygon
				(pts
					(arc
						(start 335.618836 -42.159428)
						(mid 335.543121 -42.206058)
						(end 335.496662 -42.281856)
					)
					(arc
						(start 335.391252 -42.281856)
						(mid 335.471054 -42.134074)
						(end 335.618836 -42.054272)
					)
				)
			)
		)
		(zone
			(layer "F.Cu")
			(hatch none 0.5)
			(connect_pads
				(clearance 0)
			)
			(min_thickness 0.25)
			(keepout
				(tracks not_allowed)
				(vias allowed)
				(pads allowed)
				(copperpour not_allowed)
				(footprints allowed)
			)
			(placement
				(enabled no)
				(sheetname "")
			)
			(fill
				(thermal_gap 0.5)
				(thermal_bridge_width 0.5)
				(island_removal_mode 0)
			)
			(polygon
				(pts
					(arc
						(start 335.618836 -41.219628)
						(mid 335.543121 -41.266258)
						(end 335.496662 -41.342056)
					)
					(arc
						(start 335.391252 -41.342056)
						(mid 335.471054 -41.194274)
						(end 335.618836 -41.114472)
					)
				)
			)
		)
		(zone
			(layer "F.Cu")
			(hatch none 0.5)
			(connect_pads
				(clearance 0)
			)
			(min_thickness 0.25)
			(keepout
				(tracks not_allowed)
				(vias allowed)
				(pads allowed)
				(copperpour not_allowed)
				(footprints allowed)
			)
			(placement
				(enabled no)
				(sheetname "")
			)
			(fill
				(thermal_gap 0.5)
				(thermal_bridge_width 0.5)
				(island_removal_mode 0)
			)
			(polygon
				(pts
					(arc
						(start 335.618836 -40.279828)
						(mid 335.543121 -40.326458)
						(end 335.496662 -40.402256)
					)
					(arc
						(start 335.391252 -40.402256)
						(mid 335.471054 -40.254474)
						(end 335.618836 -40.174672)
					)
				)
			)
		)
		(zone
			(layer "F.Cu")
			(hatch none 0.5)
			(connect_pads
				(clearance 0)
			)
			(min_thickness 0.25)
			(keepout
				(tracks not_allowed)
				(vias allowed)
				(pads allowed)
				(copperpour not_allowed)
				(footprints allowed)
			)
			(placement
				(enabled no)
				(sheetname "")
			)
			(fill
				(thermal_gap 0.5)
				(thermal_bridge_width 0.5)
				(island_removal_mode 0)
			)
			(polygon
				(pts
					(arc
						(start 335.73847 -56.620664)
						(mid 335.814185 -56.574034)
						(end 335.860644 -56.498236)
					)
					(arc
						(start 335.966054 -56.498236)
						(mid 335.886252 -56.646018)
						(end 335.73847 -56.72582)
					)
				)
			)
		)
		(zone
			(layer "F.Cu")
			(hatch none 0.5)
			(connect_pads
				(clearance 0)
			)
			(min_thickness 0.25)
			(keepout
				(tracks not_allowed)
				(vias allowed)
				(pads allowed)
				(copperpour not_allowed)
				(footprints allowed)
			)
			(placement
				(enabled no)
				(sheetname "")
			)
			(fill
				(thermal_gap 0.5)
				(thermal_bridge_width 0.5)
				(island_removal_mode 0)
			)
			(polygon
				(pts
					(arc
						(start 335.73847 -55.680864)
						(mid 335.814185 -55.634234)
						(end 335.860644 -55.558436)
					)
					(arc
						(start 335.966054 -55.558436)
						(mid 335.886252 -55.706218)
						(end 335.73847 -55.78602)
					)
				)
			)
		)
		(zone
			(layer "F.Cu")
			(hatch none 0.5)
			(connect_pads
				(clearance 0)
			)
			(min_thickness 0.25)
			(keepout
				(tracks not_allowed)
				(vias allowed)
				(pads allowed)
				(copperpour not_allowed)
				(footprints allowed)
			)
			(placement
				(enabled no)
				(sheetname "")
			)
			(fill
				(thermal_gap 0.5)
				(thermal_bridge_width 0.5)
				(island_removal_mode 0)
			)
			(polygon
				(pts
					(arc
						(start 335.73847 -54.741064)
						(mid 335.814185 -54.694434)
						(end 335.860644 -54.618636)
					)
					(arc
						(start 335.966054 -54.618636)
						(mid 335.886252 -54.766418)
						(end 335.73847 -54.84622)
					)
				)
			)
		)
		(zone
			(layer "F.Cu")
			(hatch none 0.5)
			(connect_pads
				(clearance 0)
			)
			(min_thickness 0.25)
			(keepout
				(tracks not_allowed)
				(vias allowed)
				(pads allowed)
				(copperpour not_allowed)
				(footprints allowed)
			)
			(placement
				(enabled no)
				(sheetname "")
			)
			(fill
				(thermal_gap 0.5)
				(thermal_bridge_width 0.5)
				(island_removal_mode 0)
			)
			(polygon
				(pts
					(arc
						(start 335.73847 -53.801264)
						(mid 335.814185 -53.754634)
						(end 335.860644 -53.678836)
					)
					(arc
						(start 335.966054 -53.678836)
						(mid 335.886252 -53.826618)
						(end 335.73847 -53.90642)
					)
				)
			)
		)
		(zone
			(layer "F.Cu")
			(hatch none 0.5)
			(connect_pads
				(clearance 0)
			)
			(min_thickness 0.25)
			(keepout
				(tracks not_allowed)
				(vias allowed)
				(pads allowed)
				(copperpour not_allowed)
				(footprints allowed)
			)
			(placement
				(enabled no)
				(sheetname "")
			)
			(fill
				(thermal_gap 0.5)
				(thermal_bridge_width 0.5)
				(island_removal_mode 0)
			)
			(polygon
				(pts
					(arc
						(start 335.73847 -52.861464)
						(mid 335.814185 -52.814834)
						(end 335.860644 -52.739036)
					)
					(arc
						(start 335.966054 -52.739036)
						(mid 335.886252 -52.886818)
						(end 335.73847 -52.96662)
					)
				)
			)
		)
		(zone
			(layer "F.Cu")
			(hatch none 0.5)
			(connect_pads
				(clearance 0)
			)
			(min_thickness 0.25)
			(keepout
				(tracks not_allowed)
				(vias allowed)
				(pads allowed)
				(copperpour not_allowed)
				(footprints allowed)
			)
			(placement
				(enabled no)
				(sheetname "")
			)
			(fill
				(thermal_gap 0.5)
				(thermal_bridge_width 0.5)
				(island_removal_mode 0)
			)
			(polygon
				(pts
					(arc
						(start 335.73847 -44.403264)
						(mid 335.814185 -44.356634)
						(end 335.860644 -44.280836)
					)
					(arc
						(start 335.966054 -44.280836)
						(mid 335.886252 -44.428618)
						(end 335.73847 -44.50842)
					)
				)
			)
		)
		(zone
			(layer "F.Cu")
			(hatch none 0.5)
			(connect_pads
				(clearance 0)
			)
			(min_thickness 0.25)
			(keepout
				(tracks not_allowed)
				(vias allowed)
				(pads allowed)
				(copperpour not_allowed)
				(footprints allowed)
			)
			(placement
				(enabled no)
				(sheetname "")
			)
			(fill
				(thermal_gap 0.5)
				(thermal_bridge_width 0.5)
				(island_removal_mode 0)
			)
			(polygon
				(pts
					(arc
						(start 335.73847 -43.463464)
						(mid 335.814185 -43.416834)
						(end 335.860644 -43.341036)
					)
					(arc
						(start 335.966054 -43.341036)
						(mid 335.886252 -43.488818)
						(end 335.73847 -43.56862)
					)
				)
			)
		)
		(zone
			(layer "F.Cu")
			(hatch none 0.5)
			(connect_pads
				(clearance 0)
			)
			(min_thickness 0.25)
			(keepout
				(tracks not_allowed)
				(vias allowed)
				(pads allowed)
				(copperpour not_allowed)
				(footprints allowed)
			)
			(placement
				(enabled no)
				(sheetname "")
			)
			(fill
				(thermal_gap 0.5)
				(thermal_bridge_width 0.5)
				(island_removal_mode 0)
			)
			(polygon
				(pts
					(arc
						(start 335.73847 -42.523664)
						(mid 335.814185 -42.477034)
						(end 335.860644 -42.401236)
					)
					(arc
						(start 335.966054 -42.401236)
						(mid 335.886252 -42.549018)
						(end 335.73847 -42.62882)
					)
				)
			)
		)
		(zone
			(layer "F.Cu")
			(hatch none 0.5)
			(connect_pads
				(clearance 0)
			)
			(min_thickness 0.25)
			(keepout
				(tracks not_allowed)
				(vias allowed)
				(pads allowed)
				(copperpour not_allowed)
				(footprints allowed)
			)
			(placement
				(enabled no)
				(sheetname "")
			)
			(fill
				(thermal_gap 0.5)
				(thermal_bridge_width 0.5)
				(island_removal_mode 0)
			)
			(polygon
				(pts
					(arc
						(start 335.73847 -41.583864)
						(mid 335.814185 -41.537234)
						(end 335.860644 -41.461436)
					)
					(arc
						(start 335.966054 -41.461436)
						(mid 335.886252 -41.609218)
						(end 335.73847 -41.68902)
					)
				)
			)
		)
		(zone
			(layer "F.Cu")
			(hatch none 0.5)
			(connect_pads
				(clearance 0)
			)
			(min_thickness 0.25)
			(keepout
				(tracks not_allowed)
				(vias allowed)
				(pads allowed)
				(copperpour not_allowed)
				(footprints allowed)
			)
			(placement
				(enabled no)
				(sheetname "")
			)
			(fill
				(thermal_gap 0.5)
				(thermal_bridge_width 0.5)
				(island_removal_mode 0)
			)
			(polygon
				(pts
					(arc
						(start 335.73847 -40.644064)
						(mid 335.814185 -40.597434)
						(end 335.860644 -40.521636)
					)
					(arc
						(start 335.966054 -40.521636)
						(mid 335.886252 -40.669418)
						(end 335.73847 -40.74922)
					)
				)
			)
		)
		(zone
			(layer "F.Cu")
			(hatch none 0.5)
			(connect_pads
				(clearance 0)
			)
			(min_thickness 0.25)
			(keepout
				(tracks not_allowed)
				(vias allowed)
				(pads allowed)
				(copperpour not_allowed)
				(footprints allowed)
			)
			(placement
				(enabled no)
				(sheetname "")
			)
			(fill
				(thermal_gap 0.5)
				(thermal_bridge_width 0.5)
				(island_removal_mode 0)
			)
			(polygon
				(pts
					(arc
						(start 335.860644 -56.378856)
						(mid 335.814129 -56.303114)
						(end 335.73847 -56.256428)
					)
					(arc
						(start 335.73847 -56.151272)
						(mid 335.886252 -56.231074)
						(end 335.966054 -56.378856)
					)
				)
			)
		)
		(zone
			(layer "F.Cu")
			(hatch none 0.5)
			(connect_pads
				(clearance 0)
			)
			(min_thickness 0.25)
			(keepout
				(tracks not_allowed)
				(vias allowed)
				(pads allowed)
				(copperpour not_allowed)
				(footprints allowed)
			)
			(placement
				(enabled no)
				(sheetname "")
			)
			(fill
				(thermal_gap 0.5)
				(thermal_bridge_width 0.5)
				(island_removal_mode 0)
			)
			(polygon
				(pts
					(arc
						(start 335.860644 -55.439056)
						(mid 335.814129 -55.363314)
						(end 335.73847 -55.316628)
					)
					(arc
						(start 335.73847 -55.211472)
						(mid 335.886252 -55.291274)
						(end 335.966054 -55.439056)
					)
				)
			)
		)
		(zone
			(layer "F.Cu")
			(hatch none 0.5)
			(connect_pads
				(clearance 0)
			)
			(min_thickness 0.25)
			(keepout
				(tracks not_allowed)
				(vias allowed)
				(pads allowed)
				(copperpour not_allowed)
				(footprints allowed)
			)
			(placement
				(enabled no)
				(sheetname "")
			)
			(fill
				(thermal_gap 0.5)
				(thermal_bridge_width 0.5)
				(island_removal_mode 0)
			)
			(polygon
				(pts
					(arc
						(start 335.860644 -54.499256)
						(mid 335.814129 -54.423514)
						(end 335.73847 -54.376828)
					)
					(arc
						(start 335.73847 -54.271672)
						(mid 335.886252 -54.351474)
						(end 335.966054 -54.499256)
					)
				)
			)
		)
		(zone
			(layer "F.Cu")
			(hatch none 0.5)
			(connect_pads
				(clearance 0)
			)
			(min_thickness 0.25)
			(keepout
				(tracks not_allowed)
				(vias allowed)
				(pads allowed)
				(copperpour not_allowed)
				(footprints allowed)
			)
			(placement
				(enabled no)
				(sheetname "")
			)
			(fill
				(thermal_gap 0.5)
				(thermal_bridge_width 0.5)
				(island_removal_mode 0)
			)
			(polygon
				(pts
					(arc
						(start 335.860644 -53.559456)
						(mid 335.814129 -53.483714)
						(end 335.73847 -53.437028)
					)
					(arc
						(start 335.73847 -53.331872)
						(mid 335.886252 -53.411674)
						(end 335.966054 -53.559456)
					)
				)
			)
		)
		(zone
			(layer "F.Cu")
			(hatch none 0.5)
			(connect_pads
				(clearance 0)
			)
			(min_thickness 0.25)
			(keepout
				(tracks not_allowed)
				(vias allowed)
				(pads allowed)
				(copperpour not_allowed)
				(footprints allowed)
			)
			(placement
				(enabled no)
				(sheetname "")
			)
			(fill
				(thermal_gap 0.5)
				(thermal_bridge_width 0.5)
				(island_removal_mode 0)
			)
			(polygon
				(pts
					(arc
						(start 335.860644 -52.619656)
						(mid 335.814129 -52.543914)
						(end 335.73847 -52.497228)
					)
					(arc
						(start 335.73847 -52.392072)
						(mid 335.886252 -52.471874)
						(end 335.966054 -52.619656)
					)
				)
			)
		)
		(zone
			(layer "F.Cu")
			(hatch none 0.5)
			(connect_pads
				(clearance 0)
			)
			(min_thickness 0.25)
			(keepout
				(tracks not_allowed)
				(vias allowed)
				(pads allowed)
				(copperpour not_allowed)
				(footprints allowed)
			)
			(placement
				(enabled no)
				(sheetname "")
			)
			(fill
				(thermal_gap 0.5)
				(thermal_bridge_width 0.5)
				(island_removal_mode 0)
			)
			(polygon
				(pts
					(arc
						(start 335.860644 -44.161456)
						(mid 335.814129 -44.085714)
						(end 335.73847 -44.039028)
					)
					(arc
						(start 335.73847 -43.933872)
						(mid 335.886252 -44.013674)
						(end 335.966054 -44.161456)
					)
				)
			)
		)
		(zone
			(layer "F.Cu")
			(hatch none 0.5)
			(connect_pads
				(clearance 0)
			)
			(min_thickness 0.25)
			(keepout
				(tracks not_allowed)
				(vias allowed)
				(pads allowed)
				(copperpour not_allowed)
				(footprints allowed)
			)
			(placement
				(enabled no)
				(sheetname "")
			)
			(fill
				(thermal_gap 0.5)
				(thermal_bridge_width 0.5)
				(island_removal_mode 0)
			)
			(polygon
				(pts
					(arc
						(start 335.860644 -43.221656)
						(mid 335.814129 -43.145914)
						(end 335.73847 -43.099228)
					)
					(arc
						(start 335.73847 -42.994072)
						(mid 335.886252 -43.073874)
						(end 335.966054 -43.221656)
					)
				)
			)
		)
		(zone
			(layer "F.Cu")
			(hatch none 0.5)
			(connect_pads
				(clearance 0)
			)
			(min_thickness 0.25)
			(keepout
				(tracks not_allowed)
				(vias allowed)
				(pads allowed)
				(copperpour not_allowed)
				(footprints allowed)
			)
			(placement
				(enabled no)
				(sheetname "")
			)
			(fill
				(thermal_gap 0.5)
				(thermal_bridge_width 0.5)
				(island_removal_mode 0)
			)
			(polygon
				(pts
					(arc
						(start 335.860644 -42.281856)
						(mid 335.814129 -42.206114)
						(end 335.73847 -42.159428)
					)
					(arc
						(start 335.73847 -42.054272)
						(mid 335.886252 -42.134074)
						(end 335.966054 -42.281856)
					)
				)
			)
		)
		(zone
			(layer "F.Cu")
			(hatch none 0.5)
			(connect_pads
				(clearance 0)
			)
			(min_thickness 0.25)
			(keepout
				(tracks not_allowed)
				(vias allowed)
				(pads allowed)
				(copperpour not_allowed)
				(footprints allowed)
			)
			(placement
				(enabled no)
				(sheetname "")
			)
			(fill
				(thermal_gap 0.5)
				(thermal_bridge_width 0.5)
				(island_removal_mode 0)
			)
			(polygon
				(pts
					(arc
						(start 335.860644 -41.342056)
						(mid 335.814129 -41.266314)
						(end 335.73847 -41.219628)
					)
					(arc
						(start 335.73847 -41.114472)
						(mid 335.886252 -41.194274)
						(end 335.966054 -41.342056)
					)
				)
			)
		)
		(zone
			(layer "F.Cu")
			(hatch none 0.5)
			(connect_pads
				(clearance 0)
			)
			(min_thickness 0.25)
			(keepout
				(tracks not_allowed)
				(vias allowed)
				(pads allowed)
				(copperpour not_allowed)
				(footprints allowed)
			)
			(placement
				(enabled no)
				(sheetname "")
			)
			(fill
				(thermal_gap 0.5)
				(thermal_bridge_width 0.5)
				(island_removal_mode 0)
			)
			(polygon
				(pts
					(arc
						(start 335.860644 -40.402256)
						(mid 335.814129 -40.326514)
						(end 335.73847 -40.279828)
					)
					(arc
						(start 335.73847 -40.174672)
						(mid 335.886252 -40.254474)
						(end 335.966054 -40.402256)
					)
				)
			)
		)
		(zone
			(layer "F.Cu")
			(hatch none 0.5)
			(connect_pads
				(clearance 0)
			)
			(min_thickness 0.25)
			(keepout
				(tracks not_allowed)
				(vias allowed)
				(pads allowed)
				(copperpour not_allowed)
				(footprints allowed)
			)
			(placement
				(enabled no)
				(sheetname "")
			)
			(fill
				(thermal_gap 0.5)
				(thermal_bridge_width 0.5)
				(island_removal_mode 0)
			)
			(polygon
				(pts
					(arc
						(start 335.91754 -51.710336)
						(mid 335.964141 -51.786163)
						(end 336.039968 -51.832764)
					)
					(arc
						(start 336.039968 -51.93792)
						(mid 335.892186 -51.858118)
						(end 335.812384 -51.710336)
					)
				)
			)
		)
		(zone
			(layer "F.Cu")
			(hatch none 0.5)
			(connect_pads
				(clearance 0)
			)
			(min_thickness 0.25)
			(keepout
				(tracks not_allowed)
				(vias allowed)
				(pads allowed)
				(copperpour not_allowed)
				(footprints allowed)
			)
			(placement
				(enabled no)
				(sheetname "")
			)
			(fill
				(thermal_gap 0.5)
				(thermal_bridge_width 0.5)
				(island_removal_mode 0)
			)
			(polygon
				(pts
					(arc
						(start 335.91754 -50.910236)
						(mid 335.964141 -50.986063)
						(end 336.039968 -51.032664)
					)
					(arc
						(start 336.039968 -51.13782)
						(mid 335.892186 -51.058018)
						(end 335.812384 -50.910236)
					)
				)
			)
		)
		(zone
			(layer "F.Cu")
			(hatch none 0.5)
			(connect_pads
				(clearance 0)
			)
			(min_thickness 0.25)
			(keepout
				(tracks not_allowed)
				(vias allowed)
				(pads allowed)
				(copperpour not_allowed)
				(footprints allowed)
			)
			(placement
				(enabled no)
				(sheetname "")
			)
			(fill
				(thermal_gap 0.5)
				(thermal_bridge_width 0.5)
				(island_removal_mode 0)
			)
			(polygon
				(pts
					(arc
						(start 335.91754 -50.110136)
						(mid 335.964141 -50.185963)
						(end 336.039968 -50.232564)
					)
					(arc
						(start 336.039968 -50.33772)
						(mid 335.892186 -50.257918)
						(end 335.812384 -50.110136)
					)
				)
			)
		)
		(zone
			(layer "F.Cu")
			(hatch none 0.5)
			(connect_pads
				(clearance 0)
			)
			(min_thickness 0.25)
			(keepout
				(tracks not_allowed)
				(vias allowed)
				(pads allowed)
				(copperpour not_allowed)
				(footprints allowed)
			)
			(placement
				(enabled no)
				(sheetname "")
			)
			(fill
				(thermal_gap 0.5)
				(thermal_bridge_width 0.5)
				(island_removal_mode 0)
			)
			(polygon
				(pts
					(arc
						(start 335.91754 -49.310036)
						(mid 335.964141 -49.385863)
						(end 336.039968 -49.432464)
					)
					(arc
						(start 336.039968 -49.53762)
						(mid 335.892186 -49.457818)
						(end 335.812384 -49.310036)
					)
				)
			)
		)
		(zone
			(layer "F.Cu")
			(hatch none 0.5)
			(connect_pads
				(clearance 0)
			)
			(min_thickness 0.25)
			(keepout
				(tracks not_allowed)
				(vias allowed)
				(pads allowed)
				(copperpour not_allowed)
				(footprints allowed)
			)
			(placement
				(enabled no)
				(sheetname "")
			)
			(fill
				(thermal_gap 0.5)
				(thermal_bridge_width 0.5)
				(island_removal_mode 0)
			)
			(polygon
				(pts
					(arc
						(start 335.91754 -48.509936)
						(mid 335.964141 -48.585763)
						(end 336.039968 -48.632364)
					)
					(arc
						(start 336.039968 -48.73752)
						(mid 335.892186 -48.657718)
						(end 335.812384 -48.509936)
					)
				)
			)
		)
		(zone
			(layer "F.Cu")
			(hatch none 0.5)
			(connect_pads
				(clearance 0)
			)
			(min_thickness 0.25)
			(keepout
				(tracks not_allowed)
				(vias allowed)
				(pads allowed)
				(copperpour not_allowed)
				(footprints allowed)
			)
			(placement
				(enabled no)
				(sheetname "")
			)
			(fill
				(thermal_gap 0.5)
				(thermal_bridge_width 0.5)
				(island_removal_mode 0)
			)
			(polygon
				(pts
					(arc
						(start 335.91754 -47.709836)
						(mid 335.964141 -47.785663)
						(end 336.039968 -47.832264)
					)
					(arc
						(start 336.039968 -47.93742)
						(mid 335.892186 -47.857618)
						(end 335.812384 -47.709836)
					)
				)
			)
		)
		(zone
			(layer "F.Cu")
			(hatch none 0.5)
			(connect_pads
				(clearance 0)
			)
			(min_thickness 0.25)
			(keepout
				(tracks not_allowed)
				(vias allowed)
				(pads allowed)
				(copperpour not_allowed)
				(footprints allowed)
			)
			(placement
				(enabled no)
				(sheetname "")
			)
			(fill
				(thermal_gap 0.5)
				(thermal_bridge_width 0.5)
				(island_removal_mode 0)
			)
			(polygon
				(pts
					(arc
						(start 335.91754 -46.909736)
						(mid 335.964141 -46.985563)
						(end 336.039968 -47.032164)
					)
					(arc
						(start 336.039968 -47.13732)
						(mid 335.892186 -47.057518)
						(end 335.812384 -46.909736)
					)
				)
			)
		)
		(zone
			(layer "F.Cu")
			(hatch none 0.5)
			(connect_pads
				(clearance 0)
			)
			(min_thickness 0.25)
			(keepout
				(tracks not_allowed)
				(vias allowed)
				(pads allowed)
				(copperpour not_allowed)
				(footprints allowed)
			)
			(placement
				(enabled no)
				(sheetname "")
			)
			(fill
				(thermal_gap 0.5)
				(thermal_bridge_width 0.5)
				(island_removal_mode 0)
			)
			(polygon
				(pts
					(arc
						(start 335.91754 -46.109636)
						(mid 335.964141 -46.185463)
						(end 336.039968 -46.232064)
					)
					(arc
						(start 336.039968 -46.33722)
						(mid 335.892186 -46.257418)
						(end 335.812384 -46.109636)
					)
				)
			)
		)
		(zone
			(layer "F.Cu")
			(hatch none 0.5)
			(connect_pads
				(clearance 0)
			)
			(min_thickness 0.25)
			(keepout
				(tracks not_allowed)
				(vias allowed)
				(pads allowed)
				(copperpour not_allowed)
				(footprints allowed)
			)
			(placement
				(enabled no)
				(sheetname "")
			)
			(fill
				(thermal_gap 0.5)
				(thermal_bridge_width 0.5)
				(island_removal_mode 0)
			)
			(polygon
				(pts
					(arc
						(start 335.91754 -45.309536)
						(mid 335.964141 -45.385363)
						(end 336.039968 -45.431964)
					)
					(arc
						(start 336.039968 -45.53712)
						(mid 335.892186 -45.457318)
						(end 335.812384 -45.309536)
					)
				)
			)
		)
		(zone
			(layer "F.Cu")
			(hatch none 0.5)
			(connect_pads
				(clearance 0)
			)
			(min_thickness 0.25)
			(keepout
				(tracks not_allowed)
				(vias allowed)
				(pads allowed)
				(copperpour not_allowed)
				(footprints allowed)
			)
			(placement
				(enabled no)
				(sheetname "")
			)
			(fill
				(thermal_gap 0.5)
				(thermal_bridge_width 0.5)
				(island_removal_mode 0)
			)
			(polygon
				(pts
					(arc
						(start 336.039968 -51.468528)
						(mid 335.964141 -51.515129)
						(end 335.91754 -51.590956)
					)
					(arc
						(start 335.812384 -51.590956)
						(mid 335.892186 -51.443174)
						(end 336.039968 -51.363372)
					)
				)
			)
		)
		(zone
			(layer "F.Cu")
			(hatch none 0.5)
			(connect_pads
				(clearance 0)
			)
			(min_thickness 0.25)
			(keepout
				(tracks not_allowed)
				(vias allowed)
				(pads allowed)
				(copperpour not_allowed)
				(footprints allowed)
			)
			(placement
				(enabled no)
				(sheetname "")
			)
			(fill
				(thermal_gap 0.5)
				(thermal_bridge_width 0.5)
				(island_removal_mode 0)
			)
			(polygon
				(pts
					(arc
						(start 336.039968 -50.668428)
						(mid 335.964141 -50.715029)
						(end 335.91754 -50.790856)
					)
					(arc
						(start 335.812384 -50.790856)
						(mid 335.892186 -50.643074)
						(end 336.039968 -50.563272)
					)
				)
			)
		)
		(zone
			(layer "F.Cu")
			(hatch none 0.5)
			(connect_pads
				(clearance 0)
			)
			(min_thickness 0.25)
			(keepout
				(tracks not_allowed)
				(vias allowed)
				(pads allowed)
				(copperpour not_allowed)
				(footprints allowed)
			)
			(placement
				(enabled no)
				(sheetname "")
			)
			(fill
				(thermal_gap 0.5)
				(thermal_bridge_width 0.5)
				(island_removal_mode 0)
			)
			(polygon
				(pts
					(arc
						(start 336.039968 -49.868328)
						(mid 335.964141 -49.914929)
						(end 335.91754 -49.990756)
					)
					(arc
						(start 335.812384 -49.990756)
						(mid 335.892186 -49.842974)
						(end 336.039968 -49.763172)
					)
				)
			)
		)
		(zone
			(layer "F.Cu")
			(hatch none 0.5)
			(connect_pads
				(clearance 0)
			)
			(min_thickness 0.25)
			(keepout
				(tracks not_allowed)
				(vias allowed)
				(pads allowed)
				(copperpour not_allowed)
				(footprints allowed)
			)
			(placement
				(enabled no)
				(sheetname "")
			)
			(fill
				(thermal_gap 0.5)
				(thermal_bridge_width 0.5)
				(island_removal_mode 0)
			)
			(polygon
				(pts
					(arc
						(start 336.039968 -49.068228)
						(mid 335.964141 -49.114829)
						(end 335.91754 -49.190656)
					)
					(arc
						(start 335.812384 -49.190656)
						(mid 335.892186 -49.042874)
						(end 336.039968 -48.963072)
					)
				)
			)
		)
		(zone
			(layer "F.Cu")
			(hatch none 0.5)
			(connect_pads
				(clearance 0)
			)
			(min_thickness 0.25)
			(keepout
				(tracks not_allowed)
				(vias allowed)
				(pads allowed)
				(copperpour not_allowed)
				(footprints allowed)
			)
			(placement
				(enabled no)
				(sheetname "")
			)
			(fill
				(thermal_gap 0.5)
				(thermal_bridge_width 0.5)
				(island_removal_mode 0)
			)
			(polygon
				(pts
					(arc
						(start 336.039968 -48.268128)
						(mid 335.964141 -48.314729)
						(end 335.91754 -48.390556)
					)
					(arc
						(start 335.812384 -48.390556)
						(mid 335.892186 -48.242774)
						(end 336.039968 -48.162972)
					)
				)
			)
		)
		(zone
			(layer "F.Cu")
			(hatch none 0.5)
			(connect_pads
				(clearance 0)
			)
			(min_thickness 0.25)
			(keepout
				(tracks not_allowed)
				(vias allowed)
				(pads allowed)
				(copperpour not_allowed)
				(footprints allowed)
			)
			(placement
				(enabled no)
				(sheetname "")
			)
			(fill
				(thermal_gap 0.5)
				(thermal_bridge_width 0.5)
				(island_removal_mode 0)
			)
			(polygon
				(pts
					(arc
						(start 336.039968 -47.468028)
						(mid 335.964141 -47.514629)
						(end 335.91754 -47.590456)
					)
					(arc
						(start 335.812384 -47.590456)
						(mid 335.892186 -47.442674)
						(end 336.039968 -47.362872)
					)
				)
			)
		)
		(zone
			(layer "F.Cu")
			(hatch none 0.5)
			(connect_pads
				(clearance 0)
			)
			(min_thickness 0.25)
			(keepout
				(tracks not_allowed)
				(vias allowed)
				(pads allowed)
				(copperpour not_allowed)
				(footprints allowed)
			)
			(placement
				(enabled no)
				(sheetname "")
			)
			(fill
				(thermal_gap 0.5)
				(thermal_bridge_width 0.5)
				(island_removal_mode 0)
			)
			(polygon
				(pts
					(arc
						(start 336.039968 -46.667928)
						(mid 335.964141 -46.714529)
						(end 335.91754 -46.790356)
					)
					(arc
						(start 335.812384 -46.790356)
						(mid 335.892186 -46.642574)
						(end 336.039968 -46.562772)
					)
				)
			)
		)
		(zone
			(layer "F.Cu")
			(hatch none 0.5)
			(connect_pads
				(clearance 0)
			)
			(min_thickness 0.25)
			(keepout
				(tracks not_allowed)
				(vias allowed)
				(pads allowed)
				(copperpour not_allowed)
				(footprints allowed)
			)
			(placement
				(enabled no)
				(sheetname "")
			)
			(fill
				(thermal_gap 0.5)
				(thermal_bridge_width 0.5)
				(island_removal_mode 0)
			)
			(polygon
				(pts
					(arc
						(start 336.039968 -45.867828)
						(mid 335.964141 -45.914429)
						(end 335.91754 -45.990256)
					)
					(arc
						(start 335.812384 -45.990256)
						(mid 335.892186 -45.842474)
						(end 336.039968 -45.762672)
					)
				)
			)
		)
		(zone
			(layer "F.Cu")
			(hatch none 0.5)
			(connect_pads
				(clearance 0)
			)
			(min_thickness 0.25)
			(keepout
				(tracks not_allowed)
				(vias allowed)
				(pads allowed)
				(copperpour not_allowed)
				(footprints allowed)
			)
			(placement
				(enabled no)
				(sheetname "")
			)
			(fill
				(thermal_gap 0.5)
				(thermal_bridge_width 0.5)
				(island_removal_mode 0)
			)
			(polygon
				(pts
					(arc
						(start 336.039968 -45.067728)
						(mid 335.964141 -45.114329)
						(end 335.91754 -45.190156)
					)
					(arc
						(start 335.812384 -45.190156)
						(mid 335.892186 -45.042374)
						(end 336.039968 -44.962572)
					)
				)
			)
		)
		(zone
			(layer "F.Cu")
			(hatch none 0.5)
			(connect_pads
				(clearance 0)
			)
			(min_thickness 0.25)
			(keepout
				(tracks not_allowed)
				(vias allowed)
				(pads allowed)
				(copperpour not_allowed)
				(footprints allowed)
			)
			(placement
				(enabled no)
				(sheetname "")
			)
			(fill
				(thermal_gap 0.5)
				(thermal_bridge_width 0.5)
				(island_removal_mode 0)
			)
			(polygon
				(pts
					(arc
						(start 336.159348 -51.832764)
						(mid 336.235175 -51.786163)
						(end 336.281776 -51.710336)
					)
					(arc
						(start 336.386932 -51.710336)
						(mid 336.30713 -51.858118)
						(end 336.159348 -51.93792)
					)
				)
			)
		)
		(zone
			(layer "F.Cu")
			(hatch none 0.5)
			(connect_pads
				(clearance 0)
			)
			(min_thickness 0.25)
			(keepout
				(tracks not_allowed)
				(vias allowed)
				(pads allowed)
				(copperpour not_allowed)
				(footprints allowed)
			)
			(placement
				(enabled no)
				(sheetname "")
			)
			(fill
				(thermal_gap 0.5)
				(thermal_bridge_width 0.5)
				(island_removal_mode 0)
			)
			(polygon
				(pts
					(arc
						(start 336.159348 -51.032664)
						(mid 336.235175 -50.986063)
						(end 336.281776 -50.910236)
					)
					(arc
						(start 336.386932 -50.910236)
						(mid 336.30713 -51.058018)
						(end 336.159348 -51.13782)
					)
				)
			)
		)
		(zone
			(layer "F.Cu")
			(hatch none 0.5)
			(connect_pads
				(clearance 0)
			)
			(min_thickness 0.25)
			(keepout
				(tracks not_allowed)
				(vias allowed)
				(pads allowed)
				(copperpour not_allowed)
				(footprints allowed)
			)
			(placement
				(enabled no)
				(sheetname "")
			)
			(fill
				(thermal_gap 0.5)
				(thermal_bridge_width 0.5)
				(island_removal_mode 0)
			)
			(polygon
				(pts
					(arc
						(start 336.159348 -50.232564)
						(mid 336.235175 -50.185963)
						(end 336.281776 -50.110136)
					)
					(arc
						(start 336.386932 -50.110136)
						(mid 336.30713 -50.257918)
						(end 336.159348 -50.33772)
					)
				)
			)
		)
		(zone
			(layer "F.Cu")
			(hatch none 0.5)
			(connect_pads
				(clearance 0)
			)
			(min_thickness 0.25)
			(keepout
				(tracks not_allowed)
				(vias allowed)
				(pads allowed)
				(copperpour not_allowed)
				(footprints allowed)
			)
			(placement
				(enabled no)
				(sheetname "")
			)
			(fill
				(thermal_gap 0.5)
				(thermal_bridge_width 0.5)
				(island_removal_mode 0)
			)
			(polygon
				(pts
					(arc
						(start 336.159348 -49.432464)
						(mid 336.235175 -49.385863)
						(end 336.281776 -49.310036)
					)
					(arc
						(start 336.386932 -49.310036)
						(mid 336.30713 -49.457818)
						(end 336.159348 -49.53762)
					)
				)
			)
		)
		(zone
			(layer "F.Cu")
			(hatch none 0.5)
			(connect_pads
				(clearance 0)
			)
			(min_thickness 0.25)
			(keepout
				(tracks not_allowed)
				(vias allowed)
				(pads allowed)
				(copperpour not_allowed)
				(footprints allowed)
			)
			(placement
				(enabled no)
				(sheetname "")
			)
			(fill
				(thermal_gap 0.5)
				(thermal_bridge_width 0.5)
				(island_removal_mode 0)
			)
			(polygon
				(pts
					(arc
						(start 336.159348 -48.632364)
						(mid 336.235175 -48.585763)
						(end 336.281776 -48.509936)
					)
					(arc
						(start 336.386932 -48.509936)
						(mid 336.30713 -48.657718)
						(end 336.159348 -48.73752)
					)
				)
			)
		)
		(zone
			(layer "F.Cu")
			(hatch none 0.5)
			(connect_pads
				(clearance 0)
			)
			(min_thickness 0.25)
			(keepout
				(tracks not_allowed)
				(vias allowed)
				(pads allowed)
				(copperpour not_allowed)
				(footprints allowed)
			)
			(placement
				(enabled no)
				(sheetname "")
			)
			(fill
				(thermal_gap 0.5)
				(thermal_bridge_width 0.5)
				(island_removal_mode 0)
			)
			(polygon
				(pts
					(arc
						(start 336.159348 -47.832264)
						(mid 336.235175 -47.785663)
						(end 336.281776 -47.709836)
					)
					(arc
						(start 336.386932 -47.709836)
						(mid 336.30713 -47.857618)
						(end 336.159348 -47.93742)
					)
				)
			)
		)
		(zone
			(layer "F.Cu")
			(hatch none 0.5)
			(connect_pads
				(clearance 0)
			)
			(min_thickness 0.25)
			(keepout
				(tracks not_allowed)
				(vias allowed)
				(pads allowed)
				(copperpour not_allowed)
				(footprints allowed)
			)
			(placement
				(enabled no)
				(sheetname "")
			)
			(fill
				(thermal_gap 0.5)
				(thermal_bridge_width 0.5)
				(island_removal_mode 0)
			)
			(polygon
				(pts
					(arc
						(start 336.159348 -47.032164)
						(mid 336.235175 -46.985563)
						(end 336.281776 -46.909736)
					)
					(arc
						(start 336.386932 -46.909736)
						(mid 336.30713 -47.057518)
						(end 336.159348 -47.13732)
					)
				)
			)
		)
		(zone
			(layer "F.Cu")
			(hatch none 0.5)
			(connect_pads
				(clearance 0)
			)
			(min_thickness 0.25)
			(keepout
				(tracks not_allowed)
				(vias allowed)
				(pads allowed)
				(copperpour not_allowed)
				(footprints allowed)
			)
			(placement
				(enabled no)
				(sheetname "")
			)
			(fill
				(thermal_gap 0.5)
				(thermal_bridge_width 0.5)
				(island_removal_mode 0)
			)
			(polygon
				(pts
					(arc
						(start 336.159348 -46.232064)
						(mid 336.235175 -46.185463)
						(end 336.281776 -46.109636)
					)
					(arc
						(start 336.386932 -46.109636)
						(mid 336.30713 -46.257418)
						(end 336.159348 -46.33722)
					)
				)
			)
		)
		(zone
			(layer "F.Cu")
			(hatch none 0.5)
			(connect_pads
				(clearance 0)
			)
			(min_thickness 0.25)
			(keepout
				(tracks not_allowed)
				(vias allowed)
				(pads allowed)
				(copperpour not_allowed)
				(footprints allowed)
			)
			(placement
				(enabled no)
				(sheetname "")
			)
			(fill
				(thermal_gap 0.5)
				(thermal_bridge_width 0.5)
				(island_removal_mode 0)
			)
			(polygon
				(pts
					(arc
						(start 336.159348 -45.431964)
						(mid 336.235175 -45.385363)
						(end 336.281776 -45.309536)
					)
					(arc
						(start 336.386932 -45.309536)
						(mid 336.30713 -45.457318)
						(end 336.159348 -45.53712)
					)
				)
			)
		)
		(zone
			(layer "F.Cu")
			(hatch none 0.5)
			(connect_pads
				(clearance 0)
			)
			(min_thickness 0.25)
			(keepout
				(tracks not_allowed)
				(vias allowed)
				(pads allowed)
				(copperpour not_allowed)
				(footprints allowed)
			)
			(placement
				(enabled no)
				(sheetname "")
			)
			(fill
				(thermal_gap 0.5)
				(thermal_bridge_width 0.5)
				(island_removal_mode 0)
			)
			(polygon
				(pts
					(arc
						(start 336.281776 -51.590956)
						(mid 336.235175 -51.515129)
						(end 336.159348 -51.468528)
					)
					(arc
						(start 336.159348 -51.363372)
						(mid 336.30713 -51.443174)
						(end 336.386932 -51.590956)
					)
				)
			)
		)
		(zone
			(layer "F.Cu")
			(hatch none 0.5)
			(connect_pads
				(clearance 0)
			)
			(min_thickness 0.25)
			(keepout
				(tracks not_allowed)
				(vias allowed)
				(pads allowed)
				(copperpour not_allowed)
				(footprints allowed)
			)
			(placement
				(enabled no)
				(sheetname "")
			)
			(fill
				(thermal_gap 0.5)
				(thermal_bridge_width 0.5)
				(island_removal_mode 0)
			)
			(polygon
				(pts
					(arc
						(start 336.281776 -50.790856)
						(mid 336.235175 -50.715029)
						(end 336.159348 -50.668428)
					)
					(arc
						(start 336.159348 -50.563272)
						(mid 336.30713 -50.643074)
						(end 336.386932 -50.790856)
					)
				)
			)
		)
		(zone
			(layer "F.Cu")
			(hatch none 0.5)
			(connect_pads
				(clearance 0)
			)
			(min_thickness 0.25)
			(keepout
				(tracks not_allowed)
				(vias allowed)
				(pads allowed)
				(copperpour not_allowed)
				(footprints allowed)
			)
			(placement
				(enabled no)
				(sheetname "")
			)
			(fill
				(thermal_gap 0.5)
				(thermal_bridge_width 0.5)
				(island_removal_mode 0)
			)
			(polygon
				(pts
					(arc
						(start 336.281776 -49.990756)
						(mid 336.235175 -49.914929)
						(end 336.159348 -49.868328)
					)
					(arc
						(start 336.159348 -49.763172)
						(mid 336.30713 -49.842974)
						(end 336.386932 -49.990756)
					)
				)
			)
		)
		(zone
			(layer "F.Cu")
			(hatch none 0.5)
			(connect_pads
				(clearance 0)
			)
			(min_thickness 0.25)
			(keepout
				(tracks not_allowed)
				(vias allowed)
				(pads allowed)
				(copperpour not_allowed)
				(footprints allowed)
			)
			(placement
				(enabled no)
				(sheetname "")
			)
			(fill
				(thermal_gap 0.5)
				(thermal_bridge_width 0.5)
				(island_removal_mode 0)
			)
			(polygon
				(pts
					(arc
						(start 336.281776 -49.190656)
						(mid 336.235175 -49.114829)
						(end 336.159348 -49.068228)
					)
					(arc
						(start 336.159348 -48.963072)
						(mid 336.30713 -49.042874)
						(end 336.386932 -49.190656)
					)
				)
			)
		)
		(zone
			(layer "F.Cu")
			(hatch none 0.5)
			(connect_pads
				(clearance 0)
			)
			(min_thickness 0.25)
			(keepout
				(tracks not_allowed)
				(vias allowed)
				(pads allowed)
				(copperpour not_allowed)
				(footprints allowed)
			)
			(placement
				(enabled no)
				(sheetname "")
			)
			(fill
				(thermal_gap 0.5)
				(thermal_bridge_width 0.5)
				(island_removal_mode 0)
			)
			(polygon
				(pts
					(arc
						(start 336.281776 -48.390556)
						(mid 336.235175 -48.314729)
						(end 336.159348 -48.268128)
					)
					(arc
						(start 336.159348 -48.162972)
						(mid 336.30713 -48.242774)
						(end 336.386932 -48.390556)
					)
				)
			)
		)
		(zone
			(layer "F.Cu")
			(hatch none 0.5)
			(connect_pads
				(clearance 0)
			)
			(min_thickness 0.25)
			(keepout
				(tracks not_allowed)
				(vias allowed)
				(pads allowed)
				(copperpour not_allowed)
				(footprints allowed)
			)
			(placement
				(enabled no)
				(sheetname "")
			)
			(fill
				(thermal_gap 0.5)
				(thermal_bridge_width 0.5)
				(island_removal_mode 0)
			)
			(polygon
				(pts
					(arc
						(start 336.281776 -47.590456)
						(mid 336.235175 -47.514629)
						(end 336.159348 -47.468028)
					)
					(arc
						(start 336.159348 -47.362872)
						(mid 336.30713 -47.442674)
						(end 336.386932 -47.590456)
					)
				)
			)
		)
		(zone
			(layer "F.Cu")
			(hatch none 0.5)
			(connect_pads
				(clearance 0)
			)
			(min_thickness 0.25)
			(keepout
				(tracks not_allowed)
				(vias allowed)
				(pads allowed)
				(copperpour not_allowed)
				(footprints allowed)
			)
			(placement
				(enabled no)
				(sheetname "")
			)
			(fill
				(thermal_gap 0.5)
				(thermal_bridge_width 0.5)
				(island_removal_mode 0)
			)
			(polygon
				(pts
					(arc
						(start 336.281776 -46.790356)
						(mid 336.235175 -46.714529)
						(end 336.159348 -46.667928)
					)
					(arc
						(start 336.159348 -46.562772)
						(mid 336.30713 -46.642574)
						(end 336.386932 -46.790356)
					)
				)
			)
		)
		(zone
			(layer "F.Cu")
			(hatch none 0.5)
			(connect_pads
				(clearance 0)
			)
			(min_thickness 0.25)
			(keepout
				(tracks not_allowed)
				(vias allowed)
				(pads allowed)
				(copperpour not_allowed)
				(footprints allowed)
			)
			(placement
				(enabled no)
				(sheetname "")
			)
			(fill
				(thermal_gap 0.5)
				(thermal_bridge_width 0.5)
				(island_removal_mode 0)
			)
			(polygon
				(pts
					(arc
						(start 336.281776 -45.990256)
						(mid 336.235175 -45.914429)
						(end 336.159348 -45.867828)
					)
					(arc
						(start 336.159348 -45.762672)
						(mid 336.30713 -45.842474)
						(end 336.386932 -45.990256)
					)
				)
			)
		)
		(zone
			(layer "F.Cu")
			(hatch none 0.5)
			(connect_pads
				(clearance 0)
			)
			(min_thickness 0.25)
			(keepout
				(tracks not_allowed)
				(vias allowed)
				(pads allowed)
				(copperpour not_allowed)
				(footprints allowed)
			)
			(placement
				(enabled no)
				(sheetname "")
			)
			(fill
				(thermal_gap 0.5)
				(thermal_bridge_width 0.5)
				(island_removal_mode 0)
			)
			(polygon
				(pts
					(arc
						(start 336.281776 -45.190156)
						(mid 336.235175 -45.114329)
						(end 336.159348 -45.067728)
					)
					(arc
						(start 336.159348 -44.962572)
						(mid 336.30713 -45.042374)
						(end 336.386932 -45.190156)
					)
				)
			)
		)
		(zone
			(layer "F.Cu")
			(hatch none 0.5)
			(connect_pads
				(clearance 0)
			)
			(min_thickness 0.25)
			(keepout
				(tracks not_allowed)
				(vias allowed)
				(pads allowed)
				(copperpour not_allowed)
				(footprints allowed)
			)
			(placement
				(enabled no)
				(sheetname "")
			)
			(fill
				(thermal_gap 0.5)
				(thermal_bridge_width 0.5)
				(island_removal_mode 0)
			)
			(polygon
				(pts
					(arc
						(start 336.310478 -43.810936)
						(mid 336.357079 -43.886763)
						(end 336.432906 -43.933364)
					)
					(arc
						(start 336.432906 -44.03852)
						(mid 336.285124 -43.958718)
						(end 336.205322 -43.810936)
					)
				)
			)
		)
		(zone
			(layer "F.Cu")
			(hatch none 0.5)
			(connect_pads
				(clearance 0)
			)
			(min_thickness 0.25)
			(keepout
				(tracks not_allowed)
				(vias allowed)
				(pads allowed)
				(copperpour not_allowed)
				(footprints allowed)
			)
			(placement
				(enabled no)
				(sheetname "")
			)
			(fill
				(thermal_gap 0.5)
				(thermal_bridge_width 0.5)
				(island_removal_mode 0)
			)
			(polygon
				(pts
					(arc
						(start 336.310478 -42.871136)
						(mid 336.357079 -42.946963)
						(end 336.432906 -42.993564)
					)
					(arc
						(start 336.432906 -43.09872)
						(mid 336.285124 -43.018918)
						(end 336.205322 -42.871136)
					)
				)
			)
		)
		(zone
			(layer "F.Cu")
			(hatch none 0.5)
			(connect_pads
				(clearance 0)
			)
			(min_thickness 0.25)
			(keepout
				(tracks not_allowed)
				(vias allowed)
				(pads allowed)
				(copperpour not_allowed)
				(footprints allowed)
			)
			(placement
				(enabled no)
				(sheetname "")
			)
			(fill
				(thermal_gap 0.5)
				(thermal_bridge_width 0.5)
				(island_removal_mode 0)
			)
			(polygon
				(pts
					(arc
						(start 336.310478 -41.931336)
						(mid 336.357079 -42.007163)
						(end 336.432906 -42.053764)
					)
					(arc
						(start 336.432906 -42.15892)
						(mid 336.285124 -42.079118)
						(end 336.205322 -41.931336)
					)
				)
			)
		)
		(zone
			(layer "F.Cu")
			(hatch none 0.5)
			(connect_pads
				(clearance 0)
			)
			(min_thickness 0.25)
			(keepout
				(tracks not_allowed)
				(vias allowed)
				(pads allowed)
				(copperpour not_allowed)
				(footprints allowed)
			)
			(placement
				(enabled no)
				(sheetname "")
			)
			(fill
				(thermal_gap 0.5)
				(thermal_bridge_width 0.5)
				(island_removal_mode 0)
			)
			(polygon
				(pts
					(arc
						(start 336.310478 -40.991536)
						(mid 336.357079 -41.067363)
						(end 336.432906 -41.113964)
					)
					(arc
						(start 336.432906 -41.21912)
						(mid 336.285124 -41.139318)
						(end 336.205322 -40.991536)
					)
				)
			)
		)
		(zone
			(layer "F.Cu")
			(hatch none 0.5)
			(connect_pads
				(clearance 0)
			)
			(min_thickness 0.25)
			(keepout
				(tracks not_allowed)
				(vias allowed)
				(pads allowed)
				(copperpour not_allowed)
				(footprints allowed)
			)
			(placement
				(enabled no)
				(sheetname "")
			)
			(fill
				(thermal_gap 0.5)
				(thermal_bridge_width 0.5)
				(island_removal_mode 0)
			)
			(polygon
				(pts
					(arc
						(start 336.310478 -40.051736)
						(mid 336.357079 -40.127563)
						(end 336.432906 -40.174164)
					)
					(arc
						(start 336.432906 -40.27932)
						(mid 336.285124 -40.199518)
						(end 336.205322 -40.051736)
					)
				)
			)
		)
		(zone
			(layer "F.Cu")
			(hatch none 0.5)
			(connect_pads
				(clearance 0)
			)
			(min_thickness 0.25)
			(keepout
				(tracks not_allowed)
				(vias allowed)
				(pads allowed)
				(copperpour not_allowed)
				(footprints allowed)
			)
			(placement
				(enabled no)
				(sheetname "")
			)
			(fill
				(thermal_gap 0.5)
				(thermal_bridge_width 0.5)
				(island_removal_mode 0)
			)
			(polygon
				(pts
					(arc
						(start 336.310732 -56.968136)
						(mid 336.357333 -57.043963)
						(end 336.43316 -57.090564)
					)
					(arc
						(start 336.43316 -57.19572)
						(mid 336.285378 -57.115918)
						(end 336.205576 -56.968136)
					)
				)
			)
		)
		(zone
			(layer "F.Cu")
			(hatch none 0.5)
			(connect_pads
				(clearance 0)
			)
			(min_thickness 0.25)
			(keepout
				(tracks not_allowed)
				(vias allowed)
				(pads allowed)
				(copperpour not_allowed)
				(footprints allowed)
			)
			(placement
				(enabled no)
				(sheetname "")
			)
			(fill
				(thermal_gap 0.5)
				(thermal_bridge_width 0.5)
				(island_removal_mode 0)
			)
			(polygon
				(pts
					(arc
						(start 336.310732 -56.028336)
						(mid 336.357333 -56.104163)
						(end 336.43316 -56.150764)
					)
					(arc
						(start 336.43316 -56.25592)
						(mid 336.285378 -56.176118)
						(end 336.205576 -56.028336)
					)
				)
			)
		)
		(zone
			(layer "F.Cu")
			(hatch none 0.5)
			(connect_pads
				(clearance 0)
			)
			(min_thickness 0.25)
			(keepout
				(tracks not_allowed)
				(vias allowed)
				(pads allowed)
				(copperpour not_allowed)
				(footprints allowed)
			)
			(placement
				(enabled no)
				(sheetname "")
			)
			(fill
				(thermal_gap 0.5)
				(thermal_bridge_width 0.5)
				(island_removal_mode 0)
			)
			(polygon
				(pts
					(arc
						(start 336.310732 -55.088536)
						(mid 336.357333 -55.164363)
						(end 336.43316 -55.210964)
					)
					(arc
						(start 336.43316 -55.31612)
						(mid 336.285378 -55.236318)
						(end 336.205576 -55.088536)
					)
				)
			)
		)
		(zone
			(layer "F.Cu")
			(hatch none 0.5)
			(connect_pads
				(clearance 0)
			)
			(min_thickness 0.25)
			(keepout
				(tracks not_allowed)
				(vias allowed)
				(pads allowed)
				(copperpour not_allowed)
				(footprints allowed)
			)
			(placement
				(enabled no)
				(sheetname "")
			)
			(fill
				(thermal_gap 0.5)
				(thermal_bridge_width 0.5)
				(island_removal_mode 0)
			)
			(polygon
				(pts
					(arc
						(start 336.310732 -54.148736)
						(mid 336.357333 -54.224563)
						(end 336.43316 -54.271164)
					)
					(arc
						(start 336.43316 -54.37632)
						(mid 336.285378 -54.296518)
						(end 336.205576 -54.148736)
					)
				)
			)
		)
		(zone
			(layer "F.Cu")
			(hatch none 0.5)
			(connect_pads
				(clearance 0)
			)
			(min_thickness 0.25)
			(keepout
				(tracks not_allowed)
				(vias allowed)
				(pads allowed)
				(copperpour not_allowed)
				(footprints allowed)
			)
			(placement
				(enabled no)
				(sheetname "")
			)
			(fill
				(thermal_gap 0.5)
				(thermal_bridge_width 0.5)
				(island_removal_mode 0)
			)
			(polygon
				(pts
					(arc
						(start 336.310732 -53.208936)
						(mid 336.357333 -53.284763)
						(end 336.43316 -53.331364)
					)
					(arc
						(start 336.43316 -53.43652)
						(mid 336.285378 -53.356718)
						(end 336.205576 -53.208936)
					)
				)
			)
		)
		(zone
			(layer "F.Cu")
			(hatch none 0.5)
			(connect_pads
				(clearance 0)
			)
			(min_thickness 0.25)
			(keepout
				(tracks not_allowed)
				(vias allowed)
				(pads allowed)
				(copperpour not_allowed)
				(footprints allowed)
			)
			(placement
				(enabled no)
				(sheetname "")
			)
			(fill
				(thermal_gap 0.5)
				(thermal_bridge_width 0.5)
				(island_removal_mode 0)
			)
			(polygon
				(pts
					(arc
						(start 336.432906 -43.569128)
						(mid 336.357079 -43.615729)
						(end 336.310478 -43.691556)
					)
					(arc
						(start 336.205322 -43.691556)
						(mid 336.285124 -43.543774)
						(end 336.432906 -43.463972)
					)
				)
			)
		)
		(zone
			(layer "F.Cu")
			(hatch none 0.5)
			(connect_pads
				(clearance 0)
			)
			(min_thickness 0.25)
			(keepout
				(tracks not_allowed)
				(vias allowed)
				(pads allowed)
				(copperpour not_allowed)
				(footprints allowed)
			)
			(placement
				(enabled no)
				(sheetname "")
			)
			(fill
				(thermal_gap 0.5)
				(thermal_bridge_width 0.5)
				(island_removal_mode 0)
			)
			(polygon
				(pts
					(arc
						(start 336.432906 -42.629328)
						(mid 336.357079 -42.675929)
						(end 336.310478 -42.751756)
					)
					(arc
						(start 336.205322 -42.751756)
						(mid 336.285124 -42.603974)
						(end 336.432906 -42.524172)
					)
				)
			)
		)
		(zone
			(layer "F.Cu")
			(hatch none 0.5)
			(connect_pads
				(clearance 0)
			)
			(min_thickness 0.25)
			(keepout
				(tracks not_allowed)
				(vias allowed)
				(pads allowed)
				(copperpour not_allowed)
				(footprints allowed)
			)
			(placement
				(enabled no)
				(sheetname "")
			)
			(fill
				(thermal_gap 0.5)
				(thermal_bridge_width 0.5)
				(island_removal_mode 0)
			)
			(polygon
				(pts
					(arc
						(start 336.432906 -41.689528)
						(mid 336.357079 -41.736129)
						(end 336.310478 -41.811956)
					)
					(arc
						(start 336.205322 -41.811956)
						(mid 336.285124 -41.664174)
						(end 336.432906 -41.584372)
					)
				)
			)
		)
		(zone
			(layer "F.Cu")
			(hatch none 0.5)
			(connect_pads
				(clearance 0)
			)
			(min_thickness 0.25)
			(keepout
				(tracks not_allowed)
				(vias allowed)
				(pads allowed)
				(copperpour not_allowed)
				(footprints allowed)
			)
			(placement
				(enabled no)
				(sheetname "")
			)
			(fill
				(thermal_gap 0.5)
				(thermal_bridge_width 0.5)
				(island_removal_mode 0)
			)
			(polygon
				(pts
					(arc
						(start 336.432906 -40.749728)
						(mid 336.357079 -40.796329)
						(end 336.310478 -40.872156)
					)
					(arc
						(start 336.205322 -40.872156)
						(mid 336.285124 -40.724374)
						(end 336.432906 -40.644572)
					)
				)
			)
		)
		(zone
			(layer "F.Cu")
			(hatch none 0.5)
			(connect_pads
				(clearance 0)
			)
			(min_thickness 0.25)
			(keepout
				(tracks not_allowed)
				(vias allowed)
				(pads allowed)
				(copperpour not_allowed)
				(footprints allowed)
			)
			(placement
				(enabled no)
				(sheetname "")
			)
			(fill
				(thermal_gap 0.5)
				(thermal_bridge_width 0.5)
				(island_removal_mode 0)
			)
			(polygon
				(pts
					(arc
						(start 336.432906 -39.809928)
						(mid 336.357079 -39.856529)
						(end 336.310478 -39.932356)
					)
					(arc
						(start 336.205322 -39.932356)
						(mid 336.285124 -39.784574)
						(end 336.432906 -39.704772)
					)
				)
			)
		)
		(zone
			(layer "F.Cu")
			(hatch none 0.5)
			(connect_pads
				(clearance 0)
			)
			(min_thickness 0.25)
			(keepout
				(tracks not_allowed)
				(vias allowed)
				(pads allowed)
				(copperpour not_allowed)
				(footprints allowed)
			)
			(placement
				(enabled no)
				(sheetname "")
			)
			(fill
				(thermal_gap 0.5)
				(thermal_bridge_width 0.5)
				(island_removal_mode 0)
			)
			(polygon
				(pts
					(arc
						(start 336.43316 -56.726328)
						(mid 336.357333 -56.772929)
						(end 336.310732 -56.848756)
					)
					(arc
						(start 336.205576 -56.848756)
						(mid 336.285378 -56.700974)
						(end 336.43316 -56.621172)
					)
				)
			)
		)
		(zone
			(layer "F.Cu")
			(hatch none 0.5)
			(connect_pads
				(clearance 0)
			)
			(min_thickness 0.25)
			(keepout
				(tracks not_allowed)
				(vias allowed)
				(pads allowed)
				(copperpour not_allowed)
				(footprints allowed)
			)
			(placement
				(enabled no)
				(sheetname "")
			)
			(fill
				(thermal_gap 0.5)
				(thermal_bridge_width 0.5)
				(island_removal_mode 0)
			)
			(polygon
				(pts
					(arc
						(start 336.43316 -55.786528)
						(mid 336.357333 -55.833129)
						(end 336.310732 -55.908956)
					)
					(arc
						(start 336.205576 -55.908956)
						(mid 336.285378 -55.761174)
						(end 336.43316 -55.681372)
					)
				)
			)
		)
		(zone
			(layer "F.Cu")
			(hatch none 0.5)
			(connect_pads
				(clearance 0)
			)
			(min_thickness 0.25)
			(keepout
				(tracks not_allowed)
				(vias allowed)
				(pads allowed)
				(copperpour not_allowed)
				(footprints allowed)
			)
			(placement
				(enabled no)
				(sheetname "")
			)
			(fill
				(thermal_gap 0.5)
				(thermal_bridge_width 0.5)
				(island_removal_mode 0)
			)
			(polygon
				(pts
					(arc
						(start 336.43316 -54.846728)
						(mid 336.357333 -54.893329)
						(end 336.310732 -54.969156)
					)
					(arc
						(start 336.205576 -54.969156)
						(mid 336.285378 -54.821374)
						(end 336.43316 -54.741572)
					)
				)
			)
		)
		(zone
			(layer "F.Cu")
			(hatch none 0.5)
			(connect_pads
				(clearance 0)
			)
			(min_thickness 0.25)
			(keepout
				(tracks not_allowed)
				(vias allowed)
				(pads allowed)
				(copperpour not_allowed)
				(footprints allowed)
			)
			(placement
				(enabled no)
				(sheetname "")
			)
			(fill
				(thermal_gap 0.5)
				(thermal_bridge_width 0.5)
				(island_removal_mode 0)
			)
			(polygon
				(pts
					(arc
						(start 336.43316 -53.906928)
						(mid 336.357333 -53.953529)
						(end 336.310732 -54.029356)
					)
					(arc
						(start 336.205576 -54.029356)
						(mid 336.285378 -53.881574)
						(end 336.43316 -53.801772)
					)
				)
			)
		)
		(zone
			(layer "F.Cu")
			(hatch none 0.5)
			(connect_pads
				(clearance 0)
			)
			(min_thickness 0.25)
			(keepout
				(tracks not_allowed)
				(vias allowed)
				(pads allowed)
				(copperpour not_allowed)
				(footprints allowed)
			)
			(placement
				(enabled no)
				(sheetname "")
			)
			(fill
				(thermal_gap 0.5)
				(thermal_bridge_width 0.5)
				(island_removal_mode 0)
			)
			(polygon
				(pts
					(arc
						(start 336.43316 -52.967128)
						(mid 336.357333 -53.013729)
						(end 336.310732 -53.089556)
					)
					(arc
						(start 336.205576 -53.089556)
						(mid 336.285378 -52.941774)
						(end 336.43316 -52.861972)
					)
				)
			)
		)
		(zone
			(layer "F.Cu")
			(hatch none 0.5)
			(connect_pads
				(clearance 0)
			)
			(min_thickness 0.25)
			(keepout
				(tracks not_allowed)
				(vias allowed)
				(pads allowed)
				(copperpour not_allowed)
				(footprints allowed)
			)
			(placement
				(enabled no)
				(sheetname "")
			)
			(fill
				(thermal_gap 0.5)
				(thermal_bridge_width 0.5)
				(island_removal_mode 0)
			)
			(polygon
				(pts
					(arc
						(start 336.552286 -43.933364)
						(mid 336.628113 -43.886763)
						(end 336.674714 -43.810936)
					)
					(arc
						(start 336.77987 -43.810936)
						(mid 336.700068 -43.958718)
						(end 336.552286 -44.03852)
					)
				)
			)
		)
		(zone
			(layer "F.Cu")
			(hatch none 0.5)
			(connect_pads
				(clearance 0)
			)
			(min_thickness 0.25)
			(keepout
				(tracks not_allowed)
				(vias allowed)
				(pads allowed)
				(copperpour not_allowed)
				(footprints allowed)
			)
			(placement
				(enabled no)
				(sheetname "")
			)
			(fill
				(thermal_gap 0.5)
				(thermal_bridge_width 0.5)
				(island_removal_mode 0)
			)
			(polygon
				(pts
					(arc
						(start 336.552286 -42.993564)
						(mid 336.628113 -42.946963)
						(end 336.674714 -42.871136)
					)
					(arc
						(start 336.77987 -42.871136)
						(mid 336.700068 -43.018918)
						(end 336.552286 -43.09872)
					)
				)
			)
		)
		(zone
			(layer "F.Cu")
			(hatch none 0.5)
			(connect_pads
				(clearance 0)
			)
			(min_thickness 0.25)
			(keepout
				(tracks not_allowed)
				(vias allowed)
				(pads allowed)
				(copperpour not_allowed)
				(footprints allowed)
			)
			(placement
				(enabled no)
				(sheetname "")
			)
			(fill
				(thermal_gap 0.5)
				(thermal_bridge_width 0.5)
				(island_removal_mode 0)
			)
			(polygon
				(pts
					(arc
						(start 336.552286 -42.053764)
						(mid 336.628113 -42.007163)
						(end 336.674714 -41.931336)
					)
					(arc
						(start 336.77987 -41.931336)
						(mid 336.700068 -42.079118)
						(end 336.552286 -42.15892)
					)
				)
			)
		)
		(zone
			(layer "F.Cu")
			(hatch none 0.5)
			(connect_pads
				(clearance 0)
			)
			(min_thickness 0.25)
			(keepout
				(tracks not_allowed)
				(vias allowed)
				(pads allowed)
				(copperpour not_allowed)
				(footprints allowed)
			)
			(placement
				(enabled no)
				(sheetname "")
			)
			(fill
				(thermal_gap 0.5)
				(thermal_bridge_width 0.5)
				(island_removal_mode 0)
			)
			(polygon
				(pts
					(arc
						(start 336.552286 -41.113964)
						(mid 336.628113 -41.067363)
						(end 336.674714 -40.991536)
					)
					(arc
						(start 336.77987 -40.991536)
						(mid 336.700068 -41.139318)
						(end 336.552286 -41.21912)
					)
				)
			)
		)
		(zone
			(layer "F.Cu")
			(hatch none 0.5)
			(connect_pads
				(clearance 0)
			)
			(min_thickness 0.25)
			(keepout
				(tracks not_allowed)
				(vias allowed)
				(pads allowed)
				(copperpour not_allowed)
				(footprints allowed)
			)
			(placement
				(enabled no)
				(sheetname "")
			)
			(fill
				(thermal_gap 0.5)
				(thermal_bridge_width 0.5)
				(island_removal_mode 0)
			)
			(polygon
				(pts
					(arc
						(start 336.552286 -40.174164)
						(mid 336.628113 -40.127563)
						(end 336.674714 -40.051736)
					)
					(arc
						(start 336.77987 -40.051736)
						(mid 336.700068 -40.199518)
						(end 336.552286 -40.27932)
					)
				)
			)
		)
		(zone
			(layer "F.Cu")
			(hatch none 0.5)
			(connect_pads
				(clearance 0)
			)
			(min_thickness 0.25)
			(keepout
				(tracks not_allowed)
				(vias allowed)
				(pads allowed)
				(copperpour not_allowed)
				(footprints allowed)
			)
			(placement
				(enabled no)
				(sheetname "")
			)
			(fill
				(thermal_gap 0.5)
				(thermal_bridge_width 0.5)
				(island_removal_mode 0)
			)
			(polygon
				(pts
					(arc
						(start 336.55254 -57.090564)
						(mid 336.628367 -57.043963)
						(end 336.674968 -56.968136)
					)
					(arc
						(start 336.780124 -56.968136)
						(mid 336.700322 -57.115918)
						(end 336.55254 -57.19572)
					)
				)
			)
		)
		(zone
			(layer "F.Cu")
			(hatch none 0.5)
			(connect_pads
				(clearance 0)
			)
			(min_thickness 0.25)
			(keepout
				(tracks not_allowed)
				(vias allowed)
				(pads allowed)
				(copperpour not_allowed)
				(footprints allowed)
			)
			(placement
				(enabled no)
				(sheetname "")
			)
			(fill
				(thermal_gap 0.5)
				(thermal_bridge_width 0.5)
				(island_removal_mode 0)
			)
			(polygon
				(pts
					(arc
						(start 336.55254 -56.150764)
						(mid 336.628367 -56.104163)
						(end 336.674968 -56.028336)
					)
					(arc
						(start 336.780124 -56.028336)
						(mid 336.700322 -56.176118)
						(end 336.55254 -56.25592)
					)
				)
			)
		)
		(zone
			(layer "F.Cu")
			(hatch none 0.5)
			(connect_pads
				(clearance 0)
			)
			(min_thickness 0.25)
			(keepout
				(tracks not_allowed)
				(vias allowed)
				(pads allowed)
				(copperpour not_allowed)
				(footprints allowed)
			)
			(placement
				(enabled no)
				(sheetname "")
			)
			(fill
				(thermal_gap 0.5)
				(thermal_bridge_width 0.5)
				(island_removal_mode 0)
			)
			(polygon
				(pts
					(arc
						(start 336.55254 -55.210964)
						(mid 336.628367 -55.164363)
						(end 336.674968 -55.088536)
					)
					(arc
						(start 336.780124 -55.088536)
						(mid 336.700322 -55.236318)
						(end 336.55254 -55.31612)
					)
				)
			)
		)
		(zone
			(layer "F.Cu")
			(hatch none 0.5)
			(connect_pads
				(clearance 0)
			)
			(min_thickness 0.25)
			(keepout
				(tracks not_allowed)
				(vias allowed)
				(pads allowed)
				(copperpour not_allowed)
				(footprints allowed)
			)
			(placement
				(enabled no)
				(sheetname "")
			)
			(fill
				(thermal_gap 0.5)
				(thermal_bridge_width 0.5)
				(island_removal_mode 0)
			)
			(polygon
				(pts
					(arc
						(start 336.55254 -54.271164)
						(mid 336.628367 -54.224563)
						(end 336.674968 -54.148736)
					)
					(arc
						(start 336.780124 -54.148736)
						(mid 336.700322 -54.296518)
						(end 336.55254 -54.37632)
					)
				)
			)
		)
		(zone
			(layer "F.Cu")
			(hatch none 0.5)
			(connect_pads
				(clearance 0)
			)
			(min_thickness 0.25)
			(keepout
				(tracks not_allowed)
				(vias allowed)
				(pads allowed)
				(copperpour not_allowed)
				(footprints allowed)
			)
			(placement
				(enabled no)
				(sheetname "")
			)
			(fill
				(thermal_gap 0.5)
				(thermal_bridge_width 0.5)
				(island_removal_mode 0)
			)
			(polygon
				(pts
					(arc
						(start 336.55254 -53.331364)
						(mid 336.628367 -53.284763)
						(end 336.674968 -53.208936)
					)
					(arc
						(start 336.780124 -53.208936)
						(mid 336.700322 -53.356718)
						(end 336.55254 -53.43652)
					)
				)
			)
		)
		(zone
			(layer "F.Cu")
			(hatch none 0.5)
			(connect_pads
				(clearance 0)
			)
			(min_thickness 0.25)
			(keepout
				(tracks not_allowed)
				(vias allowed)
				(pads allowed)
				(copperpour not_allowed)
				(footprints allowed)
			)
			(placement
				(enabled no)
				(sheetname "")
			)
			(fill
				(thermal_gap 0.5)
				(thermal_bridge_width 0.5)
				(island_removal_mode 0)
			)
			(polygon
				(pts
					(arc
						(start 336.674714 -43.691556)
						(mid 336.628113 -43.615729)
						(end 336.552286 -43.569128)
					)
					(arc
						(start 336.552286 -43.463972)
						(mid 336.700068 -43.543774)
						(end 336.77987 -43.691556)
					)
				)
			)
		)
		(zone
			(layer "F.Cu")
			(hatch none 0.5)
			(connect_pads
				(clearance 0)
			)
			(min_thickness 0.25)
			(keepout
				(tracks not_allowed)
				(vias allowed)
				(pads allowed)
				(copperpour not_allowed)
				(footprints allowed)
			)
			(placement
				(enabled no)
				(sheetname "")
			)
			(fill
				(thermal_gap 0.5)
				(thermal_bridge_width 0.5)
				(island_removal_mode 0)
			)
			(polygon
				(pts
					(arc
						(start 336.674714 -42.751756)
						(mid 336.628113 -42.675929)
						(end 336.552286 -42.629328)
					)
					(arc
						(start 336.552286 -42.524172)
						(mid 336.700068 -42.603974)
						(end 336.77987 -42.751756)
					)
				)
			)
		)
		(zone
			(layer "F.Cu")
			(hatch none 0.5)
			(connect_pads
				(clearance 0)
			)
			(min_thickness 0.25)
			(keepout
				(tracks not_allowed)
				(vias allowed)
				(pads allowed)
				(copperpour not_allowed)
				(footprints allowed)
			)
			(placement
				(enabled no)
				(sheetname "")
			)
			(fill
				(thermal_gap 0.5)
				(thermal_bridge_width 0.5)
				(island_removal_mode 0)
			)
			(polygon
				(pts
					(arc
						(start 336.674714 -41.811956)
						(mid 336.628113 -41.736129)
						(end 336.552286 -41.689528)
					)
					(arc
						(start 336.552286 -41.584372)
						(mid 336.700068 -41.664174)
						(end 336.77987 -41.811956)
					)
				)
			)
		)
		(zone
			(layer "F.Cu")
			(hatch none 0.5)
			(connect_pads
				(clearance 0)
			)
			(min_thickness 0.25)
			(keepout
				(tracks not_allowed)
				(vias allowed)
				(pads allowed)
				(copperpour not_allowed)
				(footprints allowed)
			)
			(placement
				(enabled no)
				(sheetname "")
			)
			(fill
				(thermal_gap 0.5)
				(thermal_bridge_width 0.5)
				(island_removal_mode 0)
			)
			(polygon
				(pts
					(arc
						(start 336.674714 -40.872156)
						(mid 336.628113 -40.796329)
						(end 336.552286 -40.749728)
					)
					(arc
						(start 336.552286 -40.644572)
						(mid 336.700068 -40.724374)
						(end 336.77987 -40.872156)
					)
				)
			)
		)
		(zone
			(layer "F.Cu")
			(hatch none 0.5)
			(connect_pads
				(clearance 0)
			)
			(min_thickness 0.25)
			(keepout
				(tracks not_allowed)
				(vias allowed)
				(pads allowed)
				(copperpour not_allowed)
				(footprints allowed)
			)
			(placement
				(enabled no)
				(sheetname "")
			)
			(fill
				(thermal_gap 0.5)
				(thermal_bridge_width 0.5)
				(island_removal_mode 0)
			)
			(polygon
				(pts
					(arc
						(start 336.674714 -39.932356)
						(mid 336.628113 -39.856529)
						(end 336.552286 -39.809928)
					)
					(arc
						(start 336.552286 -39.704772)
						(mid 336.700068 -39.784574)
						(end 336.77987 -39.932356)
					)
				)
			)
		)
		(zone
			(layer "F.Cu")
			(hatch none 0.5)
			(connect_pads
				(clearance 0)
			)
			(min_thickness 0.25)
			(keepout
				(tracks not_allowed)
				(vias allowed)
				(pads allowed)
				(copperpour not_allowed)
				(footprints allowed)
			)
			(placement
				(enabled no)
				(sheetname "")
			)
			(fill
				(thermal_gap 0.5)
				(thermal_bridge_width 0.5)
				(island_removal_mode 0)
			)
			(polygon
				(pts
					(arc
						(start 336.674968 -56.848756)
						(mid 336.628367 -56.772929)
						(end 336.55254 -56.726328)
					)
					(arc
						(start 336.55254 -56.621172)
						(mid 336.700322 -56.700974)
						(end 336.780124 -56.848756)
					)
				)
			)
		)
		(zone
			(layer "F.Cu")
			(hatch none 0.5)
			(connect_pads
				(clearance 0)
			)
			(min_thickness 0.25)
			(keepout
				(tracks not_allowed)
				(vias allowed)
				(pads allowed)
				(copperpour not_allowed)
				(footprints allowed)
			)
			(placement
				(enabled no)
				(sheetname "")
			)
			(fill
				(thermal_gap 0.5)
				(thermal_bridge_width 0.5)
				(island_removal_mode 0)
			)
			(polygon
				(pts
					(arc
						(start 336.674968 -55.908956)
						(mid 336.628367 -55.833129)
						(end 336.55254 -55.786528)
					)
					(arc
						(start 336.55254 -55.681372)
						(mid 336.700322 -55.761174)
						(end 336.780124 -55.908956)
					)
				)
			)
		)
		(zone
			(layer "F.Cu")
			(hatch none 0.5)
			(connect_pads
				(clearance 0)
			)
			(min_thickness 0.25)
			(keepout
				(tracks not_allowed)
				(vias allowed)
				(pads allowed)
				(copperpour not_allowed)
				(footprints allowed)
			)
			(placement
				(enabled no)
				(sheetname "")
			)
			(fill
				(thermal_gap 0.5)
				(thermal_bridge_width 0.5)
				(island_removal_mode 0)
			)
			(polygon
				(pts
					(arc
						(start 336.674968 -54.969156)
						(mid 336.628367 -54.893329)
						(end 336.55254 -54.846728)
					)
					(arc
						(start 336.55254 -54.741572)
						(mid 336.700322 -54.821374)
						(end 336.780124 -54.969156)
					)
				)
			)
		)
		(zone
			(layer "F.Cu")
			(hatch none 0.5)
			(connect_pads
				(clearance 0)
			)
			(min_thickness 0.25)
			(keepout
				(tracks not_allowed)
				(vias allowed)
				(pads allowed)
				(copperpour not_allowed)
				(footprints allowed)
			)
			(placement
				(enabled no)
				(sheetname "")
			)
			(fill
				(thermal_gap 0.5)
				(thermal_bridge_width 0.5)
				(island_removal_mode 0)
			)
			(polygon
				(pts
					(arc
						(start 336.674968 -54.029356)
						(mid 336.628367 -53.953529)
						(end 336.55254 -53.906928)
					)
					(arc
						(start 336.55254 -53.801772)
						(mid 336.700322 -53.881574)
						(end 336.780124 -54.029356)
					)
				)
			)
		)
		(zone
			(layer "F.Cu")
			(hatch none 0.5)
			(connect_pads
				(clearance 0)
			)
			(min_thickness 0.25)
			(keepout
				(tracks not_allowed)
				(vias allowed)
				(pads allowed)
				(copperpour not_allowed)
				(footprints allowed)
			)
			(placement
				(enabled no)
				(sheetname "")
			)
			(fill
				(thermal_gap 0.5)
				(thermal_bridge_width 0.5)
				(island_removal_mode 0)
			)
			(polygon
				(pts
					(arc
						(start 336.674968 -53.089556)
						(mid 336.628367 -53.013729)
						(end 336.55254 -52.967128)
					)
					(arc
						(start 336.55254 -52.861972)
						(mid 336.700322 -52.941774)
						(end 336.780124 -53.089556)
					)
				)
			)
		)
		(zone
			(layer "F.Cu")
			(hatch none 0.5)
			(connect_pads
				(clearance 0)
			)
			(min_thickness 0.25)
			(keepout
				(tracks not_allowed)
				(vias allowed)
				(pads allowed)
				(copperpour not_allowed)
				(footprints allowed)
			)
			(placement
				(enabled no)
				(sheetname "")
			)
			(fill
				(thermal_gap 0.5)
				(thermal_bridge_width 0.5)
				(island_removal_mode 0)
			)
			(polygon
				(pts
					(arc
						(start 336.71764 -51.710336)
						(mid 336.764241 -51.786163)
						(end 336.840068 -51.832764)
					)
					(arc
						(start 336.840068 -51.93792)
						(mid 336.692286 -51.858118)
						(end 336.612484 -51.710336)
					)
				)
			)
		)
		(zone
			(layer "F.Cu")
			(hatch none 0.5)
			(connect_pads
				(clearance 0)
			)
			(min_thickness 0.25)
			(keepout
				(tracks not_allowed)
				(vias allowed)
				(pads allowed)
				(copperpour not_allowed)
				(footprints allowed)
			)
			(placement
				(enabled no)
				(sheetname "")
			)
			(fill
				(thermal_gap 0.5)
				(thermal_bridge_width 0.5)
				(island_removal_mode 0)
			)
			(polygon
				(pts
					(arc
						(start 336.71764 -50.910236)
						(mid 336.764241 -50.986063)
						(end 336.840068 -51.032664)
					)
					(arc
						(start 336.840068 -51.13782)
						(mid 336.692286 -51.058018)
						(end 336.612484 -50.910236)
					)
				)
			)
		)
		(zone
			(layer "F.Cu")
			(hatch none 0.5)
			(connect_pads
				(clearance 0)
			)
			(min_thickness 0.25)
			(keepout
				(tracks not_allowed)
				(vias allowed)
				(pads allowed)
				(copperpour not_allowed)
				(footprints allowed)
			)
			(placement
				(enabled no)
				(sheetname "")
			)
			(fill
				(thermal_gap 0.5)
				(thermal_bridge_width 0.5)
				(island_removal_mode 0)
			)
			(polygon
				(pts
					(arc
						(start 336.71764 -50.110136)
						(mid 336.764241 -50.185963)
						(end 336.840068 -50.232564)
					)
					(arc
						(start 336.840068 -50.33772)
						(mid 336.692286 -50.257918)
						(end 336.612484 -50.110136)
					)
				)
			)
		)
		(zone
			(layer "F.Cu")
			(hatch none 0.5)
			(connect_pads
				(clearance 0)
			)
			(min_thickness 0.25)
			(keepout
				(tracks not_allowed)
				(vias allowed)
				(pads allowed)
				(copperpour not_allowed)
				(footprints allowed)
			)
			(placement
				(enabled no)
				(sheetname "")
			)
			(fill
				(thermal_gap 0.5)
				(thermal_bridge_width 0.5)
				(island_removal_mode 0)
			)
			(polygon
				(pts
					(arc
						(start 336.71764 -49.310036)
						(mid 336.764241 -49.385863)
						(end 336.840068 -49.432464)
					)
					(arc
						(start 336.840068 -49.53762)
						(mid 336.692286 -49.457818)
						(end 336.612484 -49.310036)
					)
				)
			)
		)
		(zone
			(layer "F.Cu")
			(hatch none 0.5)
			(connect_pads
				(clearance 0)
			)
			(min_thickness 0.25)
			(keepout
				(tracks not_allowed)
				(vias allowed)
				(pads allowed)
				(copperpour not_allowed)
				(footprints allowed)
			)
			(placement
				(enabled no)
				(sheetname "")
			)
			(fill
				(thermal_gap 0.5)
				(thermal_bridge_width 0.5)
				(island_removal_mode 0)
			)
			(polygon
				(pts
					(arc
						(start 336.71764 -48.509936)
						(mid 336.764241 -48.585763)
						(end 336.840068 -48.632364)
					)
					(arc
						(start 336.840068 -48.73752)
						(mid 336.692286 -48.657718)
						(end 336.612484 -48.509936)
					)
				)
			)
		)
		(zone
			(layer "F.Cu")
			(hatch none 0.5)
			(connect_pads
				(clearance 0)
			)
			(min_thickness 0.25)
			(keepout
				(tracks not_allowed)
				(vias allowed)
				(pads allowed)
				(copperpour not_allowed)
				(footprints allowed)
			)
			(placement
				(enabled no)
				(sheetname "")
			)
			(fill
				(thermal_gap 0.5)
				(thermal_bridge_width 0.5)
				(island_removal_mode 0)
			)
			(polygon
				(pts
					(arc
						(start 336.71764 -47.709836)
						(mid 336.764241 -47.785663)
						(end 336.840068 -47.832264)
					)
					(arc
						(start 336.840068 -47.93742)
						(mid 336.692286 -47.857618)
						(end 336.612484 -47.709836)
					)
				)
			)
		)
		(zone
			(layer "F.Cu")
			(hatch none 0.5)
			(connect_pads
				(clearance 0)
			)
			(min_thickness 0.25)
			(keepout
				(tracks not_allowed)
				(vias allowed)
				(pads allowed)
				(copperpour not_allowed)
				(footprints allowed)
			)
			(placement
				(enabled no)
				(sheetname "")
			)
			(fill
				(thermal_gap 0.5)
				(thermal_bridge_width 0.5)
				(island_removal_mode 0)
			)
			(polygon
				(pts
					(arc
						(start 336.71764 -46.909736)
						(mid 336.764241 -46.985563)
						(end 336.840068 -47.032164)
					)
					(arc
						(start 336.840068 -47.13732)
						(mid 336.692286 -47.057518)
						(end 336.612484 -46.909736)
					)
				)
			)
		)
		(zone
			(layer "F.Cu")
			(hatch none 0.5)
			(connect_pads
				(clearance 0)
			)
			(min_thickness 0.25)
			(keepout
				(tracks not_allowed)
				(vias allowed)
				(pads allowed)
				(copperpour not_allowed)
				(footprints allowed)
			)
			(placement
				(enabled no)
				(sheetname "")
			)
			(fill
				(thermal_gap 0.5)
				(thermal_bridge_width 0.5)
				(island_removal_mode 0)
			)
			(polygon
				(pts
					(arc
						(start 336.71764 -46.109636)
						(mid 336.764241 -46.185463)
						(end 336.840068 -46.232064)
					)
					(arc
						(start 336.840068 -46.33722)
						(mid 336.692286 -46.257418)
						(end 336.612484 -46.109636)
					)
				)
			)
		)
		(zone
			(layer "F.Cu")
			(hatch none 0.5)
			(connect_pads
				(clearance 0)
			)
			(min_thickness 0.25)
			(keepout
				(tracks not_allowed)
				(vias allowed)
				(pads allowed)
				(copperpour not_allowed)
				(footprints allowed)
			)
			(placement
				(enabled no)
				(sheetname "")
			)
			(fill
				(thermal_gap 0.5)
				(thermal_bridge_width 0.5)
				(island_removal_mode 0)
			)
			(polygon
				(pts
					(arc
						(start 336.71764 -45.309536)
						(mid 336.764241 -45.385363)
						(end 336.840068 -45.431964)
					)
					(arc
						(start 336.840068 -45.53712)
						(mid 336.692286 -45.457318)
						(end 336.612484 -45.309536)
					)
				)
			)
		)
		(zone
			(layer "F.Cu")
			(hatch none 0.5)
			(connect_pads
				(clearance 0)
			)
			(min_thickness 0.25)
			(keepout
				(tracks not_allowed)
				(vias allowed)
				(pads allowed)
				(copperpour not_allowed)
				(footprints allowed)
			)
			(placement
				(enabled no)
				(sheetname "")
			)
			(fill
				(thermal_gap 0.5)
				(thermal_bridge_width 0.5)
				(island_removal_mode 0)
			)
			(polygon
				(pts
					(arc
						(start 336.840068 -51.468528)
						(mid 336.764241 -51.515129)
						(end 336.71764 -51.590956)
					)
					(arc
						(start 336.612484 -51.590956)
						(mid 336.692286 -51.443174)
						(end 336.840068 -51.363372)
					)
				)
			)
		)
		(zone
			(layer "F.Cu")
			(hatch none 0.5)
			(connect_pads
				(clearance 0)
			)
			(min_thickness 0.25)
			(keepout
				(tracks not_allowed)
				(vias allowed)
				(pads allowed)
				(copperpour not_allowed)
				(footprints allowed)
			)
			(placement
				(enabled no)
				(sheetname "")
			)
			(fill
				(thermal_gap 0.5)
				(thermal_bridge_width 0.5)
				(island_removal_mode 0)
			)
			(polygon
				(pts
					(arc
						(start 336.840068 -50.668428)
						(mid 336.764241 -50.715029)
						(end 336.71764 -50.790856)
					)
					(arc
						(start 336.612484 -50.790856)
						(mid 336.692286 -50.643074)
						(end 336.840068 -50.563272)
					)
				)
			)
		)
		(zone
			(layer "F.Cu")
			(hatch none 0.5)
			(connect_pads
				(clearance 0)
			)
			(min_thickness 0.25)
			(keepout
				(tracks not_allowed)
				(vias allowed)
				(pads allowed)
				(copperpour not_allowed)
				(footprints allowed)
			)
			(placement
				(enabled no)
				(sheetname "")
			)
			(fill
				(thermal_gap 0.5)
				(thermal_bridge_width 0.5)
				(island_removal_mode 0)
			)
			(polygon
				(pts
					(arc
						(start 336.840068 -49.868328)
						(mid 336.764241 -49.914929)
						(end 336.71764 -49.990756)
					)
					(arc
						(start 336.612484 -49.990756)
						(mid 336.692286 -49.842974)
						(end 336.840068 -49.763172)
					)
				)
			)
		)
		(zone
			(layer "F.Cu")
			(hatch none 0.5)
			(connect_pads
				(clearance 0)
			)
			(min_thickness 0.25)
			(keepout
				(tracks not_allowed)
				(vias allowed)
				(pads allowed)
				(copperpour not_allowed)
				(footprints allowed)
			)
			(placement
				(enabled no)
				(sheetname "")
			)
			(fill
				(thermal_gap 0.5)
				(thermal_bridge_width 0.5)
				(island_removal_mode 0)
			)
			(polygon
				(pts
					(arc
						(start 336.840068 -49.068228)
						(mid 336.764241 -49.114829)
						(end 336.71764 -49.190656)
					)
					(arc
						(start 336.612484 -49.190656)
						(mid 336.692286 -49.042874)
						(end 336.840068 -48.963072)
					)
				)
			)
		)
		(zone
			(layer "F.Cu")
			(hatch none 0.5)
			(connect_pads
				(clearance 0)
			)
			(min_thickness 0.25)
			(keepout
				(tracks not_allowed)
				(vias allowed)
				(pads allowed)
				(copperpour not_allowed)
				(footprints allowed)
			)
			(placement
				(enabled no)
				(sheetname "")
			)
			(fill
				(thermal_gap 0.5)
				(thermal_bridge_width 0.5)
				(island_removal_mode 0)
			)
			(polygon
				(pts
					(arc
						(start 336.840068 -48.268128)
						(mid 336.764241 -48.314729)
						(end 336.71764 -48.390556)
					)
					(arc
						(start 336.612484 -48.390556)
						(mid 336.692286 -48.242774)
						(end 336.840068 -48.162972)
					)
				)
			)
		)
		(zone
			(layer "F.Cu")
			(hatch none 0.5)
			(connect_pads
				(clearance 0)
			)
			(min_thickness 0.25)
			(keepout
				(tracks not_allowed)
				(vias allowed)
				(pads allowed)
				(copperpour not_allowed)
				(footprints allowed)
			)
			(placement
				(enabled no)
				(sheetname "")
			)
			(fill
				(thermal_gap 0.5)
				(thermal_bridge_width 0.5)
				(island_removal_mode 0)
			)
			(polygon
				(pts
					(arc
						(start 336.840068 -47.468028)
						(mid 336.764241 -47.514629)
						(end 336.71764 -47.590456)
					)
					(arc
						(start 336.612484 -47.590456)
						(mid 336.692286 -47.442674)
						(end 336.840068 -47.362872)
					)
				)
			)
		)
		(zone
			(layer "F.Cu")
			(hatch none 0.5)
			(connect_pads
				(clearance 0)
			)
			(min_thickness 0.25)
			(keepout
				(tracks not_allowed)
				(vias allowed)
				(pads allowed)
				(copperpour not_allowed)
				(footprints allowed)
			)
			(placement
				(enabled no)
				(sheetname "")
			)
			(fill
				(thermal_gap 0.5)
				(thermal_bridge_width 0.5)
				(island_removal_mode 0)
			)
			(polygon
				(pts
					(arc
						(start 336.840068 -46.667928)
						(mid 336.764241 -46.714529)
						(end 336.71764 -46.790356)
					)
					(arc
						(start 336.612484 -46.790356)
						(mid 336.692286 -46.642574)
						(end 336.840068 -46.562772)
					)
				)
			)
		)
		(zone
			(layer "F.Cu")
			(hatch none 0.5)
			(connect_pads
				(clearance 0)
			)
			(min_thickness 0.25)
			(keepout
				(tracks not_allowed)
				(vias allowed)
				(pads allowed)
				(copperpour not_allowed)
				(footprints allowed)
			)
			(placement
				(enabled no)
				(sheetname "")
			)
			(fill
				(thermal_gap 0.5)
				(thermal_bridge_width 0.5)
				(island_removal_mode 0)
			)
			(polygon
				(pts
					(arc
						(start 336.840068 -45.867828)
						(mid 336.764241 -45.914429)
						(end 336.71764 -45.990256)
					)
					(arc
						(start 336.612484 -45.990256)
						(mid 336.692286 -45.842474)
						(end 336.840068 -45.762672)
					)
				)
			)
		)
		(zone
			(layer "F.Cu")
			(hatch none 0.5)
			(connect_pads
				(clearance 0)
			)
			(min_thickness 0.25)
			(keepout
				(tracks not_allowed)
				(vias allowed)
				(pads allowed)
				(copperpour not_allowed)
				(footprints allowed)
			)
			(placement
				(enabled no)
				(sheetname "")
			)
			(fill
				(thermal_gap 0.5)
				(thermal_bridge_width 0.5)
				(island_removal_mode 0)
			)
			(polygon
				(pts
					(arc
						(start 336.840068 -45.067728)
						(mid 336.764241 -45.114329)
						(end 336.71764 -45.190156)
					)
					(arc
						(start 336.612484 -45.190156)
						(mid 336.692286 -45.042374)
						(end 336.840068 -44.962572)
					)
				)
			)
		)
		(zone
			(layer "F.Cu")
			(hatch none 0.5)
			(connect_pads
				(clearance 0)
			)
			(min_thickness 0.25)
			(keepout
				(tracks not_allowed)
				(vias allowed)
				(pads allowed)
				(copperpour not_allowed)
				(footprints allowed)
			)
			(placement
				(enabled no)
				(sheetname "")
			)
			(fill
				(thermal_gap 0.5)
				(thermal_bridge_width 0.5)
				(island_removal_mode 0)
			)
			(polygon
				(pts
					(arc
						(start 336.959448 -51.832764)
						(mid 337.035275 -51.786163)
						(end 337.081876 -51.710336)
					)
					(arc
						(start 337.187032 -51.710336)
						(mid 337.10723 -51.858118)
						(end 336.959448 -51.93792)
					)
				)
			)
		)
		(zone
			(layer "F.Cu")
			(hatch none 0.5)
			(connect_pads
				(clearance 0)
			)
			(min_thickness 0.25)
			(keepout
				(tracks not_allowed)
				(vias allowed)
				(pads allowed)
				(copperpour not_allowed)
				(footprints allowed)
			)
			(placement
				(enabled no)
				(sheetname "")
			)
			(fill
				(thermal_gap 0.5)
				(thermal_bridge_width 0.5)
				(island_removal_mode 0)
			)
			(polygon
				(pts
					(arc
						(start 336.959448 -51.032664)
						(mid 337.035275 -50.986063)
						(end 337.081876 -50.910236)
					)
					(arc
						(start 337.187032 -50.910236)
						(mid 337.10723 -51.058018)
						(end 336.959448 -51.13782)
					)
				)
			)
		)
		(zone
			(layer "F.Cu")
			(hatch none 0.5)
			(connect_pads
				(clearance 0)
			)
			(min_thickness 0.25)
			(keepout
				(tracks not_allowed)
				(vias allowed)
				(pads allowed)
				(copperpour not_allowed)
				(footprints allowed)
			)
			(placement
				(enabled no)
				(sheetname "")
			)
			(fill
				(thermal_gap 0.5)
				(thermal_bridge_width 0.5)
				(island_removal_mode 0)
			)
			(polygon
				(pts
					(arc
						(start 336.959448 -50.232564)
						(mid 337.035275 -50.185963)
						(end 337.081876 -50.110136)
					)
					(arc
						(start 337.187032 -50.110136)
						(mid 337.10723 -50.257918)
						(end 336.959448 -50.33772)
					)
				)
			)
		)
		(zone
			(layer "F.Cu")
			(hatch none 0.5)
			(connect_pads
				(clearance 0)
			)
			(min_thickness 0.25)
			(keepout
				(tracks not_allowed)
				(vias allowed)
				(pads allowed)
				(copperpour not_allowed)
				(footprints allowed)
			)
			(placement
				(enabled no)
				(sheetname "")
			)
			(fill
				(thermal_gap 0.5)
				(thermal_bridge_width 0.5)
				(island_removal_mode 0)
			)
			(polygon
				(pts
					(arc
						(start 336.959448 -49.432464)
						(mid 337.035275 -49.385863)
						(end 337.081876 -49.310036)
					)
					(arc
						(start 337.187032 -49.310036)
						(mid 337.10723 -49.457818)
						(end 336.959448 -49.53762)
					)
				)
			)
		)
		(zone
			(layer "F.Cu")
			(hatch none 0.5)
			(connect_pads
				(clearance 0)
			)
			(min_thickness 0.25)
			(keepout
				(tracks not_allowed)
				(vias allowed)
				(pads allowed)
				(copperpour not_allowed)
				(footprints allowed)
			)
			(placement
				(enabled no)
				(sheetname "")
			)
			(fill
				(thermal_gap 0.5)
				(thermal_bridge_width 0.5)
				(island_removal_mode 0)
			)
			(polygon
				(pts
					(arc
						(start 336.959448 -48.632364)
						(mid 337.035275 -48.585763)
						(end 337.081876 -48.509936)
					)
					(arc
						(start 337.187032 -48.509936)
						(mid 337.10723 -48.657718)
						(end 336.959448 -48.73752)
					)
				)
			)
		)
		(zone
			(layer "F.Cu")
			(hatch none 0.5)
			(connect_pads
				(clearance 0)
			)
			(min_thickness 0.25)
			(keepout
				(tracks not_allowed)
				(vias allowed)
				(pads allowed)
				(copperpour not_allowed)
				(footprints allowed)
			)
			(placement
				(enabled no)
				(sheetname "")
			)
			(fill
				(thermal_gap 0.5)
				(thermal_bridge_width 0.5)
				(island_removal_mode 0)
			)
			(polygon
				(pts
					(arc
						(start 336.959448 -47.832264)
						(mid 337.035275 -47.785663)
						(end 337.081876 -47.709836)
					)
					(arc
						(start 337.187032 -47.709836)
						(mid 337.10723 -47.857618)
						(end 336.959448 -47.93742)
					)
				)
			)
		)
		(zone
			(layer "F.Cu")
			(hatch none 0.5)
			(connect_pads
				(clearance 0)
			)
			(min_thickness 0.25)
			(keepout
				(tracks not_allowed)
				(vias allowed)
				(pads allowed)
				(copperpour not_allowed)
				(footprints allowed)
			)
			(placement
				(enabled no)
				(sheetname "")
			)
			(fill
				(thermal_gap 0.5)
				(thermal_bridge_width 0.5)
				(island_removal_mode 0)
			)
			(polygon
				(pts
					(arc
						(start 336.959448 -47.032164)
						(mid 337.035275 -46.985563)
						(end 337.081876 -46.909736)
					)
					(arc
						(start 337.187032 -46.909736)
						(mid 337.10723 -47.057518)
						(end 336.959448 -47.13732)
					)
				)
			)
		)
		(zone
			(layer "F.Cu")
			(hatch none 0.5)
			(connect_pads
				(clearance 0)
			)
			(min_thickness 0.25)
			(keepout
				(tracks not_allowed)
				(vias allowed)
				(pads allowed)
				(copperpour not_allowed)
				(footprints allowed)
			)
			(placement
				(enabled no)
				(sheetname "")
			)
			(fill
				(thermal_gap 0.5)
				(thermal_bridge_width 0.5)
				(island_removal_mode 0)
			)
			(polygon
				(pts
					(arc
						(start 336.959448 -46.232064)
						(mid 337.035275 -46.185463)
						(end 337.081876 -46.109636)
					)
					(arc
						(start 337.187032 -46.109636)
						(mid 337.10723 -46.257418)
						(end 336.959448 -46.33722)
					)
				)
			)
		)
		(zone
			(layer "F.Cu")
			(hatch none 0.5)
			(connect_pads
				(clearance 0)
			)
			(min_thickness 0.25)
			(keepout
				(tracks not_allowed)
				(vias allowed)
				(pads allowed)
				(copperpour not_allowed)
				(footprints allowed)
			)
			(placement
				(enabled no)
				(sheetname "")
			)
			(fill
				(thermal_gap 0.5)
				(thermal_bridge_width 0.5)
				(island_removal_mode 0)
			)
			(polygon
				(pts
					(arc
						(start 336.959448 -45.431964)
						(mid 337.035275 -45.385363)
						(end 337.081876 -45.309536)
					)
					(arc
						(start 337.187032 -45.309536)
						(mid 337.10723 -45.457318)
						(end 336.959448 -45.53712)
					)
				)
			)
		)
		(zone
			(layer "F.Cu")
			(hatch none 0.5)
			(connect_pads
				(clearance 0)
			)
			(min_thickness 0.25)
			(keepout
				(tracks not_allowed)
				(vias allowed)
				(pads allowed)
				(copperpour not_allowed)
				(footprints allowed)
			)
			(placement
				(enabled no)
				(sheetname "")
			)
			(fill
				(thermal_gap 0.5)
				(thermal_bridge_width 0.5)
				(island_removal_mode 0)
			)
			(polygon
				(pts
					(arc
						(start 337.081876 -51.590956)
						(mid 337.035275 -51.515129)
						(end 336.959448 -51.468528)
					)
					(arc
						(start 336.959448 -51.363372)
						(mid 337.10723 -51.443174)
						(end 337.187032 -51.590956)
					)
				)
			)
		)
		(zone
			(layer "F.Cu")
			(hatch none 0.5)
			(connect_pads
				(clearance 0)
			)
			(min_thickness 0.25)
			(keepout
				(tracks not_allowed)
				(vias allowed)
				(pads allowed)
				(copperpour not_allowed)
				(footprints allowed)
			)
			(placement
				(enabled no)
				(sheetname "")
			)
			(fill
				(thermal_gap 0.5)
				(thermal_bridge_width 0.5)
				(island_removal_mode 0)
			)
			(polygon
				(pts
					(arc
						(start 337.081876 -50.790856)
						(mid 337.035275 -50.715029)
						(end 336.959448 -50.668428)
					)
					(arc
						(start 336.959448 -50.563272)
						(mid 337.10723 -50.643074)
						(end 337.187032 -50.790856)
					)
				)
			)
		)
		(zone
			(layer "F.Cu")
			(hatch none 0.5)
			(connect_pads
				(clearance 0)
			)
			(min_thickness 0.25)
			(keepout
				(tracks not_allowed)
				(vias allowed)
				(pads allowed)
				(copperpour not_allowed)
				(footprints allowed)
			)
			(placement
				(enabled no)
				(sheetname "")
			)
			(fill
				(thermal_gap 0.5)
				(thermal_bridge_width 0.5)
				(island_removal_mode 0)
			)
			(polygon
				(pts
					(arc
						(start 337.081876 -49.990756)
						(mid 337.035275 -49.914929)
						(end 336.959448 -49.868328)
					)
					(arc
						(start 336.959448 -49.763172)
						(mid 337.10723 -49.842974)
						(end 337.187032 -49.990756)
					)
				)
			)
		)
		(zone
			(layer "F.Cu")
			(hatch none 0.5)
			(connect_pads
				(clearance 0)
			)
			(min_thickness 0.25)
			(keepout
				(tracks not_allowed)
				(vias allowed)
				(pads allowed)
				(copperpour not_allowed)
				(footprints allowed)
			)
			(placement
				(enabled no)
				(sheetname "")
			)
			(fill
				(thermal_gap 0.5)
				(thermal_bridge_width 0.5)
				(island_removal_mode 0)
			)
			(polygon
				(pts
					(arc
						(start 337.081876 -49.190656)
						(mid 337.035275 -49.114829)
						(end 336.959448 -49.068228)
					)
					(arc
						(start 336.959448 -48.963072)
						(mid 337.10723 -49.042874)
						(end 337.187032 -49.190656)
					)
				)
			)
		)
		(zone
			(layer "F.Cu")
			(hatch none 0.5)
			(connect_pads
				(clearance 0)
			)
			(min_thickness 0.25)
			(keepout
				(tracks not_allowed)
				(vias allowed)
				(pads allowed)
				(copperpour not_allowed)
				(footprints allowed)
			)
			(placement
				(enabled no)
				(sheetname "")
			)
			(fill
				(thermal_gap 0.5)
				(thermal_bridge_width 0.5)
				(island_removal_mode 0)
			)
			(polygon
				(pts
					(arc
						(start 337.081876 -48.390556)
						(mid 337.035275 -48.314729)
						(end 336.959448 -48.268128)
					)
					(arc
						(start 336.959448 -48.162972)
						(mid 337.10723 -48.242774)
						(end 337.187032 -48.390556)
					)
				)
			)
		)
		(zone
			(layer "F.Cu")
			(hatch none 0.5)
			(connect_pads
				(clearance 0)
			)
			(min_thickness 0.25)
			(keepout
				(tracks not_allowed)
				(vias allowed)
				(pads allowed)
				(copperpour not_allowed)
				(footprints allowed)
			)
			(placement
				(enabled no)
				(sheetname "")
			)
			(fill
				(thermal_gap 0.5)
				(thermal_bridge_width 0.5)
				(island_removal_mode 0)
			)
			(polygon
				(pts
					(arc
						(start 337.081876 -47.590456)
						(mid 337.035275 -47.514629)
						(end 336.959448 -47.468028)
					)
					(arc
						(start 336.959448 -47.362872)
						(mid 337.10723 -47.442674)
						(end 337.187032 -47.590456)
					)
				)
			)
		)
		(zone
			(layer "F.Cu")
			(hatch none 0.5)
			(connect_pads
				(clearance 0)
			)
			(min_thickness 0.25)
			(keepout
				(tracks not_allowed)
				(vias allowed)
				(pads allowed)
				(copperpour not_allowed)
				(footprints allowed)
			)
			(placement
				(enabled no)
				(sheetname "")
			)
			(fill
				(thermal_gap 0.5)
				(thermal_bridge_width 0.5)
				(island_removal_mode 0)
			)
			(polygon
				(pts
					(arc
						(start 337.081876 -46.790356)
						(mid 337.035275 -46.714529)
						(end 336.959448 -46.667928)
					)
					(arc
						(start 336.959448 -46.562772)
						(mid 337.10723 -46.642574)
						(end 337.187032 -46.790356)
					)
				)
			)
		)
		(zone
			(layer "F.Cu")
			(hatch none 0.5)
			(connect_pads
				(clearance 0)
			)
			(min_thickness 0.25)
			(keepout
				(tracks not_allowed)
				(vias allowed)
				(pads allowed)
				(copperpour not_allowed)
				(footprints allowed)
			)
			(placement
				(enabled no)
				(sheetname "")
			)
			(fill
				(thermal_gap 0.5)
				(thermal_bridge_width 0.5)
				(island_removal_mode 0)
			)
			(polygon
				(pts
					(arc
						(start 337.081876 -45.990256)
						(mid 337.035275 -45.914429)
						(end 336.959448 -45.867828)
					)
					(arc
						(start 336.959448 -45.762672)
						(mid 337.10723 -45.842474)
						(end 337.187032 -45.990256)
					)
				)
			)
		)
		(zone
			(layer "F.Cu")
			(hatch none 0.5)
			(connect_pads
				(clearance 0)
			)
			(min_thickness 0.25)
			(keepout
				(tracks not_allowed)
				(vias allowed)
				(pads allowed)
				(copperpour not_allowed)
				(footprints allowed)
			)
			(placement
				(enabled no)
				(sheetname "")
			)
			(fill
				(thermal_gap 0.5)
				(thermal_bridge_width 0.5)
				(island_removal_mode 0)
			)
			(polygon
				(pts
					(arc
						(start 337.081876 -45.190156)
						(mid 337.035275 -45.114329)
						(end 336.959448 -45.067728)
					)
					(arc
						(start 336.959448 -44.962572)
						(mid 337.10723 -45.042374)
						(end 337.187032 -45.190156)
					)
				)
			)
		)
		(zone
			(layer "F.Cu")
			(hatch none 0.5)
			(connect_pads
				(clearance 0)
			)
			(min_thickness 0.25)
			(keepout
				(tracks not_allowed)
				(vias allowed)
				(pads allowed)
				(copperpour not_allowed)
				(footprints allowed)
			)
			(placement
				(enabled no)
				(sheetname "")
			)
			(fill
				(thermal_gap 0.5)
				(thermal_bridge_width 0.5)
				(island_removal_mode 0)
			)
			(polygon
				(pts
					(arc
						(start 337.124548 -56.498236)
						(mid 337.171149 -56.574063)
						(end 337.246976 -56.620664)
					)
					(arc
						(start 337.246976 -56.72582)
						(mid 337.099194 -56.646018)
						(end 337.019392 -56.498236)
					)
				)
			)
		)
		(zone
			(layer "F.Cu")
			(hatch none 0.5)
			(connect_pads
				(clearance 0)
			)
			(min_thickness 0.25)
			(keepout
				(tracks not_allowed)
				(vias allowed)
				(pads allowed)
				(copperpour not_allowed)
				(footprints allowed)
			)
			(placement
				(enabled no)
				(sheetname "")
			)
			(fill
				(thermal_gap 0.5)
				(thermal_bridge_width 0.5)
				(island_removal_mode 0)
			)
			(polygon
				(pts
					(arc
						(start 337.124548 -55.558436)
						(mid 337.171149 -55.634263)
						(end 337.246976 -55.680864)
					)
					(arc
						(start 337.246976 -55.78602)
						(mid 337.099194 -55.706218)
						(end 337.019392 -55.558436)
					)
				)
			)
		)
		(zone
			(layer "F.Cu")
			(hatch none 0.5)
			(connect_pads
				(clearance 0)
			)
			(min_thickness 0.25)
			(keepout
				(tracks not_allowed)
				(vias allowed)
				(pads allowed)
				(copperpour not_allowed)
				(footprints allowed)
			)
			(placement
				(enabled no)
				(sheetname "")
			)
			(fill
				(thermal_gap 0.5)
				(thermal_bridge_width 0.5)
				(island_removal_mode 0)
			)
			(polygon
				(pts
					(arc
						(start 337.124548 -54.618636)
						(mid 337.171149 -54.694463)
						(end 337.246976 -54.741064)
					)
					(arc
						(start 337.246976 -54.84622)
						(mid 337.099194 -54.766418)
						(end 337.019392 -54.618636)
					)
				)
			)
		)
		(zone
			(layer "F.Cu")
			(hatch none 0.5)
			(connect_pads
				(clearance 0)
			)
			(min_thickness 0.25)
			(keepout
				(tracks not_allowed)
				(vias allowed)
				(pads allowed)
				(copperpour not_allowed)
				(footprints allowed)
			)
			(placement
				(enabled no)
				(sheetname "")
			)
			(fill
				(thermal_gap 0.5)
				(thermal_bridge_width 0.5)
				(island_removal_mode 0)
			)
			(polygon
				(pts
					(arc
						(start 337.124548 -53.678836)
						(mid 337.171149 -53.754663)
						(end 337.246976 -53.801264)
					)
					(arc
						(start 337.246976 -53.90642)
						(mid 337.099194 -53.826618)
						(end 337.019392 -53.678836)
					)
				)
			)
		)
		(zone
			(layer "F.Cu")
			(hatch none 0.5)
			(connect_pads
				(clearance 0)
			)
			(min_thickness 0.25)
			(keepout
				(tracks not_allowed)
				(vias allowed)
				(pads allowed)
				(copperpour not_allowed)
				(footprints allowed)
			)
			(placement
				(enabled no)
				(sheetname "")
			)
			(fill
				(thermal_gap 0.5)
				(thermal_bridge_width 0.5)
				(island_removal_mode 0)
			)
			(polygon
				(pts
					(arc
						(start 337.124548 -52.739036)
						(mid 337.171149 -52.814863)
						(end 337.246976 -52.861464)
					)
					(arc
						(start 337.246976 -52.96662)
						(mid 337.099194 -52.886818)
						(end 337.019392 -52.739036)
					)
				)
			)
		)
		(zone
			(layer "F.Cu")
			(hatch none 0.5)
			(connect_pads
				(clearance 0)
			)
			(min_thickness 0.25)
			(keepout
				(tracks not_allowed)
				(vias allowed)
				(pads allowed)
				(copperpour not_allowed)
				(footprints allowed)
			)
			(placement
				(enabled no)
				(sheetname "")
			)
			(fill
				(thermal_gap 0.5)
				(thermal_bridge_width 0.5)
				(island_removal_mode 0)
			)
			(polygon
				(pts
					(arc
						(start 337.124548 -44.280836)
						(mid 337.171149 -44.356663)
						(end 337.246976 -44.403264)
					)
					(arc
						(start 337.246976 -44.50842)
						(mid 337.099194 -44.428618)
						(end 337.019392 -44.280836)
					)
				)
			)
		)
		(zone
			(layer "F.Cu")
			(hatch none 0.5)
			(connect_pads
				(clearance 0)
			)
			(min_thickness 0.25)
			(keepout
				(tracks not_allowed)
				(vias allowed)
				(pads allowed)
				(copperpour not_allowed)
				(footprints allowed)
			)
			(placement
				(enabled no)
				(sheetname "")
			)
			(fill
				(thermal_gap 0.5)
				(thermal_bridge_width 0.5)
				(island_removal_mode 0)
			)
			(polygon
				(pts
					(arc
						(start 337.124548 -43.341036)
						(mid 337.171149 -43.416863)
						(end 337.246976 -43.463464)
					)
					(arc
						(start 337.246976 -43.56862)
						(mid 337.099194 -43.488818)
						(end 337.019392 -43.341036)
					)
				)
			)
		)
		(zone
			(layer "F.Cu")
			(hatch none 0.5)
			(connect_pads
				(clearance 0)
			)
			(min_thickness 0.25)
			(keepout
				(tracks not_allowed)
				(vias allowed)
				(pads allowed)
				(copperpour not_allowed)
				(footprints allowed)
			)
			(placement
				(enabled no)
				(sheetname "")
			)
			(fill
				(thermal_gap 0.5)
				(thermal_bridge_width 0.5)
				(island_removal_mode 0)
			)
			(polygon
				(pts
					(arc
						(start 337.124548 -42.401236)
						(mid 337.171149 -42.477063)
						(end 337.246976 -42.523664)
					)
					(arc
						(start 337.246976 -42.62882)
						(mid 337.099194 -42.549018)
						(end 337.019392 -42.401236)
					)
				)
			)
		)
		(zone
			(layer "F.Cu")
			(hatch none 0.5)
			(connect_pads
				(clearance 0)
			)
			(min_thickness 0.25)
			(keepout
				(tracks not_allowed)
				(vias allowed)
				(pads allowed)
				(copperpour not_allowed)
				(footprints allowed)
			)
			(placement
				(enabled no)
				(sheetname "")
			)
			(fill
				(thermal_gap 0.5)
				(thermal_bridge_width 0.5)
				(island_removal_mode 0)
			)
			(polygon
				(pts
					(arc
						(start 337.124548 -41.461436)
						(mid 337.171149 -41.537263)
						(end 337.246976 -41.583864)
					)
					(arc
						(start 337.246976 -41.68902)
						(mid 337.099194 -41.609218)
						(end 337.019392 -41.461436)
					)
				)
			)
		)
		(zone
			(layer "F.Cu")
			(hatch none 0.5)
			(connect_pads
				(clearance 0)
			)
			(min_thickness 0.25)
			(keepout
				(tracks not_allowed)
				(vias allowed)
				(pads allowed)
				(copperpour not_allowed)
				(footprints allowed)
			)
			(placement
				(enabled no)
				(sheetname "")
			)
			(fill
				(thermal_gap 0.5)
				(thermal_bridge_width 0.5)
				(island_removal_mode 0)
			)
			(polygon
				(pts
					(arc
						(start 337.124548 -40.521636)
						(mid 337.171149 -40.597463)
						(end 337.246976 -40.644064)
					)
					(arc
						(start 337.246976 -40.74922)
						(mid 337.099194 -40.669418)
						(end 337.019392 -40.521636)
					)
				)
			)
		)
		(zone
			(layer "F.Cu")
			(hatch none 0.5)
			(connect_pads
				(clearance 0)
			)
			(min_thickness 0.25)
			(keepout
				(tracks not_allowed)
				(vias allowed)
				(pads allowed)
				(copperpour not_allowed)
				(footprints allowed)
			)
			(placement
				(enabled no)
				(sheetname "")
			)
			(fill
				(thermal_gap 0.5)
				(thermal_bridge_width 0.5)
				(island_removal_mode 0)
			)
			(polygon
				(pts
					(arc
						(start 337.246976 -56.256428)
						(mid 337.171149 -56.303029)
						(end 337.124548 -56.378856)
					)
					(arc
						(start 337.019392 -56.378856)
						(mid 337.099194 -56.231074)
						(end 337.246976 -56.151272)
					)
				)
			)
		)
		(zone
			(layer "F.Cu")
			(hatch none 0.5)
			(connect_pads
				(clearance 0)
			)
			(min_thickness 0.25)
			(keepout
				(tracks not_allowed)
				(vias allowed)
				(pads allowed)
				(copperpour not_allowed)
				(footprints allowed)
			)
			(placement
				(enabled no)
				(sheetname "")
			)
			(fill
				(thermal_gap 0.5)
				(thermal_bridge_width 0.5)
				(island_removal_mode 0)
			)
			(polygon
				(pts
					(arc
						(start 337.246976 -55.316628)
						(mid 337.171149 -55.363229)
						(end 337.124548 -55.439056)
					)
					(arc
						(start 337.019392 -55.439056)
						(mid 337.099194 -55.291274)
						(end 337.246976 -55.211472)
					)
				)
			)
		)
		(zone
			(layer "F.Cu")
			(hatch none 0.5)
			(connect_pads
				(clearance 0)
			)
			(min_thickness 0.25)
			(keepout
				(tracks not_allowed)
				(vias allowed)
				(pads allowed)
				(copperpour not_allowed)
				(footprints allowed)
			)
			(placement
				(enabled no)
				(sheetname "")
			)
			(fill
				(thermal_gap 0.5)
				(thermal_bridge_width 0.5)
				(island_removal_mode 0)
			)
			(polygon
				(pts
					(arc
						(start 337.246976 -54.376828)
						(mid 337.171149 -54.423429)
						(end 337.124548 -54.499256)
					)
					(arc
						(start 337.019392 -54.499256)
						(mid 337.099194 -54.351474)
						(end 337.246976 -54.271672)
					)
				)
			)
		)
		(zone
			(layer "F.Cu")
			(hatch none 0.5)
			(connect_pads
				(clearance 0)
			)
			(min_thickness 0.25)
			(keepout
				(tracks not_allowed)
				(vias allowed)
				(pads allowed)
				(copperpour not_allowed)
				(footprints allowed)
			)
			(placement
				(enabled no)
				(sheetname "")
			)
			(fill
				(thermal_gap 0.5)
				(thermal_bridge_width 0.5)
				(island_removal_mode 0)
			)
			(polygon
				(pts
					(arc
						(start 337.246976 -53.437028)
						(mid 337.171149 -53.483629)
						(end 337.124548 -53.559456)
					)
					(arc
						(start 337.019392 -53.559456)
						(mid 337.099194 -53.411674)
						(end 337.246976 -53.331872)
					)
				)
			)
		)
		(zone
			(layer "F.Cu")
			(hatch none 0.5)
			(connect_pads
				(clearance 0)
			)
			(min_thickness 0.25)
			(keepout
				(tracks not_allowed)
				(vias allowed)
				(pads allowed)
				(copperpour not_allowed)
				(footprints allowed)
			)
			(placement
				(enabled no)
				(sheetname "")
			)
			(fill
				(thermal_gap 0.5)
				(thermal_bridge_width 0.5)
				(island_removal_mode 0)
			)
			(polygon
				(pts
					(arc
						(start 337.246976 -52.497228)
						(mid 337.171149 -52.543829)
						(end 337.124548 -52.619656)
					)
					(arc
						(start 337.019392 -52.619656)
						(mid 337.099194 -52.471874)
						(end 337.246976 -52.392072)
					)
				)
			)
		)
		(zone
			(layer "F.Cu")
			(hatch none 0.5)
			(connect_pads
				(clearance 0)
			)
			(min_thickness 0.25)
			(keepout
				(tracks not_allowed)
				(vias allowed)
				(pads allowed)
				(copperpour not_allowed)
				(footprints allowed)
			)
			(placement
				(enabled no)
				(sheetname "")
			)
			(fill
				(thermal_gap 0.5)
				(thermal_bridge_width 0.5)
				(island_removal_mode 0)
			)
			(polygon
				(pts
					(arc
						(start 337.246976 -44.039028)
						(mid 337.171149 -44.085629)
						(end 337.124548 -44.161456)
					)
					(arc
						(start 337.019392 -44.161456)
						(mid 337.099194 -44.013674)
						(end 337.246976 -43.933872)
					)
				)
			)
		)
		(zone
			(layer "F.Cu")
			(hatch none 0.5)
			(connect_pads
				(clearance 0)
			)
			(min_thickness 0.25)
			(keepout
				(tracks not_allowed)
				(vias allowed)
				(pads allowed)
				(copperpour not_allowed)
				(footprints allowed)
			)
			(placement
				(enabled no)
				(sheetname "")
			)
			(fill
				(thermal_gap 0.5)
				(thermal_bridge_width 0.5)
				(island_removal_mode 0)
			)
			(polygon
				(pts
					(arc
						(start 337.246976 -43.099228)
						(mid 337.171149 -43.145829)
						(end 337.124548 -43.221656)
					)
					(arc
						(start 337.019392 -43.221656)
						(mid 337.099194 -43.073874)
						(end 337.246976 -42.994072)
					)
				)
			)
		)
		(zone
			(layer "F.Cu")
			(hatch none 0.5)
			(connect_pads
				(clearance 0)
			)
			(min_thickness 0.25)
			(keepout
				(tracks not_allowed)
				(vias allowed)
				(pads allowed)
				(copperpour not_allowed)
				(footprints allowed)
			)
			(placement
				(enabled no)
				(sheetname "")
			)
			(fill
				(thermal_gap 0.5)
				(thermal_bridge_width 0.5)
				(island_removal_mode 0)
			)
			(polygon
				(pts
					(arc
						(start 337.246976 -42.159428)
						(mid 337.171149 -42.206029)
						(end 337.124548 -42.281856)
					)
					(arc
						(start 337.019392 -42.281856)
						(mid 337.099194 -42.134074)
						(end 337.246976 -42.054272)
					)
				)
			)
		)
		(zone
			(layer "F.Cu")
			(hatch none 0.5)
			(connect_pads
				(clearance 0)
			)
			(min_thickness 0.25)
			(keepout
				(tracks not_allowed)
				(vias allowed)
				(pads allowed)
				(copperpour not_allowed)
				(footprints allowed)
			)
			(placement
				(enabled no)
				(sheetname "")
			)
			(fill
				(thermal_gap 0.5)
				(thermal_bridge_width 0.5)
				(island_removal_mode 0)
			)
			(polygon
				(pts
					(arc
						(start 337.246976 -41.219628)
						(mid 337.171149 -41.266229)
						(end 337.124548 -41.342056)
					)
					(arc
						(start 337.019392 -41.342056)
						(mid 337.099194 -41.194274)
						(end 337.246976 -41.114472)
					)
				)
			)
		)
		(zone
			(layer "F.Cu")
			(hatch none 0.5)
			(connect_pads
				(clearance 0)
			)
			(min_thickness 0.25)
			(keepout
				(tracks not_allowed)
				(vias allowed)
				(pads allowed)
				(copperpour not_allowed)
				(footprints allowed)
			)
			(placement
				(enabled no)
				(sheetname "")
			)
			(fill
				(thermal_gap 0.5)
				(thermal_bridge_width 0.5)
				(island_removal_mode 0)
			)
			(polygon
				(pts
					(arc
						(start 337.246976 -40.279828)
						(mid 337.171149 -40.326429)
						(end 337.124548 -40.402256)
					)
					(arc
						(start 337.019392 -40.402256)
						(mid 337.099194 -40.254474)
						(end 337.246976 -40.174672)
					)
				)
			)
		)
		(zone
			(layer "F.Cu")
			(hatch none 0.5)
			(connect_pads
				(clearance 0)
			)
			(min_thickness 0.25)
			(keepout
				(tracks not_allowed)
				(vias allowed)
				(pads allowed)
				(copperpour not_allowed)
				(footprints allowed)
			)
			(placement
				(enabled no)
				(sheetname "")
			)
			(fill
				(thermal_gap 0.5)
				(thermal_bridge_width 0.5)
				(island_removal_mode 0)
			)
			(polygon
				(pts
					(arc
						(start 337.366356 -56.620664)
						(mid 337.442183 -56.574063)
						(end 337.488784 -56.498236)
					)
					(arc
						(start 337.59394 -56.498236)
						(mid 337.514138 -56.646018)
						(end 337.366356 -56.72582)
					)
				)
			)
		)
		(zone
			(layer "F.Cu")
			(hatch none 0.5)
			(connect_pads
				(clearance 0)
			)
			(min_thickness 0.25)
			(keepout
				(tracks not_allowed)
				(vias allowed)
				(pads allowed)
				(copperpour not_allowed)
				(footprints allowed)
			)
			(placement
				(enabled no)
				(sheetname "")
			)
			(fill
				(thermal_gap 0.5)
				(thermal_bridge_width 0.5)
				(island_removal_mode 0)
			)
			(polygon
				(pts
					(arc
						(start 337.366356 -55.680864)
						(mid 337.442183 -55.634263)
						(end 337.488784 -55.558436)
					)
					(arc
						(start 337.59394 -55.558436)
						(mid 337.514138 -55.706218)
						(end 337.366356 -55.78602)
					)
				)
			)
		)
		(zone
			(layer "F.Cu")
			(hatch none 0.5)
			(connect_pads
				(clearance 0)
			)
			(min_thickness 0.25)
			(keepout
				(tracks not_allowed)
				(vias allowed)
				(pads allowed)
				(copperpour not_allowed)
				(footprints allowed)
			)
			(placement
				(enabled no)
				(sheetname "")
			)
			(fill
				(thermal_gap 0.5)
				(thermal_bridge_width 0.5)
				(island_removal_mode 0)
			)
			(polygon
				(pts
					(arc
						(start 337.366356 -54.741064)
						(mid 337.442183 -54.694463)
						(end 337.488784 -54.618636)
					)
					(arc
						(start 337.59394 -54.618636)
						(mid 337.514138 -54.766418)
						(end 337.366356 -54.84622)
					)
				)
			)
		)
		(zone
			(layer "F.Cu")
			(hatch none 0.5)
			(connect_pads
				(clearance 0)
			)
			(min_thickness 0.25)
			(keepout
				(tracks not_allowed)
				(vias allowed)
				(pads allowed)
				(copperpour not_allowed)
				(footprints allowed)
			)
			(placement
				(enabled no)
				(sheetname "")
			)
			(fill
				(thermal_gap 0.5)
				(thermal_bridge_width 0.5)
				(island_removal_mode 0)
			)
			(polygon
				(pts
					(arc
						(start 337.366356 -53.801264)
						(mid 337.442183 -53.754663)
						(end 337.488784 -53.678836)
					)
					(arc
						(start 337.59394 -53.678836)
						(mid 337.514138 -53.826618)
						(end 337.366356 -53.90642)
					)
				)
			)
		)
		(zone
			(layer "F.Cu")
			(hatch none 0.5)
			(connect_pads
				(clearance 0)
			)
			(min_thickness 0.25)
			(keepout
				(tracks not_allowed)
				(vias allowed)
				(pads allowed)
				(copperpour not_allowed)
				(footprints allowed)
			)
			(placement
				(enabled no)
				(sheetname "")
			)
			(fill
				(thermal_gap 0.5)
				(thermal_bridge_width 0.5)
				(island_removal_mode 0)
			)
			(polygon
				(pts
					(arc
						(start 337.366356 -52.861464)
						(mid 337.442183 -52.814863)
						(end 337.488784 -52.739036)
					)
					(arc
						(start 337.59394 -52.739036)
						(mid 337.514138 -52.886818)
						(end 337.366356 -52.96662)
					)
				)
			)
		)
		(zone
			(layer "F.Cu")
			(hatch none 0.5)
			(connect_pads
				(clearance 0)
			)
			(min_thickness 0.25)
			(keepout
				(tracks not_allowed)
				(vias allowed)
				(pads allowed)
				(copperpour not_allowed)
				(footprints allowed)
			)
			(placement
				(enabled no)
				(sheetname "")
			)
			(fill
				(thermal_gap 0.5)
				(thermal_bridge_width 0.5)
				(island_removal_mode 0)
			)
			(polygon
				(pts
					(arc
						(start 337.366356 -44.403264)
						(mid 337.442183 -44.356663)
						(end 337.488784 -44.280836)
					)
					(arc
						(start 337.59394 -44.280836)
						(mid 337.514138 -44.428618)
						(end 337.366356 -44.50842)
					)
				)
			)
		)
		(zone
			(layer "F.Cu")
			(hatch none 0.5)
			(connect_pads
				(clearance 0)
			)
			(min_thickness 0.25)
			(keepout
				(tracks not_allowed)
				(vias allowed)
				(pads allowed)
				(copperpour not_allowed)
				(footprints allowed)
			)
			(placement
				(enabled no)
				(sheetname "")
			)
			(fill
				(thermal_gap 0.5)
				(thermal_bridge_width 0.5)
				(island_removal_mode 0)
			)
			(polygon
				(pts
					(arc
						(start 337.366356 -43.463464)
						(mid 337.442183 -43.416863)
						(end 337.488784 -43.341036)
					)
					(arc
						(start 337.59394 -43.341036)
						(mid 337.514138 -43.488818)
						(end 337.366356 -43.56862)
					)
				)
			)
		)
		(zone
			(layer "F.Cu")
			(hatch none 0.5)
			(connect_pads
				(clearance 0)
			)
			(min_thickness 0.25)
			(keepout
				(tracks not_allowed)
				(vias allowed)
				(pads allowed)
				(copperpour not_allowed)
				(footprints allowed)
			)
			(placement
				(enabled no)
				(sheetname "")
			)
			(fill
				(thermal_gap 0.5)
				(thermal_bridge_width 0.5)
				(island_removal_mode 0)
			)
			(polygon
				(pts
					(arc
						(start 337.366356 -42.523664)
						(mid 337.442183 -42.477063)
						(end 337.488784 -42.401236)
					)
					(arc
						(start 337.59394 -42.401236)
						(mid 337.514138 -42.549018)
						(end 337.366356 -42.62882)
					)
				)
			)
		)
		(zone
			(layer "F.Cu")
			(hatch none 0.5)
			(connect_pads
				(clearance 0)
			)
			(min_thickness 0.25)
			(keepout
				(tracks not_allowed)
				(vias allowed)
				(pads allowed)
				(copperpour not_allowed)
				(footprints allowed)
			)
			(placement
				(enabled no)
				(sheetname "")
			)
			(fill
				(thermal_gap 0.5)
				(thermal_bridge_width 0.5)
				(island_removal_mode 0)
			)
			(polygon
				(pts
					(arc
						(start 337.366356 -41.583864)
						(mid 337.442183 -41.537263)
						(end 337.488784 -41.461436)
					)
					(arc
						(start 337.59394 -41.461436)
						(mid 337.514138 -41.609218)
						(end 337.366356 -41.68902)
					)
				)
			)
		)
		(zone
			(layer "F.Cu")
			(hatch none 0.5)
			(connect_pads
				(clearance 0)
			)
			(min_thickness 0.25)
			(keepout
				(tracks not_allowed)
				(vias allowed)
				(pads allowed)
				(copperpour not_allowed)
				(footprints allowed)
			)
			(placement
				(enabled no)
				(sheetname "")
			)
			(fill
				(thermal_gap 0.5)
				(thermal_bridge_width 0.5)
				(island_removal_mode 0)
			)
			(polygon
				(pts
					(arc
						(start 337.366356 -40.644064)
						(mid 337.442183 -40.597463)
						(end 337.488784 -40.521636)
					)
					(arc
						(start 337.59394 -40.521636)
						(mid 337.514138 -40.669418)
						(end 337.366356 -40.74922)
					)
				)
			)
		)
		(zone
			(layer "F.Cu")
			(hatch none 0.5)
			(connect_pads
				(clearance 0)
			)
			(min_thickness 0.25)
			(keepout
				(tracks not_allowed)
				(vias allowed)
				(pads allowed)
				(copperpour not_allowed)
				(footprints allowed)
			)
			(placement
				(enabled no)
				(sheetname "")
			)
			(fill
				(thermal_gap 0.5)
				(thermal_bridge_width 0.5)
				(island_removal_mode 0)
			)
			(polygon
				(pts
					(arc
						(start 337.488784 -56.378856)
						(mid 337.442183 -56.303029)
						(end 337.366356 -56.256428)
					)
					(arc
						(start 337.366356 -56.151272)
						(mid 337.514138 -56.231074)
						(end 337.59394 -56.378856)
					)
				)
			)
		)
		(zone
			(layer "F.Cu")
			(hatch none 0.5)
			(connect_pads
				(clearance 0)
			)
			(min_thickness 0.25)
			(keepout
				(tracks not_allowed)
				(vias allowed)
				(pads allowed)
				(copperpour not_allowed)
				(footprints allowed)
			)
			(placement
				(enabled no)
				(sheetname "")
			)
			(fill
				(thermal_gap 0.5)
				(thermal_bridge_width 0.5)
				(island_removal_mode 0)
			)
			(polygon
				(pts
					(arc
						(start 337.488784 -55.439056)
						(mid 337.442183 -55.363229)
						(end 337.366356 -55.316628)
					)
					(arc
						(start 337.366356 -55.211472)
						(mid 337.514138 -55.291274)
						(end 337.59394 -55.439056)
					)
				)
			)
		)
		(zone
			(layer "F.Cu")
			(hatch none 0.5)
			(connect_pads
				(clearance 0)
			)
			(min_thickness 0.25)
			(keepout
				(tracks not_allowed)
				(vias allowed)
				(pads allowed)
				(copperpour not_allowed)
				(footprints allowed)
			)
			(placement
				(enabled no)
				(sheetname "")
			)
			(fill
				(thermal_gap 0.5)
				(thermal_bridge_width 0.5)
				(island_removal_mode 0)
			)
			(polygon
				(pts
					(arc
						(start 337.488784 -54.499256)
						(mid 337.442183 -54.423429)
						(end 337.366356 -54.376828)
					)
					(arc
						(start 337.366356 -54.271672)
						(mid 337.514138 -54.351474)
						(end 337.59394 -54.499256)
					)
				)
			)
		)
		(zone
			(layer "F.Cu")
			(hatch none 0.5)
			(connect_pads
				(clearance 0)
			)
			(min_thickness 0.25)
			(keepout
				(tracks not_allowed)
				(vias allowed)
				(pads allowed)
				(copperpour not_allowed)
				(footprints allowed)
			)
			(placement
				(enabled no)
				(sheetname "")
			)
			(fill
				(thermal_gap 0.5)
				(thermal_bridge_width 0.5)
				(island_removal_mode 0)
			)
			(polygon
				(pts
					(arc
						(start 337.488784 -53.559456)
						(mid 337.442183 -53.483629)
						(end 337.366356 -53.437028)
					)
					(arc
						(start 337.366356 -53.331872)
						(mid 337.514138 -53.411674)
						(end 337.59394 -53.559456)
					)
				)
			)
		)
		(zone
			(layer "F.Cu")
			(hatch none 0.5)
			(connect_pads
				(clearance 0)
			)
			(min_thickness 0.25)
			(keepout
				(tracks not_allowed)
				(vias allowed)
				(pads allowed)
				(copperpour not_allowed)
				(footprints allowed)
			)
			(placement
				(enabled no)
				(sheetname "")
			)
			(fill
				(thermal_gap 0.5)
				(thermal_bridge_width 0.5)
				(island_removal_mode 0)
			)
			(polygon
				(pts
					(arc
						(start 337.488784 -52.619656)
						(mid 337.442183 -52.543829)
						(end 337.366356 -52.497228)
					)
					(arc
						(start 337.366356 -52.392072)
						(mid 337.514138 -52.471874)
						(end 337.59394 -52.619656)
					)
				)
			)
		)
		(zone
			(layer "F.Cu")
			(hatch none 0.5)
			(connect_pads
				(clearance 0)
			)
			(min_thickness 0.25)
			(keepout
				(tracks not_allowed)
				(vias allowed)
				(pads allowed)
				(copperpour not_allowed)
				(footprints allowed)
			)
			(placement
				(enabled no)
				(sheetname "")
			)
			(fill
				(thermal_gap 0.5)
				(thermal_bridge_width 0.5)
				(island_removal_mode 0)
			)
			(polygon
				(pts
					(arc
						(start 337.488784 -44.161456)
						(mid 337.442183 -44.085629)
						(end 337.366356 -44.039028)
					)
					(arc
						(start 337.366356 -43.933872)
						(mid 337.514138 -44.013674)
						(end 337.59394 -44.161456)
					)
				)
			)
		)
		(zone
			(layer "F.Cu")
			(hatch none 0.5)
			(connect_pads
				(clearance 0)
			)
			(min_thickness 0.25)
			(keepout
				(tracks not_allowed)
				(vias allowed)
				(pads allowed)
				(copperpour not_allowed)
				(footprints allowed)
			)
			(placement
				(enabled no)
				(sheetname "")
			)
			(fill
				(thermal_gap 0.5)
				(thermal_bridge_width 0.5)
				(island_removal_mode 0)
			)
			(polygon
				(pts
					(arc
						(start 337.488784 -43.221656)
						(mid 337.442183 -43.145829)
						(end 337.366356 -43.099228)
					)
					(arc
						(start 337.366356 -42.994072)
						(mid 337.514138 -43.073874)
						(end 337.59394 -43.221656)
					)
				)
			)
		)
		(zone
			(layer "F.Cu")
			(hatch none 0.5)
			(connect_pads
				(clearance 0)
			)
			(min_thickness 0.25)
			(keepout
				(tracks not_allowed)
				(vias allowed)
				(pads allowed)
				(copperpour not_allowed)
				(footprints allowed)
			)
			(placement
				(enabled no)
				(sheetname "")
			)
			(fill
				(thermal_gap 0.5)
				(thermal_bridge_width 0.5)
				(island_removal_mode 0)
			)
			(polygon
				(pts
					(arc
						(start 337.488784 -42.281856)
						(mid 337.442183 -42.206029)
						(end 337.366356 -42.159428)
					)
					(arc
						(start 337.366356 -42.054272)
						(mid 337.514138 -42.134074)
						(end 337.59394 -42.281856)
					)
				)
			)
		)
		(zone
			(layer "F.Cu")
			(hatch none 0.5)
			(connect_pads
				(clearance 0)
			)
			(min_thickness 0.25)
			(keepout
				(tracks not_allowed)
				(vias allowed)
				(pads allowed)
				(copperpour not_allowed)
				(footprints allowed)
			)
			(placement
				(enabled no)
				(sheetname "")
			)
			(fill
				(thermal_gap 0.5)
				(thermal_bridge_width 0.5)
				(island_removal_mode 0)
			)
			(polygon
				(pts
					(arc
						(start 337.488784 -41.342056)
						(mid 337.442183 -41.266229)
						(end 337.366356 -41.219628)
					)
					(arc
						(start 337.366356 -41.114472)
						(mid 337.514138 -41.194274)
						(end 337.59394 -41.342056)
					)
				)
			)
		)
		(zone
			(layer "F.Cu")
			(hatch none 0.5)
			(connect_pads
				(clearance 0)
			)
			(min_thickness 0.25)
			(keepout
				(tracks not_allowed)
				(vias allowed)
				(pads allowed)
				(copperpour not_allowed)
				(footprints allowed)
			)
			(placement
				(enabled no)
				(sheetname "")
			)
			(fill
				(thermal_gap 0.5)
				(thermal_bridge_width 0.5)
				(island_removal_mode 0)
			)
			(polygon
				(pts
					(arc
						(start 337.488784 -40.402256)
						(mid 337.442183 -40.326429)
						(end 337.366356 -40.279828)
					)
					(arc
						(start 337.366356 -40.174672)
						(mid 337.514138 -40.254474)
						(end 337.59394 -40.402256)
					)
				)
			)
		)
		(zone
			(layer "F.Cu")
			(hatch none 0.5)
			(connect_pads
				(clearance 0)
			)
			(min_thickness 0.25)
			(keepout
				(tracks not_allowed)
				(vias allowed)
				(pads allowed)
				(copperpour not_allowed)
				(footprints allowed)
			)
			(placement
				(enabled no)
				(sheetname "")
			)
			(fill
				(thermal_gap 0.5)
				(thermal_bridge_width 0.5)
				(island_removal_mode 0)
			)
			(polygon
				(pts
					(arc
						(start 337.51774 -51.710336)
						(mid 337.564341 -51.786163)
						(end 337.640168 -51.832764)
					)
					(arc
						(start 337.640168 -51.93792)
						(mid 337.492386 -51.858118)
						(end 337.412584 -51.710336)
					)
				)
			)
		)
		(zone
			(layer "F.Cu")
			(hatch none 0.5)
			(connect_pads
				(clearance 0)
			)
			(min_thickness 0.25)
			(keepout
				(tracks not_allowed)
				(vias allowed)
				(pads allowed)
				(copperpour not_allowed)
				(footprints allowed)
			)
			(placement
				(enabled no)
				(sheetname "")
			)
			(fill
				(thermal_gap 0.5)
				(thermal_bridge_width 0.5)
				(island_removal_mode 0)
			)
			(polygon
				(pts
					(arc
						(start 337.51774 -50.910236)
						(mid 337.564341 -50.986063)
						(end 337.640168 -51.032664)
					)
					(arc
						(start 337.640168 -51.13782)
						(mid 337.492386 -51.058018)
						(end 337.412584 -50.910236)
					)
				)
			)
		)
		(zone
			(layer "F.Cu")
			(hatch none 0.5)
			(connect_pads
				(clearance 0)
			)
			(min_thickness 0.25)
			(keepout
				(tracks not_allowed)
				(vias allowed)
				(pads allowed)
				(copperpour not_allowed)
				(footprints allowed)
			)
			(placement
				(enabled no)
				(sheetname "")
			)
			(fill
				(thermal_gap 0.5)
				(thermal_bridge_width 0.5)
				(island_removal_mode 0)
			)
			(polygon
				(pts
					(arc
						(start 337.51774 -50.110136)
						(mid 337.564341 -50.185963)
						(end 337.640168 -50.232564)
					)
					(arc
						(start 337.640168 -50.33772)
						(mid 337.492386 -50.257918)
						(end 337.412584 -50.110136)
					)
				)
			)
		)
		(zone
			(layer "F.Cu")
			(hatch none 0.5)
			(connect_pads
				(clearance 0)
			)
			(min_thickness 0.25)
			(keepout
				(tracks not_allowed)
				(vias allowed)
				(pads allowed)
				(copperpour not_allowed)
				(footprints allowed)
			)
			(placement
				(enabled no)
				(sheetname "")
			)
			(fill
				(thermal_gap 0.5)
				(thermal_bridge_width 0.5)
				(island_removal_mode 0)
			)
			(polygon
				(pts
					(arc
						(start 337.51774 -49.310036)
						(mid 337.564341 -49.385863)
						(end 337.640168 -49.432464)
					)
					(arc
						(start 337.640168 -49.53762)
						(mid 337.492386 -49.457818)
						(end 337.412584 -49.310036)
					)
				)
			)
		)
		(zone
			(layer "F.Cu")
			(hatch none 0.5)
			(connect_pads
				(clearance 0)
			)
			(min_thickness 0.25)
			(keepout
				(tracks not_allowed)
				(vias allowed)
				(pads allowed)
				(copperpour not_allowed)
				(footprints allowed)
			)
			(placement
				(enabled no)
				(sheetname "")
			)
			(fill
				(thermal_gap 0.5)
				(thermal_bridge_width 0.5)
				(island_removal_mode 0)
			)
			(polygon
				(pts
					(arc
						(start 337.51774 -48.509936)
						(mid 337.564341 -48.585763)
						(end 337.640168 -48.632364)
					)
					(arc
						(start 337.640168 -48.73752)
						(mid 337.492386 -48.657718)
						(end 337.412584 -48.509936)
					)
				)
			)
		)
		(zone
			(layer "F.Cu")
			(hatch none 0.5)
			(connect_pads
				(clearance 0)
			)
			(min_thickness 0.25)
			(keepout
				(tracks not_allowed)
				(vias allowed)
				(pads allowed)
				(copperpour not_allowed)
				(footprints allowed)
			)
			(placement
				(enabled no)
				(sheetname "")
			)
			(fill
				(thermal_gap 0.5)
				(thermal_bridge_width 0.5)
				(island_removal_mode 0)
			)
			(polygon
				(pts
					(arc
						(start 337.51774 -47.709836)
						(mid 337.564341 -47.785663)
						(end 337.640168 -47.832264)
					)
					(arc
						(start 337.640168 -47.93742)
						(mid 337.492386 -47.857618)
						(end 337.412584 -47.709836)
					)
				)
			)
		)
		(zone
			(layer "F.Cu")
			(hatch none 0.5)
			(connect_pads
				(clearance 0)
			)
			(min_thickness 0.25)
			(keepout
				(tracks not_allowed)
				(vias allowed)
				(pads allowed)
				(copperpour not_allowed)
				(footprints allowed)
			)
			(placement
				(enabled no)
				(sheetname "")
			)
			(fill
				(thermal_gap 0.5)
				(thermal_bridge_width 0.5)
				(island_removal_mode 0)
			)
			(polygon
				(pts
					(arc
						(start 337.51774 -46.909736)
						(mid 337.564341 -46.985563)
						(end 337.640168 -47.032164)
					)
					(arc
						(start 337.640168 -47.13732)
						(mid 337.492386 -47.057518)
						(end 337.412584 -46.909736)
					)
				)
			)
		)
		(zone
			(layer "F.Cu")
			(hatch none 0.5)
			(connect_pads
				(clearance 0)
			)
			(min_thickness 0.25)
			(keepout
				(tracks not_allowed)
				(vias allowed)
				(pads allowed)
				(copperpour not_allowed)
				(footprints allowed)
			)
			(placement
				(enabled no)
				(sheetname "")
			)
			(fill
				(thermal_gap 0.5)
				(thermal_bridge_width 0.5)
				(island_removal_mode 0)
			)
			(polygon
				(pts
					(arc
						(start 337.51774 -46.109636)
						(mid 337.564341 -46.185463)
						(end 337.640168 -46.232064)
					)
					(arc
						(start 337.640168 -46.33722)
						(mid 337.492386 -46.257418)
						(end 337.412584 -46.109636)
					)
				)
			)
		)
		(zone
			(layer "F.Cu")
			(hatch none 0.5)
			(connect_pads
				(clearance 0)
			)
			(min_thickness 0.25)
			(keepout
				(tracks not_allowed)
				(vias allowed)
				(pads allowed)
				(copperpour not_allowed)
				(footprints allowed)
			)
			(placement
				(enabled no)
				(sheetname "")
			)
			(fill
				(thermal_gap 0.5)
				(thermal_bridge_width 0.5)
				(island_removal_mode 0)
			)
			(polygon
				(pts
					(arc
						(start 337.51774 -45.309536)
						(mid 337.564341 -45.385363)
						(end 337.640168 -45.431964)
					)
					(arc
						(start 337.640168 -45.53712)
						(mid 337.492386 -45.457318)
						(end 337.412584 -45.309536)
					)
				)
			)
		)
		(zone
			(layer "F.Cu")
			(hatch none 0.5)
			(connect_pads
				(clearance 0)
			)
			(min_thickness 0.25)
			(keepout
				(tracks not_allowed)
				(vias allowed)
				(pads allowed)
				(copperpour not_allowed)
				(footprints allowed)
			)
			(placement
				(enabled no)
				(sheetname "")
			)
			(fill
				(thermal_gap 0.5)
				(thermal_bridge_width 0.5)
				(island_removal_mode 0)
			)
			(polygon
				(pts
					(arc
						(start 337.640168 -51.468528)
						(mid 337.564341 -51.515129)
						(end 337.51774 -51.590956)
					)
					(arc
						(start 337.412584 -51.590956)
						(mid 337.492386 -51.443174)
						(end 337.640168 -51.363372)
					)
				)
			)
		)
		(zone
			(layer "F.Cu")
			(hatch none 0.5)
			(connect_pads
				(clearance 0)
			)
			(min_thickness 0.25)
			(keepout
				(tracks not_allowed)
				(vias allowed)
				(pads allowed)
				(copperpour not_allowed)
				(footprints allowed)
			)
			(placement
				(enabled no)
				(sheetname "")
			)
			(fill
				(thermal_gap 0.5)
				(thermal_bridge_width 0.5)
				(island_removal_mode 0)
			)
			(polygon
				(pts
					(arc
						(start 337.640168 -50.668428)
						(mid 337.564341 -50.715029)
						(end 337.51774 -50.790856)
					)
					(arc
						(start 337.412584 -50.790856)
						(mid 337.492386 -50.643074)
						(end 337.640168 -50.563272)
					)
				)
			)
		)
		(zone
			(layer "F.Cu")
			(hatch none 0.5)
			(connect_pads
				(clearance 0)
			)
			(min_thickness 0.25)
			(keepout
				(tracks not_allowed)
				(vias allowed)
				(pads allowed)
				(copperpour not_allowed)
				(footprints allowed)
			)
			(placement
				(enabled no)
				(sheetname "")
			)
			(fill
				(thermal_gap 0.5)
				(thermal_bridge_width 0.5)
				(island_removal_mode 0)
			)
			(polygon
				(pts
					(arc
						(start 337.640168 -49.868328)
						(mid 337.564341 -49.914929)
						(end 337.51774 -49.990756)
					)
					(arc
						(start 337.412584 -49.990756)
						(mid 337.492386 -49.842974)
						(end 337.640168 -49.763172)
					)
				)
			)
		)
		(zone
			(layer "F.Cu")
			(hatch none 0.5)
			(connect_pads
				(clearance 0)
			)
			(min_thickness 0.25)
			(keepout
				(tracks not_allowed)
				(vias allowed)
				(pads allowed)
				(copperpour not_allowed)
				(footprints allowed)
			)
			(placement
				(enabled no)
				(sheetname "")
			)
			(fill
				(thermal_gap 0.5)
				(thermal_bridge_width 0.5)
				(island_removal_mode 0)
			)
			(polygon
				(pts
					(arc
						(start 337.640168 -49.068228)
						(mid 337.564341 -49.114829)
						(end 337.51774 -49.190656)
					)
					(arc
						(start 337.412584 -49.190656)
						(mid 337.492386 -49.042874)
						(end 337.640168 -48.963072)
					)
				)
			)
		)
		(zone
			(layer "F.Cu")
			(hatch none 0.5)
			(connect_pads
				(clearance 0)
			)
			(min_thickness 0.25)
			(keepout
				(tracks not_allowed)
				(vias allowed)
				(pads allowed)
				(copperpour not_allowed)
				(footprints allowed)
			)
			(placement
				(enabled no)
				(sheetname "")
			)
			(fill
				(thermal_gap 0.5)
				(thermal_bridge_width 0.5)
				(island_removal_mode 0)
			)
			(polygon
				(pts
					(arc
						(start 337.640168 -48.268128)
						(mid 337.564341 -48.314729)
						(end 337.51774 -48.390556)
					)
					(arc
						(start 337.412584 -48.390556)
						(mid 337.492386 -48.242774)
						(end 337.640168 -48.162972)
					)
				)
			)
		)
		(zone
			(layer "F.Cu")
			(hatch none 0.5)
			(connect_pads
				(clearance 0)
			)
			(min_thickness 0.25)
			(keepout
				(tracks not_allowed)
				(vias allowed)
				(pads allowed)
				(copperpour not_allowed)
				(footprints allowed)
			)
			(placement
				(enabled no)
				(sheetname "")
			)
			(fill
				(thermal_gap 0.5)
				(thermal_bridge_width 0.5)
				(island_removal_mode 0)
			)
			(polygon
				(pts
					(arc
						(start 337.640168 -47.468028)
						(mid 337.564341 -47.514629)
						(end 337.51774 -47.590456)
					)
					(arc
						(start 337.412584 -47.590456)
						(mid 337.492386 -47.442674)
						(end 337.640168 -47.362872)
					)
				)
			)
		)
		(zone
			(layer "F.Cu")
			(hatch none 0.5)
			(connect_pads
				(clearance 0)
			)
			(min_thickness 0.25)
			(keepout
				(tracks not_allowed)
				(vias allowed)
				(pads allowed)
				(copperpour not_allowed)
				(footprints allowed)
			)
			(placement
				(enabled no)
				(sheetname "")
			)
			(fill
				(thermal_gap 0.5)
				(thermal_bridge_width 0.5)
				(island_removal_mode 0)
			)
			(polygon
				(pts
					(arc
						(start 337.640168 -46.667928)
						(mid 337.564341 -46.714529)
						(end 337.51774 -46.790356)
					)
					(arc
						(start 337.412584 -46.790356)
						(mid 337.492386 -46.642574)
						(end 337.640168 -46.562772)
					)
				)
			)
		)
		(zone
			(layer "F.Cu")
			(hatch none 0.5)
			(connect_pads
				(clearance 0)
			)
			(min_thickness 0.25)
			(keepout
				(tracks not_allowed)
				(vias allowed)
				(pads allowed)
				(copperpour not_allowed)
				(footprints allowed)
			)
			(placement
				(enabled no)
				(sheetname "")
			)
			(fill
				(thermal_gap 0.5)
				(thermal_bridge_width 0.5)
				(island_removal_mode 0)
			)
			(polygon
				(pts
					(arc
						(start 337.640168 -45.867828)
						(mid 337.564341 -45.914429)
						(end 337.51774 -45.990256)
					)
					(arc
						(start 337.412584 -45.990256)
						(mid 337.492386 -45.842474)
						(end 337.640168 -45.762672)
					)
				)
			)
		)
		(zone
			(layer "F.Cu")
			(hatch none 0.5)
			(connect_pads
				(clearance 0)
			)
			(min_thickness 0.25)
			(keepout
				(tracks not_allowed)
				(vias allowed)
				(pads allowed)
				(copperpour not_allowed)
				(footprints allowed)
			)
			(placement
				(enabled no)
				(sheetname "")
			)
			(fill
				(thermal_gap 0.5)
				(thermal_bridge_width 0.5)
				(island_removal_mode 0)
			)
			(polygon
				(pts
					(arc
						(start 337.640168 -45.067728)
						(mid 337.564341 -45.114329)
						(end 337.51774 -45.190156)
					)
					(arc
						(start 337.412584 -45.190156)
						(mid 337.492386 -45.042374)
						(end 337.640168 -44.962572)
					)
				)
			)
		)
		(zone
			(layer "F.Cu")
			(hatch none 0.5)
			(connect_pads
				(clearance 0)
			)
			(min_thickness 0.25)
			(keepout
				(tracks not_allowed)
				(vias allowed)
				(pads allowed)
				(copperpour not_allowed)
				(footprints allowed)
			)
			(placement
				(enabled no)
				(sheetname "")
			)
			(fill
				(thermal_gap 0.5)
				(thermal_bridge_width 0.5)
				(island_removal_mode 0)
			)
			(polygon
				(pts
					(arc
						(start 337.759548 -51.832764)
						(mid 337.835375 -51.786163)
						(end 337.881976 -51.710336)
					)
					(arc
						(start 337.987132 -51.710336)
						(mid 337.90733 -51.858118)
						(end 337.759548 -51.93792)
					)
				)
			)
		)
		(zone
			(layer "F.Cu")
			(hatch none 0.5)
			(connect_pads
				(clearance 0)
			)
			(min_thickness 0.25)
			(keepout
				(tracks not_allowed)
				(vias allowed)
				(pads allowed)
				(copperpour not_allowed)
				(footprints allowed)
			)
			(placement
				(enabled no)
				(sheetname "")
			)
			(fill
				(thermal_gap 0.5)
				(thermal_bridge_width 0.5)
				(island_removal_mode 0)
			)
			(polygon
				(pts
					(arc
						(start 337.759548 -51.032664)
						(mid 337.835375 -50.986063)
						(end 337.881976 -50.910236)
					)
					(arc
						(start 337.987132 -50.910236)
						(mid 337.90733 -51.058018)
						(end 337.759548 -51.13782)
					)
				)
			)
		)
		(zone
			(layer "F.Cu")
			(hatch none 0.5)
			(connect_pads
				(clearance 0)
			)
			(min_thickness 0.25)
			(keepout
				(tracks not_allowed)
				(vias allowed)
				(pads allowed)
				(copperpour not_allowed)
				(footprints allowed)
			)
			(placement
				(enabled no)
				(sheetname "")
			)
			(fill
				(thermal_gap 0.5)
				(thermal_bridge_width 0.5)
				(island_removal_mode 0)
			)
			(polygon
				(pts
					(arc
						(start 337.759548 -50.232564)
						(mid 337.835375 -50.185963)
						(end 337.881976 -50.110136)
					)
					(arc
						(start 337.987132 -50.110136)
						(mid 337.90733 -50.257918)
						(end 337.759548 -50.33772)
					)
				)
			)
		)
		(zone
			(layer "F.Cu")
			(hatch none 0.5)
			(connect_pads
				(clearance 0)
			)
			(min_thickness 0.25)
			(keepout
				(tracks not_allowed)
				(vias allowed)
				(pads allowed)
				(copperpour not_allowed)
				(footprints allowed)
			)
			(placement
				(enabled no)
				(sheetname "")
			)
			(fill
				(thermal_gap 0.5)
				(thermal_bridge_width 0.5)
				(island_removal_mode 0)
			)
			(polygon
				(pts
					(arc
						(start 337.759548 -49.432464)
						(mid 337.835375 -49.385863)
						(end 337.881976 -49.310036)
					)
					(arc
						(start 337.987132 -49.310036)
						(mid 337.90733 -49.457818)
						(end 337.759548 -49.53762)
					)
				)
			)
		)
		(zone
			(layer "F.Cu")
			(hatch none 0.5)
			(connect_pads
				(clearance 0)
			)
			(min_thickness 0.25)
			(keepout
				(tracks not_allowed)
				(vias allowed)
				(pads allowed)
				(copperpour not_allowed)
				(footprints allowed)
			)
			(placement
				(enabled no)
				(sheetname "")
			)
			(fill
				(thermal_gap 0.5)
				(thermal_bridge_width 0.5)
				(island_removal_mode 0)
			)
			(polygon
				(pts
					(arc
						(start 337.759548 -48.632364)
						(mid 337.835375 -48.585763)
						(end 337.881976 -48.509936)
					)
					(arc
						(start 337.987132 -48.509936)
						(mid 337.90733 -48.657718)
						(end 337.759548 -48.73752)
					)
				)
			)
		)
		(zone
			(layer "F.Cu")
			(hatch none 0.5)
			(connect_pads
				(clearance 0)
			)
			(min_thickness 0.25)
			(keepout
				(tracks not_allowed)
				(vias allowed)
				(pads allowed)
				(copperpour not_allowed)
				(footprints allowed)
			)
			(placement
				(enabled no)
				(sheetname "")
			)
			(fill
				(thermal_gap 0.5)
				(thermal_bridge_width 0.5)
				(island_removal_mode 0)
			)
			(polygon
				(pts
					(arc
						(start 337.759548 -47.832264)
						(mid 337.835375 -47.785663)
						(end 337.881976 -47.709836)
					)
					(arc
						(start 337.987132 -47.709836)
						(mid 337.90733 -47.857618)
						(end 337.759548 -47.93742)
					)
				)
			)
		)
		(zone
			(layer "F.Cu")
			(hatch none 0.5)
			(connect_pads
				(clearance 0)
			)
			(min_thickness 0.25)
			(keepout
				(tracks not_allowed)
				(vias allowed)
				(pads allowed)
				(copperpour not_allowed)
				(footprints allowed)
			)
			(placement
				(enabled no)
				(sheetname "")
			)
			(fill
				(thermal_gap 0.5)
				(thermal_bridge_width 0.5)
				(island_removal_mode 0)
			)
			(polygon
				(pts
					(arc
						(start 337.759548 -47.032164)
						(mid 337.835375 -46.985563)
						(end 337.881976 -46.909736)
					)
					(arc
						(start 337.987132 -46.909736)
						(mid 337.90733 -47.057518)
						(end 337.759548 -47.13732)
					)
				)
			)
		)
		(zone
			(layer "F.Cu")
			(hatch none 0.5)
			(connect_pads
				(clearance 0)
			)
			(min_thickness 0.25)
			(keepout
				(tracks not_allowed)
				(vias allowed)
				(pads allowed)
				(copperpour not_allowed)
				(footprints allowed)
			)
			(placement
				(enabled no)
				(sheetname "")
			)
			(fill
				(thermal_gap 0.5)
				(thermal_bridge_width 0.5)
				(island_removal_mode 0)
			)
			(polygon
				(pts
					(arc
						(start 337.759548 -46.232064)
						(mid 337.835375 -46.185463)
						(end 337.881976 -46.109636)
					)
					(arc
						(start 337.987132 -46.109636)
						(mid 337.90733 -46.257418)
						(end 337.759548 -46.33722)
					)
				)
			)
		)
		(zone
			(layer "F.Cu")
			(hatch none 0.5)
			(connect_pads
				(clearance 0)
			)
			(min_thickness 0.25)
			(keepout
				(tracks not_allowed)
				(vias allowed)
				(pads allowed)
				(copperpour not_allowed)
				(footprints allowed)
			)
			(placement
				(enabled no)
				(sheetname "")
			)
			(fill
				(thermal_gap 0.5)
				(thermal_bridge_width 0.5)
				(island_removal_mode 0)
			)
			(polygon
				(pts
					(arc
						(start 337.759548 -45.431964)
						(mid 337.835375 -45.385363)
						(end 337.881976 -45.309536)
					)
					(arc
						(start 337.987132 -45.309536)
						(mid 337.90733 -45.457318)
						(end 337.759548 -45.53712)
					)
				)
			)
		)
		(zone
			(layer "F.Cu")
			(hatch none 0.5)
			(connect_pads
				(clearance 0)
			)
			(min_thickness 0.25)
			(keepout
				(tracks not_allowed)
				(vias allowed)
				(pads allowed)
				(copperpour not_allowed)
				(footprints allowed)
			)
			(placement
				(enabled no)
				(sheetname "")
			)
			(fill
				(thermal_gap 0.5)
				(thermal_bridge_width 0.5)
				(island_removal_mode 0)
			)
			(polygon
				(pts
					(arc
						(start 337.881976 -51.590956)
						(mid 337.835375 -51.515129)
						(end 337.759548 -51.468528)
					)
					(arc
						(start 337.759548 -51.363372)
						(mid 337.90733 -51.443174)
						(end 337.987132 -51.590956)
					)
				)
			)
		)
		(zone
			(layer "F.Cu")
			(hatch none 0.5)
			(connect_pads
				(clearance 0)
			)
			(min_thickness 0.25)
			(keepout
				(tracks not_allowed)
				(vias allowed)
				(pads allowed)
				(copperpour not_allowed)
				(footprints allowed)
			)
			(placement
				(enabled no)
				(sheetname "")
			)
			(fill
				(thermal_gap 0.5)
				(thermal_bridge_width 0.5)
				(island_removal_mode 0)
			)
			(polygon
				(pts
					(arc
						(start 337.881976 -50.790856)
						(mid 337.835375 -50.715029)
						(end 337.759548 -50.668428)
					)
					(arc
						(start 337.759548 -50.563272)
						(mid 337.90733 -50.643074)
						(end 337.987132 -50.790856)
					)
				)
			)
		)
		(zone
			(layer "F.Cu")
			(hatch none 0.5)
			(connect_pads
				(clearance 0)
			)
			(min_thickness 0.25)
			(keepout
				(tracks not_allowed)
				(vias allowed)
				(pads allowed)
				(copperpour not_allowed)
				(footprints allowed)
			)
			(placement
				(enabled no)
				(sheetname "")
			)
			(fill
				(thermal_gap 0.5)
				(thermal_bridge_width 0.5)
				(island_removal_mode 0)
			)
			(polygon
				(pts
					(arc
						(start 337.881976 -49.990756)
						(mid 337.835375 -49.914929)
						(end 337.759548 -49.868328)
					)
					(arc
						(start 337.759548 -49.763172)
						(mid 337.90733 -49.842974)
						(end 337.987132 -49.990756)
					)
				)
			)
		)
		(zone
			(layer "F.Cu")
			(hatch none 0.5)
			(connect_pads
				(clearance 0)
			)
			(min_thickness 0.25)
			(keepout
				(tracks not_allowed)
				(vias allowed)
				(pads allowed)
				(copperpour not_allowed)
				(footprints allowed)
			)
			(placement
				(enabled no)
				(sheetname "")
			)
			(fill
				(thermal_gap 0.5)
				(thermal_bridge_width 0.5)
				(island_removal_mode 0)
			)
			(polygon
				(pts
					(arc
						(start 337.881976 -49.190656)
						(mid 337.835375 -49.114829)
						(end 337.759548 -49.068228)
					)
					(arc
						(start 337.759548 -48.963072)
						(mid 337.90733 -49.042874)
						(end 337.987132 -49.190656)
					)
				)
			)
		)
		(zone
			(layer "F.Cu")
			(hatch none 0.5)
			(connect_pads
				(clearance 0)
			)
			(min_thickness 0.25)
			(keepout
				(tracks not_allowed)
				(vias allowed)
				(pads allowed)
				(copperpour not_allowed)
				(footprints allowed)
			)
			(placement
				(enabled no)
				(sheetname "")
			)
			(fill
				(thermal_gap 0.5)
				(thermal_bridge_width 0.5)
				(island_removal_mode 0)
			)
			(polygon
				(pts
					(arc
						(start 337.881976 -48.390556)
						(mid 337.835375 -48.314729)
						(end 337.759548 -48.268128)
					)
					(arc
						(start 337.759548 -48.162972)
						(mid 337.90733 -48.242774)
						(end 337.987132 -48.390556)
					)
				)
			)
		)
		(zone
			(layer "F.Cu")
			(hatch none 0.5)
			(connect_pads
				(clearance 0)
			)
			(min_thickness 0.25)
			(keepout
				(tracks not_allowed)
				(vias allowed)
				(pads allowed)
				(copperpour not_allowed)
				(footprints allowed)
			)
			(placement
				(enabled no)
				(sheetname "")
			)
			(fill
				(thermal_gap 0.5)
				(thermal_bridge_width 0.5)
				(island_removal_mode 0)
			)
			(polygon
				(pts
					(arc
						(start 337.881976 -47.590456)
						(mid 337.835375 -47.514629)
						(end 337.759548 -47.468028)
					)
					(arc
						(start 337.759548 -47.362872)
						(mid 337.90733 -47.442674)
						(end 337.987132 -47.590456)
					)
				)
			)
		)
		(zone
			(layer "F.Cu")
			(hatch none 0.5)
			(connect_pads
				(clearance 0)
			)
			(min_thickness 0.25)
			(keepout
				(tracks not_allowed)
				(vias allowed)
				(pads allowed)
				(copperpour not_allowed)
				(footprints allowed)
			)
			(placement
				(enabled no)
				(sheetname "")
			)
			(fill
				(thermal_gap 0.5)
				(thermal_bridge_width 0.5)
				(island_removal_mode 0)
			)
			(polygon
				(pts
					(arc
						(start 337.881976 -46.790356)
						(mid 337.835375 -46.714529)
						(end 337.759548 -46.667928)
					)
					(arc
						(start 337.759548 -46.562772)
						(mid 337.90733 -46.642574)
						(end 337.987132 -46.790356)
					)
				)
			)
		)
		(zone
			(layer "F.Cu")
			(hatch none 0.5)
			(connect_pads
				(clearance 0)
			)
			(min_thickness 0.25)
			(keepout
				(tracks not_allowed)
				(vias allowed)
				(pads allowed)
				(copperpour not_allowed)
				(footprints allowed)
			)
			(placement
				(enabled no)
				(sheetname "")
			)
			(fill
				(thermal_gap 0.5)
				(thermal_bridge_width 0.5)
				(island_removal_mode 0)
			)
			(polygon
				(pts
					(arc
						(start 337.881976 -45.990256)
						(mid 337.835375 -45.914429)
						(end 337.759548 -45.867828)
					)
					(arc
						(start 337.759548 -45.762672)
						(mid 337.90733 -45.842474)
						(end 337.987132 -45.990256)
					)
				)
			)
		)
		(zone
			(layer "F.Cu")
			(hatch none 0.5)
			(connect_pads
				(clearance 0)
			)
			(min_thickness 0.25)
			(keepout
				(tracks not_allowed)
				(vias allowed)
				(pads allowed)
				(copperpour not_allowed)
				(footprints allowed)
			)
			(placement
				(enabled no)
				(sheetname "")
			)
			(fill
				(thermal_gap 0.5)
				(thermal_bridge_width 0.5)
				(island_removal_mode 0)
			)
			(polygon
				(pts
					(arc
						(start 337.881976 -45.190156)
						(mid 337.835375 -45.114329)
						(end 337.759548 -45.067728)
					)
					(arc
						(start 337.759548 -44.962572)
						(mid 337.90733 -45.042374)
						(end 337.987132 -45.190156)
					)
				)
			)
		)
		(zone
			(layer "F.Cu")
			(hatch none 0.5)
			(connect_pads
				(clearance 0)
			)
			(min_thickness 0.25)
			(keepout
				(tracks not_allowed)
				(vias allowed)
				(pads allowed)
				(copperpour not_allowed)
				(footprints allowed)
			)
			(placement
				(enabled no)
				(sheetname "")
			)
			(fill
				(thermal_gap 0.5)
				(thermal_bridge_width 0.5)
				(island_removal_mode 0)
			)
			(polygon
				(pts
					(arc
						(start 337.938872 -56.968136)
						(mid 337.985387 -57.043878)
						(end 338.061046 -57.090564)
					)
					(arc
						(start 338.061046 -57.19572)
						(mid 337.913264 -57.115918)
						(end 337.833462 -56.968136)
					)
				)
			)
		)
		(zone
			(layer "F.Cu")
			(hatch none 0.5)
			(connect_pads
				(clearance 0)
			)
			(min_thickness 0.25)
			(keepout
				(tracks not_allowed)
				(vias allowed)
				(pads allowed)
				(copperpour not_allowed)
				(footprints allowed)
			)
			(placement
				(enabled no)
				(sheetname "")
			)
			(fill
				(thermal_gap 0.5)
				(thermal_bridge_width 0.5)
				(island_removal_mode 0)
			)
			(polygon
				(pts
					(arc
						(start 337.938872 -56.028336)
						(mid 337.985387 -56.104078)
						(end 338.061046 -56.150764)
					)
					(arc
						(start 338.061046 -56.25592)
						(mid 337.913264 -56.176118)
						(end 337.833462 -56.028336)
					)
				)
			)
		)
		(zone
			(layer "F.Cu")
			(hatch none 0.5)
			(connect_pads
				(clearance 0)
			)
			(min_thickness 0.25)
			(keepout
				(tracks not_allowed)
				(vias allowed)
				(pads allowed)
				(copperpour not_allowed)
				(footprints allowed)
			)
			(placement
				(enabled no)
				(sheetname "")
			)
			(fill
				(thermal_gap 0.5)
				(thermal_bridge_width 0.5)
				(island_removal_mode 0)
			)
			(polygon
				(pts
					(arc
						(start 337.938872 -55.088536)
						(mid 337.985387 -55.164278)
						(end 338.061046 -55.210964)
					)
					(arc
						(start 338.061046 -55.31612)
						(mid 337.913264 -55.236318)
						(end 337.833462 -55.088536)
					)
				)
			)
		)
		(zone
			(layer "F.Cu")
			(hatch none 0.5)
			(connect_pads
				(clearance 0)
			)
			(min_thickness 0.25)
			(keepout
				(tracks not_allowed)
				(vias allowed)
				(pads allowed)
				(copperpour not_allowed)
				(footprints allowed)
			)
			(placement
				(enabled no)
				(sheetname "")
			)
			(fill
				(thermal_gap 0.5)
				(thermal_bridge_width 0.5)
				(island_removal_mode 0)
			)
			(polygon
				(pts
					(arc
						(start 337.938872 -54.148736)
						(mid 337.985387 -54.224478)
						(end 338.061046 -54.271164)
					)
					(arc
						(start 338.061046 -54.37632)
						(mid 337.913264 -54.296518)
						(end 337.833462 -54.148736)
					)
				)
			)
		)
		(zone
			(layer "F.Cu")
			(hatch none 0.5)
			(connect_pads
				(clearance 0)
			)
			(min_thickness 0.25)
			(keepout
				(tracks not_allowed)
				(vias allowed)
				(pads allowed)
				(copperpour not_allowed)
				(footprints allowed)
			)
			(placement
				(enabled no)
				(sheetname "")
			)
			(fill
				(thermal_gap 0.5)
				(thermal_bridge_width 0.5)
				(island_removal_mode 0)
			)
			(polygon
				(pts
					(arc
						(start 337.938872 -53.208936)
						(mid 337.985387 -53.284678)
						(end 338.061046 -53.331364)
					)
					(arc
						(start 338.061046 -53.43652)
						(mid 337.913264 -53.356718)
						(end 337.833462 -53.208936)
					)
				)
			)
		)
		(zone
			(layer "F.Cu")
			(hatch none 0.5)
			(connect_pads
				(clearance 0)
			)
			(min_thickness 0.25)
			(keepout
				(tracks not_allowed)
				(vias allowed)
				(pads allowed)
				(copperpour not_allowed)
				(footprints allowed)
			)
			(placement
				(enabled no)
				(sheetname "")
			)
			(fill
				(thermal_gap 0.5)
				(thermal_bridge_width 0.5)
				(island_removal_mode 0)
			)
			(polygon
				(pts
					(arc
						(start 337.938872 -43.810936)
						(mid 337.985387 -43.886678)
						(end 338.061046 -43.933364)
					)
					(arc
						(start 338.061046 -44.03852)
						(mid 337.913264 -43.958718)
						(end 337.833462 -43.810936)
					)
				)
			)
		)
		(zone
			(layer "F.Cu")
			(hatch none 0.5)
			(connect_pads
				(clearance 0)
			)
			(min_thickness 0.25)
			(keepout
				(tracks not_allowed)
				(vias allowed)
				(pads allowed)
				(copperpour not_allowed)
				(footprints allowed)
			)
			(placement
				(enabled no)
				(sheetname "")
			)
			(fill
				(thermal_gap 0.5)
				(thermal_bridge_width 0.5)
				(island_removal_mode 0)
			)
			(polygon
				(pts
					(arc
						(start 337.938872 -42.871136)
						(mid 337.985387 -42.946878)
						(end 338.061046 -42.993564)
					)
					(arc
						(start 338.061046 -43.09872)
						(mid 337.913264 -43.018918)
						(end 337.833462 -42.871136)
					)
				)
			)
		)
		(zone
			(layer "F.Cu")
			(hatch none 0.5)
			(connect_pads
				(clearance 0)
			)
			(min_thickness 0.25)
			(keepout
				(tracks not_allowed)
				(vias allowed)
				(pads allowed)
				(copperpour not_allowed)
				(footprints allowed)
			)
			(placement
				(enabled no)
				(sheetname "")
			)
			(fill
				(thermal_gap 0.5)
				(thermal_bridge_width 0.5)
				(island_removal_mode 0)
			)
			(polygon
				(pts
					(arc
						(start 337.938872 -41.931336)
						(mid 337.985387 -42.007078)
						(end 338.061046 -42.053764)
					)
					(arc
						(start 338.061046 -42.15892)
						(mid 337.913264 -42.079118)
						(end 337.833462 -41.931336)
					)
				)
			)
		)
		(zone
			(layer "F.Cu")
			(hatch none 0.5)
			(connect_pads
				(clearance 0)
			)
			(min_thickness 0.25)
			(keepout
				(tracks not_allowed)
				(vias allowed)
				(pads allowed)
				(copperpour not_allowed)
				(footprints allowed)
			)
			(placement
				(enabled no)
				(sheetname "")
			)
			(fill
				(thermal_gap 0.5)
				(thermal_bridge_width 0.5)
				(island_removal_mode 0)
			)
			(polygon
				(pts
					(arc
						(start 337.938872 -40.991536)
						(mid 337.985387 -41.067278)
						(end 338.061046 -41.113964)
					)
					(arc
						(start 338.061046 -41.21912)
						(mid 337.913264 -41.139318)
						(end 337.833462 -40.991536)
					)
				)
			)
		)
		(zone
			(layer "F.Cu")
			(hatch none 0.5)
			(connect_pads
				(clearance 0)
			)
			(min_thickness 0.25)
			(keepout
				(tracks not_allowed)
				(vias allowed)
				(pads allowed)
				(copperpour not_allowed)
				(footprints allowed)
			)
			(placement
				(enabled no)
				(sheetname "")
			)
			(fill
				(thermal_gap 0.5)
				(thermal_bridge_width 0.5)
				(island_removal_mode 0)
			)
			(polygon
				(pts
					(arc
						(start 337.938872 -40.051736)
						(mid 337.985387 -40.127478)
						(end 338.061046 -40.174164)
					)
					(arc
						(start 338.061046 -40.27932)
						(mid 337.913264 -40.199518)
						(end 337.833462 -40.051736)
					)
				)
			)
		)
		(zone
			(layer "F.Cu")
			(hatch none 0.5)
			(connect_pads
				(clearance 0)
			)
			(min_thickness 0.25)
			(keepout
				(tracks not_allowed)
				(vias allowed)
				(pads allowed)
				(copperpour not_allowed)
				(footprints allowed)
			)
			(placement
				(enabled no)
				(sheetname "")
			)
			(fill
				(thermal_gap 0.5)
				(thermal_bridge_width 0.5)
				(island_removal_mode 0)
			)
			(polygon
				(pts
					(arc
						(start 338.061046 -56.726328)
						(mid 337.985331 -56.772958)
						(end 337.938872 -56.848756)
					)
					(arc
						(start 337.833462 -56.848756)
						(mid 337.913264 -56.700974)
						(end 338.061046 -56.621172)
					)
				)
			)
		)
		(zone
			(layer "F.Cu")
			(hatch none 0.5)
			(connect_pads
				(clearance 0)
			)
			(min_thickness 0.25)
			(keepout
				(tracks not_allowed)
				(vias allowed)
				(pads allowed)
				(copperpour not_allowed)
				(footprints allowed)
			)
			(placement
				(enabled no)
				(sheetname "")
			)
			(fill
				(thermal_gap 0.5)
				(thermal_bridge_width 0.5)
				(island_removal_mode 0)
			)
			(polygon
				(pts
					(arc
						(start 338.061046 -55.786528)
						(mid 337.985331 -55.833158)
						(end 337.938872 -55.908956)
					)
					(arc
						(start 337.833462 -55.908956)
						(mid 337.913264 -55.761174)
						(end 338.061046 -55.681372)
					)
				)
			)
		)
		(zone
			(layer "F.Cu")
			(hatch none 0.5)
			(connect_pads
				(clearance 0)
			)
			(min_thickness 0.25)
			(keepout
				(tracks not_allowed)
				(vias allowed)
				(pads allowed)
				(copperpour not_allowed)
				(footprints allowed)
			)
			(placement
				(enabled no)
				(sheetname "")
			)
			(fill
				(thermal_gap 0.5)
				(thermal_bridge_width 0.5)
				(island_removal_mode 0)
			)
			(polygon
				(pts
					(arc
						(start 338.061046 -54.846728)
						(mid 337.985331 -54.893358)
						(end 337.938872 -54.969156)
					)
					(arc
						(start 337.833462 -54.969156)
						(mid 337.913264 -54.821374)
						(end 338.061046 -54.741572)
					)
				)
			)
		)
		(zone
			(layer "F.Cu")
			(hatch none 0.5)
			(connect_pads
				(clearance 0)
			)
			(min_thickness 0.25)
			(keepout
				(tracks not_allowed)
				(vias allowed)
				(pads allowed)
				(copperpour not_allowed)
				(footprints allowed)
			)
			(placement
				(enabled no)
				(sheetname "")
			)
			(fill
				(thermal_gap 0.5)
				(thermal_bridge_width 0.5)
				(island_removal_mode 0)
			)
			(polygon
				(pts
					(arc
						(start 338.061046 -53.906928)
						(mid 337.985331 -53.953558)
						(end 337.938872 -54.029356)
					)
					(arc
						(start 337.833462 -54.029356)
						(mid 337.913264 -53.881574)
						(end 338.061046 -53.801772)
					)
				)
			)
		)
		(zone
			(layer "F.Cu")
			(hatch none 0.5)
			(connect_pads
				(clearance 0)
			)
			(min_thickness 0.25)
			(keepout
				(tracks not_allowed)
				(vias allowed)
				(pads allowed)
				(copperpour not_allowed)
				(footprints allowed)
			)
			(placement
				(enabled no)
				(sheetname "")
			)
			(fill
				(thermal_gap 0.5)
				(thermal_bridge_width 0.5)
				(island_removal_mode 0)
			)
			(polygon
				(pts
					(arc
						(start 338.061046 -52.967128)
						(mid 337.985331 -53.013758)
						(end 337.938872 -53.089556)
					)
					(arc
						(start 337.833462 -53.089556)
						(mid 337.913264 -52.941774)
						(end 338.061046 -52.861972)
					)
				)
			)
		)
		(zone
			(layer "F.Cu")
			(hatch none 0.5)
			(connect_pads
				(clearance 0)
			)
			(min_thickness 0.25)
			(keepout
				(tracks not_allowed)
				(vias allowed)
				(pads allowed)
				(copperpour not_allowed)
				(footprints allowed)
			)
			(placement
				(enabled no)
				(sheetname "")
			)
			(fill
				(thermal_gap 0.5)
				(thermal_bridge_width 0.5)
				(island_removal_mode 0)
			)
			(polygon
				(pts
					(arc
						(start 338.061046 -43.569128)
						(mid 337.985331 -43.615758)
						(end 337.938872 -43.691556)
					)
					(arc
						(start 337.833462 -43.691556)
						(mid 337.913264 -43.543774)
						(end 338.061046 -43.463972)
					)
				)
			)
		)
		(zone
			(layer "F.Cu")
			(hatch none 0.5)
			(connect_pads
				(clearance 0)
			)
			(min_thickness 0.25)
			(keepout
				(tracks not_allowed)
				(vias allowed)
				(pads allowed)
				(copperpour not_allowed)
				(footprints allowed)
			)
			(placement
				(enabled no)
				(sheetname "")
			)
			(fill
				(thermal_gap 0.5)
				(thermal_bridge_width 0.5)
				(island_removal_mode 0)
			)
			(polygon
				(pts
					(arc
						(start 338.061046 -42.629328)
						(mid 337.985331 -42.675958)
						(end 337.938872 -42.751756)
					)
					(arc
						(start 337.833462 -42.751756)
						(mid 337.913264 -42.603974)
						(end 338.061046 -42.524172)
					)
				)
			)
		)
		(zone
			(layer "F.Cu")
			(hatch none 0.5)
			(connect_pads
				(clearance 0)
			)
			(min_thickness 0.25)
			(keepout
				(tracks not_allowed)
				(vias allowed)
				(pads allowed)
				(copperpour not_allowed)
				(footprints allowed)
			)
			(placement
				(enabled no)
				(sheetname "")
			)
			(fill
				(thermal_gap 0.5)
				(thermal_bridge_width 0.5)
				(island_removal_mode 0)
			)
			(polygon
				(pts
					(arc
						(start 338.061046 -41.689528)
						(mid 337.985331 -41.736158)
						(end 337.938872 -41.811956)
					)
					(arc
						(start 337.833462 -41.811956)
						(mid 337.913264 -41.664174)
						(end 338.061046 -41.584372)
					)
				)
			)
		)
		(zone
			(layer "F.Cu")
			(hatch none 0.5)
			(connect_pads
				(clearance 0)
			)
			(min_thickness 0.25)
			(keepout
				(tracks not_allowed)
				(vias allowed)
				(pads allowed)
				(copperpour not_allowed)
				(footprints allowed)
			)
			(placement
				(enabled no)
				(sheetname "")
			)
			(fill
				(thermal_gap 0.5)
				(thermal_bridge_width 0.5)
				(island_removal_mode 0)
			)
			(polygon
				(pts
					(arc
						(start 338.061046 -40.749728)
						(mid 337.985331 -40.796358)
						(end 337.938872 -40.872156)
					)
					(arc
						(start 337.833462 -40.872156)
						(mid 337.913264 -40.724374)
						(end 338.061046 -40.644572)
					)
				)
			)
		)
		(zone
			(layer "F.Cu")
			(hatch none 0.5)
			(connect_pads
				(clearance 0)
			)
			(min_thickness 0.25)
			(keepout
				(tracks not_allowed)
				(vias allowed)
				(pads allowed)
				(copperpour not_allowed)
				(footprints allowed)
			)
			(placement
				(enabled no)
				(sheetname "")
			)
			(fill
				(thermal_gap 0.5)
				(thermal_bridge_width 0.5)
				(island_removal_mode 0)
			)
			(polygon
				(pts
					(arc
						(start 338.061046 -39.809928)
						(mid 337.985331 -39.856558)
						(end 337.938872 -39.932356)
					)
					(arc
						(start 337.833462 -39.932356)
						(mid 337.913264 -39.784574)
						(end 338.061046 -39.704772)
					)
				)
			)
		)
		(zone
			(layer "F.Cu")
			(hatch none 0.5)
			(connect_pads
				(clearance 0)
			)
			(min_thickness 0.25)
			(keepout
				(tracks not_allowed)
				(vias allowed)
				(pads allowed)
				(copperpour not_allowed)
				(footprints allowed)
			)
			(placement
				(enabled no)
				(sheetname "")
			)
			(fill
				(thermal_gap 0.5)
				(thermal_bridge_width 0.5)
				(island_removal_mode 0)
			)
			(polygon
				(pts
					(arc
						(start 338.18068 -57.090564)
						(mid 338.256395 -57.043934)
						(end 338.302854 -56.968136)
					)
					(arc
						(start 338.408264 -56.968136)
						(mid 338.328462 -57.115918)
						(end 338.18068 -57.19572)
					)
				)
			)
		)
		(zone
			(layer "F.Cu")
			(hatch none 0.5)
			(connect_pads
				(clearance 0)
			)
			(min_thickness 0.25)
			(keepout
				(tracks not_allowed)
				(vias allowed)
				(pads allowed)
				(copperpour not_allowed)
				(footprints allowed)
			)
			(placement
				(enabled no)
				(sheetname "")
			)
			(fill
				(thermal_gap 0.5)
				(thermal_bridge_width 0.5)
				(island_removal_mode 0)
			)
			(polygon
				(pts
					(arc
						(start 338.18068 -56.150764)
						(mid 338.256395 -56.104134)
						(end 338.302854 -56.028336)
					)
					(arc
						(start 338.408264 -56.028336)
						(mid 338.328462 -56.176118)
						(end 338.18068 -56.25592)
					)
				)
			)
		)
		(zone
			(layer "F.Cu")
			(hatch none 0.5)
			(connect_pads
				(clearance 0)
			)
			(min_thickness 0.25)
			(keepout
				(tracks not_allowed)
				(vias allowed)
				(pads allowed)
				(copperpour not_allowed)
				(footprints allowed)
			)
			(placement
				(enabled no)
				(sheetname "")
			)
			(fill
				(thermal_gap 0.5)
				(thermal_bridge_width 0.5)
				(island_removal_mode 0)
			)
			(polygon
				(pts
					(arc
						(start 338.18068 -55.210964)
						(mid 338.256395 -55.164334)
						(end 338.302854 -55.088536)
					)
					(arc
						(start 338.408264 -55.088536)
						(mid 338.328462 -55.236318)
						(end 338.18068 -55.31612)
					)
				)
			)
		)
		(zone
			(layer "F.Cu")
			(hatch none 0.5)
			(connect_pads
				(clearance 0)
			)
			(min_thickness 0.25)
			(keepout
				(tracks not_allowed)
				(vias allowed)
				(pads allowed)
				(copperpour not_allowed)
				(footprints allowed)
			)
			(placement
				(enabled no)
				(sheetname "")
			)
			(fill
				(thermal_gap 0.5)
				(thermal_bridge_width 0.5)
				(island_removal_mode 0)
			)
			(polygon
				(pts
					(arc
						(start 338.18068 -54.271164)
						(mid 338.256395 -54.224534)
						(end 338.302854 -54.148736)
					)
					(arc
						(start 338.408264 -54.148736)
						(mid 338.328462 -54.296518)
						(end 338.18068 -54.37632)
					)
				)
			)
		)
		(zone
			(layer "F.Cu")
			(hatch none 0.5)
			(connect_pads
				(clearance 0)
			)
			(min_thickness 0.25)
			(keepout
				(tracks not_allowed)
				(vias allowed)
				(pads allowed)
				(copperpour not_allowed)
				(footprints allowed)
			)
			(placement
				(enabled no)
				(sheetname "")
			)
			(fill
				(thermal_gap 0.5)
				(thermal_bridge_width 0.5)
				(island_removal_mode 0)
			)
			(polygon
				(pts
					(arc
						(start 338.18068 -53.331364)
						(mid 338.256395 -53.284734)
						(end 338.302854 -53.208936)
					)
					(arc
						(start 338.408264 -53.208936)
						(mid 338.328462 -53.356718)
						(end 338.18068 -53.43652)
					)
				)
			)
		)
		(zone
			(layer "F.Cu")
			(hatch none 0.5)
			(connect_pads
				(clearance 0)
			)
			(min_thickness 0.25)
			(keepout
				(tracks not_allowed)
				(vias allowed)
				(pads allowed)
				(copperpour not_allowed)
				(footprints allowed)
			)
			(placement
				(enabled no)
				(sheetname "")
			)
			(fill
				(thermal_gap 0.5)
				(thermal_bridge_width 0.5)
				(island_removal_mode 0)
			)
			(polygon
				(pts
					(arc
						(start 338.18068 -43.933364)
						(mid 338.256395 -43.886734)
						(end 338.302854 -43.810936)
					)
					(arc
						(start 338.408264 -43.810936)
						(mid 338.328462 -43.958718)
						(end 338.18068 -44.03852)
					)
				)
			)
		)
		(zone
			(layer "F.Cu")
			(hatch none 0.5)
			(connect_pads
				(clearance 0)
			)
			(min_thickness 0.25)
			(keepout
				(tracks not_allowed)
				(vias allowed)
				(pads allowed)
				(copperpour not_allowed)
				(footprints allowed)
			)
			(placement
				(enabled no)
				(sheetname "")
			)
			(fill
				(thermal_gap 0.5)
				(thermal_bridge_width 0.5)
				(island_removal_mode 0)
			)
			(polygon
				(pts
					(arc
						(start 338.18068 -42.993564)
						(mid 338.256395 -42.946934)
						(end 338.302854 -42.871136)
					)
					(arc
						(start 338.408264 -42.871136)
						(mid 338.328462 -43.018918)
						(end 338.18068 -43.09872)
					)
				)
			)
		)
		(zone
			(layer "F.Cu")
			(hatch none 0.5)
			(connect_pads
				(clearance 0)
			)
			(min_thickness 0.25)
			(keepout
				(tracks not_allowed)
				(vias allowed)
				(pads allowed)
				(copperpour not_allowed)
				(footprints allowed)
			)
			(placement
				(enabled no)
				(sheetname "")
			)
			(fill
				(thermal_gap 0.5)
				(thermal_bridge_width 0.5)
				(island_removal_mode 0)
			)
			(polygon
				(pts
					(arc
						(start 338.18068 -42.053764)
						(mid 338.256395 -42.007134)
						(end 338.302854 -41.931336)
					)
					(arc
						(start 338.408264 -41.931336)
						(mid 338.328462 -42.079118)
						(end 338.18068 -42.15892)
					)
				)
			)
		)
		(zone
			(layer "F.Cu")
			(hatch none 0.5)
			(connect_pads
				(clearance 0)
			)
			(min_thickness 0.25)
			(keepout
				(tracks not_allowed)
				(vias allowed)
				(pads allowed)
				(copperpour not_allowed)
				(footprints allowed)
			)
			(placement
				(enabled no)
				(sheetname "")
			)
			(fill
				(thermal_gap 0.5)
				(thermal_bridge_width 0.5)
				(island_removal_mode 0)
			)
			(polygon
				(pts
					(arc
						(start 338.18068 -41.113964)
						(mid 338.256395 -41.067334)
						(end 338.302854 -40.991536)
					)
					(arc
						(start 338.408264 -40.991536)
						(mid 338.328462 -41.139318)
						(end 338.18068 -41.21912)
					)
				)
			)
		)
		(zone
			(layer "F.Cu")
			(hatch none 0.5)
			(connect_pads
				(clearance 0)
			)
			(min_thickness 0.25)
			(keepout
				(tracks not_allowed)
				(vias allowed)
				(pads allowed)
				(copperpour not_allowed)
				(footprints allowed)
			)
			(placement
				(enabled no)
				(sheetname "")
			)
			(fill
				(thermal_gap 0.5)
				(thermal_bridge_width 0.5)
				(island_removal_mode 0)
			)
			(polygon
				(pts
					(arc
						(start 338.18068 -40.174164)
						(mid 338.256395 -40.127534)
						(end 338.302854 -40.051736)
					)
					(arc
						(start 338.408264 -40.051736)
						(mid 338.328462 -40.199518)
						(end 338.18068 -40.27932)
					)
				)
			)
		)
		(zone
			(layer "F.Cu")
			(hatch none 0.5)
			(connect_pads
				(clearance 0)
			)
			(min_thickness 0.25)
			(keepout
				(tracks not_allowed)
				(vias allowed)
				(pads allowed)
				(copperpour not_allowed)
				(footprints allowed)
			)
			(placement
				(enabled no)
				(sheetname "")
			)
			(fill
				(thermal_gap 0.5)
				(thermal_bridge_width 0.5)
				(island_removal_mode 0)
			)
			(polygon
				(pts
					(arc
						(start 338.302854 -56.848756)
						(mid 338.256339 -56.773014)
						(end 338.18068 -56.726328)
					)
					(arc
						(start 338.18068 -56.621172)
						(mid 338.328462 -56.700974)
						(end 338.408264 -56.848756)
					)
				)
			)
		)
		(zone
			(layer "F.Cu")
			(hatch none 0.5)
			(connect_pads
				(clearance 0)
			)
			(min_thickness 0.25)
			(keepout
				(tracks not_allowed)
				(vias allowed)
				(pads allowed)
				(copperpour not_allowed)
				(footprints allowed)
			)
			(placement
				(enabled no)
				(sheetname "")
			)
			(fill
				(thermal_gap 0.5)
				(thermal_bridge_width 0.5)
				(island_removal_mode 0)
			)
			(polygon
				(pts
					(arc
						(start 338.302854 -55.908956)
						(mid 338.256339 -55.833214)
						(end 338.18068 -55.786528)
					)
					(arc
						(start 338.18068 -55.681372)
						(mid 338.328462 -55.761174)
						(end 338.408264 -55.908956)
					)
				)
			)
		)
		(zone
			(layer "F.Cu")
			(hatch none 0.5)
			(connect_pads
				(clearance 0)
			)
			(min_thickness 0.25)
			(keepout
				(tracks not_allowed)
				(vias allowed)
				(pads allowed)
				(copperpour not_allowed)
				(footprints allowed)
			)
			(placement
				(enabled no)
				(sheetname "")
			)
			(fill
				(thermal_gap 0.5)
				(thermal_bridge_width 0.5)
				(island_removal_mode 0)
			)
			(polygon
				(pts
					(arc
						(start 338.302854 -54.969156)
						(mid 338.256339 -54.893414)
						(end 338.18068 -54.846728)
					)
					(arc
						(start 338.18068 -54.741572)
						(mid 338.328462 -54.821374)
						(end 338.408264 -54.969156)
					)
				)
			)
		)
		(zone
			(layer "F.Cu")
			(hatch none 0.5)
			(connect_pads
				(clearance 0)
			)
			(min_thickness 0.25)
			(keepout
				(tracks not_allowed)
				(vias allowed)
				(pads allowed)
				(copperpour not_allowed)
				(footprints allowed)
			)
			(placement
				(enabled no)
				(sheetname "")
			)
			(fill
				(thermal_gap 0.5)
				(thermal_bridge_width 0.5)
				(island_removal_mode 0)
			)
			(polygon
				(pts
					(arc
						(start 338.302854 -54.029356)
						(mid 338.256339 -53.953614)
						(end 338.18068 -53.906928)
					)
					(arc
						(start 338.18068 -53.801772)
						(mid 338.328462 -53.881574)
						(end 338.408264 -54.029356)
					)
				)
			)
		)
		(zone
			(layer "F.Cu")
			(hatch none 0.5)
			(connect_pads
				(clearance 0)
			)
			(min_thickness 0.25)
			(keepout
				(tracks not_allowed)
				(vias allowed)
				(pads allowed)
				(copperpour not_allowed)
				(footprints allowed)
			)
			(placement
				(enabled no)
				(sheetname "")
			)
			(fill
				(thermal_gap 0.5)
				(thermal_bridge_width 0.5)
				(island_removal_mode 0)
			)
			(polygon
				(pts
					(arc
						(start 338.302854 -53.089556)
						(mid 338.256339 -53.013814)
						(end 338.18068 -52.967128)
					)
					(arc
						(start 338.18068 -52.861972)
						(mid 338.328462 -52.941774)
						(end 338.408264 -53.089556)
					)
				)
			)
		)
		(zone
			(layer "F.Cu")
			(hatch none 0.5)
			(connect_pads
				(clearance 0)
			)
			(min_thickness 0.25)
			(keepout
				(tracks not_allowed)
				(vias allowed)
				(pads allowed)
				(copperpour not_allowed)
				(footprints allowed)
			)
			(placement
				(enabled no)
				(sheetname "")
			)
			(fill
				(thermal_gap 0.5)
				(thermal_bridge_width 0.5)
				(island_removal_mode 0)
			)
			(polygon
				(pts
					(arc
						(start 338.302854 -43.691556)
						(mid 338.256339 -43.615814)
						(end 338.18068 -43.569128)
					)
					(arc
						(start 338.18068 -43.463972)
						(mid 338.328462 -43.543774)
						(end 338.408264 -43.691556)
					)
				)
			)
		)
		(zone
			(layer "F.Cu")
			(hatch none 0.5)
			(connect_pads
				(clearance 0)
			)
			(min_thickness 0.25)
			(keepout
				(tracks not_allowed)
				(vias allowed)
				(pads allowed)
				(copperpour not_allowed)
				(footprints allowed)
			)
			(placement
				(enabled no)
				(sheetname "")
			)
			(fill
				(thermal_gap 0.5)
				(thermal_bridge_width 0.5)
				(island_removal_mode 0)
			)
			(polygon
				(pts
					(arc
						(start 338.302854 -42.751756)
						(mid 338.256339 -42.676014)
						(end 338.18068 -42.629328)
					)
					(arc
						(start 338.18068 -42.524172)
						(mid 338.328462 -42.603974)
						(end 338.408264 -42.751756)
					)
				)
			)
		)
		(zone
			(layer "F.Cu")
			(hatch none 0.5)
			(connect_pads
				(clearance 0)
			)
			(min_thickness 0.25)
			(keepout
				(tracks not_allowed)
				(vias allowed)
				(pads allowed)
				(copperpour not_allowed)
				(footprints allowed)
			)
			(placement
				(enabled no)
				(sheetname "")
			)
			(fill
				(thermal_gap 0.5)
				(thermal_bridge_width 0.5)
				(island_removal_mode 0)
			)
			(polygon
				(pts
					(arc
						(start 338.302854 -41.811956)
						(mid 338.256339 -41.736214)
						(end 338.18068 -41.689528)
					)
					(arc
						(start 338.18068 -41.584372)
						(mid 338.328462 -41.664174)
						(end 338.408264 -41.811956)
					)
				)
			)
		)
		(zone
			(layer "F.Cu")
			(hatch none 0.5)
			(connect_pads
				(clearance 0)
			)
			(min_thickness 0.25)
			(keepout
				(tracks not_allowed)
				(vias allowed)
				(pads allowed)
				(copperpour not_allowed)
				(footprints allowed)
			)
			(placement
				(enabled no)
				(sheetname "")
			)
			(fill
				(thermal_gap 0.5)
				(thermal_bridge_width 0.5)
				(island_removal_mode 0)
			)
			(polygon
				(pts
					(arc
						(start 338.302854 -40.872156)
						(mid 338.256339 -40.796414)
						(end 338.18068 -40.749728)
					)
					(arc
						(start 338.18068 -40.644572)
						(mid 338.328462 -40.724374)
						(end 338.408264 -40.872156)
					)
				)
			)
		)
		(zone
			(layer "F.Cu")
			(hatch none 0.5)
			(connect_pads
				(clearance 0)
			)
			(min_thickness 0.25)
			(keepout
				(tracks not_allowed)
				(vias allowed)
				(pads allowed)
				(copperpour not_allowed)
				(footprints allowed)
			)
			(placement
				(enabled no)
				(sheetname "")
			)
			(fill
				(thermal_gap 0.5)
				(thermal_bridge_width 0.5)
				(island_removal_mode 0)
			)
			(polygon
				(pts
					(arc
						(start 338.302854 -39.932356)
						(mid 338.256339 -39.856614)
						(end 338.18068 -39.809928)
					)
					(arc
						(start 338.18068 -39.704772)
						(mid 338.328462 -39.784574)
						(end 338.408264 -39.932356)
					)
				)
			)
		)
		(zone
			(layer "F.Cu")
			(hatch none 0.5)
			(connect_pads
				(clearance 0)
			)
			(min_thickness 0.25)
			(keepout
				(tracks not_allowed)
				(vias allowed)
				(pads allowed)
				(copperpour not_allowed)
				(footprints allowed)
			)
			(placement
				(enabled no)
				(sheetname "")
			)
			(fill
				(thermal_gap 0.5)
				(thermal_bridge_width 0.5)
				(island_removal_mode 0)
			)
			(polygon
				(pts
					(arc
						(start 338.31784 -51.710336)
						(mid 338.364441 -51.786163)
						(end 338.440268 -51.832764)
					)
					(arc
						(start 338.440268 -51.93792)
						(mid 338.292486 -51.858118)
						(end 338.212684 -51.710336)
					)
				)
			)
		)
		(zone
			(layer "F.Cu")
			(hatch none 0.5)
			(connect_pads
				(clearance 0)
			)
			(min_thickness 0.25)
			(keepout
				(tracks not_allowed)
				(vias allowed)
				(pads allowed)
				(copperpour not_allowed)
				(footprints allowed)
			)
			(placement
				(enabled no)
				(sheetname "")
			)
			(fill
				(thermal_gap 0.5)
				(thermal_bridge_width 0.5)
				(island_removal_mode 0)
			)
			(polygon
				(pts
					(arc
						(start 338.31784 -50.910236)
						(mid 338.364441 -50.986063)
						(end 338.440268 -51.032664)
					)
					(arc
						(start 338.440268 -51.13782)
						(mid 338.292486 -51.058018)
						(end 338.212684 -50.910236)
					)
				)
			)
		)
		(zone
			(layer "F.Cu")
			(hatch none 0.5)
			(connect_pads
				(clearance 0)
			)
			(min_thickness 0.25)
			(keepout
				(tracks not_allowed)
				(vias allowed)
				(pads allowed)
				(copperpour not_allowed)
				(footprints allowed)
			)
			(placement
				(enabled no)
				(sheetname "")
			)
			(fill
				(thermal_gap 0.5)
				(thermal_bridge_width 0.5)
				(island_removal_mode 0)
			)
			(polygon
				(pts
					(arc
						(start 338.31784 -50.110136)
						(mid 338.364441 -50.185963)
						(end 338.440268 -50.232564)
					)
					(arc
						(start 338.440268 -50.33772)
						(mid 338.292486 -50.257918)
						(end 338.212684 -50.110136)
					)
				)
			)
		)
		(zone
			(layer "F.Cu")
			(hatch none 0.5)
			(connect_pads
				(clearance 0)
			)
			(min_thickness 0.25)
			(keepout
				(tracks not_allowed)
				(vias allowed)
				(pads allowed)
				(copperpour not_allowed)
				(footprints allowed)
			)
			(placement
				(enabled no)
				(sheetname "")
			)
			(fill
				(thermal_gap 0.5)
				(thermal_bridge_width 0.5)
				(island_removal_mode 0)
			)
			(polygon
				(pts
					(arc
						(start 338.31784 -49.310036)
						(mid 338.364441 -49.385863)
						(end 338.440268 -49.432464)
					)
					(arc
						(start 338.440268 -49.53762)
						(mid 338.292486 -49.457818)
						(end 338.212684 -49.310036)
					)
				)
			)
		)
		(zone
			(layer "F.Cu")
			(hatch none 0.5)
			(connect_pads
				(clearance 0)
			)
			(min_thickness 0.25)
			(keepout
				(tracks not_allowed)
				(vias allowed)
				(pads allowed)
				(copperpour not_allowed)
				(footprints allowed)
			)
			(placement
				(enabled no)
				(sheetname "")
			)
			(fill
				(thermal_gap 0.5)
				(thermal_bridge_width 0.5)
				(island_removal_mode 0)
			)
			(polygon
				(pts
					(arc
						(start 338.31784 -48.509936)
						(mid 338.364441 -48.585763)
						(end 338.440268 -48.632364)
					)
					(arc
						(start 338.440268 -48.73752)
						(mid 338.292486 -48.657718)
						(end 338.212684 -48.509936)
					)
				)
			)
		)
		(zone
			(layer "F.Cu")
			(hatch none 0.5)
			(connect_pads
				(clearance 0)
			)
			(min_thickness 0.25)
			(keepout
				(tracks not_allowed)
				(vias allowed)
				(pads allowed)
				(copperpour not_allowed)
				(footprints allowed)
			)
			(placement
				(enabled no)
				(sheetname "")
			)
			(fill
				(thermal_gap 0.5)
				(thermal_bridge_width 0.5)
				(island_removal_mode 0)
			)
			(polygon
				(pts
					(arc
						(start 338.31784 -47.709836)
						(mid 338.364441 -47.785663)
						(end 338.440268 -47.832264)
					)
					(arc
						(start 338.440268 -47.93742)
						(mid 338.292486 -47.857618)
						(end 338.212684 -47.709836)
					)
				)
			)
		)
		(zone
			(layer "F.Cu")
			(hatch none 0.5)
			(connect_pads
				(clearance 0)
			)
			(min_thickness 0.25)
			(keepout
				(tracks not_allowed)
				(vias allowed)
				(pads allowed)
				(copperpour not_allowed)
				(footprints allowed)
			)
			(placement
				(enabled no)
				(sheetname "")
			)
			(fill
				(thermal_gap 0.5)
				(thermal_bridge_width 0.5)
				(island_removal_mode 0)
			)
			(polygon
				(pts
					(arc
						(start 338.31784 -46.909736)
						(mid 338.364441 -46.985563)
						(end 338.440268 -47.032164)
					)
					(arc
						(start 338.440268 -47.13732)
						(mid 338.292486 -47.057518)
						(end 338.212684 -46.909736)
					)
				)
			)
		)
		(zone
			(layer "F.Cu")
			(hatch none 0.5)
			(connect_pads
				(clearance 0)
			)
			(min_thickness 0.25)
			(keepout
				(tracks not_allowed)
				(vias allowed)
				(pads allowed)
				(copperpour not_allowed)
				(footprints allowed)
			)
			(placement
				(enabled no)
				(sheetname "")
			)
			(fill
				(thermal_gap 0.5)
				(thermal_bridge_width 0.5)
				(island_removal_mode 0)
			)
			(polygon
				(pts
					(arc
						(start 338.31784 -46.109636)
						(mid 338.364441 -46.185463)
						(end 338.440268 -46.232064)
					)
					(arc
						(start 338.440268 -46.33722)
						(mid 338.292486 -46.257418)
						(end 338.212684 -46.109636)
					)
				)
			)
		)
		(zone
			(layer "F.Cu")
			(hatch none 0.5)
			(connect_pads
				(clearance 0)
			)
			(min_thickness 0.25)
			(keepout
				(tracks not_allowed)
				(vias allowed)
				(pads allowed)
				(copperpour not_allowed)
				(footprints allowed)
			)
			(placement
				(enabled no)
				(sheetname "")
			)
			(fill
				(thermal_gap 0.5)
				(thermal_bridge_width 0.5)
				(island_removal_mode 0)
			)
			(polygon
				(pts
					(arc
						(start 338.31784 -45.309536)
						(mid 338.364441 -45.385363)
						(end 338.440268 -45.431964)
					)
					(arc
						(start 338.440268 -45.53712)
						(mid 338.292486 -45.457318)
						(end 338.212684 -45.309536)
					)
				)
			)
		)
		(zone
			(layer "F.Cu")
			(hatch none 0.5)
			(connect_pads
				(clearance 0)
			)
			(min_thickness 0.25)
			(keepout
				(tracks not_allowed)
				(vias allowed)
				(pads allowed)
				(copperpour not_allowed)
				(footprints allowed)
			)
			(placement
				(enabled no)
				(sheetname "")
			)
			(fill
				(thermal_gap 0.5)
				(thermal_bridge_width 0.5)
				(island_removal_mode 0)
			)
			(polygon
				(pts
					(arc
						(start 338.440268 -51.468528)
						(mid 338.364441 -51.515129)
						(end 338.31784 -51.590956)
					)
					(arc
						(start 338.212684 -51.590956)
						(mid 338.292486 -51.443174)
						(end 338.440268 -51.363372)
					)
				)
			)
		)
		(zone
			(layer "F.Cu")
			(hatch none 0.5)
			(connect_pads
				(clearance 0)
			)
			(min_thickness 0.25)
			(keepout
				(tracks not_allowed)
				(vias allowed)
				(pads allowed)
				(copperpour not_allowed)
				(footprints allowed)
			)
			(placement
				(enabled no)
				(sheetname "")
			)
			(fill
				(thermal_gap 0.5)
				(thermal_bridge_width 0.5)
				(island_removal_mode 0)
			)
			(polygon
				(pts
					(arc
						(start 338.440268 -50.668428)
						(mid 338.364441 -50.715029)
						(end 338.31784 -50.790856)
					)
					(arc
						(start 338.212684 -50.790856)
						(mid 338.292486 -50.643074)
						(end 338.440268 -50.563272)
					)
				)
			)
		)
		(zone
			(layer "F.Cu")
			(hatch none 0.5)
			(connect_pads
				(clearance 0)
			)
			(min_thickness 0.25)
			(keepout
				(tracks not_allowed)
				(vias allowed)
				(pads allowed)
				(copperpour not_allowed)
				(footprints allowed)
			)
			(placement
				(enabled no)
				(sheetname "")
			)
			(fill
				(thermal_gap 0.5)
				(thermal_bridge_width 0.5)
				(island_removal_mode 0)
			)
			(polygon
				(pts
					(arc
						(start 338.440268 -49.868328)
						(mid 338.364441 -49.914929)
						(end 338.31784 -49.990756)
					)
					(arc
						(start 338.212684 -49.990756)
						(mid 338.292486 -49.842974)
						(end 338.440268 -49.763172)
					)
				)
			)
		)
		(zone
			(layer "F.Cu")
			(hatch none 0.5)
			(connect_pads
				(clearance 0)
			)
			(min_thickness 0.25)
			(keepout
				(tracks not_allowed)
				(vias allowed)
				(pads allowed)
				(copperpour not_allowed)
				(footprints allowed)
			)
			(placement
				(enabled no)
				(sheetname "")
			)
			(fill
				(thermal_gap 0.5)
				(thermal_bridge_width 0.5)
				(island_removal_mode 0)
			)
			(polygon
				(pts
					(arc
						(start 338.440268 -49.068228)
						(mid 338.364441 -49.114829)
						(end 338.31784 -49.190656)
					)
					(arc
						(start 338.212684 -49.190656)
						(mid 338.292486 -49.042874)
						(end 338.440268 -48.963072)
					)
				)
			)
		)
		(zone
			(layer "F.Cu")
			(hatch none 0.5)
			(connect_pads
				(clearance 0)
			)
			(min_thickness 0.25)
			(keepout
				(tracks not_allowed)
				(vias allowed)
				(pads allowed)
				(copperpour not_allowed)
				(footprints allowed)
			)
			(placement
				(enabled no)
				(sheetname "")
			)
			(fill
				(thermal_gap 0.5)
				(thermal_bridge_width 0.5)
				(island_removal_mode 0)
			)
			(polygon
				(pts
					(arc
						(start 338.440268 -48.268128)
						(mid 338.364441 -48.314729)
						(end 338.31784 -48.390556)
					)
					(arc
						(start 338.212684 -48.390556)
						(mid 338.292486 -48.242774)
						(end 338.440268 -48.162972)
					)
				)
			)
		)
		(zone
			(layer "F.Cu")
			(hatch none 0.5)
			(connect_pads
				(clearance 0)
			)
			(min_thickness 0.25)
			(keepout
				(tracks not_allowed)
				(vias allowed)
				(pads allowed)
				(copperpour not_allowed)
				(footprints allowed)
			)
			(placement
				(enabled no)
				(sheetname "")
			)
			(fill
				(thermal_gap 0.5)
				(thermal_bridge_width 0.5)
				(island_removal_mode 0)
			)
			(polygon
				(pts
					(arc
						(start 338.440268 -47.468028)
						(mid 338.364441 -47.514629)
						(end 338.31784 -47.590456)
					)
					(arc
						(start 338.212684 -47.590456)
						(mid 338.292486 -47.442674)
						(end 338.440268 -47.362872)
					)
				)
			)
		)
		(zone
			(layer "F.Cu")
			(hatch none 0.5)
			(connect_pads
				(clearance 0)
			)
			(min_thickness 0.25)
			(keepout
				(tracks not_allowed)
				(vias allowed)
				(pads allowed)
				(copperpour not_allowed)
				(footprints allowed)
			)
			(placement
				(enabled no)
				(sheetname "")
			)
			(fill
				(thermal_gap 0.5)
				(thermal_bridge_width 0.5)
				(island_removal_mode 0)
			)
			(polygon
				(pts
					(arc
						(start 338.440268 -46.667928)
						(mid 338.364441 -46.714529)
						(end 338.31784 -46.790356)
					)
					(arc
						(start 338.212684 -46.790356)
						(mid 338.292486 -46.642574)
						(end 338.440268 -46.562772)
					)
				)
			)
		)
		(zone
			(layer "F.Cu")
			(hatch none 0.5)
			(connect_pads
				(clearance 0)
			)
			(min_thickness 0.25)
			(keepout
				(tracks not_allowed)
				(vias allowed)
				(pads allowed)
				(copperpour not_allowed)
				(footprints allowed)
			)
			(placement
				(enabled no)
				(sheetname "")
			)
			(fill
				(thermal_gap 0.5)
				(thermal_bridge_width 0.5)
				(island_removal_mode 0)
			)
			(polygon
				(pts
					(arc
						(start 338.440268 -45.867828)
						(mid 338.364441 -45.914429)
						(end 338.31784 -45.990256)
					)
					(arc
						(start 338.212684 -45.990256)
						(mid 338.292486 -45.842474)
						(end 338.440268 -45.762672)
					)
				)
			)
		)
		(zone
			(layer "F.Cu")
			(hatch none 0.5)
			(connect_pads
				(clearance 0)
			)
			(min_thickness 0.25)
			(keepout
				(tracks not_allowed)
				(vias allowed)
				(pads allowed)
				(copperpour not_allowed)
				(footprints allowed)
			)
			(placement
				(enabled no)
				(sheetname "")
			)
			(fill
				(thermal_gap 0.5)
				(thermal_bridge_width 0.5)
				(island_removal_mode 0)
			)
			(polygon
				(pts
					(arc
						(start 338.440268 -45.067728)
						(mid 338.364441 -45.114329)
						(end 338.31784 -45.190156)
					)
					(arc
						(start 338.212684 -45.190156)
						(mid 338.292486 -45.042374)
						(end 338.440268 -44.962572)
					)
				)
			)
		)
		(zone
			(layer "F.Cu")
			(hatch none 0.5)
			(connect_pads
				(clearance 0)
			)
			(min_thickness 0.25)
			(keepout
				(tracks not_allowed)
				(vias allowed)
				(pads allowed)
				(copperpour not_allowed)
				(footprints allowed)
			)
			(placement
				(enabled no)
				(sheetname "")
			)
			(fill
				(thermal_gap 0.5)
				(thermal_bridge_width 0.5)
				(island_removal_mode 0)
			)
			(polygon
				(pts
					(arc
						(start 338.559648 -51.832764)
						(mid 338.635475 -51.786163)
						(end 338.682076 -51.710336)
					)
					(arc
						(start 338.787232 -51.710336)
						(mid 338.70743 -51.858118)
						(end 338.559648 -51.93792)
					)
				)
			)
		)
		(zone
			(layer "F.Cu")
			(hatch none 0.5)
			(connect_pads
				(clearance 0)
			)
			(min_thickness 0.25)
			(keepout
				(tracks not_allowed)
				(vias allowed)
				(pads allowed)
				(copperpour not_allowed)
				(footprints allowed)
			)
			(placement
				(enabled no)
				(sheetname "")
			)
			(fill
				(thermal_gap 0.5)
				(thermal_bridge_width 0.5)
				(island_removal_mode 0)
			)
			(polygon
				(pts
					(arc
						(start 338.559648 -51.032664)
						(mid 338.635475 -50.986063)
						(end 338.682076 -50.910236)
					)
					(arc
						(start 338.787232 -50.910236)
						(mid 338.70743 -51.058018)
						(end 338.559648 -51.13782)
					)
				)
			)
		)
		(zone
			(layer "F.Cu")
			(hatch none 0.5)
			(connect_pads
				(clearance 0)
			)
			(min_thickness 0.25)
			(keepout
				(tracks not_allowed)
				(vias allowed)
				(pads allowed)
				(copperpour not_allowed)
				(footprints allowed)
			)
			(placement
				(enabled no)
				(sheetname "")
			)
			(fill
				(thermal_gap 0.5)
				(thermal_bridge_width 0.5)
				(island_removal_mode 0)
			)
			(polygon
				(pts
					(arc
						(start 338.559648 -50.232564)
						(mid 338.635475 -50.185963)
						(end 338.682076 -50.110136)
					)
					(arc
						(start 338.787232 -50.110136)
						(mid 338.70743 -50.257918)
						(end 338.559648 -50.33772)
					)
				)
			)
		)
		(zone
			(layer "F.Cu")
			(hatch none 0.5)
			(connect_pads
				(clearance 0)
			)
			(min_thickness 0.25)
			(keepout
				(tracks not_allowed)
				(vias allowed)
				(pads allowed)
				(copperpour not_allowed)
				(footprints allowed)
			)
			(placement
				(enabled no)
				(sheetname "")
			)
			(fill
				(thermal_gap 0.5)
				(thermal_bridge_width 0.5)
				(island_removal_mode 0)
			)
			(polygon
				(pts
					(arc
						(start 338.559648 -49.432464)
						(mid 338.635475 -49.385863)
						(end 338.682076 -49.310036)
					)
					(arc
						(start 338.787232 -49.310036)
						(mid 338.70743 -49.457818)
						(end 338.559648 -49.53762)
					)
				)
			)
		)
		(zone
			(layer "F.Cu")
			(hatch none 0.5)
			(connect_pads
				(clearance 0)
			)
			(min_thickness 0.25)
			(keepout
				(tracks not_allowed)
				(vias allowed)
				(pads allowed)
				(copperpour not_allowed)
				(footprints allowed)
			)
			(placement
				(enabled no)
				(sheetname "")
			)
			(fill
				(thermal_gap 0.5)
				(thermal_bridge_width 0.5)
				(island_removal_mode 0)
			)
			(polygon
				(pts
					(arc
						(start 338.559648 -48.632364)
						(mid 338.635475 -48.585763)
						(end 338.682076 -48.509936)
					)
					(arc
						(start 338.787232 -48.509936)
						(mid 338.70743 -48.657718)
						(end 338.559648 -48.73752)
					)
				)
			)
		)
		(zone
			(layer "F.Cu")
			(hatch none 0.5)
			(connect_pads
				(clearance 0)
			)
			(min_thickness 0.25)
			(keepout
				(tracks not_allowed)
				(vias allowed)
				(pads allowed)
				(copperpour not_allowed)
				(footprints allowed)
			)
			(placement
				(enabled no)
				(sheetname "")
			)
			(fill
				(thermal_gap 0.5)
				(thermal_bridge_width 0.5)
				(island_removal_mode 0)
			)
			(polygon
				(pts
					(arc
						(start 338.559648 -47.832264)
						(mid 338.635475 -47.785663)
						(end 338.682076 -47.709836)
					)
					(arc
						(start 338.787232 -47.709836)
						(mid 338.70743 -47.857618)
						(end 338.559648 -47.93742)
					)
				)
			)
		)
		(zone
			(layer "F.Cu")
			(hatch none 0.5)
			(connect_pads
				(clearance 0)
			)
			(min_thickness 0.25)
			(keepout
				(tracks not_allowed)
				(vias allowed)
				(pads allowed)
				(copperpour not_allowed)
				(footprints allowed)
			)
			(placement
				(enabled no)
				(sheetname "")
			)
			(fill
				(thermal_gap 0.5)
				(thermal_bridge_width 0.5)
				(island_removal_mode 0)
			)
			(polygon
				(pts
					(arc
						(start 338.559648 -47.032164)
						(mid 338.635475 -46.985563)
						(end 338.682076 -46.909736)
					)
					(arc
						(start 338.787232 -46.909736)
						(mid 338.70743 -47.057518)
						(end 338.559648 -47.13732)
					)
				)
			)
		)
		(zone
			(layer "F.Cu")
			(hatch none 0.5)
			(connect_pads
				(clearance 0)
			)
			(min_thickness 0.25)
			(keepout
				(tracks not_allowed)
				(vias allowed)
				(pads allowed)
				(copperpour not_allowed)
				(footprints allowed)
			)
			(placement
				(enabled no)
				(sheetname "")
			)
			(fill
				(thermal_gap 0.5)
				(thermal_bridge_width 0.5)
				(island_removal_mode 0)
			)
			(polygon
				(pts
					(arc
						(start 338.559648 -46.232064)
						(mid 338.635475 -46.185463)
						(end 338.682076 -46.109636)
					)
					(arc
						(start 338.787232 -46.109636)
						(mid 338.70743 -46.257418)
						(end 338.559648 -46.33722)
					)
				)
			)
		)
		(zone
			(layer "F.Cu")
			(hatch none 0.5)
			(connect_pads
				(clearance 0)
			)
			(min_thickness 0.25)
			(keepout
				(tracks not_allowed)
				(vias allowed)
				(pads allowed)
				(copperpour not_allowed)
				(footprints allowed)
			)
			(placement
				(enabled no)
				(sheetname "")
			)
			(fill
				(thermal_gap 0.5)
				(thermal_bridge_width 0.5)
				(island_removal_mode 0)
			)
			(polygon
				(pts
					(arc
						(start 338.559648 -45.431964)
						(mid 338.635475 -45.385363)
						(end 338.682076 -45.309536)
					)
					(arc
						(start 338.787232 -45.309536)
						(mid 338.70743 -45.457318)
						(end 338.559648 -45.53712)
					)
				)
			)
		)
		(zone
			(layer "F.Cu")
			(hatch none 0.5)
			(connect_pads
				(clearance 0)
			)
			(min_thickness 0.25)
			(keepout
				(tracks not_allowed)
				(vias allowed)
				(pads allowed)
				(copperpour not_allowed)
				(footprints allowed)
			)
			(placement
				(enabled no)
				(sheetname "")
			)
			(fill
				(thermal_gap 0.5)
				(thermal_bridge_width 0.5)
				(island_removal_mode 0)
			)
			(polygon
				(pts
					(arc
						(start 338.682076 -51.590956)
						(mid 338.635475 -51.515129)
						(end 338.559648 -51.468528)
					)
					(arc
						(start 338.559648 -51.363372)
						(mid 338.70743 -51.443174)
						(end 338.787232 -51.590956)
					)
				)
			)
		)
		(zone
			(layer "F.Cu")
			(hatch none 0.5)
			(connect_pads
				(clearance 0)
			)
			(min_thickness 0.25)
			(keepout
				(tracks not_allowed)
				(vias allowed)
				(pads allowed)
				(copperpour not_allowed)
				(footprints allowed)
			)
			(placement
				(enabled no)
				(sheetname "")
			)
			(fill
				(thermal_gap 0.5)
				(thermal_bridge_width 0.5)
				(island_removal_mode 0)
			)
			(polygon
				(pts
					(arc
						(start 338.682076 -50.790856)
						(mid 338.635475 -50.715029)
						(end 338.559648 -50.668428)
					)
					(arc
						(start 338.559648 -50.563272)
						(mid 338.70743 -50.643074)
						(end 338.787232 -50.790856)
					)
				)
			)
		)
		(zone
			(layer "F.Cu")
			(hatch none 0.5)
			(connect_pads
				(clearance 0)
			)
			(min_thickness 0.25)
			(keepout
				(tracks not_allowed)
				(vias allowed)
				(pads allowed)
				(copperpour not_allowed)
				(footprints allowed)
			)
			(placement
				(enabled no)
				(sheetname "")
			)
			(fill
				(thermal_gap 0.5)
				(thermal_bridge_width 0.5)
				(island_removal_mode 0)
			)
			(polygon
				(pts
					(arc
						(start 338.682076 -49.990756)
						(mid 338.635475 -49.914929)
						(end 338.559648 -49.868328)
					)
					(arc
						(start 338.559648 -49.763172)
						(mid 338.70743 -49.842974)
						(end 338.787232 -49.990756)
					)
				)
			)
		)
		(zone
			(layer "F.Cu")
			(hatch none 0.5)
			(connect_pads
				(clearance 0)
			)
			(min_thickness 0.25)
			(keepout
				(tracks not_allowed)
				(vias allowed)
				(pads allowed)
				(copperpour not_allowed)
				(footprints allowed)
			)
			(placement
				(enabled no)
				(sheetname "")
			)
			(fill
				(thermal_gap 0.5)
				(thermal_bridge_width 0.5)
				(island_removal_mode 0)
			)
			(polygon
				(pts
					(arc
						(start 338.682076 -49.190656)
						(mid 338.635475 -49.114829)
						(end 338.559648 -49.068228)
					)
					(arc
						(start 338.559648 -48.963072)
						(mid 338.70743 -49.042874)
						(end 338.787232 -49.190656)
					)
				)
			)
		)
		(zone
			(layer "F.Cu")
			(hatch none 0.5)
			(connect_pads
				(clearance 0)
			)
			(min_thickness 0.25)
			(keepout
				(tracks not_allowed)
				(vias allowed)
				(pads allowed)
				(copperpour not_allowed)
				(footprints allowed)
			)
			(placement
				(enabled no)
				(sheetname "")
			)
			(fill
				(thermal_gap 0.5)
				(thermal_bridge_width 0.5)
				(island_removal_mode 0)
			)
			(polygon
				(pts
					(arc
						(start 338.682076 -48.390556)
						(mid 338.635475 -48.314729)
						(end 338.559648 -48.268128)
					)
					(arc
						(start 338.559648 -48.162972)
						(mid 338.70743 -48.242774)
						(end 338.787232 -48.390556)
					)
				)
			)
		)
		(zone
			(layer "F.Cu")
			(hatch none 0.5)
			(connect_pads
				(clearance 0)
			)
			(min_thickness 0.25)
			(keepout
				(tracks not_allowed)
				(vias allowed)
				(pads allowed)
				(copperpour not_allowed)
				(footprints allowed)
			)
			(placement
				(enabled no)
				(sheetname "")
			)
			(fill
				(thermal_gap 0.5)
				(thermal_bridge_width 0.5)
				(island_removal_mode 0)
			)
			(polygon
				(pts
					(arc
						(start 338.682076 -47.590456)
						(mid 338.635475 -47.514629)
						(end 338.559648 -47.468028)
					)
					(arc
						(start 338.559648 -47.362872)
						(mid 338.70743 -47.442674)
						(end 338.787232 -47.590456)
					)
				)
			)
		)
		(zone
			(layer "F.Cu")
			(hatch none 0.5)
			(connect_pads
				(clearance 0)
			)
			(min_thickness 0.25)
			(keepout
				(tracks not_allowed)
				(vias allowed)
				(pads allowed)
				(copperpour not_allowed)
				(footprints allowed)
			)
			(placement
				(enabled no)
				(sheetname "")
			)
			(fill
				(thermal_gap 0.5)
				(thermal_bridge_width 0.5)
				(island_removal_mode 0)
			)
			(polygon
				(pts
					(arc
						(start 338.682076 -46.790356)
						(mid 338.635475 -46.714529)
						(end 338.559648 -46.667928)
					)
					(arc
						(start 338.559648 -46.562772)
						(mid 338.70743 -46.642574)
						(end 338.787232 -46.790356)
					)
				)
			)
		)
		(zone
			(layer "F.Cu")
			(hatch none 0.5)
			(connect_pads
				(clearance 0)
			)
			(min_thickness 0.25)
			(keepout
				(tracks not_allowed)
				(vias allowed)
				(pads allowed)
				(copperpour not_allowed)
				(footprints allowed)
			)
			(placement
				(enabled no)
				(sheetname "")
			)
			(fill
				(thermal_gap 0.5)
				(thermal_bridge_width 0.5)
				(island_removal_mode 0)
			)
			(polygon
				(pts
					(arc
						(start 338.682076 -45.990256)
						(mid 338.635475 -45.914429)
						(end 338.559648 -45.867828)
					)
					(arc
						(start 338.559648 -45.762672)
						(mid 338.70743 -45.842474)
						(end 338.787232 -45.990256)
					)
				)
			)
		)
		(zone
			(layer "F.Cu")
			(hatch none 0.5)
			(connect_pads
				(clearance 0)
			)
			(min_thickness 0.25)
			(keepout
				(tracks not_allowed)
				(vias allowed)
				(pads allowed)
				(copperpour not_allowed)
				(footprints allowed)
			)
			(placement
				(enabled no)
				(sheetname "")
			)
			(fill
				(thermal_gap 0.5)
				(thermal_bridge_width 0.5)
				(island_removal_mode 0)
			)
			(polygon
				(pts
					(arc
						(start 338.682076 -45.190156)
						(mid 338.635475 -45.114329)
						(end 338.559648 -45.067728)
					)
					(arc
						(start 338.559648 -44.962572)
						(mid 338.70743 -45.042374)
						(end 338.787232 -45.190156)
					)
				)
			)
		)
		(zone
			(layer "F.Cu")
			(hatch none 0.5)
			(connect_pads
				(clearance 0)
			)
			(min_thickness 0.25)
			(keepout
				(tracks not_allowed)
				(vias allowed)
				(pads allowed)
				(copperpour not_allowed)
				(footprints allowed)
			)
			(placement
				(enabled no)
				(sheetname "")
			)
			(fill
				(thermal_gap 0.5)
				(thermal_bridge_width 0.5)
				(island_removal_mode 0)
			)
			(polygon
				(pts
					(arc
						(start 338.752688 -56.498236)
						(mid 338.799289 -56.574063)
						(end 338.875116 -56.620664)
					)
					(arc
						(start 338.875116 -56.72582)
						(mid 338.727334 -56.646018)
						(end 338.647532 -56.498236)
					)
				)
			)
		)
		(zone
			(layer "F.Cu")
			(hatch none 0.5)
			(connect_pads
				(clearance 0)
			)
			(min_thickness 0.25)
			(keepout
				(tracks not_allowed)
				(vias allowed)
				(pads allowed)
				(copperpour not_allowed)
				(footprints allowed)
			)
			(placement
				(enabled no)
				(sheetname "")
			)
			(fill
				(thermal_gap 0.5)
				(thermal_bridge_width 0.5)
				(island_removal_mode 0)
			)
			(polygon
				(pts
					(arc
						(start 338.752688 -55.558436)
						(mid 338.799289 -55.634263)
						(end 338.875116 -55.680864)
					)
					(arc
						(start 338.875116 -55.78602)
						(mid 338.727334 -55.706218)
						(end 338.647532 -55.558436)
					)
				)
			)
		)
		(zone
			(layer "F.Cu")
			(hatch none 0.5)
			(connect_pads
				(clearance 0)
			)
			(min_thickness 0.25)
			(keepout
				(tracks not_allowed)
				(vias allowed)
				(pads allowed)
				(copperpour not_allowed)
				(footprints allowed)
			)
			(placement
				(enabled no)
				(sheetname "")
			)
			(fill
				(thermal_gap 0.5)
				(thermal_bridge_width 0.5)
				(island_removal_mode 0)
			)
			(polygon
				(pts
					(arc
						(start 338.752688 -54.618636)
						(mid 338.799289 -54.694463)
						(end 338.875116 -54.741064)
					)
					(arc
						(start 338.875116 -54.84622)
						(mid 338.727334 -54.766418)
						(end 338.647532 -54.618636)
					)
				)
			)
		)
		(zone
			(layer "F.Cu")
			(hatch none 0.5)
			(connect_pads
				(clearance 0)
			)
			(min_thickness 0.25)
			(keepout
				(tracks not_allowed)
				(vias allowed)
				(pads allowed)
				(copperpour not_allowed)
				(footprints allowed)
			)
			(placement
				(enabled no)
				(sheetname "")
			)
			(fill
				(thermal_gap 0.5)
				(thermal_bridge_width 0.5)
				(island_removal_mode 0)
			)
			(polygon
				(pts
					(arc
						(start 338.752688 -53.678836)
						(mid 338.799289 -53.754663)
						(end 338.875116 -53.801264)
					)
					(arc
						(start 338.875116 -53.90642)
						(mid 338.727334 -53.826618)
						(end 338.647532 -53.678836)
					)
				)
			)
		)
		(zone
			(layer "F.Cu")
			(hatch none 0.5)
			(connect_pads
				(clearance 0)
			)
			(min_thickness 0.25)
			(keepout
				(tracks not_allowed)
				(vias allowed)
				(pads allowed)
				(copperpour not_allowed)
				(footprints allowed)
			)
			(placement
				(enabled no)
				(sheetname "")
			)
			(fill
				(thermal_gap 0.5)
				(thermal_bridge_width 0.5)
				(island_removal_mode 0)
			)
			(polygon
				(pts
					(arc
						(start 338.752688 -52.739036)
						(mid 338.799289 -52.814863)
						(end 338.875116 -52.861464)
					)
					(arc
						(start 338.875116 -52.96662)
						(mid 338.727334 -52.886818)
						(end 338.647532 -52.739036)
					)
				)
			)
		)
		(zone
			(layer "F.Cu")
			(hatch none 0.5)
			(connect_pads
				(clearance 0)
			)
			(min_thickness 0.25)
			(keepout
				(tracks not_allowed)
				(vias allowed)
				(pads allowed)
				(copperpour not_allowed)
				(footprints allowed)
			)
			(placement
				(enabled no)
				(sheetname "")
			)
			(fill
				(thermal_gap 0.5)
				(thermal_bridge_width 0.5)
				(island_removal_mode 0)
			)
			(polygon
				(pts
					(arc
						(start 338.752942 -44.280836)
						(mid 338.799543 -44.356663)
						(end 338.87537 -44.403264)
					)
					(arc
						(start 338.87537 -44.50842)
						(mid 338.727458 -44.428669)
						(end 338.647532 -44.280836)
					)
				)
			)
		)
		(zone
			(layer "F.Cu")
			(hatch none 0.5)
			(connect_pads
				(clearance 0)
			)
			(min_thickness 0.25)
			(keepout
				(tracks not_allowed)
				(vias allowed)
				(pads allowed)
				(copperpour not_allowed)
				(footprints allowed)
			)
			(placement
				(enabled no)
				(sheetname "")
			)
			(fill
				(thermal_gap 0.5)
				(thermal_bridge_width 0.5)
				(island_removal_mode 0)
			)
			(polygon
				(pts
					(arc
						(start 338.752942 -43.341036)
						(mid 338.799543 -43.416863)
						(end 338.87537 -43.463464)
					)
					(arc
						(start 338.87537 -43.56862)
						(mid 338.727458 -43.488869)
						(end 338.647532 -43.341036)
					)
				)
			)
		)
		(zone
			(layer "F.Cu")
			(hatch none 0.5)
			(connect_pads
				(clearance 0)
			)
			(min_thickness 0.25)
			(keepout
				(tracks not_allowed)
				(vias allowed)
				(pads allowed)
				(copperpour not_allowed)
				(footprints allowed)
			)
			(placement
				(enabled no)
				(sheetname "")
			)
			(fill
				(thermal_gap 0.5)
				(thermal_bridge_width 0.5)
				(island_removal_mode 0)
			)
			(polygon
				(pts
					(arc
						(start 338.752942 -42.401236)
						(mid 338.799543 -42.477063)
						(end 338.87537 -42.523664)
					)
					(arc
						(start 338.87537 -42.62882)
						(mid 338.727458 -42.549069)
						(end 338.647532 -42.401236)
					)
				)
			)
		)
		(zone
			(layer "F.Cu")
			(hatch none 0.5)
			(connect_pads
				(clearance 0)
			)
			(min_thickness 0.25)
			(keepout
				(tracks not_allowed)
				(vias allowed)
				(pads allowed)
				(copperpour not_allowed)
				(footprints allowed)
			)
			(placement
				(enabled no)
				(sheetname "")
			)
			(fill
				(thermal_gap 0.5)
				(thermal_bridge_width 0.5)
				(island_removal_mode 0)
			)
			(polygon
				(pts
					(arc
						(start 338.752942 -41.461436)
						(mid 338.799543 -41.537263)
						(end 338.87537 -41.583864)
					)
					(arc
						(start 338.87537 -41.68902)
						(mid 338.727458 -41.609269)
						(end 338.647532 -41.461436)
					)
				)
			)
		)
		(zone
			(layer "F.Cu")
			(hatch none 0.5)
			(connect_pads
				(clearance 0)
			)
			(min_thickness 0.25)
			(keepout
				(tracks not_allowed)
				(vias allowed)
				(pads allowed)
				(copperpour not_allowed)
				(footprints allowed)
			)
			(placement
				(enabled no)
				(sheetname "")
			)
			(fill
				(thermal_gap 0.5)
				(thermal_bridge_width 0.5)
				(island_removal_mode 0)
			)
			(polygon
				(pts
					(arc
						(start 338.752942 -40.521636)
						(mid 338.799543 -40.597463)
						(end 338.87537 -40.644064)
					)
					(arc
						(start 338.87537 -40.74922)
						(mid 338.727458 -40.669469)
						(end 338.647532 -40.521636)
					)
				)
			)
		)
		(zone
			(layer "F.Cu")
			(hatch none 0.5)
			(connect_pads
				(clearance 0)
			)
			(min_thickness 0.25)
			(keepout
				(tracks not_allowed)
				(vias allowed)
				(pads allowed)
				(copperpour not_allowed)
				(footprints allowed)
			)
			(placement
				(enabled no)
				(sheetname "")
			)
			(fill
				(thermal_gap 0.5)
				(thermal_bridge_width 0.5)
				(island_removal_mode 0)
			)
			(polygon
				(pts
					(arc
						(start 338.875116 -56.256428)
						(mid 338.799289 -56.303029)
						(end 338.752688 -56.378856)
					)
					(arc
						(start 338.647532 -56.378856)
						(mid 338.727334 -56.231074)
						(end 338.875116 -56.151272)
					)
				)
			)
		)
		(zone
			(layer "F.Cu")
			(hatch none 0.5)
			(connect_pads
				(clearance 0)
			)
			(min_thickness 0.25)
			(keepout
				(tracks not_allowed)
				(vias allowed)
				(pads allowed)
				(copperpour not_allowed)
				(footprints allowed)
			)
			(placement
				(enabled no)
				(sheetname "")
			)
			(fill
				(thermal_gap 0.5)
				(thermal_bridge_width 0.5)
				(island_removal_mode 0)
			)
			(polygon
				(pts
					(arc
						(start 338.875116 -55.316628)
						(mid 338.799289 -55.363229)
						(end 338.752688 -55.439056)
					)
					(arc
						(start 338.647532 -55.439056)
						(mid 338.727334 -55.291274)
						(end 338.875116 -55.211472)
					)
				)
			)
		)
		(zone
			(layer "F.Cu")
			(hatch none 0.5)
			(connect_pads
				(clearance 0)
			)
			(min_thickness 0.25)
			(keepout
				(tracks not_allowed)
				(vias allowed)
				(pads allowed)
				(copperpour not_allowed)
				(footprints allowed)
			)
			(placement
				(enabled no)
				(sheetname "")
			)
			(fill
				(thermal_gap 0.5)
				(thermal_bridge_width 0.5)
				(island_removal_mode 0)
			)
			(polygon
				(pts
					(arc
						(start 338.875116 -54.376828)
						(mid 338.799289 -54.423429)
						(end 338.752688 -54.499256)
					)
					(arc
						(start 338.647532 -54.499256)
						(mid 338.727334 -54.351474)
						(end 338.875116 -54.271672)
					)
				)
			)
		)
		(zone
			(layer "F.Cu")
			(hatch none 0.5)
			(connect_pads
				(clearance 0)
			)
			(min_thickness 0.25)
			(keepout
				(tracks not_allowed)
				(vias allowed)
				(pads allowed)
				(copperpour not_allowed)
				(footprints allowed)
			)
			(placement
				(enabled no)
				(sheetname "")
			)
			(fill
				(thermal_gap 0.5)
				(thermal_bridge_width 0.5)
				(island_removal_mode 0)
			)
			(polygon
				(pts
					(arc
						(start 338.875116 -53.437028)
						(mid 338.799289 -53.483629)
						(end 338.752688 -53.559456)
					)
					(arc
						(start 338.647532 -53.559456)
						(mid 338.727334 -53.411674)
						(end 338.875116 -53.331872)
					)
				)
			)
		)
		(zone
			(layer "F.Cu")
			(hatch none 0.5)
			(connect_pads
				(clearance 0)
			)
			(min_thickness 0.25)
			(keepout
				(tracks not_allowed)
				(vias allowed)
				(pads allowed)
				(copperpour not_allowed)
				(footprints allowed)
			)
			(placement
				(enabled no)
				(sheetname "")
			)
			(fill
				(thermal_gap 0.5)
				(thermal_bridge_width 0.5)
				(island_removal_mode 0)
			)
			(polygon
				(pts
					(arc
						(start 338.875116 -52.497228)
						(mid 338.799289 -52.543829)
						(end 338.752688 -52.619656)
					)
					(arc
						(start 338.647532 -52.619656)
						(mid 338.727334 -52.471874)
						(end 338.875116 -52.392072)
					)
				)
			)
		)
		(zone
			(layer "F.Cu")
			(hatch none 0.5)
			(connect_pads
				(clearance 0)
			)
			(min_thickness 0.25)
			(keepout
				(tracks not_allowed)
				(vias allowed)
				(pads allowed)
				(copperpour not_allowed)
				(footprints allowed)
			)
			(placement
				(enabled no)
				(sheetname "")
			)
			(fill
				(thermal_gap 0.5)
				(thermal_bridge_width 0.5)
				(island_removal_mode 0)
			)
			(polygon
				(pts
					(arc
						(start 338.87537 -44.039028)
						(mid 338.799543 -44.085629)
						(end 338.752942 -44.161456)
					)
					(arc
						(start 338.647532 -44.161456)
						(mid 338.727422 -44.013586)
						(end 338.87537 -43.933872)
					)
				)
			)
		)
		(zone
			(layer "F.Cu")
			(hatch none 0.5)
			(connect_pads
				(clearance 0)
			)
			(min_thickness 0.25)
			(keepout
				(tracks not_allowed)
				(vias allowed)
				(pads allowed)
				(copperpour not_allowed)
				(footprints allowed)
			)
			(placement
				(enabled no)
				(sheetname "")
			)
			(fill
				(thermal_gap 0.5)
				(thermal_bridge_width 0.5)
				(island_removal_mode 0)
			)
			(polygon
				(pts
					(arc
						(start 338.87537 -43.099228)
						(mid 338.799543 -43.145829)
						(end 338.752942 -43.221656)
					)
					(arc
						(start 338.647532 -43.221656)
						(mid 338.727422 -43.073786)
						(end 338.87537 -42.994072)
					)
				)
			)
		)
		(zone
			(layer "F.Cu")
			(hatch none 0.5)
			(connect_pads
				(clearance 0)
			)
			(min_thickness 0.25)
			(keepout
				(tracks not_allowed)
				(vias allowed)
				(pads allowed)
				(copperpour not_allowed)
				(footprints allowed)
			)
			(placement
				(enabled no)
				(sheetname "")
			)
			(fill
				(thermal_gap 0.5)
				(thermal_bridge_width 0.5)
				(island_removal_mode 0)
			)
			(polygon
				(pts
					(arc
						(start 338.87537 -42.159428)
						(mid 338.799543 -42.206029)
						(end 338.752942 -42.281856)
					)
					(arc
						(start 338.647532 -42.281856)
						(mid 338.727422 -42.133986)
						(end 338.87537 -42.054272)
					)
				)
			)
		)
		(zone
			(layer "F.Cu")
			(hatch none 0.5)
			(connect_pads
				(clearance 0)
			)
			(min_thickness 0.25)
			(keepout
				(tracks not_allowed)
				(vias allowed)
				(pads allowed)
				(copperpour not_allowed)
				(footprints allowed)
			)
			(placement
				(enabled no)
				(sheetname "")
			)
			(fill
				(thermal_gap 0.5)
				(thermal_bridge_width 0.5)
				(island_removal_mode 0)
			)
			(polygon
				(pts
					(arc
						(start 338.87537 -41.219628)
						(mid 338.799543 -41.266229)
						(end 338.752942 -41.342056)
					)
					(arc
						(start 338.647532 -41.342056)
						(mid 338.727422 -41.194186)
						(end 338.87537 -41.114472)
					)
				)
			)
		)
		(zone
			(layer "F.Cu")
			(hatch none 0.5)
			(connect_pads
				(clearance 0)
			)
			(min_thickness 0.25)
			(keepout
				(tracks not_allowed)
				(vias allowed)
				(pads allowed)
				(copperpour not_allowed)
				(footprints allowed)
			)
			(placement
				(enabled no)
				(sheetname "")
			)
			(fill
				(thermal_gap 0.5)
				(thermal_bridge_width 0.5)
				(island_removal_mode 0)
			)
			(polygon
				(pts
					(arc
						(start 338.87537 -40.279828)
						(mid 338.799543 -40.326429)
						(end 338.752942 -40.402256)
					)
					(arc
						(start 338.647532 -40.402256)
						(mid 338.727422 -40.254386)
						(end 338.87537 -40.174672)
					)
				)
			)
		)
		(zone
			(layer "F.Cu")
			(hatch none 0.5)
			(connect_pads
				(clearance 0)
			)
			(min_thickness 0.25)
			(keepout
				(tracks not_allowed)
				(vias allowed)
				(pads allowed)
				(copperpour not_allowed)
				(footprints allowed)
			)
			(placement
				(enabled no)
				(sheetname "")
			)
			(fill
				(thermal_gap 0.5)
				(thermal_bridge_width 0.5)
				(island_removal_mode 0)
			)
			(polygon
				(pts
					(arc
						(start 338.994496 -56.620664)
						(mid 339.070323 -56.574063)
						(end 339.116924 -56.498236)
					)
					(arc
						(start 339.22208 -56.498236)
						(mid 339.142278 -56.646018)
						(end 338.994496 -56.72582)
					)
				)
			)
		)
		(zone
			(layer "F.Cu")
			(hatch none 0.5)
			(connect_pads
				(clearance 0)
			)
			(min_thickness 0.25)
			(keepout
				(tracks not_allowed)
				(vias allowed)
				(pads allowed)
				(copperpour not_allowed)
				(footprints allowed)
			)
			(placement
				(enabled no)
				(sheetname "")
			)
			(fill
				(thermal_gap 0.5)
				(thermal_bridge_width 0.5)
				(island_removal_mode 0)
			)
			(polygon
				(pts
					(arc
						(start 338.994496 -55.680864)
						(mid 339.070323 -55.634263)
						(end 339.116924 -55.558436)
					)
					(arc
						(start 339.22208 -55.558436)
						(mid 339.142278 -55.706218)
						(end 338.994496 -55.78602)
					)
				)
			)
		)
		(zone
			(layer "F.Cu")
			(hatch none 0.5)
			(connect_pads
				(clearance 0)
			)
			(min_thickness 0.25)
			(keepout
				(tracks not_allowed)
				(vias allowed)
				(pads allowed)
				(copperpour not_allowed)
				(footprints allowed)
			)
			(placement
				(enabled no)
				(sheetname "")
			)
			(fill
				(thermal_gap 0.5)
				(thermal_bridge_width 0.5)
				(island_removal_mode 0)
			)
			(polygon
				(pts
					(arc
						(start 338.994496 -54.741064)
						(mid 339.070323 -54.694463)
						(end 339.116924 -54.618636)
					)
					(arc
						(start 339.22208 -54.618636)
						(mid 339.142278 -54.766418)
						(end 338.994496 -54.84622)
					)
				)
			)
		)
		(zone
			(layer "F.Cu")
			(hatch none 0.5)
			(connect_pads
				(clearance 0)
			)
			(min_thickness 0.25)
			(keepout
				(tracks not_allowed)
				(vias allowed)
				(pads allowed)
				(copperpour not_allowed)
				(footprints allowed)
			)
			(placement
				(enabled no)
				(sheetname "")
			)
			(fill
				(thermal_gap 0.5)
				(thermal_bridge_width 0.5)
				(island_removal_mode 0)
			)
			(polygon
				(pts
					(arc
						(start 338.994496 -53.801264)
						(mid 339.070323 -53.754663)
						(end 339.116924 -53.678836)
					)
					(arc
						(start 339.22208 -53.678836)
						(mid 339.142278 -53.826618)
						(end 338.994496 -53.90642)
					)
				)
			)
		)
		(zone
			(layer "F.Cu")
			(hatch none 0.5)
			(connect_pads
				(clearance 0)
			)
			(min_thickness 0.25)
			(keepout
				(tracks not_allowed)
				(vias allowed)
				(pads allowed)
				(copperpour not_allowed)
				(footprints allowed)
			)
			(placement
				(enabled no)
				(sheetname "")
			)
			(fill
				(thermal_gap 0.5)
				(thermal_bridge_width 0.5)
				(island_removal_mode 0)
			)
			(polygon
				(pts
					(arc
						(start 338.994496 -52.861464)
						(mid 339.070323 -52.814863)
						(end 339.116924 -52.739036)
					)
					(arc
						(start 339.22208 -52.739036)
						(mid 339.142278 -52.886818)
						(end 338.994496 -52.96662)
					)
				)
			)
		)
		(zone
			(layer "F.Cu")
			(hatch none 0.5)
			(connect_pads
				(clearance 0)
			)
			(min_thickness 0.25)
			(keepout
				(tracks not_allowed)
				(vias allowed)
				(pads allowed)
				(copperpour not_allowed)
				(footprints allowed)
			)
			(placement
				(enabled no)
				(sheetname "")
			)
			(fill
				(thermal_gap 0.5)
				(thermal_bridge_width 0.5)
				(island_removal_mode 0)
			)
			(polygon
				(pts
					(arc
						(start 338.99475 -44.403264)
						(mid 339.070577 -44.356663)
						(end 339.117178 -44.280836)
					)
					(arc
						(start 339.222334 -44.280836)
						(mid 339.142532 -44.428618)
						(end 338.99475 -44.50842)
					)
				)
			)
		)
		(zone
			(layer "F.Cu")
			(hatch none 0.5)
			(connect_pads
				(clearance 0)
			)
			(min_thickness 0.25)
			(keepout
				(tracks not_allowed)
				(vias allowed)
				(pads allowed)
				(copperpour not_allowed)
				(footprints allowed)
			)
			(placement
				(enabled no)
				(sheetname "")
			)
			(fill
				(thermal_gap 0.5)
				(thermal_bridge_width 0.5)
				(island_removal_mode 0)
			)
			(polygon
				(pts
					(arc
						(start 338.99475 -43.463464)
						(mid 339.070577 -43.416863)
						(end 339.117178 -43.341036)
					)
					(arc
						(start 339.222334 -43.341036)
						(mid 339.142532 -43.488818)
						(end 338.99475 -43.56862)
					)
				)
			)
		)
		(zone
			(layer "F.Cu")
			(hatch none 0.5)
			(connect_pads
				(clearance 0)
			)
			(min_thickness 0.25)
			(keepout
				(tracks not_allowed)
				(vias allowed)
				(pads allowed)
				(copperpour not_allowed)
				(footprints allowed)
			)
			(placement
				(enabled no)
				(sheetname "")
			)
			(fill
				(thermal_gap 0.5)
				(thermal_bridge_width 0.5)
				(island_removal_mode 0)
			)
			(polygon
				(pts
					(arc
						(start 338.99475 -42.523664)
						(mid 339.070577 -42.477063)
						(end 339.117178 -42.401236)
					)
					(arc
						(start 339.222334 -42.401236)
						(mid 339.142532 -42.549018)
						(end 338.99475 -42.62882)
					)
				)
			)
		)
		(zone
			(layer "F.Cu")
			(hatch none 0.5)
			(connect_pads
				(clearance 0)
			)
			(min_thickness 0.25)
			(keepout
				(tracks not_allowed)
				(vias allowed)
				(pads allowed)
				(copperpour not_allowed)
				(footprints allowed)
			)
			(placement
				(enabled no)
				(sheetname "")
			)
			(fill
				(thermal_gap 0.5)
				(thermal_bridge_width 0.5)
				(island_removal_mode 0)
			)
			(polygon
				(pts
					(arc
						(start 338.99475 -41.583864)
						(mid 339.070577 -41.537263)
						(end 339.117178 -41.461436)
					)
					(arc
						(start 339.222334 -41.461436)
						(mid 339.142532 -41.609218)
						(end 338.99475 -41.68902)
					)
				)
			)
		)
		(zone
			(layer "F.Cu")
			(hatch none 0.5)
			(connect_pads
				(clearance 0)
			)
			(min_thickness 0.25)
			(keepout
				(tracks not_allowed)
				(vias allowed)
				(pads allowed)
				(copperpour not_allowed)
				(footprints allowed)
			)
			(placement
				(enabled no)
				(sheetname "")
			)
			(fill
				(thermal_gap 0.5)
				(thermal_bridge_width 0.5)
				(island_removal_mode 0)
			)
			(polygon
				(pts
					(arc
						(start 338.99475 -40.644064)
						(mid 339.070577 -40.597463)
						(end 339.117178 -40.521636)
					)
					(arc
						(start 339.222334 -40.521636)
						(mid 339.142532 -40.669418)
						(end 338.99475 -40.74922)
					)
				)
			)
		)
		(zone
			(layer "F.Cu")
			(hatch none 0.5)
			(connect_pads
				(clearance 0)
			)
			(min_thickness 0.25)
			(keepout
				(tracks not_allowed)
				(vias allowed)
				(pads allowed)
				(copperpour not_allowed)
				(footprints allowed)
			)
			(placement
				(enabled no)
				(sheetname "")
			)
			(fill
				(thermal_gap 0.5)
				(thermal_bridge_width 0.5)
				(island_removal_mode 0)
			)
			(polygon
				(pts
					(arc
						(start 339.116924 -56.378856)
						(mid 339.070323 -56.303029)
						(end 338.994496 -56.256428)
					)
					(arc
						(start 338.994496 -56.151272)
						(mid 339.142278 -56.231074)
						(end 339.22208 -56.378856)
					)
				)
			)
		)
		(zone
			(layer "F.Cu")
			(hatch none 0.5)
			(connect_pads
				(clearance 0)
			)
			(min_thickness 0.25)
			(keepout
				(tracks not_allowed)
				(vias allowed)
				(pads allowed)
				(copperpour not_allowed)
				(footprints allowed)
			)
			(placement
				(enabled no)
				(sheetname "")
			)
			(fill
				(thermal_gap 0.5)
				(thermal_bridge_width 0.5)
				(island_removal_mode 0)
			)
			(polygon
				(pts
					(arc
						(start 339.116924 -55.439056)
						(mid 339.070323 -55.363229)
						(end 338.994496 -55.316628)
					)
					(arc
						(start 338.994496 -55.211472)
						(mid 339.142278 -55.291274)
						(end 339.22208 -55.439056)
					)
				)
			)
		)
		(zone
			(layer "F.Cu")
			(hatch none 0.5)
			(connect_pads
				(clearance 0)
			)
			(min_thickness 0.25)
			(keepout
				(tracks not_allowed)
				(vias allowed)
				(pads allowed)
				(copperpour not_allowed)
				(footprints allowed)
			)
			(placement
				(enabled no)
				(sheetname "")
			)
			(fill
				(thermal_gap 0.5)
				(thermal_bridge_width 0.5)
				(island_removal_mode 0)
			)
			(polygon
				(pts
					(arc
						(start 339.116924 -54.499256)
						(mid 339.070323 -54.423429)
						(end 338.994496 -54.376828)
					)
					(arc
						(start 338.994496 -54.271672)
						(mid 339.142278 -54.351474)
						(end 339.22208 -54.499256)
					)
				)
			)
		)
		(zone
			(layer "F.Cu")
			(hatch none 0.5)
			(connect_pads
				(clearance 0)
			)
			(min_thickness 0.25)
			(keepout
				(tracks not_allowed)
				(vias allowed)
				(pads allowed)
				(copperpour not_allowed)
				(footprints allowed)
			)
			(placement
				(enabled no)
				(sheetname "")
			)
			(fill
				(thermal_gap 0.5)
				(thermal_bridge_width 0.5)
				(island_removal_mode 0)
			)
			(polygon
				(pts
					(arc
						(start 339.116924 -53.559456)
						(mid 339.070323 -53.483629)
						(end 338.994496 -53.437028)
					)
					(arc
						(start 338.994496 -53.331872)
						(mid 339.142278 -53.411674)
						(end 339.22208 -53.559456)
					)
				)
			)
		)
		(zone
			(layer "F.Cu")
			(hatch none 0.5)
			(connect_pads
				(clearance 0)
			)
			(min_thickness 0.25)
			(keepout
				(tracks not_allowed)
				(vias allowed)
				(pads allowed)
				(copperpour not_allowed)
				(footprints allowed)
			)
			(placement
				(enabled no)
				(sheetname "")
			)
			(fill
				(thermal_gap 0.5)
				(thermal_bridge_width 0.5)
				(island_removal_mode 0)
			)
			(polygon
				(pts
					(arc
						(start 339.116924 -52.619656)
						(mid 339.070323 -52.543829)
						(end 338.994496 -52.497228)
					)
					(arc
						(start 338.994496 -52.392072)
						(mid 339.142278 -52.471874)
						(end 339.22208 -52.619656)
					)
				)
			)
		)
		(zone
			(layer "F.Cu")
			(hatch none 0.5)
			(connect_pads
				(clearance 0)
			)
			(min_thickness 0.25)
			(keepout
				(tracks not_allowed)
				(vias allowed)
				(pads allowed)
				(copperpour not_allowed)
				(footprints allowed)
			)
			(placement
				(enabled no)
				(sheetname "")
			)
			(fill
				(thermal_gap 0.5)
				(thermal_bridge_width 0.5)
				(island_removal_mode 0)
			)
			(polygon
				(pts
					(arc
						(start 339.117178 -44.161456)
						(mid 339.070577 -44.085629)
						(end 338.99475 -44.039028)
					)
					(arc
						(start 338.99475 -43.933872)
						(mid 339.142532 -44.013674)
						(end 339.222334 -44.161456)
					)
				)
			)
		)
		(zone
			(layer "F.Cu")
			(hatch none 0.5)
			(connect_pads
				(clearance 0)
			)
			(min_thickness 0.25)
			(keepout
				(tracks not_allowed)
				(vias allowed)
				(pads allowed)
				(copperpour not_allowed)
				(footprints allowed)
			)
			(placement
				(enabled no)
				(sheetname "")
			)
			(fill
				(thermal_gap 0.5)
				(thermal_bridge_width 0.5)
				(island_removal_mode 0)
			)
			(polygon
				(pts
					(arc
						(start 339.117178 -43.221656)
						(mid 339.070577 -43.145829)
						(end 338.99475 -43.099228)
					)
					(arc
						(start 338.99475 -42.994072)
						(mid 339.142532 -43.073874)
						(end 339.222334 -43.221656)
					)
				)
			)
		)
		(zone
			(layer "F.Cu")
			(hatch none 0.5)
			(connect_pads
				(clearance 0)
			)
			(min_thickness 0.25)
			(keepout
				(tracks not_allowed)
				(vias allowed)
				(pads allowed)
				(copperpour not_allowed)
				(footprints allowed)
			)
			(placement
				(enabled no)
				(sheetname "")
			)
			(fill
				(thermal_gap 0.5)
				(thermal_bridge_width 0.5)
				(island_removal_mode 0)
			)
			(polygon
				(pts
					(arc
						(start 339.117178 -42.281856)
						(mid 339.070577 -42.206029)
						(end 338.99475 -42.159428)
					)
					(arc
						(start 338.99475 -42.054272)
						(mid 339.142532 -42.134074)
						(end 339.222334 -42.281856)
					)
				)
			)
		)
		(zone
			(layer "F.Cu")
			(hatch none 0.5)
			(connect_pads
				(clearance 0)
			)
			(min_thickness 0.25)
			(keepout
				(tracks not_allowed)
				(vias allowed)
				(pads allowed)
				(copperpour not_allowed)
				(footprints allowed)
			)
			(placement
				(enabled no)
				(sheetname "")
			)
			(fill
				(thermal_gap 0.5)
				(thermal_bridge_width 0.5)
				(island_removal_mode 0)
			)
			(polygon
				(pts
					(arc
						(start 339.117178 -41.342056)
						(mid 339.070577 -41.266229)
						(end 338.99475 -41.219628)
					)
					(arc
						(start 338.99475 -41.114472)
						(mid 339.142532 -41.194274)
						(end 339.222334 -41.342056)
					)
				)
			)
		)
		(zone
			(layer "F.Cu")
			(hatch none 0.5)
			(connect_pads
				(clearance 0)
			)
			(min_thickness 0.25)
			(keepout
				(tracks not_allowed)
				(vias allowed)
				(pads allowed)
				(copperpour not_allowed)
				(footprints allowed)
			)
			(placement
				(enabled no)
				(sheetname "")
			)
			(fill
				(thermal_gap 0.5)
				(thermal_bridge_width 0.5)
				(island_removal_mode 0)
			)
			(polygon
				(pts
					(arc
						(start 339.117178 -40.402256)
						(mid 339.070577 -40.326429)
						(end 338.99475 -40.279828)
					)
					(arc
						(start 338.99475 -40.174672)
						(mid 339.142532 -40.254474)
						(end 339.222334 -40.402256)
					)
				)
			)
		)
		(zone
			(layer "F.Cu")
			(hatch none 0.5)
			(connect_pads
				(clearance 0)
			)
			(min_thickness 0.25)
			(keepout
				(tracks not_allowed)
				(vias allowed)
				(pads allowed)
				(copperpour not_allowed)
				(footprints allowed)
			)
			(placement
				(enabled no)
				(sheetname "")
			)
			(fill
				(thermal_gap 0.5)
				(thermal_bridge_width 0.5)
				(island_removal_mode 0)
			)
			(polygon
				(pts
					(arc
						(start 339.11794 -51.710336)
						(mid 339.164541 -51.786163)
						(end 339.240368 -51.832764)
					)
					(arc
						(start 339.240368 -51.93792)
						(mid 339.092586 -51.858118)
						(end 339.012784 -51.710336)
					)
				)
			)
		)
		(zone
			(layer "F.Cu")
			(hatch none 0.5)
			(connect_pads
				(clearance 0)
			)
			(min_thickness 0.25)
			(keepout
				(tracks not_allowed)
				(vias allowed)
				(pads allowed)
				(copperpour not_allowed)
				(footprints allowed)
			)
			(placement
				(enabled no)
				(sheetname "")
			)
			(fill
				(thermal_gap 0.5)
				(thermal_bridge_width 0.5)
				(island_removal_mode 0)
			)
			(polygon
				(pts
					(arc
						(start 339.11794 -50.910236)
						(mid 339.164541 -50.986063)
						(end 339.240368 -51.032664)
					)
					(arc
						(start 339.240368 -51.13782)
						(mid 339.092586 -51.058018)
						(end 339.012784 -50.910236)
					)
				)
			)
		)
		(zone
			(layer "F.Cu")
			(hatch none 0.5)
			(connect_pads
				(clearance 0)
			)
			(min_thickness 0.25)
			(keepout
				(tracks not_allowed)
				(vias allowed)
				(pads allowed)
				(copperpour not_allowed)
				(footprints allowed)
			)
			(placement
				(enabled no)
				(sheetname "")
			)
			(fill
				(thermal_gap 0.5)
				(thermal_bridge_width 0.5)
				(island_removal_mode 0)
			)
			(polygon
				(pts
					(arc
						(start 339.11794 -50.110136)
						(mid 339.164541 -50.185963)
						(end 339.240368 -50.232564)
					)
					(arc
						(start 339.240368 -50.33772)
						(mid 339.092586 -50.257918)
						(end 339.012784 -50.110136)
					)
				)
			)
		)
		(zone
			(layer "F.Cu")
			(hatch none 0.5)
			(connect_pads
				(clearance 0)
			)
			(min_thickness 0.25)
			(keepout
				(tracks not_allowed)
				(vias allowed)
				(pads allowed)
				(copperpour not_allowed)
				(footprints allowed)
			)
			(placement
				(enabled no)
				(sheetname "")
			)
			(fill
				(thermal_gap 0.5)
				(thermal_bridge_width 0.5)
				(island_removal_mode 0)
			)
			(polygon
				(pts
					(arc
						(start 339.11794 -49.310036)
						(mid 339.164541 -49.385863)
						(end 339.240368 -49.432464)
					)
					(arc
						(start 339.240368 -49.53762)
						(mid 339.092586 -49.457818)
						(end 339.012784 -49.310036)
					)
				)
			)
		)
		(zone
			(layer "F.Cu")
			(hatch none 0.5)
			(connect_pads
				(clearance 0)
			)
			(min_thickness 0.25)
			(keepout
				(tracks not_allowed)
				(vias allowed)
				(pads allowed)
				(copperpour not_allowed)
				(footprints allowed)
			)
			(placement
				(enabled no)
				(sheetname "")
			)
			(fill
				(thermal_gap 0.5)
				(thermal_bridge_width 0.5)
				(island_removal_mode 0)
			)
			(polygon
				(pts
					(arc
						(start 339.11794 -48.509936)
						(mid 339.164541 -48.585763)
						(end 339.240368 -48.632364)
					)
					(arc
						(start 339.240368 -48.73752)
						(mid 339.092586 -48.657718)
						(end 339.012784 -48.509936)
					)
				)
			)
		)
		(zone
			(layer "F.Cu")
			(hatch none 0.5)
			(connect_pads
				(clearance 0)
			)
			(min_thickness 0.25)
			(keepout
				(tracks not_allowed)
				(vias allowed)
				(pads allowed)
				(copperpour not_allowed)
				(footprints allowed)
			)
			(placement
				(enabled no)
				(sheetname "")
			)
			(fill
				(thermal_gap 0.5)
				(thermal_bridge_width 0.5)
				(island_removal_mode 0)
			)
			(polygon
				(pts
					(arc
						(start 339.11794 -47.709836)
						(mid 339.164541 -47.785663)
						(end 339.240368 -47.832264)
					)
					(arc
						(start 339.240368 -47.93742)
						(mid 339.092586 -47.857618)
						(end 339.012784 -47.709836)
					)
				)
			)
		)
		(zone
			(layer "F.Cu")
			(hatch none 0.5)
			(connect_pads
				(clearance 0)
			)
			(min_thickness 0.25)
			(keepout
				(tracks not_allowed)
				(vias allowed)
				(pads allowed)
				(copperpour not_allowed)
				(footprints allowed)
			)
			(placement
				(enabled no)
				(sheetname "")
			)
			(fill
				(thermal_gap 0.5)
				(thermal_bridge_width 0.5)
				(island_removal_mode 0)
			)
			(polygon
				(pts
					(arc
						(start 339.11794 -46.909736)
						(mid 339.164541 -46.985563)
						(end 339.240368 -47.032164)
					)
					(arc
						(start 339.240368 -47.13732)
						(mid 339.092586 -47.057518)
						(end 339.012784 -46.909736)
					)
				)
			)
		)
		(zone
			(layer "F.Cu")
			(hatch none 0.5)
			(connect_pads
				(clearance 0)
			)
			(min_thickness 0.25)
			(keepout
				(tracks not_allowed)
				(vias allowed)
				(pads allowed)
				(copperpour not_allowed)
				(footprints allowed)
			)
			(placement
				(enabled no)
				(sheetname "")
			)
			(fill
				(thermal_gap 0.5)
				(thermal_bridge_width 0.5)
				(island_removal_mode 0)
			)
			(polygon
				(pts
					(arc
						(start 339.11794 -46.109636)
						(mid 339.164541 -46.185463)
						(end 339.240368 -46.232064)
					)
					(arc
						(start 339.240368 -46.33722)
						(mid 339.092586 -46.257418)
						(end 339.012784 -46.109636)
					)
				)
			)
		)
		(zone
			(layer "F.Cu")
			(hatch none 0.5)
			(connect_pads
				(clearance 0)
			)
			(min_thickness 0.25)
			(keepout
				(tracks not_allowed)
				(vias allowed)
				(pads allowed)
				(copperpour not_allowed)
				(footprints allowed)
			)
			(placement
				(enabled no)
				(sheetname "")
			)
			(fill
				(thermal_gap 0.5)
				(thermal_bridge_width 0.5)
				(island_removal_mode 0)
			)
			(polygon
				(pts
					(arc
						(start 339.11794 -45.309536)
						(mid 339.164541 -45.385363)
						(end 339.240368 -45.431964)
					)
					(arc
						(start 339.240368 -45.53712)
						(mid 339.092586 -45.457318)
						(end 339.012784 -45.309536)
					)
				)
			)
		)
		(zone
			(layer "F.Cu")
			(hatch none 0.5)
			(connect_pads
				(clearance 0)
			)
			(min_thickness 0.25)
			(keepout
				(tracks not_allowed)
				(vias allowed)
				(pads allowed)
				(copperpour not_allowed)
				(footprints allowed)
			)
			(placement
				(enabled no)
				(sheetname "")
			)
			(fill
				(thermal_gap 0.5)
				(thermal_bridge_width 0.5)
				(island_removal_mode 0)
			)
			(polygon
				(pts
					(arc
						(start 339.240368 -51.468528)
						(mid 339.164541 -51.515129)
						(end 339.11794 -51.590956)
					)
					(arc
						(start 339.012784 -51.590956)
						(mid 339.092586 -51.443174)
						(end 339.240368 -51.363372)
					)
				)
			)
		)
		(zone
			(layer "F.Cu")
			(hatch none 0.5)
			(connect_pads
				(clearance 0)
			)
			(min_thickness 0.25)
			(keepout
				(tracks not_allowed)
				(vias allowed)
				(pads allowed)
				(copperpour not_allowed)
				(footprints allowed)
			)
			(placement
				(enabled no)
				(sheetname "")
			)
			(fill
				(thermal_gap 0.5)
				(thermal_bridge_width 0.5)
				(island_removal_mode 0)
			)
			(polygon
				(pts
					(arc
						(start 339.240368 -50.668428)
						(mid 339.164541 -50.715029)
						(end 339.11794 -50.790856)
					)
					(arc
						(start 339.012784 -50.790856)
						(mid 339.092586 -50.643074)
						(end 339.240368 -50.563272)
					)
				)
			)
		)
		(zone
			(layer "F.Cu")
			(hatch none 0.5)
			(connect_pads
				(clearance 0)
			)
			(min_thickness 0.25)
			(keepout
				(tracks not_allowed)
				(vias allowed)
				(pads allowed)
				(copperpour not_allowed)
				(footprints allowed)
			)
			(placement
				(enabled no)
				(sheetname "")
			)
			(fill
				(thermal_gap 0.5)
				(thermal_bridge_width 0.5)
				(island_removal_mode 0)
			)
			(polygon
				(pts
					(arc
						(start 339.240368 -49.868328)
						(mid 339.164541 -49.914929)
						(end 339.11794 -49.990756)
					)
					(arc
						(start 339.012784 -49.990756)
						(mid 339.092586 -49.842974)
						(end 339.240368 -49.763172)
					)
				)
			)
		)
		(zone
			(layer "F.Cu")
			(hatch none 0.5)
			(connect_pads
				(clearance 0)
			)
			(min_thickness 0.25)
			(keepout
				(tracks not_allowed)
				(vias allowed)
				(pads allowed)
				(copperpour not_allowed)
				(footprints allowed)
			)
			(placement
				(enabled no)
				(sheetname "")
			)
			(fill
				(thermal_gap 0.5)
				(thermal_bridge_width 0.5)
				(island_removal_mode 0)
			)
			(polygon
				(pts
					(arc
						(start 339.240368 -49.068228)
						(mid 339.164541 -49.114829)
						(end 339.11794 -49.190656)
					)
					(arc
						(start 339.012784 -49.190656)
						(mid 339.092586 -49.042874)
						(end 339.240368 -48.963072)
					)
				)
			)
		)
		(zone
			(layer "F.Cu")
			(hatch none 0.5)
			(connect_pads
				(clearance 0)
			)
			(min_thickness 0.25)
			(keepout
				(tracks not_allowed)
				(vias allowed)
				(pads allowed)
				(copperpour not_allowed)
				(footprints allowed)
			)
			(placement
				(enabled no)
				(sheetname "")
			)
			(fill
				(thermal_gap 0.5)
				(thermal_bridge_width 0.5)
				(island_removal_mode 0)
			)
			(polygon
				(pts
					(arc
						(start 339.240368 -48.268128)
						(mid 339.164541 -48.314729)
						(end 339.11794 -48.390556)
					)
					(arc
						(start 339.012784 -48.390556)
						(mid 339.092586 -48.242774)
						(end 339.240368 -48.162972)
					)
				)
			)
		)
		(zone
			(layer "F.Cu")
			(hatch none 0.5)
			(connect_pads
				(clearance 0)
			)
			(min_thickness 0.25)
			(keepout
				(tracks not_allowed)
				(vias allowed)
				(pads allowed)
				(copperpour not_allowed)
				(footprints allowed)
			)
			(placement
				(enabled no)
				(sheetname "")
			)
			(fill
				(thermal_gap 0.5)
				(thermal_bridge_width 0.5)
				(island_removal_mode 0)
			)
			(polygon
				(pts
					(arc
						(start 339.240368 -47.468028)
						(mid 339.164541 -47.514629)
						(end 339.11794 -47.590456)
					)
					(arc
						(start 339.012784 -47.590456)
						(mid 339.092586 -47.442674)
						(end 339.240368 -47.362872)
					)
				)
			)
		)
		(zone
			(layer "F.Cu")
			(hatch none 0.5)
			(connect_pads
				(clearance 0)
			)
			(min_thickness 0.25)
			(keepout
				(tracks not_allowed)
				(vias allowed)
				(pads allowed)
				(copperpour not_allowed)
				(footprints allowed)
			)
			(placement
				(enabled no)
				(sheetname "")
			)
			(fill
				(thermal_gap 0.5)
				(thermal_bridge_width 0.5)
				(island_removal_mode 0)
			)
			(polygon
				(pts
					(arc
						(start 339.240368 -46.667928)
						(mid 339.164541 -46.714529)
						(end 339.11794 -46.790356)
					)
					(arc
						(start 339.012784 -46.790356)
						(mid 339.092586 -46.642574)
						(end 339.240368 -46.562772)
					)
				)
			)
		)
		(zone
			(layer "F.Cu")
			(hatch none 0.5)
			(connect_pads
				(clearance 0)
			)
			(min_thickness 0.25)
			(keepout
				(tracks not_allowed)
				(vias allowed)
				(pads allowed)
				(copperpour not_allowed)
				(footprints allowed)
			)
			(placement
				(enabled no)
				(sheetname "")
			)
			(fill
				(thermal_gap 0.5)
				(thermal_bridge_width 0.5)
				(island_removal_mode 0)
			)
			(polygon
				(pts
					(arc
						(start 339.240368 -45.867828)
						(mid 339.164541 -45.914429)
						(end 339.11794 -45.990256)
					)
					(arc
						(start 339.012784 -45.990256)
						(mid 339.092586 -45.842474)
						(end 339.240368 -45.762672)
					)
				)
			)
		)
		(zone
			(layer "F.Cu")
			(hatch none 0.5)
			(connect_pads
				(clearance 0)
			)
			(min_thickness 0.25)
			(keepout
				(tracks not_allowed)
				(vias allowed)
				(pads allowed)
				(copperpour not_allowed)
				(footprints allowed)
			)
			(placement
				(enabled no)
				(sheetname "")
			)
			(fill
				(thermal_gap 0.5)
				(thermal_bridge_width 0.5)
				(island_removal_mode 0)
			)
			(polygon
				(pts
					(arc
						(start 339.240368 -45.067728)
						(mid 339.164541 -45.114329)
						(end 339.11794 -45.190156)
					)
					(arc
						(start 339.012784 -45.190156)
						(mid 339.092586 -45.042374)
						(end 339.240368 -44.962572)
					)
				)
			)
		)
		(zone
			(layer "F.Cu")
			(hatch none 0.5)
			(connect_pads
				(clearance 0)
			)
			(min_thickness 0.25)
			(keepout
				(tracks not_allowed)
				(vias allowed)
				(pads allowed)
				(copperpour not_allowed)
				(footprints allowed)
			)
			(placement
				(enabled no)
				(sheetname "")
			)
			(fill
				(thermal_gap 0.5)
				(thermal_bridge_width 0.5)
				(island_removal_mode 0)
			)
			(polygon
				(pts
					(arc
						(start 339.359748 -51.832764)
						(mid 339.435575 -51.786163)
						(end 339.482176 -51.710336)
					)
					(arc
						(start 339.587332 -51.710336)
						(mid 339.50753 -51.858118)
						(end 339.359748 -51.93792)
					)
				)
			)
		)
		(zone
			(layer "F.Cu")
			(hatch none 0.5)
			(connect_pads
				(clearance 0)
			)
			(min_thickness 0.25)
			(keepout
				(tracks not_allowed)
				(vias allowed)
				(pads allowed)
				(copperpour not_allowed)
				(footprints allowed)
			)
			(placement
				(enabled no)
				(sheetname "")
			)
			(fill
				(thermal_gap 0.5)
				(thermal_bridge_width 0.5)
				(island_removal_mode 0)
			)
			(polygon
				(pts
					(arc
						(start 339.359748 -51.032664)
						(mid 339.435575 -50.986063)
						(end 339.482176 -50.910236)
					)
					(arc
						(start 339.587332 -50.910236)
						(mid 339.50753 -51.058018)
						(end 339.359748 -51.13782)
					)
				)
			)
		)
		(zone
			(layer "F.Cu")
			(hatch none 0.5)
			(connect_pads
				(clearance 0)
			)
			(min_thickness 0.25)
			(keepout
				(tracks not_allowed)
				(vias allowed)
				(pads allowed)
				(copperpour not_allowed)
				(footprints allowed)
			)
			(placement
				(enabled no)
				(sheetname "")
			)
			(fill
				(thermal_gap 0.5)
				(thermal_bridge_width 0.5)
				(island_removal_mode 0)
			)
			(polygon
				(pts
					(arc
						(start 339.359748 -50.232564)
						(mid 339.435575 -50.185963)
						(end 339.482176 -50.110136)
					)
					(arc
						(start 339.587332 -50.110136)
						(mid 339.50753 -50.257918)
						(end 339.359748 -50.33772)
					)
				)
			)
		)
		(zone
			(layer "F.Cu")
			(hatch none 0.5)
			(connect_pads
				(clearance 0)
			)
			(min_thickness 0.25)
			(keepout
				(tracks not_allowed)
				(vias allowed)
				(pads allowed)
				(copperpour not_allowed)
				(footprints allowed)
			)
			(placement
				(enabled no)
				(sheetname "")
			)
			(fill
				(thermal_gap 0.5)
				(thermal_bridge_width 0.5)
				(island_removal_mode 0)
			)
			(polygon
				(pts
					(arc
						(start 339.359748 -49.432464)
						(mid 339.435575 -49.385863)
						(end 339.482176 -49.310036)
					)
					(arc
						(start 339.587332 -49.310036)
						(mid 339.50753 -49.457818)
						(end 339.359748 -49.53762)
					)
				)
			)
		)
		(zone
			(layer "F.Cu")
			(hatch none 0.5)
			(connect_pads
				(clearance 0)
			)
			(min_thickness 0.25)
			(keepout
				(tracks not_allowed)
				(vias allowed)
				(pads allowed)
				(copperpour not_allowed)
				(footprints allowed)
			)
			(placement
				(enabled no)
				(sheetname "")
			)
			(fill
				(thermal_gap 0.5)
				(thermal_bridge_width 0.5)
				(island_removal_mode 0)
			)
			(polygon
				(pts
					(arc
						(start 339.359748 -48.632364)
						(mid 339.435575 -48.585763)
						(end 339.482176 -48.509936)
					)
					(arc
						(start 339.587332 -48.509936)
						(mid 339.50753 -48.657718)
						(end 339.359748 -48.73752)
					)
				)
			)
		)
		(zone
			(layer "F.Cu")
			(hatch none 0.5)
			(connect_pads
				(clearance 0)
			)
			(min_thickness 0.25)
			(keepout
				(tracks not_allowed)
				(vias allowed)
				(pads allowed)
				(copperpour not_allowed)
				(footprints allowed)
			)
			(placement
				(enabled no)
				(sheetname "")
			)
			(fill
				(thermal_gap 0.5)
				(thermal_bridge_width 0.5)
				(island_removal_mode 0)
			)
			(polygon
				(pts
					(arc
						(start 339.359748 -47.832264)
						(mid 339.435575 -47.785663)
						(end 339.482176 -47.709836)
					)
					(arc
						(start 339.587332 -47.709836)
						(mid 339.50753 -47.857618)
						(end 339.359748 -47.93742)
					)
				)
			)
		)
		(zone
			(layer "F.Cu")
			(hatch none 0.5)
			(connect_pads
				(clearance 0)
			)
			(min_thickness 0.25)
			(keepout
				(tracks not_allowed)
				(vias allowed)
				(pads allowed)
				(copperpour not_allowed)
				(footprints allowed)
			)
			(placement
				(enabled no)
				(sheetname "")
			)
			(fill
				(thermal_gap 0.5)
				(thermal_bridge_width 0.5)
				(island_removal_mode 0)
			)
			(polygon
				(pts
					(arc
						(start 339.359748 -47.032164)
						(mid 339.435575 -46.985563)
						(end 339.482176 -46.909736)
					)
					(arc
						(start 339.587332 -46.909736)
						(mid 339.50753 -47.057518)
						(end 339.359748 -47.13732)
					)
				)
			)
		)
		(zone
			(layer "F.Cu")
			(hatch none 0.5)
			(connect_pads
				(clearance 0)
			)
			(min_thickness 0.25)
			(keepout
				(tracks not_allowed)
				(vias allowed)
				(pads allowed)
				(copperpour not_allowed)
				(footprints allowed)
			)
			(placement
				(enabled no)
				(sheetname "")
			)
			(fill
				(thermal_gap 0.5)
				(thermal_bridge_width 0.5)
				(island_removal_mode 0)
			)
			(polygon
				(pts
					(arc
						(start 339.359748 -46.232064)
						(mid 339.435575 -46.185463)
						(end 339.482176 -46.109636)
					)
					(arc
						(start 339.587332 -46.109636)
						(mid 339.50753 -46.257418)
						(end 339.359748 -46.33722)
					)
				)
			)
		)
		(zone
			(layer "F.Cu")
			(hatch none 0.5)
			(connect_pads
				(clearance 0)
			)
			(min_thickness 0.25)
			(keepout
				(tracks not_allowed)
				(vias allowed)
				(pads allowed)
				(copperpour not_allowed)
				(footprints allowed)
			)
			(placement
				(enabled no)
				(sheetname "")
			)
			(fill
				(thermal_gap 0.5)
				(thermal_bridge_width 0.5)
				(island_removal_mode 0)
			)
			(polygon
				(pts
					(arc
						(start 339.359748 -45.431964)
						(mid 339.435575 -45.385363)
						(end 339.482176 -45.309536)
					)
					(arc
						(start 339.587332 -45.309536)
						(mid 339.50753 -45.457318)
						(end 339.359748 -45.53712)
					)
				)
			)
		)
		(zone
			(layer "F.Cu")
			(hatch none 0.5)
			(connect_pads
				(clearance 0)
			)
			(min_thickness 0.25)
			(keepout
				(tracks not_allowed)
				(vias allowed)
				(pads allowed)
				(copperpour not_allowed)
				(footprints allowed)
			)
			(placement
				(enabled no)
				(sheetname "")
			)
			(fill
				(thermal_gap 0.5)
				(thermal_bridge_width 0.5)
				(island_removal_mode 0)
			)
			(polygon
				(pts
					(arc
						(start 339.482176 -51.590956)
						(mid 339.435575 -51.515129)
						(end 339.359748 -51.468528)
					)
					(arc
						(start 339.359748 -51.363372)
						(mid 339.50753 -51.443174)
						(end 339.587332 -51.590956)
					)
				)
			)
		)
		(zone
			(layer "F.Cu")
			(hatch none 0.5)
			(connect_pads
				(clearance 0)
			)
			(min_thickness 0.25)
			(keepout
				(tracks not_allowed)
				(vias allowed)
				(pads allowed)
				(copperpour not_allowed)
				(footprints allowed)
			)
			(placement
				(enabled no)
				(sheetname "")
			)
			(fill
				(thermal_gap 0.5)
				(thermal_bridge_width 0.5)
				(island_removal_mode 0)
			)
			(polygon
				(pts
					(arc
						(start 339.482176 -50.790856)
						(mid 339.435575 -50.715029)
						(end 339.359748 -50.668428)
					)
					(arc
						(start 339.359748 -50.563272)
						(mid 339.50753 -50.643074)
						(end 339.587332 -50.790856)
					)
				)
			)
		)
		(zone
			(layer "F.Cu")
			(hatch none 0.5)
			(connect_pads
				(clearance 0)
			)
			(min_thickness 0.25)
			(keepout
				(tracks not_allowed)
				(vias allowed)
				(pads allowed)
				(copperpour not_allowed)
				(footprints allowed)
			)
			(placement
				(enabled no)
				(sheetname "")
			)
			(fill
				(thermal_gap 0.5)
				(thermal_bridge_width 0.5)
				(island_removal_mode 0)
			)
			(polygon
				(pts
					(arc
						(start 339.482176 -49.990756)
						(mid 339.435575 -49.914929)
						(end 339.359748 -49.868328)
					)
					(arc
						(start 339.359748 -49.763172)
						(mid 339.50753 -49.842974)
						(end 339.587332 -49.990756)
					)
				)
			)
		)
		(zone
			(layer "F.Cu")
			(hatch none 0.5)
			(connect_pads
				(clearance 0)
			)
			(min_thickness 0.25)
			(keepout
				(tracks not_allowed)
				(vias allowed)
				(pads allowed)
				(copperpour not_allowed)
				(footprints allowed)
			)
			(placement
				(enabled no)
				(sheetname "")
			)
			(fill
				(thermal_gap 0.5)
				(thermal_bridge_width 0.5)
				(island_removal_mode 0)
			)
			(polygon
				(pts
					(arc
						(start 339.482176 -49.190656)
						(mid 339.435575 -49.114829)
						(end 339.359748 -49.068228)
					)
					(arc
						(start 339.359748 -48.963072)
						(mid 339.50753 -49.042874)
						(end 339.587332 -49.190656)
					)
				)
			)
		)
		(zone
			(layer "F.Cu")
			(hatch none 0.5)
			(connect_pads
				(clearance 0)
			)
			(min_thickness 0.25)
			(keepout
				(tracks not_allowed)
				(vias allowed)
				(pads allowed)
				(copperpour not_allowed)
				(footprints allowed)
			)
			(placement
				(enabled no)
				(sheetname "")
			)
			(fill
				(thermal_gap 0.5)
				(thermal_bridge_width 0.5)
				(island_removal_mode 0)
			)
			(polygon
				(pts
					(arc
						(start 339.482176 -48.390556)
						(mid 339.435575 -48.314729)
						(end 339.359748 -48.268128)
					)
					(arc
						(start 339.359748 -48.162972)
						(mid 339.50753 -48.242774)
						(end 339.587332 -48.390556)
					)
				)
			)
		)
		(zone
			(layer "F.Cu")
			(hatch none 0.5)
			(connect_pads
				(clearance 0)
			)
			(min_thickness 0.25)
			(keepout
				(tracks not_allowed)
				(vias allowed)
				(pads allowed)
				(copperpour not_allowed)
				(footprints allowed)
			)
			(placement
				(enabled no)
				(sheetname "")
			)
			(fill
				(thermal_gap 0.5)
				(thermal_bridge_width 0.5)
				(island_removal_mode 0)
			)
			(polygon
				(pts
					(arc
						(start 339.482176 -47.590456)
						(mid 339.435575 -47.514629)
						(end 339.359748 -47.468028)
					)
					(arc
						(start 339.359748 -47.362872)
						(mid 339.50753 -47.442674)
						(end 339.587332 -47.590456)
					)
				)
			)
		)
		(zone
			(layer "F.Cu")
			(hatch none 0.5)
			(connect_pads
				(clearance 0)
			)
			(min_thickness 0.25)
			(keepout
				(tracks not_allowed)
				(vias allowed)
				(pads allowed)
				(copperpour not_allowed)
				(footprints allowed)
			)
			(placement
				(enabled no)
				(sheetname "")
			)
			(fill
				(thermal_gap 0.5)
				(thermal_bridge_width 0.5)
				(island_removal_mode 0)
			)
			(polygon
				(pts
					(arc
						(start 339.482176 -46.790356)
						(mid 339.435575 -46.714529)
						(end 339.359748 -46.667928)
					)
					(arc
						(start 339.359748 -46.562772)
						(mid 339.50753 -46.642574)
						(end 339.587332 -46.790356)
					)
				)
			)
		)
		(zone
			(layer "F.Cu")
			(hatch none 0.5)
			(connect_pads
				(clearance 0)
			)
			(min_thickness 0.25)
			(keepout
				(tracks not_allowed)
				(vias allowed)
				(pads allowed)
				(copperpour not_allowed)
				(footprints allowed)
			)
			(placement
				(enabled no)
				(sheetname "")
			)
			(fill
				(thermal_gap 0.5)
				(thermal_bridge_width 0.5)
				(island_removal_mode 0)
			)
			(polygon
				(pts
					(arc
						(start 339.482176 -45.990256)
						(mid 339.435575 -45.914429)
						(end 339.359748 -45.867828)
					)
					(arc
						(start 339.359748 -45.762672)
						(mid 339.50753 -45.842474)
						(end 339.587332 -45.990256)
					)
				)
			)
		)
		(zone
			(layer "F.Cu")
			(hatch none 0.5)
			(connect_pads
				(clearance 0)
			)
			(min_thickness 0.25)
			(keepout
				(tracks not_allowed)
				(vias allowed)
				(pads allowed)
				(copperpour not_allowed)
				(footprints allowed)
			)
			(placement
				(enabled no)
				(sheetname "")
			)
			(fill
				(thermal_gap 0.5)
				(thermal_bridge_width 0.5)
				(island_removal_mode 0)
			)
			(polygon
				(pts
					(arc
						(start 339.482176 -45.190156)
						(mid 339.435575 -45.114329)
						(end 339.359748 -45.067728)
					)
					(arc
						(start 339.359748 -44.962572)
						(mid 339.50753 -45.042374)
						(end 339.587332 -45.190156)
					)
				)
			)
		)
		(zone
			(layer "F.Cu")
			(hatch none 0.5)
			(connect_pads
				(clearance 0)
			)
			(min_thickness 0.25)
			(keepout
				(tracks not_allowed)
				(vias allowed)
				(pads allowed)
				(copperpour not_allowed)
				(footprints allowed)
			)
			(placement
				(enabled no)
				(sheetname "")
			)
			(fill
				(thermal_gap 0.5)
				(thermal_bridge_width 0.5)
				(island_removal_mode 0)
			)
			(polygon
				(pts
					(arc
						(start 339.566758 -56.968136)
						(mid 339.613359 -57.043963)
						(end 339.689186 -57.090564)
					)
					(arc
						(start 339.689186 -57.19572)
						(mid 339.541404 -57.115918)
						(end 339.461602 -56.968136)
					)
				)
			)
		)
		(zone
			(layer "F.Cu")
			(hatch none 0.5)
			(connect_pads
				(clearance 0)
			)
			(min_thickness 0.25)
			(keepout
				(tracks not_allowed)
				(vias allowed)
				(pads allowed)
				(copperpour not_allowed)
				(footprints allowed)
			)
			(placement
				(enabled no)
				(sheetname "")
			)
			(fill
				(thermal_gap 0.5)
				(thermal_bridge_width 0.5)
				(island_removal_mode 0)
			)
			(polygon
				(pts
					(arc
						(start 339.566758 -56.028336)
						(mid 339.613359 -56.104163)
						(end 339.689186 -56.150764)
					)
					(arc
						(start 339.689186 -56.25592)
						(mid 339.541404 -56.176118)
						(end 339.461602 -56.028336)
					)
				)
			)
		)
		(zone
			(layer "F.Cu")
			(hatch none 0.5)
			(connect_pads
				(clearance 0)
			)
			(min_thickness 0.25)
			(keepout
				(tracks not_allowed)
				(vias allowed)
				(pads allowed)
				(copperpour not_allowed)
				(footprints allowed)
			)
			(placement
				(enabled no)
				(sheetname "")
			)
			(fill
				(thermal_gap 0.5)
				(thermal_bridge_width 0.5)
				(island_removal_mode 0)
			)
			(polygon
				(pts
					(arc
						(start 339.566758 -55.088536)
						(mid 339.613359 -55.164363)
						(end 339.689186 -55.210964)
					)
					(arc
						(start 339.689186 -55.31612)
						(mid 339.541404 -55.236318)
						(end 339.461602 -55.088536)
					)
				)
			)
		)
		(zone
			(layer "F.Cu")
			(hatch none 0.5)
			(connect_pads
				(clearance 0)
			)
			(min_thickness 0.25)
			(keepout
				(tracks not_allowed)
				(vias allowed)
				(pads allowed)
				(copperpour not_allowed)
				(footprints allowed)
			)
			(placement
				(enabled no)
				(sheetname "")
			)
			(fill
				(thermal_gap 0.5)
				(thermal_bridge_width 0.5)
				(island_removal_mode 0)
			)
			(polygon
				(pts
					(arc
						(start 339.566758 -54.148736)
						(mid 339.613359 -54.224563)
						(end 339.689186 -54.271164)
					)
					(arc
						(start 339.689186 -54.37632)
						(mid 339.541404 -54.296518)
						(end 339.461602 -54.148736)
					)
				)
			)
		)
		(zone
			(layer "F.Cu")
			(hatch none 0.5)
			(connect_pads
				(clearance 0)
			)
			(min_thickness 0.25)
			(keepout
				(tracks not_allowed)
				(vias allowed)
				(pads allowed)
				(copperpour not_allowed)
				(footprints allowed)
			)
			(placement
				(enabled no)
				(sheetname "")
			)
			(fill
				(thermal_gap 0.5)
				(thermal_bridge_width 0.5)
				(island_removal_mode 0)
			)
			(polygon
				(pts
					(arc
						(start 339.566758 -53.208936)
						(mid 339.613359 -53.284763)
						(end 339.689186 -53.331364)
					)
					(arc
						(start 339.689186 -53.43652)
						(mid 339.541404 -53.356718)
						(end 339.461602 -53.208936)
					)
				)
			)
		)
		(zone
			(layer "F.Cu")
			(hatch none 0.5)
			(connect_pads
				(clearance 0)
			)
			(min_thickness 0.25)
			(keepout
				(tracks not_allowed)
				(vias allowed)
				(pads allowed)
				(copperpour not_allowed)
				(footprints allowed)
			)
			(placement
				(enabled no)
				(sheetname "")
			)
			(fill
				(thermal_gap 0.5)
				(thermal_bridge_width 0.5)
				(island_removal_mode 0)
			)
			(polygon
				(pts
					(arc
						(start 339.566758 -43.810936)
						(mid 339.613359 -43.886763)
						(end 339.689186 -43.933364)
					)
					(arc
						(start 339.689186 -44.03852)
						(mid 339.541404 -43.958718)
						(end 339.461602 -43.810936)
					)
				)
			)
		)
		(zone
			(layer "F.Cu")
			(hatch none 0.5)
			(connect_pads
				(clearance 0)
			)
			(min_thickness 0.25)
			(keepout
				(tracks not_allowed)
				(vias allowed)
				(pads allowed)
				(copperpour not_allowed)
				(footprints allowed)
			)
			(placement
				(enabled no)
				(sheetname "")
			)
			(fill
				(thermal_gap 0.5)
				(thermal_bridge_width 0.5)
				(island_removal_mode 0)
			)
			(polygon
				(pts
					(arc
						(start 339.566758 -42.871136)
						(mid 339.613359 -42.946963)
						(end 339.689186 -42.993564)
					)
					(arc
						(start 339.689186 -43.09872)
						(mid 339.541404 -43.018918)
						(end 339.461602 -42.871136)
					)
				)
			)
		)
		(zone
			(layer "F.Cu")
			(hatch none 0.5)
			(connect_pads
				(clearance 0)
			)
			(min_thickness 0.25)
			(keepout
				(tracks not_allowed)
				(vias allowed)
				(pads allowed)
				(copperpour not_allowed)
				(footprints allowed)
			)
			(placement
				(enabled no)
				(sheetname "")
			)
			(fill
				(thermal_gap 0.5)
				(thermal_bridge_width 0.5)
				(island_removal_mode 0)
			)
			(polygon
				(pts
					(arc
						(start 339.566758 -41.931336)
						(mid 339.613359 -42.007163)
						(end 339.689186 -42.053764)
					)
					(arc
						(start 339.689186 -42.15892)
						(mid 339.541404 -42.079118)
						(end 339.461602 -41.931336)
					)
				)
			)
		)
		(zone
			(layer "F.Cu")
			(hatch none 0.5)
			(connect_pads
				(clearance 0)
			)
			(min_thickness 0.25)
			(keepout
				(tracks not_allowed)
				(vias allowed)
				(pads allowed)
				(copperpour not_allowed)
				(footprints allowed)
			)
			(placement
				(enabled no)
				(sheetname "")
			)
			(fill
				(thermal_gap 0.5)
				(thermal_bridge_width 0.5)
				(island_removal_mode 0)
			)
			(polygon
				(pts
					(arc
						(start 339.566758 -40.991536)
						(mid 339.613359 -41.067363)
						(end 339.689186 -41.113964)
					)
					(arc
						(start 339.689186 -41.21912)
						(mid 339.541404 -41.139318)
						(end 339.461602 -40.991536)
					)
				)
			)
		)
		(zone
			(layer "F.Cu")
			(hatch none 0.5)
			(connect_pads
				(clearance 0)
			)
			(min_thickness 0.25)
			(keepout
				(tracks not_allowed)
				(vias allowed)
				(pads allowed)
				(copperpour not_allowed)
				(footprints allowed)
			)
			(placement
				(enabled no)
				(sheetname "")
			)
			(fill
				(thermal_gap 0.5)
				(thermal_bridge_width 0.5)
				(island_removal_mode 0)
			)
			(polygon
				(pts
					(arc
						(start 339.566758 -40.051736)
						(mid 339.613359 -40.127563)
						(end 339.689186 -40.174164)
					)
					(arc
						(start 339.689186 -40.27932)
						(mid 339.541404 -40.199518)
						(end 339.461602 -40.051736)
					)
				)
			)
		)
		(zone
			(layer "F.Cu")
			(hatch none 0.5)
			(connect_pads
				(clearance 0)
			)
			(min_thickness 0.25)
			(keepout
				(tracks not_allowed)
				(vias allowed)
				(pads allowed)
				(copperpour not_allowed)
				(footprints allowed)
			)
			(placement
				(enabled no)
				(sheetname "")
			)
			(fill
				(thermal_gap 0.5)
				(thermal_bridge_width 0.5)
				(island_removal_mode 0)
			)
			(polygon
				(pts
					(arc
						(start 339.689186 -56.726328)
						(mid 339.613359 -56.772929)
						(end 339.566758 -56.848756)
					)
					(arc
						(start 339.461602 -56.848756)
						(mid 339.541404 -56.700974)
						(end 339.689186 -56.621172)
					)
				)
			)
		)
		(zone
			(layer "F.Cu")
			(hatch none 0.5)
			(connect_pads
				(clearance 0)
			)
			(min_thickness 0.25)
			(keepout
				(tracks not_allowed)
				(vias allowed)
				(pads allowed)
				(copperpour not_allowed)
				(footprints allowed)
			)
			(placement
				(enabled no)
				(sheetname "")
			)
			(fill
				(thermal_gap 0.5)
				(thermal_bridge_width 0.5)
				(island_removal_mode 0)
			)
			(polygon
				(pts
					(arc
						(start 339.689186 -55.786528)
						(mid 339.613359 -55.833129)
						(end 339.566758 -55.908956)
					)
					(arc
						(start 339.461602 -55.908956)
						(mid 339.541404 -55.761174)
						(end 339.689186 -55.681372)
					)
				)
			)
		)
		(zone
			(layer "F.Cu")
			(hatch none 0.5)
			(connect_pads
				(clearance 0)
			)
			(min_thickness 0.25)
			(keepout
				(tracks not_allowed)
				(vias allowed)
				(pads allowed)
				(copperpour not_allowed)
				(footprints allowed)
			)
			(placement
				(enabled no)
				(sheetname "")
			)
			(fill
				(thermal_gap 0.5)
				(thermal_bridge_width 0.5)
				(island_removal_mode 0)
			)
			(polygon
				(pts
					(arc
						(start 339.689186 -54.846728)
						(mid 339.613359 -54.893329)
						(end 339.566758 -54.969156)
					)
					(arc
						(start 339.461602 -54.969156)
						(mid 339.541404 -54.821374)
						(end 339.689186 -54.741572)
					)
				)
			)
		)
		(zone
			(layer "F.Cu")
			(hatch none 0.5)
			(connect_pads
				(clearance 0)
			)
			(min_thickness 0.25)
			(keepout
				(tracks not_allowed)
				(vias allowed)
				(pads allowed)
				(copperpour not_allowed)
				(footprints allowed)
			)
			(placement
				(enabled no)
				(sheetname "")
			)
			(fill
				(thermal_gap 0.5)
				(thermal_bridge_width 0.5)
				(island_removal_mode 0)
			)
			(polygon
				(pts
					(arc
						(start 339.689186 -53.906928)
						(mid 339.613359 -53.953529)
						(end 339.566758 -54.029356)
					)
					(arc
						(start 339.461602 -54.029356)
						(mid 339.541404 -53.881574)
						(end 339.689186 -53.801772)
					)
				)
			)
		)
		(zone
			(layer "F.Cu")
			(hatch none 0.5)
			(connect_pads
				(clearance 0)
			)
			(min_thickness 0.25)
			(keepout
				(tracks not_allowed)
				(vias allowed)
				(pads allowed)
				(copperpour not_allowed)
				(footprints allowed)
			)
			(placement
				(enabled no)
				(sheetname "")
			)
			(fill
				(thermal_gap 0.5)
				(thermal_bridge_width 0.5)
				(island_removal_mode 0)
			)
			(polygon
				(pts
					(arc
						(start 339.689186 -52.967128)
						(mid 339.613359 -53.013729)
						(end 339.566758 -53.089556)
					)
					(arc
						(start 339.461602 -53.089556)
						(mid 339.541404 -52.941774)
						(end 339.689186 -52.861972)
					)
				)
			)
		)
		(zone
			(layer "F.Cu")
			(hatch none 0.5)
			(connect_pads
				(clearance 0)
			)
			(min_thickness 0.25)
			(keepout
				(tracks not_allowed)
				(vias allowed)
				(pads allowed)
				(copperpour not_allowed)
				(footprints allowed)
			)
			(placement
				(enabled no)
				(sheetname "")
			)
			(fill
				(thermal_gap 0.5)
				(thermal_bridge_width 0.5)
				(island_removal_mode 0)
			)
			(polygon
				(pts
					(arc
						(start 339.689186 -43.569128)
						(mid 339.613359 -43.615729)
						(end 339.566758 -43.691556)
					)
					(arc
						(start 339.461602 -43.691556)
						(mid 339.541404 -43.543774)
						(end 339.689186 -43.463972)
					)
				)
			)
		)
		(zone
			(layer "F.Cu")
			(hatch none 0.5)
			(connect_pads
				(clearance 0)
			)
			(min_thickness 0.25)
			(keepout
				(tracks not_allowed)
				(vias allowed)
				(pads allowed)
				(copperpour not_allowed)
				(footprints allowed)
			)
			(placement
				(enabled no)
				(sheetname "")
			)
			(fill
				(thermal_gap 0.5)
				(thermal_bridge_width 0.5)
				(island_removal_mode 0)
			)
			(polygon
				(pts
					(arc
						(start 339.689186 -42.629328)
						(mid 339.613359 -42.675929)
						(end 339.566758 -42.751756)
					)
					(arc
						(start 339.461602 -42.751756)
						(mid 339.541404 -42.603974)
						(end 339.689186 -42.524172)
					)
				)
			)
		)
		(zone
			(layer "F.Cu")
			(hatch none 0.5)
			(connect_pads
				(clearance 0)
			)
			(min_thickness 0.25)
			(keepout
				(tracks not_allowed)
				(vias allowed)
				(pads allowed)
				(copperpour not_allowed)
				(footprints allowed)
			)
			(placement
				(enabled no)
				(sheetname "")
			)
			(fill
				(thermal_gap 0.5)
				(thermal_bridge_width 0.5)
				(island_removal_mode 0)
			)
			(polygon
				(pts
					(arc
						(start 339.689186 -41.689528)
						(mid 339.613359 -41.736129)
						(end 339.566758 -41.811956)
					)
					(arc
						(start 339.461602 -41.811956)
						(mid 339.541404 -41.664174)
						(end 339.689186 -41.584372)
					)
				)
			)
		)
		(zone
			(layer "F.Cu")
			(hatch none 0.5)
			(connect_pads
				(clearance 0)
			)
			(min_thickness 0.25)
			(keepout
				(tracks not_allowed)
				(vias allowed)
				(pads allowed)
				(copperpour not_allowed)
				(footprints allowed)
			)
			(placement
				(enabled no)
				(sheetname "")
			)
			(fill
				(thermal_gap 0.5)
				(thermal_bridge_width 0.5)
				(island_removal_mode 0)
			)
			(polygon
				(pts
					(arc
						(start 339.689186 -40.749728)
						(mid 339.613359 -40.796329)
						(end 339.566758 -40.872156)
					)
					(arc
						(start 339.461602 -40.872156)
						(mid 339.541404 -40.724374)
						(end 339.689186 -40.644572)
					)
				)
			)
		)
		(zone
			(layer "F.Cu")
			(hatch none 0.5)
			(connect_pads
				(clearance 0)
			)
			(min_thickness 0.25)
			(keepout
				(tracks not_allowed)
				(vias allowed)
				(pads allowed)
				(copperpour not_allowed)
				(footprints allowed)
			)
			(placement
				(enabled no)
				(sheetname "")
			)
			(fill
				(thermal_gap 0.5)
				(thermal_bridge_width 0.5)
				(island_removal_mode 0)
			)
			(polygon
				(pts
					(arc
						(start 339.689186 -39.809928)
						(mid 339.613359 -39.856529)
						(end 339.566758 -39.932356)
					)
					(arc
						(start 339.461602 -39.932356)
						(mid 339.541404 -39.784574)
						(end 339.689186 -39.704772)
					)
				)
			)
		)
		(zone
			(layer "F.Cu")
			(hatch none 0.5)
			(connect_pads
				(clearance 0)
			)
			(min_thickness 0.25)
			(keepout
				(tracks not_allowed)
				(vias allowed)
				(pads allowed)
				(copperpour not_allowed)
				(footprints allowed)
			)
			(placement
				(enabled no)
				(sheetname "")
			)
			(fill
				(thermal_gap 0.5)
				(thermal_bridge_width 0.5)
				(island_removal_mode 0)
			)
			(polygon
				(pts
					(arc
						(start 339.808566 -57.090564)
						(mid 339.884393 -57.043963)
						(end 339.930994 -56.968136)
					)
					(arc
						(start 340.03615 -56.968136)
						(mid 339.956348 -57.115918)
						(end 339.808566 -57.19572)
					)
				)
			)
		)
		(zone
			(layer "F.Cu")
			(hatch none 0.5)
			(connect_pads
				(clearance 0)
			)
			(min_thickness 0.25)
			(keepout
				(tracks not_allowed)
				(vias allowed)
				(pads allowed)
				(copperpour not_allowed)
				(footprints allowed)
			)
			(placement
				(enabled no)
				(sheetname "")
			)
			(fill
				(thermal_gap 0.5)
				(thermal_bridge_width 0.5)
				(island_removal_mode 0)
			)
			(polygon
				(pts
					(arc
						(start 339.808566 -56.150764)
						(mid 339.884393 -56.104163)
						(end 339.930994 -56.028336)
					)
					(arc
						(start 340.03615 -56.028336)
						(mid 339.956348 -56.176118)
						(end 339.808566 -56.25592)
					)
				)
			)
		)
		(zone
			(layer "F.Cu")
			(hatch none 0.5)
			(connect_pads
				(clearance 0)
			)
			(min_thickness 0.25)
			(keepout
				(tracks not_allowed)
				(vias allowed)
				(pads allowed)
				(copperpour not_allowed)
				(footprints allowed)
			)
			(placement
				(enabled no)
				(sheetname "")
			)
			(fill
				(thermal_gap 0.5)
				(thermal_bridge_width 0.5)
				(island_removal_mode 0)
			)
			(polygon
				(pts
					(arc
						(start 339.808566 -55.210964)
						(mid 339.884393 -55.164363)
						(end 339.930994 -55.088536)
					)
					(arc
						(start 340.03615 -55.088536)
						(mid 339.956348 -55.236318)
						(end 339.808566 -55.31612)
					)
				)
			)
		)
		(zone
			(layer "F.Cu")
			(hatch none 0.5)
			(connect_pads
				(clearance 0)
			)
			(min_thickness 0.25)
			(keepout
				(tracks not_allowed)
				(vias allowed)
				(pads allowed)
				(copperpour not_allowed)
				(footprints allowed)
			)
			(placement
				(enabled no)
				(sheetname "")
			)
			(fill
				(thermal_gap 0.5)
				(thermal_bridge_width 0.5)
				(island_removal_mode 0)
			)
			(polygon
				(pts
					(arc
						(start 339.808566 -54.271164)
						(mid 339.884393 -54.224563)
						(end 339.930994 -54.148736)
					)
					(arc
						(start 340.03615 -54.148736)
						(mid 339.956348 -54.296518)
						(end 339.808566 -54.37632)
					)
				)
			)
		)
		(zone
			(layer "F.Cu")
			(hatch none 0.5)
			(connect_pads
				(clearance 0)
			)
			(min_thickness 0.25)
			(keepout
				(tracks not_allowed)
				(vias allowed)
				(pads allowed)
				(copperpour not_allowed)
				(footprints allowed)
			)
			(placement
				(enabled no)
				(sheetname "")
			)
			(fill
				(thermal_gap 0.5)
				(thermal_bridge_width 0.5)
				(island_removal_mode 0)
			)
			(polygon
				(pts
					(arc
						(start 339.808566 -53.331364)
						(mid 339.884393 -53.284763)
						(end 339.930994 -53.208936)
					)
					(arc
						(start 340.03615 -53.208936)
						(mid 339.956348 -53.356718)
						(end 339.808566 -53.43652)
					)
				)
			)
		)
		(zone
			(layer "F.Cu")
			(hatch none 0.5)
			(connect_pads
				(clearance 0)
			)
			(min_thickness 0.25)
			(keepout
				(tracks not_allowed)
				(vias allowed)
				(pads allowed)
				(copperpour not_allowed)
				(footprints allowed)
			)
			(placement
				(enabled no)
				(sheetname "")
			)
			(fill
				(thermal_gap 0.5)
				(thermal_bridge_width 0.5)
				(island_removal_mode 0)
			)
			(polygon
				(pts
					(arc
						(start 339.808566 -43.933364)
						(mid 339.884393 -43.886763)
						(end 339.930994 -43.810936)
					)
					(arc
						(start 340.03615 -43.810936)
						(mid 339.956348 -43.958718)
						(end 339.808566 -44.03852)
					)
				)
			)
		)
		(zone
			(layer "F.Cu")
			(hatch none 0.5)
			(connect_pads
				(clearance 0)
			)
			(min_thickness 0.25)
			(keepout
				(tracks not_allowed)
				(vias allowed)
				(pads allowed)
				(copperpour not_allowed)
				(footprints allowed)
			)
			(placement
				(enabled no)
				(sheetname "")
			)
			(fill
				(thermal_gap 0.5)
				(thermal_bridge_width 0.5)
				(island_removal_mode 0)
			)
			(polygon
				(pts
					(arc
						(start 339.808566 -42.993564)
						(mid 339.884393 -42.946963)
						(end 339.930994 -42.871136)
					)
					(arc
						(start 340.03615 -42.871136)
						(mid 339.956348 -43.018918)
						(end 339.808566 -43.09872)
					)
				)
			)
		)
		(zone
			(layer "F.Cu")
			(hatch none 0.5)
			(connect_pads
				(clearance 0)
			)
			(min_thickness 0.25)
			(keepout
				(tracks not_allowed)
				(vias allowed)
				(pads allowed)
				(copperpour not_allowed)
				(footprints allowed)
			)
			(placement
				(enabled no)
				(sheetname "")
			)
			(fill
				(thermal_gap 0.5)
				(thermal_bridge_width 0.5)
				(island_removal_mode 0)
			)
			(polygon
				(pts
					(arc
						(start 339.808566 -42.053764)
						(mid 339.884393 -42.007163)
						(end 339.930994 -41.931336)
					)
					(arc
						(start 340.03615 -41.931336)
						(mid 339.956348 -42.079118)
						(end 339.808566 -42.15892)
					)
				)
			)
		)
		(zone
			(layer "F.Cu")
			(hatch none 0.5)
			(connect_pads
				(clearance 0)
			)
			(min_thickness 0.25)
			(keepout
				(tracks not_allowed)
				(vias allowed)
				(pads allowed)
				(copperpour not_allowed)
				(footprints allowed)
			)
			(placement
				(enabled no)
				(sheetname "")
			)
			(fill
				(thermal_gap 0.5)
				(thermal_bridge_width 0.5)
				(island_removal_mode 0)
			)
			(polygon
				(pts
					(arc
						(start 339.808566 -41.113964)
						(mid 339.884393 -41.067363)
						(end 339.930994 -40.991536)
					)
					(arc
						(start 340.03615 -40.991536)
						(mid 339.956348 -41.139318)
						(end 339.808566 -41.21912)
					)
				)
			)
		)
		(zone
			(layer "F.Cu")
			(hatch none 0.5)
			(connect_pads
				(clearance 0)
			)
			(min_thickness 0.25)
			(keepout
				(tracks not_allowed)
				(vias allowed)
				(pads allowed)
				(copperpour not_allowed)
				(footprints allowed)
			)
			(placement
				(enabled no)
				(sheetname "")
			)
			(fill
				(thermal_gap 0.5)
				(thermal_bridge_width 0.5)
				(island_removal_mode 0)
			)
			(polygon
				(pts
					(arc
						(start 339.808566 -40.174164)
						(mid 339.884393 -40.127563)
						(end 339.930994 -40.051736)
					)
					(arc
						(start 340.03615 -40.051736)
						(mid 339.956348 -40.199518)
						(end 339.808566 -40.27932)
					)
				)
			)
		)
		(zone
			(layer "F.Cu")
			(hatch none 0.5)
			(connect_pads
				(clearance 0)
			)
			(min_thickness 0.25)
			(keepout
				(tracks not_allowed)
				(vias allowed)
				(pads allowed)
				(copperpour not_allowed)
				(footprints allowed)
			)
			(placement
				(enabled no)
				(sheetname "")
			)
			(fill
				(thermal_gap 0.5)
				(thermal_bridge_width 0.5)
				(island_removal_mode 0)
			)
			(polygon
				(pts
					(arc
						(start 339.930994 -56.848756)
						(mid 339.884393 -56.772929)
						(end 339.808566 -56.726328)
					)
					(arc
						(start 339.808566 -56.621172)
						(mid 339.956348 -56.700974)
						(end 340.03615 -56.848756)
					)
				)
			)
		)
		(zone
			(layer "F.Cu")
			(hatch none 0.5)
			(connect_pads
				(clearance 0)
			)
			(min_thickness 0.25)
			(keepout
				(tracks not_allowed)
				(vias allowed)
				(pads allowed)
				(copperpour not_allowed)
				(footprints allowed)
			)
			(placement
				(enabled no)
				(sheetname "")
			)
			(fill
				(thermal_gap 0.5)
				(thermal_bridge_width 0.5)
				(island_removal_mode 0)
			)
			(polygon
				(pts
					(arc
						(start 339.930994 -55.908956)
						(mid 339.884393 -55.833129)
						(end 339.808566 -55.786528)
					)
					(arc
						(start 339.808566 -55.681372)
						(mid 339.956348 -55.761174)
						(end 340.03615 -55.908956)
					)
				)
			)
		)
		(zone
			(layer "F.Cu")
			(hatch none 0.5)
			(connect_pads
				(clearance 0)
			)
			(min_thickness 0.25)
			(keepout
				(tracks not_allowed)
				(vias allowed)
				(pads allowed)
				(copperpour not_allowed)
				(footprints allowed)
			)
			(placement
				(enabled no)
				(sheetname "")
			)
			(fill
				(thermal_gap 0.5)
				(thermal_bridge_width 0.5)
				(island_removal_mode 0)
			)
			(polygon
				(pts
					(arc
						(start 339.930994 -54.969156)
						(mid 339.884393 -54.893329)
						(end 339.808566 -54.846728)
					)
					(arc
						(start 339.808566 -54.741572)
						(mid 339.956348 -54.821374)
						(end 340.03615 -54.969156)
					)
				)
			)
		)
		(zone
			(layer "F.Cu")
			(hatch none 0.5)
			(connect_pads
				(clearance 0)
			)
			(min_thickness 0.25)
			(keepout
				(tracks not_allowed)
				(vias allowed)
				(pads allowed)
				(copperpour not_allowed)
				(footprints allowed)
			)
			(placement
				(enabled no)
				(sheetname "")
			)
			(fill
				(thermal_gap 0.5)
				(thermal_bridge_width 0.5)
				(island_removal_mode 0)
			)
			(polygon
				(pts
					(arc
						(start 339.930994 -54.029356)
						(mid 339.884393 -53.953529)
						(end 339.808566 -53.906928)
					)
					(arc
						(start 339.808566 -53.801772)
						(mid 339.956348 -53.881574)
						(end 340.03615 -54.029356)
					)
				)
			)
		)
		(zone
			(layer "F.Cu")
			(hatch none 0.5)
			(connect_pads
				(clearance 0)
			)
			(min_thickness 0.25)
			(keepout
				(tracks not_allowed)
				(vias allowed)
				(pads allowed)
				(copperpour not_allowed)
				(footprints allowed)
			)
			(placement
				(enabled no)
				(sheetname "")
			)
			(fill
				(thermal_gap 0.5)
				(thermal_bridge_width 0.5)
				(island_removal_mode 0)
			)
			(polygon
				(pts
					(arc
						(start 339.930994 -53.089556)
						(mid 339.884393 -53.013729)
						(end 339.808566 -52.967128)
					)
					(arc
						(start 339.808566 -52.861972)
						(mid 339.956348 -52.941774)
						(end 340.03615 -53.089556)
					)
				)
			)
		)
		(zone
			(layer "F.Cu")
			(hatch none 0.5)
			(connect_pads
				(clearance 0)
			)
			(min_thickness 0.25)
			(keepout
				(tracks not_allowed)
				(vias allowed)
				(pads allowed)
				(copperpour not_allowed)
				(footprints allowed)
			)
			(placement
				(enabled no)
				(sheetname "")
			)
			(fill
				(thermal_gap 0.5)
				(thermal_bridge_width 0.5)
				(island_removal_mode 0)
			)
			(polygon
				(pts
					(arc
						(start 339.930994 -43.691556)
						(mid 339.884393 -43.615729)
						(end 339.808566 -43.569128)
					)
					(arc
						(start 339.808566 -43.463972)
						(mid 339.956348 -43.543774)
						(end 340.03615 -43.691556)
					)
				)
			)
		)
		(zone
			(layer "F.Cu")
			(hatch none 0.5)
			(connect_pads
				(clearance 0)
			)
			(min_thickness 0.25)
			(keepout
				(tracks not_allowed)
				(vias allowed)
				(pads allowed)
				(copperpour not_allowed)
				(footprints allowed)
			)
			(placement
				(enabled no)
				(sheetname "")
			)
			(fill
				(thermal_gap 0.5)
				(thermal_bridge_width 0.5)
				(island_removal_mode 0)
			)
			(polygon
				(pts
					(arc
						(start 339.930994 -42.751756)
						(mid 339.884393 -42.675929)
						(end 339.808566 -42.629328)
					)
					(arc
						(start 339.808566 -42.524172)
						(mid 339.956348 -42.603974)
						(end 340.03615 -42.751756)
					)
				)
			)
		)
		(zone
			(layer "F.Cu")
			(hatch none 0.5)
			(connect_pads
				(clearance 0)
			)
			(min_thickness 0.25)
			(keepout
				(tracks not_allowed)
				(vias allowed)
				(pads allowed)
				(copperpour not_allowed)
				(footprints allowed)
			)
			(placement
				(enabled no)
				(sheetname "")
			)
			(fill
				(thermal_gap 0.5)
				(thermal_bridge_width 0.5)
				(island_removal_mode 0)
			)
			(polygon
				(pts
					(arc
						(start 339.930994 -41.811956)
						(mid 339.884393 -41.736129)
						(end 339.808566 -41.689528)
					)
					(arc
						(start 339.808566 -41.584372)
						(mid 339.956348 -41.664174)
						(end 340.03615 -41.811956)
					)
				)
			)
		)
		(zone
			(layer "F.Cu")
			(hatch none 0.5)
			(connect_pads
				(clearance 0)
			)
			(min_thickness 0.25)
			(keepout
				(tracks not_allowed)
				(vias allowed)
				(pads allowed)
				(copperpour not_allowed)
				(footprints allowed)
			)
			(placement
				(enabled no)
				(sheetname "")
			)
			(fill
				(thermal_gap 0.5)
				(thermal_bridge_width 0.5)
				(island_removal_mode 0)
			)
			(polygon
				(pts
					(arc
						(start 339.930994 -40.872156)
						(mid 339.884393 -40.796329)
						(end 339.808566 -40.749728)
					)
					(arc
						(start 339.808566 -40.644572)
						(mid 339.956348 -40.724374)
						(end 340.03615 -40.872156)
					)
				)
			)
		)
		(zone
			(layer "F.Cu")
			(hatch none 0.5)
			(connect_pads
				(clearance 0)
			)
			(min_thickness 0.25)
			(keepout
				(tracks not_allowed)
				(vias allowed)
				(pads allowed)
				(copperpour not_allowed)
				(footprints allowed)
			)
			(placement
				(enabled no)
				(sheetname "")
			)
			(fill
				(thermal_gap 0.5)
				(thermal_bridge_width 0.5)
				(island_removal_mode 0)
			)
			(polygon
				(pts
					(arc
						(start 339.930994 -39.932356)
						(mid 339.884393 -39.856529)
						(end 339.808566 -39.809928)
					)
					(arc
						(start 339.808566 -39.704772)
						(mid 339.956348 -39.784574)
						(end 340.03615 -39.932356)
					)
				)
			)
		)
		(zone
			(layer "F.Cu")
			(hatch none 0.5)
			(connect_pads
				(clearance 0)
			)
			(min_thickness 0.25)
			(keepout
				(tracks not_allowed)
				(vias allowed)
				(pads allowed)
				(copperpour not_allowed)
				(footprints allowed)
			)
			(placement
				(enabled no)
				(sheetname "")
			)
			(fill
				(thermal_gap 0.5)
				(thermal_bridge_width 0.5)
				(island_removal_mode 0)
			)
			(polygon
				(pts
					(arc
						(start 340.381082 -56.498236)
						(mid 340.427597 -56.573978)
						(end 340.503256 -56.620664)
					)
					(arc
						(start 340.503256 -56.72582)
						(mid 340.355474 -56.646018)
						(end 340.275672 -56.498236)
					)
				)
			)
		)
		(zone
			(layer "F.Cu")
			(hatch none 0.5)
			(connect_pads
				(clearance 0)
			)
			(min_thickness 0.25)
			(keepout
				(tracks not_allowed)
				(vias allowed)
				(pads allowed)
				(copperpour not_allowed)
				(footprints allowed)
			)
			(placement
				(enabled no)
				(sheetname "")
			)
			(fill
				(thermal_gap 0.5)
				(thermal_bridge_width 0.5)
				(island_removal_mode 0)
			)
			(polygon
				(pts
					(arc
						(start 340.381082 -55.558436)
						(mid 340.427597 -55.634178)
						(end 340.503256 -55.680864)
					)
					(arc
						(start 340.503256 -55.78602)
						(mid 340.355474 -55.706218)
						(end 340.275672 -55.558436)
					)
				)
			)
		)
		(zone
			(layer "F.Cu")
			(hatch none 0.5)
			(connect_pads
				(clearance 0)
			)
			(min_thickness 0.25)
			(keepout
				(tracks not_allowed)
				(vias allowed)
				(pads allowed)
				(copperpour not_allowed)
				(footprints allowed)
			)
			(placement
				(enabled no)
				(sheetname "")
			)
			(fill
				(thermal_gap 0.5)
				(thermal_bridge_width 0.5)
				(island_removal_mode 0)
			)
			(polygon
				(pts
					(arc
						(start 340.381082 -54.618636)
						(mid 340.427597 -54.694378)
						(end 340.503256 -54.741064)
					)
					(arc
						(start 340.503256 -54.84622)
						(mid 340.355474 -54.766418)
						(end 340.275672 -54.618636)
					)
				)
			)
		)
		(zone
			(layer "F.Cu")
			(hatch none 0.5)
			(connect_pads
				(clearance 0)
			)
			(min_thickness 0.25)
			(keepout
				(tracks not_allowed)
				(vias allowed)
				(pads allowed)
				(copperpour not_allowed)
				(footprints allowed)
			)
			(placement
				(enabled no)
				(sheetname "")
			)
			(fill
				(thermal_gap 0.5)
				(thermal_bridge_width 0.5)
				(island_removal_mode 0)
			)
			(polygon
				(pts
					(arc
						(start 340.381082 -53.678836)
						(mid 340.427597 -53.754578)
						(end 340.503256 -53.801264)
					)
					(arc
						(start 340.503256 -53.90642)
						(mid 340.355474 -53.826618)
						(end 340.275672 -53.678836)
					)
				)
			)
		)
		(zone
			(layer "F.Cu")
			(hatch none 0.5)
			(connect_pads
				(clearance 0)
			)
			(min_thickness 0.25)
			(keepout
				(tracks not_allowed)
				(vias allowed)
				(pads allowed)
				(copperpour not_allowed)
				(footprints allowed)
			)
			(placement
				(enabled no)
				(sheetname "")
			)
			(fill
				(thermal_gap 0.5)
				(thermal_bridge_width 0.5)
				(island_removal_mode 0)
			)
			(polygon
				(pts
					(arc
						(start 340.381082 -52.739036)
						(mid 340.427597 -52.814778)
						(end 340.503256 -52.861464)
					)
					(arc
						(start 340.503256 -52.96662)
						(mid 340.355474 -52.886818)
						(end 340.275672 -52.739036)
					)
				)
			)
		)
		(zone
			(layer "F.Cu")
			(hatch none 0.5)
			(connect_pads
				(clearance 0)
			)
			(min_thickness 0.25)
			(keepout
				(tracks not_allowed)
				(vias allowed)
				(pads allowed)
				(copperpour not_allowed)
				(footprints allowed)
			)
			(placement
				(enabled no)
				(sheetname "")
			)
			(fill
				(thermal_gap 0.5)
				(thermal_bridge_width 0.5)
				(island_removal_mode 0)
			)
			(polygon
				(pts
					(arc
						(start 340.381082 -51.799236)
						(mid 340.427597 -51.874978)
						(end 340.503256 -51.921664)
					)
					(arc
						(start 340.503256 -52.02682)
						(mid 340.355474 -51.947018)
						(end 340.275672 -51.799236)
					)
				)
			)
		)
		(zone
			(layer "F.Cu")
			(hatch none 0.5)
			(connect_pads
				(clearance 0)
			)
			(min_thickness 0.25)
			(keepout
				(tracks not_allowed)
				(vias allowed)
				(pads allowed)
				(copperpour not_allowed)
				(footprints allowed)
			)
			(placement
				(enabled no)
				(sheetname "")
			)
			(fill
				(thermal_gap 0.5)
				(thermal_bridge_width 0.5)
				(island_removal_mode 0)
			)
			(polygon
				(pts
					(arc
						(start 340.381082 -50.859436)
						(mid 340.427597 -50.935178)
						(end 340.503256 -50.981864)
					)
					(arc
						(start 340.503256 -51.08702)
						(mid 340.355474 -51.007218)
						(end 340.275672 -50.859436)
					)
				)
			)
		)
		(zone
			(layer "F.Cu")
			(hatch none 0.5)
			(connect_pads
				(clearance 0)
			)
			(min_thickness 0.25)
			(keepout
				(tracks not_allowed)
				(vias allowed)
				(pads allowed)
				(copperpour not_allowed)
				(footprints allowed)
			)
			(placement
				(enabled no)
				(sheetname "")
			)
			(fill
				(thermal_gap 0.5)
				(thermal_bridge_width 0.5)
				(island_removal_mode 0)
			)
			(polygon
				(pts
					(arc
						(start 340.381082 -49.919636)
						(mid 340.427597 -49.995378)
						(end 340.503256 -50.042064)
					)
					(arc
						(start 340.503256 -50.14722)
						(mid 340.355474 -50.067418)
						(end 340.275672 -49.919636)
					)
				)
			)
		)
		(zone
			(layer "F.Cu")
			(hatch none 0.5)
			(connect_pads
				(clearance 0)
			)
			(min_thickness 0.25)
			(keepout
				(tracks not_allowed)
				(vias allowed)
				(pads allowed)
				(copperpour not_allowed)
				(footprints allowed)
			)
			(placement
				(enabled no)
				(sheetname "")
			)
			(fill
				(thermal_gap 0.5)
				(thermal_bridge_width 0.5)
				(island_removal_mode 0)
			)
			(polygon
				(pts
					(arc
						(start 340.381082 -48.979836)
						(mid 340.427597 -49.055578)
						(end 340.503256 -49.102264)
					)
					(arc
						(start 340.503256 -49.20742)
						(mid 340.355474 -49.127618)
						(end 340.275672 -48.979836)
					)
				)
			)
		)
		(zone
			(layer "F.Cu")
			(hatch none 0.5)
			(connect_pads
				(clearance 0)
			)
			(min_thickness 0.25)
			(keepout
				(tracks not_allowed)
				(vias allowed)
				(pads allowed)
				(copperpour not_allowed)
				(footprints allowed)
			)
			(placement
				(enabled no)
				(sheetname "")
			)
			(fill
				(thermal_gap 0.5)
				(thermal_bridge_width 0.5)
				(island_removal_mode 0)
			)
			(polygon
				(pts
					(arc
						(start 340.381082 -48.040036)
						(mid 340.427597 -48.115778)
						(end 340.503256 -48.162464)
					)
					(arc
						(start 340.503256 -48.26762)
						(mid 340.355474 -48.187818)
						(end 340.275672 -48.040036)
					)
				)
			)
		)
		(zone
			(layer "F.Cu")
			(hatch none 0.5)
			(connect_pads
				(clearance 0)
			)
			(min_thickness 0.25)
			(keepout
				(tracks not_allowed)
				(vias allowed)
				(pads allowed)
				(copperpour not_allowed)
				(footprints allowed)
			)
			(placement
				(enabled no)
				(sheetname "")
			)
			(fill
				(thermal_gap 0.5)
				(thermal_bridge_width 0.5)
				(island_removal_mode 0)
			)
			(polygon
				(pts
					(arc
						(start 340.381082 -47.100236)
						(mid 340.427597 -47.175978)
						(end 340.503256 -47.222664)
					)
					(arc
						(start 340.503256 -47.32782)
						(mid 340.355474 -47.248018)
						(end 340.275672 -47.100236)
					)
				)
			)
		)
		(zone
			(layer "F.Cu")
			(hatch none 0.5)
			(connect_pads
				(clearance 0)
			)
			(min_thickness 0.25)
			(keepout
				(tracks not_allowed)
				(vias allowed)
				(pads allowed)
				(copperpour not_allowed)
				(footprints allowed)
			)
			(placement
				(enabled no)
				(sheetname "")
			)
			(fill
				(thermal_gap 0.5)
				(thermal_bridge_width 0.5)
				(island_removal_mode 0)
			)
			(polygon
				(pts
					(arc
						(start 340.381082 -46.160436)
						(mid 340.427597 -46.236178)
						(end 340.503256 -46.282864)
					)
					(arc
						(start 340.503256 -46.38802)
						(mid 340.355474 -46.308218)
						(end 340.275672 -46.160436)
					)
				)
			)
		)
		(zone
			(layer "F.Cu")
			(hatch none 0.5)
			(connect_pads
				(clearance 0)
			)
			(min_thickness 0.25)
			(keepout
				(tracks not_allowed)
				(vias allowed)
				(pads allowed)
				(copperpour not_allowed)
				(footprints allowed)
			)
			(placement
				(enabled no)
				(sheetname "")
			)
			(fill
				(thermal_gap 0.5)
				(thermal_bridge_width 0.5)
				(island_removal_mode 0)
			)
			(polygon
				(pts
					(arc
						(start 340.381082 -45.220636)
						(mid 340.427597 -45.296378)
						(end 340.503256 -45.343064)
					)
					(arc
						(start 340.503256 -45.44822)
						(mid 340.355474 -45.368418)
						(end 340.275672 -45.220636)
					)
				)
			)
		)
		(zone
			(layer "F.Cu")
			(hatch none 0.5)
			(connect_pads
				(clearance 0)
			)
			(min_thickness 0.25)
			(keepout
				(tracks not_allowed)
				(vias allowed)
				(pads allowed)
				(copperpour not_allowed)
				(footprints allowed)
			)
			(placement
				(enabled no)
				(sheetname "")
			)
			(fill
				(thermal_gap 0.5)
				(thermal_bridge_width 0.5)
				(island_removal_mode 0)
			)
			(polygon
				(pts
					(arc
						(start 340.381082 -44.280836)
						(mid 340.427597 -44.356578)
						(end 340.503256 -44.403264)
					)
					(arc
						(start 340.503256 -44.50842)
						(mid 340.355474 -44.428618)
						(end 340.275672 -44.280836)
					)
				)
			)
		)
		(zone
			(layer "F.Cu")
			(hatch none 0.5)
			(connect_pads
				(clearance 0)
			)
			(min_thickness 0.25)
			(keepout
				(tracks not_allowed)
				(vias allowed)
				(pads allowed)
				(copperpour not_allowed)
				(footprints allowed)
			)
			(placement
				(enabled no)
				(sheetname "")
			)
			(fill
				(thermal_gap 0.5)
				(thermal_bridge_width 0.5)
				(island_removal_mode 0)
			)
			(polygon
				(pts
					(arc
						(start 340.381082 -43.341036)
						(mid 340.427597 -43.416778)
						(end 340.503256 -43.463464)
					)
					(arc
						(start 340.503256 -43.56862)
						(mid 340.355474 -43.488818)
						(end 340.275672 -43.341036)
					)
				)
			)
		)
		(zone
			(layer "F.Cu")
			(hatch none 0.5)
			(connect_pads
				(clearance 0)
			)
			(min_thickness 0.25)
			(keepout
				(tracks not_allowed)
				(vias allowed)
				(pads allowed)
				(copperpour not_allowed)
				(footprints allowed)
			)
			(placement
				(enabled no)
				(sheetname "")
			)
			(fill
				(thermal_gap 0.5)
				(thermal_bridge_width 0.5)
				(island_removal_mode 0)
			)
			(polygon
				(pts
					(arc
						(start 340.381082 -42.401236)
						(mid 340.427597 -42.476978)
						(end 340.503256 -42.523664)
					)
					(arc
						(start 340.503256 -42.62882)
						(mid 340.355474 -42.549018)
						(end 340.275672 -42.401236)
					)
				)
			)
		)
		(zone
			(layer "F.Cu")
			(hatch none 0.5)
			(connect_pads
				(clearance 0)
			)
			(min_thickness 0.25)
			(keepout
				(tracks not_allowed)
				(vias allowed)
				(pads allowed)
				(copperpour not_allowed)
				(footprints allowed)
			)
			(placement
				(enabled no)
				(sheetname "")
			)
			(fill
				(thermal_gap 0.5)
				(thermal_bridge_width 0.5)
				(island_removal_mode 0)
			)
			(polygon
				(pts
					(arc
						(start 340.381082 -41.461436)
						(mid 340.427597 -41.537178)
						(end 340.503256 -41.583864)
					)
					(arc
						(start 340.503256 -41.68902)
						(mid 340.355474 -41.609218)
						(end 340.275672 -41.461436)
					)
				)
			)
		)
		(zone
			(layer "F.Cu")
			(hatch none 0.5)
			(connect_pads
				(clearance 0)
			)
			(min_thickness 0.25)
			(keepout
				(tracks not_allowed)
				(vias allowed)
				(pads allowed)
				(copperpour not_allowed)
				(footprints allowed)
			)
			(placement
				(enabled no)
				(sheetname "")
			)
			(fill
				(thermal_gap 0.5)
				(thermal_bridge_width 0.5)
				(island_removal_mode 0)
			)
			(polygon
				(pts
					(arc
						(start 340.381082 -40.521636)
						(mid 340.427597 -40.597378)
						(end 340.503256 -40.644064)
					)
					(arc
						(start 340.503256 -40.74922)
						(mid 340.355474 -40.669418)
						(end 340.275672 -40.521636)
					)
				)
			)
		)
		(zone
			(layer "F.Cu")
			(hatch none 0.5)
			(connect_pads
				(clearance 0)
			)
			(min_thickness 0.25)
			(keepout
				(tracks not_allowed)
				(vias allowed)
				(pads allowed)
				(copperpour not_allowed)
				(footprints allowed)
			)
			(placement
				(enabled no)
				(sheetname "")
			)
			(fill
				(thermal_gap 0.5)
				(thermal_bridge_width 0.5)
				(island_removal_mode 0)
			)
			(polygon
				(pts
					(arc
						(start 340.503256 -56.256428)
						(mid 340.427541 -56.303058)
						(end 340.381082 -56.378856)
					)
					(arc
						(start 340.275672 -56.378856)
						(mid 340.355474 -56.231074)
						(end 340.503256 -56.151272)
					)
				)
			)
		)
		(zone
			(layer "F.Cu")
			(hatch none 0.5)
			(connect_pads
				(clearance 0)
			)
			(min_thickness 0.25)
			(keepout
				(tracks not_allowed)
				(vias allowed)
				(pads allowed)
				(copperpour not_allowed)
				(footprints allowed)
			)
			(placement
				(enabled no)
				(sheetname "")
			)
			(fill
				(thermal_gap 0.5)
				(thermal_bridge_width 0.5)
				(island_removal_mode 0)
			)
			(polygon
				(pts
					(arc
						(start 340.503256 -55.316628)
						(mid 340.427541 -55.363258)
						(end 340.381082 -55.439056)
					)
					(arc
						(start 340.275672 -55.439056)
						(mid 340.355474 -55.291274)
						(end 340.503256 -55.211472)
					)
				)
			)
		)
		(zone
			(layer "F.Cu")
			(hatch none 0.5)
			(connect_pads
				(clearance 0)
			)
			(min_thickness 0.25)
			(keepout
				(tracks not_allowed)
				(vias allowed)
				(pads allowed)
				(copperpour not_allowed)
				(footprints allowed)
			)
			(placement
				(enabled no)
				(sheetname "")
			)
			(fill
				(thermal_gap 0.5)
				(thermal_bridge_width 0.5)
				(island_removal_mode 0)
			)
			(polygon
				(pts
					(arc
						(start 340.503256 -54.376828)
						(mid 340.427541 -54.423458)
						(end 340.381082 -54.499256)
					)
					(arc
						(start 340.275672 -54.499256)
						(mid 340.355474 -54.351474)
						(end 340.503256 -54.271672)
					)
				)
			)
		)
		(zone
			(layer "F.Cu")
			(hatch none 0.5)
			(connect_pads
				(clearance 0)
			)
			(min_thickness 0.25)
			(keepout
				(tracks not_allowed)
				(vias allowed)
				(pads allowed)
				(copperpour not_allowed)
				(footprints allowed)
			)
			(placement
				(enabled no)
				(sheetname "")
			)
			(fill
				(thermal_gap 0.5)
				(thermal_bridge_width 0.5)
				(island_removal_mode 0)
			)
			(polygon
				(pts
					(arc
						(start 340.503256 -53.437028)
						(mid 340.427541 -53.483658)
						(end 340.381082 -53.559456)
					)
					(arc
						(start 340.275672 -53.559456)
						(mid 340.355474 -53.411674)
						(end 340.503256 -53.331872)
					)
				)
			)
		)
		(zone
			(layer "F.Cu")
			(hatch none 0.5)
			(connect_pads
				(clearance 0)
			)
			(min_thickness 0.25)
			(keepout
				(tracks not_allowed)
				(vias allowed)
				(pads allowed)
				(copperpour not_allowed)
				(footprints allowed)
			)
			(placement
				(enabled no)
				(sheetname "")
			)
			(fill
				(thermal_gap 0.5)
				(thermal_bridge_width 0.5)
				(island_removal_mode 0)
			)
			(polygon
				(pts
					(arc
						(start 340.503256 -52.497228)
						(mid 340.427541 -52.543858)
						(end 340.381082 -52.619656)
					)
					(arc
						(start 340.275672 -52.619656)
						(mid 340.355474 -52.471874)
						(end 340.503256 -52.392072)
					)
				)
			)
		)
		(zone
			(layer "F.Cu")
			(hatch none 0.5)
			(connect_pads
				(clearance 0)
			)
			(min_thickness 0.25)
			(keepout
				(tracks not_allowed)
				(vias allowed)
				(pads allowed)
				(copperpour not_allowed)
				(footprints allowed)
			)
			(placement
				(enabled no)
				(sheetname "")
			)
			(fill
				(thermal_gap 0.5)
				(thermal_bridge_width 0.5)
				(island_removal_mode 0)
			)
			(polygon
				(pts
					(arc
						(start 340.503256 -51.557428)
						(mid 340.427541 -51.604058)
						(end 340.381082 -51.679856)
					)
					(arc
						(start 340.275672 -51.679856)
						(mid 340.355474 -51.532074)
						(end 340.503256 -51.452272)
					)
				)
			)
		)
		(zone
			(layer "F.Cu")
			(hatch none 0.5)
			(connect_pads
				(clearance 0)
			)
			(min_thickness 0.25)
			(keepout
				(tracks not_allowed)
				(vias allowed)
				(pads allowed)
				(copperpour not_allowed)
				(footprints allowed)
			)
			(placement
				(enabled no)
				(sheetname "")
			)
			(fill
				(thermal_gap 0.5)
				(thermal_bridge_width 0.5)
				(island_removal_mode 0)
			)
			(polygon
				(pts
					(arc
						(start 340.503256 -50.617628)
						(mid 340.427541 -50.664258)
						(end 340.381082 -50.740056)
					)
					(arc
						(start 340.275672 -50.740056)
						(mid 340.355474 -50.592274)
						(end 340.503256 -50.512472)
					)
				)
			)
		)
		(zone
			(layer "F.Cu")
			(hatch none 0.5)
			(connect_pads
				(clearance 0)
			)
			(min_thickness 0.25)
			(keepout
				(tracks not_allowed)
				(vias allowed)
				(pads allowed)
				(copperpour not_allowed)
				(footprints allowed)
			)
			(placement
				(enabled no)
				(sheetname "")
			)
			(fill
				(thermal_gap 0.5)
				(thermal_bridge_width 0.5)
				(island_removal_mode 0)
			)
			(polygon
				(pts
					(arc
						(start 340.503256 -49.677828)
						(mid 340.427541 -49.724458)
						(end 340.381082 -49.800256)
					)
					(arc
						(start 340.275672 -49.800256)
						(mid 340.355474 -49.652474)
						(end 340.503256 -49.572672)
					)
				)
			)
		)
		(zone
			(layer "F.Cu")
			(hatch none 0.5)
			(connect_pads
				(clearance 0)
			)
			(min_thickness 0.25)
			(keepout
				(tracks not_allowed)
				(vias allowed)
				(pads allowed)
				(copperpour not_allowed)
				(footprints allowed)
			)
			(placement
				(enabled no)
				(sheetname "")
			)
			(fill
				(thermal_gap 0.5)
				(thermal_bridge_width 0.5)
				(island_removal_mode 0)
			)
			(polygon
				(pts
					(arc
						(start 340.503256 -48.738028)
						(mid 340.427541 -48.784658)
						(end 340.381082 -48.860456)
					)
					(arc
						(start 340.275672 -48.860456)
						(mid 340.355474 -48.712674)
						(end 340.503256 -48.632872)
					)
				)
			)
		)
		(zone
			(layer "F.Cu")
			(hatch none 0.5)
			(connect_pads
				(clearance 0)
			)
			(min_thickness 0.25)
			(keepout
				(tracks not_allowed)
				(vias allowed)
				(pads allowed)
				(copperpour not_allowed)
				(footprints allowed)
			)
			(placement
				(enabled no)
				(sheetname "")
			)
			(fill
				(thermal_gap 0.5)
				(thermal_bridge_width 0.5)
				(island_removal_mode 0)
			)
			(polygon
				(pts
					(arc
						(start 340.503256 -47.798228)
						(mid 340.427541 -47.844858)
						(end 340.381082 -47.920656)
					)
					(arc
						(start 340.275672 -47.920656)
						(mid 340.355474 -47.772874)
						(end 340.503256 -47.693072)
					)
				)
			)
		)
		(zone
			(layer "F.Cu")
			(hatch none 0.5)
			(connect_pads
				(clearance 0)
			)
			(min_thickness 0.25)
			(keepout
				(tracks not_allowed)
				(vias allowed)
				(pads allowed)
				(copperpour not_allowed)
				(footprints allowed)
			)
			(placement
				(enabled no)
				(sheetname "")
			)
			(fill
				(thermal_gap 0.5)
				(thermal_bridge_width 0.5)
				(island_removal_mode 0)
			)
			(polygon
				(pts
					(arc
						(start 340.503256 -46.858428)
						(mid 340.427541 -46.905058)
						(end 340.381082 -46.980856)
					)
					(arc
						(start 340.275672 -46.980856)
						(mid 340.355474 -46.833074)
						(end 340.503256 -46.753272)
					)
				)
			)
		)
		(zone
			(layer "F.Cu")
			(hatch none 0.5)
			(connect_pads
				(clearance 0)
			)
			(min_thickness 0.25)
			(keepout
				(tracks not_allowed)
				(vias allowed)
				(pads allowed)
				(copperpour not_allowed)
				(footprints allowed)
			)
			(placement
				(enabled no)
				(sheetname "")
			)
			(fill
				(thermal_gap 0.5)
				(thermal_bridge_width 0.5)
				(island_removal_mode 0)
			)
			(polygon
				(pts
					(arc
						(start 340.503256 -45.918628)
						(mid 340.427541 -45.965258)
						(end 340.381082 -46.041056)
					)
					(arc
						(start 340.275672 -46.041056)
						(mid 340.355474 -45.893274)
						(end 340.503256 -45.813472)
					)
				)
			)
		)
		(zone
			(layer "F.Cu")
			(hatch none 0.5)
			(connect_pads
				(clearance 0)
			)
			(min_thickness 0.25)
			(keepout
				(tracks not_allowed)
				(vias allowed)
				(pads allowed)
				(copperpour not_allowed)
				(footprints allowed)
			)
			(placement
				(enabled no)
				(sheetname "")
			)
			(fill
				(thermal_gap 0.5)
				(thermal_bridge_width 0.5)
				(island_removal_mode 0)
			)
			(polygon
				(pts
					(arc
						(start 340.503256 -44.978828)
						(mid 340.427541 -45.025458)
						(end 340.381082 -45.101256)
					)
					(arc
						(start 340.275672 -45.101256)
						(mid 340.355474 -44.953474)
						(end 340.503256 -44.873672)
					)
				)
			)
		)
		(zone
			(layer "F.Cu")
			(hatch none 0.5)
			(connect_pads
				(clearance 0)
			)
			(min_thickness 0.25)
			(keepout
				(tracks not_allowed)
				(vias allowed)
				(pads allowed)
				(copperpour not_allowed)
				(footprints allowed)
			)
			(placement
				(enabled no)
				(sheetname "")
			)
			(fill
				(thermal_gap 0.5)
				(thermal_bridge_width 0.5)
				(island_removal_mode 0)
			)
			(polygon
				(pts
					(arc
						(start 340.503256 -44.039028)
						(mid 340.427541 -44.085658)
						(end 340.381082 -44.161456)
					)
					(arc
						(start 340.275672 -44.161456)
						(mid 340.355474 -44.013674)
						(end 340.503256 -43.933872)
					)
				)
			)
		)
		(zone
			(layer "F.Cu")
			(hatch none 0.5)
			(connect_pads
				(clearance 0)
			)
			(min_thickness 0.25)
			(keepout
				(tracks not_allowed)
				(vias allowed)
				(pads allowed)
				(copperpour not_allowed)
				(footprints allowed)
			)
			(placement
				(enabled no)
				(sheetname "")
			)
			(fill
				(thermal_gap 0.5)
				(thermal_bridge_width 0.5)
				(island_removal_mode 0)
			)
			(polygon
				(pts
					(arc
						(start 340.503256 -43.099228)
						(mid 340.427541 -43.145858)
						(end 340.381082 -43.221656)
					)
					(arc
						(start 340.275672 -43.221656)
						(mid 340.355474 -43.073874)
						(end 340.503256 -42.994072)
					)
				)
			)
		)
		(zone
			(layer "F.Cu")
			(hatch none 0.5)
			(connect_pads
				(clearance 0)
			)
			(min_thickness 0.25)
			(keepout
				(tracks not_allowed)
				(vias allowed)
				(pads allowed)
				(copperpour not_allowed)
				(footprints allowed)
			)
			(placement
				(enabled no)
				(sheetname "")
			)
			(fill
				(thermal_gap 0.5)
				(thermal_bridge_width 0.5)
				(island_removal_mode 0)
			)
			(polygon
				(pts
					(arc
						(start 340.503256 -42.159428)
						(mid 340.427541 -42.206058)
						(end 340.381082 -42.281856)
					)
					(arc
						(start 340.275672 -42.281856)
						(mid 340.355474 -42.134074)
						(end 340.503256 -42.054272)
					)
				)
			)
		)
		(zone
			(layer "F.Cu")
			(hatch none 0.5)
			(connect_pads
				(clearance 0)
			)
			(min_thickness 0.25)
			(keepout
				(tracks not_allowed)
				(vias allowed)
				(pads allowed)
				(copperpour not_allowed)
				(footprints allowed)
			)
			(placement
				(enabled no)
				(sheetname "")
			)
			(fill
				(thermal_gap 0.5)
				(thermal_bridge_width 0.5)
				(island_removal_mode 0)
			)
			(polygon
				(pts
					(arc
						(start 340.503256 -41.219628)
						(mid 340.427541 -41.266258)
						(end 340.381082 -41.342056)
					)
					(arc
						(start 340.275672 -41.342056)
						(mid 340.355474 -41.194274)
						(end 340.503256 -41.114472)
					)
				)
			)
		)
		(zone
			(layer "F.Cu")
			(hatch none 0.5)
			(connect_pads
				(clearance 0)
			)
			(min_thickness 0.25)
			(keepout
				(tracks not_allowed)
				(vias allowed)
				(pads allowed)
				(copperpour not_allowed)
				(footprints allowed)
			)
			(placement
				(enabled no)
				(sheetname "")
			)
			(fill
				(thermal_gap 0.5)
				(thermal_bridge_width 0.5)
				(island_removal_mode 0)
			)
			(polygon
				(pts
					(arc
						(start 340.503256 -40.279828)
						(mid 340.427541 -40.326458)
						(end 340.381082 -40.402256)
					)
					(arc
						(start 340.275672 -40.402256)
						(mid 340.355474 -40.254474)
						(end 340.503256 -40.174672)
					)
				)
			)
		)
		(zone
			(layer "F.Cu")
			(hatch none 0.5)
			(connect_pads
				(clearance 0)
			)
			(min_thickness 0.25)
			(keepout
				(tracks not_allowed)
				(vias allowed)
				(pads allowed)
				(copperpour not_allowed)
				(footprints allowed)
			)
			(placement
				(enabled no)
				(sheetname "")
			)
			(fill
				(thermal_gap 0.5)
				(thermal_bridge_width 0.5)
				(island_removal_mode 0)
			)
			(polygon
				(pts
					(arc
						(start 340.622636 -56.620664)
						(mid 340.698463 -56.574063)
						(end 340.745064 -56.498236)
					)
					(arc
						(start 340.850474 -56.498236)
						(mid 340.770584 -56.646106)
						(end 340.622636 -56.72582)
					)
				)
			)
		)
		(zone
			(layer "F.Cu")
			(hatch none 0.5)
			(connect_pads
				(clearance 0)
			)
			(min_thickness 0.25)
			(keepout
				(tracks not_allowed)
				(vias allowed)
				(pads allowed)
				(copperpour not_allowed)
				(footprints allowed)
			)
			(placement
				(enabled no)
				(sheetname "")
			)
			(fill
				(thermal_gap 0.5)
				(thermal_bridge_width 0.5)
				(island_removal_mode 0)
			)
			(polygon
				(pts
					(arc
						(start 340.622636 -55.680864)
						(mid 340.698463 -55.634263)
						(end 340.745064 -55.558436)
					)
					(arc
						(start 340.850474 -55.558436)
						(mid 340.770584 -55.706306)
						(end 340.622636 -55.78602)
					)
				)
			)
		)
		(zone
			(layer "F.Cu")
			(hatch none 0.5)
			(connect_pads
				(clearance 0)
			)
			(min_thickness 0.25)
			(keepout
				(tracks not_allowed)
				(vias allowed)
				(pads allowed)
				(copperpour not_allowed)
				(footprints allowed)
			)
			(placement
				(enabled no)
				(sheetname "")
			)
			(fill
				(thermal_gap 0.5)
				(thermal_bridge_width 0.5)
				(island_removal_mode 0)
			)
			(polygon
				(pts
					(arc
						(start 340.622636 -54.741064)
						(mid 340.698463 -54.694463)
						(end 340.745064 -54.618636)
					)
					(arc
						(start 340.850474 -54.618636)
						(mid 340.770584 -54.766506)
						(end 340.622636 -54.84622)
					)
				)
			)
		)
		(zone
			(layer "F.Cu")
			(hatch none 0.5)
			(connect_pads
				(clearance 0)
			)
			(min_thickness 0.25)
			(keepout
				(tracks not_allowed)
				(vias allowed)
				(pads allowed)
				(copperpour not_allowed)
				(footprints allowed)
			)
			(placement
				(enabled no)
				(sheetname "")
			)
			(fill
				(thermal_gap 0.5)
				(thermal_bridge_width 0.5)
				(island_removal_mode 0)
			)
			(polygon
				(pts
					(arc
						(start 340.622636 -53.801264)
						(mid 340.698463 -53.754663)
						(end 340.745064 -53.678836)
					)
					(arc
						(start 340.850474 -53.678836)
						(mid 340.770584 -53.826706)
						(end 340.622636 -53.90642)
					)
				)
			)
		)
		(zone
			(layer "F.Cu")
			(hatch none 0.5)
			(connect_pads
				(clearance 0)
			)
			(min_thickness 0.25)
			(keepout
				(tracks not_allowed)
				(vias allowed)
				(pads allowed)
				(copperpour not_allowed)
				(footprints allowed)
			)
			(placement
				(enabled no)
				(sheetname "")
			)
			(fill
				(thermal_gap 0.5)
				(thermal_bridge_width 0.5)
				(island_removal_mode 0)
			)
			(polygon
				(pts
					(arc
						(start 340.622636 -52.861464)
						(mid 340.698463 -52.814863)
						(end 340.745064 -52.739036)
					)
					(arc
						(start 340.850474 -52.739036)
						(mid 340.770584 -52.886906)
						(end 340.622636 -52.96662)
					)
				)
			)
		)
		(zone
			(layer "F.Cu")
			(hatch none 0.5)
			(connect_pads
				(clearance 0)
			)
			(min_thickness 0.25)
			(keepout
				(tracks not_allowed)
				(vias allowed)
				(pads allowed)
				(copperpour not_allowed)
				(footprints allowed)
			)
			(placement
				(enabled no)
				(sheetname "")
			)
			(fill
				(thermal_gap 0.5)
				(thermal_bridge_width 0.5)
				(island_removal_mode 0)
			)
			(polygon
				(pts
					(arc
						(start 340.622636 -51.921664)
						(mid 340.698463 -51.875063)
						(end 340.745064 -51.799236)
					)
					(arc
						(start 340.850474 -51.799236)
						(mid 340.770584 -51.947106)
						(end 340.622636 -52.02682)
					)
				)
			)
		)
		(zone
			(layer "F.Cu")
			(hatch none 0.5)
			(connect_pads
				(clearance 0)
			)
			(min_thickness 0.25)
			(keepout
				(tracks not_allowed)
				(vias allowed)
				(pads allowed)
				(copperpour not_allowed)
				(footprints allowed)
			)
			(placement
				(enabled no)
				(sheetname "")
			)
			(fill
				(thermal_gap 0.5)
				(thermal_bridge_width 0.5)
				(island_removal_mode 0)
			)
			(polygon
				(pts
					(arc
						(start 340.622636 -50.981864)
						(mid 340.698463 -50.935263)
						(end 340.745064 -50.859436)
					)
					(arc
						(start 340.850474 -50.859436)
						(mid 340.770584 -51.007306)
						(end 340.622636 -51.08702)
					)
				)
			)
		)
		(zone
			(layer "F.Cu")
			(hatch none 0.5)
			(connect_pads
				(clearance 0)
			)
			(min_thickness 0.25)
			(keepout
				(tracks not_allowed)
				(vias allowed)
				(pads allowed)
				(copperpour not_allowed)
				(footprints allowed)
			)
			(placement
				(enabled no)
				(sheetname "")
			)
			(fill
				(thermal_gap 0.5)
				(thermal_bridge_width 0.5)
				(island_removal_mode 0)
			)
			(polygon
				(pts
					(arc
						(start 340.622636 -50.042064)
						(mid 340.698463 -49.995463)
						(end 340.745064 -49.919636)
					)
					(arc
						(start 340.850474 -49.919636)
						(mid 340.770584 -50.067506)
						(end 340.622636 -50.14722)
					)
				)
			)
		)
		(zone
			(layer "F.Cu")
			(hatch none 0.5)
			(connect_pads
				(clearance 0)
			)
			(min_thickness 0.25)
			(keepout
				(tracks not_allowed)
				(vias allowed)
				(pads allowed)
				(copperpour not_allowed)
				(footprints allowed)
			)
			(placement
				(enabled no)
				(sheetname "")
			)
			(fill
				(thermal_gap 0.5)
				(thermal_bridge_width 0.5)
				(island_removal_mode 0)
			)
			(polygon
				(pts
					(arc
						(start 340.622636 -49.102264)
						(mid 340.698463 -49.055663)
						(end 340.745064 -48.979836)
					)
					(arc
						(start 340.850474 -48.979836)
						(mid 340.770584 -49.127706)
						(end 340.622636 -49.20742)
					)
				)
			)
		)
		(zone
			(layer "F.Cu")
			(hatch none 0.5)
			(connect_pads
				(clearance 0)
			)
			(min_thickness 0.25)
			(keepout
				(tracks not_allowed)
				(vias allowed)
				(pads allowed)
				(copperpour not_allowed)
				(footprints allowed)
			)
			(placement
				(enabled no)
				(sheetname "")
			)
			(fill
				(thermal_gap 0.5)
				(thermal_bridge_width 0.5)
				(island_removal_mode 0)
			)
			(polygon
				(pts
					(arc
						(start 340.622636 -48.162464)
						(mid 340.698463 -48.115863)
						(end 340.745064 -48.040036)
					)
					(arc
						(start 340.850474 -48.040036)
						(mid 340.770584 -48.187906)
						(end 340.622636 -48.26762)
					)
				)
			)
		)
		(zone
			(layer "F.Cu")
			(hatch none 0.5)
			(connect_pads
				(clearance 0)
			)
			(min_thickness 0.25)
			(keepout
				(tracks not_allowed)
				(vias allowed)
				(pads allowed)
				(copperpour not_allowed)
				(footprints allowed)
			)
			(placement
				(enabled no)
				(sheetname "")
			)
			(fill
				(thermal_gap 0.5)
				(thermal_bridge_width 0.5)
				(island_removal_mode 0)
			)
			(polygon
				(pts
					(arc
						(start 340.622636 -47.222664)
						(mid 340.698463 -47.176063)
						(end 340.745064 -47.100236)
					)
					(arc
						(start 340.850474 -47.100236)
						(mid 340.770584 -47.248106)
						(end 340.622636 -47.32782)
					)
				)
			)
		)
		(zone
			(layer "F.Cu")
			(hatch none 0.5)
			(connect_pads
				(clearance 0)
			)
			(min_thickness 0.25)
			(keepout
				(tracks not_allowed)
				(vias allowed)
				(pads allowed)
				(copperpour not_allowed)
				(footprints allowed)
			)
			(placement
				(enabled no)
				(sheetname "")
			)
			(fill
				(thermal_gap 0.5)
				(thermal_bridge_width 0.5)
				(island_removal_mode 0)
			)
			(polygon
				(pts
					(arc
						(start 340.622636 -46.282864)
						(mid 340.698463 -46.236263)
						(end 340.745064 -46.160436)
					)
					(arc
						(start 340.850474 -46.160436)
						(mid 340.770584 -46.308306)
						(end 340.622636 -46.38802)
					)
				)
			)
		)
		(zone
			(layer "F.Cu")
			(hatch none 0.5)
			(connect_pads
				(clearance 0)
			)
			(min_thickness 0.25)
			(keepout
				(tracks not_allowed)
				(vias allowed)
				(pads allowed)
				(copperpour not_allowed)
				(footprints allowed)
			)
			(placement
				(enabled no)
				(sheetname "")
			)
			(fill
				(thermal_gap 0.5)
				(thermal_bridge_width 0.5)
				(island_removal_mode 0)
			)
			(polygon
				(pts
					(arc
						(start 340.622636 -45.343064)
						(mid 340.698463 -45.296463)
						(end 340.745064 -45.220636)
					)
					(arc
						(start 340.850474 -45.220636)
						(mid 340.770584 -45.368506)
						(end 340.622636 -45.44822)
					)
				)
			)
		)
		(zone
			(layer "F.Cu")
			(hatch none 0.5)
			(connect_pads
				(clearance 0)
			)
			(min_thickness 0.25)
			(keepout
				(tracks not_allowed)
				(vias allowed)
				(pads allowed)
				(copperpour not_allowed)
				(footprints allowed)
			)
			(placement
				(enabled no)
				(sheetname "")
			)
			(fill
				(thermal_gap 0.5)
				(thermal_bridge_width 0.5)
				(island_removal_mode 0)
			)
			(polygon
				(pts
					(arc
						(start 340.622636 -44.403264)
						(mid 340.698463 -44.356663)
						(end 340.745064 -44.280836)
					)
					(arc
						(start 340.850474 -44.280836)
						(mid 340.770584 -44.428706)
						(end 340.622636 -44.50842)
					)
				)
			)
		)
		(zone
			(layer "F.Cu")
			(hatch none 0.5)
			(connect_pads
				(clearance 0)
			)
			(min_thickness 0.25)
			(keepout
				(tracks not_allowed)
				(vias allowed)
				(pads allowed)
				(copperpour not_allowed)
				(footprints allowed)
			)
			(placement
				(enabled no)
				(sheetname "")
			)
			(fill
				(thermal_gap 0.5)
				(thermal_bridge_width 0.5)
				(island_removal_mode 0)
			)
			(polygon
				(pts
					(arc
						(start 340.622636 -43.463464)
						(mid 340.698463 -43.416863)
						(end 340.745064 -43.341036)
					)
					(arc
						(start 340.850474 -43.341036)
						(mid 340.770584 -43.488906)
						(end 340.622636 -43.56862)
					)
				)
			)
		)
		(zone
			(layer "F.Cu")
			(hatch none 0.5)
			(connect_pads
				(clearance 0)
			)
			(min_thickness 0.25)
			(keepout
				(tracks not_allowed)
				(vias allowed)
				(pads allowed)
				(copperpour not_allowed)
				(footprints allowed)
			)
			(placement
				(enabled no)
				(sheetname "")
			)
			(fill
				(thermal_gap 0.5)
				(thermal_bridge_width 0.5)
				(island_removal_mode 0)
			)
			(polygon
				(pts
					(arc
						(start 340.622636 -42.523664)
						(mid 340.698463 -42.477063)
						(end 340.745064 -42.401236)
					)
					(arc
						(start 340.850474 -42.401236)
						(mid 340.770584 -42.549106)
						(end 340.622636 -42.62882)
					)
				)
			)
		)
		(zone
			(layer "F.Cu")
			(hatch none 0.5)
			(connect_pads
				(clearance 0)
			)
			(min_thickness 0.25)
			(keepout
				(tracks not_allowed)
				(vias allowed)
				(pads allowed)
				(copperpour not_allowed)
				(footprints allowed)
			)
			(placement
				(enabled no)
				(sheetname "")
			)
			(fill
				(thermal_gap 0.5)
				(thermal_bridge_width 0.5)
				(island_removal_mode 0)
			)
			(polygon
				(pts
					(arc
						(start 340.622636 -41.583864)
						(mid 340.698463 -41.537263)
						(end 340.745064 -41.461436)
					)
					(arc
						(start 340.850474 -41.461436)
						(mid 340.770584 -41.609306)
						(end 340.622636 -41.68902)
					)
				)
			)
		)
		(zone
			(layer "F.Cu")
			(hatch none 0.5)
			(connect_pads
				(clearance 0)
			)
			(min_thickness 0.25)
			(keepout
				(tracks not_allowed)
				(vias allowed)
				(pads allowed)
				(copperpour not_allowed)
				(footprints allowed)
			)
			(placement
				(enabled no)
				(sheetname "")
			)
			(fill
				(thermal_gap 0.5)
				(thermal_bridge_width 0.5)
				(island_removal_mode 0)
			)
			(polygon
				(pts
					(arc
						(start 340.622636 -40.644064)
						(mid 340.698463 -40.597463)
						(end 340.745064 -40.521636)
					)
					(arc
						(start 340.850474 -40.521636)
						(mid 340.770584 -40.669506)
						(end 340.622636 -40.74922)
					)
				)
			)
		)
		(zone
			(layer "F.Cu")
			(hatch none 0.5)
			(connect_pads
				(clearance 0)
			)
			(min_thickness 0.25)
			(keepout
				(tracks not_allowed)
				(vias allowed)
				(pads allowed)
				(copperpour not_allowed)
				(footprints allowed)
			)
			(placement
				(enabled no)
				(sheetname "")
			)
			(fill
				(thermal_gap 0.5)
				(thermal_bridge_width 0.5)
				(island_removal_mode 0)
			)
			(polygon
				(pts
					(arc
						(start 340.745064 -56.378856)
						(mid 340.698463 -56.303029)
						(end 340.622636 -56.256428)
					)
					(arc
						(start 340.622636 -56.151272)
						(mid 340.770548 -56.231023)
						(end 340.850474 -56.378856)
					)
				)
			)
		)
		(zone
			(layer "F.Cu")
			(hatch none 0.5)
			(connect_pads
				(clearance 0)
			)
			(min_thickness 0.25)
			(keepout
				(tracks not_allowed)
				(vias allowed)
				(pads allowed)
				(copperpour not_allowed)
				(footprints allowed)
			)
			(placement
				(enabled no)
				(sheetname "")
			)
			(fill
				(thermal_gap 0.5)
				(thermal_bridge_width 0.5)
				(island_removal_mode 0)
			)
			(polygon
				(pts
					(arc
						(start 340.745064 -55.439056)
						(mid 340.698463 -55.363229)
						(end 340.622636 -55.316628)
					)
					(arc
						(start 340.622636 -55.211472)
						(mid 340.770548 -55.291223)
						(end 340.850474 -55.439056)
					)
				)
			)
		)
		(zone
			(layer "F.Cu")
			(hatch none 0.5)
			(connect_pads
				(clearance 0)
			)
			(min_thickness 0.25)
			(keepout
				(tracks not_allowed)
				(vias allowed)
				(pads allowed)
				(copperpour not_allowed)
				(footprints allowed)
			)
			(placement
				(enabled no)
				(sheetname "")
			)
			(fill
				(thermal_gap 0.5)
				(thermal_bridge_width 0.5)
				(island_removal_mode 0)
			)
			(polygon
				(pts
					(arc
						(start 340.745064 -54.499256)
						(mid 340.698463 -54.423429)
						(end 340.622636 -54.376828)
					)
					(arc
						(start 340.622636 -54.271672)
						(mid 340.770548 -54.351423)
						(end 340.850474 -54.499256)
					)
				)
			)
		)
		(zone
			(layer "F.Cu")
			(hatch none 0.5)
			(connect_pads
				(clearance 0)
			)
			(min_thickness 0.25)
			(keepout
				(tracks not_allowed)
				(vias allowed)
				(pads allowed)
				(copperpour not_allowed)
				(footprints allowed)
			)
			(placement
				(enabled no)
				(sheetname "")
			)
			(fill
				(thermal_gap 0.5)
				(thermal_bridge_width 0.5)
				(island_removal_mode 0)
			)
			(polygon
				(pts
					(arc
						(start 340.745064 -53.559456)
						(mid 340.698463 -53.483629)
						(end 340.622636 -53.437028)
					)
					(arc
						(start 340.622636 -53.331872)
						(mid 340.770548 -53.411623)
						(end 340.850474 -53.559456)
					)
				)
			)
		)
		(zone
			(layer "F.Cu")
			(hatch none 0.5)
			(connect_pads
				(clearance 0)
			)
			(min_thickness 0.25)
			(keepout
				(tracks not_allowed)
				(vias allowed)
				(pads allowed)
				(copperpour not_allowed)
				(footprints allowed)
			)
			(placement
				(enabled no)
				(sheetname "")
			)
			(fill
				(thermal_gap 0.5)
				(thermal_bridge_width 0.5)
				(island_removal_mode 0)
			)
			(polygon
				(pts
					(arc
						(start 340.745064 -52.619656)
						(mid 340.698463 -52.543829)
						(end 340.622636 -52.497228)
					)
					(arc
						(start 340.622636 -52.392072)
						(mid 340.770548 -52.471823)
						(end 340.850474 -52.619656)
					)
				)
			)
		)
		(zone
			(layer "F.Cu")
			(hatch none 0.5)
			(connect_pads
				(clearance 0)
			)
			(min_thickness 0.25)
			(keepout
				(tracks not_allowed)
				(vias allowed)
				(pads allowed)
				(copperpour not_allowed)
				(footprints allowed)
			)
			(placement
				(enabled no)
				(sheetname "")
			)
			(fill
				(thermal_gap 0.5)
				(thermal_bridge_width 0.5)
				(island_removal_mode 0)
			)
			(polygon
				(pts
					(arc
						(start 340.745064 -51.679856)
						(mid 340.698463 -51.604029)
						(end 340.622636 -51.557428)
					)
					(arc
						(start 340.622636 -51.452272)
						(mid 340.770548 -51.532023)
						(end 340.850474 -51.679856)
					)
				)
			)
		)
		(zone
			(layer "F.Cu")
			(hatch none 0.5)
			(connect_pads
				(clearance 0)
			)
			(min_thickness 0.25)
			(keepout
				(tracks not_allowed)
				(vias allowed)
				(pads allowed)
				(copperpour not_allowed)
				(footprints allowed)
			)
			(placement
				(enabled no)
				(sheetname "")
			)
			(fill
				(thermal_gap 0.5)
				(thermal_bridge_width 0.5)
				(island_removal_mode 0)
			)
			(polygon
				(pts
					(arc
						(start 340.745064 -50.740056)
						(mid 340.698463 -50.664229)
						(end 340.622636 -50.617628)
					)
					(arc
						(start 340.622636 -50.512472)
						(mid 340.770548 -50.592223)
						(end 340.850474 -50.740056)
					)
				)
			)
		)
		(zone
			(layer "F.Cu")
			(hatch none 0.5)
			(connect_pads
				(clearance 0)
			)
			(min_thickness 0.25)
			(keepout
				(tracks not_allowed)
				(vias allowed)
				(pads allowed)
				(copperpour not_allowed)
				(footprints allowed)
			)
			(placement
				(enabled no)
				(sheetname "")
			)
			(fill
				(thermal_gap 0.5)
				(thermal_bridge_width 0.5)
				(island_removal_mode 0)
			)
			(polygon
				(pts
					(arc
						(start 340.745064 -49.800256)
						(mid 340.698463 -49.724429)
						(end 340.622636 -49.677828)
					)
					(arc
						(start 340.622636 -49.572672)
						(mid 340.770548 -49.652423)
						(end 340.850474 -49.800256)
					)
				)
			)
		)
		(zone
			(layer "F.Cu")
			(hatch none 0.5)
			(connect_pads
				(clearance 0)
			)
			(min_thickness 0.25)
			(keepout
				(tracks not_allowed)
				(vias allowed)
				(pads allowed)
				(copperpour not_allowed)
				(footprints allowed)
			)
			(placement
				(enabled no)
				(sheetname "")
			)
			(fill
				(thermal_gap 0.5)
				(thermal_bridge_width 0.5)
				(island_removal_mode 0)
			)
			(polygon
				(pts
					(arc
						(start 340.745064 -48.860456)
						(mid 340.698463 -48.784629)
						(end 340.622636 -48.738028)
					)
					(arc
						(start 340.622636 -48.632872)
						(mid 340.770548 -48.712623)
						(end 340.850474 -48.860456)
					)
				)
			)
		)
		(zone
			(layer "F.Cu")
			(hatch none 0.5)
			(connect_pads
				(clearance 0)
			)
			(min_thickness 0.25)
			(keepout
				(tracks not_allowed)
				(vias allowed)
				(pads allowed)
				(copperpour not_allowed)
				(footprints allowed)
			)
			(placement
				(enabled no)
				(sheetname "")
			)
			(fill
				(thermal_gap 0.5)
				(thermal_bridge_width 0.5)
				(island_removal_mode 0)
			)
			(polygon
				(pts
					(arc
						(start 340.745064 -47.920656)
						(mid 340.698463 -47.844829)
						(end 340.622636 -47.798228)
					)
					(arc
						(start 340.622636 -47.693072)
						(mid 340.770548 -47.772823)
						(end 340.850474 -47.920656)
					)
				)
			)
		)
		(zone
			(layer "F.Cu")
			(hatch none 0.5)
			(connect_pads
				(clearance 0)
			)
			(min_thickness 0.25)
			(keepout
				(tracks not_allowed)
				(vias allowed)
				(pads allowed)
				(copperpour not_allowed)
				(footprints allowed)
			)
			(placement
				(enabled no)
				(sheetname "")
			)
			(fill
				(thermal_gap 0.5)
				(thermal_bridge_width 0.5)
				(island_removal_mode 0)
			)
			(polygon
				(pts
					(arc
						(start 340.745064 -46.980856)
						(mid 340.698463 -46.905029)
						(end 340.622636 -46.858428)
					)
					(arc
						(start 340.622636 -46.753272)
						(mid 340.770548 -46.833023)
						(end 340.850474 -46.980856)
					)
				)
			)
		)
		(zone
			(layer "F.Cu")
			(hatch none 0.5)
			(connect_pads
				(clearance 0)
			)
			(min_thickness 0.25)
			(keepout
				(tracks not_allowed)
				(vias allowed)
				(pads allowed)
				(copperpour not_allowed)
				(footprints allowed)
			)
			(placement
				(enabled no)
				(sheetname "")
			)
			(fill
				(thermal_gap 0.5)
				(thermal_bridge_width 0.5)
				(island_removal_mode 0)
			)
			(polygon
				(pts
					(arc
						(start 340.745064 -46.041056)
						(mid 340.698463 -45.965229)
						(end 340.622636 -45.918628)
					)
					(arc
						(start 340.622636 -45.813472)
						(mid 340.770548 -45.893223)
						(end 340.850474 -46.041056)
					)
				)
			)
		)
		(zone
			(layer "F.Cu")
			(hatch none 0.5)
			(connect_pads
				(clearance 0)
			)
			(min_thickness 0.25)
			(keepout
				(tracks not_allowed)
				(vias allowed)
				(pads allowed)
				(copperpour not_allowed)
				(footprints allowed)
			)
			(placement
				(enabled no)
				(sheetname "")
			)
			(fill
				(thermal_gap 0.5)
				(thermal_bridge_width 0.5)
				(island_removal_mode 0)
			)
			(polygon
				(pts
					(arc
						(start 340.745064 -45.101256)
						(mid 340.698463 -45.025429)
						(end 340.622636 -44.978828)
					)
					(arc
						(start 340.622636 -44.873672)
						(mid 340.770548 -44.953423)
						(end 340.850474 -45.101256)
					)
				)
			)
		)
		(zone
			(layer "F.Cu")
			(hatch none 0.5)
			(connect_pads
				(clearance 0)
			)
			(min_thickness 0.25)
			(keepout
				(tracks not_allowed)
				(vias allowed)
				(pads allowed)
				(copperpour not_allowed)
				(footprints allowed)
			)
			(placement
				(enabled no)
				(sheetname "")
			)
			(fill
				(thermal_gap 0.5)
				(thermal_bridge_width 0.5)
				(island_removal_mode 0)
			)
			(polygon
				(pts
					(arc
						(start 340.745064 -44.161456)
						(mid 340.698463 -44.085629)
						(end 340.622636 -44.039028)
					)
					(arc
						(start 340.622636 -43.933872)
						(mid 340.770548 -44.013623)
						(end 340.850474 -44.161456)
					)
				)
			)
		)
		(zone
			(layer "F.Cu")
			(hatch none 0.5)
			(connect_pads
				(clearance 0)
			)
			(min_thickness 0.25)
			(keepout
				(tracks not_allowed)
				(vias allowed)
				(pads allowed)
				(copperpour not_allowed)
				(footprints allowed)
			)
			(placement
				(enabled no)
				(sheetname "")
			)
			(fill
				(thermal_gap 0.5)
				(thermal_bridge_width 0.5)
				(island_removal_mode 0)
			)
			(polygon
				(pts
					(arc
						(start 340.745064 -43.221656)
						(mid 340.698463 -43.145829)
						(end 340.622636 -43.099228)
					)
					(arc
						(start 340.622636 -42.994072)
						(mid 340.770548 -43.073823)
						(end 340.850474 -43.221656)
					)
				)
			)
		)
		(zone
			(layer "F.Cu")
			(hatch none 0.5)
			(connect_pads
				(clearance 0)
			)
			(min_thickness 0.25)
			(keepout
				(tracks not_allowed)
				(vias allowed)
				(pads allowed)
				(copperpour not_allowed)
				(footprints allowed)
			)
			(placement
				(enabled no)
				(sheetname "")
			)
			(fill
				(thermal_gap 0.5)
				(thermal_bridge_width 0.5)
				(island_removal_mode 0)
			)
			(polygon
				(pts
					(arc
						(start 340.745064 -42.281856)
						(mid 340.698463 -42.206029)
						(end 340.622636 -42.159428)
					)
					(arc
						(start 340.622636 -42.054272)
						(mid 340.770548 -42.134023)
						(end 340.850474 -42.281856)
					)
				)
			)
		)
		(zone
			(layer "F.Cu")
			(hatch none 0.5)
			(connect_pads
				(clearance 0)
			)
			(min_thickness 0.25)
			(keepout
				(tracks not_allowed)
				(vias allowed)
				(pads allowed)
				(copperpour not_allowed)
				(footprints allowed)
			)
			(placement
				(enabled no)
				(sheetname "")
			)
			(fill
				(thermal_gap 0.5)
				(thermal_bridge_width 0.5)
				(island_removal_mode 0)
			)
			(polygon
				(pts
					(arc
						(start 340.745064 -41.342056)
						(mid 340.698463 -41.266229)
						(end 340.622636 -41.219628)
					)
					(arc
						(start 340.622636 -41.114472)
						(mid 340.770548 -41.194223)
						(end 340.850474 -41.342056)
					)
				)
			)
		)
		(zone
			(layer "F.Cu")
			(hatch none 0.5)
			(connect_pads
				(clearance 0)
			)
			(min_thickness 0.25)
			(keepout
				(tracks not_allowed)
				(vias allowed)
				(pads allowed)
				(copperpour not_allowed)
				(footprints allowed)
			)
			(placement
				(enabled no)
				(sheetname "")
			)
			(fill
				(thermal_gap 0.5)
				(thermal_bridge_width 0.5)
				(island_removal_mode 0)
			)
			(polygon
				(pts
					(arc
						(start 340.745064 -40.402256)
						(mid 340.698463 -40.326429)
						(end 340.622636 -40.279828)
					)
					(arc
						(start 340.622636 -40.174672)
						(mid 340.770548 -40.254423)
						(end 340.850474 -40.402256)
					)
				)
			)
		)
		(zone
			(layer "F.Cu")
			(hatch none 0.5)
			(connect_pads
				(clearance 0)
			)
			(min_thickness 0.25)
			(keepout
				(tracks not_allowed)
				(vias allowed)
				(pads allowed)
				(copperpour not_allowed)
				(footprints allowed)
			)
			(placement
				(enabled no)
				(sheetname "")
			)
			(fill
				(thermal_gap 0.5)
				(thermal_bridge_width 0.5)
				(island_removal_mode 0)
			)
			(polygon
				(pts
					(arc
						(start 341.195152 -56.968136)
						(mid 341.241753 -57.043963)
						(end 341.31758 -57.090564)
					)
					(arc
						(start 341.31758 -57.19572)
						(mid 341.169668 -57.115969)
						(end 341.089742 -56.968136)
					)
				)
			)
		)
		(zone
			(layer "F.Cu")
			(hatch none 0.5)
			(connect_pads
				(clearance 0)
			)
			(min_thickness 0.25)
			(keepout
				(tracks not_allowed)
				(vias allowed)
				(pads allowed)
				(copperpour not_allowed)
				(footprints allowed)
			)
			(placement
				(enabled no)
				(sheetname "")
			)
			(fill
				(thermal_gap 0.5)
				(thermal_bridge_width 0.5)
				(island_removal_mode 0)
			)
			(polygon
				(pts
					(arc
						(start 341.195152 -56.028336)
						(mid 341.241753 -56.104163)
						(end 341.31758 -56.150764)
					)
					(arc
						(start 341.31758 -56.25592)
						(mid 341.169668 -56.176169)
						(end 341.089742 -56.028336)
					)
				)
			)
		)
		(zone
			(layer "F.Cu")
			(hatch none 0.5)
			(connect_pads
				(clearance 0)
			)
			(min_thickness 0.25)
			(keepout
				(tracks not_allowed)
				(vias allowed)
				(pads allowed)
				(copperpour not_allowed)
				(footprints allowed)
			)
			(placement
				(enabled no)
				(sheetname "")
			)
			(fill
				(thermal_gap 0.5)
				(thermal_bridge_width 0.5)
				(island_removal_mode 0)
			)
			(polygon
				(pts
					(arc
						(start 341.195152 -55.088536)
						(mid 341.241753 -55.164363)
						(end 341.31758 -55.210964)
					)
					(arc
						(start 341.31758 -55.31612)
						(mid 341.169668 -55.236369)
						(end 341.089742 -55.088536)
					)
				)
			)
		)
		(zone
			(layer "F.Cu")
			(hatch none 0.5)
			(connect_pads
				(clearance 0)
			)
			(min_thickness 0.25)
			(keepout
				(tracks not_allowed)
				(vias allowed)
				(pads allowed)
				(copperpour not_allowed)
				(footprints allowed)
			)
			(placement
				(enabled no)
				(sheetname "")
			)
			(fill
				(thermal_gap 0.5)
				(thermal_bridge_width 0.5)
				(island_removal_mode 0)
			)
			(polygon
				(pts
					(arc
						(start 341.195152 -54.148736)
						(mid 341.241753 -54.224563)
						(end 341.31758 -54.271164)
					)
					(arc
						(start 341.31758 -54.37632)
						(mid 341.169668 -54.296569)
						(end 341.089742 -54.148736)
					)
				)
			)
		)
		(zone
			(layer "F.Cu")
			(hatch none 0.5)
			(connect_pads
				(clearance 0)
			)
			(min_thickness 0.25)
			(keepout
				(tracks not_allowed)
				(vias allowed)
				(pads allowed)
				(copperpour not_allowed)
				(footprints allowed)
			)
			(placement
				(enabled no)
				(sheetname "")
			)
			(fill
				(thermal_gap 0.5)
				(thermal_bridge_width 0.5)
				(island_removal_mode 0)
			)
			(polygon
				(pts
					(arc
						(start 341.195152 -53.208936)
						(mid 341.241753 -53.284763)
						(end 341.31758 -53.331364)
					)
					(arc
						(start 341.31758 -53.43652)
						(mid 341.169668 -53.356769)
						(end 341.089742 -53.208936)
					)
				)
			)
		)
		(zone
			(layer "F.Cu")
			(hatch none 0.5)
			(connect_pads
				(clearance 0)
			)
			(min_thickness 0.25)
			(keepout
				(tracks not_allowed)
				(vias allowed)
				(pads allowed)
				(copperpour not_allowed)
				(footprints allowed)
			)
			(placement
				(enabled no)
				(sheetname "")
			)
			(fill
				(thermal_gap 0.5)
				(thermal_bridge_width 0.5)
				(island_removal_mode 0)
			)
			(polygon
				(pts
					(arc
						(start 341.195152 -52.269136)
						(mid 341.241753 -52.344963)
						(end 341.31758 -52.391564)
					)
					(arc
						(start 341.31758 -52.49672)
						(mid 341.169668 -52.416969)
						(end 341.089742 -52.269136)
					)
				)
			)
		)
		(zone
			(layer "F.Cu")
			(hatch none 0.5)
			(connect_pads
				(clearance 0)
			)
			(min_thickness 0.25)
			(keepout
				(tracks not_allowed)
				(vias allowed)
				(pads allowed)
				(copperpour not_allowed)
				(footprints allowed)
			)
			(placement
				(enabled no)
				(sheetname "")
			)
			(fill
				(thermal_gap 0.5)
				(thermal_bridge_width 0.5)
				(island_removal_mode 0)
			)
			(polygon
				(pts
					(arc
						(start 341.195152 -51.329336)
						(mid 341.241753 -51.405163)
						(end 341.31758 -51.451764)
					)
					(arc
						(start 341.31758 -51.55692)
						(mid 341.169668 -51.477169)
						(end 341.089742 -51.329336)
					)
				)
			)
		)
		(zone
			(layer "F.Cu")
			(hatch none 0.5)
			(connect_pads
				(clearance 0)
			)
			(min_thickness 0.25)
			(keepout
				(tracks not_allowed)
				(vias allowed)
				(pads allowed)
				(copperpour not_allowed)
				(footprints allowed)
			)
			(placement
				(enabled no)
				(sheetname "")
			)
			(fill
				(thermal_gap 0.5)
				(thermal_bridge_width 0.5)
				(island_removal_mode 0)
			)
			(polygon
				(pts
					(arc
						(start 341.195152 -50.389536)
						(mid 341.241753 -50.465363)
						(end 341.31758 -50.511964)
					)
					(arc
						(start 341.31758 -50.61712)
						(mid 341.169668 -50.537369)
						(end 341.089742 -50.389536)
					)
				)
			)
		)
		(zone
			(layer "F.Cu")
			(hatch none 0.5)
			(connect_pads
				(clearance 0)
			)
			(min_thickness 0.25)
			(keepout
				(tracks not_allowed)
				(vias allowed)
				(pads allowed)
				(copperpour not_allowed)
				(footprints allowed)
			)
			(placement
				(enabled no)
				(sheetname "")
			)
			(fill
				(thermal_gap 0.5)
				(thermal_bridge_width 0.5)
				(island_removal_mode 0)
			)
			(polygon
				(pts
					(arc
						(start 341.195152 -49.449736)
						(mid 341.241753 -49.525563)
						(end 341.31758 -49.572164)
					)
					(arc
						(start 341.31758 -49.67732)
						(mid 341.169668 -49.597569)
						(end 341.089742 -49.449736)
					)
				)
			)
		)
		(zone
			(layer "F.Cu")
			(hatch none 0.5)
			(connect_pads
				(clearance 0)
			)
			(min_thickness 0.25)
			(keepout
				(tracks not_allowed)
				(vias allowed)
				(pads allowed)
				(copperpour not_allowed)
				(footprints allowed)
			)
			(placement
				(enabled no)
				(sheetname "")
			)
			(fill
				(thermal_gap 0.5)
				(thermal_bridge_width 0.5)
				(island_removal_mode 0)
			)
			(polygon
				(pts
					(arc
						(start 341.195152 -48.509936)
						(mid 341.241753 -48.585763)
						(end 341.31758 -48.632364)
					)
					(arc
						(start 341.31758 -48.73752)
						(mid 341.169668 -48.657769)
						(end 341.089742 -48.509936)
					)
				)
			)
		)
		(zone
			(layer "F.Cu")
			(hatch none 0.5)
			(connect_pads
				(clearance 0)
			)
			(min_thickness 0.25)
			(keepout
				(tracks not_allowed)
				(vias allowed)
				(pads allowed)
				(copperpour not_allowed)
				(footprints allowed)
			)
			(placement
				(enabled no)
				(sheetname "")
			)
			(fill
				(thermal_gap 0.5)
				(thermal_bridge_width 0.5)
				(island_removal_mode 0)
			)
			(polygon
				(pts
					(arc
						(start 341.195152 -47.570136)
						(mid 341.241753 -47.645963)
						(end 341.31758 -47.692564)
					)
					(arc
						(start 341.31758 -47.79772)
						(mid 341.169668 -47.717969)
						(end 341.089742 -47.570136)
					)
				)
			)
		)
		(zone
			(layer "F.Cu")
			(hatch none 0.5)
			(connect_pads
				(clearance 0)
			)
			(min_thickness 0.25)
			(keepout
				(tracks not_allowed)
				(vias allowed)
				(pads allowed)
				(copperpour not_allowed)
				(footprints allowed)
			)
			(placement
				(enabled no)
				(sheetname "")
			)
			(fill
				(thermal_gap 0.5)
				(thermal_bridge_width 0.5)
				(island_removal_mode 0)
			)
			(polygon
				(pts
					(arc
						(start 341.195152 -46.630336)
						(mid 341.241753 -46.706163)
						(end 341.31758 -46.752764)
					)
					(arc
						(start 341.31758 -46.85792)
						(mid 341.169668 -46.778169)
						(end 341.089742 -46.630336)
					)
				)
			)
		)
		(zone
			(layer "F.Cu")
			(hatch none 0.5)
			(connect_pads
				(clearance 0)
			)
			(min_thickness 0.25)
			(keepout
				(tracks not_allowed)
				(vias allowed)
				(pads allowed)
				(copperpour not_allowed)
				(footprints allowed)
			)
			(placement
				(enabled no)
				(sheetname "")
			)
			(fill
				(thermal_gap 0.5)
				(thermal_bridge_width 0.5)
				(island_removal_mode 0)
			)
			(polygon
				(pts
					(arc
						(start 341.195152 -45.690536)
						(mid 341.241753 -45.766363)
						(end 341.31758 -45.812964)
					)
					(arc
						(start 341.31758 -45.91812)
						(mid 341.169668 -45.838369)
						(end 341.089742 -45.690536)
					)
				)
			)
		)
		(zone
			(layer "F.Cu")
			(hatch none 0.5)
			(connect_pads
				(clearance 0)
			)
			(min_thickness 0.25)
			(keepout
				(tracks not_allowed)
				(vias allowed)
				(pads allowed)
				(copperpour not_allowed)
				(footprints allowed)
			)
			(placement
				(enabled no)
				(sheetname "")
			)
			(fill
				(thermal_gap 0.5)
				(thermal_bridge_width 0.5)
				(island_removal_mode 0)
			)
			(polygon
				(pts
					(arc
						(start 341.195152 -44.750736)
						(mid 341.241753 -44.826563)
						(end 341.31758 -44.873164)
					)
					(arc
						(start 341.31758 -44.97832)
						(mid 341.169668 -44.898569)
						(end 341.089742 -44.750736)
					)
				)
			)
		)
		(zone
			(layer "F.Cu")
			(hatch none 0.5)
			(connect_pads
				(clearance 0)
			)
			(min_thickness 0.25)
			(keepout
				(tracks not_allowed)
				(vias allowed)
				(pads allowed)
				(copperpour not_allowed)
				(footprints allowed)
			)
			(placement
				(enabled no)
				(sheetname "")
			)
			(fill
				(thermal_gap 0.5)
				(thermal_bridge_width 0.5)
				(island_removal_mode 0)
			)
			(polygon
				(pts
					(arc
						(start 341.195152 -43.810936)
						(mid 341.241753 -43.886763)
						(end 341.31758 -43.933364)
					)
					(arc
						(start 341.31758 -44.03852)
						(mid 341.169668 -43.958769)
						(end 341.089742 -43.810936)
					)
				)
			)
		)
		(zone
			(layer "F.Cu")
			(hatch none 0.5)
			(connect_pads
				(clearance 0)
			)
			(min_thickness 0.25)
			(keepout
				(tracks not_allowed)
				(vias allowed)
				(pads allowed)
				(copperpour not_allowed)
				(footprints allowed)
			)
			(placement
				(enabled no)
				(sheetname "")
			)
			(fill
				(thermal_gap 0.5)
				(thermal_bridge_width 0.5)
				(island_removal_mode 0)
			)
			(polygon
				(pts
					(arc
						(start 341.195152 -42.871136)
						(mid 341.241753 -42.946963)
						(end 341.31758 -42.993564)
					)
					(arc
						(start 341.31758 -43.09872)
						(mid 341.169668 -43.018969)
						(end 341.089742 -42.871136)
					)
				)
			)
		)
		(zone
			(layer "F.Cu")
			(hatch none 0.5)
			(connect_pads
				(clearance 0)
			)
			(min_thickness 0.25)
			(keepout
				(tracks not_allowed)
				(vias allowed)
				(pads allowed)
				(copperpour not_allowed)
				(footprints allowed)
			)
			(placement
				(enabled no)
				(sheetname "")
			)
			(fill
				(thermal_gap 0.5)
				(thermal_bridge_width 0.5)
				(island_removal_mode 0)
			)
			(polygon
				(pts
					(arc
						(start 341.195152 -41.931336)
						(mid 341.241753 -42.007163)
						(end 341.31758 -42.053764)
					)
					(arc
						(start 341.31758 -42.15892)
						(mid 341.169668 -42.079169)
						(end 341.089742 -41.931336)
					)
				)
			)
		)
		(zone
			(layer "F.Cu")
			(hatch none 0.5)
			(connect_pads
				(clearance 0)
			)
			(min_thickness 0.25)
			(keepout
				(tracks not_allowed)
				(vias allowed)
				(pads allowed)
				(copperpour not_allowed)
				(footprints allowed)
			)
			(placement
				(enabled no)
				(sheetname "")
			)
			(fill
				(thermal_gap 0.5)
				(thermal_bridge_width 0.5)
				(island_removal_mode 0)
			)
			(polygon
				(pts
					(arc
						(start 341.195152 -40.991536)
						(mid 341.241753 -41.067363)
						(end 341.31758 -41.113964)
					)
					(arc
						(start 341.31758 -41.21912)
						(mid 341.169668 -41.139369)
						(end 341.089742 -40.991536)
					)
				)
			)
		)
		(zone
			(layer "F.Cu")
			(hatch none 0.5)
			(connect_pads
				(clearance 0)
			)
			(min_thickness 0.25)
			(keepout
				(tracks not_allowed)
				(vias allowed)
				(pads allowed)
				(copperpour not_allowed)
				(footprints allowed)
			)
			(placement
				(enabled no)
				(sheetname "")
			)
			(fill
				(thermal_gap 0.5)
				(thermal_bridge_width 0.5)
				(island_removal_mode 0)
			)
			(polygon
				(pts
					(arc
						(start 341.195152 -40.051736)
						(mid 341.241753 -40.127563)
						(end 341.31758 -40.174164)
					)
					(arc
						(start 341.31758 -40.27932)
						(mid 341.169668 -40.199569)
						(end 341.089742 -40.051736)
					)
				)
			)
		)
		(zone
			(layer "F.Cu")
			(hatch none 0.5)
			(connect_pads
				(clearance 0)
			)
			(min_thickness 0.25)
			(keepout
				(tracks not_allowed)
				(vias allowed)
				(pads allowed)
				(copperpour not_allowed)
				(footprints allowed)
			)
			(placement
				(enabled no)
				(sheetname "")
			)
			(fill
				(thermal_gap 0.5)
				(thermal_bridge_width 0.5)
				(island_removal_mode 0)
			)
			(polygon
				(pts
					(arc
						(start 341.31758 -56.726328)
						(mid 341.241753 -56.772929)
						(end 341.195152 -56.848756)
					)
					(arc
						(start 341.089742 -56.848756)
						(mid 341.169632 -56.700886)
						(end 341.31758 -56.621172)
					)
				)
			)
		)
		(zone
			(layer "F.Cu")
			(hatch none 0.5)
			(connect_pads
				(clearance 0)
			)
			(min_thickness 0.25)
			(keepout
				(tracks not_allowed)
				(vias allowed)
				(pads allowed)
				(copperpour not_allowed)
				(footprints allowed)
			)
			(placement
				(enabled no)
				(sheetname "")
			)
			(fill
				(thermal_gap 0.5)
				(thermal_bridge_width 0.5)
				(island_removal_mode 0)
			)
			(polygon
				(pts
					(arc
						(start 341.31758 -55.786528)
						(mid 341.241753 -55.833129)
						(end 341.195152 -55.908956)
					)
					(arc
						(start 341.089742 -55.908956)
						(mid 341.169632 -55.761086)
						(end 341.31758 -55.681372)
					)
				)
			)
		)
		(zone
			(layer "F.Cu")
			(hatch none 0.5)
			(connect_pads
				(clearance 0)
			)
			(min_thickness 0.25)
			(keepout
				(tracks not_allowed)
				(vias allowed)
				(pads allowed)
				(copperpour not_allowed)
				(footprints allowed)
			)
			(placement
				(enabled no)
				(sheetname "")
			)
			(fill
				(thermal_gap 0.5)
				(thermal_bridge_width 0.5)
				(island_removal_mode 0)
			)
			(polygon
				(pts
					(arc
						(start 341.31758 -54.846728)
						(mid 341.241753 -54.893329)
						(end 341.195152 -54.969156)
					)
					(arc
						(start 341.089742 -54.969156)
						(mid 341.169632 -54.821286)
						(end 341.31758 -54.741572)
					)
				)
			)
		)
		(zone
			(layer "F.Cu")
			(hatch none 0.5)
			(connect_pads
				(clearance 0)
			)
			(min_thickness 0.25)
			(keepout
				(tracks not_allowed)
				(vias allowed)
				(pads allowed)
				(copperpour not_allowed)
				(footprints allowed)
			)
			(placement
				(enabled no)
				(sheetname "")
			)
			(fill
				(thermal_gap 0.5)
				(thermal_bridge_width 0.5)
				(island_removal_mode 0)
			)
			(polygon
				(pts
					(arc
						(start 341.31758 -53.906928)
						(mid 341.241753 -53.953529)
						(end 341.195152 -54.029356)
					)
					(arc
						(start 341.089742 -54.029356)
						(mid 341.169632 -53.881486)
						(end 341.31758 -53.801772)
					)
				)
			)
		)
		(zone
			(layer "F.Cu")
			(hatch none 0.5)
			(connect_pads
				(clearance 0)
			)
			(min_thickness 0.25)
			(keepout
				(tracks not_allowed)
				(vias allowed)
				(pads allowed)
				(copperpour not_allowed)
				(footprints allowed)
			)
			(placement
				(enabled no)
				(sheetname "")
			)
			(fill
				(thermal_gap 0.5)
				(thermal_bridge_width 0.5)
				(island_removal_mode 0)
			)
			(polygon
				(pts
					(arc
						(start 341.31758 -52.967128)
						(mid 341.241753 -53.013729)
						(end 341.195152 -53.089556)
					)
					(arc
						(start 341.089742 -53.089556)
						(mid 341.169632 -52.941686)
						(end 341.31758 -52.861972)
					)
				)
			)
		)
		(zone
			(layer "F.Cu")
			(hatch none 0.5)
			(connect_pads
				(clearance 0)
			)
			(min_thickness 0.25)
			(keepout
				(tracks not_allowed)
				(vias allowed)
				(pads allowed)
				(copperpour not_allowed)
				(footprints allowed)
			)
			(placement
				(enabled no)
				(sheetname "")
			)
			(fill
				(thermal_gap 0.5)
				(thermal_bridge_width 0.5)
				(island_removal_mode 0)
			)
			(polygon
				(pts
					(arc
						(start 341.31758 -52.027328)
						(mid 341.241753 -52.073929)
						(end 341.195152 -52.149756)
					)
					(arc
						(start 341.089742 -52.149756)
						(mid 341.169632 -52.001886)
						(end 341.31758 -51.922172)
					)
				)
			)
		)
		(zone
			(layer "F.Cu")
			(hatch none 0.5)
			(connect_pads
				(clearance 0)
			)
			(min_thickness 0.25)
			(keepout
				(tracks not_allowed)
				(vias allowed)
				(pads allowed)
				(copperpour not_allowed)
				(footprints allowed)
			)
			(placement
				(enabled no)
				(sheetname "")
			)
			(fill
				(thermal_gap 0.5)
				(thermal_bridge_width 0.5)
				(island_removal_mode 0)
			)
			(polygon
				(pts
					(arc
						(start 341.31758 -51.087528)
						(mid 341.241753 -51.134129)
						(end 341.195152 -51.209956)
					)
					(arc
						(start 341.089742 -51.209956)
						(mid 341.169632 -51.062086)
						(end 341.31758 -50.982372)
					)
				)
			)
		)
		(zone
			(layer "F.Cu")
			(hatch none 0.5)
			(connect_pads
				(clearance 0)
			)
			(min_thickness 0.25)
			(keepout
				(tracks not_allowed)
				(vias allowed)
				(pads allowed)
				(copperpour not_allowed)
				(footprints allowed)
			)
			(placement
				(enabled no)
				(sheetname "")
			)
			(fill
				(thermal_gap 0.5)
				(thermal_bridge_width 0.5)
				(island_removal_mode 0)
			)
			(polygon
				(pts
					(arc
						(start 341.31758 -50.147728)
						(mid 341.241753 -50.194329)
						(end 341.195152 -50.270156)
					)
					(arc
						(start 341.089742 -50.270156)
						(mid 341.169632 -50.122286)
						(end 341.31758 -50.042572)
					)
				)
			)
		)
		(zone
			(layer "F.Cu")
			(hatch none 0.5)
			(connect_pads
				(clearance 0)
			)
			(min_thickness 0.25)
			(keepout
				(tracks not_allowed)
				(vias allowed)
				(pads allowed)
				(copperpour not_allowed)
				(footprints allowed)
			)
			(placement
				(enabled no)
				(sheetname "")
			)
			(fill
				(thermal_gap 0.5)
				(thermal_bridge_width 0.5)
				(island_removal_mode 0)
			)
			(polygon
				(pts
					(arc
						(start 341.31758 -49.207928)
						(mid 341.241753 -49.254529)
						(end 341.195152 -49.330356)
					)
					(arc
						(start 341.089742 -49.330356)
						(mid 341.169632 -49.182486)
						(end 341.31758 -49.102772)
					)
				)
			)
		)
		(zone
			(layer "F.Cu")
			(hatch none 0.5)
			(connect_pads
				(clearance 0)
			)
			(min_thickness 0.25)
			(keepout
				(tracks not_allowed)
				(vias allowed)
				(pads allowed)
				(copperpour not_allowed)
				(footprints allowed)
			)
			(placement
				(enabled no)
				(sheetname "")
			)
			(fill
				(thermal_gap 0.5)
				(thermal_bridge_width 0.5)
				(island_removal_mode 0)
			)
			(polygon
				(pts
					(arc
						(start 341.31758 -48.268128)
						(mid 341.241753 -48.314729)
						(end 341.195152 -48.390556)
					)
					(arc
						(start 341.089742 -48.390556)
						(mid 341.169632 -48.242686)
						(end 341.31758 -48.162972)
					)
				)
			)
		)
		(zone
			(layer "F.Cu")
			(hatch none 0.5)
			(connect_pads
				(clearance 0)
			)
			(min_thickness 0.25)
			(keepout
				(tracks not_allowed)
				(vias allowed)
				(pads allowed)
				(copperpour not_allowed)
				(footprints allowed)
			)
			(placement
				(enabled no)
				(sheetname "")
			)
			(fill
				(thermal_gap 0.5)
				(thermal_bridge_width 0.5)
				(island_removal_mode 0)
			)
			(polygon
				(pts
					(arc
						(start 341.31758 -47.328328)
						(mid 341.241753 -47.374929)
						(end 341.195152 -47.450756)
					)
					(arc
						(start 341.089742 -47.450756)
						(mid 341.169632 -47.302886)
						(end 341.31758 -47.223172)
					)
				)
			)
		)
		(zone
			(layer "F.Cu")
			(hatch none 0.5)
			(connect_pads
				(clearance 0)
			)
			(min_thickness 0.25)
			(keepout
				(tracks not_allowed)
				(vias allowed)
				(pads allowed)
				(copperpour not_allowed)
				(footprints allowed)
			)
			(placement
				(enabled no)
				(sheetname "")
			)
			(fill
				(thermal_gap 0.5)
				(thermal_bridge_width 0.5)
				(island_removal_mode 0)
			)
			(polygon
				(pts
					(arc
						(start 341.31758 -46.388528)
						(mid 341.241753 -46.435129)
						(end 341.195152 -46.510956)
					)
					(arc
						(start 341.089742 -46.510956)
						(mid 341.169632 -46.363086)
						(end 341.31758 -46.283372)
					)
				)
			)
		)
		(zone
			(layer "F.Cu")
			(hatch none 0.5)
			(connect_pads
				(clearance 0)
			)
			(min_thickness 0.25)
			(keepout
				(tracks not_allowed)
				(vias allowed)
				(pads allowed)
				(copperpour not_allowed)
				(footprints allowed)
			)
			(placement
				(enabled no)
				(sheetname "")
			)
			(fill
				(thermal_gap 0.5)
				(thermal_bridge_width 0.5)
				(island_removal_mode 0)
			)
			(polygon
				(pts
					(arc
						(start 341.31758 -45.448728)
						(mid 341.241753 -45.495329)
						(end 341.195152 -45.571156)
					)
					(arc
						(start 341.089742 -45.571156)
						(mid 341.169632 -45.423286)
						(end 341.31758 -45.343572)
					)
				)
			)
		)
		(zone
			(layer "F.Cu")
			(hatch none 0.5)
			(connect_pads
				(clearance 0)
			)
			(min_thickness 0.25)
			(keepout
				(tracks not_allowed)
				(vias allowed)
				(pads allowed)
				(copperpour not_allowed)
				(footprints allowed)
			)
			(placement
				(enabled no)
				(sheetname "")
			)
			(fill
				(thermal_gap 0.5)
				(thermal_bridge_width 0.5)
				(island_removal_mode 0)
			)
			(polygon
				(pts
					(arc
						(start 341.31758 -44.508928)
						(mid 341.241753 -44.555529)
						(end 341.195152 -44.631356)
					)
					(arc
						(start 341.089742 -44.631356)
						(mid 341.169632 -44.483486)
						(end 341.31758 -44.403772)
					)
				)
			)
		)
		(zone
			(layer "F.Cu")
			(hatch none 0.5)
			(connect_pads
				(clearance 0)
			)
			(min_thickness 0.25)
			(keepout
				(tracks not_allowed)
				(vias allowed)
				(pads allowed)
				(copperpour not_allowed)
				(footprints allowed)
			)
			(placement
				(enabled no)
				(sheetname "")
			)
			(fill
				(thermal_gap 0.5)
				(thermal_bridge_width 0.5)
				(island_removal_mode 0)
			)
			(polygon
				(pts
					(arc
						(start 341.31758 -43.569128)
						(mid 341.241753 -43.615729)
						(end 341.195152 -43.691556)
					)
					(arc
						(start 341.089742 -43.691556)
						(mid 341.169632 -43.543686)
						(end 341.31758 -43.463972)
					)
				)
			)
		)
		(zone
			(layer "F.Cu")
			(hatch none 0.5)
			(connect_pads
				(clearance 0)
			)
			(min_thickness 0.25)
			(keepout
				(tracks not_allowed)
				(vias allowed)
				(pads allowed)
				(copperpour not_allowed)
				(footprints allowed)
			)
			(placement
				(enabled no)
				(sheetname "")
			)
			(fill
				(thermal_gap 0.5)
				(thermal_bridge_width 0.5)
				(island_removal_mode 0)
			)
			(polygon
				(pts
					(arc
						(start 341.31758 -42.629328)
						(mid 341.241753 -42.675929)
						(end 341.195152 -42.751756)
					)
					(arc
						(start 341.089742 -42.751756)
						(mid 341.169632 -42.603886)
						(end 341.31758 -42.524172)
					)
				)
			)
		)
		(zone
			(layer "F.Cu")
			(hatch none 0.5)
			(connect_pads
				(clearance 0)
			)
			(min_thickness 0.25)
			(keepout
				(tracks not_allowed)
				(vias allowed)
				(pads allowed)
				(copperpour not_allowed)
				(footprints allowed)
			)
			(placement
				(enabled no)
				(sheetname "")
			)
			(fill
				(thermal_gap 0.5)
				(thermal_bridge_width 0.5)
				(island_removal_mode 0)
			)
			(polygon
				(pts
					(arc
						(start 341.31758 -41.689528)
						(mid 341.241753 -41.736129)
						(end 341.195152 -41.811956)
					)
					(arc
						(start 341.089742 -41.811956)
						(mid 341.169632 -41.664086)
						(end 341.31758 -41.584372)
					)
				)
			)
		)
		(zone
			(layer "F.Cu")
			(hatch none 0.5)
			(connect_pads
				(clearance 0)
			)
			(min_thickness 0.25)
			(keepout
				(tracks not_allowed)
				(vias allowed)
				(pads allowed)
				(copperpour not_allowed)
				(footprints allowed)
			)
			(placement
				(enabled no)
				(sheetname "")
			)
			(fill
				(thermal_gap 0.5)
				(thermal_bridge_width 0.5)
				(island_removal_mode 0)
			)
			(polygon
				(pts
					(arc
						(start 341.31758 -40.749728)
						(mid 341.241753 -40.796329)
						(end 341.195152 -40.872156)
					)
					(arc
						(start 341.089742 -40.872156)
						(mid 341.169632 -40.724286)
						(end 341.31758 -40.644572)
					)
				)
			)
		)
		(zone
			(layer "F.Cu")
			(hatch none 0.5)
			(connect_pads
				(clearance 0)
			)
			(min_thickness 0.25)
			(keepout
				(tracks not_allowed)
				(vias allowed)
				(pads allowed)
				(copperpour not_allowed)
				(footprints allowed)
			)
			(placement
				(enabled no)
				(sheetname "")
			)
			(fill
				(thermal_gap 0.5)
				(thermal_bridge_width 0.5)
				(island_removal_mode 0)
			)
			(polygon
				(pts
					(arc
						(start 341.31758 -39.809928)
						(mid 341.241753 -39.856529)
						(end 341.195152 -39.932356)
					)
					(arc
						(start 341.089742 -39.932356)
						(mid 341.169632 -39.784486)
						(end 341.31758 -39.704772)
					)
				)
			)
		)
		(zone
			(layer "F.Cu")
			(hatch none 0.5)
			(connect_pads
				(clearance 0)
			)
			(min_thickness 0.25)
			(keepout
				(tracks not_allowed)
				(vias allowed)
				(pads allowed)
				(copperpour not_allowed)
				(footprints allowed)
			)
			(placement
				(enabled no)
				(sheetname "")
			)
			(fill
				(thermal_gap 0.5)
				(thermal_bridge_width 0.5)
				(island_removal_mode 0)
			)
			(polygon
				(pts
					(arc
						(start 341.43696 -57.090564)
						(mid 341.512675 -57.043934)
						(end 341.559134 -56.968136)
					)
					(arc
						(start 341.664544 -56.968136)
						(mid 341.584742 -57.115918)
						(end 341.43696 -57.19572)
					)
				)
			)
		)
		(zone
			(layer "F.Cu")
			(hatch none 0.5)
			(connect_pads
				(clearance 0)
			)
			(min_thickness 0.25)
			(keepout
				(tracks not_allowed)
				(vias allowed)
				(pads allowed)
				(copperpour not_allowed)
				(footprints allowed)
			)
			(placement
				(enabled no)
				(sheetname "")
			)
			(fill
				(thermal_gap 0.5)
				(thermal_bridge_width 0.5)
				(island_removal_mode 0)
			)
			(polygon
				(pts
					(arc
						(start 341.43696 -56.150764)
						(mid 341.512675 -56.104134)
						(end 341.559134 -56.028336)
					)
					(arc
						(start 341.664544 -56.028336)
						(mid 341.584742 -56.176118)
						(end 341.43696 -56.25592)
					)
				)
			)
		)
		(zone
			(layer "F.Cu")
			(hatch none 0.5)
			(connect_pads
				(clearance 0)
			)
			(min_thickness 0.25)
			(keepout
				(tracks not_allowed)
				(vias allowed)
				(pads allowed)
				(copperpour not_allowed)
				(footprints allowed)
			)
			(placement
				(enabled no)
				(sheetname "")
			)
			(fill
				(thermal_gap 0.5)
				(thermal_bridge_width 0.5)
				(island_removal_mode 0)
			)
			(polygon
				(pts
					(arc
						(start 341.43696 -55.210964)
						(mid 341.512675 -55.164334)
						(end 341.559134 -55.088536)
					)
					(arc
						(start 341.664544 -55.088536)
						(mid 341.584742 -55.236318)
						(end 341.43696 -55.31612)
					)
				)
			)
		)
		(zone
			(layer "F.Cu")
			(hatch none 0.5)
			(connect_pads
				(clearance 0)
			)
			(min_thickness 0.25)
			(keepout
				(tracks not_allowed)
				(vias allowed)
				(pads allowed)
				(copperpour not_allowed)
				(footprints allowed)
			)
			(placement
				(enabled no)
				(sheetname "")
			)
			(fill
				(thermal_gap 0.5)
				(thermal_bridge_width 0.5)
				(island_removal_mode 0)
			)
			(polygon
				(pts
					(arc
						(start 341.43696 -54.271164)
						(mid 341.512675 -54.224534)
						(end 341.559134 -54.148736)
					)
					(arc
						(start 341.664544 -54.148736)
						(mid 341.584742 -54.296518)
						(end 341.43696 -54.37632)
					)
				)
			)
		)
		(zone
			(layer "F.Cu")
			(hatch none 0.5)
			(connect_pads
				(clearance 0)
			)
			(min_thickness 0.25)
			(keepout
				(tracks not_allowed)
				(vias allowed)
				(pads allowed)
				(copperpour not_allowed)
				(footprints allowed)
			)
			(placement
				(enabled no)
				(sheetname "")
			)
			(fill
				(thermal_gap 0.5)
				(thermal_bridge_width 0.5)
				(island_removal_mode 0)
			)
			(polygon
				(pts
					(arc
						(start 341.43696 -53.331364)
						(mid 341.512675 -53.284734)
						(end 341.559134 -53.208936)
					)
					(arc
						(start 341.664544 -53.208936)
						(mid 341.584742 -53.356718)
						(end 341.43696 -53.43652)
					)
				)
			)
		)
		(zone
			(layer "F.Cu")
			(hatch none 0.5)
			(connect_pads
				(clearance 0)
			)
			(min_thickness 0.25)
			(keepout
				(tracks not_allowed)
				(vias allowed)
				(pads allowed)
				(copperpour not_allowed)
				(footprints allowed)
			)
			(placement
				(enabled no)
				(sheetname "")
			)
			(fill
				(thermal_gap 0.5)
				(thermal_bridge_width 0.5)
				(island_removal_mode 0)
			)
			(polygon
				(pts
					(arc
						(start 341.43696 -52.391564)
						(mid 341.512675 -52.344934)
						(end 341.559134 -52.269136)
					)
					(arc
						(start 341.664544 -52.269136)
						(mid 341.584742 -52.416918)
						(end 341.43696 -52.49672)
					)
				)
			)
		)
		(zone
			(layer "F.Cu")
			(hatch none 0.5)
			(connect_pads
				(clearance 0)
			)
			(min_thickness 0.25)
			(keepout
				(tracks not_allowed)
				(vias allowed)
				(pads allowed)
				(copperpour not_allowed)
				(footprints allowed)
			)
			(placement
				(enabled no)
				(sheetname "")
			)
			(fill
				(thermal_gap 0.5)
				(thermal_bridge_width 0.5)
				(island_removal_mode 0)
			)
			(polygon
				(pts
					(arc
						(start 341.43696 -51.451764)
						(mid 341.512675 -51.405134)
						(end 341.559134 -51.329336)
					)
					(arc
						(start 341.664544 -51.329336)
						(mid 341.584742 -51.477118)
						(end 341.43696 -51.55692)
					)
				)
			)
		)
		(zone
			(layer "F.Cu")
			(hatch none 0.5)
			(connect_pads
				(clearance 0)
			)
			(min_thickness 0.25)
			(keepout
				(tracks not_allowed)
				(vias allowed)
				(pads allowed)
				(copperpour not_allowed)
				(footprints allowed)
			)
			(placement
				(enabled no)
				(sheetname "")
			)
			(fill
				(thermal_gap 0.5)
				(thermal_bridge_width 0.5)
				(island_removal_mode 0)
			)
			(polygon
				(pts
					(arc
						(start 341.43696 -50.511964)
						(mid 341.512675 -50.465334)
						(end 341.559134 -50.389536)
					)
					(arc
						(start 341.664544 -50.389536)
						(mid 341.584742 -50.537318)
						(end 341.43696 -50.61712)
					)
				)
			)
		)
		(zone
			(layer "F.Cu")
			(hatch none 0.5)
			(connect_pads
				(clearance 0)
			)
			(min_thickness 0.25)
			(keepout
				(tracks not_allowed)
				(vias allowed)
				(pads allowed)
				(copperpour not_allowed)
				(footprints allowed)
			)
			(placement
				(enabled no)
				(sheetname "")
			)
			(fill
				(thermal_gap 0.5)
				(thermal_bridge_width 0.5)
				(island_removal_mode 0)
			)
			(polygon
				(pts
					(arc
						(start 341.43696 -49.572164)
						(mid 341.512675 -49.525534)
						(end 341.559134 -49.449736)
					)
					(arc
						(start 341.664544 -49.449736)
						(mid 341.584742 -49.597518)
						(end 341.43696 -49.67732)
					)
				)
			)
		)
		(zone
			(layer "F.Cu")
			(hatch none 0.5)
			(connect_pads
				(clearance 0)
			)
			(min_thickness 0.25)
			(keepout
				(tracks not_allowed)
				(vias allowed)
				(pads allowed)
				(copperpour not_allowed)
				(footprints allowed)
			)
			(placement
				(enabled no)
				(sheetname "")
			)
			(fill
				(thermal_gap 0.5)
				(thermal_bridge_width 0.5)
				(island_removal_mode 0)
			)
			(polygon
				(pts
					(arc
						(start 341.43696 -48.632364)
						(mid 341.512675 -48.585734)
						(end 341.559134 -48.509936)
					)
					(arc
						(start 341.664544 -48.509936)
						(mid 341.584742 -48.657718)
						(end 341.43696 -48.73752)
					)
				)
			)
		)
		(zone
			(layer "F.Cu")
			(hatch none 0.5)
			(connect_pads
				(clearance 0)
			)
			(min_thickness 0.25)
			(keepout
				(tracks not_allowed)
				(vias allowed)
				(pads allowed)
				(copperpour not_allowed)
				(footprints allowed)
			)
			(placement
				(enabled no)
				(sheetname "")
			)
			(fill
				(thermal_gap 0.5)
				(thermal_bridge_width 0.5)
				(island_removal_mode 0)
			)
			(polygon
				(pts
					(arc
						(start 341.43696 -47.692564)
						(mid 341.512675 -47.645934)
						(end 341.559134 -47.570136)
					)
					(arc
						(start 341.664544 -47.570136)
						(mid 341.584742 -47.717918)
						(end 341.43696 -47.79772)
					)
				)
			)
		)
		(zone
			(layer "F.Cu")
			(hatch none 0.5)
			(connect_pads
				(clearance 0)
			)
			(min_thickness 0.25)
			(keepout
				(tracks not_allowed)
				(vias allowed)
				(pads allowed)
				(copperpour not_allowed)
				(footprints allowed)
			)
			(placement
				(enabled no)
				(sheetname "")
			)
			(fill
				(thermal_gap 0.5)
				(thermal_bridge_width 0.5)
				(island_removal_mode 0)
			)
			(polygon
				(pts
					(arc
						(start 341.43696 -46.752764)
						(mid 341.512675 -46.706134)
						(end 341.559134 -46.630336)
					)
					(arc
						(start 341.664544 -46.630336)
						(mid 341.584742 -46.778118)
						(end 341.43696 -46.85792)
					)
				)
			)
		)
		(zone
			(layer "F.Cu")
			(hatch none 0.5)
			(connect_pads
				(clearance 0)
			)
			(min_thickness 0.25)
			(keepout
				(tracks not_allowed)
				(vias allowed)
				(pads allowed)
				(copperpour not_allowed)
				(footprints allowed)
			)
			(placement
				(enabled no)
				(sheetname "")
			)
			(fill
				(thermal_gap 0.5)
				(thermal_bridge_width 0.5)
				(island_removal_mode 0)
			)
			(polygon
				(pts
					(arc
						(start 341.43696 -45.812964)
						(mid 341.512675 -45.766334)
						(end 341.559134 -45.690536)
					)
					(arc
						(start 341.664544 -45.690536)
						(mid 341.584742 -45.838318)
						(end 341.43696 -45.91812)
					)
				)
			)
		)
		(zone
			(layer "F.Cu")
			(hatch none 0.5)
			(connect_pads
				(clearance 0)
			)
			(min_thickness 0.25)
			(keepout
				(tracks not_allowed)
				(vias allowed)
				(pads allowed)
				(copperpour not_allowed)
				(footprints allowed)
			)
			(placement
				(enabled no)
				(sheetname "")
			)
			(fill
				(thermal_gap 0.5)
				(thermal_bridge_width 0.5)
				(island_removal_mode 0)
			)
			(polygon
				(pts
					(arc
						(start 341.43696 -44.873164)
						(mid 341.512675 -44.826534)
						(end 341.559134 -44.750736)
					)
					(arc
						(start 341.664544 -44.750736)
						(mid 341.584742 -44.898518)
						(end 341.43696 -44.97832)
					)
				)
			)
		)
		(zone
			(layer "F.Cu")
			(hatch none 0.5)
			(connect_pads
				(clearance 0)
			)
			(min_thickness 0.25)
			(keepout
				(tracks not_allowed)
				(vias allowed)
				(pads allowed)
				(copperpour not_allowed)
				(footprints allowed)
			)
			(placement
				(enabled no)
				(sheetname "")
			)
			(fill
				(thermal_gap 0.5)
				(thermal_bridge_width 0.5)
				(island_removal_mode 0)
			)
			(polygon
				(pts
					(arc
						(start 341.43696 -43.933364)
						(mid 341.512675 -43.886734)
						(end 341.559134 -43.810936)
					)
					(arc
						(start 341.664544 -43.810936)
						(mid 341.584742 -43.958718)
						(end 341.43696 -44.03852)
					)
				)
			)
		)
		(zone
			(layer "F.Cu")
			(hatch none 0.5)
			(connect_pads
				(clearance 0)
			)
			(min_thickness 0.25)
			(keepout
				(tracks not_allowed)
				(vias allowed)
				(pads allowed)
				(copperpour not_allowed)
				(footprints allowed)
			)
			(placement
				(enabled no)
				(sheetname "")
			)
			(fill
				(thermal_gap 0.5)
				(thermal_bridge_width 0.5)
				(island_removal_mode 0)
			)
			(polygon
				(pts
					(arc
						(start 341.43696 -42.993564)
						(mid 341.512675 -42.946934)
						(end 341.559134 -42.871136)
					)
					(arc
						(start 341.664544 -42.871136)
						(mid 341.584742 -43.018918)
						(end 341.43696 -43.09872)
					)
				)
			)
		)
		(zone
			(layer "F.Cu")
			(hatch none 0.5)
			(connect_pads
				(clearance 0)
			)
			(min_thickness 0.25)
			(keepout
				(tracks not_allowed)
				(vias allowed)
				(pads allowed)
				(copperpour not_allowed)
				(footprints allowed)
			)
			(placement
				(enabled no)
				(sheetname "")
			)
			(fill
				(thermal_gap 0.5)
				(thermal_bridge_width 0.5)
				(island_removal_mode 0)
			)
			(polygon
				(pts
					(arc
						(start 341.43696 -42.053764)
						(mid 341.512675 -42.007134)
						(end 341.559134 -41.931336)
					)
					(arc
						(start 341.664544 -41.931336)
						(mid 341.584742 -42.079118)
						(end 341.43696 -42.15892)
					)
				)
			)
		)
		(zone
			(layer "F.Cu")
			(hatch none 0.5)
			(connect_pads
				(clearance 0)
			)
			(min_thickness 0.25)
			(keepout
				(tracks not_allowed)
				(vias allowed)
				(pads allowed)
				(copperpour not_allowed)
				(footprints allowed)
			)
			(placement
				(enabled no)
				(sheetname "")
			)
			(fill
				(thermal_gap 0.5)
				(thermal_bridge_width 0.5)
				(island_removal_mode 0)
			)
			(polygon
				(pts
					(arc
						(start 341.43696 -41.113964)
						(mid 341.512675 -41.067334)
						(end 341.559134 -40.991536)
					)
					(arc
						(start 341.664544 -40.991536)
						(mid 341.584742 -41.139318)
						(end 341.43696 -41.21912)
					)
				)
			)
		)
		(zone
			(layer "F.Cu")
			(hatch none 0.5)
			(connect_pads
				(clearance 0)
			)
			(min_thickness 0.25)
			(keepout
				(tracks not_allowed)
				(vias allowed)
				(pads allowed)
				(copperpour not_allowed)
				(footprints allowed)
			)
			(placement
				(enabled no)
				(sheetname "")
			)
			(fill
				(thermal_gap 0.5)
				(thermal_bridge_width 0.5)
				(island_removal_mode 0)
			)
			(polygon
				(pts
					(arc
						(start 341.43696 -40.174164)
						(mid 341.512675 -40.127534)
						(end 341.559134 -40.051736)
					)
					(arc
						(start 341.664544 -40.051736)
						(mid 341.584742 -40.199518)
						(end 341.43696 -40.27932)
					)
				)
			)
		)
		(zone
			(layer "F.Cu")
			(hatch none 0.5)
			(connect_pads
				(clearance 0)
			)
			(min_thickness 0.25)
			(keepout
				(tracks not_allowed)
				(vias allowed)
				(pads allowed)
				(copperpour not_allowed)
				(footprints allowed)
			)
			(placement
				(enabled no)
				(sheetname "")
			)
			(fill
				(thermal_gap 0.5)
				(thermal_bridge_width 0.5)
				(island_removal_mode 0)
			)
			(polygon
				(pts
					(arc
						(start 341.559134 -56.848756)
						(mid 341.512619 -56.773014)
						(end 341.43696 -56.726328)
					)
					(arc
						(start 341.43696 -56.621172)
						(mid 341.584742 -56.700974)
						(end 341.664544 -56.848756)
					)
				)
			)
		)
		(zone
			(layer "F.Cu")
			(hatch none 0.5)
			(connect_pads
				(clearance 0)
			)
			(min_thickness 0.25)
			(keepout
				(tracks not_allowed)
				(vias allowed)
				(pads allowed)
				(copperpour not_allowed)
				(footprints allowed)
			)
			(placement
				(enabled no)
				(sheetname "")
			)
			(fill
				(thermal_gap 0.5)
				(thermal_bridge_width 0.5)
				(island_removal_mode 0)
			)
			(polygon
				(pts
					(arc
						(start 341.559134 -55.908956)
						(mid 341.512619 -55.833214)
						(end 341.43696 -55.786528)
					)
					(arc
						(start 341.43696 -55.681372)
						(mid 341.584742 -55.761174)
						(end 341.664544 -55.908956)
					)
				)
			)
		)
		(zone
			(layer "F.Cu")
			(hatch none 0.5)
			(connect_pads
				(clearance 0)
			)
			(min_thickness 0.25)
			(keepout
				(tracks not_allowed)
				(vias allowed)
				(pads allowed)
				(copperpour not_allowed)
				(footprints allowed)
			)
			(placement
				(enabled no)
				(sheetname "")
			)
			(fill
				(thermal_gap 0.5)
				(thermal_bridge_width 0.5)
				(island_removal_mode 0)
			)
			(polygon
				(pts
					(arc
						(start 341.559134 -54.969156)
						(mid 341.512619 -54.893414)
						(end 341.43696 -54.846728)
					)
					(arc
						(start 341.43696 -54.741572)
						(mid 341.584742 -54.821374)
						(end 341.664544 -54.969156)
					)
				)
			)
		)
		(zone
			(layer "F.Cu")
			(hatch none 0.5)
			(connect_pads
				(clearance 0)
			)
			(min_thickness 0.25)
			(keepout
				(tracks not_allowed)
				(vias allowed)
				(pads allowed)
				(copperpour not_allowed)
				(footprints allowed)
			)
			(placement
				(enabled no)
				(sheetname "")
			)
			(fill
				(thermal_gap 0.5)
				(thermal_bridge_width 0.5)
				(island_removal_mode 0)
			)
			(polygon
				(pts
					(arc
						(start 341.559134 -54.029356)
						(mid 341.512619 -53.953614)
						(end 341.43696 -53.906928)
					)
					(arc
						(start 341.43696 -53.801772)
						(mid 341.584742 -53.881574)
						(end 341.664544 -54.029356)
					)
				)
			)
		)
		(zone
			(layer "F.Cu")
			(hatch none 0.5)
			(connect_pads
				(clearance 0)
			)
			(min_thickness 0.25)
			(keepout
				(tracks not_allowed)
				(vias allowed)
				(pads allowed)
				(copperpour not_allowed)
				(footprints allowed)
			)
			(placement
				(enabled no)
				(sheetname "")
			)
			(fill
				(thermal_gap 0.5)
				(thermal_bridge_width 0.5)
				(island_removal_mode 0)
			)
			(polygon
				(pts
					(arc
						(start 341.559134 -53.089556)
						(mid 341.512619 -53.013814)
						(end 341.43696 -52.967128)
					)
					(arc
						(start 341.43696 -52.861972)
						(mid 341.584742 -52.941774)
						(end 341.664544 -53.089556)
					)
				)
			)
		)
		(zone
			(layer "F.Cu")
			(hatch none 0.5)
			(connect_pads
				(clearance 0)
			)
			(min_thickness 0.25)
			(keepout
				(tracks not_allowed)
				(vias allowed)
				(pads allowed)
				(copperpour not_allowed)
				(footprints allowed)
			)
			(placement
				(enabled no)
				(sheetname "")
			)
			(fill
				(thermal_gap 0.5)
				(thermal_bridge_width 0.5)
				(island_removal_mode 0)
			)
			(polygon
				(pts
					(arc
						(start 341.559134 -52.149756)
						(mid 341.512619 -52.074014)
						(end 341.43696 -52.027328)
					)
					(arc
						(start 341.43696 -51.922172)
						(mid 341.584742 -52.001974)
						(end 341.664544 -52.149756)
					)
				)
			)
		)
		(zone
			(layer "F.Cu")
			(hatch none 0.5)
			(connect_pads
				(clearance 0)
			)
			(min_thickness 0.25)
			(keepout
				(tracks not_allowed)
				(vias allowed)
				(pads allowed)
				(copperpour not_allowed)
				(footprints allowed)
			)
			(placement
				(enabled no)
				(sheetname "")
			)
			(fill
				(thermal_gap 0.5)
				(thermal_bridge_width 0.5)
				(island_removal_mode 0)
			)
			(polygon
				(pts
					(arc
						(start 341.559134 -51.209956)
						(mid 341.512619 -51.134214)
						(end 341.43696 -51.087528)
					)
					(arc
						(start 341.43696 -50.982372)
						(mid 341.584742 -51.062174)
						(end 341.664544 -51.209956)
					)
				)
			)
		)
		(zone
			(layer "F.Cu")
			(hatch none 0.5)
			(connect_pads
				(clearance 0)
			)
			(min_thickness 0.25)
			(keepout
				(tracks not_allowed)
				(vias allowed)
				(pads allowed)
				(copperpour not_allowed)
				(footprints allowed)
			)
			(placement
				(enabled no)
				(sheetname "")
			)
			(fill
				(thermal_gap 0.5)
				(thermal_bridge_width 0.5)
				(island_removal_mode 0)
			)
			(polygon
				(pts
					(arc
						(start 341.559134 -50.270156)
						(mid 341.512619 -50.194414)
						(end 341.43696 -50.147728)
					)
					(arc
						(start 341.43696 -50.042572)
						(mid 341.584742 -50.122374)
						(end 341.664544 -50.270156)
					)
				)
			)
		)
		(zone
			(layer "F.Cu")
			(hatch none 0.5)
			(connect_pads
				(clearance 0)
			)
			(min_thickness 0.25)
			(keepout
				(tracks not_allowed)
				(vias allowed)
				(pads allowed)
				(copperpour not_allowed)
				(footprints allowed)
			)
			(placement
				(enabled no)
				(sheetname "")
			)
			(fill
				(thermal_gap 0.5)
				(thermal_bridge_width 0.5)
				(island_removal_mode 0)
			)
			(polygon
				(pts
					(arc
						(start 341.559134 -49.330356)
						(mid 341.512619 -49.254614)
						(end 341.43696 -49.207928)
					)
					(arc
						(start 341.43696 -49.102772)
						(mid 341.584742 -49.182574)
						(end 341.664544 -49.330356)
					)
				)
			)
		)
		(zone
			(layer "F.Cu")
			(hatch none 0.5)
			(connect_pads
				(clearance 0)
			)
			(min_thickness 0.25)
			(keepout
				(tracks not_allowed)
				(vias allowed)
				(pads allowed)
				(copperpour not_allowed)
				(footprints allowed)
			)
			(placement
				(enabled no)
				(sheetname "")
			)
			(fill
				(thermal_gap 0.5)
				(thermal_bridge_width 0.5)
				(island_removal_mode 0)
			)
			(polygon
				(pts
					(arc
						(start 341.559134 -48.390556)
						(mid 341.512619 -48.314814)
						(end 341.43696 -48.268128)
					)
					(arc
						(start 341.43696 -48.162972)
						(mid 341.584742 -48.242774)
						(end 341.664544 -48.390556)
					)
				)
			)
		)
		(zone
			(layer "F.Cu")
			(hatch none 0.5)
			(connect_pads
				(clearance 0)
			)
			(min_thickness 0.25)
			(keepout
				(tracks not_allowed)
				(vias allowed)
				(pads allowed)
				(copperpour not_allowed)
				(footprints allowed)
			)
			(placement
				(enabled no)
				(sheetname "")
			)
			(fill
				(thermal_gap 0.5)
				(thermal_bridge_width 0.5)
				(island_removal_mode 0)
			)
			(polygon
				(pts
					(arc
						(start 341.559134 -47.450756)
						(mid 341.512619 -47.375014)
						(end 341.43696 -47.328328)
					)
					(arc
						(start 341.43696 -47.223172)
						(mid 341.584742 -47.302974)
						(end 341.664544 -47.450756)
					)
				)
			)
		)
		(zone
			(layer "F.Cu")
			(hatch none 0.5)
			(connect_pads
				(clearance 0)
			)
			(min_thickness 0.25)
			(keepout
				(tracks not_allowed)
				(vias allowed)
				(pads allowed)
				(copperpour not_allowed)
				(footprints allowed)
			)
			(placement
				(enabled no)
				(sheetname "")
			)
			(fill
				(thermal_gap 0.5)
				(thermal_bridge_width 0.5)
				(island_removal_mode 0)
			)
			(polygon
				(pts
					(arc
						(start 341.559134 -46.510956)
						(mid 341.512619 -46.435214)
						(end 341.43696 -46.388528)
					)
					(arc
						(start 341.43696 -46.283372)
						(mid 341.584742 -46.363174)
						(end 341.664544 -46.510956)
					)
				)
			)
		)
		(zone
			(layer "F.Cu")
			(hatch none 0.5)
			(connect_pads
				(clearance 0)
			)
			(min_thickness 0.25)
			(keepout
				(tracks not_allowed)
				(vias allowed)
				(pads allowed)
				(copperpour not_allowed)
				(footprints allowed)
			)
			(placement
				(enabled no)
				(sheetname "")
			)
			(fill
				(thermal_gap 0.5)
				(thermal_bridge_width 0.5)
				(island_removal_mode 0)
			)
			(polygon
				(pts
					(arc
						(start 341.559134 -45.571156)
						(mid 341.512619 -45.495414)
						(end 341.43696 -45.448728)
					)
					(arc
						(start 341.43696 -45.343572)
						(mid 341.584742 -45.423374)
						(end 341.664544 -45.571156)
					)
				)
			)
		)
		(zone
			(layer "F.Cu")
			(hatch none 0.5)
			(connect_pads
				(clearance 0)
			)
			(min_thickness 0.25)
			(keepout
				(tracks not_allowed)
				(vias allowed)
				(pads allowed)
				(copperpour not_allowed)
				(footprints allowed)
			)
			(placement
				(enabled no)
				(sheetname "")
			)
			(fill
				(thermal_gap 0.5)
				(thermal_bridge_width 0.5)
				(island_removal_mode 0)
			)
			(polygon
				(pts
					(arc
						(start 341.559134 -44.631356)
						(mid 341.512619 -44.555614)
						(end 341.43696 -44.508928)
					)
					(arc
						(start 341.43696 -44.403772)
						(mid 341.584742 -44.483574)
						(end 341.664544 -44.631356)
					)
				)
			)
		)
		(zone
			(layer "F.Cu")
			(hatch none 0.5)
			(connect_pads
				(clearance 0)
			)
			(min_thickness 0.25)
			(keepout
				(tracks not_allowed)
				(vias allowed)
				(pads allowed)
				(copperpour not_allowed)
				(footprints allowed)
			)
			(placement
				(enabled no)
				(sheetname "")
			)
			(fill
				(thermal_gap 0.5)
				(thermal_bridge_width 0.5)
				(island_removal_mode 0)
			)
			(polygon
				(pts
					(arc
						(start 341.559134 -43.691556)
						(mid 341.512619 -43.615814)
						(end 341.43696 -43.569128)
					)
					(arc
						(start 341.43696 -43.463972)
						(mid 341.584742 -43.543774)
						(end 341.664544 -43.691556)
					)
				)
			)
		)
		(zone
			(layer "F.Cu")
			(hatch none 0.5)
			(connect_pads
				(clearance 0)
			)
			(min_thickness 0.25)
			(keepout
				(tracks not_allowed)
				(vias allowed)
				(pads allowed)
				(copperpour not_allowed)
				(footprints allowed)
			)
			(placement
				(enabled no)
				(sheetname "")
			)
			(fill
				(thermal_gap 0.5)
				(thermal_bridge_width 0.5)
				(island_removal_mode 0)
			)
			(polygon
				(pts
					(arc
						(start 341.559134 -42.751756)
						(mid 341.512619 -42.676014)
						(end 341.43696 -42.629328)
					)
					(arc
						(start 341.43696 -42.524172)
						(mid 341.584742 -42.603974)
						(end 341.664544 -42.751756)
					)
				)
			)
		)
		(zone
			(layer "F.Cu")
			(hatch none 0.5)
			(connect_pads
				(clearance 0)
			)
			(min_thickness 0.25)
			(keepout
				(tracks not_allowed)
				(vias allowed)
				(pads allowed)
				(copperpour not_allowed)
				(footprints allowed)
			)
			(placement
				(enabled no)
				(sheetname "")
			)
			(fill
				(thermal_gap 0.5)
				(thermal_bridge_width 0.5)
				(island_removal_mode 0)
			)
			(polygon
				(pts
					(arc
						(start 341.559134 -41.811956)
						(mid 341.512619 -41.736214)
						(end 341.43696 -41.689528)
					)
					(arc
						(start 341.43696 -41.584372)
						(mid 341.584742 -41.664174)
						(end 341.664544 -41.811956)
					)
				)
			)
		)
		(zone
			(layer "F.Cu")
			(hatch none 0.5)
			(connect_pads
				(clearance 0)
			)
			(min_thickness 0.25)
			(keepout
				(tracks not_allowed)
				(vias allowed)
				(pads allowed)
				(copperpour not_allowed)
				(footprints allowed)
			)
			(placement
				(enabled no)
				(sheetname "")
			)
			(fill
				(thermal_gap 0.5)
				(thermal_bridge_width 0.5)
				(island_removal_mode 0)
			)
			(polygon
				(pts
					(arc
						(start 341.559134 -40.872156)
						(mid 341.512619 -40.796414)
						(end 341.43696 -40.749728)
					)
					(arc
						(start 341.43696 -40.644572)
						(mid 341.584742 -40.724374)
						(end 341.664544 -40.872156)
					)
				)
			)
		)
		(zone
			(layer "F.Cu")
			(hatch none 0.5)
			(connect_pads
				(clearance 0)
			)
			(min_thickness 0.25)
			(keepout
				(tracks not_allowed)
				(vias allowed)
				(pads allowed)
				(copperpour not_allowed)
				(footprints allowed)
			)
			(placement
				(enabled no)
				(sheetname "")
			)
			(fill
				(thermal_gap 0.5)
				(thermal_bridge_width 0.5)
				(island_removal_mode 0)
			)
			(polygon
				(pts
					(arc
						(start 341.559134 -39.932356)
						(mid 341.512619 -39.856614)
						(end 341.43696 -39.809928)
					)
					(arc
						(start 341.43696 -39.704772)
						(mid 341.584742 -39.784574)
						(end 341.664544 -39.932356)
					)
				)
			)
		)
		(zone
			(layer "F.Cu")
			(hatch none 0.5)
			(connect_pads
				(clearance 0)
			)
			(min_thickness 0.25)
			(keepout
				(tracks not_allowed)
				(vias allowed)
				(pads allowed)
				(copperpour not_allowed)
				(footprints allowed)
			)
			(placement
				(enabled no)
				(sheetname "")
			)
			(fill
				(thermal_gap 0.5)
				(thermal_bridge_width 0.5)
				(island_removal_mode 0)
			)
			(polygon
				(pts
					(arc
						(start 342.008968 -56.498236)
						(mid 342.055569 -56.574063)
						(end 342.131396 -56.620664)
					)
					(arc
						(start 342.131396 -56.72582)
						(mid 341.983614 -56.646018)
						(end 341.903812 -56.498236)
					)
				)
			)
		)
		(zone
			(layer "F.Cu")
			(hatch none 0.5)
			(connect_pads
				(clearance 0)
			)
			(min_thickness 0.25)
			(keepout
				(tracks not_allowed)
				(vias allowed)
				(pads allowed)
				(copperpour not_allowed)
				(footprints allowed)
			)
			(placement
				(enabled no)
				(sheetname "")
			)
			(fill
				(thermal_gap 0.5)
				(thermal_bridge_width 0.5)
				(island_removal_mode 0)
			)
			(polygon
				(pts
					(arc
						(start 342.008968 -55.558436)
						(mid 342.055569 -55.634263)
						(end 342.131396 -55.680864)
					)
					(arc
						(start 342.131396 -55.78602)
						(mid 341.983614 -55.706218)
						(end 341.903812 -55.558436)
					)
				)
			)
		)
		(zone
			(layer "F.Cu")
			(hatch none 0.5)
			(connect_pads
				(clearance 0)
			)
			(min_thickness 0.25)
			(keepout
				(tracks not_allowed)
				(vias allowed)
				(pads allowed)
				(copperpour not_allowed)
				(footprints allowed)
			)
			(placement
				(enabled no)
				(sheetname "")
			)
			(fill
				(thermal_gap 0.5)
				(thermal_bridge_width 0.5)
				(island_removal_mode 0)
			)
			(polygon
				(pts
					(arc
						(start 342.008968 -54.618636)
						(mid 342.055569 -54.694463)
						(end 342.131396 -54.741064)
					)
					(arc
						(start 342.131396 -54.84622)
						(mid 341.983614 -54.766418)
						(end 341.903812 -54.618636)
					)
				)
			)
		)
		(zone
			(layer "F.Cu")
			(hatch none 0.5)
			(connect_pads
				(clearance 0)
			)
			(min_thickness 0.25)
			(keepout
				(tracks not_allowed)
				(vias allowed)
				(pads allowed)
				(copperpour not_allowed)
				(footprints allowed)
			)
			(placement
				(enabled no)
				(sheetname "")
			)
			(fill
				(thermal_gap 0.5)
				(thermal_bridge_width 0.5)
				(island_removal_mode 0)
			)
			(polygon
				(pts
					(arc
						(start 342.008968 -53.678836)
						(mid 342.055569 -53.754663)
						(end 342.131396 -53.801264)
					)
					(arc
						(start 342.131396 -53.90642)
						(mid 341.983614 -53.826618)
						(end 341.903812 -53.678836)
					)
				)
			)
		)
		(zone
			(layer "F.Cu")
			(hatch none 0.5)
			(connect_pads
				(clearance 0)
			)
			(min_thickness 0.25)
			(keepout
				(tracks not_allowed)
				(vias allowed)
				(pads allowed)
				(copperpour not_allowed)
				(footprints allowed)
			)
			(placement
				(enabled no)
				(sheetname "")
			)
			(fill
				(thermal_gap 0.5)
				(thermal_bridge_width 0.5)
				(island_removal_mode 0)
			)
			(polygon
				(pts
					(arc
						(start 342.008968 -52.739036)
						(mid 342.055569 -52.814863)
						(end 342.131396 -52.861464)
					)
					(arc
						(start 342.131396 -52.96662)
						(mid 341.983614 -52.886818)
						(end 341.903812 -52.739036)
					)
				)
			)
		)
		(zone
			(layer "F.Cu")
			(hatch none 0.5)
			(connect_pads
				(clearance 0)
			)
			(min_thickness 0.25)
			(keepout
				(tracks not_allowed)
				(vias allowed)
				(pads allowed)
				(copperpour not_allowed)
				(footprints allowed)
			)
			(placement
				(enabled no)
				(sheetname "")
			)
			(fill
				(thermal_gap 0.5)
				(thermal_bridge_width 0.5)
				(island_removal_mode 0)
			)
			(polygon
				(pts
					(arc
						(start 342.008968 -51.799236)
						(mid 342.055569 -51.875063)
						(end 342.131396 -51.921664)
					)
					(arc
						(start 342.131396 -52.02682)
						(mid 341.983614 -51.947018)
						(end 341.903812 -51.799236)
					)
				)
			)
		)
		(zone
			(layer "F.Cu")
			(hatch none 0.5)
			(connect_pads
				(clearance 0)
			)
			(min_thickness 0.25)
			(keepout
				(tracks not_allowed)
				(vias allowed)
				(pads allowed)
				(copperpour not_allowed)
				(footprints allowed)
			)
			(placement
				(enabled no)
				(sheetname "")
			)
			(fill
				(thermal_gap 0.5)
				(thermal_bridge_width 0.5)
				(island_removal_mode 0)
			)
			(polygon
				(pts
					(arc
						(start 342.008968 -50.859436)
						(mid 342.055569 -50.935263)
						(end 342.131396 -50.981864)
					)
					(arc
						(start 342.131396 -51.08702)
						(mid 341.983614 -51.007218)
						(end 341.903812 -50.859436)
					)
				)
			)
		)
		(zone
			(layer "F.Cu")
			(hatch none 0.5)
			(connect_pads
				(clearance 0)
			)
			(min_thickness 0.25)
			(keepout
				(tracks not_allowed)
				(vias allowed)
				(pads allowed)
				(copperpour not_allowed)
				(footprints allowed)
			)
			(placement
				(enabled no)
				(sheetname "")
			)
			(fill
				(thermal_gap 0.5)
				(thermal_bridge_width 0.5)
				(island_removal_mode 0)
			)
			(polygon
				(pts
					(arc
						(start 342.008968 -49.919636)
						(mid 342.055569 -49.995463)
						(end 342.131396 -50.042064)
					)
					(arc
						(start 342.131396 -50.14722)
						(mid 341.983614 -50.067418)
						(end 341.903812 -49.919636)
					)
				)
			)
		)
		(zone
			(layer "F.Cu")
			(hatch none 0.5)
			(connect_pads
				(clearance 0)
			)
			(min_thickness 0.25)
			(keepout
				(tracks not_allowed)
				(vias allowed)
				(pads allowed)
				(copperpour not_allowed)
				(footprints allowed)
			)
			(placement
				(enabled no)
				(sheetname "")
			)
			(fill
				(thermal_gap 0.5)
				(thermal_bridge_width 0.5)
				(island_removal_mode 0)
			)
			(polygon
				(pts
					(arc
						(start 342.008968 -48.979836)
						(mid 342.055569 -49.055663)
						(end 342.131396 -49.102264)
					)
					(arc
						(start 342.131396 -49.20742)
						(mid 341.983614 -49.127618)
						(end 341.903812 -48.979836)
					)
				)
			)
		)
		(zone
			(layer "F.Cu")
			(hatch none 0.5)
			(connect_pads
				(clearance 0)
			)
			(min_thickness 0.25)
			(keepout
				(tracks not_allowed)
				(vias allowed)
				(pads allowed)
				(copperpour not_allowed)
				(footprints allowed)
			)
			(placement
				(enabled no)
				(sheetname "")
			)
			(fill
				(thermal_gap 0.5)
				(thermal_bridge_width 0.5)
				(island_removal_mode 0)
			)
			(polygon
				(pts
					(arc
						(start 342.008968 -48.040036)
						(mid 342.055569 -48.115863)
						(end 342.131396 -48.162464)
					)
					(arc
						(start 342.131396 -48.26762)
						(mid 341.983614 -48.187818)
						(end 341.903812 -48.040036)
					)
				)
			)
		)
		(zone
			(layer "F.Cu")
			(hatch none 0.5)
			(connect_pads
				(clearance 0)
			)
			(min_thickness 0.25)
			(keepout
				(tracks not_allowed)
				(vias allowed)
				(pads allowed)
				(copperpour not_allowed)
				(footprints allowed)
			)
			(placement
				(enabled no)
				(sheetname "")
			)
			(fill
				(thermal_gap 0.5)
				(thermal_bridge_width 0.5)
				(island_removal_mode 0)
			)
			(polygon
				(pts
					(arc
						(start 342.009222 -47.100236)
						(mid 342.055823 -47.176063)
						(end 342.13165 -47.222664)
					)
					(arc
						(start 342.13165 -47.32782)
						(mid 341.983868 -47.248018)
						(end 341.904066 -47.100236)
					)
				)
			)
		)
		(zone
			(layer "F.Cu")
			(hatch none 0.5)
			(connect_pads
				(clearance 0)
			)
			(min_thickness 0.25)
			(keepout
				(tracks not_allowed)
				(vias allowed)
				(pads allowed)
				(copperpour not_allowed)
				(footprints allowed)
			)
			(placement
				(enabled no)
				(sheetname "")
			)
			(fill
				(thermal_gap 0.5)
				(thermal_bridge_width 0.5)
				(island_removal_mode 0)
			)
			(polygon
				(pts
					(arc
						(start 342.009222 -46.160436)
						(mid 342.055823 -46.236263)
						(end 342.13165 -46.282864)
					)
					(arc
						(start 342.13165 -46.38802)
						(mid 341.983868 -46.308218)
						(end 341.904066 -46.160436)
					)
				)
			)
		)
		(zone
			(layer "F.Cu")
			(hatch none 0.5)
			(connect_pads
				(clearance 0)
			)
			(min_thickness 0.25)
			(keepout
				(tracks not_allowed)
				(vias allowed)
				(pads allowed)
				(copperpour not_allowed)
				(footprints allowed)
			)
			(placement
				(enabled no)
				(sheetname "")
			)
			(fill
				(thermal_gap 0.5)
				(thermal_bridge_width 0.5)
				(island_removal_mode 0)
			)
			(polygon
				(pts
					(arc
						(start 342.009222 -45.220636)
						(mid 342.055823 -45.296463)
						(end 342.13165 -45.343064)
					)
					(arc
						(start 342.13165 -45.44822)
						(mid 341.983868 -45.368418)
						(end 341.904066 -45.220636)
					)
				)
			)
		)
		(zone
			(layer "F.Cu")
			(hatch none 0.5)
			(connect_pads
				(clearance 0)
			)
			(min_thickness 0.25)
			(keepout
				(tracks not_allowed)
				(vias allowed)
				(pads allowed)
				(copperpour not_allowed)
				(footprints allowed)
			)
			(placement
				(enabled no)
				(sheetname "")
			)
			(fill
				(thermal_gap 0.5)
				(thermal_bridge_width 0.5)
				(island_removal_mode 0)
			)
			(polygon
				(pts
					(arc
						(start 342.009222 -44.280836)
						(mid 342.055823 -44.356663)
						(end 342.13165 -44.403264)
					)
					(arc
						(start 342.13165 -44.50842)
						(mid 341.983868 -44.428618)
						(end 341.904066 -44.280836)
					)
				)
			)
		)
		(zone
			(layer "F.Cu")
			(hatch none 0.5)
			(connect_pads
				(clearance 0)
			)
			(min_thickness 0.25)
			(keepout
				(tracks not_allowed)
				(vias allowed)
				(pads allowed)
				(copperpour not_allowed)
				(footprints allowed)
			)
			(placement
				(enabled no)
				(sheetname "")
			)
			(fill
				(thermal_gap 0.5)
				(thermal_bridge_width 0.5)
				(island_removal_mode 0)
			)
			(polygon
				(pts
					(arc
						(start 342.009222 -43.341036)
						(mid 342.055823 -43.416863)
						(end 342.13165 -43.463464)
					)
					(arc
						(start 342.13165 -43.56862)
						(mid 341.983868 -43.488818)
						(end 341.904066 -43.341036)
					)
				)
			)
		)
		(zone
			(layer "F.Cu")
			(hatch none 0.5)
			(connect_pads
				(clearance 0)
			)
			(min_thickness 0.25)
			(keepout
				(tracks not_allowed)
				(vias allowed)
				(pads allowed)
				(copperpour not_allowed)
				(footprints allowed)
			)
			(placement
				(enabled no)
				(sheetname "")
			)
			(fill
				(thermal_gap 0.5)
				(thermal_bridge_width 0.5)
				(island_removal_mode 0)
			)
			(polygon
				(pts
					(arc
						(start 342.009222 -42.401236)
						(mid 342.055823 -42.477063)
						(end 342.13165 -42.523664)
					)
					(arc
						(start 342.13165 -42.62882)
						(mid 341.983868 -42.549018)
						(end 341.904066 -42.401236)
					)
				)
			)
		)
		(zone
			(layer "F.Cu")
			(hatch none 0.5)
			(connect_pads
				(clearance 0)
			)
			(min_thickness 0.25)
			(keepout
				(tracks not_allowed)
				(vias allowed)
				(pads allowed)
				(copperpour not_allowed)
				(footprints allowed)
			)
			(placement
				(enabled no)
				(sheetname "")
			)
			(fill
				(thermal_gap 0.5)
				(thermal_bridge_width 0.5)
				(island_removal_mode 0)
			)
			(polygon
				(pts
					(arc
						(start 342.009222 -41.461436)
						(mid 342.055823 -41.537263)
						(end 342.13165 -41.583864)
					)
					(arc
						(start 342.13165 -41.68902)
						(mid 341.983868 -41.609218)
						(end 341.904066 -41.461436)
					)
				)
			)
		)
		(zone
			(layer "F.Cu")
			(hatch none 0.5)
			(connect_pads
				(clearance 0)
			)
			(min_thickness 0.25)
			(keepout
				(tracks not_allowed)
				(vias allowed)
				(pads allowed)
				(copperpour not_allowed)
				(footprints allowed)
			)
			(placement
				(enabled no)
				(sheetname "")
			)
			(fill
				(thermal_gap 0.5)
				(thermal_bridge_width 0.5)
				(island_removal_mode 0)
			)
			(polygon
				(pts
					(arc
						(start 342.009222 -40.521636)
						(mid 342.055823 -40.597463)
						(end 342.13165 -40.644064)
					)
					(arc
						(start 342.13165 -40.74922)
						(mid 341.983868 -40.669418)
						(end 341.904066 -40.521636)
					)
				)
			)
		)
		(zone
			(layer "F.Cu")
			(hatch none 0.5)
			(connect_pads
				(clearance 0)
			)
			(min_thickness 0.25)
			(keepout
				(tracks not_allowed)
				(vias allowed)
				(pads allowed)
				(copperpour not_allowed)
				(footprints allowed)
			)
			(placement
				(enabled no)
				(sheetname "")
			)
			(fill
				(thermal_gap 0.5)
				(thermal_bridge_width 0.5)
				(island_removal_mode 0)
			)
			(polygon
				(pts
					(arc
						(start 342.131396 -56.256428)
						(mid 342.055569 -56.303029)
						(end 342.008968 -56.378856)
					)
					(arc
						(start 341.903812 -56.378856)
						(mid 341.983614 -56.231074)
						(end 342.131396 -56.151272)
					)
				)
			)
		)
		(zone
			(layer "F.Cu")
			(hatch none 0.5)
			(connect_pads
				(clearance 0)
			)
			(min_thickness 0.25)
			(keepout
				(tracks not_allowed)
				(vias allowed)
				(pads allowed)
				(copperpour not_allowed)
				(footprints allowed)
			)
			(placement
				(enabled no)
				(sheetname "")
			)
			(fill
				(thermal_gap 0.5)
				(thermal_bridge_width 0.5)
				(island_removal_mode 0)
			)
			(polygon
				(pts
					(arc
						(start 342.131396 -55.316628)
						(mid 342.055569 -55.363229)
						(end 342.008968 -55.439056)
					)
					(arc
						(start 341.903812 -55.439056)
						(mid 341.983614 -55.291274)
						(end 342.131396 -55.211472)
					)
				)
			)
		)
		(zone
			(layer "F.Cu")
			(hatch none 0.5)
			(connect_pads
				(clearance 0)
			)
			(min_thickness 0.25)
			(keepout
				(tracks not_allowed)
				(vias allowed)
				(pads allowed)
				(copperpour not_allowed)
				(footprints allowed)
			)
			(placement
				(enabled no)
				(sheetname "")
			)
			(fill
				(thermal_gap 0.5)
				(thermal_bridge_width 0.5)
				(island_removal_mode 0)
			)
			(polygon
				(pts
					(arc
						(start 342.131396 -54.376828)
						(mid 342.055569 -54.423429)
						(end 342.008968 -54.499256)
					)
					(arc
						(start 341.903812 -54.499256)
						(mid 341.983614 -54.351474)
						(end 342.131396 -54.271672)
					)
				)
			)
		)
		(zone
			(layer "F.Cu")
			(hatch none 0.5)
			(connect_pads
				(clearance 0)
			)
			(min_thickness 0.25)
			(keepout
				(tracks not_allowed)
				(vias allowed)
				(pads allowed)
				(copperpour not_allowed)
				(footprints allowed)
			)
			(placement
				(enabled no)
				(sheetname "")
			)
			(fill
				(thermal_gap 0.5)
				(thermal_bridge_width 0.5)
				(island_removal_mode 0)
			)
			(polygon
				(pts
					(arc
						(start 342.131396 -53.437028)
						(mid 342.055569 -53.483629)
						(end 342.008968 -53.559456)
					)
					(arc
						(start 341.903812 -53.559456)
						(mid 341.983614 -53.411674)
						(end 342.131396 -53.331872)
					)
				)
			)
		)
		(zone
			(layer "F.Cu")
			(hatch none 0.5)
			(connect_pads
				(clearance 0)
			)
			(min_thickness 0.25)
			(keepout
				(tracks not_allowed)
				(vias allowed)
				(pads allowed)
				(copperpour not_allowed)
				(footprints allowed)
			)
			(placement
				(enabled no)
				(sheetname "")
			)
			(fill
				(thermal_gap 0.5)
				(thermal_bridge_width 0.5)
				(island_removal_mode 0)
			)
			(polygon
				(pts
					(arc
						(start 342.131396 -52.497228)
						(mid 342.055569 -52.543829)
						(end 342.008968 -52.619656)
					)
					(arc
						(start 341.903812 -52.619656)
						(mid 341.983614 -52.471874)
						(end 342.131396 -52.392072)
					)
				)
			)
		)
		(zone
			(layer "F.Cu")
			(hatch none 0.5)
			(connect_pads
				(clearance 0)
			)
			(min_thickness 0.25)
			(keepout
				(tracks not_allowed)
				(vias allowed)
				(pads allowed)
				(copperpour not_allowed)
				(footprints allowed)
			)
			(placement
				(enabled no)
				(sheetname "")
			)
			(fill
				(thermal_gap 0.5)
				(thermal_bridge_width 0.5)
				(island_removal_mode 0)
			)
			(polygon
				(pts
					(arc
						(start 342.131396 -51.557428)
						(mid 342.055569 -51.604029)
						(end 342.008968 -51.679856)
					)
					(arc
						(start 341.903812 -51.679856)
						(mid 341.983614 -51.532074)
						(end 342.131396 -51.452272)
					)
				)
			)
		)
		(zone
			(layer "F.Cu")
			(hatch none 0.5)
			(connect_pads
				(clearance 0)
			)
			(min_thickness 0.25)
			(keepout
				(tracks not_allowed)
				(vias allowed)
				(pads allowed)
				(copperpour not_allowed)
				(footprints allowed)
			)
			(placement
				(enabled no)
				(sheetname "")
			)
			(fill
				(thermal_gap 0.5)
				(thermal_bridge_width 0.5)
				(island_removal_mode 0)
			)
			(polygon
				(pts
					(arc
						(start 342.131396 -50.617628)
						(mid 342.055569 -50.664229)
						(end 342.008968 -50.740056)
					)
					(arc
						(start 341.903812 -50.740056)
						(mid 341.983614 -50.592274)
						(end 342.131396 -50.512472)
					)
				)
			)
		)
		(zone
			(layer "F.Cu")
			(hatch none 0.5)
			(connect_pads
				(clearance 0)
			)
			(min_thickness 0.25)
			(keepout
				(tracks not_allowed)
				(vias allowed)
				(pads allowed)
				(copperpour not_allowed)
				(footprints allowed)
			)
			(placement
				(enabled no)
				(sheetname "")
			)
			(fill
				(thermal_gap 0.5)
				(thermal_bridge_width 0.5)
				(island_removal_mode 0)
			)
			(polygon
				(pts
					(arc
						(start 342.131396 -49.677828)
						(mid 342.055569 -49.724429)
						(end 342.008968 -49.800256)
					)
					(arc
						(start 341.903812 -49.800256)
						(mid 341.983614 -49.652474)
						(end 342.131396 -49.572672)
					)
				)
			)
		)
		(zone
			(layer "F.Cu")
			(hatch none 0.5)
			(connect_pads
				(clearance 0)
			)
			(min_thickness 0.25)
			(keepout
				(tracks not_allowed)
				(vias allowed)
				(pads allowed)
				(copperpour not_allowed)
				(footprints allowed)
			)
			(placement
				(enabled no)
				(sheetname "")
			)
			(fill
				(thermal_gap 0.5)
				(thermal_bridge_width 0.5)
				(island_removal_mode 0)
			)
			(polygon
				(pts
					(arc
						(start 342.131396 -48.738028)
						(mid 342.055569 -48.784629)
						(end 342.008968 -48.860456)
					)
					(arc
						(start 341.903812 -48.860456)
						(mid 341.983614 -48.712674)
						(end 342.131396 -48.632872)
					)
				)
			)
		)
		(zone
			(layer "F.Cu")
			(hatch none 0.5)
			(connect_pads
				(clearance 0)
			)
			(min_thickness 0.25)
			(keepout
				(tracks not_allowed)
				(vias allowed)
				(pads allowed)
				(copperpour not_allowed)
				(footprints allowed)
			)
			(placement
				(enabled no)
				(sheetname "")
			)
			(fill
				(thermal_gap 0.5)
				(thermal_bridge_width 0.5)
				(island_removal_mode 0)
			)
			(polygon
				(pts
					(arc
						(start 342.131396 -47.798228)
						(mid 342.055569 -47.844829)
						(end 342.008968 -47.920656)
					)
					(arc
						(start 341.903812 -47.920656)
						(mid 341.983614 -47.772874)
						(end 342.131396 -47.693072)
					)
				)
			)
		)
		(zone
			(layer "F.Cu")
			(hatch none 0.5)
			(connect_pads
				(clearance 0)
			)
			(min_thickness 0.25)
			(keepout
				(tracks not_allowed)
				(vias allowed)
				(pads allowed)
				(copperpour not_allowed)
				(footprints allowed)
			)
			(placement
				(enabled no)
				(sheetname "")
			)
			(fill
				(thermal_gap 0.5)
				(thermal_bridge_width 0.5)
				(island_removal_mode 0)
			)
			(polygon
				(pts
					(arc
						(start 342.13165 -46.858428)
						(mid 342.055823 -46.905029)
						(end 342.009222 -46.980856)
					)
					(arc
						(start 341.904066 -46.980856)
						(mid 341.983868 -46.833074)
						(end 342.13165 -46.753272)
					)
				)
			)
		)
		(zone
			(layer "F.Cu")
			(hatch none 0.5)
			(connect_pads
				(clearance 0)
			)
			(min_thickness 0.25)
			(keepout
				(tracks not_allowed)
				(vias allowed)
				(pads allowed)
				(copperpour not_allowed)
				(footprints allowed)
			)
			(placement
				(enabled no)
				(sheetname "")
			)
			(fill
				(thermal_gap 0.5)
				(thermal_bridge_width 0.5)
				(island_removal_mode 0)
			)
			(polygon
				(pts
					(arc
						(start 342.13165 -45.918628)
						(mid 342.055823 -45.965229)
						(end 342.009222 -46.041056)
					)
					(arc
						(start 341.904066 -46.041056)
						(mid 341.983868 -45.893274)
						(end 342.13165 -45.813472)
					)
				)
			)
		)
		(zone
			(layer "F.Cu")
			(hatch none 0.5)
			(connect_pads
				(clearance 0)
			)
			(min_thickness 0.25)
			(keepout
				(tracks not_allowed)
				(vias allowed)
				(pads allowed)
				(copperpour not_allowed)
				(footprints allowed)
			)
			(placement
				(enabled no)
				(sheetname "")
			)
			(fill
				(thermal_gap 0.5)
				(thermal_bridge_width 0.5)
				(island_removal_mode 0)
			)
			(polygon
				(pts
					(arc
						(start 342.13165 -44.978828)
						(mid 342.055823 -45.025429)
						(end 342.009222 -45.101256)
					)
					(arc
						(start 341.904066 -45.101256)
						(mid 341.983868 -44.953474)
						(end 342.13165 -44.873672)
					)
				)
			)
		)
		(zone
			(layer "F.Cu")
			(hatch none 0.5)
			(connect_pads
				(clearance 0)
			)
			(min_thickness 0.25)
			(keepout
				(tracks not_allowed)
				(vias allowed)
				(pads allowed)
				(copperpour not_allowed)
				(footprints allowed)
			)
			(placement
				(enabled no)
				(sheetname "")
			)
			(fill
				(thermal_gap 0.5)
				(thermal_bridge_width 0.5)
				(island_removal_mode 0)
			)
			(polygon
				(pts
					(arc
						(start 342.13165 -44.039028)
						(mid 342.055823 -44.085629)
						(end 342.009222 -44.161456)
					)
					(arc
						(start 341.904066 -44.161456)
						(mid 341.983868 -44.013674)
						(end 342.13165 -43.933872)
					)
				)
			)
		)
		(zone
			(layer "F.Cu")
			(hatch none 0.5)
			(connect_pads
				(clearance 0)
			)
			(min_thickness 0.25)
			(keepout
				(tracks not_allowed)
				(vias allowed)
				(pads allowed)
				(copperpour not_allowed)
				(footprints allowed)
			)
			(placement
				(enabled no)
				(sheetname "")
			)
			(fill
				(thermal_gap 0.5)
				(thermal_bridge_width 0.5)
				(island_removal_mode 0)
			)
			(polygon
				(pts
					(arc
						(start 342.13165 -43.099228)
						(mid 342.055823 -43.145829)
						(end 342.009222 -43.221656)
					)
					(arc
						(start 341.904066 -43.221656)
						(mid 341.983868 -43.073874)
						(end 342.13165 -42.994072)
					)
				)
			)
		)
		(zone
			(layer "F.Cu")
			(hatch none 0.5)
			(connect_pads
				(clearance 0)
			)
			(min_thickness 0.25)
			(keepout
				(tracks not_allowed)
				(vias allowed)
				(pads allowed)
				(copperpour not_allowed)
				(footprints allowed)
			)
			(placement
				(enabled no)
				(sheetname "")
			)
			(fill
				(thermal_gap 0.5)
				(thermal_bridge_width 0.5)
				(island_removal_mode 0)
			)
			(polygon
				(pts
					(arc
						(start 342.13165 -42.159428)
						(mid 342.055823 -42.206029)
						(end 342.009222 -42.281856)
					)
					(arc
						(start 341.904066 -42.281856)
						(mid 341.983868 -42.134074)
						(end 342.13165 -42.054272)
					)
				)
			)
		)
		(zone
			(layer "F.Cu")
			(hatch none 0.5)
			(connect_pads
				(clearance 0)
			)
			(min_thickness 0.25)
			(keepout
				(tracks not_allowed)
				(vias allowed)
				(pads allowed)
				(copperpour not_allowed)
				(footprints allowed)
			)
			(placement
				(enabled no)
				(sheetname "")
			)
			(fill
				(thermal_gap 0.5)
				(thermal_bridge_width 0.5)
				(island_removal_mode 0)
			)
			(polygon
				(pts
					(arc
						(start 342.13165 -41.219628)
						(mid 342.055823 -41.266229)
						(end 342.009222 -41.342056)
					)
					(arc
						(start 341.904066 -41.342056)
						(mid 341.983868 -41.194274)
						(end 342.13165 -41.114472)
					)
				)
			)
		)
		(zone
			(layer "F.Cu")
			(hatch none 0.5)
			(connect_pads
				(clearance 0)
			)
			(min_thickness 0.25)
			(keepout
				(tracks not_allowed)
				(vias allowed)
				(pads allowed)
				(copperpour not_allowed)
				(footprints allowed)
			)
			(placement
				(enabled no)
				(sheetname "")
			)
			(fill
				(thermal_gap 0.5)
				(thermal_bridge_width 0.5)
				(island_removal_mode 0)
			)
			(polygon
				(pts
					(arc
						(start 342.13165 -40.279828)
						(mid 342.055823 -40.326429)
						(end 342.009222 -40.402256)
					)
					(arc
						(start 341.904066 -40.402256)
						(mid 341.983868 -40.254474)
						(end 342.13165 -40.174672)
					)
				)
			)
		)
		(zone
			(layer "F.Cu")
			(hatch none 0.5)
			(connect_pads
				(clearance 0)
			)
			(min_thickness 0.25)
			(keepout
				(tracks not_allowed)
				(vias allowed)
				(pads allowed)
				(copperpour not_allowed)
				(footprints allowed)
			)
			(placement
				(enabled no)
				(sheetname "")
			)
			(fill
				(thermal_gap 0.5)
				(thermal_bridge_width 0.5)
				(island_removal_mode 0)
			)
			(polygon
				(pts
					(arc
						(start 342.250776 -56.620664)
						(mid 342.326603 -56.574063)
						(end 342.373204 -56.498236)
					)
					(arc
						(start 342.47836 -56.498236)
						(mid 342.398558 -56.646018)
						(end 342.250776 -56.72582)
					)
				)
			)
		)
		(zone
			(layer "F.Cu")
			(hatch none 0.5)
			(connect_pads
				(clearance 0)
			)
			(min_thickness 0.25)
			(keepout
				(tracks not_allowed)
				(vias allowed)
				(pads allowed)
				(copperpour not_allowed)
				(footprints allowed)
			)
			(placement
				(enabled no)
				(sheetname "")
			)
			(fill
				(thermal_gap 0.5)
				(thermal_bridge_width 0.5)
				(island_removal_mode 0)
			)
			(polygon
				(pts
					(arc
						(start 342.250776 -55.680864)
						(mid 342.326603 -55.634263)
						(end 342.373204 -55.558436)
					)
					(arc
						(start 342.47836 -55.558436)
						(mid 342.398558 -55.706218)
						(end 342.250776 -55.78602)
					)
				)
			)
		)
		(zone
			(layer "F.Cu")
			(hatch none 0.5)
			(connect_pads
				(clearance 0)
			)
			(min_thickness 0.25)
			(keepout
				(tracks not_allowed)
				(vias allowed)
				(pads allowed)
				(copperpour not_allowed)
				(footprints allowed)
			)
			(placement
				(enabled no)
				(sheetname "")
			)
			(fill
				(thermal_gap 0.5)
				(thermal_bridge_width 0.5)
				(island_removal_mode 0)
			)
			(polygon
				(pts
					(arc
						(start 342.250776 -54.741064)
						(mid 342.326603 -54.694463)
						(end 342.373204 -54.618636)
					)
					(arc
						(start 342.47836 -54.618636)
						(mid 342.398558 -54.766418)
						(end 342.250776 -54.84622)
					)
				)
			)
		)
		(zone
			(layer "F.Cu")
			(hatch none 0.5)
			(connect_pads
				(clearance 0)
			)
			(min_thickness 0.25)
			(keepout
				(tracks not_allowed)
				(vias allowed)
				(pads allowed)
				(copperpour not_allowed)
				(footprints allowed)
			)
			(placement
				(enabled no)
				(sheetname "")
			)
			(fill
				(thermal_gap 0.5)
				(thermal_bridge_width 0.5)
				(island_removal_mode 0)
			)
			(polygon
				(pts
					(arc
						(start 342.250776 -53.801264)
						(mid 342.326603 -53.754663)
						(end 342.373204 -53.678836)
					)
					(arc
						(start 342.47836 -53.678836)
						(mid 342.398558 -53.826618)
						(end 342.250776 -53.90642)
					)
				)
			)
		)
		(zone
			(layer "F.Cu")
			(hatch none 0.5)
			(connect_pads
				(clearance 0)
			)
			(min_thickness 0.25)
			(keepout
				(tracks not_allowed)
				(vias allowed)
				(pads allowed)
				(copperpour not_allowed)
				(footprints allowed)
			)
			(placement
				(enabled no)
				(sheetname "")
			)
			(fill
				(thermal_gap 0.5)
				(thermal_bridge_width 0.5)
				(island_removal_mode 0)
			)
			(polygon
				(pts
					(arc
						(start 342.250776 -52.861464)
						(mid 342.326603 -52.814863)
						(end 342.373204 -52.739036)
					)
					(arc
						(start 342.47836 -52.739036)
						(mid 342.398558 -52.886818)
						(end 342.250776 -52.96662)
					)
				)
			)
		)
		(zone
			(layer "F.Cu")
			(hatch none 0.5)
			(connect_pads
				(clearance 0)
			)
			(min_thickness 0.25)
			(keepout
				(tracks not_allowed)
				(vias allowed)
				(pads allowed)
				(copperpour not_allowed)
				(footprints allowed)
			)
			(placement
				(enabled no)
				(sheetname "")
			)
			(fill
				(thermal_gap 0.5)
				(thermal_bridge_width 0.5)
				(island_removal_mode 0)
			)
			(polygon
				(pts
					(arc
						(start 342.250776 -51.921664)
						(mid 342.326603 -51.875063)
						(end 342.373204 -51.799236)
					)
					(arc
						(start 342.47836 -51.799236)
						(mid 342.398558 -51.947018)
						(end 342.250776 -52.02682)
					)
				)
			)
		)
		(zone
			(layer "F.Cu")
			(hatch none 0.5)
			(connect_pads
				(clearance 0)
			)
			(min_thickness 0.25)
			(keepout
				(tracks not_allowed)
				(vias allowed)
				(pads allowed)
				(copperpour not_allowed)
				(footprints allowed)
			)
			(placement
				(enabled no)
				(sheetname "")
			)
			(fill
				(thermal_gap 0.5)
				(thermal_bridge_width 0.5)
				(island_removal_mode 0)
			)
			(polygon
				(pts
					(arc
						(start 342.250776 -50.981864)
						(mid 342.326603 -50.935263)
						(end 342.373204 -50.859436)
					)
					(arc
						(start 342.47836 -50.859436)
						(mid 342.398558 -51.007218)
						(end 342.250776 -51.08702)
					)
				)
			)
		)
		(zone
			(layer "F.Cu")
			(hatch none 0.5)
			(connect_pads
				(clearance 0)
			)
			(min_thickness 0.25)
			(keepout
				(tracks not_allowed)
				(vias allowed)
				(pads allowed)
				(copperpour not_allowed)
				(footprints allowed)
			)
			(placement
				(enabled no)
				(sheetname "")
			)
			(fill
				(thermal_gap 0.5)
				(thermal_bridge_width 0.5)
				(island_removal_mode 0)
			)
			(polygon
				(pts
					(arc
						(start 342.250776 -50.042064)
						(mid 342.326603 -49.995463)
						(end 342.373204 -49.919636)
					)
					(arc
						(start 342.47836 -49.919636)
						(mid 342.398558 -50.067418)
						(end 342.250776 -50.14722)
					)
				)
			)
		)
		(zone
			(layer "F.Cu")
			(hatch none 0.5)
			(connect_pads
				(clearance 0)
			)
			(min_thickness 0.25)
			(keepout
				(tracks not_allowed)
				(vias allowed)
				(pads allowed)
				(copperpour not_allowed)
				(footprints allowed)
			)
			(placement
				(enabled no)
				(sheetname "")
			)
			(fill
				(thermal_gap 0.5)
				(thermal_bridge_width 0.5)
				(island_removal_mode 0)
			)
			(polygon
				(pts
					(arc
						(start 342.250776 -49.102264)
						(mid 342.326603 -49.055663)
						(end 342.373204 -48.979836)
					)
					(arc
						(start 342.47836 -48.979836)
						(mid 342.398558 -49.127618)
						(end 342.250776 -49.20742)
					)
				)
			)
		)
		(zone
			(layer "F.Cu")
			(hatch none 0.5)
			(connect_pads
				(clearance 0)
			)
			(min_thickness 0.25)
			(keepout
				(tracks not_allowed)
				(vias allowed)
				(pads allowed)
				(copperpour not_allowed)
				(footprints allowed)
			)
			(placement
				(enabled no)
				(sheetname "")
			)
			(fill
				(thermal_gap 0.5)
				(thermal_bridge_width 0.5)
				(island_removal_mode 0)
			)
			(polygon
				(pts
					(arc
						(start 342.250776 -48.162464)
						(mid 342.326603 -48.115863)
						(end 342.373204 -48.040036)
					)
					(arc
						(start 342.47836 -48.040036)
						(mid 342.398558 -48.187818)
						(end 342.250776 -48.26762)
					)
				)
			)
		)
		(zone
			(layer "F.Cu")
			(hatch none 0.5)
			(connect_pads
				(clearance 0)
			)
			(min_thickness 0.25)
			(keepout
				(tracks not_allowed)
				(vias allowed)
				(pads allowed)
				(copperpour not_allowed)
				(footprints allowed)
			)
			(placement
				(enabled no)
				(sheetname "")
			)
			(fill
				(thermal_gap 0.5)
				(thermal_bridge_width 0.5)
				(island_removal_mode 0)
			)
			(polygon
				(pts
					(arc
						(start 342.25103 -47.222664)
						(mid 342.326857 -47.176063)
						(end 342.373458 -47.100236)
					)
					(arc
						(start 342.478614 -47.100236)
						(mid 342.398812 -47.248018)
						(end 342.25103 -47.32782)
					)
				)
			)
		)
		(zone
			(layer "F.Cu")
			(hatch none 0.5)
			(connect_pads
				(clearance 0)
			)
			(min_thickness 0.25)
			(keepout
				(tracks not_allowed)
				(vias allowed)
				(pads allowed)
				(copperpour not_allowed)
				(footprints allowed)
			)
			(placement
				(enabled no)
				(sheetname "")
			)
			(fill
				(thermal_gap 0.5)
				(thermal_bridge_width 0.5)
				(island_removal_mode 0)
			)
			(polygon
				(pts
					(arc
						(start 342.25103 -46.282864)
						(mid 342.326857 -46.236263)
						(end 342.373458 -46.160436)
					)
					(arc
						(start 342.478614 -46.160436)
						(mid 342.398812 -46.308218)
						(end 342.25103 -46.38802)
					)
				)
			)
		)
		(zone
			(layer "F.Cu")
			(hatch none 0.5)
			(connect_pads
				(clearance 0)
			)
			(min_thickness 0.25)
			(keepout
				(tracks not_allowed)
				(vias allowed)
				(pads allowed)
				(copperpour not_allowed)
				(footprints allowed)
			)
			(placement
				(enabled no)
				(sheetname "")
			)
			(fill
				(thermal_gap 0.5)
				(thermal_bridge_width 0.5)
				(island_removal_mode 0)
			)
			(polygon
				(pts
					(arc
						(start 342.25103 -45.343064)
						(mid 342.326857 -45.296463)
						(end 342.373458 -45.220636)
					)
					(arc
						(start 342.478614 -45.220636)
						(mid 342.398812 -45.368418)
						(end 342.25103 -45.44822)
					)
				)
			)
		)
		(zone
			(layer "F.Cu")
			(hatch none 0.5)
			(connect_pads
				(clearance 0)
			)
			(min_thickness 0.25)
			(keepout
				(tracks not_allowed)
				(vias allowed)
				(pads allowed)
				(copperpour not_allowed)
				(footprints allowed)
			)
			(placement
				(enabled no)
				(sheetname "")
			)
			(fill
				(thermal_gap 0.5)
				(thermal_bridge_width 0.5)
				(island_removal_mode 0)
			)
			(polygon
				(pts
					(arc
						(start 342.25103 -44.403264)
						(mid 342.326857 -44.356663)
						(end 342.373458 -44.280836)
					)
					(arc
						(start 342.478614 -44.280836)
						(mid 342.398812 -44.428618)
						(end 342.25103 -44.50842)
					)
				)
			)
		)
		(zone
			(layer "F.Cu")
			(hatch none 0.5)
			(connect_pads
				(clearance 0)
			)
			(min_thickness 0.25)
			(keepout
				(tracks not_allowed)
				(vias allowed)
				(pads allowed)
				(copperpour not_allowed)
				(footprints allowed)
			)
			(placement
				(enabled no)
				(sheetname "")
			)
			(fill
				(thermal_gap 0.5)
				(thermal_bridge_width 0.5)
				(island_removal_mode 0)
			)
			(polygon
				(pts
					(arc
						(start 342.25103 -43.463464)
						(mid 342.326857 -43.416863)
						(end 342.373458 -43.341036)
					)
					(arc
						(start 342.478614 -43.341036)
						(mid 342.398812 -43.488818)
						(end 342.25103 -43.56862)
					)
				)
			)
		)
		(zone
			(layer "F.Cu")
			(hatch none 0.5)
			(connect_pads
				(clearance 0)
			)
			(min_thickness 0.25)
			(keepout
				(tracks not_allowed)
				(vias allowed)
				(pads allowed)
				(copperpour not_allowed)
				(footprints allowed)
			)
			(placement
				(enabled no)
				(sheetname "")
			)
			(fill
				(thermal_gap 0.5)
				(thermal_bridge_width 0.5)
				(island_removal_mode 0)
			)
			(polygon
				(pts
					(arc
						(start 342.25103 -42.523664)
						(mid 342.326857 -42.477063)
						(end 342.373458 -42.401236)
					)
					(arc
						(start 342.478614 -42.401236)
						(mid 342.398812 -42.549018)
						(end 342.25103 -42.62882)
					)
				)
			)
		)
		(zone
			(layer "F.Cu")
			(hatch none 0.5)
			(connect_pads
				(clearance 0)
			)
			(min_thickness 0.25)
			(keepout
				(tracks not_allowed)
				(vias allowed)
				(pads allowed)
				(copperpour not_allowed)
				(footprints allowed)
			)
			(placement
				(enabled no)
				(sheetname "")
			)
			(fill
				(thermal_gap 0.5)
				(thermal_bridge_width 0.5)
				(island_removal_mode 0)
			)
			(polygon
				(pts
					(arc
						(start 342.25103 -41.583864)
						(mid 342.326857 -41.537263)
						(end 342.373458 -41.461436)
					)
					(arc
						(start 342.478614 -41.461436)
						(mid 342.398812 -41.609218)
						(end 342.25103 -41.68902)
					)
				)
			)
		)
		(zone
			(layer "F.Cu")
			(hatch none 0.5)
			(connect_pads
				(clearance 0)
			)
			(min_thickness 0.25)
			(keepout
				(tracks not_allowed)
				(vias allowed)
				(pads allowed)
				(copperpour not_allowed)
				(footprints allowed)
			)
			(placement
				(enabled no)
				(sheetname "")
			)
			(fill
				(thermal_gap 0.5)
				(thermal_bridge_width 0.5)
				(island_removal_mode 0)
			)
			(polygon
				(pts
					(arc
						(start 342.25103 -40.644064)
						(mid 342.326857 -40.597463)
						(end 342.373458 -40.521636)
					)
					(arc
						(start 342.478614 -40.521636)
						(mid 342.398812 -40.669418)
						(end 342.25103 -40.74922)
					)
				)
			)
		)
		(zone
			(layer "F.Cu")
			(hatch none 0.5)
			(connect_pads
				(clearance 0)
			)
			(min_thickness 0.25)
			(keepout
				(tracks not_allowed)
				(vias allowed)
				(pads allowed)
				(copperpour not_allowed)
				(footprints allowed)
			)
			(placement
				(enabled no)
				(sheetname "")
			)
			(fill
				(thermal_gap 0.5)
				(thermal_bridge_width 0.5)
				(island_removal_mode 0)
			)
			(polygon
				(pts
					(arc
						(start 342.373204 -56.378856)
						(mid 342.326603 -56.303029)
						(end 342.250776 -56.256428)
					)
					(arc
						(start 342.250776 -56.151272)
						(mid 342.398558 -56.231074)
						(end 342.47836 -56.378856)
					)
				)
			)
		)
		(zone
			(layer "F.Cu")
			(hatch none 0.5)
			(connect_pads
				(clearance 0)
			)
			(min_thickness 0.25)
			(keepout
				(tracks not_allowed)
				(vias allowed)
				(pads allowed)
				(copperpour not_allowed)
				(footprints allowed)
			)
			(placement
				(enabled no)
				(sheetname "")
			)
			(fill
				(thermal_gap 0.5)
				(thermal_bridge_width 0.5)
				(island_removal_mode 0)
			)
			(polygon
				(pts
					(arc
						(start 342.373204 -55.439056)
						(mid 342.326603 -55.363229)
						(end 342.250776 -55.316628)
					)
					(arc
						(start 342.250776 -55.211472)
						(mid 342.398558 -55.291274)
						(end 342.47836 -55.439056)
					)
				)
			)
		)
		(zone
			(layer "F.Cu")
			(hatch none 0.5)
			(connect_pads
				(clearance 0)
			)
			(min_thickness 0.25)
			(keepout
				(tracks not_allowed)
				(vias allowed)
				(pads allowed)
				(copperpour not_allowed)
				(footprints allowed)
			)
			(placement
				(enabled no)
				(sheetname "")
			)
			(fill
				(thermal_gap 0.5)
				(thermal_bridge_width 0.5)
				(island_removal_mode 0)
			)
			(polygon
				(pts
					(arc
						(start 342.373204 -54.499256)
						(mid 342.326603 -54.423429)
						(end 342.250776 -54.376828)
					)
					(arc
						(start 342.250776 -54.271672)
						(mid 342.398558 -54.351474)
						(end 342.47836 -54.499256)
					)
				)
			)
		)
		(zone
			(layer "F.Cu")
			(hatch none 0.5)
			(connect_pads
				(clearance 0)
			)
			(min_thickness 0.25)
			(keepout
				(tracks not_allowed)
				(vias allowed)
				(pads allowed)
				(copperpour not_allowed)
				(footprints allowed)
			)
			(placement
				(enabled no)
				(sheetname "")
			)
			(fill
				(thermal_gap 0.5)
				(thermal_bridge_width 0.5)
				(island_removal_mode 0)
			)
			(polygon
				(pts
					(arc
						(start 342.373204 -53.559456)
						(mid 342.326603 -53.483629)
						(end 342.250776 -53.437028)
					)
					(arc
						(start 342.250776 -53.331872)
						(mid 342.398558 -53.411674)
						(end 342.47836 -53.559456)
					)
				)
			)
		)
		(zone
			(layer "F.Cu")
			(hatch none 0.5)
			(connect_pads
				(clearance 0)
			)
			(min_thickness 0.25)
			(keepout
				(tracks not_allowed)
				(vias allowed)
				(pads allowed)
				(copperpour not_allowed)
				(footprints allowed)
			)
			(placement
				(enabled no)
				(sheetname "")
			)
			(fill
				(thermal_gap 0.5)
				(thermal_bridge_width 0.5)
				(island_removal_mode 0)
			)
			(polygon
				(pts
					(arc
						(start 342.373204 -52.619656)
						(mid 342.326603 -52.543829)
						(end 342.250776 -52.497228)
					)
					(arc
						(start 342.250776 -52.392072)
						(mid 342.398558 -52.471874)
						(end 342.47836 -52.619656)
					)
				)
			)
		)
		(zone
			(layer "F.Cu")
			(hatch none 0.5)
			(connect_pads
				(clearance 0)
			)
			(min_thickness 0.25)
			(keepout
				(tracks not_allowed)
				(vias allowed)
				(pads allowed)
				(copperpour not_allowed)
				(footprints allowed)
			)
			(placement
				(enabled no)
				(sheetname "")
			)
			(fill
				(thermal_gap 0.5)
				(thermal_bridge_width 0.5)
				(island_removal_mode 0)
			)
			(polygon
				(pts
					(arc
						(start 342.373204 -51.679856)
						(mid 342.326603 -51.604029)
						(end 342.250776 -51.557428)
					)
					(arc
						(start 342.250776 -51.452272)
						(mid 342.398558 -51.532074)
						(end 342.47836 -51.679856)
					)
				)
			)
		)
		(zone
			(layer "F.Cu")
			(hatch none 0.5)
			(connect_pads
				(clearance 0)
			)
			(min_thickness 0.25)
			(keepout
				(tracks not_allowed)
				(vias allowed)
				(pads allowed)
				(copperpour not_allowed)
				(footprints allowed)
			)
			(placement
				(enabled no)
				(sheetname "")
			)
			(fill
				(thermal_gap 0.5)
				(thermal_bridge_width 0.5)
				(island_removal_mode 0)
			)
			(polygon
				(pts
					(arc
						(start 342.373204 -50.740056)
						(mid 342.326603 -50.664229)
						(end 342.250776 -50.617628)
					)
					(arc
						(start 342.250776 -50.512472)
						(mid 342.398558 -50.592274)
						(end 342.47836 -50.740056)
					)
				)
			)
		)
		(zone
			(layer "F.Cu")
			(hatch none 0.5)
			(connect_pads
				(clearance 0)
			)
			(min_thickness 0.25)
			(keepout
				(tracks not_allowed)
				(vias allowed)
				(pads allowed)
				(copperpour not_allowed)
				(footprints allowed)
			)
			(placement
				(enabled no)
				(sheetname "")
			)
			(fill
				(thermal_gap 0.5)
				(thermal_bridge_width 0.5)
				(island_removal_mode 0)
			)
			(polygon
				(pts
					(arc
						(start 342.373204 -49.800256)
						(mid 342.326603 -49.724429)
						(end 342.250776 -49.677828)
					)
					(arc
						(start 342.250776 -49.572672)
						(mid 342.398558 -49.652474)
						(end 342.47836 -49.800256)
					)
				)
			)
		)
		(zone
			(layer "F.Cu")
			(hatch none 0.5)
			(connect_pads
				(clearance 0)
			)
			(min_thickness 0.25)
			(keepout
				(tracks not_allowed)
				(vias allowed)
				(pads allowed)
				(copperpour not_allowed)
				(footprints allowed)
			)
			(placement
				(enabled no)
				(sheetname "")
			)
			(fill
				(thermal_gap 0.5)
				(thermal_bridge_width 0.5)
				(island_removal_mode 0)
			)
			(polygon
				(pts
					(arc
						(start 342.373204 -48.860456)
						(mid 342.326603 -48.784629)
						(end 342.250776 -48.738028)
					)
					(arc
						(start 342.250776 -48.632872)
						(mid 342.398558 -48.712674)
						(end 342.47836 -48.860456)
					)
				)
			)
		)
		(zone
			(layer "F.Cu")
			(hatch none 0.5)
			(connect_pads
				(clearance 0)
			)
			(min_thickness 0.25)
			(keepout
				(tracks not_allowed)
				(vias allowed)
				(pads allowed)
				(copperpour not_allowed)
				(footprints allowed)
			)
			(placement
				(enabled no)
				(sheetname "")
			)
			(fill
				(thermal_gap 0.5)
				(thermal_bridge_width 0.5)
				(island_removal_mode 0)
			)
			(polygon
				(pts
					(arc
						(start 342.373204 -47.920656)
						(mid 342.326603 -47.844829)
						(end 342.250776 -47.798228)
					)
					(arc
						(start 342.250776 -47.693072)
						(mid 342.398558 -47.772874)
						(end 342.47836 -47.920656)
					)
				)
			)
		)
		(zone
			(layer "F.Cu")
			(hatch none 0.5)
			(connect_pads
				(clearance 0)
			)
			(min_thickness 0.25)
			(keepout
				(tracks not_allowed)
				(vias allowed)
				(pads allowed)
				(copperpour not_allowed)
				(footprints allowed)
			)
			(placement
				(enabled no)
				(sheetname "")
			)
			(fill
				(thermal_gap 0.5)
				(thermal_bridge_width 0.5)
				(island_removal_mode 0)
			)
			(polygon
				(pts
					(arc
						(start 342.373458 -46.980856)
						(mid 342.326857 -46.905029)
						(end 342.25103 -46.858428)
					)
					(arc
						(start 342.25103 -46.753272)
						(mid 342.398812 -46.833074)
						(end 342.478614 -46.980856)
					)
				)
			)
		)
		(zone
			(layer "F.Cu")
			(hatch none 0.5)
			(connect_pads
				(clearance 0)
			)
			(min_thickness 0.25)
			(keepout
				(tracks not_allowed)
				(vias allowed)
				(pads allowed)
				(copperpour not_allowed)
				(footprints allowed)
			)
			(placement
				(enabled no)
				(sheetname "")
			)
			(fill
				(thermal_gap 0.5)
				(thermal_bridge_width 0.5)
				(island_removal_mode 0)
			)
			(polygon
				(pts
					(arc
						(start 342.373458 -46.041056)
						(mid 342.326857 -45.965229)
						(end 342.25103 -45.918628)
					)
					(arc
						(start 342.25103 -45.813472)
						(mid 342.398812 -45.893274)
						(end 342.478614 -46.041056)
					)
				)
			)
		)
		(zone
			(layer "F.Cu")
			(hatch none 0.5)
			(connect_pads
				(clearance 0)
			)
			(min_thickness 0.25)
			(keepout
				(tracks not_allowed)
				(vias allowed)
				(pads allowed)
				(copperpour not_allowed)
				(footprints allowed)
			)
			(placement
				(enabled no)
				(sheetname "")
			)
			(fill
				(thermal_gap 0.5)
				(thermal_bridge_width 0.5)
				(island_removal_mode 0)
			)
			(polygon
				(pts
					(arc
						(start 342.373458 -45.101256)
						(mid 342.326857 -45.025429)
						(end 342.25103 -44.978828)
					)
					(arc
						(start 342.25103 -44.873672)
						(mid 342.398812 -44.953474)
						(end 342.478614 -45.101256)
					)
				)
			)
		)
		(zone
			(layer "F.Cu")
			(hatch none 0.5)
			(connect_pads
				(clearance 0)
			)
			(min_thickness 0.25)
			(keepout
				(tracks not_allowed)
				(vias allowed)
				(pads allowed)
				(copperpour not_allowed)
				(footprints allowed)
			)
			(placement
				(enabled no)
				(sheetname "")
			)
			(fill
				(thermal_gap 0.5)
				(thermal_bridge_width 0.5)
				(island_removal_mode 0)
			)
			(polygon
				(pts
					(arc
						(start 342.373458 -44.161456)
						(mid 342.326857 -44.085629)
						(end 342.25103 -44.039028)
					)
					(arc
						(start 342.25103 -43.933872)
						(mid 342.398812 -44.013674)
						(end 342.478614 -44.161456)
					)
				)
			)
		)
		(zone
			(layer "F.Cu")
			(hatch none 0.5)
			(connect_pads
				(clearance 0)
			)
			(min_thickness 0.25)
			(keepout
				(tracks not_allowed)
				(vias allowed)
				(pads allowed)
				(copperpour not_allowed)
				(footprints allowed)
			)
			(placement
				(enabled no)
				(sheetname "")
			)
			(fill
				(thermal_gap 0.5)
				(thermal_bridge_width 0.5)
				(island_removal_mode 0)
			)
			(polygon
				(pts
					(arc
						(start 342.373458 -43.221656)
						(mid 342.326857 -43.145829)
						(end 342.25103 -43.099228)
					)
					(arc
						(start 342.25103 -42.994072)
						(mid 342.398812 -43.073874)
						(end 342.478614 -43.221656)
					)
				)
			)
		)
		(zone
			(layer "F.Cu")
			(hatch none 0.5)
			(connect_pads
				(clearance 0)
			)
			(min_thickness 0.25)
			(keepout
				(tracks not_allowed)
				(vias allowed)
				(pads allowed)
				(copperpour not_allowed)
				(footprints allowed)
			)
			(placement
				(enabled no)
				(sheetname "")
			)
			(fill
				(thermal_gap 0.5)
				(thermal_bridge_width 0.5)
				(island_removal_mode 0)
			)
			(polygon
				(pts
					(arc
						(start 342.373458 -42.281856)
						(mid 342.326857 -42.206029)
						(end 342.25103 -42.159428)
					)
					(arc
						(start 342.25103 -42.054272)
						(mid 342.398812 -42.134074)
						(end 342.478614 -42.281856)
					)
				)
			)
		)
		(zone
			(layer "F.Cu")
			(hatch none 0.5)
			(connect_pads
				(clearance 0)
			)
			(min_thickness 0.25)
			(keepout
				(tracks not_allowed)
				(vias allowed)
				(pads allowed)
				(copperpour not_allowed)
				(footprints allowed)
			)
			(placement
				(enabled no)
				(sheetname "")
			)
			(fill
				(thermal_gap 0.5)
				(thermal_bridge_width 0.5)
				(island_removal_mode 0)
			)
			(polygon
				(pts
					(arc
						(start 342.373458 -41.342056)
						(mid 342.326857 -41.266229)
						(end 342.25103 -41.219628)
					)
					(arc
						(start 342.25103 -41.114472)
						(mid 342.398812 -41.194274)
						(end 342.478614 -41.342056)
					)
				)
			)
		)
		(zone
			(layer "F.Cu")
			(hatch none 0.5)
			(connect_pads
				(clearance 0)
			)
			(min_thickness 0.25)
			(keepout
				(tracks not_allowed)
				(vias allowed)
				(pads allowed)
				(copperpour not_allowed)
				(footprints allowed)
			)
			(placement
				(enabled no)
				(sheetname "")
			)
			(fill
				(thermal_gap 0.5)
				(thermal_bridge_width 0.5)
				(island_removal_mode 0)
			)
			(polygon
				(pts
					(arc
						(start 342.373458 -40.402256)
						(mid 342.326857 -40.326429)
						(end 342.25103 -40.279828)
					)
					(arc
						(start 342.25103 -40.174672)
						(mid 342.398812 -40.254474)
						(end 342.478614 -40.402256)
					)
				)
			)
		)
		(zone
			(layer "F.Cu")
			(hatch none 0.5)
			(connect_pads
				(clearance 0)
			)
			(min_thickness 0.25)
			(keepout
				(tracks not_allowed)
				(vias allowed)
				(pads allowed)
				(copperpour not_allowed)
				(footprints allowed)
			)
			(placement
				(enabled no)
				(sheetname "")
			)
			(fill
				(thermal_gap 0.5)
				(thermal_bridge_width 0.5)
				(island_removal_mode 0)
			)
			(polygon
				(pts
					(arc
						(start 342.823038 -56.968136)
						(mid 342.869639 -57.043963)
						(end 342.945466 -57.090564)
					)
					(arc
						(start 342.945466 -57.19572)
						(mid 342.797684 -57.115918)
						(end 342.717882 -56.968136)
					)
				)
			)
		)
		(zone
			(layer "F.Cu")
			(hatch none 0.5)
			(connect_pads
				(clearance 0)
			)
			(min_thickness 0.25)
			(keepout
				(tracks not_allowed)
				(vias allowed)
				(pads allowed)
				(copperpour not_allowed)
				(footprints allowed)
			)
			(placement
				(enabled no)
				(sheetname "")
			)
			(fill
				(thermal_gap 0.5)
				(thermal_bridge_width 0.5)
				(island_removal_mode 0)
			)
			(polygon
				(pts
					(arc
						(start 342.823038 -56.028336)
						(mid 342.869639 -56.104163)
						(end 342.945466 -56.150764)
					)
					(arc
						(start 342.945466 -56.25592)
						(mid 342.797684 -56.176118)
						(end 342.717882 -56.028336)
					)
				)
			)
		)
		(zone
			(layer "F.Cu")
			(hatch none 0.5)
			(connect_pads
				(clearance 0)
			)
			(min_thickness 0.25)
			(keepout
				(tracks not_allowed)
				(vias allowed)
				(pads allowed)
				(copperpour not_allowed)
				(footprints allowed)
			)
			(placement
				(enabled no)
				(sheetname "")
			)
			(fill
				(thermal_gap 0.5)
				(thermal_bridge_width 0.5)
				(island_removal_mode 0)
			)
			(polygon
				(pts
					(arc
						(start 342.823038 -55.088536)
						(mid 342.869639 -55.164363)
						(end 342.945466 -55.210964)
					)
					(arc
						(start 342.945466 -55.31612)
						(mid 342.797684 -55.236318)
						(end 342.717882 -55.088536)
					)
				)
			)
		)
		(zone
			(layer "F.Cu")
			(hatch none 0.5)
			(connect_pads
				(clearance 0)
			)
			(min_thickness 0.25)
			(keepout
				(tracks not_allowed)
				(vias allowed)
				(pads allowed)
				(copperpour not_allowed)
				(footprints allowed)
			)
			(placement
				(enabled no)
				(sheetname "")
			)
			(fill
				(thermal_gap 0.5)
				(thermal_bridge_width 0.5)
				(island_removal_mode 0)
			)
			(polygon
				(pts
					(arc
						(start 342.823038 -54.148736)
						(mid 342.869639 -54.224563)
						(end 342.945466 -54.271164)
					)
					(arc
						(start 342.945466 -54.37632)
						(mid 342.797684 -54.296518)
						(end 342.717882 -54.148736)
					)
				)
			)
		)
		(zone
			(layer "F.Cu")
			(hatch none 0.5)
			(connect_pads
				(clearance 0)
			)
			(min_thickness 0.25)
			(keepout
				(tracks not_allowed)
				(vias allowed)
				(pads allowed)
				(copperpour not_allowed)
				(footprints allowed)
			)
			(placement
				(enabled no)
				(sheetname "")
			)
			(fill
				(thermal_gap 0.5)
				(thermal_bridge_width 0.5)
				(island_removal_mode 0)
			)
			(polygon
				(pts
					(arc
						(start 342.823038 -53.208936)
						(mid 342.869639 -53.284763)
						(end 342.945466 -53.331364)
					)
					(arc
						(start 342.945466 -53.43652)
						(mid 342.797684 -53.356718)
						(end 342.717882 -53.208936)
					)
				)
			)
		)
		(zone
			(layer "F.Cu")
			(hatch none 0.5)
			(connect_pads
				(clearance 0)
			)
			(min_thickness 0.25)
			(keepout
				(tracks not_allowed)
				(vias allowed)
				(pads allowed)
				(copperpour not_allowed)
				(footprints allowed)
			)
			(placement
				(enabled no)
				(sheetname "")
			)
			(fill
				(thermal_gap 0.5)
				(thermal_bridge_width 0.5)
				(island_removal_mode 0)
			)
			(polygon
				(pts
					(arc
						(start 342.823038 -52.269136)
						(mid 342.869639 -52.344963)
						(end 342.945466 -52.391564)
					)
					(arc
						(start 342.945466 -52.49672)
						(mid 342.797684 -52.416918)
						(end 342.717882 -52.269136)
					)
				)
			)
		)
		(zone
			(layer "F.Cu")
			(hatch none 0.5)
			(connect_pads
				(clearance 0)
			)
			(min_thickness 0.25)
			(keepout
				(tracks not_allowed)
				(vias allowed)
				(pads allowed)
				(copperpour not_allowed)
				(footprints allowed)
			)
			(placement
				(enabled no)
				(sheetname "")
			)
			(fill
				(thermal_gap 0.5)
				(thermal_bridge_width 0.5)
				(island_removal_mode 0)
			)
			(polygon
				(pts
					(arc
						(start 342.823038 -51.329336)
						(mid 342.869639 -51.405163)
						(end 342.945466 -51.451764)
					)
					(arc
						(start 342.945466 -51.55692)
						(mid 342.797684 -51.477118)
						(end 342.717882 -51.329336)
					)
				)
			)
		)
		(zone
			(layer "F.Cu")
			(hatch none 0.5)
			(connect_pads
				(clearance 0)
			)
			(min_thickness 0.25)
			(keepout
				(tracks not_allowed)
				(vias allowed)
				(pads allowed)
				(copperpour not_allowed)
				(footprints allowed)
			)
			(placement
				(enabled no)
				(sheetname "")
			)
			(fill
				(thermal_gap 0.5)
				(thermal_bridge_width 0.5)
				(island_removal_mode 0)
			)
			(polygon
				(pts
					(arc
						(start 342.823038 -50.389536)
						(mid 342.869639 -50.465363)
						(end 342.945466 -50.511964)
					)
					(arc
						(start 342.945466 -50.61712)
						(mid 342.797684 -50.537318)
						(end 342.717882 -50.389536)
					)
				)
			)
		)
		(zone
			(layer "F.Cu")
			(hatch none 0.5)
			(connect_pads
				(clearance 0)
			)
			(min_thickness 0.25)
			(keepout
				(tracks not_allowed)
				(vias allowed)
				(pads allowed)
				(copperpour not_allowed)
				(footprints allowed)
			)
			(placement
				(enabled no)
				(sheetname "")
			)
			(fill
				(thermal_gap 0.5)
				(thermal_bridge_width 0.5)
				(island_removal_mode 0)
			)
			(polygon
				(pts
					(arc
						(start 342.823038 -49.449736)
						(mid 342.869639 -49.525563)
						(end 342.945466 -49.572164)
					)
					(arc
						(start 342.945466 -49.67732)
						(mid 342.797684 -49.597518)
						(end 342.717882 -49.449736)
					)
				)
			)
		)
		(zone
			(layer "F.Cu")
			(hatch none 0.5)
			(connect_pads
				(clearance 0)
			)
			(min_thickness 0.25)
			(keepout
				(tracks not_allowed)
				(vias allowed)
				(pads allowed)
				(copperpour not_allowed)
				(footprints allowed)
			)
			(placement
				(enabled no)
				(sheetname "")
			)
			(fill
				(thermal_gap 0.5)
				(thermal_bridge_width 0.5)
				(island_removal_mode 0)
			)
			(polygon
				(pts
					(arc
						(start 342.823038 -48.509936)
						(mid 342.869639 -48.585763)
						(end 342.945466 -48.632364)
					)
					(arc
						(start 342.945466 -48.73752)
						(mid 342.797684 -48.657718)
						(end 342.717882 -48.509936)
					)
				)
			)
		)
		(zone
			(layer "F.Cu")
			(hatch none 0.5)
			(connect_pads
				(clearance 0)
			)
			(min_thickness 0.25)
			(keepout
				(tracks not_allowed)
				(vias allowed)
				(pads allowed)
				(copperpour not_allowed)
				(footprints allowed)
			)
			(placement
				(enabled no)
				(sheetname "")
			)
			(fill
				(thermal_gap 0.5)
				(thermal_bridge_width 0.5)
				(island_removal_mode 0)
			)
			(polygon
				(pts
					(arc
						(start 342.823038 -47.570136)
						(mid 342.869639 -47.645963)
						(end 342.945466 -47.692564)
					)
					(arc
						(start 342.945466 -47.79772)
						(mid 342.797684 -47.717918)
						(end 342.717882 -47.570136)
					)
				)
			)
		)
		(zone
			(layer "F.Cu")
			(hatch none 0.5)
			(connect_pads
				(clearance 0)
			)
			(min_thickness 0.25)
			(keepout
				(tracks not_allowed)
				(vias allowed)
				(pads allowed)
				(copperpour not_allowed)
				(footprints allowed)
			)
			(placement
				(enabled no)
				(sheetname "")
			)
			(fill
				(thermal_gap 0.5)
				(thermal_bridge_width 0.5)
				(island_removal_mode 0)
			)
			(polygon
				(pts
					(arc
						(start 342.823038 -46.630336)
						(mid 342.869639 -46.706163)
						(end 342.945466 -46.752764)
					)
					(arc
						(start 342.945466 -46.85792)
						(mid 342.797684 -46.778118)
						(end 342.717882 -46.630336)
					)
				)
			)
		)
		(zone
			(layer "F.Cu")
			(hatch none 0.5)
			(connect_pads
				(clearance 0)
			)
			(min_thickness 0.25)
			(keepout
				(tracks not_allowed)
				(vias allowed)
				(pads allowed)
				(copperpour not_allowed)
				(footprints allowed)
			)
			(placement
				(enabled no)
				(sheetname "")
			)
			(fill
				(thermal_gap 0.5)
				(thermal_bridge_width 0.5)
				(island_removal_mode 0)
			)
			(polygon
				(pts
					(arc
						(start 342.823038 -45.690536)
						(mid 342.869639 -45.766363)
						(end 342.945466 -45.812964)
					)
					(arc
						(start 342.945466 -45.91812)
						(mid 342.797684 -45.838318)
						(end 342.717882 -45.690536)
					)
				)
			)
		)
		(zone
			(layer "F.Cu")
			(hatch none 0.5)
			(connect_pads
				(clearance 0)
			)
			(min_thickness 0.25)
			(keepout
				(tracks not_allowed)
				(vias allowed)
				(pads allowed)
				(copperpour not_allowed)
				(footprints allowed)
			)
			(placement
				(enabled no)
				(sheetname "")
			)
			(fill
				(thermal_gap 0.5)
				(thermal_bridge_width 0.5)
				(island_removal_mode 0)
			)
			(polygon
				(pts
					(arc
						(start 342.823038 -44.750736)
						(mid 342.869639 -44.826563)
						(end 342.945466 -44.873164)
					)
					(arc
						(start 342.945466 -44.97832)
						(mid 342.797684 -44.898518)
						(end 342.717882 -44.750736)
					)
				)
			)
		)
		(zone
			(layer "F.Cu")
			(hatch none 0.5)
			(connect_pads
				(clearance 0)
			)
			(min_thickness 0.25)
			(keepout
				(tracks not_allowed)
				(vias allowed)
				(pads allowed)
				(copperpour not_allowed)
				(footprints allowed)
			)
			(placement
				(enabled no)
				(sheetname "")
			)
			(fill
				(thermal_gap 0.5)
				(thermal_bridge_width 0.5)
				(island_removal_mode 0)
			)
			(polygon
				(pts
					(arc
						(start 342.823038 -43.810936)
						(mid 342.869639 -43.886763)
						(end 342.945466 -43.933364)
					)
					(arc
						(start 342.945466 -44.03852)
						(mid 342.797684 -43.958718)
						(end 342.717882 -43.810936)
					)
				)
			)
		)
		(zone
			(layer "F.Cu")
			(hatch none 0.5)
			(connect_pads
				(clearance 0)
			)
			(min_thickness 0.25)
			(keepout
				(tracks not_allowed)
				(vias allowed)
				(pads allowed)
				(copperpour not_allowed)
				(footprints allowed)
			)
			(placement
				(enabled no)
				(sheetname "")
			)
			(fill
				(thermal_gap 0.5)
				(thermal_bridge_width 0.5)
				(island_removal_mode 0)
			)
			(polygon
				(pts
					(arc
						(start 342.823038 -42.871136)
						(mid 342.869639 -42.946963)
						(end 342.945466 -42.993564)
					)
					(arc
						(start 342.945466 -43.09872)
						(mid 342.797684 -43.018918)
						(end 342.717882 -42.871136)
					)
				)
			)
		)
		(zone
			(layer "F.Cu")
			(hatch none 0.5)
			(connect_pads
				(clearance 0)
			)
			(min_thickness 0.25)
			(keepout
				(tracks not_allowed)
				(vias allowed)
				(pads allowed)
				(copperpour not_allowed)
				(footprints allowed)
			)
			(placement
				(enabled no)
				(sheetname "")
			)
			(fill
				(thermal_gap 0.5)
				(thermal_bridge_width 0.5)
				(island_removal_mode 0)
			)
			(polygon
				(pts
					(arc
						(start 342.823038 -41.931336)
						(mid 342.869639 -42.007163)
						(end 342.945466 -42.053764)
					)
					(arc
						(start 342.945466 -42.15892)
						(mid 342.797684 -42.079118)
						(end 342.717882 -41.931336)
					)
				)
			)
		)
		(zone
			(layer "F.Cu")
			(hatch none 0.5)
			(connect_pads
				(clearance 0)
			)
			(min_thickness 0.25)
			(keepout
				(tracks not_allowed)
				(vias allowed)
				(pads allowed)
				(copperpour not_allowed)
				(footprints allowed)
			)
			(placement
				(enabled no)
				(sheetname "")
			)
			(fill
				(thermal_gap 0.5)
				(thermal_bridge_width 0.5)
				(island_removal_mode 0)
			)
			(polygon
				(pts
					(arc
						(start 342.823038 -40.991536)
						(mid 342.869639 -41.067363)
						(end 342.945466 -41.113964)
					)
					(arc
						(start 342.945466 -41.21912)
						(mid 342.797684 -41.139318)
						(end 342.717882 -40.991536)
					)
				)
			)
		)
		(zone
			(layer "F.Cu")
			(hatch none 0.5)
			(connect_pads
				(clearance 0)
			)
			(min_thickness 0.25)
			(keepout
				(tracks not_allowed)
				(vias allowed)
				(pads allowed)
				(copperpour not_allowed)
				(footprints allowed)
			)
			(placement
				(enabled no)
				(sheetname "")
			)
			(fill
				(thermal_gap 0.5)
				(thermal_bridge_width 0.5)
				(island_removal_mode 0)
			)
			(polygon
				(pts
					(arc
						(start 342.823038 -40.051736)
						(mid 342.869639 -40.127563)
						(end 342.945466 -40.174164)
					)
					(arc
						(start 342.945466 -40.27932)
						(mid 342.797684 -40.199518)
						(end 342.717882 -40.051736)
					)
				)
			)
		)
		(zone
			(layer "F.Cu")
			(hatch none 0.5)
			(connect_pads
				(clearance 0)
			)
			(min_thickness 0.25)
			(keepout
				(tracks not_allowed)
				(vias allowed)
				(pads allowed)
				(copperpour not_allowed)
				(footprints allowed)
			)
			(placement
				(enabled no)
				(sheetname "")
			)
			(fill
				(thermal_gap 0.5)
				(thermal_bridge_width 0.5)
				(island_removal_mode 0)
			)
			(polygon
				(pts
					(arc
						(start 342.945466 -56.726328)
						(mid 342.869639 -56.772929)
						(end 342.823038 -56.848756)
					)
					(arc
						(start 342.717882 -56.848756)
						(mid 342.797684 -56.700974)
						(end 342.945466 -56.621172)
					)
				)
			)
		)
		(zone
			(layer "F.Cu")
			(hatch none 0.5)
			(connect_pads
				(clearance 0)
			)
			(min_thickness 0.25)
			(keepout
				(tracks not_allowed)
				(vias allowed)
				(pads allowed)
				(copperpour not_allowed)
				(footprints allowed)
			)
			(placement
				(enabled no)
				(sheetname "")
			)
			(fill
				(thermal_gap 0.5)
				(thermal_bridge_width 0.5)
				(island_removal_mode 0)
			)
			(polygon
				(pts
					(arc
						(start 342.945466 -55.786528)
						(mid 342.869639 -55.833129)
						(end 342.823038 -55.908956)
					)
					(arc
						(start 342.717882 -55.908956)
						(mid 342.797684 -55.761174)
						(end 342.945466 -55.681372)
					)
				)
			)
		)
		(zone
			(layer "F.Cu")
			(hatch none 0.5)
			(connect_pads
				(clearance 0)
			)
			(min_thickness 0.25)
			(keepout
				(tracks not_allowed)
				(vias allowed)
				(pads allowed)
				(copperpour not_allowed)
				(footprints allowed)
			)
			(placement
				(enabled no)
				(sheetname "")
			)
			(fill
				(thermal_gap 0.5)
				(thermal_bridge_width 0.5)
				(island_removal_mode 0)
			)
			(polygon
				(pts
					(arc
						(start 342.945466 -54.846728)
						(mid 342.869639 -54.893329)
						(end 342.823038 -54.969156)
					)
					(arc
						(start 342.717882 -54.969156)
						(mid 342.797684 -54.821374)
						(end 342.945466 -54.741572)
					)
				)
			)
		)
		(zone
			(layer "F.Cu")
			(hatch none 0.5)
			(connect_pads
				(clearance 0)
			)
			(min_thickness 0.25)
			(keepout
				(tracks not_allowed)
				(vias allowed)
				(pads allowed)
				(copperpour not_allowed)
				(footprints allowed)
			)
			(placement
				(enabled no)
				(sheetname "")
			)
			(fill
				(thermal_gap 0.5)
				(thermal_bridge_width 0.5)
				(island_removal_mode 0)
			)
			(polygon
				(pts
					(arc
						(start 342.945466 -53.906928)
						(mid 342.869639 -53.953529)
						(end 342.823038 -54.029356)
					)
					(arc
						(start 342.717882 -54.029356)
						(mid 342.797684 -53.881574)
						(end 342.945466 -53.801772)
					)
				)
			)
		)
		(zone
			(layer "F.Cu")
			(hatch none 0.5)
			(connect_pads
				(clearance 0)
			)
			(min_thickness 0.25)
			(keepout
				(tracks not_allowed)
				(vias allowed)
				(pads allowed)
				(copperpour not_allowed)
				(footprints allowed)
			)
			(placement
				(enabled no)
				(sheetname "")
			)
			(fill
				(thermal_gap 0.5)
				(thermal_bridge_width 0.5)
				(island_removal_mode 0)
			)
			(polygon
				(pts
					(arc
						(start 342.945466 -52.967128)
						(mid 342.869639 -53.013729)
						(end 342.823038 -53.089556)
					)
					(arc
						(start 342.717882 -53.089556)
						(mid 342.797684 -52.941774)
						(end 342.945466 -52.861972)
					)
				)
			)
		)
		(zone
			(layer "F.Cu")
			(hatch none 0.5)
			(connect_pads
				(clearance 0)
			)
			(min_thickness 0.25)
			(keepout
				(tracks not_allowed)
				(vias allowed)
				(pads allowed)
				(copperpour not_allowed)
				(footprints allowed)
			)
			(placement
				(enabled no)
				(sheetname "")
			)
			(fill
				(thermal_gap 0.5)
				(thermal_bridge_width 0.5)
				(island_removal_mode 0)
			)
			(polygon
				(pts
					(arc
						(start 342.945466 -52.027328)
						(mid 342.869639 -52.073929)
						(end 342.823038 -52.149756)
					)
					(arc
						(start 342.717882 -52.149756)
						(mid 342.797684 -52.001974)
						(end 342.945466 -51.922172)
					)
				)
			)
		)
		(zone
			(layer "F.Cu")
			(hatch none 0.5)
			(connect_pads
				(clearance 0)
			)
			(min_thickness 0.25)
			(keepout
				(tracks not_allowed)
				(vias allowed)
				(pads allowed)
				(copperpour not_allowed)
				(footprints allowed)
			)
			(placement
				(enabled no)
				(sheetname "")
			)
			(fill
				(thermal_gap 0.5)
				(thermal_bridge_width 0.5)
				(island_removal_mode 0)
			)
			(polygon
				(pts
					(arc
						(start 342.945466 -51.087528)
						(mid 342.869639 -51.134129)
						(end 342.823038 -51.209956)
					)
					(arc
						(start 342.717882 -51.209956)
						(mid 342.797684 -51.062174)
						(end 342.945466 -50.982372)
					)
				)
			)
		)
		(zone
			(layer "F.Cu")
			(hatch none 0.5)
			(connect_pads
				(clearance 0)
			)
			(min_thickness 0.25)
			(keepout
				(tracks not_allowed)
				(vias allowed)
				(pads allowed)
				(copperpour not_allowed)
				(footprints allowed)
			)
			(placement
				(enabled no)
				(sheetname "")
			)
			(fill
				(thermal_gap 0.5)
				(thermal_bridge_width 0.5)
				(island_removal_mode 0)
			)
			(polygon
				(pts
					(arc
						(start 342.945466 -50.147728)
						(mid 342.869639 -50.194329)
						(end 342.823038 -50.270156)
					)
					(arc
						(start 342.717882 -50.270156)
						(mid 342.797684 -50.122374)
						(end 342.945466 -50.042572)
					)
				)
			)
		)
		(zone
			(layer "F.Cu")
			(hatch none 0.5)
			(connect_pads
				(clearance 0)
			)
			(min_thickness 0.25)
			(keepout
				(tracks not_allowed)
				(vias allowed)
				(pads allowed)
				(copperpour not_allowed)
				(footprints allowed)
			)
			(placement
				(enabled no)
				(sheetname "")
			)
			(fill
				(thermal_gap 0.5)
				(thermal_bridge_width 0.5)
				(island_removal_mode 0)
			)
			(polygon
				(pts
					(arc
						(start 342.945466 -49.207928)
						(mid 342.869639 -49.254529)
						(end 342.823038 -49.330356)
					)
					(arc
						(start 342.717882 -49.330356)
						(mid 342.797684 -49.182574)
						(end 342.945466 -49.102772)
					)
				)
			)
		)
		(zone
			(layer "F.Cu")
			(hatch none 0.5)
			(connect_pads
				(clearance 0)
			)
			(min_thickness 0.25)
			(keepout
				(tracks not_allowed)
				(vias allowed)
				(pads allowed)
				(copperpour not_allowed)
				(footprints allowed)
			)
			(placement
				(enabled no)
				(sheetname "")
			)
			(fill
				(thermal_gap 0.5)
				(thermal_bridge_width 0.5)
				(island_removal_mode 0)
			)
			(polygon
				(pts
					(arc
						(start 342.945466 -48.268128)
						(mid 342.869639 -48.314729)
						(end 342.823038 -48.390556)
					)
					(arc
						(start 342.717882 -48.390556)
						(mid 342.797684 -48.242774)
						(end 342.945466 -48.162972)
					)
				)
			)
		)
		(zone
			(layer "F.Cu")
			(hatch none 0.5)
			(connect_pads
				(clearance 0)
			)
			(min_thickness 0.25)
			(keepout
				(tracks not_allowed)
				(vias allowed)
				(pads allowed)
				(copperpour not_allowed)
				(footprints allowed)
			)
			(placement
				(enabled no)
				(sheetname "")
			)
			(fill
				(thermal_gap 0.5)
				(thermal_bridge_width 0.5)
				(island_removal_mode 0)
			)
			(polygon
				(pts
					(arc
						(start 342.945466 -47.328328)
						(mid 342.869639 -47.374929)
						(end 342.823038 -47.450756)
					)
					(arc
						(start 342.717882 -47.450756)
						(mid 342.797684 -47.302974)
						(end 342.945466 -47.223172)
					)
				)
			)
		)
		(zone
			(layer "F.Cu")
			(hatch none 0.5)
			(connect_pads
				(clearance 0)
			)
			(min_thickness 0.25)
			(keepout
				(tracks not_allowed)
				(vias allowed)
				(pads allowed)
				(copperpour not_allowed)
				(footprints allowed)
			)
			(placement
				(enabled no)
				(sheetname "")
			)
			(fill
				(thermal_gap 0.5)
				(thermal_bridge_width 0.5)
				(island_removal_mode 0)
			)
			(polygon
				(pts
					(arc
						(start 342.945466 -46.388528)
						(mid 342.869639 -46.435129)
						(end 342.823038 -46.510956)
					)
					(arc
						(start 342.717882 -46.510956)
						(mid 342.797684 -46.363174)
						(end 342.945466 -46.283372)
					)
				)
			)
		)
		(zone
			(layer "F.Cu")
			(hatch none 0.5)
			(connect_pads
				(clearance 0)
			)
			(min_thickness 0.25)
			(keepout
				(tracks not_allowed)
				(vias allowed)
				(pads allowed)
				(copperpour not_allowed)
				(footprints allowed)
			)
			(placement
				(enabled no)
				(sheetname "")
			)
			(fill
				(thermal_gap 0.5)
				(thermal_bridge_width 0.5)
				(island_removal_mode 0)
			)
			(polygon
				(pts
					(arc
						(start 342.945466 -45.448728)
						(mid 342.869639 -45.495329)
						(end 342.823038 -45.571156)
					)
					(arc
						(start 342.717882 -45.571156)
						(mid 342.797684 -45.423374)
						(end 342.945466 -45.343572)
					)
				)
			)
		)
		(zone
			(layer "F.Cu")
			(hatch none 0.5)
			(connect_pads
				(clearance 0)
			)
			(min_thickness 0.25)
			(keepout
				(tracks not_allowed)
				(vias allowed)
				(pads allowed)
				(copperpour not_allowed)
				(footprints allowed)
			)
			(placement
				(enabled no)
				(sheetname "")
			)
			(fill
				(thermal_gap 0.5)
				(thermal_bridge_width 0.5)
				(island_removal_mode 0)
			)
			(polygon
				(pts
					(arc
						(start 342.945466 -44.508928)
						(mid 342.869639 -44.555529)
						(end 342.823038 -44.631356)
					)
					(arc
						(start 342.717882 -44.631356)
						(mid 342.797684 -44.483574)
						(end 342.945466 -44.403772)
					)
				)
			)
		)
		(zone
			(layer "F.Cu")
			(hatch none 0.5)
			(connect_pads
				(clearance 0)
			)
			(min_thickness 0.25)
			(keepout
				(tracks not_allowed)
				(vias allowed)
				(pads allowed)
				(copperpour not_allowed)
				(footprints allowed)
			)
			(placement
				(enabled no)
				(sheetname "")
			)
			(fill
				(thermal_gap 0.5)
				(thermal_bridge_width 0.5)
				(island_removal_mode 0)
			)
			(polygon
				(pts
					(arc
						(start 342.945466 -43.569128)
						(mid 342.869639 -43.615729)
						(end 342.823038 -43.691556)
					)
					(arc
						(start 342.717882 -43.691556)
						(mid 342.797684 -43.543774)
						(end 342.945466 -43.463972)
					)
				)
			)
		)
		(zone
			(layer "F.Cu")
			(hatch none 0.5)
			(connect_pads
				(clearance 0)
			)
			(min_thickness 0.25)
			(keepout
				(tracks not_allowed)
				(vias allowed)
				(pads allowed)
				(copperpour not_allowed)
				(footprints allowed)
			)
			(placement
				(enabled no)
				(sheetname "")
			)
			(fill
				(thermal_gap 0.5)
				(thermal_bridge_width 0.5)
				(island_removal_mode 0)
			)
			(polygon
				(pts
					(arc
						(start 342.945466 -42.629328)
						(mid 342.869639 -42.675929)
						(end 342.823038 -42.751756)
					)
					(arc
						(start 342.717882 -42.751756)
						(mid 342.797684 -42.603974)
						(end 342.945466 -42.524172)
					)
				)
			)
		)
		(zone
			(layer "F.Cu")
			(hatch none 0.5)
			(connect_pads
				(clearance 0)
			)
			(min_thickness 0.25)
			(keepout
				(tracks not_allowed)
				(vias allowed)
				(pads allowed)
				(copperpour not_allowed)
				(footprints allowed)
			)
			(placement
				(enabled no)
				(sheetname "")
			)
			(fill
				(thermal_gap 0.5)
				(thermal_bridge_width 0.5)
				(island_removal_mode 0)
			)
			(polygon
				(pts
					(arc
						(start 342.945466 -41.689528)
						(mid 342.869639 -41.736129)
						(end 342.823038 -41.811956)
					)
					(arc
						(start 342.717882 -41.811956)
						(mid 342.797684 -41.664174)
						(end 342.945466 -41.584372)
					)
				)
			)
		)
		(zone
			(layer "F.Cu")
			(hatch none 0.5)
			(connect_pads
				(clearance 0)
			)
			(min_thickness 0.25)
			(keepout
				(tracks not_allowed)
				(vias allowed)
				(pads allowed)
				(copperpour not_allowed)
				(footprints allowed)
			)
			(placement
				(enabled no)
				(sheetname "")
			)
			(fill
				(thermal_gap 0.5)
				(thermal_bridge_width 0.5)
				(island_removal_mode 0)
			)
			(polygon
				(pts
					(arc
						(start 342.945466 -40.749728)
						(mid 342.869639 -40.796329)
						(end 342.823038 -40.872156)
					)
					(arc
						(start 342.717882 -40.872156)
						(mid 342.797684 -40.724374)
						(end 342.945466 -40.644572)
					)
				)
			)
		)
		(zone
			(layer "F.Cu")
			(hatch none 0.5)
			(connect_pads
				(clearance 0)
			)
			(min_thickness 0.25)
			(keepout
				(tracks not_allowed)
				(vias allowed)
				(pads allowed)
				(copperpour not_allowed)
				(footprints allowed)
			)
			(placement
				(enabled no)
				(sheetname "")
			)
			(fill
				(thermal_gap 0.5)
				(thermal_bridge_width 0.5)
				(island_removal_mode 0)
			)
			(polygon
				(pts
					(arc
						(start 342.945466 -39.809928)
						(mid 342.869639 -39.856529)
						(end 342.823038 -39.932356)
					)
					(arc
						(start 342.717882 -39.932356)
						(mid 342.797684 -39.784574)
						(end 342.945466 -39.704772)
					)
				)
			)
		)
		(zone
			(layer "F.Cu")
			(hatch none 0.5)
			(connect_pads
				(clearance 0)
			)
			(min_thickness 0.25)
			(keepout
				(tracks not_allowed)
				(vias allowed)
				(pads allowed)
				(copperpour not_allowed)
				(footprints allowed)
			)
			(placement
				(enabled no)
				(sheetname "")
			)
			(fill
				(thermal_gap 0.5)
				(thermal_bridge_width 0.5)
				(island_removal_mode 0)
			)
			(polygon
				(pts
					(arc
						(start 343.064846 -57.090564)
						(mid 343.140673 -57.043963)
						(end 343.187274 -56.968136)
					)
					(arc
						(start 343.292684 -56.968136)
						(mid 343.212794 -57.116006)
						(end 343.064846 -57.19572)
					)
				)
			)
		)
		(zone
			(layer "F.Cu")
			(hatch none 0.5)
			(connect_pads
				(clearance 0)
			)
			(min_thickness 0.25)
			(keepout
				(tracks not_allowed)
				(vias allowed)
				(pads allowed)
				(copperpour not_allowed)
				(footprints allowed)
			)
			(placement
				(enabled no)
				(sheetname "")
			)
			(fill
				(thermal_gap 0.5)
				(thermal_bridge_width 0.5)
				(island_removal_mode 0)
			)
			(polygon
				(pts
					(arc
						(start 343.064846 -56.150764)
						(mid 343.140673 -56.104163)
						(end 343.187274 -56.028336)
					)
					(arc
						(start 343.292684 -56.028336)
						(mid 343.212794 -56.176206)
						(end 343.064846 -56.25592)
					)
				)
			)
		)
		(zone
			(layer "F.Cu")
			(hatch none 0.5)
			(connect_pads
				(clearance 0)
			)
			(min_thickness 0.25)
			(keepout
				(tracks not_allowed)
				(vias allowed)
				(pads allowed)
				(copperpour not_allowed)
				(footprints allowed)
			)
			(placement
				(enabled no)
				(sheetname "")
			)
			(fill
				(thermal_gap 0.5)
				(thermal_bridge_width 0.5)
				(island_removal_mode 0)
			)
			(polygon
				(pts
					(arc
						(start 343.064846 -55.210964)
						(mid 343.140673 -55.164363)
						(end 343.187274 -55.088536)
					)
					(arc
						(start 343.292684 -55.088536)
						(mid 343.212794 -55.236406)
						(end 343.064846 -55.31612)
					)
				)
			)
		)
		(zone
			(layer "F.Cu")
			(hatch none 0.5)
			(connect_pads
				(clearance 0)
			)
			(min_thickness 0.25)
			(keepout
				(tracks not_allowed)
				(vias allowed)
				(pads allowed)
				(copperpour not_allowed)
				(footprints allowed)
			)
			(placement
				(enabled no)
				(sheetname "")
			)
			(fill
				(thermal_gap 0.5)
				(thermal_bridge_width 0.5)
				(island_removal_mode 0)
			)
			(polygon
				(pts
					(arc
						(start 343.064846 -54.271164)
						(mid 343.140673 -54.224563)
						(end 343.187274 -54.148736)
					)
					(arc
						(start 343.292684 -54.148736)
						(mid 343.212794 -54.296606)
						(end 343.064846 -54.37632)
					)
				)
			)
		)
		(zone
			(layer "F.Cu")
			(hatch none 0.5)
			(connect_pads
				(clearance 0)
			)
			(min_thickness 0.25)
			(keepout
				(tracks not_allowed)
				(vias allowed)
				(pads allowed)
				(copperpour not_allowed)
				(footprints allowed)
			)
			(placement
				(enabled no)
				(sheetname "")
			)
			(fill
				(thermal_gap 0.5)
				(thermal_bridge_width 0.5)
				(island_removal_mode 0)
			)
			(polygon
				(pts
					(arc
						(start 343.064846 -53.331364)
						(mid 343.140673 -53.284763)
						(end 343.187274 -53.208936)
					)
					(arc
						(start 343.292684 -53.208936)
						(mid 343.212794 -53.356806)
						(end 343.064846 -53.43652)
					)
				)
			)
		)
		(zone
			(layer "F.Cu")
			(hatch none 0.5)
			(connect_pads
				(clearance 0)
			)
			(min_thickness 0.25)
			(keepout
				(tracks not_allowed)
				(vias allowed)
				(pads allowed)
				(copperpour not_allowed)
				(footprints allowed)
			)
			(placement
				(enabled no)
				(sheetname "")
			)
			(fill
				(thermal_gap 0.5)
				(thermal_bridge_width 0.5)
				(island_removal_mode 0)
			)
			(polygon
				(pts
					(arc
						(start 343.064846 -52.391564)
						(mid 343.140673 -52.344963)
						(end 343.187274 -52.269136)
					)
					(arc
						(start 343.292684 -52.269136)
						(mid 343.212794 -52.417006)
						(end 343.064846 -52.49672)
					)
				)
			)
		)
		(zone
			(layer "F.Cu")
			(hatch none 0.5)
			(connect_pads
				(clearance 0)
			)
			(min_thickness 0.25)
			(keepout
				(tracks not_allowed)
				(vias allowed)
				(pads allowed)
				(copperpour not_allowed)
				(footprints allowed)
			)
			(placement
				(enabled no)
				(sheetname "")
			)
			(fill
				(thermal_gap 0.5)
				(thermal_bridge_width 0.5)
				(island_removal_mode 0)
			)
			(polygon
				(pts
					(arc
						(start 343.064846 -51.451764)
						(mid 343.140673 -51.405163)
						(end 343.187274 -51.329336)
					)
					(arc
						(start 343.292684 -51.329336)
						(mid 343.212794 -51.477206)
						(end 343.064846 -51.55692)
					)
				)
			)
		)
		(zone
			(layer "F.Cu")
			(hatch none 0.5)
			(connect_pads
				(clearance 0)
			)
			(min_thickness 0.25)
			(keepout
				(tracks not_allowed)
				(vias allowed)
				(pads allowed)
				(copperpour not_allowed)
				(footprints allowed)
			)
			(placement
				(enabled no)
				(sheetname "")
			)
			(fill
				(thermal_gap 0.5)
				(thermal_bridge_width 0.5)
				(island_removal_mode 0)
			)
			(polygon
				(pts
					(arc
						(start 343.064846 -50.511964)
						(mid 343.140673 -50.465363)
						(end 343.187274 -50.389536)
					)
					(arc
						(start 343.292684 -50.389536)
						(mid 343.212794 -50.537406)
						(end 343.064846 -50.61712)
					)
				)
			)
		)
		(zone
			(layer "F.Cu")
			(hatch none 0.5)
			(connect_pads
				(clearance 0)
			)
			(min_thickness 0.25)
			(keepout
				(tracks not_allowed)
				(vias allowed)
				(pads allowed)
				(copperpour not_allowed)
				(footprints allowed)
			)
			(placement
				(enabled no)
				(sheetname "")
			)
			(fill
				(thermal_gap 0.5)
				(thermal_bridge_width 0.5)
				(island_removal_mode 0)
			)
			(polygon
				(pts
					(arc
						(start 343.064846 -49.572164)
						(mid 343.140673 -49.525563)
						(end 343.187274 -49.449736)
					)
					(arc
						(start 343.292684 -49.449736)
						(mid 343.212794 -49.597606)
						(end 343.064846 -49.67732)
					)
				)
			)
		)
		(zone
			(layer "F.Cu")
			(hatch none 0.5)
			(connect_pads
				(clearance 0)
			)
			(min_thickness 0.25)
			(keepout
				(tracks not_allowed)
				(vias allowed)
				(pads allowed)
				(copperpour not_allowed)
				(footprints allowed)
			)
			(placement
				(enabled no)
				(sheetname "")
			)
			(fill
				(thermal_gap 0.5)
				(thermal_bridge_width 0.5)
				(island_removal_mode 0)
			)
			(polygon
				(pts
					(arc
						(start 343.064846 -48.632364)
						(mid 343.140673 -48.585763)
						(end 343.187274 -48.509936)
					)
					(arc
						(start 343.292684 -48.509936)
						(mid 343.212794 -48.657806)
						(end 343.064846 -48.73752)
					)
				)
			)
		)
		(zone
			(layer "F.Cu")
			(hatch none 0.5)
			(connect_pads
				(clearance 0)
			)
			(min_thickness 0.25)
			(keepout
				(tracks not_allowed)
				(vias allowed)
				(pads allowed)
				(copperpour not_allowed)
				(footprints allowed)
			)
			(placement
				(enabled no)
				(sheetname "")
			)
			(fill
				(thermal_gap 0.5)
				(thermal_bridge_width 0.5)
				(island_removal_mode 0)
			)
			(polygon
				(pts
					(arc
						(start 343.064846 -47.692564)
						(mid 343.140673 -47.645963)
						(end 343.187274 -47.570136)
					)
					(arc
						(start 343.292684 -47.570136)
						(mid 343.212794 -47.718006)
						(end 343.064846 -47.79772)
					)
				)
			)
		)
		(zone
			(layer "F.Cu")
			(hatch none 0.5)
			(connect_pads
				(clearance 0)
			)
			(min_thickness 0.25)
			(keepout
				(tracks not_allowed)
				(vias allowed)
				(pads allowed)
				(copperpour not_allowed)
				(footprints allowed)
			)
			(placement
				(enabled no)
				(sheetname "")
			)
			(fill
				(thermal_gap 0.5)
				(thermal_bridge_width 0.5)
				(island_removal_mode 0)
			)
			(polygon
				(pts
					(arc
						(start 343.064846 -46.752764)
						(mid 343.140673 -46.706163)
						(end 343.187274 -46.630336)
					)
					(arc
						(start 343.292684 -46.630336)
						(mid 343.212794 -46.778206)
						(end 343.064846 -46.85792)
					)
				)
			)
		)
		(zone
			(layer "F.Cu")
			(hatch none 0.5)
			(connect_pads
				(clearance 0)
			)
			(min_thickness 0.25)
			(keepout
				(tracks not_allowed)
				(vias allowed)
				(pads allowed)
				(copperpour not_allowed)
				(footprints allowed)
			)
			(placement
				(enabled no)
				(sheetname "")
			)
			(fill
				(thermal_gap 0.5)
				(thermal_bridge_width 0.5)
				(island_removal_mode 0)
			)
			(polygon
				(pts
					(arc
						(start 343.064846 -45.812964)
						(mid 343.140673 -45.766363)
						(end 343.187274 -45.690536)
					)
					(arc
						(start 343.292684 -45.690536)
						(mid 343.212794 -45.838406)
						(end 343.064846 -45.91812)
					)
				)
			)
		)
		(zone
			(layer "F.Cu")
			(hatch none 0.5)
			(connect_pads
				(clearance 0)
			)
			(min_thickness 0.25)
			(keepout
				(tracks not_allowed)
				(vias allowed)
				(pads allowed)
				(copperpour not_allowed)
				(footprints allowed)
			)
			(placement
				(enabled no)
				(sheetname "")
			)
			(fill
				(thermal_gap 0.5)
				(thermal_bridge_width 0.5)
				(island_removal_mode 0)
			)
			(polygon
				(pts
					(arc
						(start 343.064846 -44.873164)
						(mid 343.140673 -44.826563)
						(end 343.187274 -44.750736)
					)
					(arc
						(start 343.292684 -44.750736)
						(mid 343.212794 -44.898606)
						(end 343.064846 -44.97832)
					)
				)
			)
		)
		(zone
			(layer "F.Cu")
			(hatch none 0.5)
			(connect_pads
				(clearance 0)
			)
			(min_thickness 0.25)
			(keepout
				(tracks not_allowed)
				(vias allowed)
				(pads allowed)
				(copperpour not_allowed)
				(footprints allowed)
			)
			(placement
				(enabled no)
				(sheetname "")
			)
			(fill
				(thermal_gap 0.5)
				(thermal_bridge_width 0.5)
				(island_removal_mode 0)
			)
			(polygon
				(pts
					(arc
						(start 343.064846 -43.933364)
						(mid 343.140673 -43.886763)
						(end 343.187274 -43.810936)
					)
					(arc
						(start 343.292684 -43.810936)
						(mid 343.212794 -43.958806)
						(end 343.064846 -44.03852)
					)
				)
			)
		)
		(zone
			(layer "F.Cu")
			(hatch none 0.5)
			(connect_pads
				(clearance 0)
			)
			(min_thickness 0.25)
			(keepout
				(tracks not_allowed)
				(vias allowed)
				(pads allowed)
				(copperpour not_allowed)
				(footprints allowed)
			)
			(placement
				(enabled no)
				(sheetname "")
			)
			(fill
				(thermal_gap 0.5)
				(thermal_bridge_width 0.5)
				(island_removal_mode 0)
			)
			(polygon
				(pts
					(arc
						(start 343.064846 -42.993564)
						(mid 343.140673 -42.946963)
						(end 343.187274 -42.871136)
					)
					(arc
						(start 343.292684 -42.871136)
						(mid 343.212794 -43.019006)
						(end 343.064846 -43.09872)
					)
				)
			)
		)
		(zone
			(layer "F.Cu")
			(hatch none 0.5)
			(connect_pads
				(clearance 0)
			)
			(min_thickness 0.25)
			(keepout
				(tracks not_allowed)
				(vias allowed)
				(pads allowed)
				(copperpour not_allowed)
				(footprints allowed)
			)
			(placement
				(enabled no)
				(sheetname "")
			)
			(fill
				(thermal_gap 0.5)
				(thermal_bridge_width 0.5)
				(island_removal_mode 0)
			)
			(polygon
				(pts
					(arc
						(start 343.064846 -42.053764)
						(mid 343.140673 -42.007163)
						(end 343.187274 -41.931336)
					)
					(arc
						(start 343.292684 -41.931336)
						(mid 343.212794 -42.079206)
						(end 343.064846 -42.15892)
					)
				)
			)
		)
		(zone
			(layer "F.Cu")
			(hatch none 0.5)
			(connect_pads
				(clearance 0)
			)
			(min_thickness 0.25)
			(keepout
				(tracks not_allowed)
				(vias allowed)
				(pads allowed)
				(copperpour not_allowed)
				(footprints allowed)
			)
			(placement
				(enabled no)
				(sheetname "")
			)
			(fill
				(thermal_gap 0.5)
				(thermal_bridge_width 0.5)
				(island_removal_mode 0)
			)
			(polygon
				(pts
					(arc
						(start 343.064846 -41.113964)
						(mid 343.140673 -41.067363)
						(end 343.187274 -40.991536)
					)
					(arc
						(start 343.292684 -40.991536)
						(mid 343.212794 -41.139406)
						(end 343.064846 -41.21912)
					)
				)
			)
		)
		(zone
			(layer "F.Cu")
			(hatch none 0.5)
			(connect_pads
				(clearance 0)
			)
			(min_thickness 0.25)
			(keepout
				(tracks not_allowed)
				(vias allowed)
				(pads allowed)
				(copperpour not_allowed)
				(footprints allowed)
			)
			(placement
				(enabled no)
				(sheetname "")
			)
			(fill
				(thermal_gap 0.5)
				(thermal_bridge_width 0.5)
				(island_removal_mode 0)
			)
			(polygon
				(pts
					(arc
						(start 343.064846 -40.174164)
						(mid 343.140673 -40.127563)
						(end 343.187274 -40.051736)
					)
					(arc
						(start 343.292684 -40.051736)
						(mid 343.212794 -40.199606)
						(end 343.064846 -40.27932)
					)
				)
			)
		)
		(zone
			(layer "F.Cu")
			(hatch none 0.5)
			(connect_pads
				(clearance 0)
			)
			(min_thickness 0.25)
			(keepout
				(tracks not_allowed)
				(vias allowed)
				(pads allowed)
				(copperpour not_allowed)
				(footprints allowed)
			)
			(placement
				(enabled no)
				(sheetname "")
			)
			(fill
				(thermal_gap 0.5)
				(thermal_bridge_width 0.5)
				(island_removal_mode 0)
			)
			(polygon
				(pts
					(arc
						(start 343.187274 -56.848756)
						(mid 343.140673 -56.772929)
						(end 343.064846 -56.726328)
					)
					(arc
						(start 343.064846 -56.621172)
						(mid 343.212758 -56.700923)
						(end 343.292684 -56.848756)
					)
				)
			)
		)
		(zone
			(layer "F.Cu")
			(hatch none 0.5)
			(connect_pads
				(clearance 0)
			)
			(min_thickness 0.25)
			(keepout
				(tracks not_allowed)
				(vias allowed)
				(pads allowed)
				(copperpour not_allowed)
				(footprints allowed)
			)
			(placement
				(enabled no)
				(sheetname "")
			)
			(fill
				(thermal_gap 0.5)
				(thermal_bridge_width 0.5)
				(island_removal_mode 0)
			)
			(polygon
				(pts
					(arc
						(start 343.187274 -55.908956)
						(mid 343.140673 -55.833129)
						(end 343.064846 -55.786528)
					)
					(arc
						(start 343.064846 -55.681372)
						(mid 343.212758 -55.761123)
						(end 343.292684 -55.908956)
					)
				)
			)
		)
		(zone
			(layer "F.Cu")
			(hatch none 0.5)
			(connect_pads
				(clearance 0)
			)
			(min_thickness 0.25)
			(keepout
				(tracks not_allowed)
				(vias allowed)
				(pads allowed)
				(copperpour not_allowed)
				(footprints allowed)
			)
			(placement
				(enabled no)
				(sheetname "")
			)
			(fill
				(thermal_gap 0.5)
				(thermal_bridge_width 0.5)
				(island_removal_mode 0)
			)
			(polygon
				(pts
					(arc
						(start 343.187274 -54.969156)
						(mid 343.140673 -54.893329)
						(end 343.064846 -54.846728)
					)
					(arc
						(start 343.064846 -54.741572)
						(mid 343.212758 -54.821323)
						(end 343.292684 -54.969156)
					)
				)
			)
		)
		(zone
			(layer "F.Cu")
			(hatch none 0.5)
			(connect_pads
				(clearance 0)
			)
			(min_thickness 0.25)
			(keepout
				(tracks not_allowed)
				(vias allowed)
				(pads allowed)
				(copperpour not_allowed)
				(footprints allowed)
			)
			(placement
				(enabled no)
				(sheetname "")
			)
			(fill
				(thermal_gap 0.5)
				(thermal_bridge_width 0.5)
				(island_removal_mode 0)
			)
			(polygon
				(pts
					(arc
						(start 343.187274 -54.029356)
						(mid 343.140673 -53.953529)
						(end 343.064846 -53.906928)
					)
					(arc
						(start 343.064846 -53.801772)
						(mid 343.212758 -53.881523)
						(end 343.292684 -54.029356)
					)
				)
			)
		)
		(zone
			(layer "F.Cu")
			(hatch none 0.5)
			(connect_pads
				(clearance 0)
			)
			(min_thickness 0.25)
			(keepout
				(tracks not_allowed)
				(vias allowed)
				(pads allowed)
				(copperpour not_allowed)
				(footprints allowed)
			)
			(placement
				(enabled no)
				(sheetname "")
			)
			(fill
				(thermal_gap 0.5)
				(thermal_bridge_width 0.5)
				(island_removal_mode 0)
			)
			(polygon
				(pts
					(arc
						(start 343.187274 -53.089556)
						(mid 343.140673 -53.013729)
						(end 343.064846 -52.967128)
					)
					(arc
						(start 343.064846 -52.861972)
						(mid 343.212758 -52.941723)
						(end 343.292684 -53.089556)
					)
				)
			)
		)
		(zone
			(layer "F.Cu")
			(hatch none 0.5)
			(connect_pads
				(clearance 0)
			)
			(min_thickness 0.25)
			(keepout
				(tracks not_allowed)
				(vias allowed)
				(pads allowed)
				(copperpour not_allowed)
				(footprints allowed)
			)
			(placement
				(enabled no)
				(sheetname "")
			)
			(fill
				(thermal_gap 0.5)
				(thermal_bridge_width 0.5)
				(island_removal_mode 0)
			)
			(polygon
				(pts
					(arc
						(start 343.187274 -52.149756)
						(mid 343.140673 -52.073929)
						(end 343.064846 -52.027328)
					)
					(arc
						(start 343.064846 -51.922172)
						(mid 343.212758 -52.001923)
						(end 343.292684 -52.149756)
					)
				)
			)
		)
		(zone
			(layer "F.Cu")
			(hatch none 0.5)
			(connect_pads
				(clearance 0)
			)
			(min_thickness 0.25)
			(keepout
				(tracks not_allowed)
				(vias allowed)
				(pads allowed)
				(copperpour not_allowed)
				(footprints allowed)
			)
			(placement
				(enabled no)
				(sheetname "")
			)
			(fill
				(thermal_gap 0.5)
				(thermal_bridge_width 0.5)
				(island_removal_mode 0)
			)
			(polygon
				(pts
					(arc
						(start 343.187274 -51.209956)
						(mid 343.140673 -51.134129)
						(end 343.064846 -51.087528)
					)
					(arc
						(start 343.064846 -50.982372)
						(mid 343.212758 -51.062123)
						(end 343.292684 -51.209956)
					)
				)
			)
		)
		(zone
			(layer "F.Cu")
			(hatch none 0.5)
			(connect_pads
				(clearance 0)
			)
			(min_thickness 0.25)
			(keepout
				(tracks not_allowed)
				(vias allowed)
				(pads allowed)
				(copperpour not_allowed)
				(footprints allowed)
			)
			(placement
				(enabled no)
				(sheetname "")
			)
			(fill
				(thermal_gap 0.5)
				(thermal_bridge_width 0.5)
				(island_removal_mode 0)
			)
			(polygon
				(pts
					(arc
						(start 343.187274 -50.270156)
						(mid 343.140673 -50.194329)
						(end 343.064846 -50.147728)
					)
					(arc
						(start 343.064846 -50.042572)
						(mid 343.212758 -50.122323)
						(end 343.292684 -50.270156)
					)
				)
			)
		)
		(zone
			(layer "F.Cu")
			(hatch none 0.5)
			(connect_pads
				(clearance 0)
			)
			(min_thickness 0.25)
			(keepout
				(tracks not_allowed)
				(vias allowed)
				(pads allowed)
				(copperpour not_allowed)
				(footprints allowed)
			)
			(placement
				(enabled no)
				(sheetname "")
			)
			(fill
				(thermal_gap 0.5)
				(thermal_bridge_width 0.5)
				(island_removal_mode 0)
			)
			(polygon
				(pts
					(arc
						(start 343.187274 -49.330356)
						(mid 343.140673 -49.254529)
						(end 343.064846 -49.207928)
					)
					(arc
						(start 343.064846 -49.102772)
						(mid 343.212758 -49.182523)
						(end 343.292684 -49.330356)
					)
				)
			)
		)
		(zone
			(layer "F.Cu")
			(hatch none 0.5)
			(connect_pads
				(clearance 0)
			)
			(min_thickness 0.25)
			(keepout
				(tracks not_allowed)
				(vias allowed)
				(pads allowed)
				(copperpour not_allowed)
				(footprints allowed)
			)
			(placement
				(enabled no)
				(sheetname "")
			)
			(fill
				(thermal_gap 0.5)
				(thermal_bridge_width 0.5)
				(island_removal_mode 0)
			)
			(polygon
				(pts
					(arc
						(start 343.187274 -48.390556)
						(mid 343.140673 -48.314729)
						(end 343.064846 -48.268128)
					)
					(arc
						(start 343.064846 -48.162972)
						(mid 343.212758 -48.242723)
						(end 343.292684 -48.390556)
					)
				)
			)
		)
		(zone
			(layer "F.Cu")
			(hatch none 0.5)
			(connect_pads
				(clearance 0)
			)
			(min_thickness 0.25)
			(keepout
				(tracks not_allowed)
				(vias allowed)
				(pads allowed)
				(copperpour not_allowed)
				(footprints allowed)
			)
			(placement
				(enabled no)
				(sheetname "")
			)
			(fill
				(thermal_gap 0.5)
				(thermal_bridge_width 0.5)
				(island_removal_mode 0)
			)
			(polygon
				(pts
					(arc
						(start 343.187274 -47.450756)
						(mid 343.140673 -47.374929)
						(end 343.064846 -47.328328)
					)
					(arc
						(start 343.064846 -47.223172)
						(mid 343.212758 -47.302923)
						(end 343.292684 -47.450756)
					)
				)
			)
		)
		(zone
			(layer "F.Cu")
			(hatch none 0.5)
			(connect_pads
				(clearance 0)
			)
			(min_thickness 0.25)
			(keepout
				(tracks not_allowed)
				(vias allowed)
				(pads allowed)
				(copperpour not_allowed)
				(footprints allowed)
			)
			(placement
				(enabled no)
				(sheetname "")
			)
			(fill
				(thermal_gap 0.5)
				(thermal_bridge_width 0.5)
				(island_removal_mode 0)
			)
			(polygon
				(pts
					(arc
						(start 343.187274 -46.510956)
						(mid 343.140673 -46.435129)
						(end 343.064846 -46.388528)
					)
					(arc
						(start 343.064846 -46.283372)
						(mid 343.212758 -46.363123)
						(end 343.292684 -46.510956)
					)
				)
			)
		)
		(zone
			(layer "F.Cu")
			(hatch none 0.5)
			(connect_pads
				(clearance 0)
			)
			(min_thickness 0.25)
			(keepout
				(tracks not_allowed)
				(vias allowed)
				(pads allowed)
				(copperpour not_allowed)
				(footprints allowed)
			)
			(placement
				(enabled no)
				(sheetname "")
			)
			(fill
				(thermal_gap 0.5)
				(thermal_bridge_width 0.5)
				(island_removal_mode 0)
			)
			(polygon
				(pts
					(arc
						(start 343.187274 -45.571156)
						(mid 343.140673 -45.495329)
						(end 343.064846 -45.448728)
					)
					(arc
						(start 343.064846 -45.343572)
						(mid 343.212758 -45.423323)
						(end 343.292684 -45.571156)
					)
				)
			)
		)
		(zone
			(layer "F.Cu")
			(hatch none 0.5)
			(connect_pads
				(clearance 0)
			)
			(min_thickness 0.25)
			(keepout
				(tracks not_allowed)
				(vias allowed)
				(pads allowed)
				(copperpour not_allowed)
				(footprints allowed)
			)
			(placement
				(enabled no)
				(sheetname "")
			)
			(fill
				(thermal_gap 0.5)
				(thermal_bridge_width 0.5)
				(island_removal_mode 0)
			)
			(polygon
				(pts
					(arc
						(start 343.187274 -44.631356)
						(mid 343.140673 -44.555529)
						(end 343.064846 -44.508928)
					)
					(arc
						(start 343.064846 -44.403772)
						(mid 343.212758 -44.483523)
						(end 343.292684 -44.631356)
					)
				)
			)
		)
		(zone
			(layer "F.Cu")
			(hatch none 0.5)
			(connect_pads
				(clearance 0)
			)
			(min_thickness 0.25)
			(keepout
				(tracks not_allowed)
				(vias allowed)
				(pads allowed)
				(copperpour not_allowed)
				(footprints allowed)
			)
			(placement
				(enabled no)
				(sheetname "")
			)
			(fill
				(thermal_gap 0.5)
				(thermal_bridge_width 0.5)
				(island_removal_mode 0)
			)
			(polygon
				(pts
					(arc
						(start 343.187274 -43.691556)
						(mid 343.140673 -43.615729)
						(end 343.064846 -43.569128)
					)
					(arc
						(start 343.064846 -43.463972)
						(mid 343.212758 -43.543723)
						(end 343.292684 -43.691556)
					)
				)
			)
		)
		(zone
			(layer "F.Cu")
			(hatch none 0.5)
			(connect_pads
				(clearance 0)
			)
			(min_thickness 0.25)
			(keepout
				(tracks not_allowed)
				(vias allowed)
				(pads allowed)
				(copperpour not_allowed)
				(footprints allowed)
			)
			(placement
				(enabled no)
				(sheetname "")
			)
			(fill
				(thermal_gap 0.5)
				(thermal_bridge_width 0.5)
				(island_removal_mode 0)
			)
			(polygon
				(pts
					(arc
						(start 343.187274 -42.751756)
						(mid 343.140673 -42.675929)
						(end 343.064846 -42.629328)
					)
					(arc
						(start 343.064846 -42.524172)
						(mid 343.212758 -42.603923)
						(end 343.292684 -42.751756)
					)
				)
			)
		)
		(zone
			(layer "F.Cu")
			(hatch none 0.5)
			(connect_pads
				(clearance 0)
			)
			(min_thickness 0.25)
			(keepout
				(tracks not_allowed)
				(vias allowed)
				(pads allowed)
				(copperpour not_allowed)
				(footprints allowed)
			)
			(placement
				(enabled no)
				(sheetname "")
			)
			(fill
				(thermal_gap 0.5)
				(thermal_bridge_width 0.5)
				(island_removal_mode 0)
			)
			(polygon
				(pts
					(arc
						(start 343.187274 -41.811956)
						(mid 343.140673 -41.736129)
						(end 343.064846 -41.689528)
					)
					(arc
						(start 343.064846 -41.584372)
						(mid 343.212758 -41.664123)
						(end 343.292684 -41.811956)
					)
				)
			)
		)
		(zone
			(layer "F.Cu")
			(hatch none 0.5)
			(connect_pads
				(clearance 0)
			)
			(min_thickness 0.25)
			(keepout
				(tracks not_allowed)
				(vias allowed)
				(pads allowed)
				(copperpour not_allowed)
				(footprints allowed)
			)
			(placement
				(enabled no)
				(sheetname "")
			)
			(fill
				(thermal_gap 0.5)
				(thermal_bridge_width 0.5)
				(island_removal_mode 0)
			)
			(polygon
				(pts
					(arc
						(start 343.187274 -40.872156)
						(mid 343.140673 -40.796329)
						(end 343.064846 -40.749728)
					)
					(arc
						(start 343.064846 -40.644572)
						(mid 343.212758 -40.724323)
						(end 343.292684 -40.872156)
					)
				)
			)
		)
		(zone
			(layer "F.Cu")
			(hatch none 0.5)
			(connect_pads
				(clearance 0)
			)
			(min_thickness 0.25)
			(keepout
				(tracks not_allowed)
				(vias allowed)
				(pads allowed)
				(copperpour not_allowed)
				(footprints allowed)
			)
			(placement
				(enabled no)
				(sheetname "")
			)
			(fill
				(thermal_gap 0.5)
				(thermal_bridge_width 0.5)
				(island_removal_mode 0)
			)
			(polygon
				(pts
					(arc
						(start 343.187274 -39.932356)
						(mid 343.140673 -39.856529)
						(end 343.064846 -39.809928)
					)
					(arc
						(start 343.064846 -39.704772)
						(mid 343.212758 -39.784523)
						(end 343.292684 -39.932356)
					)
				)
			)
		)
		(zone
			(layer "F.Cu")
			(hatch none 0.5)
			(connect_pads
				(clearance 0)
			)
			(min_thickness 0.25)
			(keepout
				(tracks not_allowed)
				(vias allowed)
				(pads allowed)
				(copperpour not_allowed)
				(footprints allowed)
			)
			(placement
				(enabled no)
				(sheetname "")
			)
			(fill
				(thermal_gap 0.5)
				(thermal_bridge_width 0.5)
				(island_removal_mode 0)
			)
			(polygon
				(pts
					(arc
						(start 343.637362 -56.498236)
						(mid 343.683877 -56.573978)
						(end 343.759536 -56.620664)
					)
					(arc
						(start 343.759536 -56.72582)
						(mid 343.611754 -56.646018)
						(end 343.531952 -56.498236)
					)
				)
			)
		)
		(zone
			(layer "F.Cu")
			(hatch none 0.5)
			(connect_pads
				(clearance 0)
			)
			(min_thickness 0.25)
			(keepout
				(tracks not_allowed)
				(vias allowed)
				(pads allowed)
				(copperpour not_allowed)
				(footprints allowed)
			)
			(placement
				(enabled no)
				(sheetname "")
			)
			(fill
				(thermal_gap 0.5)
				(thermal_bridge_width 0.5)
				(island_removal_mode 0)
			)
			(polygon
				(pts
					(arc
						(start 343.637362 -55.558436)
						(mid 343.683877 -55.634178)
						(end 343.759536 -55.680864)
					)
					(arc
						(start 343.759536 -55.78602)
						(mid 343.611754 -55.706218)
						(end 343.531952 -55.558436)
					)
				)
			)
		)
		(zone
			(layer "F.Cu")
			(hatch none 0.5)
			(connect_pads
				(clearance 0)
			)
			(min_thickness 0.25)
			(keepout
				(tracks not_allowed)
				(vias allowed)
				(pads allowed)
				(copperpour not_allowed)
				(footprints allowed)
			)
			(placement
				(enabled no)
				(sheetname "")
			)
			(fill
				(thermal_gap 0.5)
				(thermal_bridge_width 0.5)
				(island_removal_mode 0)
			)
			(polygon
				(pts
					(arc
						(start 343.637362 -54.618636)
						(mid 343.683877 -54.694378)
						(end 343.759536 -54.741064)
					)
					(arc
						(start 343.759536 -54.84622)
						(mid 343.611754 -54.766418)
						(end 343.531952 -54.618636)
					)
				)
			)
		)
		(zone
			(layer "F.Cu")
			(hatch none 0.5)
			(connect_pads
				(clearance 0)
			)
			(min_thickness 0.25)
			(keepout
				(tracks not_allowed)
				(vias allowed)
				(pads allowed)
				(copperpour not_allowed)
				(footprints allowed)
			)
			(placement
				(enabled no)
				(sheetname "")
			)
			(fill
				(thermal_gap 0.5)
				(thermal_bridge_width 0.5)
				(island_removal_mode 0)
			)
			(polygon
				(pts
					(arc
						(start 343.637362 -53.678836)
						(mid 343.683877 -53.754578)
						(end 343.759536 -53.801264)
					)
					(arc
						(start 343.759536 -53.90642)
						(mid 343.611754 -53.826618)
						(end 343.531952 -53.678836)
					)
				)
			)
		)
		(zone
			(layer "F.Cu")
			(hatch none 0.5)
			(connect_pads
				(clearance 0)
			)
			(min_thickness 0.25)
			(keepout
				(tracks not_allowed)
				(vias allowed)
				(pads allowed)
				(copperpour not_allowed)
				(footprints allowed)
			)
			(placement
				(enabled no)
				(sheetname "")
			)
			(fill
				(thermal_gap 0.5)
				(thermal_bridge_width 0.5)
				(island_removal_mode 0)
			)
			(polygon
				(pts
					(arc
						(start 343.637362 -52.739036)
						(mid 343.683877 -52.814778)
						(end 343.759536 -52.861464)
					)
					(arc
						(start 343.759536 -52.96662)
						(mid 343.611754 -52.886818)
						(end 343.531952 -52.739036)
					)
				)
			)
		)
		(zone
			(layer "F.Cu")
			(hatch none 0.5)
			(connect_pads
				(clearance 0)
			)
			(min_thickness 0.25)
			(keepout
				(tracks not_allowed)
				(vias allowed)
				(pads allowed)
				(copperpour not_allowed)
				(footprints allowed)
			)
			(placement
				(enabled no)
				(sheetname "")
			)
			(fill
				(thermal_gap 0.5)
				(thermal_bridge_width 0.5)
				(island_removal_mode 0)
			)
			(polygon
				(pts
					(arc
						(start 343.637362 -51.799236)
						(mid 343.683877 -51.874978)
						(end 343.759536 -51.921664)
					)
					(arc
						(start 343.759536 -52.02682)
						(mid 343.611754 -51.947018)
						(end 343.531952 -51.799236)
					)
				)
			)
		)
		(zone
			(layer "F.Cu")
			(hatch none 0.5)
			(connect_pads
				(clearance 0)
			)
			(min_thickness 0.25)
			(keepout
				(tracks not_allowed)
				(vias allowed)
				(pads allowed)
				(copperpour not_allowed)
				(footprints allowed)
			)
			(placement
				(enabled no)
				(sheetname "")
			)
			(fill
				(thermal_gap 0.5)
				(thermal_bridge_width 0.5)
				(island_removal_mode 0)
			)
			(polygon
				(pts
					(arc
						(start 343.637362 -50.859436)
						(mid 343.683877 -50.935178)
						(end 343.759536 -50.981864)
					)
					(arc
						(start 343.759536 -51.08702)
						(mid 343.611754 -51.007218)
						(end 343.531952 -50.859436)
					)
				)
			)
		)
		(zone
			(layer "F.Cu")
			(hatch none 0.5)
			(connect_pads
				(clearance 0)
			)
			(min_thickness 0.25)
			(keepout
				(tracks not_allowed)
				(vias allowed)
				(pads allowed)
				(copperpour not_allowed)
				(footprints allowed)
			)
			(placement
				(enabled no)
				(sheetname "")
			)
			(fill
				(thermal_gap 0.5)
				(thermal_bridge_width 0.5)
				(island_removal_mode 0)
			)
			(polygon
				(pts
					(arc
						(start 343.637362 -49.919636)
						(mid 343.683877 -49.995378)
						(end 343.759536 -50.042064)
					)
					(arc
						(start 343.759536 -50.14722)
						(mid 343.611754 -50.067418)
						(end 343.531952 -49.919636)
					)
				)
			)
		)
		(zone
			(layer "F.Cu")
			(hatch none 0.5)
			(connect_pads
				(clearance 0)
			)
			(min_thickness 0.25)
			(keepout
				(tracks not_allowed)
				(vias allowed)
				(pads allowed)
				(copperpour not_allowed)
				(footprints allowed)
			)
			(placement
				(enabled no)
				(sheetname "")
			)
			(fill
				(thermal_gap 0.5)
				(thermal_bridge_width 0.5)
				(island_removal_mode 0)
			)
			(polygon
				(pts
					(arc
						(start 343.637362 -48.979836)
						(mid 343.683877 -49.055578)
						(end 343.759536 -49.102264)
					)
					(arc
						(start 343.759536 -49.20742)
						(mid 343.611754 -49.127618)
						(end 343.531952 -48.979836)
					)
				)
			)
		)
		(zone
			(layer "F.Cu")
			(hatch none 0.5)
			(connect_pads
				(clearance 0)
			)
			(min_thickness 0.25)
			(keepout
				(tracks not_allowed)
				(vias allowed)
				(pads allowed)
				(copperpour not_allowed)
				(footprints allowed)
			)
			(placement
				(enabled no)
				(sheetname "")
			)
			(fill
				(thermal_gap 0.5)
				(thermal_bridge_width 0.5)
				(island_removal_mode 0)
			)
			(polygon
				(pts
					(arc
						(start 343.637362 -48.040036)
						(mid 343.683877 -48.115778)
						(end 343.759536 -48.162464)
					)
					(arc
						(start 343.759536 -48.26762)
						(mid 343.611754 -48.187818)
						(end 343.531952 -48.040036)
					)
				)
			)
		)
		(zone
			(layer "F.Cu")
			(hatch none 0.5)
			(connect_pads
				(clearance 0)
			)
			(min_thickness 0.25)
			(keepout
				(tracks not_allowed)
				(vias allowed)
				(pads allowed)
				(copperpour not_allowed)
				(footprints allowed)
			)
			(placement
				(enabled no)
				(sheetname "")
			)
			(fill
				(thermal_gap 0.5)
				(thermal_bridge_width 0.5)
				(island_removal_mode 0)
			)
			(polygon
				(pts
					(arc
						(start 343.637362 -47.100236)
						(mid 343.683877 -47.175978)
						(end 343.759536 -47.222664)
					)
					(arc
						(start 343.759536 -47.32782)
						(mid 343.611754 -47.248018)
						(end 343.531952 -47.100236)
					)
				)
			)
		)
		(zone
			(layer "F.Cu")
			(hatch none 0.5)
			(connect_pads
				(clearance 0)
			)
			(min_thickness 0.25)
			(keepout
				(tracks not_allowed)
				(vias allowed)
				(pads allowed)
				(copperpour not_allowed)
				(footprints allowed)
			)
			(placement
				(enabled no)
				(sheetname "")
			)
			(fill
				(thermal_gap 0.5)
				(thermal_bridge_width 0.5)
				(island_removal_mode 0)
			)
			(polygon
				(pts
					(arc
						(start 343.637362 -46.160436)
						(mid 343.683877 -46.236178)
						(end 343.759536 -46.282864)
					)
					(arc
						(start 343.759536 -46.38802)
						(mid 343.611754 -46.308218)
						(end 343.531952 -46.160436)
					)
				)
			)
		)
		(zone
			(layer "F.Cu")
			(hatch none 0.5)
			(connect_pads
				(clearance 0)
			)
			(min_thickness 0.25)
			(keepout
				(tracks not_allowed)
				(vias allowed)
				(pads allowed)
				(copperpour not_allowed)
				(footprints allowed)
			)
			(placement
				(enabled no)
				(sheetname "")
			)
			(fill
				(thermal_gap 0.5)
				(thermal_bridge_width 0.5)
				(island_removal_mode 0)
			)
			(polygon
				(pts
					(arc
						(start 343.637362 -45.220636)
						(mid 343.683877 -45.296378)
						(end 343.759536 -45.343064)
					)
					(arc
						(start 343.759536 -45.44822)
						(mid 343.611754 -45.368418)
						(end 343.531952 -45.220636)
					)
				)
			)
		)
		(zone
			(layer "F.Cu")
			(hatch none 0.5)
			(connect_pads
				(clearance 0)
			)
			(min_thickness 0.25)
			(keepout
				(tracks not_allowed)
				(vias allowed)
				(pads allowed)
				(copperpour not_allowed)
				(footprints allowed)
			)
			(placement
				(enabled no)
				(sheetname "")
			)
			(fill
				(thermal_gap 0.5)
				(thermal_bridge_width 0.5)
				(island_removal_mode 0)
			)
			(polygon
				(pts
					(arc
						(start 343.637362 -44.280836)
						(mid 343.683877 -44.356578)
						(end 343.759536 -44.403264)
					)
					(arc
						(start 343.759536 -44.50842)
						(mid 343.611754 -44.428618)
						(end 343.531952 -44.280836)
					)
				)
			)
		)
		(zone
			(layer "F.Cu")
			(hatch none 0.5)
			(connect_pads
				(clearance 0)
			)
			(min_thickness 0.25)
			(keepout
				(tracks not_allowed)
				(vias allowed)
				(pads allowed)
				(copperpour not_allowed)
				(footprints allowed)
			)
			(placement
				(enabled no)
				(sheetname "")
			)
			(fill
				(thermal_gap 0.5)
				(thermal_bridge_width 0.5)
				(island_removal_mode 0)
			)
			(polygon
				(pts
					(arc
						(start 343.637362 -43.341036)
						(mid 343.683877 -43.416778)
						(end 343.759536 -43.463464)
					)
					(arc
						(start 343.759536 -43.56862)
						(mid 343.611754 -43.488818)
						(end 343.531952 -43.341036)
					)
				)
			)
		)
		(zone
			(layer "F.Cu")
			(hatch none 0.5)
			(connect_pads
				(clearance 0)
			)
			(min_thickness 0.25)
			(keepout
				(tracks not_allowed)
				(vias allowed)
				(pads allowed)
				(copperpour not_allowed)
				(footprints allowed)
			)
			(placement
				(enabled no)
				(sheetname "")
			)
			(fill
				(thermal_gap 0.5)
				(thermal_bridge_width 0.5)
				(island_removal_mode 0)
			)
			(polygon
				(pts
					(arc
						(start 343.637362 -42.401236)
						(mid 343.683877 -42.476978)
						(end 343.759536 -42.523664)
					)
					(arc
						(start 343.759536 -42.62882)
						(mid 343.611754 -42.549018)
						(end 343.531952 -42.401236)
					)
				)
			)
		)
		(zone
			(layer "F.Cu")
			(hatch none 0.5)
			(connect_pads
				(clearance 0)
			)
			(min_thickness 0.25)
			(keepout
				(tracks not_allowed)
				(vias allowed)
				(pads allowed)
				(copperpour not_allowed)
				(footprints allowed)
			)
			(placement
				(enabled no)
				(sheetname "")
			)
			(fill
				(thermal_gap 0.5)
				(thermal_bridge_width 0.5)
				(island_removal_mode 0)
			)
			(polygon
				(pts
					(arc
						(start 343.637362 -41.461436)
						(mid 343.683877 -41.537178)
						(end 343.759536 -41.583864)
					)
					(arc
						(start 343.759536 -41.68902)
						(mid 343.611754 -41.609218)
						(end 343.531952 -41.461436)
					)
				)
			)
		)
		(zone
			(layer "F.Cu")
			(hatch none 0.5)
			(connect_pads
				(clearance 0)
			)
			(min_thickness 0.25)
			(keepout
				(tracks not_allowed)
				(vias allowed)
				(pads allowed)
				(copperpour not_allowed)
				(footprints allowed)
			)
			(placement
				(enabled no)
				(sheetname "")
			)
			(fill
				(thermal_gap 0.5)
				(thermal_bridge_width 0.5)
				(island_removal_mode 0)
			)
			(polygon
				(pts
					(arc
						(start 343.637362 -40.521636)
						(mid 343.683877 -40.597378)
						(end 343.759536 -40.644064)
					)
					(arc
						(start 343.759536 -40.74922)
						(mid 343.611754 -40.669418)
						(end 343.531952 -40.521636)
					)
				)
			)
		)
		(zone
			(layer "F.Cu")
			(hatch none 0.5)
			(connect_pads
				(clearance 0)
			)
			(min_thickness 0.25)
			(keepout
				(tracks not_allowed)
				(vias allowed)
				(pads allowed)
				(copperpour not_allowed)
				(footprints allowed)
			)
			(placement
				(enabled no)
				(sheetname "")
			)
			(fill
				(thermal_gap 0.5)
				(thermal_bridge_width 0.5)
				(island_removal_mode 0)
			)
			(polygon
				(pts
					(arc
						(start 343.759536 -56.256428)
						(mid 343.683821 -56.303058)
						(end 343.637362 -56.378856)
					)
					(arc
						(start 343.531952 -56.378856)
						(mid 343.611754 -56.231074)
						(end 343.759536 -56.151272)
					)
				)
			)
		)
		(zone
			(layer "F.Cu")
			(hatch none 0.5)
			(connect_pads
				(clearance 0)
			)
			(min_thickness 0.25)
			(keepout
				(tracks not_allowed)
				(vias allowed)
				(pads allowed)
				(copperpour not_allowed)
				(footprints allowed)
			)
			(placement
				(enabled no)
				(sheetname "")
			)
			(fill
				(thermal_gap 0.5)
				(thermal_bridge_width 0.5)
				(island_removal_mode 0)
			)
			(polygon
				(pts
					(arc
						(start 343.759536 -55.316628)
						(mid 343.683821 -55.363258)
						(end 343.637362 -55.439056)
					)
					(arc
						(start 343.531952 -55.439056)
						(mid 343.611754 -55.291274)
						(end 343.759536 -55.211472)
					)
				)
			)
		)
		(zone
			(layer "F.Cu")
			(hatch none 0.5)
			(connect_pads
				(clearance 0)
			)
			(min_thickness 0.25)
			(keepout
				(tracks not_allowed)
				(vias allowed)
				(pads allowed)
				(copperpour not_allowed)
				(footprints allowed)
			)
			(placement
				(enabled no)
				(sheetname "")
			)
			(fill
				(thermal_gap 0.5)
				(thermal_bridge_width 0.5)
				(island_removal_mode 0)
			)
			(polygon
				(pts
					(arc
						(start 343.759536 -54.376828)
						(mid 343.683821 -54.423458)
						(end 343.637362 -54.499256)
					)
					(arc
						(start 343.531952 -54.499256)
						(mid 343.611754 -54.351474)
						(end 343.759536 -54.271672)
					)
				)
			)
		)
		(zone
			(layer "F.Cu")
			(hatch none 0.5)
			(connect_pads
				(clearance 0)
			)
			(min_thickness 0.25)
			(keepout
				(tracks not_allowed)
				(vias allowed)
				(pads allowed)
				(copperpour not_allowed)
				(footprints allowed)
			)
			(placement
				(enabled no)
				(sheetname "")
			)
			(fill
				(thermal_gap 0.5)
				(thermal_bridge_width 0.5)
				(island_removal_mode 0)
			)
			(polygon
				(pts
					(arc
						(start 343.759536 -53.437028)
						(mid 343.683821 -53.483658)
						(end 343.637362 -53.559456)
					)
					(arc
						(start 343.531952 -53.559456)
						(mid 343.611754 -53.411674)
						(end 343.759536 -53.331872)
					)
				)
			)
		)
		(zone
			(layer "F.Cu")
			(hatch none 0.5)
			(connect_pads
				(clearance 0)
			)
			(min_thickness 0.25)
			(keepout
				(tracks not_allowed)
				(vias allowed)
				(pads allowed)
				(copperpour not_allowed)
				(footprints allowed)
			)
			(placement
				(enabled no)
				(sheetname "")
			)
			(fill
				(thermal_gap 0.5)
				(thermal_bridge_width 0.5)
				(island_removal_mode 0)
			)
			(polygon
				(pts
					(arc
						(start 343.759536 -52.497228)
						(mid 343.683821 -52.543858)
						(end 343.637362 -52.619656)
					)
					(arc
						(start 343.531952 -52.619656)
						(mid 343.611754 -52.471874)
						(end 343.759536 -52.392072)
					)
				)
			)
		)
		(zone
			(layer "F.Cu")
			(hatch none 0.5)
			(connect_pads
				(clearance 0)
			)
			(min_thickness 0.25)
			(keepout
				(tracks not_allowed)
				(vias allowed)
				(pads allowed)
				(copperpour not_allowed)
				(footprints allowed)
			)
			(placement
				(enabled no)
				(sheetname "")
			)
			(fill
				(thermal_gap 0.5)
				(thermal_bridge_width 0.5)
				(island_removal_mode 0)
			)
			(polygon
				(pts
					(arc
						(start 343.759536 -51.557428)
						(mid 343.683821 -51.604058)
						(end 343.637362 -51.679856)
					)
					(arc
						(start 343.531952 -51.679856)
						(mid 343.611754 -51.532074)
						(end 343.759536 -51.452272)
					)
				)
			)
		)
		(zone
			(layer "F.Cu")
			(hatch none 0.5)
			(connect_pads
				(clearance 0)
			)
			(min_thickness 0.25)
			(keepout
				(tracks not_allowed)
				(vias allowed)
				(pads allowed)
				(copperpour not_allowed)
				(footprints allowed)
			)
			(placement
				(enabled no)
				(sheetname "")
			)
			(fill
				(thermal_gap 0.5)
				(thermal_bridge_width 0.5)
				(island_removal_mode 0)
			)
			(polygon
				(pts
					(arc
						(start 343.759536 -50.617628)
						(mid 343.683821 -50.664258)
						(end 343.637362 -50.740056)
					)
					(arc
						(start 343.531952 -50.740056)
						(mid 343.611754 -50.592274)
						(end 343.759536 -50.512472)
					)
				)
			)
		)
		(zone
			(layer "F.Cu")
			(hatch none 0.5)
			(connect_pads
				(clearance 0)
			)
			(min_thickness 0.25)
			(keepout
				(tracks not_allowed)
				(vias allowed)
				(pads allowed)
				(copperpour not_allowed)
				(footprints allowed)
			)
			(placement
				(enabled no)
				(sheetname "")
			)
			(fill
				(thermal_gap 0.5)
				(thermal_bridge_width 0.5)
				(island_removal_mode 0)
			)
			(polygon
				(pts
					(arc
						(start 343.759536 -49.677828)
						(mid 343.683821 -49.724458)
						(end 343.637362 -49.800256)
					)
					(arc
						(start 343.531952 -49.800256)
						(mid 343.611754 -49.652474)
						(end 343.759536 -49.572672)
					)
				)
			)
		)
		(zone
			(layer "F.Cu")
			(hatch none 0.5)
			(connect_pads
				(clearance 0)
			)
			(min_thickness 0.25)
			(keepout
				(tracks not_allowed)
				(vias allowed)
				(pads allowed)
				(copperpour not_allowed)
				(footprints allowed)
			)
			(placement
				(enabled no)
				(sheetname "")
			)
			(fill
				(thermal_gap 0.5)
				(thermal_bridge_width 0.5)
				(island_removal_mode 0)
			)
			(polygon
				(pts
					(arc
						(start 343.759536 -48.738028)
						(mid 343.683821 -48.784658)
						(end 343.637362 -48.860456)
					)
					(arc
						(start 343.531952 -48.860456)
						(mid 343.611754 -48.712674)
						(end 343.759536 -48.632872)
					)
				)
			)
		)
		(zone
			(layer "F.Cu")
			(hatch none 0.5)
			(connect_pads
				(clearance 0)
			)
			(min_thickness 0.25)
			(keepout
				(tracks not_allowed)
				(vias allowed)
				(pads allowed)
				(copperpour not_allowed)
				(footprints allowed)
			)
			(placement
				(enabled no)
				(sheetname "")
			)
			(fill
				(thermal_gap 0.5)
				(thermal_bridge_width 0.5)
				(island_removal_mode 0)
			)
			(polygon
				(pts
					(arc
						(start 343.759536 -47.798228)
						(mid 343.683821 -47.844858)
						(end 343.637362 -47.920656)
					)
					(arc
						(start 343.531952 -47.920656)
						(mid 343.611754 -47.772874)
						(end 343.759536 -47.693072)
					)
				)
			)
		)
		(zone
			(layer "F.Cu")
			(hatch none 0.5)
			(connect_pads
				(clearance 0)
			)
			(min_thickness 0.25)
			(keepout
				(tracks not_allowed)
				(vias allowed)
				(pads allowed)
				(copperpour not_allowed)
				(footprints allowed)
			)
			(placement
				(enabled no)
				(sheetname "")
			)
			(fill
				(thermal_gap 0.5)
				(thermal_bridge_width 0.5)
				(island_removal_mode 0)
			)
			(polygon
				(pts
					(arc
						(start 343.759536 -46.858428)
						(mid 343.683821 -46.905058)
						(end 343.637362 -46.980856)
					)
					(arc
						(start 343.531952 -46.980856)
						(mid 343.611754 -46.833074)
						(end 343.759536 -46.753272)
					)
				)
			)
		)
		(zone
			(layer "F.Cu")
			(hatch none 0.5)
			(connect_pads
				(clearance 0)
			)
			(min_thickness 0.25)
			(keepout
				(tracks not_allowed)
				(vias allowed)
				(pads allowed)
				(copperpour not_allowed)
				(footprints allowed)
			)
			(placement
				(enabled no)
				(sheetname "")
			)
			(fill
				(thermal_gap 0.5)
				(thermal_bridge_width 0.5)
				(island_removal_mode 0)
			)
			(polygon
				(pts
					(arc
						(start 343.759536 -45.918628)
						(mid 343.683821 -45.965258)
						(end 343.637362 -46.041056)
					)
					(arc
						(start 343.531952 -46.041056)
						(mid 343.611754 -45.893274)
						(end 343.759536 -45.813472)
					)
				)
			)
		)
		(zone
			(layer "F.Cu")
			(hatch none 0.5)
			(connect_pads
				(clearance 0)
			)
			(min_thickness 0.25)
			(keepout
				(tracks not_allowed)
				(vias allowed)
				(pads allowed)
				(copperpour not_allowed)
				(footprints allowed)
			)
			(placement
				(enabled no)
				(sheetname "")
			)
			(fill
				(thermal_gap 0.5)
				(thermal_bridge_width 0.5)
				(island_removal_mode 0)
			)
			(polygon
				(pts
					(arc
						(start 343.759536 -44.978828)
						(mid 343.683821 -45.025458)
						(end 343.637362 -45.101256)
					)
					(arc
						(start 343.531952 -45.101256)
						(mid 343.611754 -44.953474)
						(end 343.759536 -44.873672)
					)
				)
			)
		)
		(zone
			(layer "F.Cu")
			(hatch none 0.5)
			(connect_pads
				(clearance 0)
			)
			(min_thickness 0.25)
			(keepout
				(tracks not_allowed)
				(vias allowed)
				(pads allowed)
				(copperpour not_allowed)
				(footprints allowed)
			)
			(placement
				(enabled no)
				(sheetname "")
			)
			(fill
				(thermal_gap 0.5)
				(thermal_bridge_width 0.5)
				(island_removal_mode 0)
			)
			(polygon
				(pts
					(arc
						(start 343.759536 -44.039028)
						(mid 343.683821 -44.085658)
						(end 343.637362 -44.161456)
					)
					(arc
						(start 343.531952 -44.161456)
						(mid 343.611754 -44.013674)
						(end 343.759536 -43.933872)
					)
				)
			)
		)
		(zone
			(layer "F.Cu")
			(hatch none 0.5)
			(connect_pads
				(clearance 0)
			)
			(min_thickness 0.25)
			(keepout
				(tracks not_allowed)
				(vias allowed)
				(pads allowed)
				(copperpour not_allowed)
				(footprints allowed)
			)
			(placement
				(enabled no)
				(sheetname "")
			)
			(fill
				(thermal_gap 0.5)
				(thermal_bridge_width 0.5)
				(island_removal_mode 0)
			)
			(polygon
				(pts
					(arc
						(start 343.759536 -43.099228)
						(mid 343.683821 -43.145858)
						(end 343.637362 -43.221656)
					)
					(arc
						(start 343.531952 -43.221656)
						(mid 343.611754 -43.073874)
						(end 343.759536 -42.994072)
					)
				)
			)
		)
		(zone
			(layer "F.Cu")
			(hatch none 0.5)
			(connect_pads
				(clearance 0)
			)
			(min_thickness 0.25)
			(keepout
				(tracks not_allowed)
				(vias allowed)
				(pads allowed)
				(copperpour not_allowed)
				(footprints allowed)
			)
			(placement
				(enabled no)
				(sheetname "")
			)
			(fill
				(thermal_gap 0.5)
				(thermal_bridge_width 0.5)
				(island_removal_mode 0)
			)
			(polygon
				(pts
					(arc
						(start 343.759536 -42.159428)
						(mid 343.683821 -42.206058)
						(end 343.637362 -42.281856)
					)
					(arc
						(start 343.531952 -42.281856)
						(mid 343.611754 -42.134074)
						(end 343.759536 -42.054272)
					)
				)
			)
		)
		(zone
			(layer "F.Cu")
			(hatch none 0.5)
			(connect_pads
				(clearance 0)
			)
			(min_thickness 0.25)
			(keepout
				(tracks not_allowed)
				(vias allowed)
				(pads allowed)
				(copperpour not_allowed)
				(footprints allowed)
			)
			(placement
				(enabled no)
				(sheetname "")
			)
			(fill
				(thermal_gap 0.5)
				(thermal_bridge_width 0.5)
				(island_removal_mode 0)
			)
			(polygon
				(pts
					(arc
						(start 343.759536 -41.219628)
						(mid 343.683821 -41.266258)
						(end 343.637362 -41.342056)
					)
					(arc
						(start 343.531952 -41.342056)
						(mid 343.611754 -41.194274)
						(end 343.759536 -41.114472)
					)
				)
			)
		)
		(zone
			(layer "F.Cu")
			(hatch none 0.5)
			(connect_pads
				(clearance 0)
			)
			(min_thickness 0.25)
			(keepout
				(tracks not_allowed)
				(vias allowed)
				(pads allowed)
				(copperpour not_allowed)
				(footprints allowed)
			)
			(placement
				(enabled no)
				(sheetname "")
			)
			(fill
				(thermal_gap 0.5)
				(thermal_bridge_width 0.5)
				(island_removal_mode 0)
			)
			(polygon
				(pts
					(arc
						(start 343.759536 -40.279828)
						(mid 343.683821 -40.326458)
						(end 343.637362 -40.402256)
					)
					(arc
						(start 343.531952 -40.402256)
						(mid 343.611754 -40.254474)
						(end 343.759536 -40.174672)
					)
				)
			)
		)
		(zone
			(layer "F.Cu")
			(hatch none 0.5)
			(connect_pads
				(clearance 0)
			)
			(min_thickness 0.25)
			(keepout
				(tracks not_allowed)
				(vias allowed)
				(pads allowed)
				(copperpour not_allowed)
				(footprints allowed)
			)
			(placement
				(enabled no)
				(sheetname "")
			)
			(fill
				(thermal_gap 0.5)
				(thermal_bridge_width 0.5)
				(island_removal_mode 0)
			)
			(polygon
				(pts
					(arc
						(start 343.87917 -56.620664)
						(mid 343.954885 -56.574034)
						(end 344.001344 -56.498236)
					)
					(arc
						(start 344.106754 -56.498236)
						(mid 344.026952 -56.646018)
						(end 343.87917 -56.72582)
					)
				)
			)
		)
		(zone
			(layer "F.Cu")
			(hatch none 0.5)
			(connect_pads
				(clearance 0)
			)
			(min_thickness 0.25)
			(keepout
				(tracks not_allowed)
				(vias allowed)
				(pads allowed)
				(copperpour not_allowed)
				(footprints allowed)
			)
			(placement
				(enabled no)
				(sheetname "")
			)
			(fill
				(thermal_gap 0.5)
				(thermal_bridge_width 0.5)
				(island_removal_mode 0)
			)
			(polygon
				(pts
					(arc
						(start 343.87917 -55.680864)
						(mid 343.954885 -55.634234)
						(end 344.001344 -55.558436)
					)
					(arc
						(start 344.106754 -55.558436)
						(mid 344.026952 -55.706218)
						(end 343.87917 -55.78602)
					)
				)
			)
		)
		(zone
			(layer "F.Cu")
			(hatch none 0.5)
			(connect_pads
				(clearance 0)
			)
			(min_thickness 0.25)
			(keepout
				(tracks not_allowed)
				(vias allowed)
				(pads allowed)
				(copperpour not_allowed)
				(footprints allowed)
			)
			(placement
				(enabled no)
				(sheetname "")
			)
			(fill
				(thermal_gap 0.5)
				(thermal_bridge_width 0.5)
				(island_removal_mode 0)
			)
			(polygon
				(pts
					(arc
						(start 343.87917 -54.741064)
						(mid 343.954885 -54.694434)
						(end 344.001344 -54.618636)
					)
					(arc
						(start 344.106754 -54.618636)
						(mid 344.026952 -54.766418)
						(end 343.87917 -54.84622)
					)
				)
			)
		)
		(zone
			(layer "F.Cu")
			(hatch none 0.5)
			(connect_pads
				(clearance 0)
			)
			(min_thickness 0.25)
			(keepout
				(tracks not_allowed)
				(vias allowed)
				(pads allowed)
				(copperpour not_allowed)
				(footprints allowed)
			)
			(placement
				(enabled no)
				(sheetname "")
			)
			(fill
				(thermal_gap 0.5)
				(thermal_bridge_width 0.5)
				(island_removal_mode 0)
			)
			(polygon
				(pts
					(arc
						(start 343.87917 -53.801264)
						(mid 343.954885 -53.754634)
						(end 344.001344 -53.678836)
					)
					(arc
						(start 344.106754 -53.678836)
						(mid 344.026952 -53.826618)
						(end 343.87917 -53.90642)
					)
				)
			)
		)
		(zone
			(layer "F.Cu")
			(hatch none 0.5)
			(connect_pads
				(clearance 0)
			)
			(min_thickness 0.25)
			(keepout
				(tracks not_allowed)
				(vias allowed)
				(pads allowed)
				(copperpour not_allowed)
				(footprints allowed)
			)
			(placement
				(enabled no)
				(sheetname "")
			)
			(fill
				(thermal_gap 0.5)
				(thermal_bridge_width 0.5)
				(island_removal_mode 0)
			)
			(polygon
				(pts
					(arc
						(start 343.87917 -52.861464)
						(mid 343.954885 -52.814834)
						(end 344.001344 -52.739036)
					)
					(arc
						(start 344.106754 -52.739036)
						(mid 344.026952 -52.886818)
						(end 343.87917 -52.96662)
					)
				)
			)
		)
		(zone
			(layer "F.Cu")
			(hatch none 0.5)
			(connect_pads
				(clearance 0)
			)
			(min_thickness 0.25)
			(keepout
				(tracks not_allowed)
				(vias allowed)
				(pads allowed)
				(copperpour not_allowed)
				(footprints allowed)
			)
			(placement
				(enabled no)
				(sheetname "")
			)
			(fill
				(thermal_gap 0.5)
				(thermal_bridge_width 0.5)
				(island_removal_mode 0)
			)
			(polygon
				(pts
					(arc
						(start 343.87917 -51.921664)
						(mid 343.954885 -51.875034)
						(end 344.001344 -51.799236)
					)
					(arc
						(start 344.106754 -51.799236)
						(mid 344.026952 -51.947018)
						(end 343.87917 -52.02682)
					)
				)
			)
		)
		(zone
			(layer "F.Cu")
			(hatch none 0.5)
			(connect_pads
				(clearance 0)
			)
			(min_thickness 0.25)
			(keepout
				(tracks not_allowed)
				(vias allowed)
				(pads allowed)
				(copperpour not_allowed)
				(footprints allowed)
			)
			(placement
				(enabled no)
				(sheetname "")
			)
			(fill
				(thermal_gap 0.5)
				(thermal_bridge_width 0.5)
				(island_removal_mode 0)
			)
			(polygon
				(pts
					(arc
						(start 343.87917 -50.981864)
						(mid 343.954885 -50.935234)
						(end 344.001344 -50.859436)
					)
					(arc
						(start 344.106754 -50.859436)
						(mid 344.026952 -51.007218)
						(end 343.87917 -51.08702)
					)
				)
			)
		)
		(zone
			(layer "F.Cu")
			(hatch none 0.5)
			(connect_pads
				(clearance 0)
			)
			(min_thickness 0.25)
			(keepout
				(tracks not_allowed)
				(vias allowed)
				(pads allowed)
				(copperpour not_allowed)
				(footprints allowed)
			)
			(placement
				(enabled no)
				(sheetname "")
			)
			(fill
				(thermal_gap 0.5)
				(thermal_bridge_width 0.5)
				(island_removal_mode 0)
			)
			(polygon
				(pts
					(arc
						(start 343.87917 -50.042064)
						(mid 343.954885 -49.995434)
						(end 344.001344 -49.919636)
					)
					(arc
						(start 344.106754 -49.919636)
						(mid 344.026952 -50.067418)
						(end 343.87917 -50.14722)
					)
				)
			)
		)
		(zone
			(layer "F.Cu")
			(hatch none 0.5)
			(connect_pads
				(clearance 0)
			)
			(min_thickness 0.25)
			(keepout
				(tracks not_allowed)
				(vias allowed)
				(pads allowed)
				(copperpour not_allowed)
				(footprints allowed)
			)
			(placement
				(enabled no)
				(sheetname "")
			)
			(fill
				(thermal_gap 0.5)
				(thermal_bridge_width 0.5)
				(island_removal_mode 0)
			)
			(polygon
				(pts
					(arc
						(start 343.87917 -49.102264)
						(mid 343.954885 -49.055634)
						(end 344.001344 -48.979836)
					)
					(arc
						(start 344.106754 -48.979836)
						(mid 344.026952 -49.127618)
						(end 343.87917 -49.20742)
					)
				)
			)
		)
		(zone
			(layer "F.Cu")
			(hatch none 0.5)
			(connect_pads
				(clearance 0)
			)
			(min_thickness 0.25)
			(keepout
				(tracks not_allowed)
				(vias allowed)
				(pads allowed)
				(copperpour not_allowed)
				(footprints allowed)
			)
			(placement
				(enabled no)
				(sheetname "")
			)
			(fill
				(thermal_gap 0.5)
				(thermal_bridge_width 0.5)
				(island_removal_mode 0)
			)
			(polygon
				(pts
					(arc
						(start 343.87917 -48.162464)
						(mid 343.954885 -48.115834)
						(end 344.001344 -48.040036)
					)
					(arc
						(start 344.106754 -48.040036)
						(mid 344.026952 -48.187818)
						(end 343.87917 -48.26762)
					)
				)
			)
		)
		(zone
			(layer "F.Cu")
			(hatch none 0.5)
			(connect_pads
				(clearance 0)
			)
			(min_thickness 0.25)
			(keepout
				(tracks not_allowed)
				(vias allowed)
				(pads allowed)
				(copperpour not_allowed)
				(footprints allowed)
			)
			(placement
				(enabled no)
				(sheetname "")
			)
			(fill
				(thermal_gap 0.5)
				(thermal_bridge_width 0.5)
				(island_removal_mode 0)
			)
			(polygon
				(pts
					(arc
						(start 343.87917 -47.222664)
						(mid 343.954885 -47.176034)
						(end 344.001344 -47.100236)
					)
					(arc
						(start 344.106754 -47.100236)
						(mid 344.026952 -47.248018)
						(end 343.87917 -47.32782)
					)
				)
			)
		)
		(zone
			(layer "F.Cu")
			(hatch none 0.5)
			(connect_pads
				(clearance 0)
			)
			(min_thickness 0.25)
			(keepout
				(tracks not_allowed)
				(vias allowed)
				(pads allowed)
				(copperpour not_allowed)
				(footprints allowed)
			)
			(placement
				(enabled no)
				(sheetname "")
			)
			(fill
				(thermal_gap 0.5)
				(thermal_bridge_width 0.5)
				(island_removal_mode 0)
			)
			(polygon
				(pts
					(arc
						(start 343.87917 -46.282864)
						(mid 343.954885 -46.236234)
						(end 344.001344 -46.160436)
					)
					(arc
						(start 344.106754 -46.160436)
						(mid 344.026952 -46.308218)
						(end 343.87917 -46.38802)
					)
				)
			)
		)
		(zone
			(layer "F.Cu")
			(hatch none 0.5)
			(connect_pads
				(clearance 0)
			)
			(min_thickness 0.25)
			(keepout
				(tracks not_allowed)
				(vias allowed)
				(pads allowed)
				(copperpour not_allowed)
				(footprints allowed)
			)
			(placement
				(enabled no)
				(sheetname "")
			)
			(fill
				(thermal_gap 0.5)
				(thermal_bridge_width 0.5)
				(island_removal_mode 0)
			)
			(polygon
				(pts
					(arc
						(start 343.87917 -45.343064)
						(mid 343.954885 -45.296434)
						(end 344.001344 -45.220636)
					)
					(arc
						(start 344.106754 -45.220636)
						(mid 344.026952 -45.368418)
						(end 343.87917 -45.44822)
					)
				)
			)
		)
		(zone
			(layer "F.Cu")
			(hatch none 0.5)
			(connect_pads
				(clearance 0)
			)
			(min_thickness 0.25)
			(keepout
				(tracks not_allowed)
				(vias allowed)
				(pads allowed)
				(copperpour not_allowed)
				(footprints allowed)
			)
			(placement
				(enabled no)
				(sheetname "")
			)
			(fill
				(thermal_gap 0.5)
				(thermal_bridge_width 0.5)
				(island_removal_mode 0)
			)
			(polygon
				(pts
					(arc
						(start 343.87917 -44.403264)
						(mid 343.954885 -44.356634)
						(end 344.001344 -44.280836)
					)
					(arc
						(start 344.106754 -44.280836)
						(mid 344.026952 -44.428618)
						(end 343.87917 -44.50842)
					)
				)
			)
		)
		(zone
			(layer "F.Cu")
			(hatch none 0.5)
			(connect_pads
				(clearance 0)
			)
			(min_thickness 0.25)
			(keepout
				(tracks not_allowed)
				(vias allowed)
				(pads allowed)
				(copperpour not_allowed)
				(footprints allowed)
			)
			(placement
				(enabled no)
				(sheetname "")
			)
			(fill
				(thermal_gap 0.5)
				(thermal_bridge_width 0.5)
				(island_removal_mode 0)
			)
			(polygon
				(pts
					(arc
						(start 343.87917 -43.463464)
						(mid 343.954885 -43.416834)
						(end 344.001344 -43.341036)
					)
					(arc
						(start 344.106754 -43.341036)
						(mid 344.026952 -43.488818)
						(end 343.87917 -43.56862)
					)
				)
			)
		)
		(zone
			(layer "F.Cu")
			(hatch none 0.5)
			(connect_pads
				(clearance 0)
			)
			(min_thickness 0.25)
			(keepout
				(tracks not_allowed)
				(vias allowed)
				(pads allowed)
				(copperpour not_allowed)
				(footprints allowed)
			)
			(placement
				(enabled no)
				(sheetname "")
			)
			(fill
				(thermal_gap 0.5)
				(thermal_bridge_width 0.5)
				(island_removal_mode 0)
			)
			(polygon
				(pts
					(arc
						(start 343.87917 -42.523664)
						(mid 343.954885 -42.477034)
						(end 344.001344 -42.401236)
					)
					(arc
						(start 344.106754 -42.401236)
						(mid 344.026952 -42.549018)
						(end 343.87917 -42.62882)
					)
				)
			)
		)
		(zone
			(layer "F.Cu")
			(hatch none 0.5)
			(connect_pads
				(clearance 0)
			)
			(min_thickness 0.25)
			(keepout
				(tracks not_allowed)
				(vias allowed)
				(pads allowed)
				(copperpour not_allowed)
				(footprints allowed)
			)
			(placement
				(enabled no)
				(sheetname "")
			)
			(fill
				(thermal_gap 0.5)
				(thermal_bridge_width 0.5)
				(island_removal_mode 0)
			)
			(polygon
				(pts
					(arc
						(start 343.87917 -41.583864)
						(mid 343.954885 -41.537234)
						(end 344.001344 -41.461436)
					)
					(arc
						(start 344.106754 -41.461436)
						(mid 344.026952 -41.609218)
						(end 343.87917 -41.68902)
					)
				)
			)
		)
		(zone
			(layer "F.Cu")
			(hatch none 0.5)
			(connect_pads
				(clearance 0)
			)
			(min_thickness 0.25)
			(keepout
				(tracks not_allowed)
				(vias allowed)
				(pads allowed)
				(copperpour not_allowed)
				(footprints allowed)
			)
			(placement
				(enabled no)
				(sheetname "")
			)
			(fill
				(thermal_gap 0.5)
				(thermal_bridge_width 0.5)
				(island_removal_mode 0)
			)
			(polygon
				(pts
					(arc
						(start 343.87917 -40.644064)
						(mid 343.954885 -40.597434)
						(end 344.001344 -40.521636)
					)
					(arc
						(start 344.106754 -40.521636)
						(mid 344.026952 -40.669418)
						(end 343.87917 -40.74922)
					)
				)
			)
		)
		(zone
			(layer "F.Cu")
			(hatch none 0.5)
			(connect_pads
				(clearance 0)
			)
			(min_thickness 0.25)
			(keepout
				(tracks not_allowed)
				(vias allowed)
				(pads allowed)
				(copperpour not_allowed)
				(footprints allowed)
			)
			(placement
				(enabled no)
				(sheetname "")
			)
			(fill
				(thermal_gap 0.5)
				(thermal_bridge_width 0.5)
				(island_removal_mode 0)
			)
			(polygon
				(pts
					(arc
						(start 344.001344 -56.378856)
						(mid 343.954829 -56.303114)
						(end 343.87917 -56.256428)
					)
					(arc
						(start 343.87917 -56.151272)
						(mid 344.026952 -56.231074)
						(end 344.106754 -56.378856)
					)
				)
			)
		)
		(zone
			(layer "F.Cu")
			(hatch none 0.5)
			(connect_pads
				(clearance 0)
			)
			(min_thickness 0.25)
			(keepout
				(tracks not_allowed)
				(vias allowed)
				(pads allowed)
				(copperpour not_allowed)
				(footprints allowed)
			)
			(placement
				(enabled no)
				(sheetname "")
			)
			(fill
				(thermal_gap 0.5)
				(thermal_bridge_width 0.5)
				(island_removal_mode 0)
			)
			(polygon
				(pts
					(arc
						(start 344.001344 -55.439056)
						(mid 343.954829 -55.363314)
						(end 343.87917 -55.316628)
					)
					(arc
						(start 343.87917 -55.211472)
						(mid 344.026952 -55.291274)
						(end 344.106754 -55.439056)
					)
				)
			)
		)
		(zone
			(layer "F.Cu")
			(hatch none 0.5)
			(connect_pads
				(clearance 0)
			)
			(min_thickness 0.25)
			(keepout
				(tracks not_allowed)
				(vias allowed)
				(pads allowed)
				(copperpour not_allowed)
				(footprints allowed)
			)
			(placement
				(enabled no)
				(sheetname "")
			)
			(fill
				(thermal_gap 0.5)
				(thermal_bridge_width 0.5)
				(island_removal_mode 0)
			)
			(polygon
				(pts
					(arc
						(start 344.001344 -54.499256)
						(mid 343.954829 -54.423514)
						(end 343.87917 -54.376828)
					)
					(arc
						(start 343.87917 -54.271672)
						(mid 344.026952 -54.351474)
						(end 344.106754 -54.499256)
					)
				)
			)
		)
		(zone
			(layer "F.Cu")
			(hatch none 0.5)
			(connect_pads
				(clearance 0)
			)
			(min_thickness 0.25)
			(keepout
				(tracks not_allowed)
				(vias allowed)
				(pads allowed)
				(copperpour not_allowed)
				(footprints allowed)
			)
			(placement
				(enabled no)
				(sheetname "")
			)
			(fill
				(thermal_gap 0.5)
				(thermal_bridge_width 0.5)
				(island_removal_mode 0)
			)
			(polygon
				(pts
					(arc
						(start 344.001344 -53.559456)
						(mid 343.954829 -53.483714)
						(end 343.87917 -53.437028)
					)
					(arc
						(start 343.87917 -53.331872)
						(mid 344.026952 -53.411674)
						(end 344.106754 -53.559456)
					)
				)
			)
		)
		(zone
			(layer "F.Cu")
			(hatch none 0.5)
			(connect_pads
				(clearance 0)
			)
			(min_thickness 0.25)
			(keepout
				(tracks not_allowed)
				(vias allowed)
				(pads allowed)
				(copperpour not_allowed)
				(footprints allowed)
			)
			(placement
				(enabled no)
				(sheetname "")
			)
			(fill
				(thermal_gap 0.5)
				(thermal_bridge_width 0.5)
				(island_removal_mode 0)
			)
			(polygon
				(pts
					(arc
						(start 344.001344 -52.619656)
						(mid 343.954829 -52.543914)
						(end 343.87917 -52.497228)
					)
					(arc
						(start 343.87917 -52.392072)
						(mid 344.026952 -52.471874)
						(end 344.106754 -52.619656)
					)
				)
			)
		)
		(zone
			(layer "F.Cu")
			(hatch none 0.5)
			(connect_pads
				(clearance 0)
			)
			(min_thickness 0.25)
			(keepout
				(tracks not_allowed)
				(vias allowed)
				(pads allowed)
				(copperpour not_allowed)
				(footprints allowed)
			)
			(placement
				(enabled no)
				(sheetname "")
			)
			(fill
				(thermal_gap 0.5)
				(thermal_bridge_width 0.5)
				(island_removal_mode 0)
			)
			(polygon
				(pts
					(arc
						(start 344.001344 -51.679856)
						(mid 343.954829 -51.604114)
						(end 343.87917 -51.557428)
					)
					(arc
						(start 343.87917 -51.452272)
						(mid 344.026952 -51.532074)
						(end 344.106754 -51.679856)
					)
				)
			)
		)
		(zone
			(layer "F.Cu")
			(hatch none 0.5)
			(connect_pads
				(clearance 0)
			)
			(min_thickness 0.25)
			(keepout
				(tracks not_allowed)
				(vias allowed)
				(pads allowed)
				(copperpour not_allowed)
				(footprints allowed)
			)
			(placement
				(enabled no)
				(sheetname "")
			)
			(fill
				(thermal_gap 0.5)
				(thermal_bridge_width 0.5)
				(island_removal_mode 0)
			)
			(polygon
				(pts
					(arc
						(start 344.001344 -50.740056)
						(mid 343.954829 -50.664314)
						(end 343.87917 -50.617628)
					)
					(arc
						(start 343.87917 -50.512472)
						(mid 344.026952 -50.592274)
						(end 344.106754 -50.740056)
					)
				)
			)
		)
		(zone
			(layer "F.Cu")
			(hatch none 0.5)
			(connect_pads
				(clearance 0)
			)
			(min_thickness 0.25)
			(keepout
				(tracks not_allowed)
				(vias allowed)
				(pads allowed)
				(copperpour not_allowed)
				(footprints allowed)
			)
			(placement
				(enabled no)
				(sheetname "")
			)
			(fill
				(thermal_gap 0.5)
				(thermal_bridge_width 0.5)
				(island_removal_mode 0)
			)
			(polygon
				(pts
					(arc
						(start 344.001344 -49.800256)
						(mid 343.954829 -49.724514)
						(end 343.87917 -49.677828)
					)
					(arc
						(start 343.87917 -49.572672)
						(mid 344.026952 -49.652474)
						(end 344.106754 -49.800256)
					)
				)
			)
		)
		(zone
			(layer "F.Cu")
			(hatch none 0.5)
			(connect_pads
				(clearance 0)
			)
			(min_thickness 0.25)
			(keepout
				(tracks not_allowed)
				(vias allowed)
				(pads allowed)
				(copperpour not_allowed)
				(footprints allowed)
			)
			(placement
				(enabled no)
				(sheetname "")
			)
			(fill
				(thermal_gap 0.5)
				(thermal_bridge_width 0.5)
				(island_removal_mode 0)
			)
			(polygon
				(pts
					(arc
						(start 344.001344 -48.860456)
						(mid 343.954829 -48.784714)
						(end 343.87917 -48.738028)
					)
					(arc
						(start 343.87917 -48.632872)
						(mid 344.026952 -48.712674)
						(end 344.106754 -48.860456)
					)
				)
			)
		)
		(zone
			(layer "F.Cu")
			(hatch none 0.5)
			(connect_pads
				(clearance 0)
			)
			(min_thickness 0.25)
			(keepout
				(tracks not_allowed)
				(vias allowed)
				(pads allowed)
				(copperpour not_allowed)
				(footprints allowed)
			)
			(placement
				(enabled no)
				(sheetname "")
			)
			(fill
				(thermal_gap 0.5)
				(thermal_bridge_width 0.5)
				(island_removal_mode 0)
			)
			(polygon
				(pts
					(arc
						(start 344.001344 -47.920656)
						(mid 343.954829 -47.844914)
						(end 343.87917 -47.798228)
					)
					(arc
						(start 343.87917 -47.693072)
						(mid 344.026952 -47.772874)
						(end 344.106754 -47.920656)
					)
				)
			)
		)
		(zone
			(layer "F.Cu")
			(hatch none 0.5)
			(connect_pads
				(clearance 0)
			)
			(min_thickness 0.25)
			(keepout
				(tracks not_allowed)
				(vias allowed)
				(pads allowed)
				(copperpour not_allowed)
				(footprints allowed)
			)
			(placement
				(enabled no)
				(sheetname "")
			)
			(fill
				(thermal_gap 0.5)
				(thermal_bridge_width 0.5)
				(island_removal_mode 0)
			)
			(polygon
				(pts
					(arc
						(start 344.001344 -46.980856)
						(mid 343.954829 -46.905114)
						(end 343.87917 -46.858428)
					)
					(arc
						(start 343.87917 -46.753272)
						(mid 344.026952 -46.833074)
						(end 344.106754 -46.980856)
					)
				)
			)
		)
		(zone
			(layer "F.Cu")
			(hatch none 0.5)
			(connect_pads
				(clearance 0)
			)
			(min_thickness 0.25)
			(keepout
				(tracks not_allowed)
				(vias allowed)
				(pads allowed)
				(copperpour not_allowed)
				(footprints allowed)
			)
			(placement
				(enabled no)
				(sheetname "")
			)
			(fill
				(thermal_gap 0.5)
				(thermal_bridge_width 0.5)
				(island_removal_mode 0)
			)
			(polygon
				(pts
					(arc
						(start 344.001344 -46.041056)
						(mid 343.954829 -45.965314)
						(end 343.87917 -45.918628)
					)
					(arc
						(start 343.87917 -45.813472)
						(mid 344.026952 -45.893274)
						(end 344.106754 -46.041056)
					)
				)
			)
		)
		(zone
			(layer "F.Cu")
			(hatch none 0.5)
			(connect_pads
				(clearance 0)
			)
			(min_thickness 0.25)
			(keepout
				(tracks not_allowed)
				(vias allowed)
				(pads allowed)
				(copperpour not_allowed)
				(footprints allowed)
			)
			(placement
				(enabled no)
				(sheetname "")
			)
			(fill
				(thermal_gap 0.5)
				(thermal_bridge_width 0.5)
				(island_removal_mode 0)
			)
			(polygon
				(pts
					(arc
						(start 344.001344 -45.101256)
						(mid 343.954829 -45.025514)
						(end 343.87917 -44.978828)
					)
					(arc
						(start 343.87917 -44.873672)
						(mid 344.026952 -44.953474)
						(end 344.106754 -45.101256)
					)
				)
			)
		)
		(zone
			(layer "F.Cu")
			(hatch none 0.5)
			(connect_pads
				(clearance 0)
			)
			(min_thickness 0.25)
			(keepout
				(tracks not_allowed)
				(vias allowed)
				(pads allowed)
				(copperpour not_allowed)
				(footprints allowed)
			)
			(placement
				(enabled no)
				(sheetname "")
			)
			(fill
				(thermal_gap 0.5)
				(thermal_bridge_width 0.5)
				(island_removal_mode 0)
			)
			(polygon
				(pts
					(arc
						(start 344.001344 -44.161456)
						(mid 343.954829 -44.085714)
						(end 343.87917 -44.039028)
					)
					(arc
						(start 343.87917 -43.933872)
						(mid 344.026952 -44.013674)
						(end 344.106754 -44.161456)
					)
				)
			)
		)
		(zone
			(layer "F.Cu")
			(hatch none 0.5)
			(connect_pads
				(clearance 0)
			)
			(min_thickness 0.25)
			(keepout
				(tracks not_allowed)
				(vias allowed)
				(pads allowed)
				(copperpour not_allowed)
				(footprints allowed)
			)
			(placement
				(enabled no)
				(sheetname "")
			)
			(fill
				(thermal_gap 0.5)
				(thermal_bridge_width 0.5)
				(island_removal_mode 0)
			)
			(polygon
				(pts
					(arc
						(start 344.001344 -43.221656)
						(mid 343.954829 -43.145914)
						(end 343.87917 -43.099228)
					)
					(arc
						(start 343.87917 -42.994072)
						(mid 344.026952 -43.073874)
						(end 344.106754 -43.221656)
					)
				)
			)
		)
		(zone
			(layer "F.Cu")
			(hatch none 0.5)
			(connect_pads
				(clearance 0)
			)
			(min_thickness 0.25)
			(keepout
				(tracks not_allowed)
				(vias allowed)
				(pads allowed)
				(copperpour not_allowed)
				(footprints allowed)
			)
			(placement
				(enabled no)
				(sheetname "")
			)
			(fill
				(thermal_gap 0.5)
				(thermal_bridge_width 0.5)
				(island_removal_mode 0)
			)
			(polygon
				(pts
					(arc
						(start 344.001344 -42.281856)
						(mid 343.954829 -42.206114)
						(end 343.87917 -42.159428)
					)
					(arc
						(start 343.87917 -42.054272)
						(mid 344.026952 -42.134074)
						(end 344.106754 -42.281856)
					)
				)
			)
		)
		(zone
			(layer "F.Cu")
			(hatch none 0.5)
			(connect_pads
				(clearance 0)
			)
			(min_thickness 0.25)
			(keepout
				(tracks not_allowed)
				(vias allowed)
				(pads allowed)
				(copperpour not_allowed)
				(footprints allowed)
			)
			(placement
				(enabled no)
				(sheetname "")
			)
			(fill
				(thermal_gap 0.5)
				(thermal_bridge_width 0.5)
				(island_removal_mode 0)
			)
			(polygon
				(pts
					(arc
						(start 344.001344 -41.342056)
						(mid 343.954829 -41.266314)
						(end 343.87917 -41.219628)
					)
					(arc
						(start 343.87917 -41.114472)
						(mid 344.026952 -41.194274)
						(end 344.106754 -41.342056)
					)
				)
			)
		)
		(zone
			(layer "F.Cu")
			(hatch none 0.5)
			(connect_pads
				(clearance 0)
			)
			(min_thickness 0.25)
			(keepout
				(tracks not_allowed)
				(vias allowed)
				(pads allowed)
				(copperpour not_allowed)
				(footprints allowed)
			)
			(placement
				(enabled no)
				(sheetname "")
			)
			(fill
				(thermal_gap 0.5)
				(thermal_bridge_width 0.5)
				(island_removal_mode 0)
			)
			(polygon
				(pts
					(arc
						(start 344.001344 -40.402256)
						(mid 343.954829 -40.326514)
						(end 343.87917 -40.279828)
					)
					(arc
						(start 343.87917 -40.174672)
						(mid 344.026952 -40.254474)
						(end 344.106754 -40.402256)
					)
				)
			)
		)
		(zone
			(layer "F.Cu")
			(hatch none 0.5)
			(connect_pads
				(clearance 0)
			)
			(min_thickness 0.25)
			(keepout
				(tracks not_allowed)
				(vias allowed)
				(pads allowed)
				(copperpour not_allowed)
				(footprints allowed)
			)
			(placement
				(enabled no)
				(sheetname "")
			)
			(fill
				(thermal_gap 0.5)
				(thermal_bridge_width 0.5)
				(island_removal_mode 0)
			)
			(polygon
				(pts
					(arc
						(start 344.451432 -56.968136)
						(mid 344.498033 -57.043963)
						(end 344.57386 -57.090564)
					)
					(arc
						(start 344.57386 -57.19572)
						(mid 344.426078 -57.115918)
						(end 344.346276 -56.968136)
					)
				)
			)
		)
		(zone
			(layer "F.Cu")
			(hatch none 0.5)
			(connect_pads
				(clearance 0)
			)
			(min_thickness 0.25)
			(keepout
				(tracks not_allowed)
				(vias allowed)
				(pads allowed)
				(copperpour not_allowed)
				(footprints allowed)
			)
			(placement
				(enabled no)
				(sheetname "")
			)
			(fill
				(thermal_gap 0.5)
				(thermal_bridge_width 0.5)
				(island_removal_mode 0)
			)
			(polygon
				(pts
					(arc
						(start 344.451432 -56.028336)
						(mid 344.498033 -56.104163)
						(end 344.57386 -56.150764)
					)
					(arc
						(start 344.57386 -56.25592)
						(mid 344.426078 -56.176118)
						(end 344.346276 -56.028336)
					)
				)
			)
		)
		(zone
			(layer "F.Cu")
			(hatch none 0.5)
			(connect_pads
				(clearance 0)
			)
			(min_thickness 0.25)
			(keepout
				(tracks not_allowed)
				(vias allowed)
				(pads allowed)
				(copperpour not_allowed)
				(footprints allowed)
			)
			(placement
				(enabled no)
				(sheetname "")
			)
			(fill
				(thermal_gap 0.5)
				(thermal_bridge_width 0.5)
				(island_removal_mode 0)
			)
			(polygon
				(pts
					(arc
						(start 344.451432 -55.088536)
						(mid 344.498033 -55.164363)
						(end 344.57386 -55.210964)
					)
					(arc
						(start 344.57386 -55.31612)
						(mid 344.426078 -55.236318)
						(end 344.346276 -55.088536)
					)
				)
			)
		)
		(zone
			(layer "F.Cu")
			(hatch none 0.5)
			(connect_pads
				(clearance 0)
			)
			(min_thickness 0.25)
			(keepout
				(tracks not_allowed)
				(vias allowed)
				(pads allowed)
				(copperpour not_allowed)
				(footprints allowed)
			)
			(placement
				(enabled no)
				(sheetname "")
			)
			(fill
				(thermal_gap 0.5)
				(thermal_bridge_width 0.5)
				(island_removal_mode 0)
			)
			(polygon
				(pts
					(arc
						(start 344.451432 -54.148736)
						(mid 344.498033 -54.224563)
						(end 344.57386 -54.271164)
					)
					(arc
						(start 344.57386 -54.37632)
						(mid 344.426078 -54.296518)
						(end 344.346276 -54.148736)
					)
				)
			)
		)
		(zone
			(layer "F.Cu")
			(hatch none 0.5)
			(connect_pads
				(clearance 0)
			)
			(min_thickness 0.25)
			(keepout
				(tracks not_allowed)
				(vias allowed)
				(pads allowed)
				(copperpour not_allowed)
				(footprints allowed)
			)
			(placement
				(enabled no)
				(sheetname "")
			)
			(fill
				(thermal_gap 0.5)
				(thermal_bridge_width 0.5)
				(island_removal_mode 0)
			)
			(polygon
				(pts
					(arc
						(start 344.451432 -53.208936)
						(mid 344.498033 -53.284763)
						(end 344.57386 -53.331364)
					)
					(arc
						(start 344.57386 -53.43652)
						(mid 344.426078 -53.356718)
						(end 344.346276 -53.208936)
					)
				)
			)
		)
		(zone
			(layer "F.Cu")
			(hatch none 0.5)
			(connect_pads
				(clearance 0)
			)
			(min_thickness 0.25)
			(keepout
				(tracks not_allowed)
				(vias allowed)
				(pads allowed)
				(copperpour not_allowed)
				(footprints allowed)
			)
			(placement
				(enabled no)
				(sheetname "")
			)
			(fill
				(thermal_gap 0.5)
				(thermal_bridge_width 0.5)
				(island_removal_mode 0)
			)
			(polygon
				(pts
					(arc
						(start 344.451432 -52.269136)
						(mid 344.498033 -52.344963)
						(end 344.57386 -52.391564)
					)
					(arc
						(start 344.57386 -52.49672)
						(mid 344.426078 -52.416918)
						(end 344.346276 -52.269136)
					)
				)
			)
		)
		(zone
			(layer "F.Cu")
			(hatch none 0.5)
			(connect_pads
				(clearance 0)
			)
			(min_thickness 0.25)
			(keepout
				(tracks not_allowed)
				(vias allowed)
				(pads allowed)
				(copperpour not_allowed)
				(footprints allowed)
			)
			(placement
				(enabled no)
				(sheetname "")
			)
			(fill
				(thermal_gap 0.5)
				(thermal_bridge_width 0.5)
				(island_removal_mode 0)
			)
			(polygon
				(pts
					(arc
						(start 344.451432 -51.329336)
						(mid 344.498033 -51.405163)
						(end 344.57386 -51.451764)
					)
					(arc
						(start 344.57386 -51.55692)
						(mid 344.426078 -51.477118)
						(end 344.346276 -51.329336)
					)
				)
			)
		)
		(zone
			(layer "F.Cu")
			(hatch none 0.5)
			(connect_pads
				(clearance 0)
			)
			(min_thickness 0.25)
			(keepout
				(tracks not_allowed)
				(vias allowed)
				(pads allowed)
				(copperpour not_allowed)
				(footprints allowed)
			)
			(placement
				(enabled no)
				(sheetname "")
			)
			(fill
				(thermal_gap 0.5)
				(thermal_bridge_width 0.5)
				(island_removal_mode 0)
			)
			(polygon
				(pts
					(arc
						(start 344.451432 -50.389536)
						(mid 344.498033 -50.465363)
						(end 344.57386 -50.511964)
					)
					(arc
						(start 344.57386 -50.61712)
						(mid 344.426078 -50.537318)
						(end 344.346276 -50.389536)
					)
				)
			)
		)
		(zone
			(layer "F.Cu")
			(hatch none 0.5)
			(connect_pads
				(clearance 0)
			)
			(min_thickness 0.25)
			(keepout
				(tracks not_allowed)
				(vias allowed)
				(pads allowed)
				(copperpour not_allowed)
				(footprints allowed)
			)
			(placement
				(enabled no)
				(sheetname "")
			)
			(fill
				(thermal_gap 0.5)
				(thermal_bridge_width 0.5)
				(island_removal_mode 0)
			)
			(polygon
				(pts
					(arc
						(start 344.451432 -49.449736)
						(mid 344.498033 -49.525563)
						(end 344.57386 -49.572164)
					)
					(arc
						(start 344.57386 -49.67732)
						(mid 344.426078 -49.597518)
						(end 344.346276 -49.449736)
					)
				)
			)
		)
		(zone
			(layer "F.Cu")
			(hatch none 0.5)
			(connect_pads
				(clearance 0)
			)
			(min_thickness 0.25)
			(keepout
				(tracks not_allowed)
				(vias allowed)
				(pads allowed)
				(copperpour not_allowed)
				(footprints allowed)
			)
			(placement
				(enabled no)
				(sheetname "")
			)
			(fill
				(thermal_gap 0.5)
				(thermal_bridge_width 0.5)
				(island_removal_mode 0)
			)
			(polygon
				(pts
					(arc
						(start 344.451432 -48.509936)
						(mid 344.498033 -48.585763)
						(end 344.57386 -48.632364)
					)
					(arc
						(start 344.57386 -48.73752)
						(mid 344.426078 -48.657718)
						(end 344.346276 -48.509936)
					)
				)
			)
		)
		(zone
			(layer "F.Cu")
			(hatch none 0.5)
			(connect_pads
				(clearance 0)
			)
			(min_thickness 0.25)
			(keepout
				(tracks not_allowed)
				(vias allowed)
				(pads allowed)
				(copperpour not_allowed)
				(footprints allowed)
			)
			(placement
				(enabled no)
				(sheetname "")
			)
			(fill
				(thermal_gap 0.5)
				(thermal_bridge_width 0.5)
				(island_removal_mode 0)
			)
			(polygon
				(pts
					(arc
						(start 344.451432 -47.570136)
						(mid 344.498033 -47.645963)
						(end 344.57386 -47.692564)
					)
					(arc
						(start 344.57386 -47.79772)
						(mid 344.426078 -47.717918)
						(end 344.346276 -47.570136)
					)
				)
			)
		)
		(zone
			(layer "F.Cu")
			(hatch none 0.5)
			(connect_pads
				(clearance 0)
			)
			(min_thickness 0.25)
			(keepout
				(tracks not_allowed)
				(vias allowed)
				(pads allowed)
				(copperpour not_allowed)
				(footprints allowed)
			)
			(placement
				(enabled no)
				(sheetname "")
			)
			(fill
				(thermal_gap 0.5)
				(thermal_bridge_width 0.5)
				(island_removal_mode 0)
			)
			(polygon
				(pts
					(arc
						(start 344.451432 -46.630336)
						(mid 344.498033 -46.706163)
						(end 344.57386 -46.752764)
					)
					(arc
						(start 344.57386 -46.85792)
						(mid 344.426078 -46.778118)
						(end 344.346276 -46.630336)
					)
				)
			)
		)
		(zone
			(layer "F.Cu")
			(hatch none 0.5)
			(connect_pads
				(clearance 0)
			)
			(min_thickness 0.25)
			(keepout
				(tracks not_allowed)
				(vias allowed)
				(pads allowed)
				(copperpour not_allowed)
				(footprints allowed)
			)
			(placement
				(enabled no)
				(sheetname "")
			)
			(fill
				(thermal_gap 0.5)
				(thermal_bridge_width 0.5)
				(island_removal_mode 0)
			)
			(polygon
				(pts
					(arc
						(start 344.451432 -45.690536)
						(mid 344.498033 -45.766363)
						(end 344.57386 -45.812964)
					)
					(arc
						(start 344.57386 -45.91812)
						(mid 344.426078 -45.838318)
						(end 344.346276 -45.690536)
					)
				)
			)
		)
		(zone
			(layer "F.Cu")
			(hatch none 0.5)
			(connect_pads
				(clearance 0)
			)
			(min_thickness 0.25)
			(keepout
				(tracks not_allowed)
				(vias allowed)
				(pads allowed)
				(copperpour not_allowed)
				(footprints allowed)
			)
			(placement
				(enabled no)
				(sheetname "")
			)
			(fill
				(thermal_gap 0.5)
				(thermal_bridge_width 0.5)
				(island_removal_mode 0)
			)
			(polygon
				(pts
					(arc
						(start 344.451432 -44.750736)
						(mid 344.498033 -44.826563)
						(end 344.57386 -44.873164)
					)
					(arc
						(start 344.57386 -44.97832)
						(mid 344.426078 -44.898518)
						(end 344.346276 -44.750736)
					)
				)
			)
		)
		(zone
			(layer "F.Cu")
			(hatch none 0.5)
			(connect_pads
				(clearance 0)
			)
			(min_thickness 0.25)
			(keepout
				(tracks not_allowed)
				(vias allowed)
				(pads allowed)
				(copperpour not_allowed)
				(footprints allowed)
			)
			(placement
				(enabled no)
				(sheetname "")
			)
			(fill
				(thermal_gap 0.5)
				(thermal_bridge_width 0.5)
				(island_removal_mode 0)
			)
			(polygon
				(pts
					(arc
						(start 344.451432 -43.810936)
						(mid 344.498033 -43.886763)
						(end 344.57386 -43.933364)
					)
					(arc
						(start 344.57386 -44.03852)
						(mid 344.426078 -43.958718)
						(end 344.346276 -43.810936)
					)
				)
			)
		)
		(zone
			(layer "F.Cu")
			(hatch none 0.5)
			(connect_pads
				(clearance 0)
			)
			(min_thickness 0.25)
			(keepout
				(tracks not_allowed)
				(vias allowed)
				(pads allowed)
				(copperpour not_allowed)
				(footprints allowed)
			)
			(placement
				(enabled no)
				(sheetname "")
			)
			(fill
				(thermal_gap 0.5)
				(thermal_bridge_width 0.5)
				(island_removal_mode 0)
			)
			(polygon
				(pts
					(arc
						(start 344.451432 -42.871136)
						(mid 344.498033 -42.946963)
						(end 344.57386 -42.993564)
					)
					(arc
						(start 344.57386 -43.09872)
						(mid 344.426078 -43.018918)
						(end 344.346276 -42.871136)
					)
				)
			)
		)
		(zone
			(layer "F.Cu")
			(hatch none 0.5)
			(connect_pads
				(clearance 0)
			)
			(min_thickness 0.25)
			(keepout
				(tracks not_allowed)
				(vias allowed)
				(pads allowed)
				(copperpour not_allowed)
				(footprints allowed)
			)
			(placement
				(enabled no)
				(sheetname "")
			)
			(fill
				(thermal_gap 0.5)
				(thermal_bridge_width 0.5)
				(island_removal_mode 0)
			)
			(polygon
				(pts
					(arc
						(start 344.451432 -41.931336)
						(mid 344.498033 -42.007163)
						(end 344.57386 -42.053764)
					)
					(arc
						(start 344.57386 -42.15892)
						(mid 344.426078 -42.079118)
						(end 344.346276 -41.931336)
					)
				)
			)
		)
		(zone
			(layer "F.Cu")
			(hatch none 0.5)
			(connect_pads
				(clearance 0)
			)
			(min_thickness 0.25)
			(keepout
				(tracks not_allowed)
				(vias allowed)
				(pads allowed)
				(copperpour not_allowed)
				(footprints allowed)
			)
			(placement
				(enabled no)
				(sheetname "")
			)
			(fill
				(thermal_gap 0.5)
				(thermal_bridge_width 0.5)
				(island_removal_mode 0)
			)
			(polygon
				(pts
					(arc
						(start 344.451432 -40.991536)
						(mid 344.498033 -41.067363)
						(end 344.57386 -41.113964)
					)
					(arc
						(start 344.57386 -41.21912)
						(mid 344.426078 -41.139318)
						(end 344.346276 -40.991536)
					)
				)
			)
		)
		(zone
			(layer "F.Cu")
			(hatch none 0.5)
			(connect_pads
				(clearance 0)
			)
			(min_thickness 0.25)
			(keepout
				(tracks not_allowed)
				(vias allowed)
				(pads allowed)
				(copperpour not_allowed)
				(footprints allowed)
			)
			(placement
				(enabled no)
				(sheetname "")
			)
			(fill
				(thermal_gap 0.5)
				(thermal_bridge_width 0.5)
				(island_removal_mode 0)
			)
			(polygon
				(pts
					(arc
						(start 344.451432 -40.051736)
						(mid 344.498033 -40.127563)
						(end 344.57386 -40.174164)
					)
					(arc
						(start 344.57386 -40.27932)
						(mid 344.426078 -40.199518)
						(end 344.346276 -40.051736)
					)
				)
			)
		)
		(zone
			(layer "F.Cu")
			(hatch none 0.5)
			(connect_pads
				(clearance 0)
			)
			(min_thickness 0.25)
			(keepout
				(tracks not_allowed)
				(vias allowed)
				(pads allowed)
				(copperpour not_allowed)
				(footprints allowed)
			)
			(placement
				(enabled no)
				(sheetname "")
			)
			(fill
				(thermal_gap 0.5)
				(thermal_bridge_width 0.5)
				(island_removal_mode 0)
			)
			(polygon
				(pts
					(arc
						(start 344.57386 -56.726328)
						(mid 344.498033 -56.772929)
						(end 344.451432 -56.848756)
					)
					(arc
						(start 344.346276 -56.848756)
						(mid 344.426078 -56.700974)
						(end 344.57386 -56.621172)
					)
				)
			)
		)
		(zone
			(layer "F.Cu")
			(hatch none 0.5)
			(connect_pads
				(clearance 0)
			)
			(min_thickness 0.25)
			(keepout
				(tracks not_allowed)
				(vias allowed)
				(pads allowed)
				(copperpour not_allowed)
				(footprints allowed)
			)
			(placement
				(enabled no)
				(sheetname "")
			)
			(fill
				(thermal_gap 0.5)
				(thermal_bridge_width 0.5)
				(island_removal_mode 0)
			)
			(polygon
				(pts
					(arc
						(start 344.57386 -55.786528)
						(mid 344.498033 -55.833129)
						(end 344.451432 -55.908956)
					)
					(arc
						(start 344.346276 -55.908956)
						(mid 344.426078 -55.761174)
						(end 344.57386 -55.681372)
					)
				)
			)
		)
		(zone
			(layer "F.Cu")
			(hatch none 0.5)
			(connect_pads
				(clearance 0)
			)
			(min_thickness 0.25)
			(keepout
				(tracks not_allowed)
				(vias allowed)
				(pads allowed)
				(copperpour not_allowed)
				(footprints allowed)
			)
			(placement
				(enabled no)
				(sheetname "")
			)
			(fill
				(thermal_gap 0.5)
				(thermal_bridge_width 0.5)
				(island_removal_mode 0)
			)
			(polygon
				(pts
					(arc
						(start 344.57386 -54.846728)
						(mid 344.498033 -54.893329)
						(end 344.451432 -54.969156)
					)
					(arc
						(start 344.346276 -54.969156)
						(mid 344.426078 -54.821374)
						(end 344.57386 -54.741572)
					)
				)
			)
		)
		(zone
			(layer "F.Cu")
			(hatch none 0.5)
			(connect_pads
				(clearance 0)
			)
			(min_thickness 0.25)
			(keepout
				(tracks not_allowed)
				(vias allowed)
				(pads allowed)
				(copperpour not_allowed)
				(footprints allowed)
			)
			(placement
				(enabled no)
				(sheetname "")
			)
			(fill
				(thermal_gap 0.5)
				(thermal_bridge_width 0.5)
				(island_removal_mode 0)
			)
			(polygon
				(pts
					(arc
						(start 344.57386 -53.906928)
						(mid 344.498033 -53.953529)
						(end 344.451432 -54.029356)
					)
					(arc
						(start 344.346276 -54.029356)
						(mid 344.426078 -53.881574)
						(end 344.57386 -53.801772)
					)
				)
			)
		)
		(zone
			(layer "F.Cu")
			(hatch none 0.5)
			(connect_pads
				(clearance 0)
			)
			(min_thickness 0.25)
			(keepout
				(tracks not_allowed)
				(vias allowed)
				(pads allowed)
				(copperpour not_allowed)
				(footprints allowed)
			)
			(placement
				(enabled no)
				(sheetname "")
			)
			(fill
				(thermal_gap 0.5)
				(thermal_bridge_width 0.5)
				(island_removal_mode 0)
			)
			(polygon
				(pts
					(arc
						(start 344.57386 -52.967128)
						(mid 344.498033 -53.013729)
						(end 344.451432 -53.089556)
					)
					(arc
						(start 344.346276 -53.089556)
						(mid 344.426078 -52.941774)
						(end 344.57386 -52.861972)
					)
				)
			)
		)
		(zone
			(layer "F.Cu")
			(hatch none 0.5)
			(connect_pads
				(clearance 0)
			)
			(min_thickness 0.25)
			(keepout
				(tracks not_allowed)
				(vias allowed)
				(pads allowed)
				(copperpour not_allowed)
				(footprints allowed)
			)
			(placement
				(enabled no)
				(sheetname "")
			)
			(fill
				(thermal_gap 0.5)
				(thermal_bridge_width 0.5)
				(island_removal_mode 0)
			)
			(polygon
				(pts
					(arc
						(start 344.57386 -52.027328)
						(mid 344.498033 -52.073929)
						(end 344.451432 -52.149756)
					)
					(arc
						(start 344.346276 -52.149756)
						(mid 344.426078 -52.001974)
						(end 344.57386 -51.922172)
					)
				)
			)
		)
		(zone
			(layer "F.Cu")
			(hatch none 0.5)
			(connect_pads
				(clearance 0)
			)
			(min_thickness 0.25)
			(keepout
				(tracks not_allowed)
				(vias allowed)
				(pads allowed)
				(copperpour not_allowed)
				(footprints allowed)
			)
			(placement
				(enabled no)
				(sheetname "")
			)
			(fill
				(thermal_gap 0.5)
				(thermal_bridge_width 0.5)
				(island_removal_mode 0)
			)
			(polygon
				(pts
					(arc
						(start 344.57386 -51.087528)
						(mid 344.498033 -51.134129)
						(end 344.451432 -51.209956)
					)
					(arc
						(start 344.346276 -51.209956)
						(mid 344.426078 -51.062174)
						(end 344.57386 -50.982372)
					)
				)
			)
		)
		(zone
			(layer "F.Cu")
			(hatch none 0.5)
			(connect_pads
				(clearance 0)
			)
			(min_thickness 0.25)
			(keepout
				(tracks not_allowed)
				(vias allowed)
				(pads allowed)
				(copperpour not_allowed)
				(footprints allowed)
			)
			(placement
				(enabled no)
				(sheetname "")
			)
			(fill
				(thermal_gap 0.5)
				(thermal_bridge_width 0.5)
				(island_removal_mode 0)
			)
			(polygon
				(pts
					(arc
						(start 344.57386 -50.147728)
						(mid 344.498033 -50.194329)
						(end 344.451432 -50.270156)
					)
					(arc
						(start 344.346276 -50.270156)
						(mid 344.426078 -50.122374)
						(end 344.57386 -50.042572)
					)
				)
			)
		)
		(zone
			(layer "F.Cu")
			(hatch none 0.5)
			(connect_pads
				(clearance 0)
			)
			(min_thickness 0.25)
			(keepout
				(tracks not_allowed)
				(vias allowed)
				(pads allowed)
				(copperpour not_allowed)
				(footprints allowed)
			)
			(placement
				(enabled no)
				(sheetname "")
			)
			(fill
				(thermal_gap 0.5)
				(thermal_bridge_width 0.5)
				(island_removal_mode 0)
			)
			(polygon
				(pts
					(arc
						(start 344.57386 -49.207928)
						(mid 344.498033 -49.254529)
						(end 344.451432 -49.330356)
					)
					(arc
						(start 344.346276 -49.330356)
						(mid 344.426078 -49.182574)
						(end 344.57386 -49.102772)
					)
				)
			)
		)
		(zone
			(layer "F.Cu")
			(hatch none 0.5)
			(connect_pads
				(clearance 0)
			)
			(min_thickness 0.25)
			(keepout
				(tracks not_allowed)
				(vias allowed)
				(pads allowed)
				(copperpour not_allowed)
				(footprints allowed)
			)
			(placement
				(enabled no)
				(sheetname "")
			)
			(fill
				(thermal_gap 0.5)
				(thermal_bridge_width 0.5)
				(island_removal_mode 0)
			)
			(polygon
				(pts
					(arc
						(start 344.57386 -48.268128)
						(mid 344.498033 -48.314729)
						(end 344.451432 -48.390556)
					)
					(arc
						(start 344.346276 -48.390556)
						(mid 344.426078 -48.242774)
						(end 344.57386 -48.162972)
					)
				)
			)
		)
		(zone
			(layer "F.Cu")
			(hatch none 0.5)
			(connect_pads
				(clearance 0)
			)
			(min_thickness 0.25)
			(keepout
				(tracks not_allowed)
				(vias allowed)
				(pads allowed)
				(copperpour not_allowed)
				(footprints allowed)
			)
			(placement
				(enabled no)
				(sheetname "")
			)
			(fill
				(thermal_gap 0.5)
				(thermal_bridge_width 0.5)
				(island_removal_mode 0)
			)
			(polygon
				(pts
					(arc
						(start 344.57386 -47.328328)
						(mid 344.498033 -47.374929)
						(end 344.451432 -47.450756)
					)
					(arc
						(start 344.346276 -47.450756)
						(mid 344.426078 -47.302974)
						(end 344.57386 -47.223172)
					)
				)
			)
		)
		(zone
			(layer "F.Cu")
			(hatch none 0.5)
			(connect_pads
				(clearance 0)
			)
			(min_thickness 0.25)
			(keepout
				(tracks not_allowed)
				(vias allowed)
				(pads allowed)
				(copperpour not_allowed)
				(footprints allowed)
			)
			(placement
				(enabled no)
				(sheetname "")
			)
			(fill
				(thermal_gap 0.5)
				(thermal_bridge_width 0.5)
				(island_removal_mode 0)
			)
			(polygon
				(pts
					(arc
						(start 344.57386 -46.388528)
						(mid 344.498033 -46.435129)
						(end 344.451432 -46.510956)
					)
					(arc
						(start 344.346276 -46.510956)
						(mid 344.426078 -46.363174)
						(end 344.57386 -46.283372)
					)
				)
			)
		)
		(zone
			(layer "F.Cu")
			(hatch none 0.5)
			(connect_pads
				(clearance 0)
			)
			(min_thickness 0.25)
			(keepout
				(tracks not_allowed)
				(vias allowed)
				(pads allowed)
				(copperpour not_allowed)
				(footprints allowed)
			)
			(placement
				(enabled no)
				(sheetname "")
			)
			(fill
				(thermal_gap 0.5)
				(thermal_bridge_width 0.5)
				(island_removal_mode 0)
			)
			(polygon
				(pts
					(arc
						(start 344.57386 -45.448728)
						(mid 344.498033 -45.495329)
						(end 344.451432 -45.571156)
					)
					(arc
						(start 344.346276 -45.571156)
						(mid 344.426078 -45.423374)
						(end 344.57386 -45.343572)
					)
				)
			)
		)
		(zone
			(layer "F.Cu")
			(hatch none 0.5)
			(connect_pads
				(clearance 0)
			)
			(min_thickness 0.25)
			(keepout
				(tracks not_allowed)
				(vias allowed)
				(pads allowed)
				(copperpour not_allowed)
				(footprints allowed)
			)
			(placement
				(enabled no)
				(sheetname "")
			)
			(fill
				(thermal_gap 0.5)
				(thermal_bridge_width 0.5)
				(island_removal_mode 0)
			)
			(polygon
				(pts
					(arc
						(start 344.57386 -44.508928)
						(mid 344.498033 -44.555529)
						(end 344.451432 -44.631356)
					)
					(arc
						(start 344.346276 -44.631356)
						(mid 344.426078 -44.483574)
						(end 344.57386 -44.403772)
					)
				)
			)
		)
		(zone
			(layer "F.Cu")
			(hatch none 0.5)
			(connect_pads
				(clearance 0)
			)
			(min_thickness 0.25)
			(keepout
				(tracks not_allowed)
				(vias allowed)
				(pads allowed)
				(copperpour not_allowed)
				(footprints allowed)
			)
			(placement
				(enabled no)
				(sheetname "")
			)
			(fill
				(thermal_gap 0.5)
				(thermal_bridge_width 0.5)
				(island_removal_mode 0)
			)
			(polygon
				(pts
					(arc
						(start 344.57386 -43.569128)
						(mid 344.498033 -43.615729)
						(end 344.451432 -43.691556)
					)
					(arc
						(start 344.346276 -43.691556)
						(mid 344.426078 -43.543774)
						(end 344.57386 -43.463972)
					)
				)
			)
		)
		(zone
			(layer "F.Cu")
			(hatch none 0.5)
			(connect_pads
				(clearance 0)
			)
			(min_thickness 0.25)
			(keepout
				(tracks not_allowed)
				(vias allowed)
				(pads allowed)
				(copperpour not_allowed)
				(footprints allowed)
			)
			(placement
				(enabled no)
				(sheetname "")
			)
			(fill
				(thermal_gap 0.5)
				(thermal_bridge_width 0.5)
				(island_removal_mode 0)
			)
			(polygon
				(pts
					(arc
						(start 344.57386 -42.629328)
						(mid 344.498033 -42.675929)
						(end 344.451432 -42.751756)
					)
					(arc
						(start 344.346276 -42.751756)
						(mid 344.426078 -42.603974)
						(end 344.57386 -42.524172)
					)
				)
			)
		)
		(zone
			(layer "F.Cu")
			(hatch none 0.5)
			(connect_pads
				(clearance 0)
			)
			(min_thickness 0.25)
			(keepout
				(tracks not_allowed)
				(vias allowed)
				(pads allowed)
				(copperpour not_allowed)
				(footprints allowed)
			)
			(placement
				(enabled no)
				(sheetname "")
			)
			(fill
				(thermal_gap 0.5)
				(thermal_bridge_width 0.5)
				(island_removal_mode 0)
			)
			(polygon
				(pts
					(arc
						(start 344.57386 -41.689528)
						(mid 344.498033 -41.736129)
						(end 344.451432 -41.811956)
					)
					(arc
						(start 344.346276 -41.811956)
						(mid 344.426078 -41.664174)
						(end 344.57386 -41.584372)
					)
				)
			)
		)
		(zone
			(layer "F.Cu")
			(hatch none 0.5)
			(connect_pads
				(clearance 0)
			)
			(min_thickness 0.25)
			(keepout
				(tracks not_allowed)
				(vias allowed)
				(pads allowed)
				(copperpour not_allowed)
				(footprints allowed)
			)
			(placement
				(enabled no)
				(sheetname "")
			)
			(fill
				(thermal_gap 0.5)
				(thermal_bridge_width 0.5)
				(island_removal_mode 0)
			)
			(polygon
				(pts
					(arc
						(start 344.57386 -40.749728)
						(mid 344.498033 -40.796329)
						(end 344.451432 -40.872156)
					)
					(arc
						(start 344.346276 -40.872156)
						(mid 344.426078 -40.724374)
						(end 344.57386 -40.644572)
					)
				)
			)
		)
		(zone
			(layer "F.Cu")
			(hatch none 0.5)
			(connect_pads
				(clearance 0)
			)
			(min_thickness 0.25)
			(keepout
				(tracks not_allowed)
				(vias allowed)
				(pads allowed)
				(copperpour not_allowed)
				(footprints allowed)
			)
			(placement
				(enabled no)
				(sheetname "")
			)
			(fill
				(thermal_gap 0.5)
				(thermal_bridge_width 0.5)
				(island_removal_mode 0)
			)
			(polygon
				(pts
					(arc
						(start 344.57386 -39.809928)
						(mid 344.498033 -39.856529)
						(end 344.451432 -39.932356)
					)
					(arc
						(start 344.346276 -39.932356)
						(mid 344.426078 -39.784574)
						(end 344.57386 -39.704772)
					)
				)
			)
		)
		(zone
			(layer "F.Cu")
			(hatch none 0.5)
			(connect_pads
				(clearance 0)
			)
			(min_thickness 0.25)
			(keepout
				(tracks not_allowed)
				(vias allowed)
				(pads allowed)
				(copperpour not_allowed)
				(footprints allowed)
			)
			(placement
				(enabled no)
				(sheetname "")
			)
			(fill
				(thermal_gap 0.5)
				(thermal_bridge_width 0.5)
				(island_removal_mode 0)
			)
			(polygon
				(pts
					(arc
						(start 344.69324 -57.090564)
						(mid 344.769067 -57.043963)
						(end 344.815668 -56.968136)
					)
					(arc
						(start 344.920824 -56.968136)
						(mid 344.841022 -57.115918)
						(end 344.69324 -57.19572)
					)
				)
			)
		)
		(zone
			(layer "F.Cu")
			(hatch none 0.5)
			(connect_pads
				(clearance 0)
			)
			(min_thickness 0.25)
			(keepout
				(tracks not_allowed)
				(vias allowed)
				(pads allowed)
				(copperpour not_allowed)
				(footprints allowed)
			)
			(placement
				(enabled no)
				(sheetname "")
			)
			(fill
				(thermal_gap 0.5)
				(thermal_bridge_width 0.5)
				(island_removal_mode 0)
			)
			(polygon
				(pts
					(arc
						(start 344.69324 -56.150764)
						(mid 344.769067 -56.104163)
						(end 344.815668 -56.028336)
					)
					(arc
						(start 344.920824 -56.028336)
						(mid 344.841022 -56.176118)
						(end 344.69324 -56.25592)
					)
				)
			)
		)
		(zone
			(layer "F.Cu")
			(hatch none 0.5)
			(connect_pads
				(clearance 0)
			)
			(min_thickness 0.25)
			(keepout
				(tracks not_allowed)
				(vias allowed)
				(pads allowed)
				(copperpour not_allowed)
				(footprints allowed)
			)
			(placement
				(enabled no)
				(sheetname "")
			)
			(fill
				(thermal_gap 0.5)
				(thermal_bridge_width 0.5)
				(island_removal_mode 0)
			)
			(polygon
				(pts
					(arc
						(start 344.69324 -55.210964)
						(mid 344.769067 -55.164363)
						(end 344.815668 -55.088536)
					)
					(arc
						(start 344.920824 -55.088536)
						(mid 344.841022 -55.236318)
						(end 344.69324 -55.31612)
					)
				)
			)
		)
		(zone
			(layer "F.Cu")
			(hatch none 0.5)
			(connect_pads
				(clearance 0)
			)
			(min_thickness 0.25)
			(keepout
				(tracks not_allowed)
				(vias allowed)
				(pads allowed)
				(copperpour not_allowed)
				(footprints allowed)
			)
			(placement
				(enabled no)
				(sheetname "")
			)
			(fill
				(thermal_gap 0.5)
				(thermal_bridge_width 0.5)
				(island_removal_mode 0)
			)
			(polygon
				(pts
					(arc
						(start 344.69324 -54.271164)
						(mid 344.769067 -54.224563)
						(end 344.815668 -54.148736)
					)
					(arc
						(start 344.920824 -54.148736)
						(mid 344.841022 -54.296518)
						(end 344.69324 -54.37632)
					)
				)
			)
		)
		(zone
			(layer "F.Cu")
			(hatch none 0.5)
			(connect_pads
				(clearance 0)
			)
			(min_thickness 0.25)
			(keepout
				(tracks not_allowed)
				(vias allowed)
				(pads allowed)
				(copperpour not_allowed)
				(footprints allowed)
			)
			(placement
				(enabled no)
				(sheetname "")
			)
			(fill
				(thermal_gap 0.5)
				(thermal_bridge_width 0.5)
				(island_removal_mode 0)
			)
			(polygon
				(pts
					(arc
						(start 344.69324 -53.331364)
						(mid 344.769067 -53.284763)
						(end 344.815668 -53.208936)
					)
					(arc
						(start 344.920824 -53.208936)
						(mid 344.841022 -53.356718)
						(end 344.69324 -53.43652)
					)
				)
			)
		)
		(zone
			(layer "F.Cu")
			(hatch none 0.5)
			(connect_pads
				(clearance 0)
			)
			(min_thickness 0.25)
			(keepout
				(tracks not_allowed)
				(vias allowed)
				(pads allowed)
				(copperpour not_allowed)
				(footprints allowed)
			)
			(placement
				(enabled no)
				(sheetname "")
			)
			(fill
				(thermal_gap 0.5)
				(thermal_bridge_width 0.5)
				(island_removal_mode 0)
			)
			(polygon
				(pts
					(arc
						(start 344.69324 -52.391564)
						(mid 344.769067 -52.344963)
						(end 344.815668 -52.269136)
					)
					(arc
						(start 344.920824 -52.269136)
						(mid 344.841022 -52.416918)
						(end 344.69324 -52.49672)
					)
				)
			)
		)
		(zone
			(layer "F.Cu")
			(hatch none 0.5)
			(connect_pads
				(clearance 0)
			)
			(min_thickness 0.25)
			(keepout
				(tracks not_allowed)
				(vias allowed)
				(pads allowed)
				(copperpour not_allowed)
				(footprints allowed)
			)
			(placement
				(enabled no)
				(sheetname "")
			)
			(fill
				(thermal_gap 0.5)
				(thermal_bridge_width 0.5)
				(island_removal_mode 0)
			)
			(polygon
				(pts
					(arc
						(start 344.69324 -51.451764)
						(mid 344.769067 -51.405163)
						(end 344.815668 -51.329336)
					)
					(arc
						(start 344.920824 -51.329336)
						(mid 344.841022 -51.477118)
						(end 344.69324 -51.55692)
					)
				)
			)
		)
		(zone
			(layer "F.Cu")
			(hatch none 0.5)
			(connect_pads
				(clearance 0)
			)
			(min_thickness 0.25)
			(keepout
				(tracks not_allowed)
				(vias allowed)
				(pads allowed)
				(copperpour not_allowed)
				(footprints allowed)
			)
			(placement
				(enabled no)
				(sheetname "")
			)
			(fill
				(thermal_gap 0.5)
				(thermal_bridge_width 0.5)
				(island_removal_mode 0)
			)
			(polygon
				(pts
					(arc
						(start 344.69324 -50.511964)
						(mid 344.769067 -50.465363)
						(end 344.815668 -50.389536)
					)
					(arc
						(start 344.920824 -50.389536)
						(mid 344.841022 -50.537318)
						(end 344.69324 -50.61712)
					)
				)
			)
		)
		(zone
			(layer "F.Cu")
			(hatch none 0.5)
			(connect_pads
				(clearance 0)
			)
			(min_thickness 0.25)
			(keepout
				(tracks not_allowed)
				(vias allowed)
				(pads allowed)
				(copperpour not_allowed)
				(footprints allowed)
			)
			(placement
				(enabled no)
				(sheetname "")
			)
			(fill
				(thermal_gap 0.5)
				(thermal_bridge_width 0.5)
				(island_removal_mode 0)
			)
			(polygon
				(pts
					(arc
						(start 344.69324 -49.572164)
						(mid 344.769067 -49.525563)
						(end 344.815668 -49.449736)
					)
					(arc
						(start 344.920824 -49.449736)
						(mid 344.841022 -49.597518)
						(end 344.69324 -49.67732)
					)
				)
			)
		)
		(zone
			(layer "F.Cu")
			(hatch none 0.5)
			(connect_pads
				(clearance 0)
			)
			(min_thickness 0.25)
			(keepout
				(tracks not_allowed)
				(vias allowed)
				(pads allowed)
				(copperpour not_allowed)
				(footprints allowed)
			)
			(placement
				(enabled no)
				(sheetname "")
			)
			(fill
				(thermal_gap 0.5)
				(thermal_bridge_width 0.5)
				(island_removal_mode 0)
			)
			(polygon
				(pts
					(arc
						(start 344.69324 -48.632364)
						(mid 344.769067 -48.585763)
						(end 344.815668 -48.509936)
					)
					(arc
						(start 344.920824 -48.509936)
						(mid 344.841022 -48.657718)
						(end 344.69324 -48.73752)
					)
				)
			)
		)
		(zone
			(layer "F.Cu")
			(hatch none 0.5)
			(connect_pads
				(clearance 0)
			)
			(min_thickness 0.25)
			(keepout
				(tracks not_allowed)
				(vias allowed)
				(pads allowed)
				(copperpour not_allowed)
				(footprints allowed)
			)
			(placement
				(enabled no)
				(sheetname "")
			)
			(fill
				(thermal_gap 0.5)
				(thermal_bridge_width 0.5)
				(island_removal_mode 0)
			)
			(polygon
				(pts
					(arc
						(start 344.69324 -47.692564)
						(mid 344.769067 -47.645963)
						(end 344.815668 -47.570136)
					)
					(arc
						(start 344.920824 -47.570136)
						(mid 344.841022 -47.717918)
						(end 344.69324 -47.79772)
					)
				)
			)
		)
		(zone
			(layer "F.Cu")
			(hatch none 0.5)
			(connect_pads
				(clearance 0)
			)
			(min_thickness 0.25)
			(keepout
				(tracks not_allowed)
				(vias allowed)
				(pads allowed)
				(copperpour not_allowed)
				(footprints allowed)
			)
			(placement
				(enabled no)
				(sheetname "")
			)
			(fill
				(thermal_gap 0.5)
				(thermal_bridge_width 0.5)
				(island_removal_mode 0)
			)
			(polygon
				(pts
					(arc
						(start 344.69324 -46.752764)
						(mid 344.769067 -46.706163)
						(end 344.815668 -46.630336)
					)
					(arc
						(start 344.920824 -46.630336)
						(mid 344.841022 -46.778118)
						(end 344.69324 -46.85792)
					)
				)
			)
		)
		(zone
			(layer "F.Cu")
			(hatch none 0.5)
			(connect_pads
				(clearance 0)
			)
			(min_thickness 0.25)
			(keepout
				(tracks not_allowed)
				(vias allowed)
				(pads allowed)
				(copperpour not_allowed)
				(footprints allowed)
			)
			(placement
				(enabled no)
				(sheetname "")
			)
			(fill
				(thermal_gap 0.5)
				(thermal_bridge_width 0.5)
				(island_removal_mode 0)
			)
			(polygon
				(pts
					(arc
						(start 344.69324 -45.812964)
						(mid 344.769067 -45.766363)
						(end 344.815668 -45.690536)
					)
					(arc
						(start 344.920824 -45.690536)
						(mid 344.841022 -45.838318)
						(end 344.69324 -45.91812)
					)
				)
			)
		)
		(zone
			(layer "F.Cu")
			(hatch none 0.5)
			(connect_pads
				(clearance 0)
			)
			(min_thickness 0.25)
			(keepout
				(tracks not_allowed)
				(vias allowed)
				(pads allowed)
				(copperpour not_allowed)
				(footprints allowed)
			)
			(placement
				(enabled no)
				(sheetname "")
			)
			(fill
				(thermal_gap 0.5)
				(thermal_bridge_width 0.5)
				(island_removal_mode 0)
			)
			(polygon
				(pts
					(arc
						(start 344.69324 -44.873164)
						(mid 344.769067 -44.826563)
						(end 344.815668 -44.750736)
					)
					(arc
						(start 344.920824 -44.750736)
						(mid 344.841022 -44.898518)
						(end 344.69324 -44.97832)
					)
				)
			)
		)
		(zone
			(layer "F.Cu")
			(hatch none 0.5)
			(connect_pads
				(clearance 0)
			)
			(min_thickness 0.25)
			(keepout
				(tracks not_allowed)
				(vias allowed)
				(pads allowed)
				(copperpour not_allowed)
				(footprints allowed)
			)
			(placement
				(enabled no)
				(sheetname "")
			)
			(fill
				(thermal_gap 0.5)
				(thermal_bridge_width 0.5)
				(island_removal_mode 0)
			)
			(polygon
				(pts
					(arc
						(start 344.69324 -43.933364)
						(mid 344.769067 -43.886763)
						(end 344.815668 -43.810936)
					)
					(arc
						(start 344.920824 -43.810936)
						(mid 344.841022 -43.958718)
						(end 344.69324 -44.03852)
					)
				)
			)
		)
		(zone
			(layer "F.Cu")
			(hatch none 0.5)
			(connect_pads
				(clearance 0)
			)
			(min_thickness 0.25)
			(keepout
				(tracks not_allowed)
				(vias allowed)
				(pads allowed)
				(copperpour not_allowed)
				(footprints allowed)
			)
			(placement
				(enabled no)
				(sheetname "")
			)
			(fill
				(thermal_gap 0.5)
				(thermal_bridge_width 0.5)
				(island_removal_mode 0)
			)
			(polygon
				(pts
					(arc
						(start 344.69324 -42.993564)
						(mid 344.769067 -42.946963)
						(end 344.815668 -42.871136)
					)
					(arc
						(start 344.920824 -42.871136)
						(mid 344.841022 -43.018918)
						(end 344.69324 -43.09872)
					)
				)
			)
		)
		(zone
			(layer "F.Cu")
			(hatch none 0.5)
			(connect_pads
				(clearance 0)
			)
			(min_thickness 0.25)
			(keepout
				(tracks not_allowed)
				(vias allowed)
				(pads allowed)
				(copperpour not_allowed)
				(footprints allowed)
			)
			(placement
				(enabled no)
				(sheetname "")
			)
			(fill
				(thermal_gap 0.5)
				(thermal_bridge_width 0.5)
				(island_removal_mode 0)
			)
			(polygon
				(pts
					(arc
						(start 344.69324 -42.053764)
						(mid 344.769067 -42.007163)
						(end 344.815668 -41.931336)
					)
					(arc
						(start 344.920824 -41.931336)
						(mid 344.841022 -42.079118)
						(end 344.69324 -42.15892)
					)
				)
			)
		)
		(zone
			(layer "F.Cu")
			(hatch none 0.5)
			(connect_pads
				(clearance 0)
			)
			(min_thickness 0.25)
			(keepout
				(tracks not_allowed)
				(vias allowed)
				(pads allowed)
				(copperpour not_allowed)
				(footprints allowed)
			)
			(placement
				(enabled no)
				(sheetname "")
			)
			(fill
				(thermal_gap 0.5)
				(thermal_bridge_width 0.5)
				(island_removal_mode 0)
			)
			(polygon
				(pts
					(arc
						(start 344.69324 -41.113964)
						(mid 344.769067 -41.067363)
						(end 344.815668 -40.991536)
					)
					(arc
						(start 344.920824 -40.991536)
						(mid 344.841022 -41.139318)
						(end 344.69324 -41.21912)
					)
				)
			)
		)
		(zone
			(layer "F.Cu")
			(hatch none 0.5)
			(connect_pads
				(clearance 0)
			)
			(min_thickness 0.25)
			(keepout
				(tracks not_allowed)
				(vias allowed)
				(pads allowed)
				(copperpour not_allowed)
				(footprints allowed)
			)
			(placement
				(enabled no)
				(sheetname "")
			)
			(fill
				(thermal_gap 0.5)
				(thermal_bridge_width 0.5)
				(island_removal_mode 0)
			)
			(polygon
				(pts
					(arc
						(start 344.69324 -40.174164)
						(mid 344.769067 -40.127563)
						(end 344.815668 -40.051736)
					)
					(arc
						(start 344.920824 -40.051736)
						(mid 344.841022 -40.199518)
						(end 344.69324 -40.27932)
					)
				)
			)
		)
		(zone
			(layer "F.Cu")
			(hatch none 0.5)
			(connect_pads
				(clearance 0)
			)
			(min_thickness 0.25)
			(keepout
				(tracks not_allowed)
				(vias allowed)
				(pads allowed)
				(copperpour not_allowed)
				(footprints allowed)
			)
			(placement
				(enabled no)
				(sheetname "")
			)
			(fill
				(thermal_gap 0.5)
				(thermal_bridge_width 0.5)
				(island_removal_mode 0)
			)
			(polygon
				(pts
					(arc
						(start 344.72118 -59.172856)
						(mid 344.699083 -59.265312)
						(end 344.72118 -59.357768)
					)
					(arc
						(start 344.647266 -59.43219)
						(mid 344.597765 -59.265312)
						(end 344.647266 -59.098434)
					)
				)
			)
		)
		(zone
			(layer "F.Cu")
			(hatch none 0.5)
			(connect_pads
				(clearance 0)
			)
			(min_thickness 0.25)
			(keepout
				(tracks not_allowed)
				(vias allowed)
				(pads allowed)
				(copperpour not_allowed)
				(footprints allowed)
			)
			(placement
				(enabled no)
				(sheetname "")
			)
			(fill
				(thermal_gap 0.5)
				(thermal_bridge_width 0.5)
				(island_removal_mode 0)
			)
			(polygon
				(pts
					(arc
						(start 344.72118 -37.542724)
						(mid 344.699083 -37.63518)
						(end 344.72118 -37.727636)
					)
					(arc
						(start 344.647266 -37.802058)
						(mid 344.597765 -37.63518)
						(end 344.647266 -37.468302)
					)
				)
			)
		)
		(zone
			(layer "F.Cu")
			(hatch none 0.5)
			(connect_pads
				(clearance 0)
			)
			(min_thickness 0.25)
			(keepout
				(tracks not_allowed)
				(vias allowed)
				(pads allowed)
				(copperpour not_allowed)
				(footprints allowed)
			)
			(placement
				(enabled no)
				(sheetname "")
			)
			(fill
				(thermal_gap 0.5)
				(thermal_bridge_width 0.5)
				(island_removal_mode 0)
			)
			(polygon
				(pts
					(arc
						(start 344.811096 -59.447684)
						(mid 344.903693 -59.469896)
						(end 344.996262 -59.447684)
					)
					(arc
						(start 345.070684 -59.521852)
						(mid 344.9037 -59.571353)
						(end 344.736674 -59.521852)
					)
				)
			)
		)
		(zone
			(layer "F.Cu")
			(hatch none 0.5)
			(connect_pads
				(clearance 0)
			)
			(min_thickness 0.25)
			(keepout
				(tracks not_allowed)
				(vias allowed)
				(pads allowed)
				(copperpour not_allowed)
				(footprints allowed)
			)
			(placement
				(enabled no)
				(sheetname "")
			)
			(fill
				(thermal_gap 0.5)
				(thermal_bridge_width 0.5)
				(island_removal_mode 0)
			)
			(polygon
				(pts
					(arc
						(start 344.811096 -37.817552)
						(mid 344.903693 -37.839764)
						(end 344.996262 -37.817552)
					)
					(arc
						(start 345.070684 -37.89172)
						(mid 344.9037 -37.941221)
						(end 344.736674 -37.89172)
					)
				)
			)
		)
		(zone
			(layer "F.Cu")
			(hatch none 0.5)
			(connect_pads
				(clearance 0)
			)
			(min_thickness 0.25)
			(keepout
				(tracks not_allowed)
				(vias allowed)
				(pads allowed)
				(copperpour not_allowed)
				(footprints allowed)
			)
			(placement
				(enabled no)
				(sheetname "")
			)
			(fill
				(thermal_gap 0.5)
				(thermal_bridge_width 0.5)
				(island_removal_mode 0)
			)
			(polygon
				(pts
					(arc
						(start 344.815668 -56.848756)
						(mid 344.769067 -56.772929)
						(end 344.69324 -56.726328)
					)
					(arc
						(start 344.69324 -56.621172)
						(mid 344.841022 -56.700974)
						(end 344.920824 -56.848756)
					)
				)
			)
		)
		(zone
			(layer "F.Cu")
			(hatch none 0.5)
			(connect_pads
				(clearance 0)
			)
			(min_thickness 0.25)
			(keepout
				(tracks not_allowed)
				(vias allowed)
				(pads allowed)
				(copperpour not_allowed)
				(footprints allowed)
			)
			(placement
				(enabled no)
				(sheetname "")
			)
			(fill
				(thermal_gap 0.5)
				(thermal_bridge_width 0.5)
				(island_removal_mode 0)
			)
			(polygon
				(pts
					(arc
						(start 344.815668 -55.908956)
						(mid 344.769067 -55.833129)
						(end 344.69324 -55.786528)
					)
					(arc
						(start 344.69324 -55.681372)
						(mid 344.841022 -55.761174)
						(end 344.920824 -55.908956)
					)
				)
			)
		)
		(zone
			(layer "F.Cu")
			(hatch none 0.5)
			(connect_pads
				(clearance 0)
			)
			(min_thickness 0.25)
			(keepout
				(tracks not_allowed)
				(vias allowed)
				(pads allowed)
				(copperpour not_allowed)
				(footprints allowed)
			)
			(placement
				(enabled no)
				(sheetname "")
			)
			(fill
				(thermal_gap 0.5)
				(thermal_bridge_width 0.5)
				(island_removal_mode 0)
			)
			(polygon
				(pts
					(arc
						(start 344.815668 -54.969156)
						(mid 344.769067 -54.893329)
						(end 344.69324 -54.846728)
					)
					(arc
						(start 344.69324 -54.741572)
						(mid 344.841022 -54.821374)
						(end 344.920824 -54.969156)
					)
				)
			)
		)
		(zone
			(layer "F.Cu")
			(hatch none 0.5)
			(connect_pads
				(clearance 0)
			)
			(min_thickness 0.25)
			(keepout
				(tracks not_allowed)
				(vias allowed)
				(pads allowed)
				(copperpour not_allowed)
				(footprints allowed)
			)
			(placement
				(enabled no)
				(sheetname "")
			)
			(fill
				(thermal_gap 0.5)
				(thermal_bridge_width 0.5)
				(island_removal_mode 0)
			)
			(polygon
				(pts
					(arc
						(start 344.815668 -54.029356)
						(mid 344.769067 -53.953529)
						(end 344.69324 -53.906928)
					)
					(arc
						(start 344.69324 -53.801772)
						(mid 344.841022 -53.881574)
						(end 344.920824 -54.029356)
					)
				)
			)
		)
		(zone
			(layer "F.Cu")
			(hatch none 0.5)
			(connect_pads
				(clearance 0)
			)
			(min_thickness 0.25)
			(keepout
				(tracks not_allowed)
				(vias allowed)
				(pads allowed)
				(copperpour not_allowed)
				(footprints allowed)
			)
			(placement
				(enabled no)
				(sheetname "")
			)
			(fill
				(thermal_gap 0.5)
				(thermal_bridge_width 0.5)
				(island_removal_mode 0)
			)
			(polygon
				(pts
					(arc
						(start 344.815668 -53.089556)
						(mid 344.769067 -53.013729)
						(end 344.69324 -52.967128)
					)
					(arc
						(start 344.69324 -52.861972)
						(mid 344.841022 -52.941774)
						(end 344.920824 -53.089556)
					)
				)
			)
		)
		(zone
			(layer "F.Cu")
			(hatch none 0.5)
			(connect_pads
				(clearance 0)
			)
			(min_thickness 0.25)
			(keepout
				(tracks not_allowed)
				(vias allowed)
				(pads allowed)
				(copperpour not_allowed)
				(footprints allowed)
			)
			(placement
				(enabled no)
				(sheetname "")
			)
			(fill
				(thermal_gap 0.5)
				(thermal_bridge_width 0.5)
				(island_removal_mode 0)
			)
			(polygon
				(pts
					(arc
						(start 344.815668 -52.149756)
						(mid 344.769067 -52.073929)
						(end 344.69324 -52.027328)
					)
					(arc
						(start 344.69324 -51.922172)
						(mid 344.841022 -52.001974)
						(end 344.920824 -52.149756)
					)
				)
			)
		)
		(zone
			(layer "F.Cu")
			(hatch none 0.5)
			(connect_pads
				(clearance 0)
			)
			(min_thickness 0.25)
			(keepout
				(tracks not_allowed)
				(vias allowed)
				(pads allowed)
				(copperpour not_allowed)
				(footprints allowed)
			)
			(placement
				(enabled no)
				(sheetname "")
			)
			(fill
				(thermal_gap 0.5)
				(thermal_bridge_width 0.5)
				(island_removal_mode 0)
			)
			(polygon
				(pts
					(arc
						(start 344.815668 -51.209956)
						(mid 344.769067 -51.134129)
						(end 344.69324 -51.087528)
					)
					(arc
						(start 344.69324 -50.982372)
						(mid 344.841022 -51.062174)
						(end 344.920824 -51.209956)
					)
				)
			)
		)
		(zone
			(layer "F.Cu")
			(hatch none 0.5)
			(connect_pads
				(clearance 0)
			)
			(min_thickness 0.25)
			(keepout
				(tracks not_allowed)
				(vias allowed)
				(pads allowed)
				(copperpour not_allowed)
				(footprints allowed)
			)
			(placement
				(enabled no)
				(sheetname "")
			)
			(fill
				(thermal_gap 0.5)
				(thermal_bridge_width 0.5)
				(island_removal_mode 0)
			)
			(polygon
				(pts
					(arc
						(start 344.815668 -50.270156)
						(mid 344.769067 -50.194329)
						(end 344.69324 -50.147728)
					)
					(arc
						(start 344.69324 -50.042572)
						(mid 344.841022 -50.122374)
						(end 344.920824 -50.270156)
					)
				)
			)
		)
		(zone
			(layer "F.Cu")
			(hatch none 0.5)
			(connect_pads
				(clearance 0)
			)
			(min_thickness 0.25)
			(keepout
				(tracks not_allowed)
				(vias allowed)
				(pads allowed)
				(copperpour not_allowed)
				(footprints allowed)
			)
			(placement
				(enabled no)
				(sheetname "")
			)
			(fill
				(thermal_gap 0.5)
				(thermal_bridge_width 0.5)
				(island_removal_mode 0)
			)
			(polygon
				(pts
					(arc
						(start 344.815668 -49.330356)
						(mid 344.769067 -49.254529)
						(end 344.69324 -49.207928)
					)
					(arc
						(start 344.69324 -49.102772)
						(mid 344.841022 -49.182574)
						(end 344.920824 -49.330356)
					)
				)
			)
		)
		(zone
			(layer "F.Cu")
			(hatch none 0.5)
			(connect_pads
				(clearance 0)
			)
			(min_thickness 0.25)
			(keepout
				(tracks not_allowed)
				(vias allowed)
				(pads allowed)
				(copperpour not_allowed)
				(footprints allowed)
			)
			(placement
				(enabled no)
				(sheetname "")
			)
			(fill
				(thermal_gap 0.5)
				(thermal_bridge_width 0.5)
				(island_removal_mode 0)
			)
			(polygon
				(pts
					(arc
						(start 344.815668 -48.390556)
						(mid 344.769067 -48.314729)
						(end 344.69324 -48.268128)
					)
					(arc
						(start 344.69324 -48.162972)
						(mid 344.841022 -48.242774)
						(end 344.920824 -48.390556)
					)
				)
			)
		)
		(zone
			(layer "F.Cu")
			(hatch none 0.5)
			(connect_pads
				(clearance 0)
			)
			(min_thickness 0.25)
			(keepout
				(tracks not_allowed)
				(vias allowed)
				(pads allowed)
				(copperpour not_allowed)
				(footprints allowed)
			)
			(placement
				(enabled no)
				(sheetname "")
			)
			(fill
				(thermal_gap 0.5)
				(thermal_bridge_width 0.5)
				(island_removal_mode 0)
			)
			(polygon
				(pts
					(arc
						(start 344.815668 -47.450756)
						(mid 344.769067 -47.374929)
						(end 344.69324 -47.328328)
					)
					(arc
						(start 344.69324 -47.223172)
						(mid 344.841022 -47.302974)
						(end 344.920824 -47.450756)
					)
				)
			)
		)
		(zone
			(layer "F.Cu")
			(hatch none 0.5)
			(connect_pads
				(clearance 0)
			)
			(min_thickness 0.25)
			(keepout
				(tracks not_allowed)
				(vias allowed)
				(pads allowed)
				(copperpour not_allowed)
				(footprints allowed)
			)
			(placement
				(enabled no)
				(sheetname "")
			)
			(fill
				(thermal_gap 0.5)
				(thermal_bridge_width 0.5)
				(island_removal_mode 0)
			)
			(polygon
				(pts
					(arc
						(start 344.815668 -46.510956)
						(mid 344.769067 -46.435129)
						(end 344.69324 -46.388528)
					)
					(arc
						(start 344.69324 -46.283372)
						(mid 344.841022 -46.363174)
						(end 344.920824 -46.510956)
					)
				)
			)
		)
		(zone
			(layer "F.Cu")
			(hatch none 0.5)
			(connect_pads
				(clearance 0)
			)
			(min_thickness 0.25)
			(keepout
				(tracks not_allowed)
				(vias allowed)
				(pads allowed)
				(copperpour not_allowed)
				(footprints allowed)
			)
			(placement
				(enabled no)
				(sheetname "")
			)
			(fill
				(thermal_gap 0.5)
				(thermal_bridge_width 0.5)
				(island_removal_mode 0)
			)
			(polygon
				(pts
					(arc
						(start 344.815668 -45.571156)
						(mid 344.769067 -45.495329)
						(end 344.69324 -45.448728)
					)
					(arc
						(start 344.69324 -45.343572)
						(mid 344.841022 -45.423374)
						(end 344.920824 -45.571156)
					)
				)
			)
		)
		(zone
			(layer "F.Cu")
			(hatch none 0.5)
			(connect_pads
				(clearance 0)
			)
			(min_thickness 0.25)
			(keepout
				(tracks not_allowed)
				(vias allowed)
				(pads allowed)
				(copperpour not_allowed)
				(footprints allowed)
			)
			(placement
				(enabled no)
				(sheetname "")
			)
			(fill
				(thermal_gap 0.5)
				(thermal_bridge_width 0.5)
				(island_removal_mode 0)
			)
			(polygon
				(pts
					(arc
						(start 344.815668 -44.631356)
						(mid 344.769067 -44.555529)
						(end 344.69324 -44.508928)
					)
					(arc
						(start 344.69324 -44.403772)
						(mid 344.841022 -44.483574)
						(end 344.920824 -44.631356)
					)
				)
			)
		)
		(zone
			(layer "F.Cu")
			(hatch none 0.5)
			(connect_pads
				(clearance 0)
			)
			(min_thickness 0.25)
			(keepout
				(tracks not_allowed)
				(vias allowed)
				(pads allowed)
				(copperpour not_allowed)
				(footprints allowed)
			)
			(placement
				(enabled no)
				(sheetname "")
			)
			(fill
				(thermal_gap 0.5)
				(thermal_bridge_width 0.5)
				(island_removal_mode 0)
			)
			(polygon
				(pts
					(arc
						(start 344.815668 -43.691556)
						(mid 344.769067 -43.615729)
						(end 344.69324 -43.569128)
					)
					(arc
						(start 344.69324 -43.463972)
						(mid 344.841022 -43.543774)
						(end 344.920824 -43.691556)
					)
				)
			)
		)
		(zone
			(layer "F.Cu")
			(hatch none 0.5)
			(connect_pads
				(clearance 0)
			)
			(min_thickness 0.25)
			(keepout
				(tracks not_allowed)
				(vias allowed)
				(pads allowed)
				(copperpour not_allowed)
				(footprints allowed)
			)
			(placement
				(enabled no)
				(sheetname "")
			)
			(fill
				(thermal_gap 0.5)
				(thermal_bridge_width 0.5)
				(island_removal_mode 0)
			)
			(polygon
				(pts
					(arc
						(start 344.815668 -42.751756)
						(mid 344.769067 -42.675929)
						(end 344.69324 -42.629328)
					)
					(arc
						(start 344.69324 -42.524172)
						(mid 344.841022 -42.603974)
						(end 344.920824 -42.751756)
					)
				)
			)
		)
		(zone
			(layer "F.Cu")
			(hatch none 0.5)
			(connect_pads
				(clearance 0)
			)
			(min_thickness 0.25)
			(keepout
				(tracks not_allowed)
				(vias allowed)
				(pads allowed)
				(copperpour not_allowed)
				(footprints allowed)
			)
			(placement
				(enabled no)
				(sheetname "")
			)
			(fill
				(thermal_gap 0.5)
				(thermal_bridge_width 0.5)
				(island_removal_mode 0)
			)
			(polygon
				(pts
					(arc
						(start 344.815668 -41.811956)
						(mid 344.769067 -41.736129)
						(end 344.69324 -41.689528)
					)
					(arc
						(start 344.69324 -41.584372)
						(mid 344.841022 -41.664174)
						(end 344.920824 -41.811956)
					)
				)
			)
		)
		(zone
			(layer "F.Cu")
			(hatch none 0.5)
			(connect_pads
				(clearance 0)
			)
			(min_thickness 0.25)
			(keepout
				(tracks not_allowed)
				(vias allowed)
				(pads allowed)
				(copperpour not_allowed)
				(footprints allowed)
			)
			(placement
				(enabled no)
				(sheetname "")
			)
			(fill
				(thermal_gap 0.5)
				(thermal_bridge_width 0.5)
				(island_removal_mode 0)
			)
			(polygon
				(pts
					(arc
						(start 344.815668 -40.872156)
						(mid 344.769067 -40.796329)
						(end 344.69324 -40.749728)
					)
					(arc
						(start 344.69324 -40.644572)
						(mid 344.841022 -40.724374)
						(end 344.920824 -40.872156)
					)
				)
			)
		)
		(zone
			(layer "F.Cu")
			(hatch none 0.5)
			(connect_pads
				(clearance 0)
			)
			(min_thickness 0.25)
			(keepout
				(tracks not_allowed)
				(vias allowed)
				(pads allowed)
				(copperpour not_allowed)
				(footprints allowed)
			)
			(placement
				(enabled no)
				(sheetname "")
			)
			(fill
				(thermal_gap 0.5)
				(thermal_bridge_width 0.5)
				(island_removal_mode 0)
			)
			(polygon
				(pts
					(arc
						(start 344.815668 -39.932356)
						(mid 344.769067 -39.856529)
						(end 344.69324 -39.809928)
					)
					(arc
						(start 344.69324 -39.704772)
						(mid 344.841022 -39.784574)
						(end 344.920824 -39.932356)
					)
				)
			)
		)
		(zone
			(layer "F.Cu")
			(hatch none 0.5)
			(connect_pads
				(clearance 0)
			)
			(min_thickness 0.25)
			(keepout
				(tracks not_allowed)
				(vias allowed)
				(pads allowed)
				(copperpour not_allowed)
				(footprints allowed)
			)
			(placement
				(enabled no)
				(sheetname "")
			)
			(fill
				(thermal_gap 0.5)
				(thermal_bridge_width 0.5)
				(island_removal_mode 0)
			)
			(polygon
				(pts
					(arc
						(start 344.996262 -59.08294)
						(mid 344.903693 -59.060843)
						(end 344.811096 -59.08294)
					)
					(arc
						(start 344.736674 -59.008772)
						(mid 344.9037 -58.959133)
						(end 345.070684 -59.008772)
					)
				)
			)
		)
		(zone
			(layer "F.Cu")
			(hatch none 0.5)
			(connect_pads
				(clearance 0)
			)
			(min_thickness 0.25)
			(keepout
				(tracks not_allowed)
				(vias allowed)
				(pads allowed)
				(copperpour not_allowed)
				(footprints allowed)
			)
			(placement
				(enabled no)
				(sheetname "")
			)
			(fill
				(thermal_gap 0.5)
				(thermal_bridge_width 0.5)
				(island_removal_mode 0)
			)
			(polygon
				(pts
					(arc
						(start 344.996262 -37.452808)
						(mid 344.903693 -37.430711)
						(end 344.811096 -37.452808)
					)
					(arc
						(start 344.736674 -37.37864)
						(mid 344.9037 -37.329001)
						(end 345.070684 -37.37864)
					)
				)
			)
		)
		(zone
			(layer "F.Cu")
			(hatch none 0.5)
			(connect_pads
				(clearance 0)
			)
			(min_thickness 0.25)
			(keepout
				(tracks not_allowed)
				(vias allowed)
				(pads allowed)
				(copperpour not_allowed)
				(footprints allowed)
			)
			(placement
				(enabled no)
				(sheetname "")
			)
			(fill
				(thermal_gap 0.5)
				(thermal_bridge_width 0.5)
				(island_removal_mode 0)
			)
			(polygon
				(pts
					(arc
						(start 345.086178 -59.357768)
						(mid 345.108275 -59.265312)
						(end 345.086178 -59.172856)
					)
					(arc
						(start 345.160092 -59.098434)
						(mid 345.209593 -59.265312)
						(end 345.160092 -59.43219)
					)
				)
			)
		)
		(zone
			(layer "F.Cu")
			(hatch none 0.5)
			(connect_pads
				(clearance 0)
			)
			(min_thickness 0.25)
			(keepout
				(tracks not_allowed)
				(vias allowed)
				(pads allowed)
				(copperpour not_allowed)
				(footprints allowed)
			)
			(placement
				(enabled no)
				(sheetname "")
			)
			(fill
				(thermal_gap 0.5)
				(thermal_bridge_width 0.5)
				(island_removal_mode 0)
			)
			(polygon
				(pts
					(arc
						(start 345.086178 -37.727636)
						(mid 345.108275 -37.63518)
						(end 345.086178 -37.542724)
					)
					(arc
						(start 345.160092 -37.468302)
						(mid 345.209593 -37.63518)
						(end 345.160092 -37.802058)
					)
				)
			)
		)
		(zone
			(layer "F.Cu")
			(hatch none 0.5)
			(connect_pads
				(clearance 0)
			)
			(min_thickness 0.25)
			(keepout
				(tracks not_allowed)
				(vias allowed)
				(pads allowed)
				(copperpour not_allowed)
				(footprints allowed)
			)
			(placement
				(enabled no)
				(sheetname "")
			)
			(fill
				(thermal_gap 0.5)
				(thermal_bridge_width 0.5)
				(island_removal_mode 0)
			)
			(polygon
				(pts
					(arc
						(start 345.721686 -59.172856)
						(mid 345.699589 -59.265312)
						(end 345.721686 -59.357768)
					)
					(arc
						(start 345.647772 -59.43219)
						(mid 345.598271 -59.265312)
						(end 345.647772 -59.098434)
					)
				)
			)
		)
		(zone
			(layer "F.Cu")
			(hatch none 0.5)
			(connect_pads
				(clearance 0)
			)
			(min_thickness 0.25)
			(keepout
				(tracks not_allowed)
				(vias allowed)
				(pads allowed)
				(copperpour not_allowed)
				(footprints allowed)
			)
			(placement
				(enabled no)
				(sheetname "")
			)
			(fill
				(thermal_gap 0.5)
				(thermal_bridge_width 0.5)
				(island_removal_mode 0)
			)
			(polygon
				(pts
					(arc
						(start 345.721686 -37.542724)
						(mid 345.699589 -37.63518)
						(end 345.721686 -37.727636)
					)
					(arc
						(start 345.647772 -37.802058)
						(mid 345.598271 -37.63518)
						(end 345.647772 -37.468302)
					)
				)
			)
		)
		(zone
			(layer "F.Cu")
			(hatch none 0.5)
			(connect_pads
				(clearance 0)
			)
			(min_thickness 0.25)
			(keepout
				(tracks not_allowed)
				(vias allowed)
				(pads allowed)
				(copperpour not_allowed)
				(footprints allowed)
			)
			(placement
				(enabled no)
				(sheetname "")
			)
			(fill
				(thermal_gap 0.5)
				(thermal_bridge_width 0.5)
				(island_removal_mode 0)
			)
			(polygon
				(pts
					(arc
						(start 345.811602 -59.447684)
						(mid 345.904199 -59.469896)
						(end 345.996768 -59.447684)
					)
					(arc
						(start 346.070936 -59.521852)
						(mid 345.904058 -59.571353)
						(end 345.73718 -59.521852)
					)
				)
			)
		)
		(zone
			(layer "F.Cu")
			(hatch none 0.5)
			(connect_pads
				(clearance 0)
			)
			(min_thickness 0.25)
			(keepout
				(tracks not_allowed)
				(vias allowed)
				(pads allowed)
				(copperpour not_allowed)
				(footprints allowed)
			)
			(placement
				(enabled no)
				(sheetname "")
			)
			(fill
				(thermal_gap 0.5)
				(thermal_bridge_width 0.5)
				(island_removal_mode 0)
			)
			(polygon
				(pts
					(arc
						(start 345.811602 -37.817552)
						(mid 345.904199 -37.839764)
						(end 345.996768 -37.817552)
					)
					(arc
						(start 346.070936 -37.89172)
						(mid 345.904058 -37.941221)
						(end 345.73718 -37.89172)
					)
				)
			)
		)
		(zone
			(layer "F.Cu")
			(hatch none 0.5)
			(connect_pads
				(clearance 0)
			)
			(min_thickness 0.25)
			(keepout
				(tracks not_allowed)
				(vias allowed)
				(pads allowed)
				(copperpour not_allowed)
				(footprints allowed)
			)
			(placement
				(enabled no)
				(sheetname "")
			)
			(fill
				(thermal_gap 0.5)
				(thermal_bridge_width 0.5)
				(island_removal_mode 0)
			)
			(polygon
				(pts
					(arc
						(start 345.996768 -59.08294)
						(mid 345.904199 -59.060843)
						(end 345.811602 -59.08294)
					)
					(arc
						(start 345.73718 -59.008772)
						(mid 345.904058 -58.959271)
						(end 346.070936 -59.008772)
					)
				)
			)
		)
		(zone
			(layer "F.Cu")
			(hatch none 0.5)
			(connect_pads
				(clearance 0)
			)
			(min_thickness 0.25)
			(keepout
				(tracks not_allowed)
				(vias allowed)
				(pads allowed)
				(copperpour not_allowed)
				(footprints allowed)
			)
			(placement
				(enabled no)
				(sheetname "")
			)
			(fill
				(thermal_gap 0.5)
				(thermal_bridge_width 0.5)
				(island_removal_mode 0)
			)
			(polygon
				(pts
					(arc
						(start 345.996768 -37.452808)
						(mid 345.904199 -37.430711)
						(end 345.811602 -37.452808)
					)
					(arc
						(start 345.73718 -37.37864)
						(mid 345.904058 -37.329139)
						(end 346.070936 -37.37864)
					)
				)
			)
		)
		(zone
			(layer "F.Cu")
			(hatch none 0.5)
			(connect_pads
				(clearance 0)
			)
			(min_thickness 0.25)
			(keepout
				(tracks not_allowed)
				(vias allowed)
				(pads allowed)
				(copperpour not_allowed)
				(footprints allowed)
			)
			(placement
				(enabled no)
				(sheetname "")
			)
			(fill
				(thermal_gap 0.5)
				(thermal_bridge_width 0.5)
				(island_removal_mode 0)
			)
			(polygon
				(pts
					(arc
						(start 346.086684 -59.357768)
						(mid 346.108781 -59.265312)
						(end 346.086684 -59.172856)
					)
					(arc
						(start 346.160598 -59.098434)
						(mid 346.210099 -59.265312)
						(end 346.160598 -59.43219)
					)
				)
			)
		)
		(zone
			(layer "F.Cu")
			(hatch none 0.5)
			(connect_pads
				(clearance 0)
			)
			(min_thickness 0.25)
			(keepout
				(tracks not_allowed)
				(vias allowed)
				(pads allowed)
				(copperpour not_allowed)
				(footprints allowed)
			)
			(placement
				(enabled no)
				(sheetname "")
			)
			(fill
				(thermal_gap 0.5)
				(thermal_bridge_width 0.5)
				(island_removal_mode 0)
			)
			(polygon
				(pts
					(arc
						(start 346.086684 -37.727636)
						(mid 346.108781 -37.63518)
						(end 346.086684 -37.542724)
					)
					(arc
						(start 346.160598 -37.468302)
						(mid 346.210099 -37.63518)
						(end 346.160598 -37.802058)
					)
				)
			)
		)
		(zone
			(layer "F.Cu")
			(hatch none 0.5)
			(connect_pads
				(clearance 0)
			)
			(min_thickness 0.25)
			(keepout
				(tracks not_allowed)
				(vias allowed)
				(pads allowed)
				(copperpour not_allowed)
				(footprints allowed)
			)
			(placement
				(enabled no)
				(sheetname "")
			)
			(fill
				(thermal_gap 0.5)
				(thermal_bridge_width 0.5)
				(island_removal_mode 0)
			)
			(polygon
				(pts
					(arc
						(start 346.377006 -59.172856)
						(mid 346.354909 -59.265312)
						(end 346.377006 -59.357768)
					)
					(arc
						(start 346.302838 -59.43219)
						(mid 346.253337 -59.265312)
						(end 346.302838 -59.098434)
					)
				)
			)
		)
		(zone
			(layer "F.Cu")
			(hatch none 0.5)
			(connect_pads
				(clearance 0)
			)
			(min_thickness 0.25)
			(keepout
				(tracks not_allowed)
				(vias allowed)
				(pads allowed)
				(copperpour not_allowed)
				(footprints allowed)
			)
			(placement
				(enabled no)
				(sheetname "")
			)
			(fill
				(thermal_gap 0.5)
				(thermal_bridge_width 0.5)
				(island_removal_mode 0)
			)
			(polygon
				(pts
					(arc
						(start 346.377006 -37.542724)
						(mid 346.354909 -37.63518)
						(end 346.377006 -37.727636)
					)
					(arc
						(start 346.302838 -37.802058)
						(mid 346.253337 -37.63518)
						(end 346.302838 -37.468302)
					)
				)
			)
		)
		(zone
			(layer "F.Cu")
			(hatch none 0.5)
			(connect_pads
				(clearance 0)
			)
			(min_thickness 0.25)
			(keepout
				(tracks not_allowed)
				(vias allowed)
				(pads allowed)
				(copperpour not_allowed)
				(footprints allowed)
			)
			(placement
				(enabled no)
				(sheetname "")
			)
			(fill
				(thermal_gap 0.5)
				(thermal_bridge_width 0.5)
				(island_removal_mode 0)
			)
			(polygon
				(pts
					(arc
						(start 346.466922 -59.447684)
						(mid 346.559378 -59.469781)
						(end 346.651834 -59.447684)
					)
					(arc
						(start 346.726256 -59.521852)
						(mid 346.559378 -59.571353)
						(end 346.3925 -59.521852)
					)
				)
			)
		)
		(zone
			(layer "F.Cu")
			(hatch none 0.5)
			(connect_pads
				(clearance 0)
			)
			(min_thickness 0.25)
			(keepout
				(tracks not_allowed)
				(vias allowed)
				(pads allowed)
				(copperpour not_allowed)
				(footprints allowed)
			)
			(placement
				(enabled no)
				(sheetname "")
			)
			(fill
				(thermal_gap 0.5)
				(thermal_bridge_width 0.5)
				(island_removal_mode 0)
			)
			(polygon
				(pts
					(arc
						(start 346.466922 -37.817552)
						(mid 346.559378 -37.839649)
						(end 346.651834 -37.817552)
					)
					(arc
						(start 346.726256 -37.89172)
						(mid 346.559378 -37.941221)
						(end 346.3925 -37.89172)
					)
				)
			)
		)
		(zone
			(layer "F.Cu")
			(hatch none 0.5)
			(connect_pads
				(clearance 0)
			)
			(min_thickness 0.25)
			(keepout
				(tracks not_allowed)
				(vias allowed)
				(pads allowed)
				(copperpour not_allowed)
				(footprints allowed)
			)
			(placement
				(enabled no)
				(sheetname "")
			)
			(fill
				(thermal_gap 0.5)
				(thermal_bridge_width 0.5)
				(island_removal_mode 0)
			)
			(polygon
				(pts
					(arc
						(start 346.651834 -59.08294)
						(mid 346.559378 -59.060843)
						(end 346.466922 -59.08294)
					)
					(arc
						(start 346.3925 -59.008772)
						(mid 346.559378 -58.959271)
						(end 346.726256 -59.008772)
					)
				)
			)
		)
		(zone
			(layer "F.Cu")
			(hatch none 0.5)
			(connect_pads
				(clearance 0)
			)
			(min_thickness 0.25)
			(keepout
				(tracks not_allowed)
				(vias allowed)
				(pads allowed)
				(copperpour not_allowed)
				(footprints allowed)
			)
			(placement
				(enabled no)
				(sheetname "")
			)
			(fill
				(thermal_gap 0.5)
				(thermal_bridge_width 0.5)
				(island_removal_mode 0)
			)
			(polygon
				(pts
					(arc
						(start 346.651834 -37.452808)
						(mid 346.559378 -37.430711)
						(end 346.466922 -37.452808)
					)
					(arc
						(start 346.3925 -37.37864)
						(mid 346.559378 -37.329139)
						(end 346.726256 -37.37864)
					)
				)
			)
		)
		(zone
			(layer "F.Cu")
			(hatch none 0.5)
			(connect_pads
				(clearance 0)
			)
			(min_thickness 0.25)
			(keepout
				(tracks not_allowed)
				(vias allowed)
				(pads allowed)
				(copperpour not_allowed)
				(footprints allowed)
			)
			(placement
				(enabled no)
				(sheetname "")
			)
			(fill
				(thermal_gap 0.5)
				(thermal_bridge_width 0.5)
				(island_removal_mode 0)
			)
			(polygon
				(pts
					(arc
						(start 346.74175 -59.357768)
						(mid 346.763847 -59.265312)
						(end 346.74175 -59.172856)
					)
					(arc
						(start 346.815918 -59.098434)
						(mid 346.865419 -59.265312)
						(end 346.815918 -59.43219)
					)
				)
			)
		)
		(zone
			(layer "F.Cu")
			(hatch none 0.5)
			(connect_pads
				(clearance 0)
			)
			(min_thickness 0.25)
			(keepout
				(tracks not_allowed)
				(vias allowed)
				(pads allowed)
				(copperpour not_allowed)
				(footprints allowed)
			)
			(placement
				(enabled no)
				(sheetname "")
			)
			(fill
				(thermal_gap 0.5)
				(thermal_bridge_width 0.5)
				(island_removal_mode 0)
			)
			(polygon
				(pts
					(arc
						(start 346.74175 -37.727636)
						(mid 346.763847 -37.63518)
						(end 346.74175 -37.542724)
					)
					(arc
						(start 346.815918 -37.468302)
						(mid 346.865419 -37.63518)
						(end 346.815918 -37.802058)
					)
				)
			)
		)
		(zone
			(layer "F.Cu")
			(hatch none 0.5)
			(connect_pads
				(clearance 0)
			)
			(min_thickness 0.25)
			(keepout
				(tracks not_allowed)
				(vias allowed)
				(pads allowed)
				(copperpour not_allowed)
				(footprints allowed)
			)
			(placement
				(enabled no)
				(sheetname "")
			)
			(fill
				(thermal_gap 0.5)
				(thermal_bridge_width 0.5)
				(island_removal_mode 0)
			)
			(polygon
				(pts
					(arc
						(start 347.032326 -58.517536)
						(mid 347.010229 -58.609992)
						(end 347.032326 -58.702448)
					)
					(arc
						(start 346.958158 -58.77687)
						(mid 346.908657 -58.609992)
						(end 346.958158 -58.443114)
					)
				)
			)
		)
		(zone
			(layer "F.Cu")
			(hatch none 0.5)
			(connect_pads
				(clearance 0)
			)
			(min_thickness 0.25)
			(keepout
				(tracks not_allowed)
				(vias allowed)
				(pads allowed)
				(copperpour not_allowed)
				(footprints allowed)
			)
			(placement
				(enabled no)
				(sheetname "")
			)
			(fill
				(thermal_gap 0.5)
				(thermal_bridge_width 0.5)
				(island_removal_mode 0)
			)
			(polygon
				(pts
					(arc
						(start 347.032326 -57.86247)
						(mid 347.010229 -57.954926)
						(end 347.032326 -58.047382)
					)
					(arc
						(start 346.958158 -58.121804)
						(mid 346.908657 -57.954926)
						(end 346.958158 -57.788048)
					)
				)
			)
		)
		(zone
			(layer "F.Cu")
			(hatch none 0.5)
			(connect_pads
				(clearance 0)
			)
			(min_thickness 0.25)
			(keepout
				(tracks not_allowed)
				(vias allowed)
				(pads allowed)
				(copperpour not_allowed)
				(footprints allowed)
			)
			(placement
				(enabled no)
				(sheetname "")
			)
			(fill
				(thermal_gap 0.5)
				(thermal_bridge_width 0.5)
				(island_removal_mode 0)
			)
			(polygon
				(pts
					(arc
						(start 347.032326 -56.861964)
						(mid 347.010229 -56.95442)
						(end 347.032326 -57.046876)
					)
					(arc
						(start 346.958158 -57.121298)
						(mid 346.908657 -56.95442)
						(end 346.958158 -56.787542)
					)
				)
			)
		)
		(zone
			(layer "F.Cu")
			(hatch none 0.5)
			(connect_pads
				(clearance 0)
			)
			(min_thickness 0.25)
			(keepout
				(tracks not_allowed)
				(vias allowed)
				(pads allowed)
				(copperpour not_allowed)
				(footprints allowed)
			)
			(placement
				(enabled no)
				(sheetname "")
			)
			(fill
				(thermal_gap 0.5)
				(thermal_bridge_width 0.5)
				(island_removal_mode 0)
			)
			(polygon
				(pts
					(arc
						(start 347.032326 -39.853616)
						(mid 347.010229 -39.946072)
						(end 347.032326 -40.038528)
					)
					(arc
						(start 346.958158 -40.11295)
						(mid 346.908657 -39.946072)
						(end 346.958158 -39.779194)
					)
				)
			)
		)
		(zone
			(layer "F.Cu")
			(hatch none 0.5)
			(connect_pads
				(clearance 0)
			)
			(min_thickness 0.25)
			(keepout
				(tracks not_allowed)
				(vias allowed)
				(pads allowed)
				(copperpour not_allowed)
				(footprints allowed)
			)
			(placement
				(enabled no)
				(sheetname "")
			)
			(fill
				(thermal_gap 0.5)
				(thermal_bridge_width 0.5)
				(island_removal_mode 0)
			)
			(polygon
				(pts
					(arc
						(start 347.032326 -38.85311)
						(mid 347.010229 -38.945566)
						(end 347.032326 -39.038022)
					)
					(arc
						(start 346.958158 -39.112444)
						(mid 346.908657 -38.945566)
						(end 346.958158 -38.778688)
					)
				)
			)
		)
		(zone
			(layer "F.Cu")
			(hatch none 0.5)
			(connect_pads
				(clearance 0)
			)
			(min_thickness 0.25)
			(keepout
				(tracks not_allowed)
				(vias allowed)
				(pads allowed)
				(copperpour not_allowed)
				(footprints allowed)
			)
			(placement
				(enabled no)
				(sheetname "")
			)
			(fill
				(thermal_gap 0.5)
				(thermal_bridge_width 0.5)
				(island_removal_mode 0)
			)
			(polygon
				(pts
					(arc
						(start 347.032326 -38.198044)
						(mid 347.010229 -38.2905)
						(end 347.032326 -38.382956)
					)
					(arc
						(start 346.958158 -38.457378)
						(mid 346.908657 -38.2905)
						(end 346.958158 -38.123622)
					)
				)
			)
		)
		(zone
			(layer "F.Cu")
			(hatch none 0.5)
			(connect_pads
				(clearance 0)
			)
			(min_thickness 0.25)
			(keepout
				(tracks not_allowed)
				(vias allowed)
				(pads allowed)
				(copperpour not_allowed)
				(footprints allowed)
			)
			(placement
				(enabled no)
				(sheetname "")
			)
			(fill
				(thermal_gap 0.5)
				(thermal_bridge_width 0.5)
				(island_removal_mode 0)
			)
			(polygon
				(pts
					(arc
						(start 347.122242 -58.792364)
						(mid 347.214698 -58.814461)
						(end 347.307154 -58.792364)
					)
					(arc
						(start 347.381576 -58.866532)
						(mid 347.214698 -58.916033)
						(end 347.04782 -58.866532)
					)
				)
			)
		)
		(zone
			(layer "F.Cu")
			(hatch none 0.5)
			(connect_pads
				(clearance 0)
			)
			(min_thickness 0.25)
			(keepout
				(tracks not_allowed)
				(vias allowed)
				(pads allowed)
				(copperpour not_allowed)
				(footprints allowed)
			)
			(placement
				(enabled no)
				(sheetname "")
			)
			(fill
				(thermal_gap 0.5)
				(thermal_bridge_width 0.5)
				(island_removal_mode 0)
			)
			(polygon
				(pts
					(arc
						(start 347.122242 -58.137298)
						(mid 347.214698 -58.159395)
						(end 347.307154 -58.137298)
					)
					(arc
						(start 347.381576 -58.211466)
						(mid 347.214698 -58.260967)
						(end 347.04782 -58.211466)
					)
				)
			)
		)
		(zone
			(layer "F.Cu")
			(hatch none 0.5)
			(connect_pads
				(clearance 0)
			)
			(min_thickness 0.25)
			(keepout
				(tracks not_allowed)
				(vias allowed)
				(pads allowed)
				(copperpour not_allowed)
				(footprints allowed)
			)
			(placement
				(enabled no)
				(sheetname "")
			)
			(fill
				(thermal_gap 0.5)
				(thermal_bridge_width 0.5)
				(island_removal_mode 0)
			)
			(polygon
				(pts
					(arc
						(start 347.122242 -57.136792)
						(mid 347.214698 -57.158889)
						(end 347.307154 -57.136792)
					)
					(arc
						(start 347.381576 -57.21096)
						(mid 347.214698 -57.260461)
						(end 347.04782 -57.21096)
					)
				)
			)
		)
		(zone
			(layer "F.Cu")
			(hatch none 0.5)
			(connect_pads
				(clearance 0)
			)
			(min_thickness 0.25)
			(keepout
				(tracks not_allowed)
				(vias allowed)
				(pads allowed)
				(copperpour not_allowed)
				(footprints allowed)
			)
			(placement
				(enabled no)
				(sheetname "")
			)
			(fill
				(thermal_gap 0.5)
				(thermal_bridge_width 0.5)
				(island_removal_mode 0)
			)
			(polygon
				(pts
					(arc
						(start 347.122242 -40.128444)
						(mid 347.214698 -40.150541)
						(end 347.307154 -40.128444)
					)
					(arc
						(start 347.381576 -40.202612)
						(mid 347.214698 -40.252113)
						(end 347.04782 -40.202612)
					)
				)
			)
		)
		(zone
			(layer "F.Cu")
			(hatch none 0.5)
			(connect_pads
				(clearance 0)
			)
			(min_thickness 0.25)
			(keepout
				(tracks not_allowed)
				(vias allowed)
				(pads allowed)
				(copperpour not_allowed)
				(footprints allowed)
			)
			(placement
				(enabled no)
				(sheetname "")
			)
			(fill
				(thermal_gap 0.5)
				(thermal_bridge_width 0.5)
				(island_removal_mode 0)
			)
			(polygon
				(pts
					(arc
						(start 347.122242 -39.127938)
						(mid 347.214698 -39.150035)
						(end 347.307154 -39.127938)
					)
					(arc
						(start 347.381576 -39.202106)
						(mid 347.214698 -39.251607)
						(end 347.04782 -39.202106)
					)
				)
			)
		)
		(zone
			(layer "F.Cu")
			(hatch none 0.5)
			(connect_pads
				(clearance 0)
			)
			(min_thickness 0.25)
			(keepout
				(tracks not_allowed)
				(vias allowed)
				(pads allowed)
				(copperpour not_allowed)
				(footprints allowed)
			)
			(placement
				(enabled no)
				(sheetname "")
			)
			(fill
				(thermal_gap 0.5)
				(thermal_bridge_width 0.5)
				(island_removal_mode 0)
			)
			(polygon
				(pts
					(arc
						(start 347.122242 -38.472872)
						(mid 347.214698 -38.494969)
						(end 347.307154 -38.472872)
					)
					(arc
						(start 347.381576 -38.54704)
						(mid 347.214698 -38.596541)
						(end 347.04782 -38.54704)
					)
				)
			)
		)
		(zone
			(layer "F.Cu")
			(hatch none 0.5)
			(connect_pads
				(clearance 0)
			)
			(min_thickness 0.25)
			(keepout
				(tracks not_allowed)
				(vias allowed)
				(pads allowed)
				(copperpour not_allowed)
				(footprints allowed)
			)
			(placement
				(enabled no)
				(sheetname "")
			)
			(fill
				(thermal_gap 0.5)
				(thermal_bridge_width 0.5)
				(island_removal_mode 0)
			)
			(polygon
				(pts
					(arc
						(start 347.307154 -58.42762)
						(mid 347.214698 -58.405523)
						(end 347.122242 -58.42762)
					)
					(arc
						(start 347.04782 -58.353452)
						(mid 347.214698 -58.303951)
						(end 347.381576 -58.353452)
					)
				)
			)
		)
		(zone
			(layer "F.Cu")
			(hatch none 0.5)
			(connect_pads
				(clearance 0)
			)
			(min_thickness 0.25)
			(keepout
				(tracks not_allowed)
				(vias allowed)
				(pads allowed)
				(copperpour not_allowed)
				(footprints allowed)
			)
			(placement
				(enabled no)
				(sheetname "")
			)
			(fill
				(thermal_gap 0.5)
				(thermal_bridge_width 0.5)
				(island_removal_mode 0)
			)
			(polygon
				(pts
					(arc
						(start 347.307154 -57.772554)
						(mid 347.214698 -57.750457)
						(end 347.122242 -57.772554)
					)
					(arc
						(start 347.04782 -57.698386)
						(mid 347.214698 -57.648885)
						(end 347.381576 -57.698386)
					)
				)
			)
		)
		(zone
			(layer "F.Cu")
			(hatch none 0.5)
			(connect_pads
				(clearance 0)
			)
			(min_thickness 0.25)
			(keepout
				(tracks not_allowed)
				(vias allowed)
				(pads allowed)
				(copperpour not_allowed)
				(footprints allowed)
			)
			(placement
				(enabled no)
				(sheetname "")
			)
			(fill
				(thermal_gap 0.5)
				(thermal_bridge_width 0.5)
				(island_removal_mode 0)
			)
			(polygon
				(pts
					(arc
						(start 347.307154 -56.772048)
						(mid 347.214698 -56.749951)
						(end 347.122242 -56.772048)
					)
					(arc
						(start 347.04782 -56.69788)
						(mid 347.214698 -56.648379)
						(end 347.381576 -56.69788)
					)
				)
			)
		)
		(zone
			(layer "F.Cu")
			(hatch none 0.5)
			(connect_pads
				(clearance 0)
			)
			(min_thickness 0.25)
			(keepout
				(tracks not_allowed)
				(vias allowed)
				(pads allowed)
				(copperpour not_allowed)
				(footprints allowed)
			)
			(placement
				(enabled no)
				(sheetname "")
			)
			(fill
				(thermal_gap 0.5)
				(thermal_bridge_width 0.5)
				(island_removal_mode 0)
			)
			(polygon
				(pts
					(arc
						(start 347.307154 -39.7637)
						(mid 347.214698 -39.741603)
						(end 347.122242 -39.7637)
					)
					(arc
						(start 347.04782 -39.689532)
						(mid 347.214698 -39.640031)
						(end 347.381576 -39.689532)
					)
				)
			)
		)
		(zone
			(layer "F.Cu")
			(hatch none 0.5)
			(connect_pads
				(clearance 0)
			)
			(min_thickness 0.25)
			(keepout
				(tracks not_allowed)
				(vias allowed)
				(pads allowed)
				(copperpour not_allowed)
				(footprints allowed)
			)
			(placement
				(enabled no)
				(sheetname "")
			)
			(fill
				(thermal_gap 0.5)
				(thermal_bridge_width 0.5)
				(island_removal_mode 0)
			)
			(polygon
				(pts
					(arc
						(start 347.307154 -38.763194)
						(mid 347.214698 -38.741097)
						(end 347.122242 -38.763194)
					)
					(arc
						(start 347.04782 -38.689026)
						(mid 347.214698 -38.639525)
						(end 347.381576 -38.689026)
					)
				)
			)
		)
		(zone
			(layer "F.Cu")
			(hatch none 0.5)
			(connect_pads
				(clearance 0)
			)
			(min_thickness 0.25)
			(keepout
				(tracks not_allowed)
				(vias allowed)
				(pads allowed)
				(copperpour not_allowed)
				(footprints allowed)
			)
			(placement
				(enabled no)
				(sheetname "")
			)
			(fill
				(thermal_gap 0.5)
				(thermal_bridge_width 0.5)
				(island_removal_mode 0)
			)
			(polygon
				(pts
					(arc
						(start 347.307154 -38.108128)
						(mid 347.214698 -38.086031)
						(end 347.122242 -38.108128)
					)
					(arc
						(start 347.04782 -38.03396)
						(mid 347.214698 -37.984459)
						(end 347.381576 -38.03396)
					)
				)
			)
		)
		(zone
			(layer "F.Cu")
			(hatch none 0.5)
			(connect_pads
				(clearance 0)
			)
			(min_thickness 0.25)
			(keepout
				(tracks not_allowed)
				(vias allowed)
				(pads allowed)
				(copperpour not_allowed)
				(footprints allowed)
			)
			(placement
				(enabled no)
				(sheetname "")
			)
			(fill
				(thermal_gap 0.5)
				(thermal_bridge_width 0.5)
				(island_removal_mode 0)
			)
			(polygon
				(pts
					(arc
						(start 347.39707 -58.702448)
						(mid 347.419167 -58.609992)
						(end 347.39707 -58.517536)
					)
					(arc
						(start 347.471238 -58.443114)
						(mid 347.520739 -58.609992)
						(end 347.471238 -58.77687)
					)
				)
			)
		)
		(zone
			(layer "F.Cu")
			(hatch none 0.5)
			(connect_pads
				(clearance 0)
			)
			(min_thickness 0.25)
			(keepout
				(tracks not_allowed)
				(vias allowed)
				(pads allowed)
				(copperpour not_allowed)
				(footprints allowed)
			)
			(placement
				(enabled no)
				(sheetname "")
			)
			(fill
				(thermal_gap 0.5)
				(thermal_bridge_width 0.5)
				(island_removal_mode 0)
			)
			(polygon
				(pts
					(arc
						(start 347.39707 -58.047382)
						(mid 347.419167 -57.954926)
						(end 347.39707 -57.86247)
					)
					(arc
						(start 347.471238 -57.788048)
						(mid 347.520739 -57.954926)
						(end 347.471238 -58.121804)
					)
				)
			)
		)
		(zone
			(layer "F.Cu")
			(hatch none 0.5)
			(connect_pads
				(clearance 0)
			)
			(min_thickness 0.25)
			(keepout
				(tracks not_allowed)
				(vias allowed)
				(pads allowed)
				(copperpour not_allowed)
				(footprints allowed)
			)
			(placement
				(enabled no)
				(sheetname "")
			)
			(fill
				(thermal_gap 0.5)
				(thermal_bridge_width 0.5)
				(island_removal_mode 0)
			)
			(polygon
				(pts
					(arc
						(start 347.39707 -57.046876)
						(mid 347.419167 -56.95442)
						(end 347.39707 -56.861964)
					)
					(arc
						(start 347.471238 -56.787542)
						(mid 347.520739 -56.95442)
						(end 347.471238 -57.121298)
					)
				)
			)
		)
		(zone
			(layer "F.Cu")
			(hatch none 0.5)
			(connect_pads
				(clearance 0)
			)
			(min_thickness 0.25)
			(keepout
				(tracks not_allowed)
				(vias allowed)
				(pads allowed)
				(copperpour not_allowed)
				(footprints allowed)
			)
			(placement
				(enabled no)
				(sheetname "")
			)
			(fill
				(thermal_gap 0.5)
				(thermal_bridge_width 0.5)
				(island_removal_mode 0)
			)
			(polygon
				(pts
					(arc
						(start 347.39707 -40.038528)
						(mid 347.419167 -39.946072)
						(end 347.39707 -39.853616)
					)
					(arc
						(start 347.471238 -39.779194)
						(mid 347.520739 -39.946072)
						(end 347.471238 -40.11295)
					)
				)
			)
		)
		(zone
			(layer "F.Cu")
			(hatch none 0.5)
			(connect_pads
				(clearance 0)
			)
			(min_thickness 0.25)
			(keepout
				(tracks not_allowed)
				(vias allowed)
				(pads allowed)
				(copperpour not_allowed)
				(footprints allowed)
			)
			(placement
				(enabled no)
				(sheetname "")
			)
			(fill
				(thermal_gap 0.5)
				(thermal_bridge_width 0.5)
				(island_removal_mode 0)
			)
			(polygon
				(pts
					(arc
						(start 347.39707 -39.038022)
						(mid 347.419167 -38.945566)
						(end 347.39707 -38.85311)
					)
					(arc
						(start 347.471238 -38.778688)
						(mid 347.520739 -38.945566)
						(end 347.471238 -39.112444)
					)
				)
			)
		)
		(zone
			(layer "F.Cu")
			(hatch none 0.5)
			(connect_pads
				(clearance 0)
			)
			(min_thickness 0.25)
			(keepout
				(tracks not_allowed)
				(vias allowed)
				(pads allowed)
				(copperpour not_allowed)
				(footprints allowed)
			)
			(placement
				(enabled no)
				(sheetname "")
			)
			(fill
				(thermal_gap 0.5)
				(thermal_bridge_width 0.5)
				(island_removal_mode 0)
			)
			(polygon
				(pts
					(arc
						(start 347.39707 -38.382956)
						(mid 347.419167 -38.2905)
						(end 347.39707 -38.198044)
					)
					(arc
						(start 347.471238 -38.123622)
						(mid 347.520739 -38.2905)
						(end 347.471238 -38.457378)
					)
				)
			)
		)
	)
	(footprint ""
		(layer "F.Cu")
		(at 85.39607 -343.496138 -90)
		(property "Reference" "PC484_P1_7"
			(at 0 0 270)
			(layer "F.SilkS")
			(hide yes)
			(effects
				(font
					(size 1.27 1.27)
				)
			)
		)
		(property "Value" ""
			(at 0 0 270)
			(layer "F.Fab")
			(effects
				(font
					(size 1.27 1.27)
				)
			)
		)
		(duplicate_pad_numbers_are_jumpers no)
		(fp_line
			(start -0.7874 0.4064)
			(end -0.7874 -0.4064)
			(stroke
				(width 0.1524)
				(type default)
			)
			(layer "F.SilkS")
		)
		(fp_line
			(start 0.7874 0.4064)
			(end -0.7874 0.4064)
			(stroke
				(width 0.1524)
				(type default)
			)
			(layer "F.SilkS")
		)
		(fp_line
			(start -0.7874 -0.4064)
			(end 0.7874 -0.4064)
			(stroke
				(width 0.1524)
				(type default)
			)
			(layer "F.SilkS")
		)
		(fp_line
			(start 0.7874 -0.4064)
			(end 0.7874 0.4064)
			(stroke
				(width 0.1524)
				(type default)
			)
			(layer "F.SilkS")
		)
		(fp_line
			(start -0.67945 0.3048)
			(end -0.67945 -0.305054)
			(stroke
				(width 0.1)
				(type default)
			)
			(layer "F.Fab")
		)
		(fp_line
			(start -0.12065 0.3048)
			(end -0.67945 0.3048)
			(stroke
				(width 0.1)
				(type default)
			)
			(layer "F.Fab")
		)
		(fp_line
			(start 0.120396 0.3048)
			(end 0.120396 0.2794)
			(stroke
				(width 0.1)
				(type default)
			)
			(layer "F.Fab")
		)
		(fp_line
			(start 0.67945 0.3048)
			(end 0.120396 0.3048)
			(stroke
				(width 0.1)
				(type default)
			)
			(layer "F.Fab")
		)
		(fp_line
			(start -0.12065 0.2794)
			(end -0.12065 0.3048)
			(stroke
				(width 0.1)
				(type default)
			)
			(layer "F.Fab")
		)
		(fp_line
			(start 0.120396 0.2794)
			(end -0.12065 0.2794)
			(stroke
				(width 0.1)
				(type default)
			)
			(layer "F.Fab")
		)
		(fp_line
			(start -0.12065 -0.2794)
			(end 0.12065 -0.2794)
			(stroke
				(width 0.1)
				(type default)
			)
			(layer "F.Fab")
		)
		(fp_line
			(start 0.12065 -0.2794)
			(end 0.12065 -0.3048)
			(stroke
				(width 0.1)
				(type default)
			)
			(layer "F.Fab")
		)
		(fp_line
			(start 0.12065 -0.3048)
			(end 0.67945 -0.3048)
			(stroke
				(width 0.1)
				(type default)
			)
			(layer "F.Fab")
		)
		(fp_line
			(start 0.67945 -0.3048)
			(end 0.67945 0.3048)
			(stroke
				(width 0.1)
				(type default)
			)
			(layer "F.Fab")
		)
		(fp_line
			(start -0.67945 -0.305054)
			(end -0.12065 -0.305054)
			(stroke
				(width 0.1)
				(type default)
			)
			(layer "F.Fab")
		)
		(fp_line
			(start -0.12065 -0.305054)
			(end -0.12065 -0.2794)
			(stroke
				(width 0.1)
				(type default)
			)
			(layer "F.Fab")
		)
		(pad "1" smd circle
			(at -0.40005 0 270)
			(size 0 0)
			(layers "F.Cu" "F.Mask" "F.Paste")
			(net "SW_P12V_PVCCIN_CPU1_FLT")
		)
		(pad "2" smd circle
			(at 0.40005 0 270)
			(size 0 0)
			(layers "F.Cu" "F.Mask" "F.Paste")
			(net "GND")
		)
	)
	(footprint ""
		(layer "F.Cu")
		(at 179.12588 -130.266948 90)
		(property "Reference" "R1417"
			(at 0 0 90)
			(layer "F.SilkS")
			(hide yes)
			(effects
				(font
					(size 1.27 1.27)
				)
			)
		)
		(property "Value" ""
			(at 0 0 90)
			(layer "F.Fab")
			(effects
				(font
					(size 1.27 1.27)
				)
			)
		)
		(duplicate_pad_numbers_are_jumpers no)
		(fp_line
			(start 0.7874 -0.4064)
			(end 0.7874 0.4064)
			(stroke
				(width 0.1524)
				(type default)
			)
			(layer "F.SilkS")
		)
		(fp_line
			(start -0.7874 -0.4064)
			(end 0.7874 -0.4064)
			(stroke
				(width 0.1524)
				(type default)
			)
			(layer "F.SilkS")
		)
		(fp_line
			(start 0.7874 0.4064)
			(end -0.7874 0.4064)
			(stroke
				(width 0.1524)
				(type default)
			)
			(layer "F.SilkS")
		)
		(fp_line
			(start -0.7874 0.4064)
			(end -0.7874 -0.4064)
			(stroke
				(width 0.1524)
				(type default)
			)
			(layer "F.SilkS")
		)
		(fp_line
			(start -0.12065 -0.305054)
			(end -0.12065 -0.2794)
			(stroke
				(width 0.1)
				(type default)
			)
			(layer "F.Fab")
		)
		(fp_line
			(start -0.67945 -0.305054)
			(end -0.12065 -0.305054)
			(stroke
				(width 0.1)
				(type default)
			)
			(layer "F.Fab")
		)
		(fp_line
			(start 0.67945 -0.3048)
			(end 0.67945 0.3048)
			(stroke
				(width 0.1)
				(type default)
			)
			(layer "F.Fab")
		)
		(fp_line
			(start 0.12065 -0.3048)
			(end 0.67945 -0.3048)
			(stroke
				(width 0.1)
				(type default)
			)
			(layer "F.Fab")
		)
		(fp_line
			(start 0.12065 -0.2794)
			(end 0.12065 -0.3048)
			(stroke
				(width 0.1)
				(type default)
			)
			(layer "F.Fab")
		)
		(fp_line
			(start -0.12065 -0.2794)
			(end 0.12065 -0.2794)
			(stroke
				(width 0.1)
				(type default)
			)
			(layer "F.Fab")
		)
		(fp_line
			(start 0.120396 0.2794)
			(end -0.12065 0.2794)
			(stroke
				(width 0.1)
				(type default)
			)
			(layer "F.Fab")
		)
		(fp_line
			(start -0.12065 0.2794)
			(end -0.12065 0.3048)
			(stroke
				(width 0.1)
				(type default)
			)
			(layer "F.Fab")
		)
		(fp_line
			(start 0.67945 0.3048)
			(end 0.120396 0.3048)
			(stroke
				(width 0.1)
				(type default)
			)
			(layer "F.Fab")
		)
		(fp_line
			(start 0.120396 0.3048)
			(end 0.120396 0.2794)
			(stroke
				(width 0.1)
				(type default)
			)
			(layer "F.Fab")
		)
		(fp_line
			(start -0.12065 0.3048)
			(end -0.67945 0.3048)
			(stroke
				(width 0.1)
				(type default)
			)
			(layer "F.Fab")
		)
		(fp_line
			(start -0.67945 0.3048)
			(end -0.67945 -0.305054)
			(stroke
				(width 0.1)
				(type default)
			)
			(layer "F.Fab")
		)
		(pad "1" smd circle
			(at -0.40005 0 90)
			(size 0 0)
			(layers "F.Cu" "F.Mask" "F.Paste")
			(net "RST_PCIE_CPU0_DEV_PERST_N")
		)
		(pad "2" smd circle
			(at 0.40005 0 90)
			(size 0 0)
			(layers "F.Cu" "F.Mask" "F.Paste")
			(net "GND")
		)
	)
	(footprint ""
		(layer "F.Cu")
		(at 50.317654 -153.644854)
		(property "Reference" "PC1364"
			(at 0 0 0)
			(layer "F.SilkS")
			(hide yes)
			(effects
				(font
					(size 1.27 1.27)
				)
			)
		)
		(property "Value" ""
			(at 0 0 0)
			(layer "F.Fab")
			(effects
				(font
					(size 1.27 1.27)
				)
			)
		)
		(duplicate_pad_numbers_are_jumpers no)
		(fp_line
			(start -0.7874 -0.4064)
			(end 0.7874 -0.4064)
			(stroke
				(width 0.1524)
				(type default)
			)
			(layer "F.SilkS")
		)
		(fp_line
			(start -0.7874 0.4064)
			(end -0.7874 -0.4064)
			(stroke
				(width 0.1524)
				(type default)
			)
			(layer "F.SilkS")
		)
		(fp_line
			(start 0.7874 -0.4064)
			(end 0.7874 0.4064)
			(stroke
				(width 0.1524)
				(type default)
			)
			(layer "F.SilkS")
		)
		(fp_line
			(start 0.7874 0.4064)
			(end -0.7874 0.4064)
			(stroke
				(width 0.1524)
				(type default)
			)
			(layer "F.SilkS")
		)
		(fp_line
			(start -0.67945 -0.305054)
			(end -0.12065 -0.305054)
			(stroke
				(width 0.1)
				(type default)
			)
			(layer "F.Fab")
		)
		(fp_line
			(start -0.67945 0.3048)
			(end -0.67945 -0.305054)
			(stroke
				(width 0.1)
				(type default)
			)
			(layer "F.Fab")
		)
		(fp_line
			(start -0.12065 -0.305054)
			(end -0.12065 -0.2794)
			(stroke
				(width 0.1)
				(type default)
			)
			(layer "F.Fab")
		)
		(fp_line
			(start -0.12065 -0.2794)
			(end 0.12065 -0.2794)
			(stroke
				(width 0.1)
				(type default)
			)
			(layer "F.Fab")
		)
		(fp_line
			(start -0.12065 0.2794)
			(end -0.12065 0.3048)
			(stroke
				(width 0.1)
				(type default)
			)
			(layer "F.Fab")
		)
		(fp_line
			(start -0.12065 0.3048)
			(end -0.67945 0.3048)
			(stroke
				(width 0.1)
				(type default)
			)
			(layer "F.Fab")
		)
		(fp_line
			(start 0.120396 0.2794)
			(end -0.12065 0.2794)
			(stroke
				(width 0.1)
				(type default)
			)
			(layer "F.Fab")
		)
		(fp_line
			(start 0.120396 0.3048)
			(end 0.120396 0.2794)
			(stroke
				(width 0.1)
				(type default)
			)
			(layer "F.Fab")
		)
		(fp_line
			(start 0.12065 -0.3048)
			(end 0.67945 -0.3048)
			(stroke
				(width 0.1)
				(type default)
			)
			(layer "F.Fab")
		)
		(fp_line
			(start 0.12065 -0.2794)
			(end 0.12065 -0.3048)
			(stroke
				(width 0.1)
				(type default)
			)
			(layer "F.Fab")
		)
		(fp_line
			(start 0.67945 -0.3048)
			(end 0.67945 0.3048)
			(stroke
				(width 0.1)
				(type default)
			)
			(layer "F.Fab")
		)
		(fp_line
			(start 0.67945 0.3048)
			(end 0.120396 0.3048)
			(stroke
				(width 0.1)
				(type default)
			)
			(layer "F.Fab")
		)
		(pad "1" smd circle
			(at -0.40005 0)
			(size 0 0)
			(layers "F.Cu" "F.Mask" "F.Paste")
			(net "GND")
		)
		(pad "2" smd circle
			(at 0.40005 0)
			(size 0 0)
			(layers "F.Cu" "F.Mask" "F.Paste")
			(net "PVCCINFAON_CPU1_VREF")
		)
	)
	(footprint ""
		(layer "F.Cu")
		(at 210.3882 -107.4166 -90)
		(property "Reference" "R4783"
			(at 0 0 270)
			(layer "F.SilkS")
			(hide yes)
			(effects
				(font
					(size 1.27 1.27)
				)
			)
		)
		(property "Value" ""
			(at 0 0 270)
			(layer "F.Fab")
			(effects
				(font
					(size 1.27 1.27)
				)
			)
		)
		(duplicate_pad_numbers_are_jumpers no)
		(fp_line
			(start -0.7874 0.4064)
			(end -0.7874 -0.4064)
			(stroke
				(width 0.1524)
				(type default)
			)
			(layer "F.SilkS")
		)
		(fp_line
			(start 0.7874 0.4064)
			(end -0.7874 0.4064)
			(stroke
				(width 0.1524)
				(type default)
			)
			(layer "F.SilkS")
		)
		(fp_line
			(start -0.7874 -0.4064)
			(end 0.7874 -0.4064)
			(stroke
				(width 0.1524)
				(type default)
			)
			(layer "F.SilkS")
		)
		(fp_line
			(start 0.7874 -0.4064)
			(end 0.7874 0.4064)
			(stroke
				(width 0.1524)
				(type default)
			)
			(layer "F.SilkS")
		)
		(fp_line
			(start -0.67945 0.3048)
			(end -0.67945 -0.305054)
			(stroke
				(width 0.1)
				(type default)
			)
			(layer "F.Fab")
		)
		(fp_line
			(start -0.12065 0.3048)
			(end -0.67945 0.3048)
			(stroke
				(width 0.1)
				(type default)
			)
			(layer "F.Fab")
		)
		(fp_line
			(start 0.120396 0.3048)
			(end 0.120396 0.2794)
			(stroke
				(width 0.1)
				(type default)
			)
			(layer "F.Fab")
		)
		(fp_line
			(start 0.67945 0.3048)
			(end 0.120396 0.3048)
			(stroke
				(width 0.1)
				(type default)
			)
			(layer "F.Fab")
		)
		(fp_line
			(start -0.12065 0.2794)
			(end -0.12065 0.3048)
			(stroke
				(width 0.1)
				(type default)
			)
			(layer "F.Fab")
		)
		(fp_line
			(start 0.120396 0.2794)
			(end -0.12065 0.2794)
			(stroke
				(width 0.1)
				(type default)
			)
			(layer "F.Fab")
		)
		(fp_line
			(start -0.12065 -0.2794)
			(end 0.12065 -0.2794)
			(stroke
				(width 0.1)
				(type default)
			)
			(layer "F.Fab")
		)
		(fp_line
			(start 0.12065 -0.2794)
			(end 0.12065 -0.3048)
			(stroke
				(width 0.1)
				(type default)
			)
			(layer "F.Fab")
		)
		(fp_line
			(start 0.12065 -0.3048)
			(end 0.67945 -0.3048)
			(stroke
				(width 0.1)
				(type default)
			)
			(layer "F.Fab")
		)
		(fp_line
			(start 0.67945 -0.3048)
			(end 0.67945 0.3048)
			(stroke
				(width 0.1)
				(type default)
			)
			(layer "F.Fab")
		)
		(fp_line
			(start -0.67945 -0.305054)
			(end -0.12065 -0.305054)
			(stroke
				(width 0.1)
				(type default)
			)
			(layer "F.Fab")
		)
		(fp_line
			(start -0.12065 -0.305054)
			(end -0.12065 -0.2794)
			(stroke
				(width 0.1)
				(type default)
			)
			(layer "F.Fab")
		)
		(pad "1" smd circle
			(at -0.40005 0 270)
			(size 0 0)
			(layers "F.Cu" "F.Mask" "F.Paste")
			(net "IRQ_UV_DETECT_R2_N")
		)
		(pad "2" smd circle
			(at 0.40005 0 270)
			(size 0 0)
			(layers "F.Cu" "F.Mask" "F.Paste")
			(net "IRQ_UV_DETECT_N")
		)
	)
	(footprint ""
		(layer "F.Cu")
		(at 373.476774 -335.176368)
		(property "Reference" "PC274_P0_4"
			(at 0 0 0)
			(layer "F.SilkS")
			(hide yes)
			(effects
				(font
					(size 1.27 1.27)
				)
			)
		)
		(property "Value" ""
			(at 0 0 0)
			(layer "F.Fab")
			(effects
				(font
					(size 1.27 1.27)
				)
			)
		)
		(duplicate_pad_numbers_are_jumpers no)
		(fp_line
			(start -0.7874 -0.4064)
			(end 0.7874 -0.4064)
			(stroke
				(width 0.1524)
				(type default)
			)
			(layer "F.SilkS")
		)
		(fp_line
			(start -0.7874 0.4064)
			(end -0.7874 -0.4064)
			(stroke
				(width 0.1524)
				(type default)
			)
			(layer "F.SilkS")
		)
		(fp_line
			(start 0.7874 -0.4064)
			(end 0.7874 0.4064)
			(stroke
				(width 0.1524)
				(type default)
			)
			(layer "F.SilkS")
		)
		(fp_line
			(start 0.7874 0.4064)
			(end -0.7874 0.4064)
			(stroke
				(width 0.1524)
				(type default)
			)
			(layer "F.SilkS")
		)
		(fp_line
			(start -0.67945 -0.305054)
			(end -0.12065 -0.305054)
			(stroke
				(width 0.1)
				(type default)
			)
			(layer "F.Fab")
		)
		(fp_line
			(start -0.67945 0.3048)
			(end -0.67945 -0.305054)
			(stroke
				(width 0.1)
				(type default)
			)
			(layer "F.Fab")
		)
		(fp_line
			(start -0.12065 -0.305054)
			(end -0.12065 -0.2794)
			(stroke
				(width 0.1)
				(type default)
			)
			(layer "F.Fab")
		)
		(fp_line
			(start -0.12065 -0.2794)
			(end 0.12065 -0.2794)
			(stroke
				(width 0.1)
				(type default)
			)
			(layer "F.Fab")
		)
		(fp_line
			(start -0.12065 0.2794)
			(end -0.12065 0.3048)
			(stroke
				(width 0.1)
				(type default)
			)
			(layer "F.Fab")
		)
		(fp_line
			(start -0.12065 0.3048)
			(end -0.67945 0.3048)
			(stroke
				(width 0.1)
				(type default)
			)
			(layer "F.Fab")
		)
		(fp_line
			(start 0.120396 0.2794)
			(end -0.12065 0.2794)
			(stroke
				(width 0.1)
				(type default)
			)
			(layer "F.Fab")
		)
		(fp_line
			(start 0.120396 0.3048)
			(end 0.120396 0.2794)
			(stroke
				(width 0.1)
				(type default)
			)
			(layer "F.Fab")
		)
		(fp_line
			(start 0.12065 -0.3048)
			(end 0.67945 -0.3048)
			(stroke
				(width 0.1)
				(type default)
			)
			(layer "F.Fab")
		)
		(fp_line
			(start 0.12065 -0.2794)
			(end 0.12065 -0.3048)
			(stroke
				(width 0.1)
				(type default)
			)
			(layer "F.Fab")
		)
		(fp_line
			(start 0.67945 -0.3048)
			(end 0.67945 0.3048)
			(stroke
				(width 0.1)
				(type default)
			)
			(layer "F.Fab")
		)
		(fp_line
			(start 0.67945 0.3048)
			(end 0.120396 0.3048)
			(stroke
				(width 0.1)
				(type default)
			)
			(layer "F.Fab")
		)
		(pad "1" smd circle
			(at -0.40005 0)
			(size 0 0)
			(layers "F.Cu" "F.Mask" "F.Paste")
			(net "SW_P12V_PVCCIN_CPU0_FLT")
		)
		(pad "2" smd circle
			(at 0.40005 0)
			(size 0 0)
			(layers "F.Cu" "F.Mask" "F.Paste")
			(net "GND")
		)
	)
	(footprint ""
		(layer "F.Cu")
		(at 164.592 -103.342948)
		(property "Reference" "R1755"
			(at 0 0 0)
			(layer "F.SilkS")
			(hide yes)
			(effects
				(font
					(size 1.27 1.27)
				)
			)
		)
		(property "Value" ""
			(at 0 0 0)
			(layer "F.Fab")
			(effects
				(font
					(size 1.27 1.27)
				)
			)
		)
		(duplicate_pad_numbers_are_jumpers no)
		(fp_line
			(start -0.7874 -0.4064)
			(end 0.7874 -0.4064)
			(stroke
				(width 0.1524)
				(type default)
			)
			(layer "F.SilkS")
		)
		(fp_line
			(start -0.7874 0.4064)
			(end -0.7874 -0.4064)
			(stroke
				(width 0.1524)
				(type default)
			)
			(layer "F.SilkS")
		)
		(fp_line
			(start 0.7874 -0.4064)
			(end 0.7874 0.4064)
			(stroke
				(width 0.1524)
				(type default)
			)
			(layer "F.SilkS")
		)
		(fp_line
			(start 0.7874 0.4064)
			(end -0.7874 0.4064)
			(stroke
				(width 0.1524)
				(type default)
			)
			(layer "F.SilkS")
		)
		(fp_line
			(start -0.67945 -0.305054)
			(end -0.12065 -0.305054)
			(stroke
				(width 0.1)
				(type default)
			)
			(layer "F.Fab")
		)
		(fp_line
			(start -0.67945 0.3048)
			(end -0.67945 -0.305054)
			(stroke
				(width 0.1)
				(type default)
			)
			(layer "F.Fab")
		)
		(fp_line
			(start -0.12065 -0.305054)
			(end -0.12065 -0.2794)
			(stroke
				(width 0.1)
				(type default)
			)
			(layer "F.Fab")
		)
		(fp_line
			(start -0.12065 -0.2794)
			(end 0.12065 -0.2794)
			(stroke
				(width 0.1)
				(type default)
			)
			(layer "F.Fab")
		)
		(fp_line
			(start -0.12065 0.2794)
			(end -0.12065 0.3048)
			(stroke
				(width 0.1)
				(type default)
			)
			(layer "F.Fab")
		)
		(fp_line
			(start -0.12065 0.3048)
			(end -0.67945 0.3048)
			(stroke
				(width 0.1)
				(type default)
			)
			(layer "F.Fab")
		)
		(fp_line
			(start 0.120396 0.2794)
			(end -0.12065 0.2794)
			(stroke
				(width 0.1)
				(type default)
			)
			(layer "F.Fab")
		)
		(fp_line
			(start 0.120396 0.3048)
			(end 0.120396 0.2794)
			(stroke
				(width 0.1)
				(type default)
			)
			(layer "F.Fab")
		)
		(fp_line
			(start 0.12065 -0.3048)
			(end 0.67945 -0.3048)
			(stroke
				(width 0.1)
				(type default)
			)
			(layer "F.Fab")
		)
		(fp_line
			(start 0.12065 -0.2794)
			(end 0.12065 -0.3048)
			(stroke
				(width 0.1)
				(type default)
			)
			(layer "F.Fab")
		)
		(fp_line
			(start 0.67945 -0.3048)
			(end 0.67945 0.3048)
			(stroke
				(width 0.1)
				(type default)
			)
			(layer "F.Fab")
		)
		(fp_line
			(start 0.67945 0.3048)
			(end 0.120396 0.3048)
			(stroke
				(width 0.1)
				(type default)
			)
			(layer "F.Fab")
		)
		(pad "1" smd circle
			(at -0.40005 0)
			(size 0 0)
			(layers "F.Cu" "F.Mask" "F.Paste")
			(net "SGPIO_DO_1")
		)
		(pad "2" smd circle
			(at 0.40005 0)
			(size 0 0)
			(layers "F.Cu" "F.Mask" "F.Paste")
			(net "SGPIO_BMC_DOUT")
		)
	)
	(footprint ""
		(layer "F.Cu")
		(at 119.341138 -355.71049 180)
		(property "Reference" "C2460"
			(at 0 0 180)
			(layer "F.SilkS")
			(hide yes)
			(effects
				(font
					(size 1.27 1.27)
				)
			)
		)
		(property "Value" ""
			(at 0 0 180)
			(layer "F.Fab")
			(effects
				(font
					(size 1.27 1.27)
				)
			)
		)
		(duplicate_pad_numbers_are_jumpers no)
		(fp_line
			(start 0.7874 0.4064)
			(end -0.7874 0.4064)
			(stroke
				(width 0.1524)
				(type default)
			)
			(layer "F.SilkS")
		)
		(fp_line
			(start 0.7874 -0.4064)
			(end 0.7874 0.4064)
			(stroke
				(width 0.1524)
				(type default)
			)
			(layer "F.SilkS")
		)
		(fp_line
			(start -0.7874 0.4064)
			(end -0.7874 -0.4064)
			(stroke
				(width 0.1524)
				(type default)
			)
			(layer "F.SilkS")
		)
		(fp_line
			(start -0.7874 -0.4064)
			(end 0.7874 -0.4064)
			(stroke
				(width 0.1524)
				(type default)
			)
			(layer "F.SilkS")
		)
		(fp_line
			(start 0.67945 0.3048)
			(end 0.120396 0.3048)
			(stroke
				(width 0.1)
				(type default)
			)
			(layer "F.Fab")
		)
		(fp_line
			(start 0.67945 -0.3048)
			(end 0.67945 0.3048)
			(stroke
				(width 0.1)
				(type default)
			)
			(layer "F.Fab")
		)
		(fp_line
			(start 0.12065 -0.2794)
			(end 0.12065 -0.3048)
			(stroke
				(width 0.1)
				(type default)
			)
			(layer "F.Fab")
		)
		(fp_line
			(start 0.12065 -0.3048)
			(end 0.67945 -0.3048)
			(stroke
				(width 0.1)
				(type default)
			)
			(layer "F.Fab")
		)
		(fp_line
			(start 0.120396 0.3048)
			(end 0.120396 0.2794)
			(stroke
				(width 0.1)
				(type default)
			)
			(layer "F.Fab")
		)
		(fp_line
			(start 0.120396 0.2794)
			(end -0.12065 0.2794)
			(stroke
				(width 0.1)
				(type default)
			)
			(layer "F.Fab")
		)
		(fp_line
			(start -0.12065 0.3048)
			(end -0.67945 0.3048)
			(stroke
				(width 0.1)
				(type default)
			)
			(layer "F.Fab")
		)
		(fp_line
			(start -0.12065 0.2794)
			(end -0.12065 0.3048)
			(stroke
				(width 0.1)
				(type default)
			)
			(layer "F.Fab")
		)
		(fp_line
			(start -0.12065 -0.2794)
			(end 0.12065 -0.2794)
			(stroke
				(width 0.1)
				(type default)
			)
			(layer "F.Fab")
		)
		(fp_line
			(start -0.12065 -0.305054)
			(end -0.12065 -0.2794)
			(stroke
				(width 0.1)
				(type default)
			)
			(layer "F.Fab")
		)
		(fp_line
			(start -0.67945 0.3048)
			(end -0.67945 -0.305054)
			(stroke
				(width 0.1)
				(type default)
			)
			(layer "F.Fab")
		)
		(fp_line
			(start -0.67945 -0.305054)
			(end -0.12065 -0.305054)
			(stroke
				(width 0.1)
				(type default)
			)
			(layer "F.Fab")
		)
		(pad "1" smd circle
			(at -0.40005 0 180)
			(size 0 0)
			(layers "F.Cu" "F.Mask" "F.Paste")
			(net "PWRGD_PVPP_HBM_CPU1_R")
		)
		(pad "2" smd circle
			(at 0.40005 0 180)
			(size 0 0)
			(layers "F.Cu" "F.Mask" "F.Paste")
			(net "GND")
		)
	)
	(footprint ""
		(layer "F.Cu")
		(at 204.93736 -115.534948 180)
		(property "Reference" "R4143"
			(at 0 0 180)
			(layer "F.SilkS")
			(hide yes)
			(effects
				(font
					(size 1.27 1.27)
				)
			)
		)
		(property "Value" ""
			(at 0 0 180)
			(layer "F.Fab")
			(effects
				(font
					(size 1.27 1.27)
				)
			)
		)
		(duplicate_pad_numbers_are_jumpers no)
		(fp_line
			(start 0.7874 0.4064)
			(end -0.7874 0.4064)
			(stroke
				(width 0.1524)
				(type default)
			)
			(layer "F.SilkS")
		)
		(fp_line
			(start 0.7874 -0.4064)
			(end 0.7874 0.4064)
			(stroke
				(width 0.1524)
				(type default)
			)
			(layer "F.SilkS")
		)
		(fp_line
			(start -0.7874 0.4064)
			(end -0.7874 -0.4064)
			(stroke
				(width 0.1524)
				(type default)
			)
			(layer "F.SilkS")
		)
		(fp_line
			(start -0.7874 -0.4064)
			(end 0.7874 -0.4064)
			(stroke
				(width 0.1524)
				(type default)
			)
			(layer "F.SilkS")
		)
		(fp_line
			(start 0.67945 0.3048)
			(end 0.120396 0.3048)
			(stroke
				(width 0.1)
				(type default)
			)
			(layer "F.Fab")
		)
		(fp_line
			(start 0.67945 -0.3048)
			(end 0.67945 0.3048)
			(stroke
				(width 0.1)
				(type default)
			)
			(layer "F.Fab")
		)
		(fp_line
			(start 0.12065 -0.2794)
			(end 0.12065 -0.3048)
			(stroke
				(width 0.1)
				(type default)
			)
			(layer "F.Fab")
		)
		(fp_line
			(start 0.12065 -0.3048)
			(end 0.67945 -0.3048)
			(stroke
				(width 0.1)
				(type default)
			)
			(layer "F.Fab")
		)
		(fp_line
			(start 0.120396 0.3048)
			(end 0.120396 0.2794)
			(stroke
				(width 0.1)
				(type default)
			)
			(layer "F.Fab")
		)
		(fp_line
			(start 0.120396 0.2794)
			(end -0.12065 0.2794)
			(stroke
				(width 0.1)
				(type default)
			)
			(layer "F.Fab")
		)
		(fp_line
			(start -0.12065 0.3048)
			(end -0.67945 0.3048)
			(stroke
				(width 0.1)
				(type default)
			)
			(layer "F.Fab")
		)
		(fp_line
			(start -0.12065 0.2794)
			(end -0.12065 0.3048)
			(stroke
				(width 0.1)
				(type default)
			)
			(layer "F.Fab")
		)
		(fp_line
			(start -0.12065 -0.2794)
			(end 0.12065 -0.2794)
			(stroke
				(width 0.1)
				(type default)
			)
			(layer "F.Fab")
		)
		(fp_line
			(start -0.12065 -0.305054)
			(end -0.12065 -0.2794)
			(stroke
				(width 0.1)
				(type default)
			)
			(layer "F.Fab")
		)
		(fp_line
			(start -0.67945 0.3048)
			(end -0.67945 -0.305054)
			(stroke
				(width 0.1)
				(type default)
			)
			(layer "F.Fab")
		)
		(fp_line
			(start -0.67945 -0.305054)
			(end -0.12065 -0.305054)
			(stroke
				(width 0.1)
				(type default)
			)
			(layer "F.Fab")
		)
		(pad "1" smd circle
			(at -0.40005 0 180)
			(size 0 0)
			(layers "F.Cu" "F.Mask" "F.Paste")
			(net "GPU_3V3IO_RSVD0_FFU_ISO")
		)
		(pad "2" smd circle
			(at 0.40005 0 180)
			(size 0 0)
			(layers "F.Cu" "F.Mask" "F.Paste")
			(net "GPU_3V3IO_RSVD0_FFU_ISO_R")
		)
	)
	(footprint ""
		(layer "F.Cu")
		(at 369.259358 -92.962984 90)
		(property "Reference" "R482"
			(at 0 0 90)
			(layer "F.SilkS")
			(hide yes)
			(effects
				(font
					(size 1.27 1.27)
				)
			)
		)
		(property "Value" ""
			(at 0 0 90)
			(layer "F.Fab")
			(effects
				(font
					(size 1.27 1.27)
				)
			)
		)
		(duplicate_pad_numbers_are_jumpers no)
		(fp_line
			(start 0.7874 -0.4064)
			(end 0.7874 0.4064)
			(stroke
				(width 0.1524)
				(type default)
			)
			(layer "F.SilkS")
		)
		(fp_line
			(start -0.7874 -0.4064)
			(end 0.7874 -0.4064)
			(stroke
				(width 0.1524)
				(type default)
			)
			(layer "F.SilkS")
		)
		(fp_line
			(start 0.7874 0.4064)
			(end -0.7874 0.4064)
			(stroke
				(width 0.1524)
				(type default)
			)
			(layer "F.SilkS")
		)
		(fp_line
			(start -0.7874 0.4064)
			(end -0.7874 -0.4064)
			(stroke
				(width 0.1524)
				(type default)
			)
			(layer "F.SilkS")
		)
		(fp_line
			(start -0.12065 -0.305054)
			(end -0.12065 -0.2794)
			(stroke
				(width 0.1)
				(type default)
			)
			(layer "F.Fab")
		)
		(fp_line
			(start -0.67945 -0.305054)
			(end -0.12065 -0.305054)
			(stroke
				(width 0.1)
				(type default)
			)
			(layer "F.Fab")
		)
		(fp_line
			(start 0.67945 -0.3048)
			(end 0.67945 0.3048)
			(stroke
				(width 0.1)
				(type default)
			)
			(layer "F.Fab")
		)
		(fp_line
			(start 0.12065 -0.3048)
			(end 0.67945 -0.3048)
			(stroke
				(width 0.1)
				(type default)
			)
			(layer "F.Fab")
		)
		(fp_line
			(start 0.12065 -0.2794)
			(end 0.12065 -0.3048)
			(stroke
				(width 0.1)
				(type default)
			)
			(layer "F.Fab")
		)
		(fp_line
			(start -0.12065 -0.2794)
			(end 0.12065 -0.2794)
			(stroke
				(width 0.1)
				(type default)
			)
			(layer "F.Fab")
		)
		(fp_line
			(start 0.120396 0.2794)
			(end -0.12065 0.2794)
			(stroke
				(width 0.1)
				(type default)
			)
			(layer "F.Fab")
		)
		(fp_line
			(start -0.12065 0.2794)
			(end -0.12065 0.3048)
			(stroke
				(width 0.1)
				(type default)
			)
			(layer "F.Fab")
		)
		(fp_line
			(start 0.67945 0.3048)
			(end 0.120396 0.3048)
			(stroke
				(width 0.1)
				(type default)
			)
			(layer "F.Fab")
		)
		(fp_line
			(start 0.120396 0.3048)
			(end 0.120396 0.2794)
			(stroke
				(width 0.1)
				(type default)
			)
			(layer "F.Fab")
		)
		(fp_line
			(start -0.12065 0.3048)
			(end -0.67945 0.3048)
			(stroke
				(width 0.1)
				(type default)
			)
			(layer "F.Fab")
		)
		(fp_line
			(start -0.67945 0.3048)
			(end -0.67945 -0.305054)
			(stroke
				(width 0.1)
				(type default)
			)
			(layer "F.Fab")
		)
		(pad "1" smd circle
			(at -0.40005 0 90)
			(size 0 0)
			(layers "F.Cu" "F.Mask" "F.Paste")
			(net "JTAG_DBP_PREQ_N")
		)
		(pad "2" smd circle
			(at 0.40005 0 90)
			(size 0 0)
			(layers "F.Cu" "F.Mask" "F.Paste")
			(net "JTAG_DBP_PREQ_R_N")
		)
	)
	(footprint ""
		(layer "F.Cu")
		(at 212.118956 -30.276292 -90)
		(property "Reference" "R3561"
			(at 0 0 270)
			(layer "F.SilkS")
			(hide yes)
			(effects
				(font
					(size 1.27 1.27)
				)
			)
		)
		(property "Value" ""
			(at 0 0 270)
			(layer "F.Fab")
			(effects
				(font
					(size 1.27 1.27)
				)
			)
		)
		(duplicate_pad_numbers_are_jumpers no)
		(fp_line
			(start -0.7874 0.4064)
			(end -0.7874 -0.4064)
			(stroke
				(width 0.1524)
				(type default)
			)
			(layer "F.SilkS")
		)
		(fp_line
			(start 0.7874 0.4064)
			(end -0.7874 0.4064)
			(stroke
				(width 0.1524)
				(type default)
			)
			(layer "F.SilkS")
		)
		(fp_line
			(start -0.7874 -0.4064)
			(end 0.7874 -0.4064)
			(stroke
				(width 0.1524)
				(type default)
			)
			(layer "F.SilkS")
		)
		(fp_line
			(start 0.7874 -0.4064)
			(end 0.7874 0.4064)
			(stroke
				(width 0.1524)
				(type default)
			)
			(layer "F.SilkS")
		)
		(fp_line
			(start -0.67945 0.3048)
			(end -0.67945 -0.305054)
			(stroke
				(width 0.1)
				(type default)
			)
			(layer "F.Fab")
		)
		(fp_line
			(start -0.12065 0.3048)
			(end -0.67945 0.3048)
			(stroke
				(width 0.1)
				(type default)
			)
			(layer "F.Fab")
		)
		(fp_line
			(start 0.120396 0.3048)
			(end 0.120396 0.2794)
			(stroke
				(width 0.1)
				(type default)
			)
			(layer "F.Fab")
		)
		(fp_line
			(start 0.67945 0.3048)
			(end 0.120396 0.3048)
			(stroke
				(width 0.1)
				(type default)
			)
			(layer "F.Fab")
		)
		(fp_line
			(start -0.12065 0.2794)
			(end -0.12065 0.3048)
			(stroke
				(width 0.1)
				(type default)
			)
			(layer "F.Fab")
		)
		(fp_line
			(start 0.120396 0.2794)
			(end -0.12065 0.2794)
			(stroke
				(width 0.1)
				(type default)
			)
			(layer "F.Fab")
		)
		(fp_line
			(start -0.12065 -0.2794)
			(end 0.12065 -0.2794)
			(stroke
				(width 0.1)
				(type default)
			)
			(layer "F.Fab")
		)
		(fp_line
			(start 0.12065 -0.2794)
			(end 0.12065 -0.3048)
			(stroke
				(width 0.1)
				(type default)
			)
			(layer "F.Fab")
		)
		(fp_line
			(start 0.12065 -0.3048)
			(end 0.67945 -0.3048)
			(stroke
				(width 0.1)
				(type default)
			)
			(layer "F.Fab")
		)
		(fp_line
			(start 0.67945 -0.3048)
			(end 0.67945 0.3048)
			(stroke
				(width 0.1)
				(type default)
			)
			(layer "F.Fab")
		)
		(fp_line
			(start -0.67945 -0.305054)
			(end -0.12065 -0.305054)
			(stroke
				(width 0.1)
				(type default)
			)
			(layer "F.Fab")
		)
		(fp_line
			(start -0.12065 -0.305054)
			(end -0.12065 -0.2794)
			(stroke
				(width 0.1)
				(type default)
			)
			(layer "F.Fab")
		)
		(pad "1" smd circle
			(at -0.40005 0 270)
			(size 0 0)
			(layers "F.Cu" "F.Mask" "F.Paste")
			(net "P12V_SCM_ADC_ALERT_R")
		)
		(pad "2" smd circle
			(at 0.40005 0 270)
			(size 0 0)
			(layers "F.Cu" "F.Mask" "F.Paste")
			(net "P12V_SCM_ADC_ALERT")
		)
	)
	(footprint ""
		(layer "F.Cu")
		(at 70.358 -114.772948 180)
		(property "Reference" "R4270"
			(at 0 0 180)
			(layer "F.SilkS")
			(hide yes)
			(effects
				(font
					(size 1.27 1.27)
				)
			)
		)
		(property "Value" ""
			(at 0 0 180)
			(layer "F.Fab")
			(effects
				(font
					(size 1.27 1.27)
				)
			)
		)
		(duplicate_pad_numbers_are_jumpers no)
		(fp_line
			(start 0.7874 0.4064)
			(end -0.7874 0.4064)
			(stroke
				(width 0.1524)
				(type default)
			)
			(layer "F.SilkS")
		)
		(fp_line
			(start 0.7874 -0.4064)
			(end 0.7874 0.4064)
			(stroke
				(width 0.1524)
				(type default)
			)
			(layer "F.SilkS")
		)
		(fp_line
			(start -0.7874 0.4064)
			(end -0.7874 -0.4064)
			(stroke
				(width 0.1524)
				(type default)
			)
			(layer "F.SilkS")
		)
		(fp_line
			(start -0.7874 -0.4064)
			(end 0.7874 -0.4064)
			(stroke
				(width 0.1524)
				(type default)
			)
			(layer "F.SilkS")
		)
		(fp_line
			(start 0.67945 0.3048)
			(end 0.120396 0.3048)
			(stroke
				(width 0.1)
				(type default)
			)
			(layer "F.Fab")
		)
		(fp_line
			(start 0.67945 -0.3048)
			(end 0.67945 0.3048)
			(stroke
				(width 0.1)
				(type default)
			)
			(layer "F.Fab")
		)
		(fp_line
			(start 0.12065 -0.2794)
			(end 0.12065 -0.3048)
			(stroke
				(width 0.1)
				(type default)
			)
			(layer "F.Fab")
		)
		(fp_line
			(start 0.12065 -0.3048)
			(end 0.67945 -0.3048)
			(stroke
				(width 0.1)
				(type default)
			)
			(layer "F.Fab")
		)
		(fp_line
			(start 0.120396 0.3048)
			(end 0.120396 0.2794)
			(stroke
				(width 0.1)
				(type default)
			)
			(layer "F.Fab")
		)
		(fp_line
			(start 0.120396 0.2794)
			(end -0.12065 0.2794)
			(stroke
				(width 0.1)
				(type default)
			)
			(layer "F.Fab")
		)
		(fp_line
			(start -0.12065 0.3048)
			(end -0.67945 0.3048)
			(stroke
				(width 0.1)
				(type default)
			)
			(layer "F.Fab")
		)
		(fp_line
			(start -0.12065 0.2794)
			(end -0.12065 0.3048)
			(stroke
				(width 0.1)
				(type default)
			)
			(layer "F.Fab")
		)
		(fp_line
			(start -0.12065 -0.2794)
			(end 0.12065 -0.2794)
			(stroke
				(width 0.1)
				(type default)
			)
			(layer "F.Fab")
		)
		(fp_line
			(start -0.12065 -0.305054)
			(end -0.12065 -0.2794)
			(stroke
				(width 0.1)
				(type default)
			)
			(layer "F.Fab")
		)
		(fp_line
			(start -0.67945 0.3048)
			(end -0.67945 -0.305054)
			(stroke
				(width 0.1)
				(type default)
			)
			(layer "F.Fab")
		)
		(fp_line
			(start -0.67945 -0.305054)
			(end -0.12065 -0.305054)
			(stroke
				(width 0.1)
				(type default)
			)
			(layer "F.Fab")
		)
		(pad "1" smd circle
			(at -0.40005 0 180)
			(size 0 0)
			(layers "F.Cu" "F.Mask" "F.Paste")
			(net "P3V3_AUX")
		)
		(pad "2" smd circle
			(at 0.40005 0 180)
			(size 0 0)
			(layers "F.Cu" "F.Mask" "F.Paste")
			(net "SMB_VR_SENSOR_3V3AUX_SDA")
		)
	)
	(footprint ""
		(layer "F.Cu")
		(at 303.2506 -424.08475 90)
		(property "Reference" "Q128"
			(at -7.87908 5.816092 90)
			(unlocked yes)
			(layer "F.SilkS")
			(effects
				(font
					(size 0.7874 0.5842)
					(thickness 0.1524)
				)
				(justify left)
			)
		)
		(property "Value" ""
			(at 0 0 90)
			(layer "F.Fab")
			(effects
				(font
					(size 1.27 1.27)
				)
			)
		)
		(duplicate_pad_numbers_are_jumpers no)
		(fp_line
			(start 1.332738 -1.100074)
			(end 1.332738 1.100074)
			(stroke
				(width 0.1524)
				(type default)
			)
			(layer "F.SilkS")
		)
		(fp_line
			(start 0.4826 -1.100074)
			(end 1.332738 -1.100074)
			(stroke
				(width 0.1524)
				(type default)
			)
			(layer "F.SilkS")
		)
		(fp_line
			(start -0.4826 -1.100074)
			(end 0 -0.541274)
			(stroke
				(width 0.1524)
				(type default)
			)
			(layer "F.SilkS")
		)
		(fp_line
			(start -1.332738 -1.100074)
			(end -0.4826 -1.100074)
			(stroke
				(width 0.1524)
				(type default)
			)
			(layer "F.SilkS")
		)
		(fp_line
			(start 0 -0.541274)
			(end 0.4826 -1.100074)
			(stroke
				(width 0.1524)
				(type default)
			)
			(layer "F.SilkS")
		)
		(fp_line
			(start 1.332738 1.100074)
			(end -1.332738 1.100074)
			(stroke
				(width 0.1524)
				(type default)
			)
			(layer "F.SilkS")
		)
		(fp_line
			(start -1.332738 1.100074)
			(end -1.332738 -1.100074)
			(stroke
				(width 0.1524)
				(type default)
			)
			(layer "F.SilkS")
		)
		(fp_poly
			(pts
				(xy -2.37236 -1.427734) (xy -1.670304 -1.076706) (xy -2.37236 -0.725678)
			)
			(stroke
				(width 0)
				(type default)
			)
			(fill yes)
			(layer "F.SilkS")
		)
		(fp_line
			(start 0.674878 -1.100074)
			(end 0.674878 1.100074)
			(stroke
				(width 0.1)
				(type default)
			)
			(layer "F.Fab")
		)
		(fp_line
			(start -0.674878 -1.100074)
			(end 0.674878 -1.100074)
			(stroke
				(width 0.1)
				(type default)
			)
			(layer "F.Fab")
		)
		(fp_line
			(start 0.674878 1.100074)
			(end -0.674878 1.100074)
			(stroke
				(width 0.1)
				(type default)
			)
			(layer "F.Fab")
		)
		(fp_line
			(start -0.674878 1.100074)
			(end -0.674878 -1.100074)
			(stroke
				(width 0.1)
				(type default)
			)
			(layer "F.Fab")
		)
		(fp_poly
			(pts
				(xy -2.2352 -0.298958) (xy -2.2352 -1.001014) (xy -1.533144 -0.649986)
			)
			(stroke
				(width 0)
				(type default)
			)
			(fill yes)
			(layer "F.Fab")
		)
		(pad "1" smd rect
			(at -0.94996 -0.649986 180)
			(size 0.4318 0.508)
			(layers "F.Cu" "F.Mask" "F.Paste")
			(net "GND")
		)
		(pad "2" smd rect
			(at -0.94996 0 180)
			(size 0.4318 0.508)
			(layers "F.Cu" "F.Mask" "F.Paste")
			(net "GPU_3V3IO_RSVD0_FFU")
		)
		(pad "3" smd rect
			(at -0.94996 0.649986 180)
			(size 0.4318 0.508)
			(layers "F.Cu" "F.Mask" "F.Paste")
			(net "GPU_3V3IO_RSVD0_FFU_ISO")
		)
		(pad "4" smd rect
			(at 0.94996 0.649986 180)
			(size 0.4318 0.508)
			(layers "F.Cu" "F.Mask" "F.Paste")
			(net "GND")
		)
		(pad "5" smd rect
			(at 0.94996 0 180)
			(size 0.4318 0.508)
			(layers "F.Cu" "F.Mask" "F.Paste")
			(net "GPU_3V3IO_RSVD0_FFU_N")
		)
		(pad "6" smd rect
			(at 0.94996 -0.649986 180)
			(size 0.4318 0.508)
			(layers "F.Cu" "F.Mask" "F.Paste")
			(net "GPU_3V3IO_RSVD0_FFU_N")
		)
	)
	(footprint ""
		(layer "F.Cu")
		(at 116.41328 -417.393628)
		(property "Reference" "U196"
			(at -2.4765 -2.74447 0)
			(unlocked yes)
			(layer "F.SilkS")
			(effects
				(font
					(size 0.7874 0.5842)
					(thickness 0.1524)
				)
				(justify left)
			)
		)
		(property "Value" ""
			(at 0 0 0)
			(layer "F.Fab")
			(effects
				(font
					(size 1.27 1.27)
				)
			)
		)
		(duplicate_pad_numbers_are_jumpers no)
		(fp_line
			(start -1.3462 -1.100074)
			(end -0.670052 -1.100074)
			(stroke
				(width 0.1524)
				(type default)
			)
			(layer "F.SilkS")
		)
		(fp_line
			(start -1.3462 1.100074)
			(end -1.3462 -1.100074)
			(stroke
				(width 0.1524)
				(type default)
			)
			(layer "F.SilkS")
		)
		(fp_line
			(start -0.670052 -1.100074)
			(end 0 -0.381)
			(stroke
				(width 0.1524)
				(type default)
			)
			(layer "F.SilkS")
		)
		(fp_line
			(start 0 -0.381)
			(end 0.670052 -1.100074)
			(stroke
				(width 0.1524)
				(type default)
			)
			(layer "F.SilkS")
		)
		(fp_line
			(start 0.670052 -1.100074)
			(end 1.3462 -1.100074)
			(stroke
				(width 0.1524)
				(type default)
			)
			(layer "F.SilkS")
		)
		(fp_line
			(start 1.3462 -1.100074)
			(end 1.3462 1.100074)
			(stroke
				(width 0.1524)
				(type default)
			)
			(layer "F.SilkS")
		)
		(fp_line
			(start 1.3462 1.100074)
			(end -1.3462 1.100074)
			(stroke
				(width 0.1524)
				(type default)
			)
			(layer "F.SilkS")
		)
		(fp_poly
			(pts
				(xy -0.990854 -1.28016) (xy -1.371854 -2.04216) (xy -0.609854 -2.04216)
			)
			(stroke
				(width 0)
				(type default)
			)
			(fill yes)
			(layer "F.SilkS")
		)
		(fp_line
			(start -1.100074 -0.8001)
			(end -0.670052 -0.8001)
			(stroke
				(width 0.1)
				(type default)
			)
			(layer "F.Fab")
		)
		(fp_line
			(start -1.100074 0.8001)
			(end -1.100074 -0.8001)
			(stroke
				(width 0.1)
				(type default)
			)
			(layer "F.Fab")
		)
		(fp_line
			(start -0.670052 -1.100074)
			(end 0.670052 -1.100074)
			(stroke
				(width 0.1)
				(type default)
			)
			(layer "F.Fab")
		)
		(fp_line
			(start -0.670052 -0.8001)
			(end -0.670052 -1.100074)
			(stroke
				(width 0.1)
				(type default)
			)
			(layer "F.Fab")
		)
		(fp_line
			(start -0.670052 0.8001)
			(end -1.100074 0.8001)
			(stroke
				(width 0.1)
				(type default)
			)
			(layer "F.Fab")
		)
		(fp_line
			(start -0.670052 0.8001)
			(end -0.670052 -0.8001)
			(stroke
				(width 0.1)
				(type default)
			)
			(layer "F.Fab")
		)
		(fp_line
			(start -0.670052 1.100074)
			(end -0.670052 0.8001)
			(stroke
				(width 0.1)
				(type default)
			)
			(layer "F.Fab")
		)
		(fp_line
			(start 0.670052 -1.100074)
			(end 0.670052 -0.8001)
			(stroke
				(width 0.1)
				(type default)
			)
			(layer "F.Fab")
		)
		(fp_line
			(start 0.670052 -0.8001)
			(end 0.670052 0.8001)
			(stroke
				(width 0.1)
				(type default)
			)
			(layer "F.Fab")
		)
		(fp_line
			(start 0.670052 -0.8001)
			(end 1.100074 -0.8001)
			(stroke
				(width 0.1)
				(type default)
			)
			(layer "F.Fab")
		)
		(fp_line
			(start 0.670052 0.8001)
			(end 0.670052 1.100074)
			(stroke
				(width 0.1)
				(type default)
			)
			(layer "F.Fab")
		)
		(fp_line
			(start 0.670052 1.100074)
			(end -0.670052 1.100074)
			(stroke
				(width 0.1)
				(type default)
			)
			(layer "F.Fab")
		)
		(fp_line
			(start 1.100074 -0.8001)
			(end 1.100074 0.8001)
			(stroke
				(width 0.1)
				(type default)
			)
			(layer "F.Fab")
		)
		(fp_line
			(start 1.100074 0.8001)
			(end 0.670052 0.8001)
			(stroke
				(width 0.1)
				(type default)
			)
			(layer "F.Fab")
		)
		(fp_poly
			(pts
				(xy -1.524 -0.649986) (xy -2.286 -1.030986) (xy -2.286 -0.268986)
			)
			(stroke
				(width 0)
				(type default)
			)
			(fill yes)
			(layer "F.Fab")
		)
		(pad "1" smd rect
			(at -0.94996 -0.649986 270)
			(size 0.4064 0.508)
			(layers "F.Cu" "F.Mask" "F.Paste")
			(net "FM_GPU_PWR_EN_R")
		)
		(pad "2" smd rect
			(at -0.94996 0 270)
			(size 0.4064 0.508)
			(layers "F.Cu" "F.Mask" "F.Paste")
			(net "GND")
		)
		(pad "3" smd rect
			(at -0.94996 0.649986 270)
			(size 0.4064 0.508)
			(layers "F.Cu" "F.Mask" "F.Paste")
			(net "GPU_FPGA_RST_R_N")
		)
		(pad "4" smd rect
			(at 0.94996 0.649986 270)
			(size 0.4064 0.508)
			(layers "F.Cu" "F.Mask" "F.Paste")
			(net "GPU_FPGA_RST_R1_BUF_N")
		)
		(pad "5" smd rect
			(at 0.94996 0 270)
			(size 0.4064 0.508)
			(layers "F.Cu" "F.Mask" "F.Paste")
			(net "P3V3_AUX")
		)
		(pad "6" smd rect
			(at 0.94996 -0.649986 270)
			(size 0.4064 0.508)
			(layers "F.Cu" "F.Mask" "F.Paste")
			(net "FM_GPU_PWR_EN_R1")
		)
	)
	(footprint ""
		(layer "F.Cu")
		(at 457.0349 -51.976528)
		(property "Reference" "PC1867"
			(at 0 0 0)
			(layer "F.SilkS")
			(hide yes)
			(effects
				(font
					(size 1.27 1.27)
				)
			)
		)
		(property "Value" ""
			(at 0 0 0)
			(layer "F.Fab")
			(effects
				(font
					(size 1.27 1.27)
				)
			)
		)
		(duplicate_pad_numbers_are_jumpers no)
		(fp_line
			(start -3.400044 1.249934)
			(end 3.400044 1.249934)
			(stroke
				(width 0.1524)
				(type default)
			)
			(layer "F.SilkS")
		)
		(fp_circle
			(center 0 1.249934)
			(end 3.400044 1.249934)
			(stroke
				(width 0.1524)
				(type default)
			)
			(fill no)
			(layer "F.SilkS")
		)
		(fp_poly
			(pts
				(arc
					(start 3.400044 1.249934)
					(mid 0 4.649978)
					(end -3.400044 1.249934)
				)
			)
			(stroke
				(width 0)
				(type default)
			)
			(fill yes)
			(layer "F.SilkS")
		)
		(fp_circle
			(center 0 1.249934)
			(end 3.400044 1.249934)
			(stroke
				(width 0.1)
				(type default)
			)
			(fill no)
			(layer "F.Fab")
		)
		(pad "1" thru_hole rect
			(at 0 0)
			(size 1.524 1.524)
			(drill 1.016)
			(layers "*.Cu" "*.Mask")
			(remove_unused_layers no)
			(net "P3V3_AUX")
			(clearance 0)
			(padstack
				(mode front_inner_back)
				(layer "Inner"
					(shape circle)
					(size 1.524 1.524)
					(clearance 0)
				)
				(layer "B.Cu"
					(shape rect)
					(size 1.524 1.524)
					(clearance 0)
				)
			)
		)
		(pad "2" thru_hole circle
			(at 0 2.500122)
			(size 1.524 1.524)
			(drill 1.016)
			(layers "*.Cu" "*.Mask")
			(remove_unused_layers no)
			(net "GND")
			(clearance 0)
		)
	)
	(footprint ""
		(layer "F.Cu")
		(at 212.299296 -120.457214 180)
		(property "Reference" "U332"
			(at 1.352296 -1.992884 0)
			(unlocked yes)
			(layer "F.SilkS")
			(effects
				(font
					(size 0.7874 0.5842)
					(thickness 0.1524)
				)
				(justify left)
			)
		)
		(property "Value" ""
			(at 0 0 180)
			(layer "F.Fab")
			(effects
				(font
					(size 1.27 1.27)
				)
			)
		)
		(duplicate_pad_numbers_are_jumpers no)
		(fp_line
			(start 1.38176 1.100074)
			(end 1.38176 -1.100074)
			(stroke
				(width 0.1524)
				(type default)
			)
			(layer "F.SilkS")
		)
		(fp_line
			(start 1.38176 -1.100074)
			(end 0.592074 -1.100074)
			(stroke
				(width 0.1524)
				(type default)
			)
			(layer "F.SilkS")
		)
		(fp_line
			(start 0.592074 -1.100074)
			(end 0 -0.508)
			(stroke
				(width 0.1524)
				(type default)
			)
			(layer "F.SilkS")
		)
		(fp_line
			(start 0 -0.508)
			(end -0.592074 -1.100074)
			(stroke
				(width 0.1524)
				(type default)
			)
			(layer "F.SilkS")
		)
		(fp_line
			(start -0.592074 -1.100074)
			(end -1.38176 -1.100074)
			(stroke
				(width 0.1524)
				(type default)
			)
			(layer "F.SilkS")
		)
		(fp_line
			(start -1.38176 1.100074)
			(end 1.38176 1.100074)
			(stroke
				(width 0.1524)
				(type default)
			)
			(layer "F.SilkS")
		)
		(fp_line
			(start -1.38176 -1.100074)
			(end -1.38176 1.100074)
			(stroke
				(width 0.1524)
				(type default)
			)
			(layer "F.SilkS")
		)
		(fp_poly
			(pts
				(xy -1.9431 -0.870204) (xy -1.50241 -0.649986) (xy -1.9431 -0.429768)
			)
			(stroke
				(width 0)
				(type default)
			)
			(fill yes)
			(layer "F.SilkS")
		)
		(fp_line
			(start 0.674878 1.100074)
			(end 0.674878 -1.100074)
			(stroke
				(width 0.1)
				(type default)
			)
			(layer "F.Fab")
		)
		(fp_line
			(start 0.674878 -1.100074)
			(end -0.674878 -1.100074)
			(stroke
				(width 0.1)
				(type default)
			)
			(layer "F.Fab")
		)
		(fp_line
			(start -0.674878 1.100074)
			(end 0.674878 1.100074)
			(stroke
				(width 0.1)
				(type default)
			)
			(layer "F.Fab")
		)
		(fp_line
			(start -0.674878 -1.100074)
			(end -0.674878 1.100074)
			(stroke
				(width 0.1)
				(type default)
			)
			(layer "F.Fab")
		)
		(fp_poly
			(pts
				(xy -1.9431 -0.870204) (xy -1.50241 -0.649986) (xy -1.9431 -0.429768)
			)
			(stroke
				(width 0)
				(type default)
			)
			(fill yes)
			(layer "F.Fab")
		)
		(pad "1" smd rect
			(at -0.94996 -0.649986 90)
			(size 0.4318 0.6096)
			(layers "F.Cu" "F.Mask" "F.Paste")
			(net "FM_AC_PWR_BTN_PLD_N")
		)
		(pad "2" smd rect
			(at -0.94996 0 90)
			(size 0.4318 0.6096)
			(layers "F.Cu" "F.Mask" "F.Paste")
			(net "GND")
		)
		(pad "3" smd rect
			(at -0.94996 0.649986 90)
			(size 0.4318 0.6096)
			(layers "F.Cu" "F.Mask" "F.Paste")
			(net "GND")
		)
		(pad "4" smd rect
			(at 0.94996 0.649986 90)
			(size 0.4318 0.6096)
			(layers "F.Cu" "F.Mask" "F.Paste")
			(net "NC_UXX_2Y")
		)
		(pad "5" smd rect
			(at 0.94996 0 90)
			(size 0.4318 0.6096)
			(layers "F.Cu" "F.Mask" "F.Paste")
			(net "P3V3_AUX")
		)
		(pad "6" smd rect
			(at 0.94996 -0.649986 90)
			(size 0.4318 0.6096)
			(layers "F.Cu" "F.Mask" "F.Paste")
			(net "FM_AC_PWR_BTN_PLD_ISO_R_N")
		)
	)
	(footprint ""
		(layer "F.Cu")
		(at 365.2012 -413.6898 180)
		(property "Reference" "R4801"
			(at 0 0 180)
			(layer "F.SilkS")
			(hide yes)
			(effects
				(font
					(size 1.27 1.27)
				)
			)
		)
		(property "Value" ""
			(at 0 0 180)
			(layer "F.Fab")
			(effects
				(font
					(size 1.27 1.27)
				)
			)
		)
		(duplicate_pad_numbers_are_jumpers no)
		(fp_line
			(start 0.7874 0.4064)
			(end -0.7874 0.4064)
			(stroke
				(width 0.1524)
				(type default)
			)
			(layer "F.SilkS")
		)
		(fp_line
			(start 0.7874 -0.4064)
			(end 0.7874 0.4064)
			(stroke
				(width 0.1524)
				(type default)
			)
			(layer "F.SilkS")
		)
		(fp_line
			(start -0.7874 0.4064)
			(end -0.7874 -0.4064)
			(stroke
				(width 0.1524)
				(type default)
			)
			(layer "F.SilkS")
		)
		(fp_line
			(start -0.7874 -0.4064)
			(end 0.7874 -0.4064)
			(stroke
				(width 0.1524)
				(type default)
			)
			(layer "F.SilkS")
		)
		(fp_line
			(start 0.67945 0.3048)
			(end 0.120396 0.3048)
			(stroke
				(width 0.1)
				(type default)
			)
			(layer "F.Fab")
		)
		(fp_line
			(start 0.67945 -0.3048)
			(end 0.67945 0.3048)
			(stroke
				(width 0.1)
				(type default)
			)
			(layer "F.Fab")
		)
		(fp_line
			(start 0.12065 -0.2794)
			(end 0.12065 -0.3048)
			(stroke
				(width 0.1)
				(type default)
			)
			(layer "F.Fab")
		)
		(fp_line
			(start 0.12065 -0.3048)
			(end 0.67945 -0.3048)
			(stroke
				(width 0.1)
				(type default)
			)
			(layer "F.Fab")
		)
		(fp_line
			(start 0.120396 0.3048)
			(end 0.120396 0.2794)
			(stroke
				(width 0.1)
				(type default)
			)
			(layer "F.Fab")
		)
		(fp_line
			(start 0.120396 0.2794)
			(end -0.12065 0.2794)
			(stroke
				(width 0.1)
				(type default)
			)
			(layer "F.Fab")
		)
		(fp_line
			(start -0.12065 0.3048)
			(end -0.67945 0.3048)
			(stroke
				(width 0.1)
				(type default)
			)
			(layer "F.Fab")
		)
		(fp_line
			(start -0.12065 0.2794)
			(end -0.12065 0.3048)
			(stroke
				(width 0.1)
				(type default)
			)
			(layer "F.Fab")
		)
		(fp_line
			(start -0.12065 -0.2794)
			(end 0.12065 -0.2794)
			(stroke
				(width 0.1)
				(type default)
			)
			(layer "F.Fab")
		)
		(fp_line
			(start -0.12065 -0.305054)
			(end -0.12065 -0.2794)
			(stroke
				(width 0.1)
				(type default)
			)
			(layer "F.Fab")
		)
		(fp_line
			(start -0.67945 0.3048)
			(end -0.67945 -0.305054)
			(stroke
				(width 0.1)
				(type default)
			)
			(layer "F.Fab")
		)
		(fp_line
			(start -0.67945 -0.305054)
			(end -0.12065 -0.305054)
			(stroke
				(width 0.1)
				(type default)
			)
			(layer "F.Fab")
		)
		(pad "1" smd circle
			(at -0.40005 0 180)
			(size 0 0)
			(layers "F.Cu" "F.Mask" "F.Paste")
			(net "P3V3_AUX")
		)
		(pad "2" smd circle
			(at 0.40005 0 180)
			(size 0 0)
			(layers "F.Cu" "F.Mask" "F.Paste")
			(net "PRSNT_CABLE_GPU_A3_ISO_N")
		)
	)
	(footprint ""
		(layer "F.Cu")
		(at 192.601342 -433.96916 -90)
		(property "Reference" "U278"
			(at 1.21412 -2.605532 90)
			(unlocked yes)
			(layer "F.SilkS")
			(effects
				(font
					(size 0.7874 0.5842)
					(thickness 0.1524)
				)
				(justify left)
			)
		)
		(property "Value" ""
			(at 0 0 270)
			(layer "F.Fab")
			(effects
				(font
					(size 1.27 1.27)
				)
			)
		)
		(duplicate_pad_numbers_are_jumpers no)
		(fp_line
			(start -1.733296 1.549908)
			(end 1.733296 1.549908)
			(stroke
				(width 0.1524)
				(type default)
			)
			(layer "F.SilkS")
		)
		(fp_line
			(start 1.733296 1.549908)
			(end 1.733296 -1.549908)
			(stroke
				(width 0.1524)
				(type default)
			)
			(layer "F.SilkS")
		)
		(fp_line
			(start 0 -0.889)
			(end -0.660908 -1.549908)
			(stroke
				(width 0.1524)
				(type default)
			)
			(layer "F.SilkS")
		)
		(fp_line
			(start -1.733296 -1.549908)
			(end -1.733296 1.549908)
			(stroke
				(width 0.1524)
				(type default)
			)
			(layer "F.SilkS")
		)
		(fp_line
			(start -0.660908 -1.549908)
			(end -1.733296 -1.549908)
			(stroke
				(width 0.1524)
				(type default)
			)
			(layer "F.SilkS")
		)
		(fp_line
			(start 0.660908 -1.549908)
			(end 0 -0.889)
			(stroke
				(width 0.1524)
				(type default)
			)
			(layer "F.SilkS")
		)
		(fp_line
			(start 1.733296 -1.549908)
			(end 0.660908 -1.549908)
			(stroke
				(width 0.1524)
				(type default)
			)
			(layer "F.SilkS")
		)
		(fp_poly
			(pts
				(xy -2.4384 -1.20396) (xy -1.9304 -0.94996) (xy -2.4384 -0.69596)
			)
			(stroke
				(width 0)
				(type default)
			)
			(fill yes)
			(layer "F.SilkS")
		)
		(fp_line
			(start -0.849884 1.549908)
			(end 0.849884 1.549908)
			(stroke
				(width 0.1)
				(type default)
			)
			(layer "F.Fab")
		)
		(fp_line
			(start 0.849884 1.549908)
			(end 0.849884 -1.549908)
			(stroke
				(width 0.1)
				(type default)
			)
			(layer "F.Fab")
		)
		(fp_line
			(start -0.849884 -1.549908)
			(end -0.849884 1.549908)
			(stroke
				(width 0.1)
				(type default)
			)
			(layer "F.Fab")
		)
		(fp_line
			(start 0.849884 -1.549908)
			(end -0.849884 -1.549908)
			(stroke
				(width 0.1)
				(type default)
			)
			(layer "F.Fab")
		)
		(fp_poly
			(pts
				(xy -2.4384 -1.20396) (xy -2.4384 -0.69596) (xy -1.9304 -0.94996)
			)
			(stroke
				(width 0)
				(type default)
			)
			(fill yes)
			(layer "F.Fab")
		)
		(pad "1" smd rect
			(at -1.199896 -0.94996 180)
			(size 0.5588 0.8128)
			(layers "F.Cu" "F.Mask" "F.Paste")
			(net "FM_GPU_HSC_EN")
		)
		(pad "2" smd rect
			(at -1.199896 0 180)
			(size 0.5588 0.8128)
			(layers "F.Cu" "F.Mask" "F.Paste")
			(net "GPU_PRSNT_R")
		)
		(pad "3" smd rect
			(at -1.199896 0.94996 180)
			(size 0.5588 0.8128)
			(layers "F.Cu" "F.Mask" "F.Paste")
			(net "GND")
		)
		(pad "4" smd rect
			(at 1.199896 0.94996 180)
			(size 0.5588 0.8128)
			(layers "F.Cu" "F.Mask" "F.Paste")
			(net "FM_GPU_HSC_EN_BUF_R")
		)
		(pad "5" smd rect
			(at 1.199896 -0.94996 180)
			(size 0.5588 0.8128)
			(layers "F.Cu" "F.Mask" "F.Paste")
			(net "P3V3_AUX")
		)
	)
	(footprint ""
		(layer "F.Cu")
		(at 22.809454 -106.761026 180)
		(property "Reference" "R3668"
			(at 0 0 180)
			(layer "F.SilkS")
			(hide yes)
			(effects
				(font
					(size 1.27 1.27)
				)
			)
		)
		(property "Value" ""
			(at 0 0 180)
			(layer "F.Fab")
			(effects
				(font
					(size 1.27 1.27)
				)
			)
		)
		(duplicate_pad_numbers_are_jumpers no)
		(fp_line
			(start 0.7874 0.4064)
			(end -0.7874 0.4064)
			(stroke
				(width 0.1524)
				(type default)
			)
			(layer "F.SilkS")
		)
		(fp_line
			(start 0.7874 -0.4064)
			(end 0.7874 0.4064)
			(stroke
				(width 0.1524)
				(type default)
			)
			(layer "F.SilkS")
		)
		(fp_line
			(start -0.7874 0.4064)
			(end -0.7874 -0.4064)
			(stroke
				(width 0.1524)
				(type default)
			)
			(layer "F.SilkS")
		)
		(fp_line
			(start -0.7874 -0.4064)
			(end 0.7874 -0.4064)
			(stroke
				(width 0.1524)
				(type default)
			)
			(layer "F.SilkS")
		)
		(fp_line
			(start 0.67945 0.3048)
			(end 0.120396 0.3048)
			(stroke
				(width 0.1)
				(type default)
			)
			(layer "F.Fab")
		)
		(fp_line
			(start 0.67945 -0.3048)
			(end 0.67945 0.3048)
			(stroke
				(width 0.1)
				(type default)
			)
			(layer "F.Fab")
		)
		(fp_line
			(start 0.12065 -0.2794)
			(end 0.12065 -0.3048)
			(stroke
				(width 0.1)
				(type default)
			)
			(layer "F.Fab")
		)
		(fp_line
			(start 0.12065 -0.3048)
			(end 0.67945 -0.3048)
			(stroke
				(width 0.1)
				(type default)
			)
			(layer "F.Fab")
		)
		(fp_line
			(start 0.120396 0.3048)
			(end 0.120396 0.2794)
			(stroke
				(width 0.1)
				(type default)
			)
			(layer "F.Fab")
		)
		(fp_line
			(start 0.120396 0.2794)
			(end -0.12065 0.2794)
			(stroke
				(width 0.1)
				(type default)
			)
			(layer "F.Fab")
		)
		(fp_line
			(start -0.12065 0.3048)
			(end -0.67945 0.3048)
			(stroke
				(width 0.1)
				(type default)
			)
			(layer "F.Fab")
		)
		(fp_line
			(start -0.12065 0.2794)
			(end -0.12065 0.3048)
			(stroke
				(width 0.1)
				(type default)
			)
			(layer "F.Fab")
		)
		(fp_line
			(start -0.12065 -0.2794)
			(end 0.12065 -0.2794)
			(stroke
				(width 0.1)
				(type default)
			)
			(layer "F.Fab")
		)
		(fp_line
			(start -0.12065 -0.305054)
			(end -0.12065 -0.2794)
			(stroke
				(width 0.1)
				(type default)
			)
			(layer "F.Fab")
		)
		(fp_line
			(start -0.67945 0.3048)
			(end -0.67945 -0.305054)
			(stroke
				(width 0.1)
				(type default)
			)
			(layer "F.Fab")
		)
		(fp_line
			(start -0.67945 -0.305054)
			(end -0.12065 -0.305054)
			(stroke
				(width 0.1)
				(type default)
			)
			(layer "F.Fab")
		)
		(pad "1" smd circle
			(at -0.40005 0 180)
			(size 0 0)
			(layers "F.Cu" "F.Mask" "F.Paste")
			(net "ADC128_A1")
		)
		(pad "2" smd circle
			(at 0.40005 0 180)
			(size 0 0)
			(layers "F.Cu" "F.Mask" "F.Paste")
			(net "GND")
		)
	)
	(footprint ""
		(layer "F.Cu")
		(at 77.128878 -23.308818 180)
		(property "Reference" "PC2098"
			(at 0 0 180)
			(layer "F.SilkS")
			(hide yes)
			(effects
				(font
					(size 1.27 1.27)
				)
			)
		)
		(property "Value" ""
			(at 0 0 180)
			(layer "F.Fab")
			(effects
				(font
					(size 1.27 1.27)
				)
			)
		)
		(duplicate_pad_numbers_are_jumpers no)
		(fp_line
			(start 0.7874 0.4064)
			(end -0.7874 0.4064)
			(stroke
				(width 0.1524)
				(type default)
			)
			(layer "F.SilkS")
		)
		(fp_line
			(start 0.7874 -0.4064)
			(end 0.7874 0.4064)
			(stroke
				(width 0.1524)
				(type default)
			)
			(layer "F.SilkS")
		)
		(fp_line
			(start -0.7874 0.4064)
			(end -0.7874 -0.4064)
			(stroke
				(width 0.1524)
				(type default)
			)
			(layer "F.SilkS")
		)
		(fp_line
			(start -0.7874 -0.4064)
			(end 0.7874 -0.4064)
			(stroke
				(width 0.1524)
				(type default)
			)
			(layer "F.SilkS")
		)
		(fp_line
			(start 0.67945 0.3048)
			(end 0.120396 0.3048)
			(stroke
				(width 0.1)
				(type default)
			)
			(layer "F.Fab")
		)
		(fp_line
			(start 0.67945 -0.3048)
			(end 0.67945 0.3048)
			(stroke
				(width 0.1)
				(type default)
			)
			(layer "F.Fab")
		)
		(fp_line
			(start 0.12065 -0.2794)
			(end 0.12065 -0.3048)
			(stroke
				(width 0.1)
				(type default)
			)
			(layer "F.Fab")
		)
		(fp_line
			(start 0.12065 -0.3048)
			(end 0.67945 -0.3048)
			(stroke
				(width 0.1)
				(type default)
			)
			(layer "F.Fab")
		)
		(fp_line
			(start 0.120396 0.3048)
			(end 0.120396 0.2794)
			(stroke
				(width 0.1)
				(type default)
			)
			(layer "F.Fab")
		)
		(fp_line
			(start 0.120396 0.2794)
			(end -0.12065 0.2794)
			(stroke
				(width 0.1)
				(type default)
			)
			(layer "F.Fab")
		)
		(fp_line
			(start -0.12065 0.3048)
			(end -0.67945 0.3048)
			(stroke
				(width 0.1)
				(type default)
			)
			(layer "F.Fab")
		)
		(fp_line
			(start -0.12065 0.2794)
			(end -0.12065 0.3048)
			(stroke
				(width 0.1)
				(type default)
			)
			(layer "F.Fab")
		)
		(fp_line
			(start -0.12065 -0.2794)
			(end 0.12065 -0.2794)
			(stroke
				(width 0.1)
				(type default)
			)
			(layer "F.Fab")
		)
		(fp_line
			(start -0.12065 -0.305054)
			(end -0.12065 -0.2794)
			(stroke
				(width 0.1)
				(type default)
			)
			(layer "F.Fab")
		)
		(fp_line
			(start -0.67945 0.3048)
			(end -0.67945 -0.305054)
			(stroke
				(width 0.1)
				(type default)
			)
			(layer "F.Fab")
		)
		(fp_line
			(start -0.67945 -0.305054)
			(end -0.12065 -0.305054)
			(stroke
				(width 0.1)
				(type default)
			)
			(layer "F.Fab")
		)
		(pad "1" smd circle
			(at -0.40005 0 180)
			(size 0 0)
			(layers "F.Cu" "F.Mask" "F.Paste")
			(net "P12V_OCP_VCC_2")
		)
		(pad "2" smd circle
			(at 0.40005 0 180)
			(size 0 0)
			(layers "F.Cu" "F.Mask" "F.Paste")
			(net "GND")
		)
	)
	(footprint ""
		(layer "F.Cu")
		(at 70.93712 -53.543708)
		(property "Reference" "PR3855"
			(at 0 0 0)
			(layer "F.SilkS")
			(hide yes)
			(effects
				(font
					(size 1.27 1.27)
				)
			)
		)
		(property "Value" ""
			(at 0 0 0)
			(layer "F.Fab")
			(effects
				(font
					(size 1.27 1.27)
				)
			)
		)
		(duplicate_pad_numbers_are_jumpers no)
		(fp_line
			(start -0.7874 -0.4064)
			(end 0.7874 -0.4064)
			(stroke
				(width 0.1524)
				(type default)
			)
			(layer "F.SilkS")
		)
		(fp_line
			(start -0.7874 0.4064)
			(end -0.7874 -0.4064)
			(stroke
				(width 0.1524)
				(type default)
			)
			(layer "F.SilkS")
		)
		(fp_line
			(start 0.7874 -0.4064)
			(end 0.7874 0.4064)
			(stroke
				(width 0.1524)
				(type default)
			)
			(layer "F.SilkS")
		)
		(fp_line
			(start 0.7874 0.4064)
			(end -0.7874 0.4064)
			(stroke
				(width 0.1524)
				(type default)
			)
			(layer "F.SilkS")
		)
		(fp_line
			(start -0.67945 -0.305054)
			(end -0.12065 -0.305054)
			(stroke
				(width 0.1)
				(type default)
			)
			(layer "F.Fab")
		)
		(fp_line
			(start -0.67945 0.3048)
			(end -0.67945 -0.305054)
			(stroke
				(width 0.1)
				(type default)
			)
			(layer "F.Fab")
		)
		(fp_line
			(start -0.12065 -0.305054)
			(end -0.12065 -0.2794)
			(stroke
				(width 0.1)
				(type default)
			)
			(layer "F.Fab")
		)
		(fp_line
			(start -0.12065 -0.2794)
			(end 0.12065 -0.2794)
			(stroke
				(width 0.1)
				(type default)
			)
			(layer "F.Fab")
		)
		(fp_line
			(start -0.12065 0.2794)
			(end -0.12065 0.3048)
			(stroke
				(width 0.1)
				(type default)
			)
			(layer "F.Fab")
		)
		(fp_line
			(start -0.12065 0.3048)
			(end -0.67945 0.3048)
			(stroke
				(width 0.1)
				(type default)
			)
			(layer "F.Fab")
		)
		(fp_line
			(start 0.120396 0.2794)
			(end -0.12065 0.2794)
			(stroke
				(width 0.1)
				(type default)
			)
			(layer "F.Fab")
		)
		(fp_line
			(start 0.120396 0.3048)
			(end 0.120396 0.2794)
			(stroke
				(width 0.1)
				(type default)
			)
			(layer "F.Fab")
		)
		(fp_line
			(start 0.12065 -0.3048)
			(end 0.67945 -0.3048)
			(stroke
				(width 0.1)
				(type default)
			)
			(layer "F.Fab")
		)
		(fp_line
			(start 0.12065 -0.2794)
			(end 0.12065 -0.3048)
			(stroke
				(width 0.1)
				(type default)
			)
			(layer "F.Fab")
		)
		(fp_line
			(start 0.67945 -0.3048)
			(end 0.67945 0.3048)
			(stroke
				(width 0.1)
				(type default)
			)
			(layer "F.Fab")
		)
		(fp_line
			(start 0.67945 0.3048)
			(end 0.120396 0.3048)
			(stroke
				(width 0.1)
				(type default)
			)
			(layer "F.Fab")
		)
		(pad "1" smd circle
			(at -0.40005 0)
			(size 0 0)
			(layers "F.Cu" "F.Mask" "F.Paste")
			(net "P3V3_OCP_MODE_2")
		)
		(pad "2" smd circle
			(at 0.40005 0)
			(size 0 0)
			(layers "F.Cu" "F.Mask" "F.Paste")
			(net "GND")
		)
	)
	(footprint ""
		(layer "F.Cu")
		(at 120.438926 -122.096784 90)
		(property "Reference" "R933"
			(at 0 0 90)
			(layer "F.SilkS")
			(hide yes)
			(effects
				(font
					(size 1.27 1.27)
				)
			)
		)
		(property "Value" ""
			(at 0 0 90)
			(layer "F.Fab")
			(effects
				(font
					(size 1.27 1.27)
				)
			)
		)
		(duplicate_pad_numbers_are_jumpers no)
		(fp_line
			(start 0.7874 -0.4064)
			(end 0.7874 0.4064)
			(stroke
				(width 0.1524)
				(type default)
			)
			(layer "F.SilkS")
		)
		(fp_line
			(start -0.7874 -0.4064)
			(end 0.7874 -0.4064)
			(stroke
				(width 0.1524)
				(type default)
			)
			(layer "F.SilkS")
		)
		(fp_line
			(start 0.7874 0.4064)
			(end -0.7874 0.4064)
			(stroke
				(width 0.1524)
				(type default)
			)
			(layer "F.SilkS")
		)
		(fp_line
			(start -0.7874 0.4064)
			(end -0.7874 -0.4064)
			(stroke
				(width 0.1524)
				(type default)
			)
			(layer "F.SilkS")
		)
		(fp_line
			(start -0.12065 -0.305054)
			(end -0.12065 -0.2794)
			(stroke
				(width 0.1)
				(type default)
			)
			(layer "F.Fab")
		)
		(fp_line
			(start -0.67945 -0.305054)
			(end -0.12065 -0.305054)
			(stroke
				(width 0.1)
				(type default)
			)
			(layer "F.Fab")
		)
		(fp_line
			(start 0.67945 -0.3048)
			(end 0.67945 0.3048)
			(stroke
				(width 0.1)
				(type default)
			)
			(layer "F.Fab")
		)
		(fp_line
			(start 0.12065 -0.3048)
			(end 0.67945 -0.3048)
			(stroke
				(width 0.1)
				(type default)
			)
			(layer "F.Fab")
		)
		(fp_line
			(start 0.12065 -0.2794)
			(end 0.12065 -0.3048)
			(stroke
				(width 0.1)
				(type default)
			)
			(layer "F.Fab")
		)
		(fp_line
			(start -0.12065 -0.2794)
			(end 0.12065 -0.2794)
			(stroke
				(width 0.1)
				(type default)
			)
			(layer "F.Fab")
		)
		(fp_line
			(start 0.120396 0.2794)
			(end -0.12065 0.2794)
			(stroke
				(width 0.1)
				(type default)
			)
			(layer "F.Fab")
		)
		(fp_line
			(start -0.12065 0.2794)
			(end -0.12065 0.3048)
			(stroke
				(width 0.1)
				(type default)
			)
			(layer "F.Fab")
		)
		(fp_line
			(start 0.67945 0.3048)
			(end 0.120396 0.3048)
			(stroke
				(width 0.1)
				(type default)
			)
			(layer "F.Fab")
		)
		(fp_line
			(start 0.120396 0.3048)
			(end 0.120396 0.2794)
			(stroke
				(width 0.1)
				(type default)
			)
			(layer "F.Fab")
		)
		(fp_line
			(start -0.12065 0.3048)
			(end -0.67945 0.3048)
			(stroke
				(width 0.1)
				(type default)
			)
			(layer "F.Fab")
		)
		(fp_line
			(start -0.67945 0.3048)
			(end -0.67945 -0.305054)
			(stroke
				(width 0.1)
				(type default)
			)
			(layer "F.Fab")
		)
		(pad "1" smd circle
			(at -0.40005 0 90)
			(size 0 0)
			(layers "F.Cu" "F.Mask" "F.Paste")
			(net "RST_CPU1_DRAM_AB_N")
		)
		(pad "2" smd circle
			(at 0.40005 0 90)
			(size 0 0)
			(layers "F.Cu" "F.Mask" "F.Paste")
			(net "GND")
		)
	)
	(footprint ""
		(layer "F.Cu")
		(at 408.803348 -258.091686)
		(property "Reference" "J10"
			(at -3.683 -81.702148 0)
			(unlocked yes)
			(layer "F.SilkS")
			(effects
				(font
					(size 0.7874 0.5842)
					(thickness 0.1524)
				)
				(justify left)
			)
		)
		(property "Value" ""
			(at 0 0 0)
			(layer "F.Fab")
			(effects
				(font
					(size 1.27 1.27)
				)
			)
		)
		(duplicate_pad_numbers_are_jumpers no)
		(fp_line
			(start -3.24993 -81.000092)
			(end -3.24993 76.082398)
			(stroke
				(width 0.1524)
				(type default)
			)
			(layer "F.SilkS")
		)
		(fp_line
			(start -3.24993 81.000092)
			(end 3.24993 81.000092)
			(stroke
				(width 0.1524)
				(type default)
			)
			(layer "F.SilkS")
		)
		(fp_line
			(start 3.24993 -81.000092)
			(end -3.24993 -81.000092)
			(stroke
				(width 0.1524)
				(type default)
			)
			(layer "F.SilkS")
		)
		(fp_line
			(start 3.24993 -72.00011)
			(end -3.24993 -72.00011)
			(stroke
				(width 0.1524)
				(type default)
			)
			(layer "F.SilkS")
		)
		(fp_line
			(start 3.24993 72.00011)
			(end -3.24993 72.00011)
			(stroke
				(width 0.1524)
				(type default)
			)
			(layer "F.SilkS")
		)
		(fp_line
			(start 3.24993 81.000092)
			(end 3.24993 -81.000092)
			(stroke
				(width 0.1524)
				(type default)
			)
			(layer "F.SilkS")
		)
		(fp_poly
			(pts
				(xy -3.447288 -63.424054) (xy -4.463288 -62.916054) (xy -4.463288 -63.932054)
			)
			(stroke
				(width 0)
				(type default)
			)
			(fill yes)
			(layer "F.SilkS")
		)
		(fp_line
			(start -3.24993 -81.000092)
			(end -3.24993 81.000092)
			(stroke
				(width 0.1)
				(type default)
			)
			(layer "F.Fab")
		)
		(fp_line
			(start -3.24993 81.000092)
			(end 3.24993 81.000092)
			(stroke
				(width 0.1)
				(type default)
			)
			(layer "F.Fab")
		)
		(fp_line
			(start 3.24993 -81.000092)
			(end -3.24993 -81.000092)
			(stroke
				(width 0.1)
				(type default)
			)
			(layer "F.Fab")
		)
		(fp_line
			(start 3.24993 -72.00011)
			(end -3.24993 -72.00011)
			(stroke
				(width 0.1)
				(type default)
			)
			(layer "F.Fab")
		)
		(fp_line
			(start 3.24993 -71.000112)
			(end -3.24993 -71.000112)
			(stroke
				(width 0.1)
				(type default)
			)
			(layer "F.Fab")
		)
		(fp_line
			(start 3.24993 71.000112)
			(end -3.24993 71.000112)
			(stroke
				(width 0.1)
				(type default)
			)
			(layer "F.Fab")
		)
		(fp_line
			(start 3.24993 72.00011)
			(end -3.24993 72.00011)
			(stroke
				(width 0.1)
				(type default)
			)
			(layer "F.Fab")
		)
		(fp_line
			(start 3.24993 81.000092)
			(end 3.24993 -81.000092)
			(stroke
				(width 0.1)
				(type default)
			)
			(layer "F.Fab")
		)
		(fp_poly
			(pts
				(xy -4.445 -63.832994) (xy -4.445 -62.816994) (xy -3.429 -63.324994)
			)
			(stroke
				(width 0)
				(type default)
			)
			(fill yes)
			(layer "F.Fab")
		)
		(pad "1" smd rect
			(at -2.050034 -63.324994 270)
			(size 0.519938 1.4986)
			(layers "F.Cu" "F.Mask" "F.Paste")
			(net "P12V_S3_AUX_CPU0_NVDIMM")
		)
		(pad "2" smd rect
			(at -2.050034 -62.47511 270)
			(size 0.519938 1.4986)
			(layers "F.Cu" "F.Mask" "F.Paste")
			(net "TP_CHE_CPU0_DIMM2_FRU_0")
		)
		(pad "3" smd rect
			(at -2.050034 -61.624972 270)
			(size 0.519938 1.4986)
			(layers "F.Cu" "F.Mask" "F.Paste")
			(net "P3V3_AUX")
		)
		(pad "4" smd rect
			(at -2.050034 -60.775088 270)
			(size 0.519938 1.4986)
			(layers "F.Cu" "F.Mask" "F.Paste")
			(net "I3C_SPD_DDREFGH_CPU0_LVC1_SCL_1")
		)
		(pad "5" smd rect
			(at -2.050034 -59.92495 270)
			(size 0.519938 1.4986)
			(layers "F.Cu" "F.Mask" "F.Paste")
			(net "I3C_SPD_DDREFGH_CPU0_LVC1_SDA")
		)
		(pad "6" smd rect
			(at -2.050034 -59.075066 270)
			(size 0.519938 1.4986)
			(layers "F.Cu" "F.Mask" "F.Paste")
			(net "GND")
		)
		(pad "7" smd rect
			(at -2.050034 -58.224928 270)
			(size 0.519938 1.4986)
			(layers "F.Cu" "F.Mask" "F.Paste")
			(net "M_E_CPU0_SA_DQ<0>")
		)
		(pad "8" smd rect
			(at -2.050034 -57.375044 270)
			(size 0.519938 1.4986)
			(layers "F.Cu" "F.Mask" "F.Paste")
			(net "GND")
		)
		(pad "9" smd rect
			(at -2.050034 -56.524906 270)
			(size 0.519938 1.4986)
			(layers "F.Cu" "F.Mask" "F.Paste")
			(net "M_E_CPU0_SA_DQ<1>")
		)
		(pad "10" smd rect
			(at -2.050034 -55.675022 270)
			(size 0.519938 1.4986)
			(layers "F.Cu" "F.Mask" "F.Paste")
			(net "GND")
		)
		(pad "11" smd rect
			(at -2.050034 -54.824884 270)
			(size 0.519938 1.4986)
			(layers "F.Cu" "F.Mask" "F.Paste")
			(net "M_E_CPU0_SA_DQS_DP<0>")
		)
		(pad "12" smd rect
			(at -2.050034 -53.975 270)
			(size 0.519938 1.4986)
			(layers "F.Cu" "F.Mask" "F.Paste")
			(net "M_E_CPU0_SA_DQS_DN<0>")
		)
		(pad "13" smd rect
			(at -2.050034 -53.125116 270)
			(size 0.519938 1.4986)
			(layers "F.Cu" "F.Mask" "F.Paste")
			(net "GND")
		)
		(pad "14" smd rect
			(at -2.050034 -52.274978 270)
			(size 0.519938 1.4986)
			(layers "F.Cu" "F.Mask" "F.Paste")
			(net "M_E_CPU0_SA_DQ<4>")
		)
		(pad "15" smd rect
			(at -2.050034 -51.425094 270)
			(size 0.519938 1.4986)
			(layers "F.Cu" "F.Mask" "F.Paste")
			(net "GND")
		)
		(pad "16" smd rect
			(at -2.050034 -50.574956 270)
			(size 0.519938 1.4986)
			(layers "F.Cu" "F.Mask" "F.Paste")
			(net "M_E_CPU0_SA_DQ<5>")
		)
		(pad "17" smd rect
			(at -2.050034 -49.725072 270)
			(size 0.519938 1.4986)
			(layers "F.Cu" "F.Mask" "F.Paste")
			(net "GND")
		)
		(pad "18" smd rect
			(at -2.050034 -48.874934 270)
			(size 0.519938 1.4986)
			(layers "F.Cu" "F.Mask" "F.Paste")
			(net "M_E_CPU0_SA_DQ<8>")
		)
		(pad "19" smd rect
			(at -2.050034 -48.02505 270)
			(size 0.519938 1.4986)
			(layers "F.Cu" "F.Mask" "F.Paste")
			(net "GND")
		)
		(pad "20" smd rect
			(at -2.050034 -47.174912 270)
			(size 0.519938 1.4986)
			(layers "F.Cu" "F.Mask" "F.Paste")
			(net "M_E_CPU0_SA_DQ<9>")
		)
		(pad "21" smd rect
			(at -2.050034 -46.325028 270)
			(size 0.519938 1.4986)
			(layers "F.Cu" "F.Mask" "F.Paste")
			(net "GND")
		)
		(pad "22" smd rect
			(at -2.050034 -45.47489 270)
			(size 0.519938 1.4986)
			(layers "F.Cu" "F.Mask" "F.Paste")
			(net "M_E_CPU0_SA_DQS_DP<1>")
		)
		(pad "23" smd rect
			(at -2.050034 -44.625006 270)
			(size 0.519938 1.4986)
			(layers "F.Cu" "F.Mask" "F.Paste")
			(net "M_E_CPU0_SA_DQS_DN<1>")
		)
		(pad "24" smd rect
			(at -2.050034 -43.775122 270)
			(size 0.519938 1.4986)
			(layers "F.Cu" "F.Mask" "F.Paste")
			(net "GND")
		)
		(pad "25" smd rect
			(at -2.050034 -42.924984 270)
			(size 0.519938 1.4986)
			(layers "F.Cu" "F.Mask" "F.Paste")
			(net "M_E_CPU0_SA_DQ<12>")
		)
		(pad "26" smd rect
			(at -2.050034 -42.0751 270)
			(size 0.519938 1.4986)
			(layers "F.Cu" "F.Mask" "F.Paste")
			(net "GND")
		)
		(pad "27" smd rect
			(at -2.050034 -41.224962 270)
			(size 0.519938 1.4986)
			(layers "F.Cu" "F.Mask" "F.Paste")
			(net "M_E_CPU0_SA_DQ<13>")
		)
		(pad "28" smd rect
			(at -2.050034 -40.375078 270)
			(size 0.519938 1.4986)
			(layers "F.Cu" "F.Mask" "F.Paste")
			(net "GND")
		)
		(pad "29" smd rect
			(at -2.050034 -39.52494 270)
			(size 0.519938 1.4986)
			(layers "F.Cu" "F.Mask" "F.Paste")
			(net "M_E_CPU0_SA_DQ<16>")
		)
		(pad "30" smd rect
			(at -2.050034 -38.675056 270)
			(size 0.519938 1.4986)
			(layers "F.Cu" "F.Mask" "F.Paste")
			(net "GND")
		)
		(pad "31" smd rect
			(at -2.050034 -37.824918 270)
			(size 0.519938 1.4986)
			(layers "F.Cu" "F.Mask" "F.Paste")
			(net "M_E_CPU0_SA_DQ<17>")
		)
		(pad "32" smd rect
			(at -2.050034 -36.975034 270)
			(size 0.519938 1.4986)
			(layers "F.Cu" "F.Mask" "F.Paste")
			(net "GND")
		)
		(pad "33" smd rect
			(at -2.050034 -36.124896 270)
			(size 0.519938 1.4986)
			(layers "F.Cu" "F.Mask" "F.Paste")
			(net "M_E_CPU0_SA_DQS_DP<2>")
		)
		(pad "34" smd rect
			(at -2.050034 -35.275012 270)
			(size 0.519938 1.4986)
			(layers "F.Cu" "F.Mask" "F.Paste")
			(net "M_E_CPU0_SA_DQS_DN<2>")
		)
		(pad "35" smd rect
			(at -2.050034 -34.425128 270)
			(size 0.519938 1.4986)
			(layers "F.Cu" "F.Mask" "F.Paste")
			(net "GND")
		)
		(pad "36" smd rect
			(at -2.050034 -33.57499 270)
			(size 0.519938 1.4986)
			(layers "F.Cu" "F.Mask" "F.Paste")
			(net "M_E_CPU0_SA_DQ<20>")
		)
		(pad "37" smd rect
			(at -2.050034 -32.725106 270)
			(size 0.519938 1.4986)
			(layers "F.Cu" "F.Mask" "F.Paste")
			(net "GND")
		)
		(pad "38" smd rect
			(at -2.050034 -31.874968 270)
			(size 0.519938 1.4986)
			(layers "F.Cu" "F.Mask" "F.Paste")
			(net "M_E_CPU0_SA_DQ<21>")
		)
		(pad "39" smd rect
			(at -2.050034 -31.025084 270)
			(size 0.519938 1.4986)
			(layers "F.Cu" "F.Mask" "F.Paste")
			(net "GND")
		)
		(pad "40" smd rect
			(at -2.050034 -30.174946 270)
			(size 0.519938 1.4986)
			(layers "F.Cu" "F.Mask" "F.Paste")
			(net "M_E_CPU0_SA_DQ<24>")
		)
		(pad "41" smd rect
			(at -2.050034 -29.325062 270)
			(size 0.519938 1.4986)
			(layers "F.Cu" "F.Mask" "F.Paste")
			(net "GND")
		)
		(pad "42" smd rect
			(at -2.050034 -28.474924 270)
			(size 0.519938 1.4986)
			(layers "F.Cu" "F.Mask" "F.Paste")
			(net "M_E_CPU0_SA_DQ<25>")
		)
		(pad "43" smd rect
			(at -2.050034 -27.62504 270)
			(size 0.519938 1.4986)
			(layers "F.Cu" "F.Mask" "F.Paste")
			(net "GND")
		)
		(pad "44" smd rect
			(at -2.050034 -26.774902 270)
			(size 0.519938 1.4986)
			(layers "F.Cu" "F.Mask" "F.Paste")
			(net "M_E_CPU0_SA_DQS_DP<3>")
		)
		(pad "45" smd rect
			(at -2.050034 -25.925018 270)
			(size 0.519938 1.4986)
			(layers "F.Cu" "F.Mask" "F.Paste")
			(net "M_E_CPU0_SA_DQS_DN<3>")
		)
		(pad "46" smd rect
			(at -2.050034 -25.07488 270)
			(size 0.519938 1.4986)
			(layers "F.Cu" "F.Mask" "F.Paste")
			(net "GND")
		)
		(pad "47" smd rect
			(at -2.050034 -24.224996 270)
			(size 0.519938 1.4986)
			(layers "F.Cu" "F.Mask" "F.Paste")
			(net "M_E_CPU0_SA_DQ<28>")
		)
		(pad "48" smd rect
			(at -2.050034 -23.375112 270)
			(size 0.519938 1.4986)
			(layers "F.Cu" "F.Mask" "F.Paste")
			(net "GND")
		)
		(pad "49" smd rect
			(at -2.050034 -22.524974 270)
			(size 0.519938 1.4986)
			(layers "F.Cu" "F.Mask" "F.Paste")
			(net "M_E_CPU0_SA_DQ<29>")
		)
		(pad "50" smd rect
			(at -2.050034 -21.67509 270)
			(size 0.519938 1.4986)
			(layers "F.Cu" "F.Mask" "F.Paste")
			(net "GND")
		)
		(pad "51" smd rect
			(at -2.050034 -20.824952 270)
			(size 0.519938 1.4986)
			(layers "F.Cu" "F.Mask" "F.Paste")
			(net "M_E_CPU0_SA_CB<0>")
		)
		(pad "52" smd rect
			(at -2.050034 -19.975068 270)
			(size 0.519938 1.4986)
			(layers "F.Cu" "F.Mask" "F.Paste")
			(net "GND")
		)
		(pad "53" smd rect
			(at -2.050034 -19.12493 270)
			(size 0.519938 1.4986)
			(layers "F.Cu" "F.Mask" "F.Paste")
			(net "M_E_CPU0_SA_CB<1>")
		)
		(pad "54" smd rect
			(at -2.050034 -18.275046 270)
			(size 0.519938 1.4986)
			(layers "F.Cu" "F.Mask" "F.Paste")
			(net "GND")
		)
		(pad "55" smd rect
			(at -2.050034 -17.424908 270)
			(size 0.519938 1.4986)
			(layers "F.Cu" "F.Mask" "F.Paste")
			(net "M_E_CPU0_SA_DQS_DP<4>")
		)
		(pad "56" smd rect
			(at -2.050034 -16.575024 270)
			(size 0.519938 1.4986)
			(layers "F.Cu" "F.Mask" "F.Paste")
			(net "M_E_CPU0_SA_DQS_DN<4>")
		)
		(pad "57" smd rect
			(at -2.050034 -15.724886 270)
			(size 0.519938 1.4986)
			(layers "F.Cu" "F.Mask" "F.Paste")
			(net "GND")
		)
		(pad "58" smd rect
			(at -2.050034 -14.875002 270)
			(size 0.519938 1.4986)
			(layers "F.Cu" "F.Mask" "F.Paste")
			(net "M_E_CPU0_SA_CB<4>")
		)
		(pad "59" smd rect
			(at -2.050034 -14.025118 270)
			(size 0.519938 1.4986)
			(layers "F.Cu" "F.Mask" "F.Paste")
			(net "GND")
		)
		(pad "60" smd rect
			(at -2.050034 -13.17498 270)
			(size 0.519938 1.4986)
			(layers "F.Cu" "F.Mask" "F.Paste")
			(net "M_E_CPU0_SA_CB<5>")
		)
		(pad "61" smd rect
			(at -2.050034 -12.325096 270)
			(size 0.519938 1.4986)
			(layers "F.Cu" "F.Mask" "F.Paste")
			(net "GND")
		)
		(pad "62" smd rect
			(at -2.050034 -11.474958 270)
			(size 0.519938 1.4986)
			(layers "F.Cu" "F.Mask" "F.Paste")
			(net "M_E_CPU0_ALERT_N")
		)
		(pad "63" smd rect
			(at -2.050034 -10.625074 270)
			(size 0.519938 1.4986)
			(layers "F.Cu" "F.Mask" "F.Paste")
			(net "GND")
		)
		(pad "64" smd rect
			(at -2.050034 -9.774936 270)
			(size 0.519938 1.4986)
			(layers "F.Cu" "F.Mask" "F.Paste")
			(net "M_E_CPU0_SA_CS_N<2>")
		)
		(pad "65" smd rect
			(at -2.050034 -8.925052 270)
			(size 0.519938 1.4986)
			(layers "F.Cu" "F.Mask" "F.Paste")
			(net "GND")
		)
		(pad "66" smd rect
			(at -2.050034 -8.074914 270)
			(size 0.519938 1.4986)
			(layers "F.Cu" "F.Mask" "F.Paste")
			(net "M_E_CPU0_SA_CA<0>")
		)
		(pad "67" smd rect
			(at -2.050034 -7.22503 270)
			(size 0.519938 1.4986)
			(layers "F.Cu" "F.Mask" "F.Paste")
			(net "GND")
		)
		(pad "68" smd rect
			(at -2.050034 -6.374892 270)
			(size 0.519938 1.4986)
			(layers "F.Cu" "F.Mask" "F.Paste")
			(net "M_E_CPU0_SA_CA<2>")
		)
		(pad "69" smd rect
			(at -2.050034 -5.525008 270)
			(size 0.519938 1.4986)
			(layers "F.Cu" "F.Mask" "F.Paste")
			(net "GND")
		)
		(pad "70" smd rect
			(at -2.050034 -4.675124 270)
			(size 0.519938 1.4986)
			(layers "F.Cu" "F.Mask" "F.Paste")
			(net "M_E_CPU0_SA_CA<4>")
		)
		(pad "71" smd rect
			(at -2.050034 -3.824986 270)
			(size 0.519938 1.4986)
			(layers "F.Cu" "F.Mask" "F.Paste")
			(net "GND")
		)
		(pad "72" smd rect
			(at -2.050034 -2.975102 270)
			(size 0.519938 1.4986)
			(layers "F.Cu" "F.Mask" "F.Paste")
			(net "M_E_CPU0_SA_CA<6>")
		)
		(pad "73" smd rect
			(at -2.050034 -2.124964 270)
			(size 0.519938 1.4986)
			(layers "F.Cu" "F.Mask" "F.Paste")
			(net "GND")
		)
		(pad "74" smd rect
			(at -2.050034 -1.27508 270)
			(size 0.519938 1.4986)
			(layers "F.Cu" "F.Mask" "F.Paste")
			(net "M_E_CPU0_SA_PAR")
		)
		(pad "75" smd rect
			(at -2.050034 -0.424942 270)
			(size 0.519938 1.4986)
			(layers "F.Cu" "F.Mask" "F.Paste")
			(net "GND")
		)
		(pad "76" smd rect
			(at -2.050034 5.525008 270)
			(size 0.519938 1.4986)
			(layers "F.Cu" "F.Mask" "F.Paste")
			(net "M_E_CPU0_SB_CA<0>")
		)
		(pad "77" smd rect
			(at -2.050034 6.374892 270)
			(size 0.519938 1.4986)
			(layers "F.Cu" "F.Mask" "F.Paste")
			(net "GND")
		)
		(pad "78" smd rect
			(at -2.050034 7.22503 270)
			(size 0.519938 1.4986)
			(layers "F.Cu" "F.Mask" "F.Paste")
			(net "M_E_CPU0_SB_CA<2>")
		)
		(pad "79" smd rect
			(at -2.050034 8.074914 270)
			(size 0.519938 1.4986)
			(layers "F.Cu" "F.Mask" "F.Paste")
			(net "GND")
		)
		(pad "80" smd rect
			(at -2.050034 8.925052 270)
			(size 0.519938 1.4986)
			(layers "F.Cu" "F.Mask" "F.Paste")
			(net "M_E_CPU0_SB_CA<4>")
		)
		(pad "81" smd rect
			(at -2.050034 9.774936 270)
			(size 0.519938 1.4986)
			(layers "F.Cu" "F.Mask" "F.Paste")
			(net "GND")
		)
		(pad "82" smd rect
			(at -2.050034 10.625074 270)
			(size 0.519938 1.4986)
			(layers "F.Cu" "F.Mask" "F.Paste")
			(net "M_E_CPU0_SB_CA<6>")
		)
		(pad "83" smd rect
			(at -2.050034 11.474958 270)
			(size 0.519938 1.4986)
			(layers "F.Cu" "F.Mask" "F.Paste")
			(net "GND")
		)
		(pad "84" smd rect
			(at -2.050034 12.325096 270)
			(size 0.519938 1.4986)
			(layers "F.Cu" "F.Mask" "F.Paste")
			(net "M_E_CPU0_SB_CS_N<2>")
		)
		(pad "85" smd rect
			(at -2.050034 13.17498 270)
			(size 0.519938 1.4986)
			(layers "F.Cu" "F.Mask" "F.Paste")
			(net "GND")
		)
		(pad "86" smd rect
			(at -2.050034 14.025118 270)
			(size 0.519938 1.4986)
			(layers "F.Cu" "F.Mask" "F.Paste")
			(net "M_E_CPU0_SA_RSP<1>")
		)
		(pad "87" smd rect
			(at -2.050034 14.875002 270)
			(size 0.519938 1.4986)
			(layers "F.Cu" "F.Mask" "F.Paste")
			(net "M_E_CPU0_SB_RSP<1>")
		)
		(pad "88" smd rect
			(at -2.050034 15.724886 270)
			(size 0.519938 1.4986)
			(layers "F.Cu" "F.Mask" "F.Paste")
			(net "GND")
		)
		(pad "89" smd rect
			(at -2.050034 16.575024 270)
			(size 0.519938 1.4986)
			(layers "F.Cu" "F.Mask" "F.Paste")
			(net "M_E_CPU0_SB_CB<4>")
		)
		(pad "90" smd rect
			(at -2.050034 17.424908 270)
			(size 0.519938 1.4986)
			(layers "F.Cu" "F.Mask" "F.Paste")
			(net "GND")
		)
		(pad "91" smd rect
			(at -2.050034 18.275046 270)
			(size 0.519938 1.4986)
			(layers "F.Cu" "F.Mask" "F.Paste")
			(net "M_E_CPU0_SB_CB<5>")
		)
		(pad "92" smd rect
			(at -2.050034 19.12493 270)
			(size 0.519938 1.4986)
			(layers "F.Cu" "F.Mask" "F.Paste")
			(net "GND")
		)
		(pad "93" smd rect
			(at -2.050034 19.975068 270)
			(size 0.519938 1.4986)
			(layers "F.Cu" "F.Mask" "F.Paste")
			(net "M_E_CPU0_SB_DQS_DP<9>")
		)
		(pad "94" smd rect
			(at -2.050034 20.824952 270)
			(size 0.519938 1.4986)
			(layers "F.Cu" "F.Mask" "F.Paste")
			(net "M_E_CPU0_SB_DQS_DN<9>")
		)
		(pad "95" smd rect
			(at -2.050034 21.67509 270)
			(size 0.519938 1.4986)
			(layers "F.Cu" "F.Mask" "F.Paste")
			(net "GND")
		)
		(pad "96" smd rect
			(at -2.050034 22.524974 270)
			(size 0.519938 1.4986)
			(layers "F.Cu" "F.Mask" "F.Paste")
			(net "M_E_CPU0_SB_CB<0>")
		)
		(pad "97" smd rect
			(at -2.050034 23.375112 270)
			(size 0.519938 1.4986)
			(layers "F.Cu" "F.Mask" "F.Paste")
			(net "GND")
		)
		(pad "98" smd rect
			(at -2.050034 24.224996 270)
			(size 0.519938 1.4986)
			(layers "F.Cu" "F.Mask" "F.Paste")
			(net "M_E_CPU0_SB_CB<1>")
		)
		(pad "99" smd rect
			(at -2.050034 25.07488 270)
			(size 0.519938 1.4986)
			(layers "F.Cu" "F.Mask" "F.Paste")
			(net "GND")
		)
		(pad "100" smd rect
			(at -2.050034 25.925018 270)
			(size 0.519938 1.4986)
			(layers "F.Cu" "F.Mask" "F.Paste")
			(net "M_E_CPU0_SB_DQ<0>")
		)
		(pad "101" smd rect
			(at -2.050034 26.774902 270)
			(size 0.519938 1.4986)
			(layers "F.Cu" "F.Mask" "F.Paste")
			(net "GND")
		)
		(pad "102" smd rect
			(at -2.050034 27.62504 270)
			(size 0.519938 1.4986)
			(layers "F.Cu" "F.Mask" "F.Paste")
			(net "M_E_CPU0_SB_DQ<1>")
		)
		(pad "103" smd rect
			(at -2.050034 28.474924 270)
			(size 0.519938 1.4986)
			(layers "F.Cu" "F.Mask" "F.Paste")
			(net "GND")
		)
		(pad "104" smd rect
			(at -2.050034 29.325062 270)
			(size 0.519938 1.4986)
			(layers "F.Cu" "F.Mask" "F.Paste")
			(net "M_E_CPU0_SB_DQS_DP<0>")
		)
		(pad "105" smd rect
			(at -2.050034 30.174946 270)
			(size 0.519938 1.4986)
			(layers "F.Cu" "F.Mask" "F.Paste")
			(net "M_E_CPU0_SB_DQS_DN<0>")
		)
		(pad "106" smd rect
			(at -2.050034 31.025084 270)
			(size 0.519938 1.4986)
			(layers "F.Cu" "F.Mask" "F.Paste")
			(net "GND")
		)
		(pad "107" smd rect
			(at -2.050034 31.874968 270)
			(size 0.519938 1.4986)
			(layers "F.Cu" "F.Mask" "F.Paste")
			(net "M_E_CPU0_SB_DQ<4>")
		)
		(pad "108" smd rect
			(at -2.050034 32.725106 270)
			(size 0.519938 1.4986)
			(layers "F.Cu" "F.Mask" "F.Paste")
			(net "GND")
		)
		(pad "109" smd rect
			(at -2.050034 33.57499 270)
			(size 0.519938 1.4986)
			(layers "F.Cu" "F.Mask" "F.Paste")
			(net "M_E_CPU0_SB_DQ<5>")
		)
		(pad "110" smd rect
			(at -2.050034 34.425128 270)
			(size 0.519938 1.4986)
			(layers "F.Cu" "F.Mask" "F.Paste")
			(net "GND")
		)
		(pad "111" smd rect
			(at -2.050034 35.275012 270)
			(size 0.519938 1.4986)
			(layers "F.Cu" "F.Mask" "F.Paste")
			(net "M_E_CPU0_SB_DQ<8>")
		)
		(pad "112" smd rect
			(at -2.050034 36.124896 270)
			(size 0.519938 1.4986)
			(layers "F.Cu" "F.Mask" "F.Paste")
			(net "GND")
		)
		(pad "113" smd rect
			(at -2.050034 36.975034 270)
			(size 0.519938 1.4986)
			(layers "F.Cu" "F.Mask" "F.Paste")
			(net "M_E_CPU0_SB_DQ<9>")
		)
		(pad "114" smd rect
			(at -2.050034 37.824918 270)
			(size 0.519938 1.4986)
			(layers "F.Cu" "F.Mask" "F.Paste")
			(net "GND")
		)
		(pad "115" smd rect
			(at -2.050034 38.675056 270)
			(size 0.519938 1.4986)
			(layers "F.Cu" "F.Mask" "F.Paste")
			(net "M_E_CPU0_SB_DQS_DP<1>")
		)
		(pad "116" smd rect
			(at -2.050034 39.52494 270)
			(size 0.519938 1.4986)
			(layers "F.Cu" "F.Mask" "F.Paste")
			(net "M_E_CPU0_SB_DQS_DN<1>")
		)
		(pad "117" smd rect
			(at -2.050034 40.375078 270)
			(size 0.519938 1.4986)
			(layers "F.Cu" "F.Mask" "F.Paste")
			(net "GND")
		)
		(pad "118" smd rect
			(at -2.050034 41.224962 270)
			(size 0.519938 1.4986)
			(layers "F.Cu" "F.Mask" "F.Paste")
			(net "M_E_CPU0_SB_DQ<12>")
		)
		(pad "119" smd rect
			(at -2.050034 42.0751 270)
			(size 0.519938 1.4986)
			(layers "F.Cu" "F.Mask" "F.Paste")
			(net "GND")
		)
		(pad "120" smd rect
			(at -2.050034 42.924984 270)
			(size 0.519938 1.4986)
			(layers "F.Cu" "F.Mask" "F.Paste")
			(net "M_E_CPU0_SB_DQ<13>")
		)
		(pad "121" smd rect
			(at -2.050034 43.775122 270)
			(size 0.519938 1.4986)
			(layers "F.Cu" "F.Mask" "F.Paste")
			(net "GND")
		)
		(pad "122" smd rect
			(at -2.050034 44.625006 270)
			(size 0.519938 1.4986)
			(layers "F.Cu" "F.Mask" "F.Paste")
			(net "M_E_CPU0_SB_DQ<16>")
		)
		(pad "123" smd rect
			(at -2.050034 45.47489 270)
			(size 0.519938 1.4986)
			(layers "F.Cu" "F.Mask" "F.Paste")
			(net "GND")
		)
		(pad "124" smd rect
			(at -2.050034 46.325028 270)
			(size 0.519938 1.4986)
			(layers "F.Cu" "F.Mask" "F.Paste")
			(net "M_E_CPU0_SB_DQ<17>")
		)
		(pad "125" smd rect
			(at -2.050034 47.174912 270)
			(size 0.519938 1.4986)
			(layers "F.Cu" "F.Mask" "F.Paste")
			(net "GND")
		)
		(pad "126" smd rect
			(at -2.050034 48.02505 270)
			(size 0.519938 1.4986)
			(layers "F.Cu" "F.Mask" "F.Paste")
			(net "M_E_CPU0_SB_DQS_DP<2>")
		)
		(pad "127" smd rect
			(at -2.050034 48.874934 270)
			(size 0.519938 1.4986)
			(layers "F.Cu" "F.Mask" "F.Paste")
			(net "M_E_CPU0_SB_DQS_DN<2>")
		)
		(pad "128" smd rect
			(at -2.050034 49.725072 270)
			(size 0.519938 1.4986)
			(layers "F.Cu" "F.Mask" "F.Paste")
			(net "GND")
		)
		(pad "129" smd rect
			(at -2.050034 50.574956 270)
			(size 0.519938 1.4986)
			(layers "F.Cu" "F.Mask" "F.Paste")
			(net "M_E_CPU0_SB_DQ<20>")
		)
		(pad "130" smd rect
			(at -2.050034 51.425094 270)
			(size 0.519938 1.4986)
			(layers "F.Cu" "F.Mask" "F.Paste")
			(net "GND")
		)
		(pad "131" smd rect
			(at -2.050034 52.274978 270)
			(size 0.519938 1.4986)
			(layers "F.Cu" "F.Mask" "F.Paste")
			(net "M_E_CPU0_SB_DQ<21>")
		)
		(pad "132" smd rect
			(at -2.050034 53.125116 270)
			(size 0.519938 1.4986)
			(layers "F.Cu" "F.Mask" "F.Paste")
			(net "GND")
		)
		(pad "133" smd rect
			(at -2.050034 53.975 270)
			(size 0.519938 1.4986)
			(layers "F.Cu" "F.Mask" "F.Paste")
			(net "M_E_CPU0_SB_DQ<24>")
		)
		(pad "134" smd rect
			(at -2.050034 54.824884 270)
			(size 0.519938 1.4986)
			(layers "F.Cu" "F.Mask" "F.Paste")
			(net "GND")
		)
		(pad "135" smd rect
			(at -2.050034 55.675022 270)
			(size 0.519938 1.4986)
			(layers "F.Cu" "F.Mask" "F.Paste")
			(net "M_E_CPU0_SB_DQ<25>")
		)
		(pad "136" smd rect
			(at -2.050034 56.524906 270)
			(size 0.519938 1.4986)
			(layers "F.Cu" "F.Mask" "F.Paste")
			(net "GND")
		)
		(pad "137" smd rect
			(at -2.050034 57.375044 270)
			(size 0.519938 1.4986)
			(layers "F.Cu" "F.Mask" "F.Paste")
			(net "M_E_CPU0_SB_DQS_DP<3>")
		)
		(pad "138" smd rect
			(at -2.050034 58.224928 270)
			(size 0.519938 1.4986)
			(layers "F.Cu" "F.Mask" "F.Paste")
			(net "M_E_CPU0_SB_DQS_DN<3>")
		)
		(pad "139" smd rect
			(at -2.050034 59.075066 270)
			(size 0.519938 1.4986)
			(layers "F.Cu" "F.Mask" "F.Paste")
			(net "GND")
		)
		(pad "140" smd rect
			(at -2.050034 59.92495 270)
			(size 0.519938 1.4986)
			(layers "F.Cu" "F.Mask" "F.Paste")
			(net "M_E_CPU0_SB_DQ<28>")
		)
		(pad "141" smd rect
			(at -2.050034 60.775088 270)
			(size 0.519938 1.4986)
			(layers "F.Cu" "F.Mask" "F.Paste")
			(net "GND")
		)
		(pad "142" smd rect
			(at -2.050034 61.624972 270)
			(size 0.519938 1.4986)
			(layers "F.Cu" "F.Mask" "F.Paste")
			(net "M_E_CPU0_SB_DQ<29>")
		)
		(pad "143" smd rect
			(at -2.050034 62.47511 270)
			(size 0.519938 1.4986)
			(layers "F.Cu" "F.Mask" "F.Paste")
			(net "GND")
		)
		(pad "144" smd rect
			(at -2.050034 63.324994 270)
			(size 0.519938 1.4986)
			(layers "F.Cu" "F.Mask" "F.Paste")
			(net "TP_CHE_CPU0_DIMM2_FRU_1")
		)
		(pad "145" smd rect
			(at 2.050034 -63.324994 270)
			(size 0.519938 1.4986)
			(layers "F.Cu" "F.Mask" "F.Paste")
			(net "P12V_S3_AUX_CPU0_NVDIMM")
		)
		(pad "146" smd rect
			(at 2.050034 -62.47511 270)
			(size 0.519938 1.4986)
			(layers "F.Cu" "F.Mask" "F.Paste")
			(net "P12V_S3_AUX_CPU0_NVDIMM")
		)
		(pad "147" smd rect
			(at 2.050034 -61.624972 270)
			(size 0.519938 1.4986)
			(layers "F.Cu" "F.Mask" "F.Paste")
			(net "PWRGD_CHE_CPU0_DIMM2")
		)
		(pad "148" smd rect
			(at 2.050034 -60.775088 270)
			(size 0.519938 1.4986)
			(layers "F.Cu" "F.Mask" "F.Paste")
			(net "PD_CHE_CPU0_DIMM2_SAA")
		)
		(pad "149" smd rect
			(at 2.050034 -59.92495 270)
			(size 0.519938 1.4986)
			(layers "F.Cu" "F.Mask" "F.Paste")
			(net "TP_CHE_CPU0_DIMM2_FRU_2")
		)
		(pad "150" smd rect
			(at 2.050034 -59.075066 270)
			(size 0.519938 1.4986)
			(layers "F.Cu" "F.Mask" "F.Paste")
			(net "TP_CHE_CPU0_DIMM2_FRU_3")
		)
		(pad "151" smd rect
			(at 2.050034 -58.224928 270)
			(size 0.519938 1.4986)
			(layers "F.Cu" "F.Mask" "F.Paste")
			(net "GND")
		)
		(pad "152" smd rect
			(at 2.050034 -57.375044 270)
			(size 0.519938 1.4986)
			(layers "F.Cu" "F.Mask" "F.Paste")
			(net "M_E_CPU0_SA_DQ<2>")
		)
		(pad "153" smd rect
			(at 2.050034 -56.524906 270)
			(size 0.519938 1.4986)
			(layers "F.Cu" "F.Mask" "F.Paste")
			(net "GND")
		)
		(pad "154" smd rect
			(at 2.050034 -55.675022 270)
			(size 0.519938 1.4986)
			(layers "F.Cu" "F.Mask" "F.Paste")
			(net "M_E_CPU0_SA_DQ<3>")
		)
		(pad "155" smd rect
			(at 2.050034 -54.824884 270)
			(size 0.519938 1.4986)
			(layers "F.Cu" "F.Mask" "F.Paste")
			(net "GND")
		)
		(pad "156" smd rect
			(at 2.050034 -53.975 270)
			(size 0.519938 1.4986)
			(layers "F.Cu" "F.Mask" "F.Paste")
			(net "M_E_CPU0_SA_DQS_DN<5>")
		)
		(pad "157" smd rect
			(at 2.050034 -53.125116 270)
			(size 0.519938 1.4986)
			(layers "F.Cu" "F.Mask" "F.Paste")
			(net "M_E_CPU0_SA_DQS_DP<5>")
		)
		(pad "158" smd rect
			(at 2.050034 -52.274978 270)
			(size 0.519938 1.4986)
			(layers "F.Cu" "F.Mask" "F.Paste")
			(net "GND")
		)
		(pad "159" smd rect
			(at 2.050034 -51.425094 270)
			(size 0.519938 1.4986)
			(layers "F.Cu" "F.Mask" "F.Paste")
			(net "M_E_CPU0_SA_DQ<6>")
		)
		(pad "160" smd rect
			(at 2.050034 -50.574956 270)
			(size 0.519938 1.4986)
			(layers "F.Cu" "F.Mask" "F.Paste")
			(net "GND")
		)
		(pad "161" smd rect
			(at 2.050034 -49.725072 270)
			(size 0.519938 1.4986)
			(layers "F.Cu" "F.Mask" "F.Paste")
			(net "M_E_CPU0_SA_DQ<7>")
		)
		(pad "162" smd rect
			(at 2.050034 -48.874934 270)
			(size 0.519938 1.4986)
			(layers "F.Cu" "F.Mask" "F.Paste")
			(net "GND")
		)
		(pad "163" smd rect
			(at 2.050034 -48.02505 270)
			(size 0.519938 1.4986)
			(layers "F.Cu" "F.Mask" "F.Paste")
			(net "M_E_CPU0_SA_DQ<10>")
		)
		(pad "164" smd rect
			(at 2.050034 -47.174912 270)
			(size 0.519938 1.4986)
			(layers "F.Cu" "F.Mask" "F.Paste")
			(net "GND")
		)
		(pad "165" smd rect
			(at 2.050034 -46.325028 270)
			(size 0.519938 1.4986)
			(layers "F.Cu" "F.Mask" "F.Paste")
			(net "M_E_CPU0_SA_DQ<11>")
		)
		(pad "166" smd rect
			(at 2.050034 -45.47489 270)
			(size 0.519938 1.4986)
			(layers "F.Cu" "F.Mask" "F.Paste")
			(net "GND")
		)
		(pad "167" smd rect
			(at 2.050034 -44.625006 270)
			(size 0.519938 1.4986)
			(layers "F.Cu" "F.Mask" "F.Paste")
			(net "M_E_CPU0_SA_DQS_DN<6>")
		)
		(pad "168" smd rect
			(at 2.050034 -43.775122 270)
			(size 0.519938 1.4986)
			(layers "F.Cu" "F.Mask" "F.Paste")
			(net "M_E_CPU0_SA_DQS_DP<6>")
		)
		(pad "169" smd rect
			(at 2.050034 -42.924984 270)
			(size 0.519938 1.4986)
			(layers "F.Cu" "F.Mask" "F.Paste")
			(net "GND")
		)
		(pad "170" smd rect
			(at 2.050034 -42.0751 270)
			(size 0.519938 1.4986)
			(layers "F.Cu" "F.Mask" "F.Paste")
			(net "M_E_CPU0_SA_DQ<14>")
		)
		(pad "171" smd rect
			(at 2.050034 -41.224962 270)
			(size 0.519938 1.4986)
			(layers "F.Cu" "F.Mask" "F.Paste")
			(net "GND")
		)
		(pad "172" smd rect
			(at 2.050034 -40.375078 270)
			(size 0.519938 1.4986)
			(layers "F.Cu" "F.Mask" "F.Paste")
			(net "M_E_CPU0_SA_DQ<15>")
		)
		(pad "173" smd rect
			(at 2.050034 -39.52494 270)
			(size 0.519938 1.4986)
			(layers "F.Cu" "F.Mask" "F.Paste")
			(net "GND")
		)
		(pad "174" smd rect
			(at 2.050034 -38.675056 270)
			(size 0.519938 1.4986)
			(layers "F.Cu" "F.Mask" "F.Paste")
			(net "M_E_CPU0_SA_DQ<18>")
		)
		(pad "175" smd rect
			(at 2.050034 -37.824918 270)
			(size 0.519938 1.4986)
			(layers "F.Cu" "F.Mask" "F.Paste")
			(net "GND")
		)
		(pad "176" smd rect
			(at 2.050034 -36.975034 270)
			(size 0.519938 1.4986)
			(layers "F.Cu" "F.Mask" "F.Paste")
			(net "M_E_CPU0_SA_DQ<19>")
		)
		(pad "177" smd rect
			(at 2.050034 -36.124896 270)
			(size 0.519938 1.4986)
			(layers "F.Cu" "F.Mask" "F.Paste")
			(net "GND")
		)
		(pad "178" smd rect
			(at 2.050034 -35.275012 270)
			(size 0.519938 1.4986)
			(layers "F.Cu" "F.Mask" "F.Paste")
			(net "M_E_CPU0_SA_DQS_DN<7>")
		)
		(pad "179" smd rect
			(at 2.050034 -34.425128 270)
			(size 0.519938 1.4986)
			(layers "F.Cu" "F.Mask" "F.Paste")
			(net "M_E_CPU0_SA_DQS_DP<7>")
		)
		(pad "180" smd rect
			(at 2.050034 -33.57499 270)
			(size 0.519938 1.4986)
			(layers "F.Cu" "F.Mask" "F.Paste")
			(net "GND")
		)
		(pad "181" smd rect
			(at 2.050034 -32.725106 270)
			(size 0.519938 1.4986)
			(layers "F.Cu" "F.Mask" "F.Paste")
			(net "M_E_CPU0_SA_DQ<22>")
		)
		(pad "182" smd rect
			(at 2.050034 -31.874968 270)
			(size 0.519938 1.4986)
			(layers "F.Cu" "F.Mask" "F.Paste")
			(net "GND")
		)
		(pad "183" smd rect
			(at 2.050034 -31.025084 270)
			(size 0.519938 1.4986)
			(layers "F.Cu" "F.Mask" "F.Paste")
			(net "M_E_CPU0_SA_DQ<23>")
		)
		(pad "184" smd rect
			(at 2.050034 -30.174946 270)
			(size 0.519938 1.4986)
			(layers "F.Cu" "F.Mask" "F.Paste")
			(net "GND")
		)
		(pad "185" smd rect
			(at 2.050034 -29.325062 270)
			(size 0.519938 1.4986)
			(layers "F.Cu" "F.Mask" "F.Paste")
			(net "M_E_CPU0_SA_DQ<26>")
		)
		(pad "186" smd rect
			(at 2.050034 -28.474924 270)
			(size 0.519938 1.4986)
			(layers "F.Cu" "F.Mask" "F.Paste")
			(net "GND")
		)
		(pad "187" smd rect
			(at 2.050034 -27.62504 270)
			(size 0.519938 1.4986)
			(layers "F.Cu" "F.Mask" "F.Paste")
			(net "M_E_CPU0_SA_DQ<27>")
		)
		(pad "188" smd rect
			(at 2.050034 -26.774902 270)
			(size 0.519938 1.4986)
			(layers "F.Cu" "F.Mask" "F.Paste")
			(net "GND")
		)
		(pad "189" smd rect
			(at 2.050034 -25.925018 270)
			(size 0.519938 1.4986)
			(layers "F.Cu" "F.Mask" "F.Paste")
			(net "M_E_CPU0_SA_DQS_DN<8>")
		)
		(pad "190" smd rect
			(at 2.050034 -25.07488 270)
			(size 0.519938 1.4986)
			(layers "F.Cu" "F.Mask" "F.Paste")
			(net "M_E_CPU0_SA_DQS_DP<8>")
		)
		(pad "191" smd rect
			(at 2.050034 -24.224996 270)
			(size 0.519938 1.4986)
			(layers "F.Cu" "F.Mask" "F.Paste")
			(net "GND")
		)
		(pad "192" smd rect
			(at 2.050034 -23.375112 270)
			(size 0.519938 1.4986)
			(layers "F.Cu" "F.Mask" "F.Paste")
			(net "M_E_CPU0_SA_DQ<30>")
		)
		(pad "193" smd rect
			(at 2.050034 -22.524974 270)
			(size 0.519938 1.4986)
			(layers "F.Cu" "F.Mask" "F.Paste")
			(net "GND")
		)
		(pad "194" smd rect
			(at 2.050034 -21.67509 270)
			(size 0.519938 1.4986)
			(layers "F.Cu" "F.Mask" "F.Paste")
			(net "M_E_CPU0_SA_DQ<31>")
		)
		(pad "195" smd rect
			(at 2.050034 -20.824952 270)
			(size 0.519938 1.4986)
			(layers "F.Cu" "F.Mask" "F.Paste")
			(net "GND")
		)
		(pad "196" smd rect
			(at 2.050034 -19.975068 270)
			(size 0.519938 1.4986)
			(layers "F.Cu" "F.Mask" "F.Paste")
			(net "M_E_CPU0_SA_CB<2>")
		)
		(pad "197" smd rect
			(at 2.050034 -19.12493 270)
			(size 0.519938 1.4986)
			(layers "F.Cu" "F.Mask" "F.Paste")
			(net "GND")
		)
		(pad "198" smd rect
			(at 2.050034 -18.275046 270)
			(size 0.519938 1.4986)
			(layers "F.Cu" "F.Mask" "F.Paste")
			(net "M_E_CPU0_SA_CB<3>")
		)
		(pad "199" smd rect
			(at 2.050034 -17.424908 270)
			(size 0.519938 1.4986)
			(layers "F.Cu" "F.Mask" "F.Paste")
			(net "GND")
		)
		(pad "200" smd rect
			(at 2.050034 -16.575024 270)
			(size 0.519938 1.4986)
			(layers "F.Cu" "F.Mask" "F.Paste")
			(net "M_E_CPU0_SA_DQS_DN<9>")
		)
		(pad "201" smd rect
			(at 2.050034 -15.724886 270)
			(size 0.519938 1.4986)
			(layers "F.Cu" "F.Mask" "F.Paste")
			(net "M_E_CPU0_SA_DQS_DP<9>")
		)
		(pad "202" smd rect
			(at 2.050034 -14.875002 270)
			(size 0.519938 1.4986)
			(layers "F.Cu" "F.Mask" "F.Paste")
			(net "GND")
		)
		(pad "203" smd rect
			(at 2.050034 -14.025118 270)
			(size 0.519938 1.4986)
			(layers "F.Cu" "F.Mask" "F.Paste")
			(net "M_E_CPU0_SA_CB<6>")
		)
		(pad "204" smd rect
			(at 2.050034 -13.17498 270)
			(size 0.519938 1.4986)
			(layers "F.Cu" "F.Mask" "F.Paste")
			(net "GND")
		)
		(pad "205" smd rect
			(at 2.050034 -12.325096 270)
			(size 0.519938 1.4986)
			(layers "F.Cu" "F.Mask" "F.Paste")
			(net "M_E_CPU0_SA_CB<7>")
		)
		(pad "206" smd rect
			(at 2.050034 -11.474958 270)
			(size 0.519938 1.4986)
			(layers "F.Cu" "F.Mask" "F.Paste")
			(net "GND")
		)
		(pad "207" smd rect
			(at 2.050034 -10.625074 270)
			(size 0.519938 1.4986)
			(layers "F.Cu" "F.Mask" "F.Paste")
			(net "RST_M_EF_CPU0_FPGA_N")
		)
		(pad "208" smd rect
			(at 2.050034 -9.774936 270)
			(size 0.519938 1.4986)
			(layers "F.Cu" "F.Mask" "F.Paste")
			(net "GND")
		)
		(pad "209" smd rect
			(at 2.050034 -8.925052 270)
			(size 0.519938 1.4986)
			(layers "F.Cu" "F.Mask" "F.Paste")
			(net "M_E_CPU0_SA_CS_N<3>")
		)
		(pad "210" smd rect
			(at 2.050034 -8.074914 270)
			(size 0.519938 1.4986)
			(layers "F.Cu" "F.Mask" "F.Paste")
			(net "GND")
		)
		(pad "211" smd rect
			(at 2.050034 -7.22503 270)
			(size 0.519938 1.4986)
			(layers "F.Cu" "F.Mask" "F.Paste")
			(net "M_E_CPU0_SA_CA<1>")
		)
		(pad "212" smd rect
			(at 2.050034 -6.374892 270)
			(size 0.519938 1.4986)
			(layers "F.Cu" "F.Mask" "F.Paste")
			(net "GND")
		)
		(pad "213" smd rect
			(at 2.050034 -5.525008 270)
			(size 0.519938 1.4986)
			(layers "F.Cu" "F.Mask" "F.Paste")
			(net "M_E_CPU0_SA_CA<3>")
		)
		(pad "214" smd rect
			(at 2.050034 -4.675124 270)
			(size 0.519938 1.4986)
			(layers "F.Cu" "F.Mask" "F.Paste")
			(net "GND")
		)
		(pad "215" smd rect
			(at 2.050034 -3.824986 270)
			(size 0.519938 1.4986)
			(layers "F.Cu" "F.Mask" "F.Paste")
			(net "M_E_CPU0_SA_CA<5>")
		)
		(pad "216" smd rect
			(at 2.050034 -2.975102 270)
			(size 0.519938 1.4986)
			(layers "F.Cu" "F.Mask" "F.Paste")
			(net "GND")
		)
		(pad "217" smd rect
			(at 2.050034 -2.124964 270)
			(size 0.519938 1.4986)
			(layers "F.Cu" "F.Mask" "F.Paste")
			(net "M_E_CPU0_CLK_DP<1>")
		)
		(pad "218" smd rect
			(at 2.050034 -1.27508 270)
			(size 0.519938 1.4986)
			(layers "F.Cu" "F.Mask" "F.Paste")
			(net "M_E_CPU0_CLK_DN<1>")
		)
		(pad "219" smd rect
			(at 2.050034 -0.424942 270)
			(size 0.519938 1.4986)
			(layers "F.Cu" "F.Mask" "F.Paste")
			(net "GND")
		)
		(pad "220" smd rect
			(at 2.050034 5.525008 270)
			(size 0.519938 1.4986)
			(layers "F.Cu" "F.Mask" "F.Paste")
			(net "TP_CHE_CPU0_DIMM2_FRU_4")
		)
		(pad "221" smd rect
			(at 2.050034 6.374892 270)
			(size 0.519938 1.4986)
			(layers "F.Cu" "F.Mask" "F.Paste")
			(net "M_E_CPU0_SB_CA<1>")
		)
		(pad "222" smd rect
			(at 2.050034 7.22503 270)
			(size 0.519938 1.4986)
			(layers "F.Cu" "F.Mask" "F.Paste")
			(net "GND")
		)
		(pad "223" smd rect
			(at 2.050034 8.074914 270)
			(size 0.519938 1.4986)
			(layers "F.Cu" "F.Mask" "F.Paste")
			(net "M_E_CPU0_SB_CA<3>")
		)
		(pad "224" smd rect
			(at 2.050034 8.925052 270)
			(size 0.519938 1.4986)
			(layers "F.Cu" "F.Mask" "F.Paste")
			(net "GND")
		)
		(pad "225" smd rect
			(at 2.050034 9.774936 270)
			(size 0.519938 1.4986)
			(layers "F.Cu" "F.Mask" "F.Paste")
			(net "M_E_CPU0_SB_CA<5>")
		)
		(pad "226" smd rect
			(at 2.050034 10.625074 270)
			(size 0.519938 1.4986)
			(layers "F.Cu" "F.Mask" "F.Paste")
			(net "GND")
		)
		(pad "227" smd rect
			(at 2.050034 11.474958 270)
			(size 0.519938 1.4986)
			(layers "F.Cu" "F.Mask" "F.Paste")
			(net "M_E_CPU0_SB_PAR")
		)
		(pad "228" smd rect
			(at 2.050034 12.325096 270)
			(size 0.519938 1.4986)
			(layers "F.Cu" "F.Mask" "F.Paste")
			(net "GND")
		)
		(pad "229" smd rect
			(at 2.050034 13.17498 270)
			(size 0.519938 1.4986)
			(layers "F.Cu" "F.Mask" "F.Paste")
			(net "M_E_CPU0_SB_CS_N<3>")
		)
		(pad "230" smd rect
			(at 2.050034 14.025118 270)
			(size 0.519938 1.4986)
			(layers "F.Cu" "F.Mask" "F.Paste")
			(net "GND")
		)
		(pad "231" smd rect
			(at 2.050034 14.875002 270)
			(size 0.519938 1.4986)
			(layers "F.Cu" "F.Mask" "F.Paste")
			(net "TP_CHE_CPU0_DIMM2_FRU_5")
		)
		(pad "232" smd rect
			(at 2.050034 15.724886 270)
			(size 0.519938 1.4986)
			(layers "F.Cu" "F.Mask" "F.Paste")
			(net "TP_CHE_CPU0_DIMM2_FRU_6")
		)
		(pad "233" smd rect
			(at 2.050034 16.575024 270)
			(size 0.519938 1.4986)
			(layers "F.Cu" "F.Mask" "F.Paste")
			(net "GND")
		)
		(pad "234" smd rect
			(at 2.050034 17.424908 270)
			(size 0.519938 1.4986)
			(layers "F.Cu" "F.Mask" "F.Paste")
			(net "M_E_CPU0_SB_CB<6>")
		)
		(pad "235" smd rect
			(at 2.050034 18.275046 270)
			(size 0.519938 1.4986)
			(layers "F.Cu" "F.Mask" "F.Paste")
			(net "GND")
		)
		(pad "236" smd rect
			(at 2.050034 19.12493 270)
			(size 0.519938 1.4986)
			(layers "F.Cu" "F.Mask" "F.Paste")
			(net "M_E_CPU0_SB_CB<7>")
		)
		(pad "237" smd rect
			(at 2.050034 19.975068 270)
			(size 0.519938 1.4986)
			(layers "F.Cu" "F.Mask" "F.Paste")
			(net "GND")
		)
		(pad "238" smd rect
			(at 2.050034 20.824952 270)
			(size 0.519938 1.4986)
			(layers "F.Cu" "F.Mask" "F.Paste")
			(net "M_E_CPU0_SB_DQS_DN<4>")
		)
		(pad "239" smd rect
			(at 2.050034 21.67509 270)
			(size 0.519938 1.4986)
			(layers "F.Cu" "F.Mask" "F.Paste")
			(net "M_E_CPU0_SB_DQS_DP<4>")
		)
		(pad "240" smd rect
			(at 2.050034 22.524974 270)
			(size 0.519938 1.4986)
			(layers "F.Cu" "F.Mask" "F.Paste")
			(net "GND")
		)
		(pad "241" smd rect
			(at 2.050034 23.375112 270)
			(size 0.519938 1.4986)
			(layers "F.Cu" "F.Mask" "F.Paste")
			(net "M_E_CPU0_SB_CB<2>")
		)
		(pad "242" smd rect
			(at 2.050034 24.224996 270)
			(size 0.519938 1.4986)
			(layers "F.Cu" "F.Mask" "F.Paste")
			(net "GND")
		)
		(pad "243" smd rect
			(at 2.050034 25.07488 270)
			(size 0.519938 1.4986)
			(layers "F.Cu" "F.Mask" "F.Paste")
			(net "M_E_CPU0_SB_CB<3>")
		)
		(pad "244" smd rect
			(at 2.050034 25.925018 270)
			(size 0.519938 1.4986)
			(layers "F.Cu" "F.Mask" "F.Paste")
			(net "GND")
		)
		(pad "245" smd rect
			(at 2.050034 26.774902 270)
			(size 0.519938 1.4986)
			(layers "F.Cu" "F.Mask" "F.Paste")
			(net "M_E_CPU0_SB_DQ<2>")
		)
		(pad "246" smd rect
			(at 2.050034 27.62504 270)
			(size 0.519938 1.4986)
			(layers "F.Cu" "F.Mask" "F.Paste")
			(net "GND")
		)
		(pad "247" smd rect
			(at 2.050034 28.474924 270)
			(size 0.519938 1.4986)
			(layers "F.Cu" "F.Mask" "F.Paste")
			(net "M_E_CPU0_SB_DQ<3>")
		)
		(pad "248" smd rect
			(at 2.050034 29.325062 270)
			(size 0.519938 1.4986)
			(layers "F.Cu" "F.Mask" "F.Paste")
			(net "GND")
		)
		(pad "249" smd rect
			(at 2.050034 30.174946 270)
			(size 0.519938 1.4986)
			(layers "F.Cu" "F.Mask" "F.Paste")
			(net "M_E_CPU0_SB_DQS_DN<5>")
		)
		(pad "250" smd rect
			(at 2.050034 31.025084 270)
			(size 0.519938 1.4986)
			(layers "F.Cu" "F.Mask" "F.Paste")
			(net "M_E_CPU0_SB_DQS_DP<5>")
		)
		(pad "251" smd rect
			(at 2.050034 31.874968 270)
			(size 0.519938 1.4986)
			(layers "F.Cu" "F.Mask" "F.Paste")
			(net "GND")
		)
		(pad "252" smd rect
			(at 2.050034 32.725106 270)
			(size 0.519938 1.4986)
			(layers "F.Cu" "F.Mask" "F.Paste")
			(net "M_E_CPU0_SB_DQ<6>")
		)
		(pad "253" smd rect
			(at 2.050034 33.57499 270)
			(size 0.519938 1.4986)
			(layers "F.Cu" "F.Mask" "F.Paste")
			(net "GND")
		)
		(pad "254" smd rect
			(at 2.050034 34.425128 270)
			(size 0.519938 1.4986)
			(layers "F.Cu" "F.Mask" "F.Paste")
			(net "M_E_CPU0_SB_DQ<7>")
		)
		(pad "255" smd rect
			(at 2.050034 35.275012 270)
			(size 0.519938 1.4986)
			(layers "F.Cu" "F.Mask" "F.Paste")
			(net "GND")
		)
		(pad "256" smd rect
			(at 2.050034 36.124896 270)
			(size 0.519938 1.4986)
			(layers "F.Cu" "F.Mask" "F.Paste")
			(net "M_E_CPU0_SB_DQ<10>")
		)
		(pad "257" smd rect
			(at 2.050034 36.975034 270)
			(size 0.519938 1.4986)
			(layers "F.Cu" "F.Mask" "F.Paste")
			(net "GND")
		)
		(pad "258" smd rect
			(at 2.050034 37.824918 270)
			(size 0.519938 1.4986)
			(layers "F.Cu" "F.Mask" "F.Paste")
			(net "M_E_CPU0_SB_DQ<11>")
		)
		(pad "259" smd rect
			(at 2.050034 38.675056 270)
			(size 0.519938 1.4986)
			(layers "F.Cu" "F.Mask" "F.Paste")
			(net "GND")
		)
		(pad "260" smd rect
			(at 2.050034 39.52494 270)
			(size 0.519938 1.4986)
			(layers "F.Cu" "F.Mask" "F.Paste")
			(net "M_E_CPU0_SB_DQS_DN<6>")
		)
		(pad "261" smd rect
			(at 2.050034 40.375078 270)
			(size 0.519938 1.4986)
			(layers "F.Cu" "F.Mask" "F.Paste")
			(net "M_E_CPU0_SB_DQS_DP<6>")
		)
		(pad "262" smd rect
			(at 2.050034 41.224962 270)
			(size 0.519938 1.4986)
			(layers "F.Cu" "F.Mask" "F.Paste")
			(net "GND")
		)
		(pad "263" smd rect
			(at 2.050034 42.0751 270)
			(size 0.519938 1.4986)
			(layers "F.Cu" "F.Mask" "F.Paste")
			(net "M_E_CPU0_SB_DQ<14>")
		)
		(pad "264" smd rect
			(at 2.050034 42.924984 270)
			(size 0.519938 1.4986)
			(layers "F.Cu" "F.Mask" "F.Paste")
			(net "GND")
		)
		(pad "265" smd rect
			(at 2.050034 43.775122 270)
			(size 0.519938 1.4986)
			(layers "F.Cu" "F.Mask" "F.Paste")
			(net "M_E_CPU0_SB_DQ<15>")
		)
		(pad "266" smd rect
			(at 2.050034 44.625006 270)
			(size 0.519938 1.4986)
			(layers "F.Cu" "F.Mask" "F.Paste")
			(net "GND")
		)
		(pad "267" smd rect
			(at 2.050034 45.47489 270)
			(size 0.519938 1.4986)
			(layers "F.Cu" "F.Mask" "F.Paste")
			(net "M_E_CPU0_SB_DQ<18>")
		)
		(pad "268" smd rect
			(at 2.050034 46.325028 270)
			(size 0.519938 1.4986)
			(layers "F.Cu" "F.Mask" "F.Paste")
			(net "GND")
		)
		(pad "269" smd rect
			(at 2.050034 47.174912 270)
			(size 0.519938 1.4986)
			(layers "F.Cu" "F.Mask" "F.Paste")
			(net "M_E_CPU0_SB_DQ<19>")
		)
		(pad "270" smd rect
			(at 2.050034 48.02505 270)
			(size 0.519938 1.4986)
			(layers "F.Cu" "F.Mask" "F.Paste")
			(net "GND")
		)
		(pad "271" smd rect
			(at 2.050034 48.874934 270)
			(size 0.519938 1.4986)
			(layers "F.Cu" "F.Mask" "F.Paste")
			(net "M_E_CPU0_SB_DQS_DN<7>")
		)
		(pad "272" smd rect
			(at 2.050034 49.725072 270)
			(size 0.519938 1.4986)
			(layers "F.Cu" "F.Mask" "F.Paste")
			(net "M_E_CPU0_SB_DQS_DP<7>")
		)
		(pad "273" smd rect
			(at 2.050034 50.574956 270)
			(size 0.519938 1.4986)
			(layers "F.Cu" "F.Mask" "F.Paste")
			(net "GND")
		)
		(pad "274" smd rect
			(at 2.050034 51.425094 270)
			(size 0.519938 1.4986)
			(layers "F.Cu" "F.Mask" "F.Paste")
			(net "M_E_CPU0_SB_DQ<22>")
		)
		(pad "275" smd rect
			(at 2.050034 52.274978 270)
			(size 0.519938 1.4986)
			(layers "F.Cu" "F.Mask" "F.Paste")
			(net "GND")
		)
		(pad "276" smd rect
			(at 2.050034 53.125116 270)
			(size 0.519938 1.4986)
			(layers "F.Cu" "F.Mask" "F.Paste")
			(net "M_E_CPU0_SB_DQ<23>")
		)
		(pad "277" smd rect
			(at 2.050034 53.975 270)
			(size 0.519938 1.4986)
			(layers "F.Cu" "F.Mask" "F.Paste")
			(net "GND")
		)
		(pad "278" smd rect
			(at 2.050034 54.824884 270)
			(size 0.519938 1.4986)
			(layers "F.Cu" "F.Mask" "F.Paste")
			(net "M_E_CPU0_SB_DQ<26>")
		)
		(pad "279" smd rect
			(at 2.050034 55.675022 270)
			(size 0.519938 1.4986)
			(layers "F.Cu" "F.Mask" "F.Paste")
			(net "GND")
		)
		(pad "280" smd rect
			(at 2.050034 56.524906 270)
			(size 0.519938 1.4986)
			(layers "F.Cu" "F.Mask" "F.Paste")
			(net "M_E_CPU0_SB_DQ<27>")
		)
		(pad "281" smd rect
			(at 2.050034 57.375044 270)
			(size 0.519938 1.4986)
			(layers "F.Cu" "F.Mask" "F.Paste")
			(net "GND")
		)
		(pad "282" smd rect
			(at 2.050034 58.224928 270)
			(size 0.519938 1.4986)
			(layers "F.Cu" "F.Mask" "F.Paste")
			(net "M_E_CPU0_SB_DQS_DN<8>")
		)
		(pad "283" smd rect
			(at 2.050034 59.075066 270)
			(size 0.519938 1.4986)
			(layers "F.Cu" "F.Mask" "F.Paste")
			(net "M_E_CPU0_SB_DQS_DP<8>")
		)
		(pad "284" smd rect
			(at 2.050034 59.92495 270)
			(size 0.519938 1.4986)
			(layers "F.Cu" "F.Mask" "F.Paste")
			(net "GND")
		)
		(pad "285" smd rect
			(at 2.050034 60.775088 270)
			(size 0.519938 1.4986)
			(layers "F.Cu" "F.Mask" "F.Paste")
			(net "M_E_CPU0_SB_DQ<30>")
		)
		(pad "286" smd rect
			(at 2.050034 61.624972 270)
			(size 0.519938 1.4986)
			(layers "F.Cu" "F.Mask" "F.Paste")
			(net "GND")
		)
		(pad "287" smd rect
			(at 2.050034 62.47511 270)
			(size 0.519938 1.4986)
			(layers "F.Cu" "F.Mask" "F.Paste")
			(net "M_E_CPU0_SB_DQ<31>")
		)
		(pad "288" smd rect
			(at 2.050034 63.324994 270)
			(size 0.519938 1.4986)
			(layers "F.Cu" "F.Mask" "F.Paste")
			(net "GND")
		)
		(pad "G1" thru_hole oval
			(at 0 -68.97497)
			(size 2.8194 1.5748)
			(drill oval 2.4384 1.1938)
			(layers "*.Cu" "*.Mask")
			(remove_unused_layers no)
			(net "GND")
			(clearance 0.127)
			(thermal_gap 0.127)
		)
		(pad "G2" thru_hole oval
			(at 0 3.875024)
			(size 2.8194 1.5748)
			(drill oval 2.4384 1.1938)
			(layers "*.Cu" "*.Mask")
			(remove_unused_layers no)
			(net "GND")
			(clearance 0.127)
			(thermal_gap 0.127)
		)
		(pad "G3" thru_hole oval
			(at 0 68.97497)
			(size 2.8194 1.5748)
			(drill oval 2.4384 1.1938)
			(layers "*.Cu" "*.Mask")
			(remove_unused_layers no)
			(net "GND")
			(clearance 0.127)
			(thermal_gap 0.127)
		)
	)
	(footprint ""
		(layer "F.Cu")
		(at 162.212274 -408.517344 -90)
		(property "Reference" "C1543"
			(at 0 0 270)
			(layer "F.SilkS")
			(hide yes)
			(effects
				(font
					(size 1.27 1.27)
				)
			)
		)
		(property "Value" ""
			(at 0 0 270)
			(layer "F.Fab")
			(effects
				(font
					(size 1.27 1.27)
				)
			)
		)
		(duplicate_pad_numbers_are_jumpers no)
		(fp_line
			(start -0.299974 0.150114)
			(end -0.299974 -0.150114)
			(stroke
				(width 0.1)
				(type default)
			)
			(layer "F.Fab")
		)
		(fp_line
			(start 0.299974 0.150114)
			(end -0.299974 0.150114)
			(stroke
				(width 0.1)
				(type default)
			)
			(layer "F.Fab")
		)
		(fp_line
			(start -0.299974 -0.150114)
			(end 0.299974 -0.150114)
			(stroke
				(width 0.1)
				(type default)
			)
			(layer "F.Fab")
		)
		(fp_line
			(start 0.299974 -0.150114)
			(end 0.299974 0.150114)
			(stroke
				(width 0.1)
				(type default)
			)
			(layer "F.Fab")
		)
		(pad "1" smd rect
			(at -0.2667 0 270)
			(size 0.3048 0.381)
			(layers "F.Cu" "F.Mask" "F.Paste")
			(net "P5E_CPU1_PE3_TX_C_DP<2>")
		)
		(pad "2" smd rect
			(at 0.2667 0 270)
			(size 0.3048 0.381)
			(layers "F.Cu" "F.Mask" "F.Paste")
			(net "P5E_CPU1_PE3_TX_DP<2>")
		)
	)
	(footprint ""
		(layer "F.Cu")
		(at 355.233478 -238.162338 -90)
		(property "Reference" "C1043"
			(at 0 0 270)
			(layer "F.SilkS")
			(hide yes)
			(effects
				(font
					(size 1.27 1.27)
				)
			)
		)
		(property "Value" ""
			(at 0 0 270)
			(layer "F.Fab")
			(effects
				(font
					(size 1.27 1.27)
				)
			)
		)
		(duplicate_pad_numbers_are_jumpers no)
		(fp_line
			(start -0.7874 0.4064)
			(end -0.7874 -0.4064)
			(stroke
				(width 0.1524)
				(type default)
			)
			(layer "F.SilkS")
		)
		(fp_line
			(start 0.7874 0.4064)
			(end -0.7874 0.4064)
			(stroke
				(width 0.1524)
				(type default)
			)
			(layer "F.SilkS")
		)
		(fp_line
			(start -0.7874 -0.4064)
			(end 0.7874 -0.4064)
			(stroke
				(width 0.1524)
				(type default)
			)
			(layer "F.SilkS")
		)
		(fp_line
			(start 0.7874 -0.4064)
			(end 0.7874 0.4064)
			(stroke
				(width 0.1524)
				(type default)
			)
			(layer "F.SilkS")
		)
		(fp_line
			(start -0.67945 0.3048)
			(end -0.67945 -0.305054)
			(stroke
				(width 0.1)
				(type default)
			)
			(layer "F.Fab")
		)
		(fp_line
			(start -0.12065 0.3048)
			(end -0.67945 0.3048)
			(stroke
				(width 0.1)
				(type default)
			)
			(layer "F.Fab")
		)
		(fp_line
			(start 0.120396 0.3048)
			(end 0.120396 0.2794)
			(stroke
				(width 0.1)
				(type default)
			)
			(layer "F.Fab")
		)
		(fp_line
			(start 0.67945 0.3048)
			(end 0.120396 0.3048)
			(stroke
				(width 0.1)
				(type default)
			)
			(layer "F.Fab")
		)
		(fp_line
			(start -0.12065 0.2794)
			(end -0.12065 0.3048)
			(stroke
				(width 0.1)
				(type default)
			)
			(layer "F.Fab")
		)
		(fp_line
			(start 0.120396 0.2794)
			(end -0.12065 0.2794)
			(stroke
				(width 0.1)
				(type default)
			)
			(layer "F.Fab")
		)
		(fp_line
			(start -0.12065 -0.2794)
			(end 0.12065 -0.2794)
			(stroke
				(width 0.1)
				(type default)
			)
			(layer "F.Fab")
		)
		(fp_line
			(start 0.12065 -0.2794)
			(end 0.12065 -0.3048)
			(stroke
				(width 0.1)
				(type default)
			)
			(layer "F.Fab")
		)
		(fp_line
			(start 0.12065 -0.3048)
			(end 0.67945 -0.3048)
			(stroke
				(width 0.1)
				(type default)
			)
			(layer "F.Fab")
		)
		(fp_line
			(start 0.67945 -0.3048)
			(end 0.67945 0.3048)
			(stroke
				(width 0.1)
				(type default)
			)
			(layer "F.Fab")
		)
		(fp_line
			(start -0.67945 -0.305054)
			(end -0.12065 -0.305054)
			(stroke
				(width 0.1)
				(type default)
			)
			(layer "F.Fab")
		)
		(fp_line
			(start -0.12065 -0.305054)
			(end -0.12065 -0.2794)
			(stroke
				(width 0.1)
				(type default)
			)
			(layer "F.Fab")
		)
		(pad "1" smd circle
			(at -0.40005 0 270)
			(size 0 0)
			(layers "F.Cu" "F.Mask" "F.Paste")
			(net "PVCCIN_CPU0")
		)
		(pad "2" smd circle
			(at 0.40005 0 270)
			(size 0 0)
			(layers "F.Cu" "F.Mask" "F.Paste")
			(net "GND")
		)
	)
	(footprint ""
		(layer "F.Cu")
		(at 355.227128 -258.726686 90)
		(property "Reference" "C970"
			(at 0 0 90)
			(layer "F.SilkS")
			(hide yes)
			(effects
				(font
					(size 1.27 1.27)
				)
			)
		)
		(property "Value" ""
			(at 0 0 90)
			(layer "F.Fab")
			(effects
				(font
					(size 1.27 1.27)
				)
			)
		)
		(duplicate_pad_numbers_are_jumpers no)
		(fp_line
			(start 0.7874 -0.4064)
			(end 0.7874 0.4064)
			(stroke
				(width 0.1524)
				(type default)
			)
			(layer "F.SilkS")
		)
		(fp_line
			(start -0.7874 -0.4064)
			(end 0.7874 -0.4064)
			(stroke
				(width 0.1524)
				(type default)
			)
			(layer "F.SilkS")
		)
		(fp_line
			(start 0.7874 0.4064)
			(end -0.7874 0.4064)
			(stroke
				(width 0.1524)
				(type default)
			)
			(layer "F.SilkS")
		)
		(fp_line
			(start -0.7874 0.4064)
			(end -0.7874 -0.4064)
			(stroke
				(width 0.1524)
				(type default)
			)
			(layer "F.SilkS")
		)
		(fp_line
			(start -0.12065 -0.305054)
			(end -0.12065 -0.2794)
			(stroke
				(width 0.1)
				(type default)
			)
			(layer "F.Fab")
		)
		(fp_line
			(start -0.67945 -0.305054)
			(end -0.12065 -0.305054)
			(stroke
				(width 0.1)
				(type default)
			)
			(layer "F.Fab")
		)
		(fp_line
			(start 0.67945 -0.3048)
			(end 0.67945 0.3048)
			(stroke
				(width 0.1)
				(type default)
			)
			(layer "F.Fab")
		)
		(fp_line
			(start 0.12065 -0.3048)
			(end 0.67945 -0.3048)
			(stroke
				(width 0.1)
				(type default)
			)
			(layer "F.Fab")
		)
		(fp_line
			(start 0.12065 -0.2794)
			(end 0.12065 -0.3048)
			(stroke
				(width 0.1)
				(type default)
			)
			(layer "F.Fab")
		)
		(fp_line
			(start -0.12065 -0.2794)
			(end 0.12065 -0.2794)
			(stroke
				(width 0.1)
				(type default)
			)
			(layer "F.Fab")
		)
		(fp_line
			(start 0.120396 0.2794)
			(end -0.12065 0.2794)
			(stroke
				(width 0.1)
				(type default)
			)
			(layer "F.Fab")
		)
		(fp_line
			(start -0.12065 0.2794)
			(end -0.12065 0.3048)
			(stroke
				(width 0.1)
				(type default)
			)
			(layer "F.Fab")
		)
		(fp_line
			(start 0.67945 0.3048)
			(end 0.120396 0.3048)
			(stroke
				(width 0.1)
				(type default)
			)
			(layer "F.Fab")
		)
		(fp_line
			(start 0.120396 0.3048)
			(end 0.120396 0.2794)
			(stroke
				(width 0.1)
				(type default)
			)
			(layer "F.Fab")
		)
		(fp_line
			(start -0.12065 0.3048)
			(end -0.67945 0.3048)
			(stroke
				(width 0.1)
				(type default)
			)
			(layer "F.Fab")
		)
		(fp_line
			(start -0.67945 0.3048)
			(end -0.67945 -0.305054)
			(stroke
				(width 0.1)
				(type default)
			)
			(layer "F.Fab")
		)
		(pad "1" smd circle
			(at -0.40005 0 90)
			(size 0 0)
			(layers "F.Cu" "F.Mask" "F.Paste")
			(net "PVCCIN_CPU0")
		)
		(pad "2" smd circle
			(at 0.40005 0 90)
			(size 0 0)
			(layers "F.Cu" "F.Mask" "F.Paste")
			(net "GND")
		)
	)
	(footprint ""
		(layer "F.Cu")
		(at 400.558 -170.983148)
		(property "Reference" "PC1576"
			(at 0 0 0)
			(layer "F.SilkS")
			(hide yes)
			(effects
				(font
					(size 1.27 1.27)
				)
			)
		)
		(property "Value" ""
			(at 0 0 0)
			(layer "F.Fab")
			(effects
				(font
					(size 1.27 1.27)
				)
			)
		)
		(duplicate_pad_numbers_are_jumpers no)
		(fp_line
			(start 2.750058 0.999998)
			(end -2.750058 0.999998)
			(stroke
				(width 0.1524)
				(type default)
			)
			(layer "F.SilkS")
		)
		(fp_circle
			(center 0 0.999998)
			(end 2.750058 0.999998)
			(stroke
				(width 0.1524)
				(type default)
			)
			(fill no)
			(layer "F.SilkS")
		)
		(fp_poly
			(pts
				(arc
					(start 2.750058 0.999998)
					(mid 0 3.750056)
					(end -2.750058 0.999998)
				)
			)
			(stroke
				(width 0)
				(type default)
			)
			(fill yes)
			(layer "F.SilkS")
		)
		(fp_circle
			(center 0 0.999998)
			(end 2.750058 0.999998)
			(stroke
				(width 0.1)
				(type default)
			)
			(fill no)
			(layer "F.Fab")
		)
		(pad "1" thru_hole rect
			(at 0 0)
			(size 1.5748 1.5748)
			(drill 1.0668)
			(layers "*.Cu" "*.Mask")
			(remove_unused_layers no)
			(net "PVCCINFAON_CPU0")
			(clearance 0)
			(padstack
				(mode front_inner_back)
				(layer "Inner"
					(shape circle)
					(size 1.5748 1.5748)
					(clearance 0)
				)
				(layer "B.Cu"
					(shape rect)
					(size 1.5748 1.5748)
					(clearance 0)
				)
			)
		)
		(pad "2" thru_hole circle
			(at 0 1.999996)
			(size 1.5748 1.5748)
			(drill 1.0668)
			(layers "*.Cu" "*.Mask")
			(remove_unused_layers no)
			(net "GND")
			(clearance 0)
		)
	)
	(footprint ""
		(layer "F.Cu")
		(at 259.021326 -130.193796)
		(property "Reference" "R4498"
			(at 0 0 0)
			(layer "F.SilkS")
			(hide yes)
			(effects
				(font
					(size 1.27 1.27)
				)
			)
		)
		(property "Value" ""
			(at 0 0 0)
			(layer "F.Fab")
			(effects
				(font
					(size 1.27 1.27)
				)
			)
		)
		(duplicate_pad_numbers_are_jumpers no)
		(fp_line
			(start -0.7874 -0.4064)
			(end 0.7874 -0.4064)
			(stroke
				(width 0.1524)
				(type default)
			)
			(layer "F.SilkS")
		)
		(fp_line
			(start -0.7874 0.4064)
			(end -0.7874 -0.4064)
			(stroke
				(width 0.1524)
				(type default)
			)
			(layer "F.SilkS")
		)
		(fp_line
			(start 0.7874 -0.4064)
			(end 0.7874 0.4064)
			(stroke
				(width 0.1524)
				(type default)
			)
			(layer "F.SilkS")
		)
		(fp_line
			(start 0.7874 0.4064)
			(end -0.7874 0.4064)
			(stroke
				(width 0.1524)
				(type default)
			)
			(layer "F.SilkS")
		)
		(fp_line
			(start -0.67945 -0.305054)
			(end -0.12065 -0.305054)
			(stroke
				(width 0.1)
				(type default)
			)
			(layer "F.Fab")
		)
		(fp_line
			(start -0.67945 0.3048)
			(end -0.67945 -0.305054)
			(stroke
				(width 0.1)
				(type default)
			)
			(layer "F.Fab")
		)
		(fp_line
			(start -0.12065 -0.305054)
			(end -0.12065 -0.2794)
			(stroke
				(width 0.1)
				(type default)
			)
			(layer "F.Fab")
		)
		(fp_line
			(start -0.12065 -0.2794)
			(end 0.12065 -0.2794)
			(stroke
				(width 0.1)
				(type default)
			)
			(layer "F.Fab")
		)
		(fp_line
			(start -0.12065 0.2794)
			(end -0.12065 0.3048)
			(stroke
				(width 0.1)
				(type default)
			)
			(layer "F.Fab")
		)
		(fp_line
			(start -0.12065 0.3048)
			(end -0.67945 0.3048)
			(stroke
				(width 0.1)
				(type default)
			)
			(layer "F.Fab")
		)
		(fp_line
			(start 0.120396 0.2794)
			(end -0.12065 0.2794)
			(stroke
				(width 0.1)
				(type default)
			)
			(layer "F.Fab")
		)
		(fp_line
			(start 0.120396 0.3048)
			(end 0.120396 0.2794)
			(stroke
				(width 0.1)
				(type default)
			)
			(layer "F.Fab")
		)
		(fp_line
			(start 0.12065 -0.3048)
			(end 0.67945 -0.3048)
			(stroke
				(width 0.1)
				(type default)
			)
			(layer "F.Fab")
		)
		(fp_line
			(start 0.12065 -0.2794)
			(end 0.12065 -0.3048)
			(stroke
				(width 0.1)
				(type default)
			)
			(layer "F.Fab")
		)
		(fp_line
			(start 0.67945 -0.3048)
			(end 0.67945 0.3048)
			(stroke
				(width 0.1)
				(type default)
			)
			(layer "F.Fab")
		)
		(fp_line
			(start 0.67945 0.3048)
			(end 0.120396 0.3048)
			(stroke
				(width 0.1)
				(type default)
			)
			(layer "F.Fab")
		)
		(pad "1" smd circle
			(at -0.40005 0)
			(size 0 0)
			(layers "F.Cu" "F.Mask" "F.Paste")
			(net "P3V3")
		)
		(pad "2" smd circle
			(at 0.40005 0)
			(size 0 0)
			(layers "F.Cu" "F.Mask" "F.Paste")
			(net "SMB_HOST_CLK_BUF_ISO_3V3AUX_S_1")
		)
	)
	(footprint ""
		(layer "F.Cu")
		(at 153.60015 -70.26402 -90)
		(property "Reference" "R2309"
			(at 0 0 270)
			(layer "F.SilkS")
			(hide yes)
			(effects
				(font
					(size 1.27 1.27)
				)
			)
		)
		(property "Value" ""
			(at 0 0 270)
			(layer "F.Fab")
			(effects
				(font
					(size 1.27 1.27)
				)
			)
		)
		(duplicate_pad_numbers_are_jumpers no)
		(fp_line
			(start -0.7874 0.4064)
			(end -0.7874 -0.4064)
			(stroke
				(width 0.1524)
				(type default)
			)
			(layer "F.SilkS")
		)
		(fp_line
			(start 0.7874 0.4064)
			(end -0.7874 0.4064)
			(stroke
				(width 0.1524)
				(type default)
			)
			(layer "F.SilkS")
		)
		(fp_line
			(start -0.7874 -0.4064)
			(end 0.7874 -0.4064)
			(stroke
				(width 0.1524)
				(type default)
			)
			(layer "F.SilkS")
		)
		(fp_line
			(start 0.7874 -0.4064)
			(end 0.7874 0.4064)
			(stroke
				(width 0.1524)
				(type default)
			)
			(layer "F.SilkS")
		)
		(fp_line
			(start -0.67945 0.3048)
			(end -0.67945 -0.305054)
			(stroke
				(width 0.1)
				(type default)
			)
			(layer "F.Fab")
		)
		(fp_line
			(start -0.12065 0.3048)
			(end -0.67945 0.3048)
			(stroke
				(width 0.1)
				(type default)
			)
			(layer "F.Fab")
		)
		(fp_line
			(start 0.120396 0.3048)
			(end 0.120396 0.2794)
			(stroke
				(width 0.1)
				(type default)
			)
			(layer "F.Fab")
		)
		(fp_line
			(start 0.67945 0.3048)
			(end 0.120396 0.3048)
			(stroke
				(width 0.1)
				(type default)
			)
			(layer "F.Fab")
		)
		(fp_line
			(start -0.12065 0.2794)
			(end -0.12065 0.3048)
			(stroke
				(width 0.1)
				(type default)
			)
			(layer "F.Fab")
		)
		(fp_line
			(start 0.120396 0.2794)
			(end -0.12065 0.2794)
			(stroke
				(width 0.1)
				(type default)
			)
			(layer "F.Fab")
		)
		(fp_line
			(start -0.12065 -0.2794)
			(end 0.12065 -0.2794)
			(stroke
				(width 0.1)
				(type default)
			)
			(layer "F.Fab")
		)
		(fp_line
			(start 0.12065 -0.2794)
			(end 0.12065 -0.3048)
			(stroke
				(width 0.1)
				(type default)
			)
			(layer "F.Fab")
		)
		(fp_line
			(start 0.12065 -0.3048)
			(end 0.67945 -0.3048)
			(stroke
				(width 0.1)
				(type default)
			)
			(layer "F.Fab")
		)
		(fp_line
			(start 0.67945 -0.3048)
			(end 0.67945 0.3048)
			(stroke
				(width 0.1)
				(type default)
			)
			(layer "F.Fab")
		)
		(fp_line
			(start -0.67945 -0.305054)
			(end -0.12065 -0.305054)
			(stroke
				(width 0.1)
				(type default)
			)
			(layer "F.Fab")
		)
		(fp_line
			(start -0.12065 -0.305054)
			(end -0.12065 -0.2794)
			(stroke
				(width 0.1)
				(type default)
			)
			(layer "F.Fab")
		)
		(pad "1" smd circle
			(at -0.40005 0 270)
			(size 0 0)
			(layers "F.Cu" "F.Mask" "F.Paste")
			(net "PCA9543_S3M_ADDR1")
		)
		(pad "2" smd circle
			(at 0.40005 0 270)
			(size 0 0)
			(layers "F.Cu" "F.Mask" "F.Paste")
			(net "GND")
		)
	)
	(footprint ""
		(layer "F.Cu")
		(at 225.125788 -222.09887)
		(property "Reference" "R970"
			(at 0 0 0)
			(layer "F.SilkS")
			(hide yes)
			(effects
				(font
					(size 1.27 1.27)
				)
			)
		)
		(property "Value" ""
			(at 0 0 0)
			(layer "F.Fab")
			(effects
				(font
					(size 1.27 1.27)
				)
			)
		)
		(duplicate_pad_numbers_are_jumpers no)
		(fp_line
			(start -0.7874 -0.4064)
			(end 0.7874 -0.4064)
			(stroke
				(width 0.1524)
				(type default)
			)
			(layer "F.SilkS")
		)
		(fp_line
			(start -0.7874 0.4064)
			(end -0.7874 -0.4064)
			(stroke
				(width 0.1524)
				(type default)
			)
			(layer "F.SilkS")
		)
		(fp_line
			(start 0.7874 -0.4064)
			(end 0.7874 0.4064)
			(stroke
				(width 0.1524)
				(type default)
			)
			(layer "F.SilkS")
		)
		(fp_line
			(start 0.7874 0.4064)
			(end -0.7874 0.4064)
			(stroke
				(width 0.1524)
				(type default)
			)
			(layer "F.SilkS")
		)
		(fp_line
			(start -0.67945 -0.305054)
			(end -0.12065 -0.305054)
			(stroke
				(width 0.1)
				(type default)
			)
			(layer "F.Fab")
		)
		(fp_line
			(start -0.67945 0.3048)
			(end -0.67945 -0.305054)
			(stroke
				(width 0.1)
				(type default)
			)
			(layer "F.Fab")
		)
		(fp_line
			(start -0.12065 -0.305054)
			(end -0.12065 -0.2794)
			(stroke
				(width 0.1)
				(type default)
			)
			(layer "F.Fab")
		)
		(fp_line
			(start -0.12065 -0.2794)
			(end 0.12065 -0.2794)
			(stroke
				(width 0.1)
				(type default)
			)
			(layer "F.Fab")
		)
		(fp_line
			(start -0.12065 0.2794)
			(end -0.12065 0.3048)
			(stroke
				(width 0.1)
				(type default)
			)
			(layer "F.Fab")
		)
		(fp_line
			(start -0.12065 0.3048)
			(end -0.67945 0.3048)
			(stroke
				(width 0.1)
				(type default)
			)
			(layer "F.Fab")
		)
		(fp_line
			(start 0.120396 0.2794)
			(end -0.12065 0.2794)
			(stroke
				(width 0.1)
				(type default)
			)
			(layer "F.Fab")
		)
		(fp_line
			(start 0.120396 0.3048)
			(end 0.120396 0.2794)
			(stroke
				(width 0.1)
				(type default)
			)
			(layer "F.Fab")
		)
		(fp_line
			(start 0.12065 -0.3048)
			(end 0.67945 -0.3048)
			(stroke
				(width 0.1)
				(type default)
			)
			(layer "F.Fab")
		)
		(fp_line
			(start 0.12065 -0.2794)
			(end 0.12065 -0.3048)
			(stroke
				(width 0.1)
				(type default)
			)
			(layer "F.Fab")
		)
		(fp_line
			(start 0.67945 -0.3048)
			(end 0.67945 0.3048)
			(stroke
				(width 0.1)
				(type default)
			)
			(layer "F.Fab")
		)
		(fp_line
			(start 0.67945 0.3048)
			(end 0.120396 0.3048)
			(stroke
				(width 0.1)
				(type default)
			)
			(layer "F.Fab")
		)
		(pad "1" smd circle
			(at -0.40005 0)
			(size 0 0)
			(layers "F.Cu" "F.Mask" "F.Paste")
			(net "PVNN_TERM_CPU1")
		)
		(pad "2" smd circle
			(at 0.40005 0)
			(size 0 0)
			(layers "F.Cu" "F.Mask" "F.Paste")
			(net "SMB_S3M_CPU1_R_SCL")
		)
	)
	(footprint ""
		(layer "F.Cu")
		(at 307.456078 -422.87317 90)
		(property "Reference" "U308"
			(at -2.590292 -0.651256 0)
			(unlocked yes)
			(layer "F.SilkS")
			(effects
				(font
					(size 0.7874 0.5842)
					(thickness 0.1524)
				)
				(justify left)
			)
		)
		(property "Value" ""
			(at 0 0 90)
			(layer "F.Fab")
			(effects
				(font
					(size 1.27 1.27)
				)
			)
		)
		(duplicate_pad_numbers_are_jumpers no)
		(fp_line
			(start 1.38176 -1.100074)
			(end 0.592074 -1.100074)
			(stroke
				(width 0.1524)
				(type default)
			)
			(layer "F.SilkS")
		)
		(fp_line
			(start 0.592074 -1.100074)
			(end 0 -0.508)
			(stroke
				(width 0.1524)
				(type default)
			)
			(layer "F.SilkS")
		)
		(fp_line
			(start -0.592074 -1.100074)
			(end -1.38176 -1.100074)
			(stroke
				(width 0.1524)
				(type default)
			)
			(layer "F.SilkS")
		)
		(fp_line
			(start -1.38176 -1.100074)
			(end -1.38176 1.100074)
			(stroke
				(width 0.1524)
				(type default)
			)
			(layer "F.SilkS")
		)
		(fp_line
			(start 0 -0.508)
			(end -0.592074 -1.100074)
			(stroke
				(width 0.1524)
				(type default)
			)
			(layer "F.SilkS")
		)
		(fp_line
			(start 1.38176 1.100074)
			(end 1.38176 -1.100074)
			(stroke
				(width 0.1524)
				(type default)
			)
			(layer "F.SilkS")
		)
		(fp_line
			(start -1.38176 1.100074)
			(end 1.38176 1.100074)
			(stroke
				(width 0.1524)
				(type default)
			)
			(layer "F.SilkS")
		)
		(fp_poly
			(pts
				(xy -1.50241 -0.649986) (xy -1.9431 -0.429768) (xy -1.9431 -0.870204)
			)
			(stroke
				(width 0)
				(type default)
			)
			(fill yes)
			(layer "F.SilkS")
		)
		(fp_line
			(start 0.674878 -1.100074)
			(end -0.674878 -1.100074)
			(stroke
				(width 0.1)
				(type default)
			)
			(layer "F.Fab")
		)
		(fp_line
			(start -0.674878 -1.100074)
			(end -0.674878 1.100074)
			(stroke
				(width 0.1)
				(type default)
			)
			(layer "F.Fab")
		)
		(fp_line
			(start 0.674878 1.100074)
			(end 0.674878 -1.100074)
			(stroke
				(width 0.1)
				(type default)
			)
			(layer "F.Fab")
		)
		(fp_line
			(start -0.674878 1.100074)
			(end 0.674878 1.100074)
			(stroke
				(width 0.1)
				(type default)
			)
			(layer "F.Fab")
		)
		(fp_poly
			(pts
				(xy -1.9431 -0.870204) (xy -1.50241 -0.649986) (xy -1.9431 -0.429768)
			)
			(stroke
				(width 0)
				(type default)
			)
			(fill yes)
			(layer "F.Fab")
		)
		(pad "1" smd rect
			(at -0.94996 -0.649986)
			(size 0.4318 0.6096)
			(layers "F.Cu" "F.Mask" "F.Paste")
			(net "PWRGD_P3V3_AUX_PDB_R")
		)
		(pad "2" smd rect
			(at -0.94996 0)
			(size 0.4318 0.6096)
			(layers "F.Cu" "F.Mask" "F.Paste")
			(net "GND")
		)
		(pad "3" smd rect
			(at -0.94996 0.649986)
			(size 0.4318 0.6096)
			(layers "F.Cu" "F.Mask" "F.Paste")
			(net "Net_8600")
		)
		(pad "4" smd rect
			(at 0.94996 0.649986)
			(size 0.4318 0.6096)
			(layers "F.Cu" "F.Mask" "F.Paste")
			(net "Net_8599")
		)
		(pad "5" smd rect
			(at 0.94996 0)
			(size 0.4318 0.6096)
			(layers "F.Cu" "F.Mask" "F.Paste")
			(net "P3V3_AUX")
		)
		(pad "6" smd rect
			(at 0.94996 -0.649986)
			(size 0.4318 0.6096)
			(layers "F.Cu" "F.Mask" "F.Paste")
			(net "PWRGD_P3V3_AUX_PDB_BUF_R")
		)
	)
	(footprint ""
		(layer "F.Cu")
		(at 293.549832 -435.600094)
		(property "Reference" "H91"
			(at -6.814312 -3.983736 0)
			(unlocked yes)
			(layer "F.SilkS")
			(effects
				(font
					(size 0.7874 0.5842)
					(thickness 0.1524)
				)
				(justify left)
			)
		)
		(property "Value" ""
			(at 0 0 0)
			(layer "F.Fab")
			(effects
				(font
					(size 1.27 1.27)
				)
			)
		)
		(duplicate_pad_numbers_are_jumpers no)
		(pad "1" thru_hole circle
			(at 0 0)
			(size 10.0076 10.0076)
			(drill 5.6134)
			(layers "*.Cu" "*.Mask")
			(remove_unused_layers no)
			(net "GND")
			(clearance -1.9431)
		)
	)
	(footprint ""
		(layer "F.Cu")
		(at 36.956238 -133.81482 180)
		(property "Reference" "R2570"
			(at 0 0 180)
			(layer "F.SilkS")
			(hide yes)
			(effects
				(font
					(size 1.27 1.27)
				)
			)
		)
		(property "Value" ""
			(at 0 0 180)
			(layer "F.Fab")
			(effects
				(font
					(size 1.27 1.27)
				)
			)
		)
		(duplicate_pad_numbers_are_jumpers no)
		(fp_line
			(start 0.7874 0.4064)
			(end -0.7874 0.4064)
			(stroke
				(width 0.1524)
				(type default)
			)
			(layer "F.SilkS")
		)
		(fp_line
			(start 0.7874 -0.4064)
			(end 0.7874 0.4064)
			(stroke
				(width 0.1524)
				(type default)
			)
			(layer "F.SilkS")
		)
		(fp_line
			(start -0.7874 0.4064)
			(end -0.7874 -0.4064)
			(stroke
				(width 0.1524)
				(type default)
			)
			(layer "F.SilkS")
		)
		(fp_line
			(start -0.7874 -0.4064)
			(end 0.7874 -0.4064)
			(stroke
				(width 0.1524)
				(type default)
			)
			(layer "F.SilkS")
		)
		(fp_line
			(start 0.67945 0.3048)
			(end 0.120396 0.3048)
			(stroke
				(width 0.1)
				(type default)
			)
			(layer "F.Fab")
		)
		(fp_line
			(start 0.67945 -0.3048)
			(end 0.67945 0.3048)
			(stroke
				(width 0.1)
				(type default)
			)
			(layer "F.Fab")
		)
		(fp_line
			(start 0.12065 -0.2794)
			(end 0.12065 -0.3048)
			(stroke
				(width 0.1)
				(type default)
			)
			(layer "F.Fab")
		)
		(fp_line
			(start 0.12065 -0.3048)
			(end 0.67945 -0.3048)
			(stroke
				(width 0.1)
				(type default)
			)
			(layer "F.Fab")
		)
		(fp_line
			(start 0.120396 0.3048)
			(end 0.120396 0.2794)
			(stroke
				(width 0.1)
				(type default)
			)
			(layer "F.Fab")
		)
		(fp_line
			(start 0.120396 0.2794)
			(end -0.12065 0.2794)
			(stroke
				(width 0.1)
				(type default)
			)
			(layer "F.Fab")
		)
		(fp_line
			(start -0.12065 0.3048)
			(end -0.67945 0.3048)
			(stroke
				(width 0.1)
				(type default)
			)
			(layer "F.Fab")
		)
		(fp_line
			(start -0.12065 0.2794)
			(end -0.12065 0.3048)
			(stroke
				(width 0.1)
				(type default)
			)
			(layer "F.Fab")
		)
		(fp_line
			(start -0.12065 -0.2794)
			(end 0.12065 -0.2794)
			(stroke
				(width 0.1)
				(type default)
			)
			(layer "F.Fab")
		)
		(fp_line
			(start -0.12065 -0.305054)
			(end -0.12065 -0.2794)
			(stroke
				(width 0.1)
				(type default)
			)
			(layer "F.Fab")
		)
		(fp_line
			(start -0.67945 0.3048)
			(end -0.67945 -0.305054)
			(stroke
				(width 0.1)
				(type default)
			)
			(layer "F.Fab")
		)
		(fp_line
			(start -0.67945 -0.305054)
			(end -0.12065 -0.305054)
			(stroke
				(width 0.1)
				(type default)
			)
			(layer "F.Fab")
		)
		(pad "1" smd circle
			(at -0.40005 0 180)
			(size 0 0)
			(layers "F.Cu" "F.Mask" "F.Paste")
			(net "FM_PVCCFA_EHV_CPU1_EN")
		)
		(pad "2" smd circle
			(at 0.40005 0 180)
			(size 0 0)
			(layers "F.Cu" "F.Mask" "F.Paste")
			(net "PVCCFA_EHV_CPU1_EN_R")
		)
	)
	(footprint ""
		(layer "F.Cu")
		(at 106.476038 -38.983158)
		(property "Reference" "R3189"
			(at 0 0 0)
			(layer "F.SilkS")
			(hide yes)
			(effects
				(font
					(size 1.27 1.27)
				)
			)
		)
		(property "Value" ""
			(at 0 0 0)
			(layer "F.Fab")
			(effects
				(font
					(size 1.27 1.27)
				)
			)
		)
		(duplicate_pad_numbers_are_jumpers no)
		(fp_line
			(start -0.7874 -0.4064)
			(end 0.7874 -0.4064)
			(stroke
				(width 0.1524)
				(type default)
			)
			(layer "F.SilkS")
		)
		(fp_line
			(start -0.7874 0.4064)
			(end -0.7874 -0.4064)
			(stroke
				(width 0.1524)
				(type default)
			)
			(layer "F.SilkS")
		)
		(fp_line
			(start 0.7874 -0.4064)
			(end 0.7874 0.4064)
			(stroke
				(width 0.1524)
				(type default)
			)
			(layer "F.SilkS")
		)
		(fp_line
			(start 0.7874 0.4064)
			(end -0.7874 0.4064)
			(stroke
				(width 0.1524)
				(type default)
			)
			(layer "F.SilkS")
		)
		(fp_line
			(start -0.67945 -0.305054)
			(end -0.12065 -0.305054)
			(stroke
				(width 0.1)
				(type default)
			)
			(layer "F.Fab")
		)
		(fp_line
			(start -0.67945 0.3048)
			(end -0.67945 -0.305054)
			(stroke
				(width 0.1)
				(type default)
			)
			(layer "F.Fab")
		)
		(fp_line
			(start -0.12065 -0.305054)
			(end -0.12065 -0.2794)
			(stroke
				(width 0.1)
				(type default)
			)
			(layer "F.Fab")
		)
		(fp_line
			(start -0.12065 -0.2794)
			(end 0.12065 -0.2794)
			(stroke
				(width 0.1)
				(type default)
			)
			(layer "F.Fab")
		)
		(fp_line
			(start -0.12065 0.2794)
			(end -0.12065 0.3048)
			(stroke
				(width 0.1)
				(type default)
			)
			(layer "F.Fab")
		)
		(fp_line
			(start -0.12065 0.3048)
			(end -0.67945 0.3048)
			(stroke
				(width 0.1)
				(type default)
			)
			(layer "F.Fab")
		)
		(fp_line
			(start 0.120396 0.2794)
			(end -0.12065 0.2794)
			(stroke
				(width 0.1)
				(type default)
			)
			(layer "F.Fab")
		)
		(fp_line
			(start 0.120396 0.3048)
			(end 0.120396 0.2794)
			(stroke
				(width 0.1)
				(type default)
			)
			(layer "F.Fab")
		)
		(fp_line
			(start 0.12065 -0.3048)
			(end 0.67945 -0.3048)
			(stroke
				(width 0.1)
				(type default)
			)
			(layer "F.Fab")
		)
		(fp_line
			(start 0.12065 -0.2794)
			(end 0.12065 -0.3048)
			(stroke
				(width 0.1)
				(type default)
			)
			(layer "F.Fab")
		)
		(fp_line
			(start 0.67945 -0.3048)
			(end 0.67945 0.3048)
			(stroke
				(width 0.1)
				(type default)
			)
			(layer "F.Fab")
		)
		(fp_line
			(start 0.67945 0.3048)
			(end 0.120396 0.3048)
			(stroke
				(width 0.1)
				(type default)
			)
			(layer "F.Fab")
		)
		(pad "1" smd circle
			(at -0.40005 0)
			(size 0 0)
			(layers "F.Cu" "F.Mask" "F.Paste")
			(net "RST_OCP_V3_2_BUF_N")
		)
		(pad "2" smd circle
			(at 0.40005 0)
			(size 0 0)
			(layers "F.Cu" "F.Mask" "F.Paste")
			(net "RST_PERST3_OCP_V3_2_N")
		)
	)
	(footprint ""
		(layer "F.Cu")
		(at 453.043544 -25.638506 180)
		(property "Reference" "PR4524"
			(at 0 0 180)
			(layer "F.SilkS")
			(hide yes)
			(effects
				(font
					(size 1.27 1.27)
				)
			)
		)
		(property "Value" ""
			(at 0 0 180)
			(layer "F.Fab")
			(effects
				(font
					(size 1.27 1.27)
				)
			)
		)
		(duplicate_pad_numbers_are_jumpers no)
		(fp_line
			(start 0.7874 0.4064)
			(end -0.7874 0.4064)
			(stroke
				(width 0.1524)
				(type default)
			)
			(layer "F.SilkS")
		)
		(fp_line
			(start 0.7874 -0.4064)
			(end 0.7874 0.4064)
			(stroke
				(width 0.1524)
				(type default)
			)
			(layer "F.SilkS")
		)
		(fp_line
			(start -0.7874 0.4064)
			(end -0.7874 -0.4064)
			(stroke
				(width 0.1524)
				(type default)
			)
			(layer "F.SilkS")
		)
		(fp_line
			(start -0.7874 -0.4064)
			(end 0.7874 -0.4064)
			(stroke
				(width 0.1524)
				(type default)
			)
			(layer "F.SilkS")
		)
		(fp_line
			(start 0.67945 0.3048)
			(end 0.120396 0.3048)
			(stroke
				(width 0.1)
				(type default)
			)
			(layer "F.Fab")
		)
		(fp_line
			(start 0.67945 -0.3048)
			(end 0.67945 0.3048)
			(stroke
				(width 0.1)
				(type default)
			)
			(layer "F.Fab")
		)
		(fp_line
			(start 0.12065 -0.2794)
			(end 0.12065 -0.3048)
			(stroke
				(width 0.1)
				(type default)
			)
			(layer "F.Fab")
		)
		(fp_line
			(start 0.12065 -0.3048)
			(end 0.67945 -0.3048)
			(stroke
				(width 0.1)
				(type default)
			)
			(layer "F.Fab")
		)
		(fp_line
			(start 0.120396 0.3048)
			(end 0.120396 0.2794)
			(stroke
				(width 0.1)
				(type default)
			)
			(layer "F.Fab")
		)
		(fp_line
			(start 0.120396 0.2794)
			(end -0.12065 0.2794)
			(stroke
				(width 0.1)
				(type default)
			)
			(layer "F.Fab")
		)
		(fp_line
			(start -0.12065 0.3048)
			(end -0.67945 0.3048)
			(stroke
				(width 0.1)
				(type default)
			)
			(layer "F.Fab")
		)
		(fp_line
			(start -0.12065 0.2794)
			(end -0.12065 0.3048)
			(stroke
				(width 0.1)
				(type default)
			)
			(layer "F.Fab")
		)
		(fp_line
			(start -0.12065 -0.2794)
			(end 0.12065 -0.2794)
			(stroke
				(width 0.1)
				(type default)
			)
			(layer "F.Fab")
		)
		(fp_line
			(start -0.12065 -0.305054)
			(end -0.12065 -0.2794)
			(stroke
				(width 0.1)
				(type default)
			)
			(layer "F.Fab")
		)
		(fp_line
			(start -0.67945 0.3048)
			(end -0.67945 -0.305054)
			(stroke
				(width 0.1)
				(type default)
			)
			(layer "F.Fab")
		)
		(fp_line
			(start -0.67945 -0.305054)
			(end -0.12065 -0.305054)
			(stroke
				(width 0.1)
				(type default)
			)
			(layer "F.Fab")
		)
		(pad "1" smd circle
			(at -0.40005 0 180)
			(size 0 0)
			(layers "F.Cu" "F.Mask" "F.Paste")
			(net "P12V_OCP_SFF")
		)
		(pad "2" smd circle
			(at 0.40005 0 180)
			(size 0 0)
			(layers "F.Cu" "F.Mask" "F.Paste")
			(net "P12V_OCP_GATE_1")
		)
	)
	(footprint ""
		(layer "F.Cu")
		(at 362.646468 -358.93375)
		(property "Reference" "PC100"
			(at 0 0 0)
			(layer "F.SilkS")
			(hide yes)
			(effects
				(font
					(size 1.27 1.27)
				)
			)
		)
		(property "Value" ""
			(at 0 0 0)
			(layer "F.Fab")
			(effects
				(font
					(size 1.27 1.27)
				)
			)
		)
		(duplicate_pad_numbers_are_jumpers no)
		(fp_line
			(start -0.7874 -0.4064)
			(end 0.7874 -0.4064)
			(stroke
				(width 0.1524)
				(type default)
			)
			(layer "F.SilkS")
		)
		(fp_line
			(start -0.7874 0.4064)
			(end -0.7874 -0.4064)
			(stroke
				(width 0.1524)
				(type default)
			)
			(layer "F.SilkS")
		)
		(fp_line
			(start 0.7874 -0.4064)
			(end 0.7874 0.4064)
			(stroke
				(width 0.1524)
				(type default)
			)
			(layer "F.SilkS")
		)
		(fp_line
			(start 0.7874 0.4064)
			(end -0.7874 0.4064)
			(stroke
				(width 0.1524)
				(type default)
			)
			(layer "F.SilkS")
		)
		(fp_line
			(start -0.67945 -0.305054)
			(end -0.12065 -0.305054)
			(stroke
				(width 0.1)
				(type default)
			)
			(layer "F.Fab")
		)
		(fp_line
			(start -0.67945 0.3048)
			(end -0.67945 -0.305054)
			(stroke
				(width 0.1)
				(type default)
			)
			(layer "F.Fab")
		)
		(fp_line
			(start -0.12065 -0.305054)
			(end -0.12065 -0.2794)
			(stroke
				(width 0.1)
				(type default)
			)
			(layer "F.Fab")
		)
		(fp_line
			(start -0.12065 -0.2794)
			(end 0.12065 -0.2794)
			(stroke
				(width 0.1)
				(type default)
			)
			(layer "F.Fab")
		)
		(fp_line
			(start -0.12065 0.2794)
			(end -0.12065 0.3048)
			(stroke
				(width 0.1)
				(type default)
			)
			(layer "F.Fab")
		)
		(fp_line
			(start -0.12065 0.3048)
			(end -0.67945 0.3048)
			(stroke
				(width 0.1)
				(type default)
			)
			(layer "F.Fab")
		)
		(fp_line
			(start 0.120396 0.2794)
			(end -0.12065 0.2794)
			(stroke
				(width 0.1)
				(type default)
			)
			(layer "F.Fab")
		)
		(fp_line
			(start 0.120396 0.3048)
			(end 0.120396 0.2794)
			(stroke
				(width 0.1)
				(type default)
			)
			(layer "F.Fab")
		)
		(fp_line
			(start 0.12065 -0.3048)
			(end 0.67945 -0.3048)
			(stroke
				(width 0.1)
				(type default)
			)
			(layer "F.Fab")
		)
		(fp_line
			(start 0.12065 -0.2794)
			(end 0.12065 -0.3048)
			(stroke
				(width 0.1)
				(type default)
			)
			(layer "F.Fab")
		)
		(fp_line
			(start 0.67945 -0.3048)
			(end 0.67945 0.3048)
			(stroke
				(width 0.1)
				(type default)
			)
			(layer "F.Fab")
		)
		(fp_line
			(start 0.67945 0.3048)
			(end 0.120396 0.3048)
			(stroke
				(width 0.1)
				(type default)
			)
			(layer "F.Fab")
		)
		(pad "1" smd circle
			(at -0.40005 0)
			(size 0 0)
			(layers "F.Cu" "F.Mask" "F.Paste")
			(net "PVCCFA_EHV_FIVRA_CPU0_BTSEN")
		)
		(pad "2" smd circle
			(at 0.40005 0)
			(size 0 0)
			(layers "F.Cu" "F.Mask" "F.Paste")
			(net "GND")
		)
	)
	(footprint ""
		(layer "F.Cu")
		(at 357.487982 -386.41909 180)
		(property "Reference" "R4159"
			(at 0 0 180)
			(layer "F.SilkS")
			(hide yes)
			(effects
				(font
					(size 1.27 1.27)
				)
			)
		)
		(property "Value" ""
			(at 0 0 180)
			(layer "F.Fab")
			(effects
				(font
					(size 1.27 1.27)
				)
			)
		)
		(duplicate_pad_numbers_are_jumpers no)
		(fp_line
			(start 0.7874 0.4064)
			(end -0.7874 0.4064)
			(stroke
				(width 0.1524)
				(type default)
			)
			(layer "F.SilkS")
		)
		(fp_line
			(start 0.7874 -0.4064)
			(end 0.7874 0.4064)
			(stroke
				(width 0.1524)
				(type default)
			)
			(layer "F.SilkS")
		)
		(fp_line
			(start -0.7874 0.4064)
			(end -0.7874 -0.4064)
			(stroke
				(width 0.1524)
				(type default)
			)
			(layer "F.SilkS")
		)
		(fp_line
			(start -0.7874 -0.4064)
			(end 0.7874 -0.4064)
			(stroke
				(width 0.1524)
				(type default)
			)
			(layer "F.SilkS")
		)
		(fp_line
			(start 0.67945 0.3048)
			(end 0.120396 0.3048)
			(stroke
				(width 0.1)
				(type default)
			)
			(layer "F.Fab")
		)
		(fp_line
			(start 0.67945 -0.3048)
			(end 0.67945 0.3048)
			(stroke
				(width 0.1)
				(type default)
			)
			(layer "F.Fab")
		)
		(fp_line
			(start 0.12065 -0.2794)
			(end 0.12065 -0.3048)
			(stroke
				(width 0.1)
				(type default)
			)
			(layer "F.Fab")
		)
		(fp_line
			(start 0.12065 -0.3048)
			(end 0.67945 -0.3048)
			(stroke
				(width 0.1)
				(type default)
			)
			(layer "F.Fab")
		)
		(fp_line
			(start 0.120396 0.3048)
			(end 0.120396 0.2794)
			(stroke
				(width 0.1)
				(type default)
			)
			(layer "F.Fab")
		)
		(fp_line
			(start 0.120396 0.2794)
			(end -0.12065 0.2794)
			(stroke
				(width 0.1)
				(type default)
			)
			(layer "F.Fab")
		)
		(fp_line
			(start -0.12065 0.3048)
			(end -0.67945 0.3048)
			(stroke
				(width 0.1)
				(type default)
			)
			(layer "F.Fab")
		)
		(fp_line
			(start -0.12065 0.2794)
			(end -0.12065 0.3048)
			(stroke
				(width 0.1)
				(type default)
			)
			(layer "F.Fab")
		)
		(fp_line
			(start -0.12065 -0.2794)
			(end 0.12065 -0.2794)
			(stroke
				(width 0.1)
				(type default)
			)
			(layer "F.Fab")
		)
		(fp_line
			(start -0.12065 -0.305054)
			(end -0.12065 -0.2794)
			(stroke
				(width 0.1)
				(type default)
			)
			(layer "F.Fab")
		)
		(fp_line
			(start -0.67945 0.3048)
			(end -0.67945 -0.305054)
			(stroke
				(width 0.1)
				(type default)
			)
			(layer "F.Fab")
		)
		(fp_line
			(start -0.67945 -0.305054)
			(end -0.12065 -0.305054)
			(stroke
				(width 0.1)
				(type default)
			)
			(layer "F.Fab")
		)
		(pad "1" smd circle
			(at -0.40005 0 180)
			(size 0 0)
			(layers "F.Cu" "F.Mask" "F.Paste")
			(net "GPU_3V3IO_RSVD1")
		)
		(pad "2" smd circle
			(at 0.40005 0 180)
			(size 0 0)
			(layers "F.Cu" "F.Mask" "F.Paste")
			(net "GND")
		)
	)
	(footprint ""
		(layer "F.Cu")
		(at 432.38928 -136.644888 90)
		(property "Reference" "R2322"
			(at 0 0 90)
			(layer "F.SilkS")
			(hide yes)
			(effects
				(font
					(size 1.27 1.27)
				)
			)
		)
		(property "Value" ""
			(at 0 0 90)
			(layer "F.Fab")
			(effects
				(font
					(size 1.27 1.27)
				)
			)
		)
		(duplicate_pad_numbers_are_jumpers no)
		(fp_line
			(start 0.7874 -0.4064)
			(end 0.7874 0.4064)
			(stroke
				(width 0.1524)
				(type default)
			)
			(layer "F.SilkS")
		)
		(fp_line
			(start -0.7874 -0.4064)
			(end 0.7874 -0.4064)
			(stroke
				(width 0.1524)
				(type default)
			)
			(layer "F.SilkS")
		)
		(fp_line
			(start 0.7874 0.4064)
			(end -0.7874 0.4064)
			(stroke
				(width 0.1524)
				(type default)
			)
			(layer "F.SilkS")
		)
		(fp_line
			(start -0.7874 0.4064)
			(end -0.7874 -0.4064)
			(stroke
				(width 0.1524)
				(type default)
			)
			(layer "F.SilkS")
		)
		(fp_line
			(start -0.12065 -0.305054)
			(end -0.12065 -0.2794)
			(stroke
				(width 0.1)
				(type default)
			)
			(layer "F.Fab")
		)
		(fp_line
			(start -0.67945 -0.305054)
			(end -0.12065 -0.305054)
			(stroke
				(width 0.1)
				(type default)
			)
			(layer "F.Fab")
		)
		(fp_line
			(start 0.67945 -0.3048)
			(end 0.67945 0.3048)
			(stroke
				(width 0.1)
				(type default)
			)
			(layer "F.Fab")
		)
		(fp_line
			(start 0.12065 -0.3048)
			(end 0.67945 -0.3048)
			(stroke
				(width 0.1)
				(type default)
			)
			(layer "F.Fab")
		)
		(fp_line
			(start 0.12065 -0.2794)
			(end 0.12065 -0.3048)
			(stroke
				(width 0.1)
				(type default)
			)
			(layer "F.Fab")
		)
		(fp_line
			(start -0.12065 -0.2794)
			(end 0.12065 -0.2794)
			(stroke
				(width 0.1)
				(type default)
			)
			(layer "F.Fab")
		)
		(fp_line
			(start 0.120396 0.2794)
			(end -0.12065 0.2794)
			(stroke
				(width 0.1)
				(type default)
			)
			(layer "F.Fab")
		)
		(fp_line
			(start -0.12065 0.2794)
			(end -0.12065 0.3048)
			(stroke
				(width 0.1)
				(type default)
			)
			(layer "F.Fab")
		)
		(fp_line
			(start 0.67945 0.3048)
			(end 0.120396 0.3048)
			(stroke
				(width 0.1)
				(type default)
			)
			(layer "F.Fab")
		)
		(fp_line
			(start 0.120396 0.3048)
			(end 0.120396 0.2794)
			(stroke
				(width 0.1)
				(type default)
			)
			(layer "F.Fab")
		)
		(fp_line
			(start -0.12065 0.3048)
			(end -0.67945 0.3048)
			(stroke
				(width 0.1)
				(type default)
			)
			(layer "F.Fab")
		)
		(fp_line
			(start -0.67945 0.3048)
			(end -0.67945 -0.305054)
			(stroke
				(width 0.1)
				(type default)
			)
			(layer "F.Fab")
		)
		(pad "1" smd circle
			(at -0.40005 0 90)
			(size 0 0)
			(layers "F.Cu" "F.Mask" "F.Paste")
			(net "PVNN_TERM_CPU0")
		)
		(pad "2" smd circle
			(at 0.40005 0 90)
			(size 0 0)
			(layers "F.Cu" "F.Mask" "F.Paste")
			(net "SVID_CLK0_CPU0_R")
		)
	)
	(footprint ""
		(layer "F.Cu")
		(at 249.28703 -44.979082 90)
		(property "Reference" "PR3962"
			(at 0 0 90)
			(layer "F.SilkS")
			(hide yes)
			(effects
				(font
					(size 1.27 1.27)
				)
			)
		)
		(property "Value" ""
			(at 0 0 90)
			(layer "F.Fab")
			(effects
				(font
					(size 1.27 1.27)
				)
			)
		)
		(duplicate_pad_numbers_are_jumpers no)
		(fp_line
			(start 0.7874 -0.4064)
			(end 0.7874 0.4064)
			(stroke
				(width 0.1524)
				(type default)
			)
			(layer "F.SilkS")
		)
		(fp_line
			(start -0.7874 -0.4064)
			(end 0.7874 -0.4064)
			(stroke
				(width 0.1524)
				(type default)
			)
			(layer "F.SilkS")
		)
		(fp_line
			(start 0.7874 0.4064)
			(end -0.7874 0.4064)
			(stroke
				(width 0.1524)
				(type default)
			)
			(layer "F.SilkS")
		)
		(fp_line
			(start -0.7874 0.4064)
			(end -0.7874 -0.4064)
			(stroke
				(width 0.1524)
				(type default)
			)
			(layer "F.SilkS")
		)
		(fp_line
			(start -0.12065 -0.305054)
			(end -0.12065 -0.2794)
			(stroke
				(width 0.1)
				(type default)
			)
			(layer "F.Fab")
		)
		(fp_line
			(start -0.67945 -0.305054)
			(end -0.12065 -0.305054)
			(stroke
				(width 0.1)
				(type default)
			)
			(layer "F.Fab")
		)
		(fp_line
			(start 0.67945 -0.3048)
			(end 0.67945 0.3048)
			(stroke
				(width 0.1)
				(type default)
			)
			(layer "F.Fab")
		)
		(fp_line
			(start 0.12065 -0.3048)
			(end 0.67945 -0.3048)
			(stroke
				(width 0.1)
				(type default)
			)
			(layer "F.Fab")
		)
		(fp_line
			(start 0.12065 -0.2794)
			(end 0.12065 -0.3048)
			(stroke
				(width 0.1)
				(type default)
			)
			(layer "F.Fab")
		)
		(fp_line
			(start -0.12065 -0.2794)
			(end 0.12065 -0.2794)
			(stroke
				(width 0.1)
				(type default)
			)
			(layer "F.Fab")
		)
		(fp_line
			(start 0.120396 0.2794)
			(end -0.12065 0.2794)
			(stroke
				(width 0.1)
				(type default)
			)
			(layer "F.Fab")
		)
		(fp_line
			(start -0.12065 0.2794)
			(end -0.12065 0.3048)
			(stroke
				(width 0.1)
				(type default)
			)
			(layer "F.Fab")
		)
		(fp_line
			(start 0.67945 0.3048)
			(end 0.120396 0.3048)
			(stroke
				(width 0.1)
				(type default)
			)
			(layer "F.Fab")
		)
		(fp_line
			(start 0.120396 0.3048)
			(end 0.120396 0.2794)
			(stroke
				(width 0.1)
				(type default)
			)
			(layer "F.Fab")
		)
		(fp_line
			(start -0.12065 0.3048)
			(end -0.67945 0.3048)
			(stroke
				(width 0.1)
				(type default)
			)
			(layer "F.Fab")
		)
		(fp_line
			(start -0.67945 0.3048)
			(end -0.67945 -0.305054)
			(stroke
				(width 0.1)
				(type default)
			)
			(layer "F.Fab")
		)
		(pad "1" smd circle
			(at -0.40005 0 90)
			(size 0 0)
			(layers "F.Cu" "F.Mask" "F.Paste")
			(net "P12V_E1S_OV_0")
		)
		(pad "2" smd circle
			(at 0.40005 0 90)
			(size 0 0)
			(layers "F.Cu" "F.Mask" "F.Paste")
			(net "GND")
		)
	)
	(footprint ""
		(layer "F.Cu")
		(at 50.98288 -434.812948 90)
		(property "Reference" "R2894"
			(at 0 0 90)
			(layer "F.SilkS")
			(hide yes)
			(effects
				(font
					(size 1.27 1.27)
				)
			)
		)
		(property "Value" ""
			(at 0 0 90)
			(layer "F.Fab")
			(effects
				(font
					(size 1.27 1.27)
				)
			)
		)
		(duplicate_pad_numbers_are_jumpers no)
		(fp_line
			(start 0.7874 -0.4064)
			(end 0.7874 0.4064)
			(stroke
				(width 0.1524)
				(type default)
			)
			(layer "F.SilkS")
		)
		(fp_line
			(start -0.7874 -0.4064)
			(end 0.7874 -0.4064)
			(stroke
				(width 0.1524)
				(type default)
			)
			(layer "F.SilkS")
		)
		(fp_line
			(start 0.7874 0.4064)
			(end -0.7874 0.4064)
			(stroke
				(width 0.1524)
				(type default)
			)
			(layer "F.SilkS")
		)
		(fp_line
			(start -0.7874 0.4064)
			(end -0.7874 -0.4064)
			(stroke
				(width 0.1524)
				(type default)
			)
			(layer "F.SilkS")
		)
		(fp_line
			(start -0.12065 -0.305054)
			(end -0.12065 -0.2794)
			(stroke
				(width 0.1)
				(type default)
			)
			(layer "F.Fab")
		)
		(fp_line
			(start -0.67945 -0.305054)
			(end -0.12065 -0.305054)
			(stroke
				(width 0.1)
				(type default)
			)
			(layer "F.Fab")
		)
		(fp_line
			(start 0.67945 -0.3048)
			(end 0.67945 0.3048)
			(stroke
				(width 0.1)
				(type default)
			)
			(layer "F.Fab")
		)
		(fp_line
			(start 0.12065 -0.3048)
			(end 0.67945 -0.3048)
			(stroke
				(width 0.1)
				(type default)
			)
			(layer "F.Fab")
		)
		(fp_line
			(start 0.12065 -0.2794)
			(end 0.12065 -0.3048)
			(stroke
				(width 0.1)
				(type default)
			)
			(layer "F.Fab")
		)
		(fp_line
			(start -0.12065 -0.2794)
			(end 0.12065 -0.2794)
			(stroke
				(width 0.1)
				(type default)
			)
			(layer "F.Fab")
		)
		(fp_line
			(start 0.120396 0.2794)
			(end -0.12065 0.2794)
			(stroke
				(width 0.1)
				(type default)
			)
			(layer "F.Fab")
		)
		(fp_line
			(start -0.12065 0.2794)
			(end -0.12065 0.3048)
			(stroke
				(width 0.1)
				(type default)
			)
			(layer "F.Fab")
		)
		(fp_line
			(start 0.67945 0.3048)
			(end 0.120396 0.3048)
			(stroke
				(width 0.1)
				(type default)
			)
			(layer "F.Fab")
		)
		(fp_line
			(start 0.120396 0.3048)
			(end 0.120396 0.2794)
			(stroke
				(width 0.1)
				(type default)
			)
			(layer "F.Fab")
		)
		(fp_line
			(start -0.12065 0.3048)
			(end -0.67945 0.3048)
			(stroke
				(width 0.1)
				(type default)
			)
			(layer "F.Fab")
		)
		(fp_line
			(start -0.67945 0.3048)
			(end -0.67945 -0.305054)
			(stroke
				(width 0.1)
				(type default)
			)
			(layer "F.Fab")
		)
		(pad "1" smd circle
			(at -0.40005 0 90)
			(size 0 0)
			(layers "F.Cu" "F.Mask" "F.Paste")
			(net "SMB_1_BMC_GPU_R_SDA")
		)
		(pad "2" smd circle
			(at 0.40005 0 90)
			(size 0 0)
			(layers "F.Cu" "F.Mask" "F.Paste")
			(net "SMB_1_BMC_GPU_BUF_R_SDA")
		)
	)
	(footprint ""
		(layer "F.Cu")
		(at 50.43551 -148.536914 180)
		(property "Reference" "PR1795"
			(at 0 0 180)
			(layer "F.SilkS")
			(hide yes)
			(effects
				(font
					(size 1.27 1.27)
				)
			)
		)
		(property "Value" ""
			(at 0 0 180)
			(layer "F.Fab")
			(effects
				(font
					(size 1.27 1.27)
				)
			)
		)
		(duplicate_pad_numbers_are_jumpers no)
		(fp_line
			(start 0.7874 0.4064)
			(end -0.7874 0.4064)
			(stroke
				(width 0.1524)
				(type default)
			)
			(layer "F.SilkS")
		)
		(fp_line
			(start 0.7874 -0.4064)
			(end 0.7874 0.4064)
			(stroke
				(width 0.1524)
				(type default)
			)
			(layer "F.SilkS")
		)
		(fp_line
			(start -0.7874 0.4064)
			(end -0.7874 -0.4064)
			(stroke
				(width 0.1524)
				(type default)
			)
			(layer "F.SilkS")
		)
		(fp_line
			(start -0.7874 -0.4064)
			(end 0.7874 -0.4064)
			(stroke
				(width 0.1524)
				(type default)
			)
			(layer "F.SilkS")
		)
		(fp_line
			(start 0.67945 0.3048)
			(end 0.120396 0.3048)
			(stroke
				(width 0.1)
				(type default)
			)
			(layer "F.Fab")
		)
		(fp_line
			(start 0.67945 -0.3048)
			(end 0.67945 0.3048)
			(stroke
				(width 0.1)
				(type default)
			)
			(layer "F.Fab")
		)
		(fp_line
			(start 0.12065 -0.2794)
			(end 0.12065 -0.3048)
			(stroke
				(width 0.1)
				(type default)
			)
			(layer "F.Fab")
		)
		(fp_line
			(start 0.12065 -0.3048)
			(end 0.67945 -0.3048)
			(stroke
				(width 0.1)
				(type default)
			)
			(layer "F.Fab")
		)
		(fp_line
			(start 0.120396 0.3048)
			(end 0.120396 0.2794)
			(stroke
				(width 0.1)
				(type default)
			)
			(layer "F.Fab")
		)
		(fp_line
			(start 0.120396 0.2794)
			(end -0.12065 0.2794)
			(stroke
				(width 0.1)
				(type default)
			)
			(layer "F.Fab")
		)
		(fp_line
			(start -0.12065 0.3048)
			(end -0.67945 0.3048)
			(stroke
				(width 0.1)
				(type default)
			)
			(layer "F.Fab")
		)
		(fp_line
			(start -0.12065 0.2794)
			(end -0.12065 0.3048)
			(stroke
				(width 0.1)
				(type default)
			)
			(layer "F.Fab")
		)
		(fp_line
			(start -0.12065 -0.2794)
			(end 0.12065 -0.2794)
			(stroke
				(width 0.1)
				(type default)
			)
			(layer "F.Fab")
		)
		(fp_line
			(start -0.12065 -0.305054)
			(end -0.12065 -0.2794)
			(stroke
				(width 0.1)
				(type default)
			)
			(layer "F.Fab")
		)
		(fp_line
			(start -0.67945 0.3048)
			(end -0.67945 -0.305054)
			(stroke
				(width 0.1)
				(type default)
			)
			(layer "F.Fab")
		)
		(fp_line
			(start -0.67945 -0.305054)
			(end -0.12065 -0.305054)
			(stroke
				(width 0.1)
				(type default)
			)
			(layer "F.Fab")
		)
		(pad "1" smd circle
			(at -0.40005 0 180)
			(size 0 0)
			(layers "F.Cu" "F.Mask" "F.Paste")
			(net "SW_PVCCINFAON_CPU1_BOOT2")
		)
		(pad "2" smd circle
			(at 0.40005 0 180)
			(size 0 0)
			(layers "F.Cu" "F.Mask" "F.Paste")
			(net "SW_PVCCINFAON_CPU1_BOOT2_R")
		)
	)
	(footprint ""
		(layer "F.Cu")
		(at 179.352448 -400.223482 180)
		(property "Reference" "PR1131"
			(at 0 0 180)
			(layer "F.SilkS")
			(hide yes)
			(effects
				(font
					(size 1.27 1.27)
				)
			)
		)
		(property "Value" ""
			(at 0 0 180)
			(layer "F.Fab")
			(effects
				(font
					(size 1.27 1.27)
				)
			)
		)
		(duplicate_pad_numbers_are_jumpers no)
		(fp_line
			(start 0.7874 0.4064)
			(end -0.7874 0.4064)
			(stroke
				(width 0.1524)
				(type default)
			)
			(layer "F.SilkS")
		)
		(fp_line
			(start 0.7874 -0.4064)
			(end 0.7874 0.4064)
			(stroke
				(width 0.1524)
				(type default)
			)
			(layer "F.SilkS")
		)
		(fp_line
			(start -0.7874 0.4064)
			(end -0.7874 -0.4064)
			(stroke
				(width 0.1524)
				(type default)
			)
			(layer "F.SilkS")
		)
		(fp_line
			(start -0.7874 -0.4064)
			(end 0.7874 -0.4064)
			(stroke
				(width 0.1524)
				(type default)
			)
			(layer "F.SilkS")
		)
		(fp_line
			(start 0.67945 0.3048)
			(end 0.120396 0.3048)
			(stroke
				(width 0.1)
				(type default)
			)
			(layer "F.Fab")
		)
		(fp_line
			(start 0.67945 -0.3048)
			(end 0.67945 0.3048)
			(stroke
				(width 0.1)
				(type default)
			)
			(layer "F.Fab")
		)
		(fp_line
			(start 0.12065 -0.2794)
			(end 0.12065 -0.3048)
			(stroke
				(width 0.1)
				(type default)
			)
			(layer "F.Fab")
		)
		(fp_line
			(start 0.12065 -0.3048)
			(end 0.67945 -0.3048)
			(stroke
				(width 0.1)
				(type default)
			)
			(layer "F.Fab")
		)
		(fp_line
			(start 0.120396 0.3048)
			(end 0.120396 0.2794)
			(stroke
				(width 0.1)
				(type default)
			)
			(layer "F.Fab")
		)
		(fp_line
			(start 0.120396 0.2794)
			(end -0.12065 0.2794)
			(stroke
				(width 0.1)
				(type default)
			)
			(layer "F.Fab")
		)
		(fp_line
			(start -0.12065 0.3048)
			(end -0.67945 0.3048)
			(stroke
				(width 0.1)
				(type default)
			)
			(layer "F.Fab")
		)
		(fp_line
			(start -0.12065 0.2794)
			(end -0.12065 0.3048)
			(stroke
				(width 0.1)
				(type default)
			)
			(layer "F.Fab")
		)
		(fp_line
			(start -0.12065 -0.2794)
			(end 0.12065 -0.2794)
			(stroke
				(width 0.1)
				(type default)
			)
			(layer "F.Fab")
		)
		(fp_line
			(start -0.12065 -0.305054)
			(end -0.12065 -0.2794)
			(stroke
				(width 0.1)
				(type default)
			)
			(layer "F.Fab")
		)
		(fp_line
			(start -0.67945 0.3048)
			(end -0.67945 -0.305054)
			(stroke
				(width 0.1)
				(type default)
			)
			(layer "F.Fab")
		)
		(fp_line
			(start -0.67945 -0.305054)
			(end -0.12065 -0.305054)
			(stroke
				(width 0.1)
				(type default)
			)
			(layer "F.Fab")
		)
		(pad "1" smd circle
			(at -0.40005 0 180)
			(size 0 0)
			(layers "F.Cu" "F.Mask" "F.Paste")
			(net "HSC_CS")
		)
		(pad "2" smd circle
			(at 0.40005 0 180)
			(size 0 0)
			(layers "F.Cu" "F.Mask" "F.Paste")
			(net "AGND_HSC")
		)
	)
	(footprint ""
		(layer "F.Cu")
		(at 417.83762 -48.53178 -90)
		(property "Reference" "U99"
			(at 3.965702 1.35382 0)
			(unlocked yes)
			(layer "F.SilkS")
			(effects
				(font
					(size 0.7874 0.5842)
					(thickness 0.1524)
				)
				(justify left)
			)
		)
		(property "Value" ""
			(at 0 0 270)
			(layer "F.Fab")
			(effects
				(font
					(size 1.27 1.27)
				)
			)
		)
		(duplicate_pad_numbers_are_jumpers no)
		(fp_line
			(start -1.934972 1.5494)
			(end -1.934972 -1.5494)
			(stroke
				(width 0.1524)
				(type default)
			)
			(layer "F.SilkS")
		)
		(fp_line
			(start 1.934972 1.5494)
			(end -1.934972 1.5494)
			(stroke
				(width 0.1524)
				(type default)
			)
			(layer "F.SilkS")
		)
		(fp_line
			(start -1.934972 -1.5494)
			(end 1.934972 -1.5494)
			(stroke
				(width 0.1524)
				(type default)
			)
			(layer "F.SilkS")
		)
		(fp_line
			(start 1.934972 -1.5494)
			(end 1.934972 1.5494)
			(stroke
				(width 0.1524)
				(type default)
			)
			(layer "F.SilkS")
		)
		(fp_line
			(start -0.901446 1.5494)
			(end -0.901446 -1.5494)
			(stroke
				(width 0.1)
				(type default)
			)
			(layer "F.Fab")
		)
		(fp_line
			(start 0.901446 1.5494)
			(end -0.901446 1.5494)
			(stroke
				(width 0.1)
				(type default)
			)
			(layer "F.Fab")
		)
		(fp_line
			(start -0.901446 -1.5494)
			(end 0.901446 -1.5494)
			(stroke
				(width 0.1)
				(type default)
			)
			(layer "F.Fab")
		)
		(fp_line
			(start 0.901446 -1.5494)
			(end 0.901446 1.5494)
			(stroke
				(width 0.1)
				(type default)
			)
			(layer "F.Fab")
		)
		(pad "1" smd rect
			(at -1.299972 -0.94996 180)
			(size 0.8128 1.016)
			(layers "F.Cu" "F.Mask" "F.Paste")
			(net "PWRGD_P5V")
		)
		(pad "2" smd rect
			(at -1.299972 0.94996 180)
			(size 0.8128 1.016)
			(layers "F.Cu" "F.Mask" "F.Paste")
			(net "GND")
		)
		(pad "3" smd rect
			(at 1.299972 0 180)
			(size 0.8128 1.016)
			(layers "F.Cu" "F.Mask" "F.Paste")
			(net "P5V")
		)
	)
	(footprint ""
		(layer "F.Cu")
		(at 9.652 -48.986948)
		(property "Reference" "R3053"
			(at 0 0 0)
			(layer "F.SilkS")
			(hide yes)
			(effects
				(font
					(size 1.27 1.27)
				)
			)
		)
		(property "Value" ""
			(at 0 0 0)
			(layer "F.Fab")
			(effects
				(font
					(size 1.27 1.27)
				)
			)
		)
		(duplicate_pad_numbers_are_jumpers no)
		(fp_line
			(start -0.7874 -0.4064)
			(end 0.7874 -0.4064)
			(stroke
				(width 0.1524)
				(type default)
			)
			(layer "F.SilkS")
		)
		(fp_line
			(start -0.7874 0.4064)
			(end -0.7874 -0.4064)
			(stroke
				(width 0.1524)
				(type default)
			)
			(layer "F.SilkS")
		)
		(fp_line
			(start 0.7874 -0.4064)
			(end 0.7874 0.4064)
			(stroke
				(width 0.1524)
				(type default)
			)
			(layer "F.SilkS")
		)
		(fp_line
			(start 0.7874 0.4064)
			(end -0.7874 0.4064)
			(stroke
				(width 0.1524)
				(type default)
			)
			(layer "F.SilkS")
		)
		(fp_line
			(start -0.67945 -0.305054)
			(end -0.12065 -0.305054)
			(stroke
				(width 0.1)
				(type default)
			)
			(layer "F.Fab")
		)
		(fp_line
			(start -0.67945 0.3048)
			(end -0.67945 -0.305054)
			(stroke
				(width 0.1)
				(type default)
			)
			(layer "F.Fab")
		)
		(fp_line
			(start -0.12065 -0.305054)
			(end -0.12065 -0.2794)
			(stroke
				(width 0.1)
				(type default)
			)
			(layer "F.Fab")
		)
		(fp_line
			(start -0.12065 -0.2794)
			(end 0.12065 -0.2794)
			(stroke
				(width 0.1)
				(type default)
			)
			(layer "F.Fab")
		)
		(fp_line
			(start -0.12065 0.2794)
			(end -0.12065 0.3048)
			(stroke
				(width 0.1)
				(type default)
			)
			(layer "F.Fab")
		)
		(fp_line
			(start -0.12065 0.3048)
			(end -0.67945 0.3048)
			(stroke
				(width 0.1)
				(type default)
			)
			(layer "F.Fab")
		)
		(fp_line
			(start 0.120396 0.2794)
			(end -0.12065 0.2794)
			(stroke
				(width 0.1)
				(type default)
			)
			(layer "F.Fab")
		)
		(fp_line
			(start 0.120396 0.3048)
			(end 0.120396 0.2794)
			(stroke
				(width 0.1)
				(type default)
			)
			(layer "F.Fab")
		)
		(fp_line
			(start 0.12065 -0.3048)
			(end 0.67945 -0.3048)
			(stroke
				(width 0.1)
				(type default)
			)
			(layer "F.Fab")
		)
		(fp_line
			(start 0.12065 -0.2794)
			(end 0.12065 -0.3048)
			(stroke
				(width 0.1)
				(type default)
			)
			(layer "F.Fab")
		)
		(fp_line
			(start 0.67945 -0.3048)
			(end 0.67945 0.3048)
			(stroke
				(width 0.1)
				(type default)
			)
			(layer "F.Fab")
		)
		(fp_line
			(start 0.67945 0.3048)
			(end 0.120396 0.3048)
			(stroke
				(width 0.1)
				(type default)
			)
			(layer "F.Fab")
		)
		(pad "1" smd circle
			(at -0.40005 0)
			(size 0 0)
			(layers "F.Cu" "F.Mask" "F.Paste")
			(net "SMB_HOST_3V3AUX_SDA_R5")
		)
		(pad "2" smd circle
			(at 0.40005 0)
			(size 0 0)
			(layers "F.Cu" "F.Mask" "F.Paste")
			(net "SMB_HOST_ME_SDA")
		)
	)
	(footprint ""
		(layer "F.Cu")
		(at 156.37129 -81.90357 -90)
		(property "Reference" "R3222"
			(at 0 0 270)
			(layer "F.SilkS")
			(hide yes)
			(effects
				(font
					(size 1.27 1.27)
				)
			)
		)
		(property "Value" ""
			(at 0 0 270)
			(layer "F.Fab")
			(effects
				(font
					(size 1.27 1.27)
				)
			)
		)
		(duplicate_pad_numbers_are_jumpers no)
		(fp_line
			(start -0.7874 0.4064)
			(end -0.7874 -0.4064)
			(stroke
				(width 0.1524)
				(type default)
			)
			(layer "F.SilkS")
		)
		(fp_line
			(start 0.7874 0.4064)
			(end -0.7874 0.4064)
			(stroke
				(width 0.1524)
				(type default)
			)
			(layer "F.SilkS")
		)
		(fp_line
			(start -0.7874 -0.4064)
			(end 0.7874 -0.4064)
			(stroke
				(width 0.1524)
				(type default)
			)
			(layer "F.SilkS")
		)
		(fp_line
			(start 0.7874 -0.4064)
			(end 0.7874 0.4064)
			(stroke
				(width 0.1524)
				(type default)
			)
			(layer "F.SilkS")
		)
		(fp_line
			(start -0.67945 0.3048)
			(end -0.67945 -0.305054)
			(stroke
				(width 0.1)
				(type default)
			)
			(layer "F.Fab")
		)
		(fp_line
			(start -0.12065 0.3048)
			(end -0.67945 0.3048)
			(stroke
				(width 0.1)
				(type default)
			)
			(layer "F.Fab")
		)
		(fp_line
			(start 0.120396 0.3048)
			(end 0.120396 0.2794)
			(stroke
				(width 0.1)
				(type default)
			)
			(layer "F.Fab")
		)
		(fp_line
			(start 0.67945 0.3048)
			(end 0.120396 0.3048)
			(stroke
				(width 0.1)
				(type default)
			)
			(layer "F.Fab")
		)
		(fp_line
			(start -0.12065 0.2794)
			(end -0.12065 0.3048)
			(stroke
				(width 0.1)
				(type default)
			)
			(layer "F.Fab")
		)
		(fp_line
			(start 0.120396 0.2794)
			(end -0.12065 0.2794)
			(stroke
				(width 0.1)
				(type default)
			)
			(layer "F.Fab")
		)
		(fp_line
			(start -0.12065 -0.2794)
			(end 0.12065 -0.2794)
			(stroke
				(width 0.1)
				(type default)
			)
			(layer "F.Fab")
		)
		(fp_line
			(start 0.12065 -0.2794)
			(end 0.12065 -0.3048)
			(stroke
				(width 0.1)
				(type default)
			)
			(layer "F.Fab")
		)
		(fp_line
			(start 0.12065 -0.3048)
			(end 0.67945 -0.3048)
			(stroke
				(width 0.1)
				(type default)
			)
			(layer "F.Fab")
		)
		(fp_line
			(start 0.67945 -0.3048)
			(end 0.67945 0.3048)
			(stroke
				(width 0.1)
				(type default)
			)
			(layer "F.Fab")
		)
		(fp_line
			(start -0.67945 -0.305054)
			(end -0.12065 -0.305054)
			(stroke
				(width 0.1)
				(type default)
			)
			(layer "F.Fab")
		)
		(fp_line
			(start -0.12065 -0.305054)
			(end -0.12065 -0.2794)
			(stroke
				(width 0.1)
				(type default)
			)
			(layer "F.Fab")
		)
		(pad "1" smd circle
			(at -0.40005 0 270)
			(size 0 0)
			(layers "F.Cu" "F.Mask" "F.Paste")
			(net "SMB_S3M_CPU0_PIROM_3V3AUX_SCL")
		)
		(pad "2" smd circle
			(at 0.40005 0 270)
			(size 0 0)
			(layers "F.Cu" "F.Mask" "F.Paste")
			(net "P3V3_AUX")
		)
	)
	(footprint ""
		(layer "F.Cu")
		(at 136.07288 -92.674948 90)
		(property "Reference" "R4406"
			(at 0 0 90)
			(layer "F.SilkS")
			(hide yes)
			(effects
				(font
					(size 1.27 1.27)
				)
			)
		)
		(property "Value" ""
			(at 0 0 90)
			(layer "F.Fab")
			(effects
				(font
					(size 1.27 1.27)
				)
			)
		)
		(duplicate_pad_numbers_are_jumpers no)
		(fp_line
			(start 0.7874 -0.4064)
			(end 0.7874 0.4064)
			(stroke
				(width 0.1524)
				(type default)
			)
			(layer "F.SilkS")
		)
		(fp_line
			(start -0.7874 -0.4064)
			(end 0.7874 -0.4064)
			(stroke
				(width 0.1524)
				(type default)
			)
			(layer "F.SilkS")
		)
		(fp_line
			(start 0.7874 0.4064)
			(end -0.7874 0.4064)
			(stroke
				(width 0.1524)
				(type default)
			)
			(layer "F.SilkS")
		)
		(fp_line
			(start -0.7874 0.4064)
			(end -0.7874 -0.4064)
			(stroke
				(width 0.1524)
				(type default)
			)
			(layer "F.SilkS")
		)
		(fp_line
			(start -0.12065 -0.305054)
			(end -0.12065 -0.2794)
			(stroke
				(width 0.1)
				(type default)
			)
			(layer "F.Fab")
		)
		(fp_line
			(start -0.67945 -0.305054)
			(end -0.12065 -0.305054)
			(stroke
				(width 0.1)
				(type default)
			)
			(layer "F.Fab")
		)
		(fp_line
			(start 0.67945 -0.3048)
			(end 0.67945 0.3048)
			(stroke
				(width 0.1)
				(type default)
			)
			(layer "F.Fab")
		)
		(fp_line
			(start 0.12065 -0.3048)
			(end 0.67945 -0.3048)
			(stroke
				(width 0.1)
				(type default)
			)
			(layer "F.Fab")
		)
		(fp_line
			(start 0.12065 -0.2794)
			(end 0.12065 -0.3048)
			(stroke
				(width 0.1)
				(type default)
			)
			(layer "F.Fab")
		)
		(fp_line
			(start -0.12065 -0.2794)
			(end 0.12065 -0.2794)
			(stroke
				(width 0.1)
				(type default)
			)
			(layer "F.Fab")
		)
		(fp_line
			(start 0.120396 0.2794)
			(end -0.12065 0.2794)
			(stroke
				(width 0.1)
				(type default)
			)
			(layer "F.Fab")
		)
		(fp_line
			(start -0.12065 0.2794)
			(end -0.12065 0.3048)
			(stroke
				(width 0.1)
				(type default)
			)
			(layer "F.Fab")
		)
		(fp_line
			(start 0.67945 0.3048)
			(end 0.120396 0.3048)
			(stroke
				(width 0.1)
				(type default)
			)
			(layer "F.Fab")
		)
		(fp_line
			(start 0.120396 0.3048)
			(end 0.120396 0.2794)
			(stroke
				(width 0.1)
				(type default)
			)
			(layer "F.Fab")
		)
		(fp_line
			(start -0.12065 0.3048)
			(end -0.67945 0.3048)
			(stroke
				(width 0.1)
				(type default)
			)
			(layer "F.Fab")
		)
		(fp_line
			(start -0.67945 0.3048)
			(end -0.67945 -0.305054)
			(stroke
				(width 0.1)
				(type default)
			)
			(layer "F.Fab")
		)
		(pad "1" smd circle
			(at -0.40005 0 90)
			(size 0 0)
			(layers "F.Cu" "F.Mask" "F.Paste")
			(net "P3V3")
		)
		(pad "2" smd circle
			(at 0.40005 0 90)
			(size 0 0)
			(layers "F.Cu" "F.Mask" "F.Paste")
			(net "H_CPU1_MEMHOT_OUT_VT_N")
		)
	)
	(footprint ""
		(layer "F.Cu")
		(at 426.677836 -17.612614 90)
		(property "Reference" "C864"
			(at 0 0 90)
			(layer "F.SilkS")
			(hide yes)
			(effects
				(font
					(size 1.27 1.27)
				)
			)
		)
		(property "Value" ""
			(at 0 0 90)
			(layer "F.Fab")
			(effects
				(font
					(size 1.27 1.27)
				)
			)
		)
		(duplicate_pad_numbers_are_jumpers no)
		(fp_line
			(start 0.299974 -0.150114)
			(end 0.299974 0.150114)
			(stroke
				(width 0.1)
				(type default)
			)
			(layer "F.Fab")
		)
		(fp_line
			(start -0.299974 -0.150114)
			(end 0.299974 -0.150114)
			(stroke
				(width 0.1)
				(type default)
			)
			(layer "F.Fab")
		)
		(fp_line
			(start 0.299974 0.150114)
			(end -0.299974 0.150114)
			(stroke
				(width 0.1)
				(type default)
			)
			(layer "F.Fab")
		)
		(fp_line
			(start -0.299974 0.150114)
			(end -0.299974 -0.150114)
			(stroke
				(width 0.1)
				(type default)
			)
			(layer "F.Fab")
		)
		(pad "1" smd rect
			(at -0.2667 0 90)
			(size 0.3048 0.381)
			(layers "F.Cu" "F.Mask" "F.Paste")
			(net "P5E_CPU0_PE1_TX_C_DN<2>")
		)
		(pad "2" smd rect
			(at 0.2667 0 90)
			(size 0.3048 0.381)
			(layers "F.Cu" "F.Mask" "F.Paste")
			(net "P5E_CPU0_PE1_TX_DN<2>")
		)
	)
	(footprint ""
		(layer "F.Cu")
		(at 354.262944 -240.276888 90)
		(property "Reference" "C1031"
			(at 0 0 90)
			(layer "F.SilkS")
			(hide yes)
			(effects
				(font
					(size 1.27 1.27)
				)
			)
		)
		(property "Value" ""
			(at 0 0 90)
			(layer "F.Fab")
			(effects
				(font
					(size 1.27 1.27)
				)
			)
		)
		(duplicate_pad_numbers_are_jumpers no)
		(fp_line
			(start 0.7874 -0.4064)
			(end 0.7874 0.4064)
			(stroke
				(width 0.1524)
				(type default)
			)
			(layer "F.SilkS")
		)
		(fp_line
			(start -0.7874 -0.4064)
			(end 0.7874 -0.4064)
			(stroke
				(width 0.1524)
				(type default)
			)
			(layer "F.SilkS")
		)
		(fp_line
			(start 0.7874 0.4064)
			(end -0.7874 0.4064)
			(stroke
				(width 0.1524)
				(type default)
			)
			(layer "F.SilkS")
		)
		(fp_line
			(start -0.7874 0.4064)
			(end -0.7874 -0.4064)
			(stroke
				(width 0.1524)
				(type default)
			)
			(layer "F.SilkS")
		)
		(fp_line
			(start -0.12065 -0.305054)
			(end -0.12065 -0.2794)
			(stroke
				(width 0.1)
				(type default)
			)
			(layer "F.Fab")
		)
		(fp_line
			(start -0.67945 -0.305054)
			(end -0.12065 -0.305054)
			(stroke
				(width 0.1)
				(type default)
			)
			(layer "F.Fab")
		)
		(fp_line
			(start 0.67945 -0.3048)
			(end 0.67945 0.3048)
			(stroke
				(width 0.1)
				(type default)
			)
			(layer "F.Fab")
		)
		(fp_line
			(start 0.12065 -0.3048)
			(end 0.67945 -0.3048)
			(stroke
				(width 0.1)
				(type default)
			)
			(layer "F.Fab")
		)
		(fp_line
			(start 0.12065 -0.2794)
			(end 0.12065 -0.3048)
			(stroke
				(width 0.1)
				(type default)
			)
			(layer "F.Fab")
		)
		(fp_line
			(start -0.12065 -0.2794)
			(end 0.12065 -0.2794)
			(stroke
				(width 0.1)
				(type default)
			)
			(layer "F.Fab")
		)
		(fp_line
			(start 0.120396 0.2794)
			(end -0.12065 0.2794)
			(stroke
				(width 0.1)
				(type default)
			)
			(layer "F.Fab")
		)
		(fp_line
			(start -0.12065 0.2794)
			(end -0.12065 0.3048)
			(stroke
				(width 0.1)
				(type default)
			)
			(layer "F.Fab")
		)
		(fp_line
			(start 0.67945 0.3048)
			(end 0.120396 0.3048)
			(stroke
				(width 0.1)
				(type default)
			)
			(layer "F.Fab")
		)
		(fp_line
			(start 0.120396 0.3048)
			(end 0.120396 0.2794)
			(stroke
				(width 0.1)
				(type default)
			)
			(layer "F.Fab")
		)
		(fp_line
			(start -0.12065 0.3048)
			(end -0.67945 0.3048)
			(stroke
				(width 0.1)
				(type default)
			)
			(layer "F.Fab")
		)
		(fp_line
			(start -0.67945 0.3048)
			(end -0.67945 -0.305054)
			(stroke
				(width 0.1)
				(type default)
			)
			(layer "F.Fab")
		)
		(pad "1" smd circle
			(at -0.40005 0 90)
			(size 0 0)
			(layers "F.Cu" "F.Mask" "F.Paste")
			(net "PVCCIN_CPU0")
		)
		(pad "2" smd circle
			(at 0.40005 0 90)
			(size 0 0)
			(layers "F.Cu" "F.Mask" "F.Paste")
			(net "GND")
		)
	)
	(footprint ""
		(layer "F.Cu")
		(at 192.58788 -112.613948 90)
		(property "Reference" "R1100"
			(at 0 0 90)
			(layer "F.SilkS")
			(hide yes)
			(effects
				(font
					(size 1.27 1.27)
				)
			)
		)
		(property "Value" ""
			(at 0 0 90)
			(layer "F.Fab")
			(effects
				(font
					(size 1.27 1.27)
				)
			)
		)
		(duplicate_pad_numbers_are_jumpers no)
		(fp_line
			(start 0.7874 -0.4064)
			(end 0.7874 0.4064)
			(stroke
				(width 0.1524)
				(type default)
			)
			(layer "F.SilkS")
		)
		(fp_line
			(start -0.7874 -0.4064)
			(end 0.7874 -0.4064)
			(stroke
				(width 0.1524)
				(type default)
			)
			(layer "F.SilkS")
		)
		(fp_line
			(start 0.7874 0.4064)
			(end -0.7874 0.4064)
			(stroke
				(width 0.1524)
				(type default)
			)
			(layer "F.SilkS")
		)
		(fp_line
			(start -0.7874 0.4064)
			(end -0.7874 -0.4064)
			(stroke
				(width 0.1524)
				(type default)
			)
			(layer "F.SilkS")
		)
		(fp_line
			(start -0.12065 -0.305054)
			(end -0.12065 -0.2794)
			(stroke
				(width 0.1)
				(type default)
			)
			(layer "F.Fab")
		)
		(fp_line
			(start -0.67945 -0.305054)
			(end -0.12065 -0.305054)
			(stroke
				(width 0.1)
				(type default)
			)
			(layer "F.Fab")
		)
		(fp_line
			(start 0.67945 -0.3048)
			(end 0.67945 0.3048)
			(stroke
				(width 0.1)
				(type default)
			)
			(layer "F.Fab")
		)
		(fp_line
			(start 0.12065 -0.3048)
			(end 0.67945 -0.3048)
			(stroke
				(width 0.1)
				(type default)
			)
			(layer "F.Fab")
		)
		(fp_line
			(start 0.12065 -0.2794)
			(end 0.12065 -0.3048)
			(stroke
				(width 0.1)
				(type default)
			)
			(layer "F.Fab")
		)
		(fp_line
			(start -0.12065 -0.2794)
			(end 0.12065 -0.2794)
			(stroke
				(width 0.1)
				(type default)
			)
			(layer "F.Fab")
		)
		(fp_line
			(start 0.120396 0.2794)
			(end -0.12065 0.2794)
			(stroke
				(width 0.1)
				(type default)
			)
			(layer "F.Fab")
		)
		(fp_line
			(start -0.12065 0.2794)
			(end -0.12065 0.3048)
			(stroke
				(width 0.1)
				(type default)
			)
			(layer "F.Fab")
		)
		(fp_line
			(start 0.67945 0.3048)
			(end 0.120396 0.3048)
			(stroke
				(width 0.1)
				(type default)
			)
			(layer "F.Fab")
		)
		(fp_line
			(start 0.120396 0.3048)
			(end 0.120396 0.2794)
			(stroke
				(width 0.1)
				(type default)
			)
			(layer "F.Fab")
		)
		(fp_line
			(start -0.12065 0.3048)
			(end -0.67945 0.3048)
			(stroke
				(width 0.1)
				(type default)
			)
			(layer "F.Fab")
		)
		(fp_line
			(start -0.67945 0.3048)
			(end -0.67945 -0.305054)
			(stroke
				(width 0.1)
				(type default)
			)
			(layer "F.Fab")
		)
		(pad "1" smd circle
			(at -0.40005 0 90)
			(size 0 0)
			(layers "F.Cu" "F.Mask" "F.Paste")
			(net "CLK_25M_OSC_FPGA_R")
		)
		(pad "2" smd circle
			(at 0.40005 0 90)
			(size 0 0)
			(layers "F.Cu" "F.Mask" "F.Paste")
			(net "CLK_25M_OSC_MAIN_FPGA")
		)
	)
	(footprint ""
		(layer "F.Cu")
		(at 176.17948 -423.382948)
		(property "Reference" "R2924"
			(at 0 0 0)
			(layer "F.SilkS")
			(hide yes)
			(effects
				(font
					(size 1.27 1.27)
				)
			)
		)
		(property "Value" ""
			(at 0 0 0)
			(layer "F.Fab")
			(effects
				(font
					(size 1.27 1.27)
				)
			)
		)
		(duplicate_pad_numbers_are_jumpers no)
		(fp_line
			(start -0.7874 -0.4064)
			(end 0.7874 -0.4064)
			(stroke
				(width 0.1524)
				(type default)
			)
			(layer "F.SilkS")
		)
		(fp_line
			(start -0.7874 0.4064)
			(end -0.7874 -0.4064)
			(stroke
				(width 0.1524)
				(type default)
			)
			(layer "F.SilkS")
		)
		(fp_line
			(start 0.7874 -0.4064)
			(end 0.7874 0.4064)
			(stroke
				(width 0.1524)
				(type default)
			)
			(layer "F.SilkS")
		)
		(fp_line
			(start 0.7874 0.4064)
			(end -0.7874 0.4064)
			(stroke
				(width 0.1524)
				(type default)
			)
			(layer "F.SilkS")
		)
		(fp_line
			(start -0.67945 -0.305054)
			(end -0.12065 -0.305054)
			(stroke
				(width 0.1)
				(type default)
			)
			(layer "F.Fab")
		)
		(fp_line
			(start -0.67945 0.3048)
			(end -0.67945 -0.305054)
			(stroke
				(width 0.1)
				(type default)
			)
			(layer "F.Fab")
		)
		(fp_line
			(start -0.12065 -0.305054)
			(end -0.12065 -0.2794)
			(stroke
				(width 0.1)
				(type default)
			)
			(layer "F.Fab")
		)
		(fp_line
			(start -0.12065 -0.2794)
			(end 0.12065 -0.2794)
			(stroke
				(width 0.1)
				(type default)
			)
			(layer "F.Fab")
		)
		(fp_line
			(start -0.12065 0.2794)
			(end -0.12065 0.3048)
			(stroke
				(width 0.1)
				(type default)
			)
			(layer "F.Fab")
		)
		(fp_line
			(start -0.12065 0.3048)
			(end -0.67945 0.3048)
			(stroke
				(width 0.1)
				(type default)
			)
			(layer "F.Fab")
		)
		(fp_line
			(start 0.120396 0.2794)
			(end -0.12065 0.2794)
			(stroke
				(width 0.1)
				(type default)
			)
			(layer "F.Fab")
		)
		(fp_line
			(start 0.120396 0.3048)
			(end 0.120396 0.2794)
			(stroke
				(width 0.1)
				(type default)
			)
			(layer "F.Fab")
		)
		(fp_line
			(start 0.12065 -0.3048)
			(end 0.67945 -0.3048)
			(stroke
				(width 0.1)
				(type default)
			)
			(layer "F.Fab")
		)
		(fp_line
			(start 0.12065 -0.2794)
			(end 0.12065 -0.3048)
			(stroke
				(width 0.1)
				(type default)
			)
			(layer "F.Fab")
		)
		(fp_line
			(start 0.67945 -0.3048)
			(end 0.67945 0.3048)
			(stroke
				(width 0.1)
				(type default)
			)
			(layer "F.Fab")
		)
		(fp_line
			(start 0.67945 0.3048)
			(end 0.120396 0.3048)
			(stroke
				(width 0.1)
				(type default)
			)
			(layer "F.Fab")
		)
		(pad "1" smd circle
			(at -0.40005 0)
			(size 0 0)
			(layers "F.Cu" "F.Mask" "F.Paste")
			(net "RST_SWB_BIC_BUF_R_N")
		)
		(pad "2" smd circle
			(at 0.40005 0)
			(size 0 0)
			(layers "F.Cu" "F.Mask" "F.Paste")
			(net "RST_SWB_BIC_BUF_N")
		)
	)
	(footprint ""
		(layer "F.Cu")
		(at 193.60388 -104.955848 180)
		(property "Reference" "R1823"
			(at 0 0 180)
			(layer "F.SilkS")
			(hide yes)
			(effects
				(font
					(size 1.27 1.27)
				)
			)
		)
		(property "Value" ""
			(at 0 0 180)
			(layer "F.Fab")
			(effects
				(font
					(size 1.27 1.27)
				)
			)
		)
		(duplicate_pad_numbers_are_jumpers no)
		(fp_line
			(start 0.7874 0.4064)
			(end -0.7874 0.4064)
			(stroke
				(width 0.1524)
				(type default)
			)
			(layer "F.SilkS")
		)
		(fp_line
			(start 0.7874 -0.4064)
			(end 0.7874 0.4064)
			(stroke
				(width 0.1524)
				(type default)
			)
			(layer "F.SilkS")
		)
		(fp_line
			(start -0.7874 0.4064)
			(end -0.7874 -0.4064)
			(stroke
				(width 0.1524)
				(type default)
			)
			(layer "F.SilkS")
		)
		(fp_line
			(start -0.7874 -0.4064)
			(end 0.7874 -0.4064)
			(stroke
				(width 0.1524)
				(type default)
			)
			(layer "F.SilkS")
		)
		(fp_line
			(start 0.67945 0.3048)
			(end 0.120396 0.3048)
			(stroke
				(width 0.1)
				(type default)
			)
			(layer "F.Fab")
		)
		(fp_line
			(start 0.67945 -0.3048)
			(end 0.67945 0.3048)
			(stroke
				(width 0.1)
				(type default)
			)
			(layer "F.Fab")
		)
		(fp_line
			(start 0.12065 -0.2794)
			(end 0.12065 -0.3048)
			(stroke
				(width 0.1)
				(type default)
			)
			(layer "F.Fab")
		)
		(fp_line
			(start 0.12065 -0.3048)
			(end 0.67945 -0.3048)
			(stroke
				(width 0.1)
				(type default)
			)
			(layer "F.Fab")
		)
		(fp_line
			(start 0.120396 0.3048)
			(end 0.120396 0.2794)
			(stroke
				(width 0.1)
				(type default)
			)
			(layer "F.Fab")
		)
		(fp_line
			(start 0.120396 0.2794)
			(end -0.12065 0.2794)
			(stroke
				(width 0.1)
				(type default)
			)
			(layer "F.Fab")
		)
		(fp_line
			(start -0.12065 0.3048)
			(end -0.67945 0.3048)
			(stroke
				(width 0.1)
				(type default)
			)
			(layer "F.Fab")
		)
		(fp_line
			(start -0.12065 0.2794)
			(end -0.12065 0.3048)
			(stroke
				(width 0.1)
				(type default)
			)
			(layer "F.Fab")
		)
		(fp_line
			(start -0.12065 -0.2794)
			(end 0.12065 -0.2794)
			(stroke
				(width 0.1)
				(type default)
			)
			(layer "F.Fab")
		)
		(fp_line
			(start -0.12065 -0.305054)
			(end -0.12065 -0.2794)
			(stroke
				(width 0.1)
				(type default)
			)
			(layer "F.Fab")
		)
		(fp_line
			(start -0.67945 0.3048)
			(end -0.67945 -0.305054)
			(stroke
				(width 0.1)
				(type default)
			)
			(layer "F.Fab")
		)
		(fp_line
			(start -0.67945 -0.305054)
			(end -0.12065 -0.305054)
			(stroke
				(width 0.1)
				(type default)
			)
			(layer "F.Fab")
		)
		(pad "1" smd circle
			(at -0.40005 0 180)
			(size 0 0)
			(layers "F.Cu" "F.Mask" "F.Paste")
			(net "P3V3_AUX")
		)
		(pad "2" smd circle
			(at 0.40005 0 180)
			(size 0 0)
			(layers "F.Cu" "F.Mask" "F.Paste")
			(net "RST_MB_STBY_R_N")
		)
	)
	(footprint ""
		(layer "F.Cu")
		(at 192.052448 -404.414482)
		(property "Reference" "PR3937"
			(at 0 0 0)
			(layer "F.SilkS")
			(hide yes)
			(effects
				(font
					(size 1.27 1.27)
				)
			)
		)
		(property "Value" ""
			(at 0 0 0)
			(layer "F.Fab")
			(effects
				(font
					(size 1.27 1.27)
				)
			)
		)
		(duplicate_pad_numbers_are_jumpers no)
		(fp_line
			(start -0.7874 -0.4064)
			(end 0.7874 -0.4064)
			(stroke
				(width 0.1524)
				(type default)
			)
			(layer "F.SilkS")
		)
		(fp_line
			(start -0.7874 0.4064)
			(end -0.7874 -0.4064)
			(stroke
				(width 0.1524)
				(type default)
			)
			(layer "F.SilkS")
		)
		(fp_line
			(start 0.7874 -0.4064)
			(end 0.7874 0.4064)
			(stroke
				(width 0.1524)
				(type default)
			)
			(layer "F.SilkS")
		)
		(fp_line
			(start 0.7874 0.4064)
			(end -0.7874 0.4064)
			(stroke
				(width 0.1524)
				(type default)
			)
			(layer "F.SilkS")
		)
		(fp_line
			(start -0.67945 -0.305054)
			(end -0.12065 -0.305054)
			(stroke
				(width 0.1)
				(type default)
			)
			(layer "F.Fab")
		)
		(fp_line
			(start -0.67945 0.3048)
			(end -0.67945 -0.305054)
			(stroke
				(width 0.1)
				(type default)
			)
			(layer "F.Fab")
		)
		(fp_line
			(start -0.12065 -0.305054)
			(end -0.12065 -0.2794)
			(stroke
				(width 0.1)
				(type default)
			)
			(layer "F.Fab")
		)
		(fp_line
			(start -0.12065 -0.2794)
			(end 0.12065 -0.2794)
			(stroke
				(width 0.1)
				(type default)
			)
			(layer "F.Fab")
		)
		(fp_line
			(start -0.12065 0.2794)
			(end -0.12065 0.3048)
			(stroke
				(width 0.1)
				(type default)
			)
			(layer "F.Fab")
		)
		(fp_line
			(start -0.12065 0.3048)
			(end -0.67945 0.3048)
			(stroke
				(width 0.1)
				(type default)
			)
			(layer "F.Fab")
		)
		(fp_line
			(start 0.120396 0.2794)
			(end -0.12065 0.2794)
			(stroke
				(width 0.1)
				(type default)
			)
			(layer "F.Fab")
		)
		(fp_line
			(start 0.120396 0.3048)
			(end 0.120396 0.2794)
			(stroke
				(width 0.1)
				(type default)
			)
			(layer "F.Fab")
		)
		(fp_line
			(start 0.12065 -0.3048)
			(end 0.67945 -0.3048)
			(stroke
				(width 0.1)
				(type default)
			)
			(layer "F.Fab")
		)
		(fp_line
			(start 0.12065 -0.2794)
			(end 0.12065 -0.3048)
			(stroke
				(width 0.1)
				(type default)
			)
			(layer "F.Fab")
		)
		(fp_line
			(start 0.67945 -0.3048)
			(end 0.67945 0.3048)
			(stroke
				(width 0.1)
				(type default)
			)
			(layer "F.Fab")
		)
		(fp_line
			(start 0.67945 0.3048)
			(end 0.120396 0.3048)
			(stroke
				(width 0.1)
				(type default)
			)
			(layer "F.Fab")
		)
		(pad "1" smd circle
			(at -0.40005 0)
			(size 0 0)
			(layers "F.Cu" "F.Mask" "F.Paste")
			(net "HSC_MODE")
		)
		(pad "2" smd circle
			(at 0.40005 0)
			(size 0 0)
			(layers "F.Cu" "F.Mask" "F.Paste")
			(net "AGND_HSC")
		)
	)
	(footprint ""
		(layer "F.Cu")
		(at 36.930584 -110.587282)
		(property "Reference" "C2177"
			(at 0 0 0)
			(layer "F.SilkS")
			(hide yes)
			(effects
				(font
					(size 1.27 1.27)
				)
			)
		)
		(property "Value" ""
			(at 0 0 0)
			(layer "F.Fab")
			(effects
				(font
					(size 1.27 1.27)
				)
			)
		)
		(duplicate_pad_numbers_are_jumpers no)
		(fp_line
			(start -0.7874 -0.4064)
			(end 0.7874 -0.4064)
			(stroke
				(width 0.1524)
				(type default)
			)
			(layer "F.SilkS")
		)
		(fp_line
			(start -0.7874 0.4064)
			(end -0.7874 -0.4064)
			(stroke
				(width 0.1524)
				(type default)
			)
			(layer "F.SilkS")
		)
		(fp_line
			(start 0.7874 -0.4064)
			(end 0.7874 0.4064)
			(stroke
				(width 0.1524)
				(type default)
			)
			(layer "F.SilkS")
		)
		(fp_line
			(start 0.7874 0.4064)
			(end -0.7874 0.4064)
			(stroke
				(width 0.1524)
				(type default)
			)
			(layer "F.SilkS")
		)
		(fp_line
			(start -0.67945 -0.305054)
			(end -0.12065 -0.305054)
			(stroke
				(width 0.1)
				(type default)
			)
			(layer "F.Fab")
		)
		(fp_line
			(start -0.67945 0.3048)
			(end -0.67945 -0.305054)
			(stroke
				(width 0.1)
				(type default)
			)
			(layer "F.Fab")
		)
		(fp_line
			(start -0.12065 -0.305054)
			(end -0.12065 -0.2794)
			(stroke
				(width 0.1)
				(type default)
			)
			(layer "F.Fab")
		)
		(fp_line
			(start -0.12065 -0.2794)
			(end 0.12065 -0.2794)
			(stroke
				(width 0.1)
				(type default)
			)
			(layer "F.Fab")
		)
		(fp_line
			(start -0.12065 0.2794)
			(end -0.12065 0.3048)
			(stroke
				(width 0.1)
				(type default)
			)
			(layer "F.Fab")
		)
		(fp_line
			(start -0.12065 0.3048)
			(end -0.67945 0.3048)
			(stroke
				(width 0.1)
				(type default)
			)
			(layer "F.Fab")
		)
		(fp_line
			(start 0.120396 0.2794)
			(end -0.12065 0.2794)
			(stroke
				(width 0.1)
				(type default)
			)
			(layer "F.Fab")
		)
		(fp_line
			(start 0.120396 0.3048)
			(end 0.120396 0.2794)
			(stroke
				(width 0.1)
				(type default)
			)
			(layer "F.Fab")
		)
		(fp_line
			(start 0.12065 -0.3048)
			(end 0.67945 -0.3048)
			(stroke
				(width 0.1)
				(type default)
			)
			(layer "F.Fab")
		)
		(fp_line
			(start 0.12065 -0.2794)
			(end 0.12065 -0.3048)
			(stroke
				(width 0.1)
				(type default)
			)
			(layer "F.Fab")
		)
		(fp_line
			(start 0.67945 -0.3048)
			(end 0.67945 0.3048)
			(stroke
				(width 0.1)
				(type default)
			)
			(layer "F.Fab")
		)
		(fp_line
			(start 0.67945 0.3048)
			(end 0.120396 0.3048)
			(stroke
				(width 0.1)
				(type default)
			)
			(layer "F.Fab")
		)
		(pad "1" smd circle
			(at -0.40005 0)
			(size 0 0)
			(layers "F.Cu" "F.Mask" "F.Paste")
			(net "P12V_OCP_V3_2_ISENSE_TIC")
		)
		(pad "2" smd circle
			(at 0.40005 0)
			(size 0 0)
			(layers "F.Cu" "F.Mask" "F.Paste")
			(net "GND")
		)
	)
	(footprint ""
		(layer "F.Cu")
		(at 393.814046 -389.123936)
		(property "Reference" "ME17"
			(at 0 0 0)
			(layer "F.SilkS")
			(hide yes)
			(effects
				(font
					(size 1.27 1.27)
				)
			)
		)
		(property "Value" ""
			(at 0 0 0)
			(layer "F.Fab")
			(effects
				(font
					(size 1.27 1.27)
				)
			)
		)
		(duplicate_pad_numbers_are_jumpers no)
		(fp_line
			(start 0.089408 -2.660396)
			(end 1.561846 -4.072636)
			(stroke
				(width 0.1)
				(type default)
			)
			(layer "F.SilkS")
		)
		(fp_line
			(start 0.089408 -2.660396)
			(end 1.561846 -4.072636)
			(stroke
				(width 0.1)
				(type default)
			)
			(layer "F.SilkS")
		)
		(fp_line
			(start 0.098806 -2.611628)
			(end 1.482344 -3.938778)
			(stroke
				(width 0.1)
				(type default)
			)
			(layer "F.SilkS")
		)
		(fp_line
			(start 0.098806 -2.611628)
			(end 1.482344 -3.938778)
			(stroke
				(width 0.1)
				(type default)
			)
			(layer "F.SilkS")
		)
		(fp_line
			(start 0.108204 -2.563114)
			(end 1.4224 -3.823716)
			(stroke
				(width 0.1)
				(type default)
			)
			(layer "F.SilkS")
		)
		(fp_line
			(start 0.108204 -2.563114)
			(end 1.4224 -3.823716)
			(stroke
				(width 0.1)
				(type default)
			)
			(layer "F.SilkS")
		)
		(fp_line
			(start 0.117602 -2.514346)
			(end 1.38557 -3.730498)
			(stroke
				(width 0.1)
				(type default)
			)
			(layer "F.SilkS")
		)
		(fp_line
			(start 0.117602 -2.514346)
			(end 1.38557 -3.730498)
			(stroke
				(width 0.1)
				(type default)
			)
			(layer "F.SilkS")
		)
		(fp_line
			(start 0.127254 -2.465832)
			(end 1.360932 -3.649218)
			(stroke
				(width 0.1)
				(type default)
			)
			(layer "F.SilkS")
		)
		(fp_line
			(start 0.127254 -2.465832)
			(end 1.360932 -3.649218)
			(stroke
				(width 0.1)
				(type default)
			)
			(layer "F.SilkS")
		)
		(fp_line
			(start 0.139954 -2.420366)
			(end 1.336548 -3.568192)
			(stroke
				(width 0.1)
				(type default)
			)
			(layer "F.SilkS")
		)
		(fp_line
			(start 0.139954 -2.420366)
			(end 1.336548 -3.568192)
			(stroke
				(width 0.1)
				(type default)
			)
			(layer "F.SilkS")
		)
		(fp_line
			(start 0.152908 -2.3749)
			(end 1.31445 -3.489198)
			(stroke
				(width 0.1)
				(type default)
			)
			(layer "F.SilkS")
		)
		(fp_line
			(start 0.152908 -2.3749)
			(end 1.31445 -3.489198)
			(stroke
				(width 0.1)
				(type default)
			)
			(layer "F.SilkS")
		)
		(fp_line
			(start 0.165608 -2.329434)
			(end 1.307592 -3.424936)
			(stroke
				(width 0.1)
				(type default)
			)
			(layer "F.SilkS")
		)
		(fp_line
			(start 0.165608 -2.329434)
			(end 1.307592 -3.424936)
			(stroke
				(width 0.1)
				(type default)
			)
			(layer "F.SilkS")
		)
		(fp_line
			(start 0.178562 -2.284222)
			(end 1.300988 -3.360674)
			(stroke
				(width 0.1)
				(type default)
			)
			(layer "F.SilkS")
		)
		(fp_line
			(start 0.178562 -2.284222)
			(end 1.300988 -3.360674)
			(stroke
				(width 0.1)
				(type default)
			)
			(layer "F.SilkS")
		)
		(fp_line
			(start 0.191516 -2.238756)
			(end 1.29413 -3.296412)
			(stroke
				(width 0.1)
				(type default)
			)
			(layer "F.SilkS")
		)
		(fp_line
			(start 0.191516 -2.238756)
			(end 1.29413 -3.296412)
			(stroke
				(width 0.1)
				(type default)
			)
			(layer "F.SilkS")
		)
		(fp_line
			(start 0.205994 -2.195068)
			(end 1.287526 -3.232404)
			(stroke
				(width 0.1)
				(type default)
			)
			(layer "F.SilkS")
		)
		(fp_line
			(start 0.205994 -2.195068)
			(end 1.287526 -3.232404)
			(stroke
				(width 0.1)
				(type default)
			)
			(layer "F.SilkS")
		)
		(fp_line
			(start 0.222504 -2.153158)
			(end 1.2827 -3.170174)
			(stroke
				(width 0.1)
				(type default)
			)
			(layer "F.SilkS")
		)
		(fp_line
			(start 0.222504 -2.153158)
			(end 1.2827 -3.170174)
			(stroke
				(width 0.1)
				(type default)
			)
			(layer "F.SilkS")
		)
		(fp_line
			(start 0.239268 -2.111502)
			(end 1.287018 -3.11658)
			(stroke
				(width 0.1)
				(type default)
			)
			(layer "F.SilkS")
		)
		(fp_line
			(start 0.239268 -2.111502)
			(end 1.287018 -3.11658)
			(stroke
				(width 0.1)
				(type default)
			)
			(layer "F.SilkS")
		)
		(fp_line
			(start 0.256032 -2.069846)
			(end 1.291082 -3.062732)
			(stroke
				(width 0.1)
				(type default)
			)
			(layer "F.SilkS")
		)
		(fp_line
			(start 0.256032 -2.069846)
			(end 1.291082 -3.062732)
			(stroke
				(width 0.1)
				(type default)
			)
			(layer "F.SilkS")
		)
		(fp_line
			(start 0.272796 -2.02819)
			(end 1.295146 -3.009138)
			(stroke
				(width 0.1)
				(type default)
			)
			(layer "F.SilkS")
		)
		(fp_line
			(start 0.272796 -2.02819)
			(end 1.295146 -3.009138)
			(stroke
				(width 0.1)
				(type default)
			)
			(layer "F.SilkS")
		)
		(fp_line
			(start 0.289306 -1.986534)
			(end 1.299464 -2.955544)
			(stroke
				(width 0.1)
				(type default)
			)
			(layer "F.SilkS")
		)
		(fp_line
			(start 0.289306 -1.986534)
			(end 1.299464 -2.955544)
			(stroke
				(width 0.1)
				(type default)
			)
			(layer "F.SilkS")
		)
		(fp_line
			(start 0.307086 -1.94564)
			(end 1.303528 -2.901696)
			(stroke
				(width 0.1)
				(type default)
			)
			(layer "F.SilkS")
		)
		(fp_line
			(start 0.307086 -1.94564)
			(end 1.303528 -2.901696)
			(stroke
				(width 0.1)
				(type default)
			)
			(layer "F.SilkS")
		)
		(fp_line
			(start 0.327914 -1.908048)
			(end 1.31318 -2.853182)
			(stroke
				(width 0.1)
				(type default)
			)
			(layer "F.SilkS")
		)
		(fp_line
			(start 0.327914 -1.908048)
			(end 1.31318 -2.853182)
			(stroke
				(width 0.1)
				(type default)
			)
			(layer "F.SilkS")
		)
		(fp_line
			(start 0.348996 -1.870456)
			(end 1.325118 -2.8067)
			(stroke
				(width 0.1)
				(type default)
			)
			(layer "F.SilkS")
		)
		(fp_line
			(start 0.348996 -1.870456)
			(end 1.325118 -2.8067)
			(stroke
				(width 0.1)
				(type default)
			)
			(layer "F.SilkS")
		)
		(fp_line
			(start 0.369824 -1.832864)
			(end 1.336802 -2.760472)
			(stroke
				(width 0.1)
				(type default)
			)
			(layer "F.SilkS")
		)
		(fp_line
			(start 0.369824 -1.832864)
			(end 1.336802 -2.760472)
			(stroke
				(width 0.1)
				(type default)
			)
			(layer "F.SilkS")
		)
		(fp_line
			(start 0.390906 -1.795272)
			(end 1.348486 -2.714244)
			(stroke
				(width 0.1)
				(type default)
			)
			(layer "F.SilkS")
		)
		(fp_line
			(start 0.390906 -1.795272)
			(end 1.348486 -2.714244)
			(stroke
				(width 0.1)
				(type default)
			)
			(layer "F.SilkS")
		)
		(fp_line
			(start 0.411988 -1.75768)
			(end 1.360424 -2.667508)
			(stroke
				(width 0.1)
				(type default)
			)
			(layer "F.SilkS")
		)
		(fp_line
			(start 0.411988 -1.75768)
			(end 1.360424 -2.667508)
			(stroke
				(width 0.1)
				(type default)
			)
			(layer "F.SilkS")
		)
		(fp_line
			(start 0.432816 -1.720088)
			(end 1.372362 -2.62128)
			(stroke
				(width 0.1)
				(type default)
			)
			(layer "F.SilkS")
		)
		(fp_line
			(start 0.432816 -1.720088)
			(end 1.372362 -2.62128)
			(stroke
				(width 0.1)
				(type default)
			)
			(layer "F.SilkS")
		)
		(fp_line
			(start 0.456184 -1.684782)
			(end 1.387856 -2.578608)
			(stroke
				(width 0.1)
				(type default)
			)
			(layer "F.SilkS")
		)
		(fp_line
			(start 0.456184 -1.684782)
			(end 1.387856 -2.578608)
			(stroke
				(width 0.1)
				(type default)
			)
			(layer "F.SilkS")
		)
		(fp_line
			(start 0.481838 -1.651762)
			(end 1.40589 -2.538222)
			(stroke
				(width 0.1)
				(type default)
			)
			(layer "F.SilkS")
		)
		(fp_line
			(start 0.481838 -1.651762)
			(end 1.40589 -2.538222)
			(stroke
				(width 0.1)
				(type default)
			)
			(layer "F.SilkS")
		)
		(fp_line
			(start 0.507746 -1.618742)
			(end 1.423924 -2.497836)
			(stroke
				(width 0.1)
				(type default)
			)
			(layer "F.SilkS")
		)
		(fp_line
			(start 0.507746 -1.618742)
			(end 1.423924 -2.497836)
			(stroke
				(width 0.1)
				(type default)
			)
			(layer "F.SilkS")
		)
		(fp_line
			(start 0.5334 -1.585722)
			(end 1.441958 -2.457196)
			(stroke
				(width 0.1)
				(type default)
			)
			(layer "F.SilkS")
		)
		(fp_line
			(start 0.5334 -1.585722)
			(end 1.441958 -2.457196)
			(stroke
				(width 0.1)
				(type default)
			)
			(layer "F.SilkS")
		)
		(fp_line
			(start 0.559054 -1.552702)
			(end 1.459992 -2.41681)
			(stroke
				(width 0.1)
				(type default)
			)
			(layer "F.SilkS")
		)
		(fp_line
			(start 0.559054 -1.552702)
			(end 1.459992 -2.41681)
			(stroke
				(width 0.1)
				(type default)
			)
			(layer "F.SilkS")
		)
		(fp_line
			(start 0.584962 -1.519682)
			(end 1.477772 -2.376424)
			(stroke
				(width 0.1)
				(type default)
			)
			(layer "F.SilkS")
		)
		(fp_line
			(start 0.584962 -1.519682)
			(end 1.477772 -2.376424)
			(stroke
				(width 0.1)
				(type default)
			)
			(layer "F.SilkS")
		)
		(fp_line
			(start 0.610616 -1.486916)
			(end 1.496568 -2.336546)
			(stroke
				(width 0.1)
				(type default)
			)
			(layer "F.SilkS")
		)
		(fp_line
			(start 0.610616 -1.486916)
			(end 1.496568 -2.336546)
			(stroke
				(width 0.1)
				(type default)
			)
			(layer "F.SilkS")
		)
		(fp_line
			(start 0.637794 -1.455166)
			(end 1.52019 -2.301494)
			(stroke
				(width 0.1)
				(type default)
			)
			(layer "F.SilkS")
		)
		(fp_line
			(start 0.637794 -1.455166)
			(end 1.52019 -2.301494)
			(stroke
				(width 0.1)
				(type default)
			)
			(layer "F.SilkS")
		)
		(fp_line
			(start 0.668274 -1.426464)
			(end 1.543558 -2.266188)
			(stroke
				(width 0.1)
				(type default)
			)
			(layer "F.SilkS")
		)
		(fp_line
			(start 0.668274 -1.426464)
			(end 1.543558 -2.266188)
			(stroke
				(width 0.1)
				(type default)
			)
			(layer "F.SilkS")
		)
		(fp_line
			(start 0.6985 -1.397762)
			(end 1.56718 -2.231136)
			(stroke
				(width 0.1)
				(type default)
			)
			(layer "F.SilkS")
		)
		(fp_line
			(start 0.6985 -1.397762)
			(end 1.56718 -2.231136)
			(stroke
				(width 0.1)
				(type default)
			)
			(layer "F.SilkS")
		)
		(fp_line
			(start 0.728726 -1.36906)
			(end 1.590802 -2.196084)
			(stroke
				(width 0.1)
				(type default)
			)
			(layer "F.SilkS")
		)
		(fp_line
			(start 0.728726 -1.36906)
			(end 1.590802 -2.196084)
			(stroke
				(width 0.1)
				(type default)
			)
			(layer "F.SilkS")
		)
		(fp_line
			(start 0.758952 -1.340358)
			(end 1.61417 -2.160778)
			(stroke
				(width 0.1)
				(type default)
			)
			(layer "F.SilkS")
		)
		(fp_line
			(start 0.758952 -1.340358)
			(end 1.61417 -2.160778)
			(stroke
				(width 0.1)
				(type default)
			)
			(layer "F.SilkS")
		)
		(fp_line
			(start 0.789178 -1.31191)
			(end 1.637792 -2.125726)
			(stroke
				(width 0.1)
				(type default)
			)
			(layer "F.SilkS")
		)
		(fp_line
			(start 0.789178 -1.31191)
			(end 1.637792 -2.125726)
			(stroke
				(width 0.1)
				(type default)
			)
			(layer "F.SilkS")
		)
		(fp_line
			(start 0.819404 -1.282954)
			(end 1.663954 -2.09296)
			(stroke
				(width 0.1)
				(type default)
			)
			(layer "F.SilkS")
		)
		(fp_line
			(start 0.819404 -1.282954)
			(end 1.663954 -2.09296)
			(stroke
				(width 0.1)
				(type default)
			)
			(layer "F.SilkS")
		)
		(fp_line
			(start 0.851408 -1.25603)
			(end 1.69291 -2.063242)
			(stroke
				(width 0.1)
				(type default)
			)
			(layer "F.SilkS")
		)
		(fp_line
			(start 0.851408 -1.25603)
			(end 1.69291 -2.063242)
			(stroke
				(width 0.1)
				(type default)
			)
			(layer "F.SilkS")
		)
		(fp_line
			(start 0.885698 -1.230884)
			(end 1.72212 -2.03327)
			(stroke
				(width 0.1)
				(type default)
			)
			(layer "F.SilkS")
		)
		(fp_line
			(start 0.885698 -1.230884)
			(end 1.72212 -2.03327)
			(stroke
				(width 0.1)
				(type default)
			)
			(layer "F.SilkS")
		)
		(fp_line
			(start 0.919734 -1.206246)
			(end 1.751076 -2.003552)
			(stroke
				(width 0.1)
				(type default)
			)
			(layer "F.SilkS")
		)
		(fp_line
			(start 0.919734 -1.206246)
			(end 1.751076 -2.003552)
			(stroke
				(width 0.1)
				(type default)
			)
			(layer "F.SilkS")
		)
		(fp_line
			(start 0.954024 -1.1811)
			(end 1.780032 -1.973834)
			(stroke
				(width 0.1)
				(type default)
			)
			(layer "F.SilkS")
		)
		(fp_line
			(start 0.954024 -1.1811)
			(end 1.780032 -1.973834)
			(stroke
				(width 0.1)
				(type default)
			)
			(layer "F.SilkS")
		)
		(fp_line
			(start 0.988314 -1.156462)
			(end 1.809242 -1.943862)
			(stroke
				(width 0.1)
				(type default)
			)
			(layer "F.SilkS")
		)
		(fp_line
			(start 0.988314 -1.156462)
			(end 1.809242 -1.943862)
			(stroke
				(width 0.1)
				(type default)
			)
			(layer "F.SilkS")
		)
		(fp_line
			(start 1.02235 -1.13157)
			(end 1.838452 -1.914144)
			(stroke
				(width 0.1)
				(type default)
			)
			(layer "F.SilkS")
		)
		(fp_line
			(start 1.02235 -1.13157)
			(end 1.838452 -1.914144)
			(stroke
				(width 0.1)
				(type default)
			)
			(layer "F.SilkS")
		)
		(fp_line
			(start 1.05664 -1.106678)
			(end 1.872488 -1.889252)
			(stroke
				(width 0.1)
				(type default)
			)
			(layer "F.SilkS")
		)
		(fp_line
			(start 1.05664 -1.106678)
			(end 1.872488 -1.889252)
			(stroke
				(width 0.1)
				(type default)
			)
			(layer "F.SilkS")
		)
		(fp_line
			(start 1.09347 -1.084326)
			(end 1.907794 -1.865376)
			(stroke
				(width 0.1)
				(type default)
			)
			(layer "F.SilkS")
		)
		(fp_line
			(start 1.09347 -1.084326)
			(end 1.907794 -1.865376)
			(stroke
				(width 0.1)
				(type default)
			)
			(layer "F.SilkS")
		)
		(fp_line
			(start 1.131824 -1.063498)
			(end 1.9431 -1.8415)
			(stroke
				(width 0.1)
				(type default)
			)
			(layer "F.SilkS")
		)
		(fp_line
			(start 1.131824 -1.063498)
			(end 1.9431 -1.8415)
			(stroke
				(width 0.1)
				(type default)
			)
			(layer "F.SilkS")
		)
		(fp_line
			(start 1.133856 -5.220462)
			(end 0.47117 -4.5847)
			(stroke
				(width 0.1)
				(type default)
			)
			(layer "F.SilkS")
		)
		(fp_line
			(start 1.133856 -5.220462)
			(end 0.47117 -4.5847)
			(stroke
				(width 0.1)
				(type default)
			)
			(layer "F.SilkS")
		)
		(fp_line
			(start 1.170178 -1.042416)
			(end 1.978406 -1.817624)
			(stroke
				(width 0.1)
				(type default)
			)
			(layer "F.SilkS")
		)
		(fp_line
			(start 1.170178 -1.042416)
			(end 1.978406 -1.817624)
			(stroke
				(width 0.1)
				(type default)
			)
			(layer "F.SilkS")
		)
		(fp_line
			(start 1.208532 -1.021334)
			(end 2.013458 -1.793748)
			(stroke
				(width 0.1)
				(type default)
			)
			(layer "F.SilkS")
		)
		(fp_line
			(start 1.208532 -1.021334)
			(end 2.013458 -1.793748)
			(stroke
				(width 0.1)
				(type default)
			)
			(layer "F.SilkS")
		)
		(fp_line
			(start 1.246886 -1.000506)
			(end 2.048764 -1.769872)
			(stroke
				(width 0.1)
				(type default)
			)
			(layer "F.SilkS")
		)
		(fp_line
			(start 1.246886 -1.000506)
			(end 2.048764 -1.769872)
			(stroke
				(width 0.1)
				(type default)
			)
			(layer "F.SilkS")
		)
		(fp_line
			(start 1.28524 -0.979424)
			(end 2.087626 -1.749298)
			(stroke
				(width 0.1)
				(type default)
			)
			(layer "F.SilkS")
		)
		(fp_line
			(start 1.28524 -0.979424)
			(end 2.087626 -1.749298)
			(stroke
				(width 0.1)
				(type default)
			)
			(layer "F.SilkS")
		)
		(fp_line
			(start 1.293368 -5.315966)
			(end 0.37465 -4.434332)
			(stroke
				(width 0.1)
				(type default)
			)
			(layer "F.SilkS")
		)
		(fp_line
			(start 1.293368 -5.315966)
			(end 0.37465 -4.434332)
			(stroke
				(width 0.1)
				(type default)
			)
			(layer "F.SilkS")
		)
		(fp_line
			(start 1.323594 -0.958596)
			(end 2.130552 -1.732788)
			(stroke
				(width 0.1)
				(type default)
			)
			(layer "F.SilkS")
		)
		(fp_line
			(start 1.323594 -0.958596)
			(end 2.130552 -1.732788)
			(stroke
				(width 0.1)
				(type default)
			)
			(layer "F.SilkS")
		)
		(fp_line
			(start 1.366266 -0.941832)
			(end 2.173478 -1.716024)
			(stroke
				(width 0.1)
				(type default)
			)
			(layer "F.SilkS")
		)
		(fp_line
			(start 1.366266 -0.941832)
			(end 2.173478 -1.716024)
			(stroke
				(width 0.1)
				(type default)
			)
			(layer "F.SilkS")
		)
		(fp_line
			(start 1.408684 -0.924814)
			(end 2.21615 -1.699514)
			(stroke
				(width 0.1)
				(type default)
			)
			(layer "F.SilkS")
		)
		(fp_line
			(start 1.408684 -0.924814)
			(end 2.21615 -1.699514)
			(stroke
				(width 0.1)
				(type default)
			)
			(layer "F.SilkS")
		)
		(fp_line
			(start 1.41224 -5.3721)
			(end 0.302768 -4.307586)
			(stroke
				(width 0.1)
				(type default)
			)
			(layer "F.SilkS")
		)
		(fp_line
			(start 1.41224 -5.3721)
			(end 0.302768 -4.307586)
			(stroke
				(width 0.1)
				(type default)
			)
			(layer "F.SilkS")
		)
		(fp_line
			(start 1.451356 -0.90805)
			(end 2.259076 -1.68275)
			(stroke
				(width 0.1)
				(type default)
			)
			(layer "F.SilkS")
		)
		(fp_line
			(start 1.451356 -0.90805)
			(end 2.259076 -1.68275)
			(stroke
				(width 0.1)
				(type default)
			)
			(layer "F.SilkS")
		)
		(fp_line
			(start 1.493774 -0.891032)
			(end 2.301748 -1.66624)
			(stroke
				(width 0.1)
				(type default)
			)
			(layer "F.SilkS")
		)
		(fp_line
			(start 1.493774 -0.891032)
			(end 2.301748 -1.66624)
			(stroke
				(width 0.1)
				(type default)
			)
			(layer "F.SilkS")
		)
		(fp_line
			(start 1.52781 -5.425186)
			(end 0.256794 -4.205732)
			(stroke
				(width 0.1)
				(type default)
			)
			(layer "F.SilkS")
		)
		(fp_line
			(start 1.52781 -5.425186)
			(end 0.256794 -4.205732)
			(stroke
				(width 0.1)
				(type default)
			)
			(layer "F.SilkS")
		)
		(fp_line
			(start 1.536446 -0.874268)
			(end 2.351024 -1.655826)
			(stroke
				(width 0.1)
				(type default)
			)
			(layer "F.SilkS")
		)
		(fp_line
			(start 1.536446 -0.874268)
			(end 2.351024 -1.655826)
			(stroke
				(width 0.1)
				(type default)
			)
			(layer "F.SilkS")
		)
		(fp_line
			(start 1.578864 -0.857504)
			(end 2.404364 -1.649222)
			(stroke
				(width 0.1)
				(type default)
			)
			(layer "F.SilkS")
		)
		(fp_line
			(start 1.578864 -0.857504)
			(end 2.404364 -1.649222)
			(stroke
				(width 0.1)
				(type default)
			)
			(layer "F.SilkS")
		)
		(fp_line
			(start 1.62306 -5.458714)
			(end 0.211328 -4.10464)
			(stroke
				(width 0.1)
				(type default)
			)
			(layer "F.SilkS")
		)
		(fp_line
			(start 1.62306 -5.458714)
			(end 0.211328 -4.10464)
			(stroke
				(width 0.1)
				(type default)
			)
			(layer "F.SilkS")
		)
		(fp_line
			(start 1.623314 -0.842264)
			(end 2.457704 -1.642618)
			(stroke
				(width 0.1)
				(type default)
			)
			(layer "F.SilkS")
		)
		(fp_line
			(start 1.623314 -0.842264)
			(end 2.457704 -1.642618)
			(stroke
				(width 0.1)
				(type default)
			)
			(layer "F.SilkS")
		)
		(fp_line
			(start 1.67005 -0.829564)
			(end 2.511044 -1.636014)
			(stroke
				(width 0.1)
				(type default)
			)
			(layer "F.SilkS")
		)
		(fp_line
			(start 1.67005 -0.829564)
			(end 2.511044 -1.636014)
			(stroke
				(width 0.1)
				(type default)
			)
			(layer "F.SilkS")
		)
		(fp_line
			(start 1.716786 -0.816356)
			(end 2.56413 -1.62941)
			(stroke
				(width 0.1)
				(type default)
			)
			(layer "F.SilkS")
		)
		(fp_line
			(start 1.716786 -0.816356)
			(end 2.56413 -1.62941)
			(stroke
				(width 0.1)
				(type default)
			)
			(layer "F.SilkS")
		)
		(fp_line
			(start 1.717802 -5.492242)
			(end 0.181356 -4.018026)
			(stroke
				(width 0.1)
				(type default)
			)
			(layer "F.SilkS")
		)
		(fp_line
			(start 1.717802 -5.492242)
			(end 0.181356 -4.018026)
			(stroke
				(width 0.1)
				(type default)
			)
			(layer "F.SilkS")
		)
		(fp_line
			(start 1.763522 -0.803656)
			(end 2.624582 -1.629664)
			(stroke
				(width 0.1)
				(type default)
			)
			(layer "F.SilkS")
		)
		(fp_line
			(start 1.763522 -0.803656)
			(end 2.624582 -1.629664)
			(stroke
				(width 0.1)
				(type default)
			)
			(layer "F.SilkS")
		)
		(fp_line
			(start 1.805686 -5.518658)
			(end 0.1524 -3.932682)
			(stroke
				(width 0.1)
				(type default)
			)
			(layer "F.SilkS")
		)
		(fp_line
			(start 1.805686 -5.518658)
			(end 0.1524 -3.932682)
			(stroke
				(width 0.1)
				(type default)
			)
			(layer "F.SilkS")
		)
		(fp_line
			(start 1.810512 -0.790956)
			(end 2.692654 -1.637284)
			(stroke
				(width 0.1)
				(type default)
			)
			(layer "F.SilkS")
		)
		(fp_line
			(start 1.810512 -0.790956)
			(end 2.692654 -1.637284)
			(stroke
				(width 0.1)
				(type default)
			)
			(layer "F.SilkS")
		)
		(fp_line
			(start 1.856994 -0.777748)
			(end 2.760726 -1.64465)
			(stroke
				(width 0.1)
				(type default)
			)
			(layer "F.SilkS")
		)
		(fp_line
			(start 1.856994 -0.777748)
			(end 2.760726 -1.64465)
			(stroke
				(width 0.1)
				(type default)
			)
			(layer "F.SilkS")
		)
		(fp_line
			(start 1.886458 -5.538216)
			(end 0.128016 -3.851402)
			(stroke
				(width 0.1)
				(type default)
			)
			(layer "F.SilkS")
		)
		(fp_line
			(start 1.886458 -5.538216)
			(end 0.128016 -3.851402)
			(stroke
				(width 0.1)
				(type default)
			)
			(layer "F.SilkS")
		)
		(fp_line
			(start 1.90373 -0.765048)
			(end 2.828544 -1.65227)
			(stroke
				(width 0.1)
				(type default)
			)
			(layer "F.SilkS")
		)
		(fp_line
			(start 1.90373 -0.765048)
			(end 2.828544 -1.65227)
			(stroke
				(width 0.1)
				(type default)
			)
			(layer "F.SilkS")
		)
		(fp_line
			(start 1.954276 -0.75565)
			(end 2.906014 -1.66878)
			(stroke
				(width 0.1)
				(type default)
			)
			(layer "F.SilkS")
		)
		(fp_line
			(start 1.954276 -0.75565)
			(end 2.906014 -1.66878)
			(stroke
				(width 0.1)
				(type default)
			)
			(layer "F.SilkS")
		)
		(fp_line
			(start 1.966722 -5.557774)
			(end 0.110236 -3.776726)
			(stroke
				(width 0.1)
				(type default)
			)
			(layer "F.SilkS")
		)
		(fp_line
			(start 1.966722 -5.557774)
			(end 0.110236 -3.776726)
			(stroke
				(width 0.1)
				(type default)
			)
			(layer "F.SilkS")
		)
		(fp_line
			(start 2.00533 -0.74676)
			(end 3.000248 -1.701546)
			(stroke
				(width 0.1)
				(type default)
			)
			(layer "F.SilkS")
		)
		(fp_line
			(start 2.00533 -0.74676)
			(end 3.000248 -1.701546)
			(stroke
				(width 0.1)
				(type default)
			)
			(layer "F.SilkS")
		)
		(fp_line
			(start 2.04597 -5.576062)
			(end 0.092456 -3.70205)
			(stroke
				(width 0.1)
				(type default)
			)
			(layer "F.SilkS")
		)
		(fp_line
			(start 2.04597 -5.576062)
			(end 0.092456 -3.70205)
			(stroke
				(width 0.1)
				(type default)
			)
			(layer "F.SilkS")
		)
		(fp_line
			(start 2.05613 -0.73787)
			(end 3.094228 -1.733804)
			(stroke
				(width 0.1)
				(type default)
			)
			(layer "F.SilkS")
		)
		(fp_line
			(start 2.05613 -0.73787)
			(end 3.094228 -1.733804)
			(stroke
				(width 0.1)
				(type default)
			)
			(layer "F.SilkS")
		)
		(fp_line
			(start 2.10693 -0.72898)
			(end 3.238246 -1.814322)
			(stroke
				(width 0.1)
				(type default)
			)
			(layer "F.SilkS")
		)
		(fp_line
			(start 2.10693 -0.72898)
			(end 3.238246 -1.814322)
			(stroke
				(width 0.1)
				(type default)
			)
			(layer "F.SilkS")
		)
		(fp_line
			(start 2.116328 -5.585968)
			(end 0.07874 -3.631184)
			(stroke
				(width 0.1)
				(type default)
			)
			(layer "F.SilkS")
		)
		(fp_line
			(start 2.116328 -5.585968)
			(end 0.07874 -3.631184)
			(stroke
				(width 0.1)
				(type default)
			)
			(layer "F.SilkS")
		)
		(fp_line
			(start 2.18694 -5.595874)
			(end 0.069342 -3.564382)
			(stroke
				(width 0.1)
				(type default)
			)
			(layer "F.SilkS")
		)
		(fp_line
			(start 2.18694 -5.595874)
			(end 0.069342 -3.564382)
			(stroke
				(width 0.1)
				(type default)
			)
			(layer "F.SilkS")
		)
		(fp_line
			(start 2.208784 -0.710946)
			(end 5.142484 -3.52552)
			(stroke
				(width 0.1)
				(type default)
			)
			(layer "F.SilkS")
		)
		(fp_line
			(start 2.208784 -0.710946)
			(end 5.142484 -3.52552)
			(stroke
				(width 0.1)
				(type default)
			)
			(layer "F.SilkS")
		)
		(fp_line
			(start 2.257552 -5.60578)
			(end 0.059944 -3.49758)
			(stroke
				(width 0.1)
				(type default)
			)
			(layer "F.SilkS")
		)
		(fp_line
			(start 2.257552 -5.60578)
			(end 0.059944 -3.49758)
			(stroke
				(width 0.1)
				(type default)
			)
			(layer "F.SilkS")
		)
		(fp_line
			(start 2.2606 -0.703326)
			(end 5.147564 -3.472942)
			(stroke
				(width 0.1)
				(type default)
			)
			(layer "F.SilkS")
		)
		(fp_line
			(start 2.2606 -0.703326)
			(end 5.147564 -3.472942)
			(stroke
				(width 0.1)
				(type default)
			)
			(layer "F.SilkS")
		)
		(fp_line
			(start 2.315464 -0.698246)
			(end 5.152898 -3.42011)
			(stroke
				(width 0.1)
				(type default)
			)
			(layer "F.SilkS")
		)
		(fp_line
			(start 2.315464 -0.698246)
			(end 5.152898 -3.42011)
			(stroke
				(width 0.1)
				(type default)
			)
			(layer "F.SilkS")
		)
		(fp_line
			(start 2.32791 -5.615686)
			(end 0.051308 -3.431794)
			(stroke
				(width 0.1)
				(type default)
			)
			(layer "F.SilkS")
		)
		(fp_line
			(start 2.32791 -5.615686)
			(end 0.051308 -3.431794)
			(stroke
				(width 0.1)
				(type default)
			)
			(layer "F.SilkS")
		)
		(fp_line
			(start 2.370328 -0.693166)
			(end 5.156708 -3.366262)
			(stroke
				(width 0.1)
				(type default)
			)
			(layer "F.SilkS")
		)
		(fp_line
			(start 2.370328 -0.693166)
			(end 5.156708 -3.366262)
			(stroke
				(width 0.1)
				(type default)
			)
			(layer "F.SilkS")
		)
		(fp_line
			(start 2.390902 -5.61848)
			(end 0.048514 -3.371342)
			(stroke
				(width 0.1)
				(type default)
			)
			(layer "F.SilkS")
		)
		(fp_line
			(start 2.390902 -5.61848)
			(end 0.048514 -3.371342)
			(stroke
				(width 0.1)
				(type default)
			)
			(layer "F.SilkS")
		)
		(fp_line
			(start 2.424938 -0.687832)
			(end 5.158994 -3.310382)
			(stroke
				(width 0.1)
				(type default)
			)
			(layer "F.SilkS")
		)
		(fp_line
			(start 2.424938 -0.687832)
			(end 5.158994 -3.310382)
			(stroke
				(width 0.1)
				(type default)
			)
			(layer "F.SilkS")
		)
		(fp_line
			(start 2.454148 -5.621274)
			(end 0.04572 -3.31089)
			(stroke
				(width 0.1)
				(type default)
			)
			(layer "F.SilkS")
		)
		(fp_line
			(start 2.454148 -5.621274)
			(end 0.04572 -3.31089)
			(stroke
				(width 0.1)
				(type default)
			)
			(layer "F.SilkS")
		)
		(fp_line
			(start 2.479802 -0.682752)
			(end 5.16001 -3.25374)
			(stroke
				(width 0.1)
				(type default)
			)
			(layer "F.SilkS")
		)
		(fp_line
			(start 2.479802 -0.682752)
			(end 5.16001 -3.25374)
			(stroke
				(width 0.1)
				(type default)
			)
			(layer "F.SilkS")
		)
		(fp_line
			(start 2.517394 -5.624322)
			(end 0.042926 -3.250438)
			(stroke
				(width 0.1)
				(type default)
			)
			(layer "F.SilkS")
		)
		(fp_line
			(start 2.517394 -5.624322)
			(end 0.042926 -3.250438)
			(stroke
				(width 0.1)
				(type default)
			)
			(layer "F.SilkS")
		)
		(fp_line
			(start 2.534666 -0.677672)
			(end 5.15747 -3.193796)
			(stroke
				(width 0.1)
				(type default)
			)
			(layer "F.SilkS")
		)
		(fp_line
			(start 2.534666 -0.677672)
			(end 5.15747 -3.193796)
			(stroke
				(width 0.1)
				(type default)
			)
			(layer "F.SilkS")
		)
		(fp_line
			(start 2.580386 -5.626862)
			(end 0.041656 -3.19151)
			(stroke
				(width 0.1)
				(type default)
			)
			(layer "F.SilkS")
		)
		(fp_line
			(start 2.580386 -5.626862)
			(end 0.041656 -3.19151)
			(stroke
				(width 0.1)
				(type default)
			)
			(layer "F.SilkS")
		)
		(fp_line
			(start 2.589276 -0.672338)
			(end 5.15493 -3.133598)
			(stroke
				(width 0.1)
				(type default)
			)
			(layer "F.SilkS")
		)
		(fp_line
			(start 2.589276 -0.672338)
			(end 5.15493 -3.133598)
			(stroke
				(width 0.1)
				(type default)
			)
			(layer "F.SilkS")
		)
		(fp_line
			(start 2.64287 -5.629148)
			(end 0.042672 -3.135122)
			(stroke
				(width 0.1)
				(type default)
			)
			(layer "F.SilkS")
		)
		(fp_line
			(start 2.64287 -5.629148)
			(end 0.042672 -3.135122)
			(stroke
				(width 0.1)
				(type default)
			)
			(layer "F.SilkS")
		)
		(fp_line
			(start 2.646426 -0.669544)
			(end 5.15239 -3.073146)
			(stroke
				(width 0.1)
				(type default)
			)
			(layer "F.SilkS")
		)
		(fp_line
			(start 2.646426 -0.669544)
			(end 5.15239 -3.073146)
			(stroke
				(width 0.1)
				(type default)
			)
			(layer "F.SilkS")
		)
		(fp_line
			(start 2.700528 -5.626862)
			(end 0.04445 -3.078734)
			(stroke
				(width 0.1)
				(type default)
			)
			(layer "F.SilkS")
		)
		(fp_line
			(start 2.700528 -5.626862)
			(end 0.04445 -3.078734)
			(stroke
				(width 0.1)
				(type default)
			)
			(layer "F.SilkS")
		)
		(fp_line
			(start 2.704846 -0.66802)
			(end 5.14985 -3.013202)
			(stroke
				(width 0.1)
				(type default)
			)
			(layer "F.SilkS")
		)
		(fp_line
			(start 2.704846 -0.66802)
			(end 5.14985 -3.013202)
			(stroke
				(width 0.1)
				(type default)
			)
			(layer "F.SilkS")
		)
		(fp_line
			(start 2.75844 -5.62483)
			(end 0.048006 -3.024632)
			(stroke
				(width 0.1)
				(type default)
			)
			(layer "F.SilkS")
		)
		(fp_line
			(start 2.75844 -5.62483)
			(end 0.048006 -3.024632)
			(stroke
				(width 0.1)
				(type default)
			)
			(layer "F.SilkS")
		)
		(fp_line
			(start 2.76352 -0.666242)
			(end 5.14731 -2.953258)
			(stroke
				(width 0.1)
				(type default)
			)
			(layer "F.SilkS")
		)
		(fp_line
			(start 2.76352 -0.666242)
			(end 5.14731 -2.953258)
			(stroke
				(width 0.1)
				(type default)
			)
			(layer "F.SilkS")
		)
		(fp_line
			(start 2.816098 -5.622544)
			(end 0.051562 -2.970276)
			(stroke
				(width 0.1)
				(type default)
			)
			(layer "F.SilkS")
		)
		(fp_line
			(start 2.816098 -5.622544)
			(end 0.051562 -2.970276)
			(stroke
				(width 0.1)
				(type default)
			)
			(layer "F.SilkS")
		)
		(fp_line
			(start 2.82194 -0.664718)
			(end 5.145024 -2.89306)
			(stroke
				(width 0.1)
				(type default)
			)
			(layer "F.SilkS")
		)
		(fp_line
			(start 2.82194 -0.664718)
			(end 5.145024 -2.89306)
			(stroke
				(width 0.1)
				(type default)
			)
			(layer "F.SilkS")
		)
		(fp_line
			(start 2.87401 -5.620258)
			(end 0.054864 -2.91592)
			(stroke
				(width 0.1)
				(type default)
			)
			(layer "F.SilkS")
		)
		(fp_line
			(start 2.87401 -5.620258)
			(end 0.054864 -2.91592)
			(stroke
				(width 0.1)
				(type default)
			)
			(layer "F.SilkS")
		)
		(fp_line
			(start 2.88036 -0.662686)
			(end 5.13588 -2.826512)
			(stroke
				(width 0.1)
				(type default)
			)
			(layer "F.SilkS")
		)
		(fp_line
			(start 2.88036 -0.662686)
			(end 5.13588 -2.826512)
			(stroke
				(width 0.1)
				(type default)
			)
			(layer "F.SilkS")
		)
		(fp_line
			(start 2.92989 -5.616194)
			(end 0.061468 -2.864358)
			(stroke
				(width 0.1)
				(type default)
			)
			(layer "F.SilkS")
		)
		(fp_line
			(start 2.92989 -5.616194)
			(end 0.061468 -2.864358)
			(stroke
				(width 0.1)
				(type default)
			)
			(layer "F.SilkS")
		)
		(fp_line
			(start 2.93878 -0.661416)
			(end 5.126736 -2.760218)
			(stroke
				(width 0.1)
				(type default)
			)
			(layer "F.SilkS")
		)
		(fp_line
			(start 2.93878 -0.661416)
			(end 5.126736 -2.760218)
			(stroke
				(width 0.1)
				(type default)
			)
			(layer "F.SilkS")
		)
		(fp_line
			(start 2.98323 -5.609336)
			(end 0.067818 -2.812542)
			(stroke
				(width 0.1)
				(type default)
			)
			(layer "F.SilkS")
		)
		(fp_line
			(start 2.98323 -5.609336)
			(end 0.067818 -2.812542)
			(stroke
				(width 0.1)
				(type default)
			)
			(layer "F.SilkS")
		)
		(fp_line
			(start 2.9972 -0.659638)
			(end 5.117592 -2.69367)
			(stroke
				(width 0.1)
				(type default)
			)
			(layer "F.SilkS")
		)
		(fp_line
			(start 2.9972 -0.659638)
			(end 5.117592 -2.69367)
			(stroke
				(width 0.1)
				(type default)
			)
			(layer "F.SilkS")
		)
		(fp_line
			(start 3.03657 -5.602732)
			(end 0.073914 -2.76098)
			(stroke
				(width 0.1)
				(type default)
			)
			(layer "F.SilkS")
		)
		(fp_line
			(start 3.03657 -5.602732)
			(end 0.073914 -2.76098)
			(stroke
				(width 0.1)
				(type default)
			)
			(layer "F.SilkS")
		)
		(fp_line
			(start 3.048 -0.651002)
			(end 5.108194 -2.627122)
			(stroke
				(width 0.1)
				(type default)
			)
			(layer "F.SilkS")
		)
		(fp_line
			(start 3.048 -0.651002)
			(end 5.108194 -2.627122)
			(stroke
				(width 0.1)
				(type default)
			)
			(layer "F.SilkS")
		)
		(fp_line
			(start 3.089656 -5.596382)
			(end 0.080264 -2.709418)
			(stroke
				(width 0.1)
				(type default)
			)
			(layer "F.SilkS")
		)
		(fp_line
			(start 3.089656 -5.596382)
			(end 0.080264 -2.709418)
			(stroke
				(width 0.1)
				(type default)
			)
			(layer "F.SilkS")
		)
		(fp_line
			(start 3.094482 -0.637286)
			(end 5.09905 -2.560574)
			(stroke
				(width 0.1)
				(type default)
			)
			(layer "F.SilkS")
		)
		(fp_line
			(start 3.094482 -0.637286)
			(end 5.09905 -2.560574)
			(stroke
				(width 0.1)
				(type default)
			)
			(layer "F.SilkS")
		)
		(fp_line
			(start 3.13944 -0.622808)
			(end 5.081524 -2.485898)
			(stroke
				(width 0.1)
				(type default)
			)
			(layer "F.SilkS")
		)
		(fp_line
			(start 3.13944 -0.622808)
			(end 5.081524 -2.485898)
			(stroke
				(width 0.1)
				(type default)
			)
			(layer "F.SilkS")
		)
		(fp_line
			(start 3.14325 -5.589778)
			(end 1.972818 -4.467098)
			(stroke
				(width 0.1)
				(type default)
			)
			(layer "F.SilkS")
		)
		(fp_line
			(start 3.14325 -5.589778)
			(end 1.972818 -4.467098)
			(stroke
				(width 0.1)
				(type default)
			)
			(layer "F.SilkS")
		)
		(fp_line
			(start 3.184144 -0.60833)
			(end 5.061966 -2.409698)
			(stroke
				(width 0.1)
				(type default)
			)
			(layer "F.SilkS")
		)
		(fp_line
			(start 3.184144 -0.60833)
			(end 5.061966 -2.409698)
			(stroke
				(width 0.1)
				(type default)
			)
			(layer "F.SilkS")
		)
		(fp_line
			(start 3.19405 -5.580888)
			(end 2.123694 -4.553966)
			(stroke
				(width 0.1)
				(type default)
			)
			(layer "F.SilkS")
		)
		(fp_line
			(start 3.19405 -5.580888)
			(end 2.123694 -4.553966)
			(stroke
				(width 0.1)
				(type default)
			)
			(layer "F.SilkS")
		)
		(fp_line
			(start 3.22834 -0.592836)
			(end 5.042408 -2.33299)
			(stroke
				(width 0.1)
				(type default)
			)
			(layer "F.SilkS")
		)
		(fp_line
			(start 3.22834 -0.592836)
			(end 5.042408 -2.33299)
			(stroke
				(width 0.1)
				(type default)
			)
			(layer "F.SilkS")
		)
		(fp_line
			(start 3.243072 -5.57022)
			(end 2.217166 -4.586224)
			(stroke
				(width 0.1)
				(type default)
			)
			(layer "F.SilkS")
		)
		(fp_line
			(start 3.243072 -5.57022)
			(end 2.217166 -4.586224)
			(stroke
				(width 0.1)
				(type default)
			)
			(layer "F.SilkS")
		)
		(fp_line
			(start 3.272536 -0.577342)
			(end 5.02285 -2.256536)
			(stroke
				(width 0.1)
				(type default)
			)
			(layer "F.SilkS")
		)
		(fp_line
			(start 3.272536 -0.577342)
			(end 5.02285 -2.256536)
			(stroke
				(width 0.1)
				(type default)
			)
			(layer "F.SilkS")
		)
		(fp_line
			(start 3.292094 -5.559552)
			(end 2.310892 -4.618228)
			(stroke
				(width 0.1)
				(type default)
			)
			(layer "F.SilkS")
		)
		(fp_line
			(start 3.292094 -5.559552)
			(end 2.310892 -4.618228)
			(stroke
				(width 0.1)
				(type default)
			)
			(layer "F.SilkS")
		)
		(fp_line
			(start 3.316224 -0.561848)
			(end 4.990338 -2.167636)
			(stroke
				(width 0.1)
				(type default)
			)
			(layer "F.SilkS")
		)
		(fp_line
			(start 3.316224 -0.561848)
			(end 4.990338 -2.167636)
			(stroke
				(width 0.1)
				(type default)
			)
			(layer "F.SilkS")
		)
		(fp_line
			(start 3.34137 -5.549138)
			(end 2.389632 -4.636262)
			(stroke
				(width 0.1)
				(type default)
			)
			(layer "F.SilkS")
		)
		(fp_line
			(start 3.34137 -5.549138)
			(end 2.389632 -4.636262)
			(stroke
				(width 0.1)
				(type default)
			)
			(layer "F.SilkS")
		)
		(fp_line
			(start 3.359912 -0.545846)
			(end 4.953254 -2.074418)
			(stroke
				(width 0.1)
				(type default)
			)
			(layer "F.SilkS")
		)
		(fp_line
			(start 3.359912 -0.545846)
			(end 4.953254 -2.074418)
			(stroke
				(width 0.1)
				(type default)
			)
			(layer "F.SilkS")
		)
		(fp_line
			(start 3.390392 -5.53847)
			(end 2.458212 -4.644136)
			(stroke
				(width 0.1)
				(type default)
			)
			(layer "F.SilkS")
		)
		(fp_line
			(start 3.390392 -5.53847)
			(end 2.458212 -4.644136)
			(stroke
				(width 0.1)
				(type default)
			)
			(layer "F.SilkS")
		)
		(fp_line
			(start 3.4036 -0.530098)
			(end 4.915916 -1.980946)
			(stroke
				(width 0.1)
				(type default)
			)
			(layer "F.SilkS")
		)
		(fp_line
			(start 3.4036 -0.530098)
			(end 4.915916 -1.980946)
			(stroke
				(width 0.1)
				(type default)
			)
			(layer "F.SilkS")
		)
		(fp_line
			(start 3.437382 -5.52577)
			(end 2.526538 -4.65201)
			(stroke
				(width 0.1)
				(type default)
			)
			(layer "F.SilkS")
		)
		(fp_line
			(start 3.437382 -5.52577)
			(end 2.526538 -4.65201)
			(stroke
				(width 0.1)
				(type default)
			)
			(layer "F.SilkS")
		)
		(fp_line
			(start 3.447034 -0.513842)
			(end 4.85267 -1.862582)
			(stroke
				(width 0.1)
				(type default)
			)
			(layer "F.SilkS")
		)
		(fp_line
			(start 3.447034 -0.513842)
			(end 4.85267 -1.862582)
			(stroke
				(width 0.1)
				(type default)
			)
			(layer "F.SilkS")
		)
		(fp_line
			(start 3.482594 -5.511292)
			(end 2.593086 -4.658106)
			(stroke
				(width 0.1)
				(type default)
			)
			(layer "F.SilkS")
		)
		(fp_line
			(start 3.482594 -5.511292)
			(end 2.593086 -4.658106)
			(stroke
				(width 0.1)
				(type default)
			)
			(layer "F.SilkS")
		)
		(fp_line
			(start 3.490468 -0.498094)
			(end 4.77901 -1.734058)
			(stroke
				(width 0.1)
				(type default)
			)
			(layer "F.SilkS")
		)
		(fp_line
			(start 3.490468 -0.498094)
			(end 4.77901 -1.734058)
			(stroke
				(width 0.1)
				(type default)
			)
			(layer "F.SilkS")
		)
		(fp_line
			(start 3.527806 -5.497068)
			(end 2.647188 -4.652264)
			(stroke
				(width 0.1)
				(type default)
			)
			(layer "F.SilkS")
		)
		(fp_line
			(start 3.527806 -5.497068)
			(end 2.647188 -4.652264)
			(stroke
				(width 0.1)
				(type default)
			)
			(layer "F.SilkS")
		)
		(fp_line
			(start 3.533648 -0.481838)
			(end 4.147312 -1.070356)
			(stroke
				(width 0.1)
				(type default)
			)
			(layer "F.SilkS")
		)
		(fp_line
			(start 3.533648 -0.481838)
			(end 4.147312 -1.070356)
			(stroke
				(width 0.1)
				(type default)
			)
			(layer "F.SilkS")
		)
		(fp_line
			(start 3.573018 -5.482844)
			(end 2.700782 -4.645914)
			(stroke
				(width 0.1)
				(type default)
			)
			(layer "F.SilkS")
		)
		(fp_line
			(start 3.573018 -5.482844)
			(end 2.700782 -4.645914)
			(stroke
				(width 0.1)
				(type default)
			)
			(layer "F.SilkS")
		)
		(fp_line
			(start 3.61823 -5.468366)
			(end 2.75463 -4.639818)
			(stroke
				(width 0.1)
				(type default)
			)
			(layer "F.SilkS")
		)
		(fp_line
			(start 3.61823 -5.468366)
			(end 2.75463 -4.639818)
			(stroke
				(width 0.1)
				(type default)
			)
			(layer "F.SilkS")
		)
		(fp_line
			(start 3.620008 -0.449072)
			(end 4.2164 -1.02108)
			(stroke
				(width 0.1)
				(type default)
			)
			(layer "F.SilkS")
		)
		(fp_line
			(start 3.620008 -0.449072)
			(end 4.2164 -1.02108)
			(stroke
				(width 0.1)
				(type default)
			)
			(layer "F.SilkS")
		)
		(fp_line
			(start 3.662426 -5.452872)
			(end 2.808478 -4.633976)
			(stroke
				(width 0.1)
				(type default)
			)
			(layer "F.SilkS")
		)
		(fp_line
			(start 3.662426 -5.452872)
			(end 2.808478 -4.633976)
			(stroke
				(width 0.1)
				(type default)
			)
			(layer "F.SilkS")
		)
		(fp_line
			(start 3.663442 -0.43307)
			(end 4.250944 -0.996696)
			(stroke
				(width 0.1)
				(type default)
			)
			(layer "F.SilkS")
		)
		(fp_line
			(start 3.663442 -0.43307)
			(end 4.250944 -0.996696)
			(stroke
				(width 0.1)
				(type default)
			)
			(layer "F.SilkS")
		)
		(fp_line
			(start 3.703828 -5.435092)
			(end 2.860548 -4.626102)
			(stroke
				(width 0.1)
				(type default)
			)
			(layer "F.SilkS")
		)
		(fp_line
			(start 3.703828 -5.435092)
			(end 2.860548 -4.626102)
			(stroke
				(width 0.1)
				(type default)
			)
			(layer "F.SilkS")
		)
		(fp_line
			(start 3.706368 -0.416814)
			(end 4.285488 -0.972058)
			(stroke
				(width 0.1)
				(type default)
			)
			(layer "F.SilkS")
		)
		(fp_line
			(start 3.706368 -0.416814)
			(end 4.285488 -0.972058)
			(stroke
				(width 0.1)
				(type default)
			)
			(layer "F.SilkS")
		)
		(fp_line
			(start 3.745484 -5.417058)
			(end 2.90449 -4.610354)
			(stroke
				(width 0.1)
				(type default)
			)
			(layer "F.SilkS")
		)
		(fp_line
			(start 3.745484 -5.417058)
			(end 2.90449 -4.610354)
			(stroke
				(width 0.1)
				(type default)
			)
			(layer "F.SilkS")
		)
		(fp_line
			(start 3.749548 -0.400304)
			(end 4.320286 -0.947674)
			(stroke
				(width 0.1)
				(type default)
			)
			(layer "F.SilkS")
		)
		(fp_line
			(start 3.749548 -0.400304)
			(end 4.320286 -0.947674)
			(stroke
				(width 0.1)
				(type default)
			)
			(layer "F.SilkS")
		)
		(fp_line
			(start 3.786886 -5.399278)
			(end 2.948432 -4.595114)
			(stroke
				(width 0.1)
				(type default)
			)
			(layer "F.SilkS")
		)
		(fp_line
			(start 3.786886 -5.399278)
			(end 2.948432 -4.595114)
			(stroke
				(width 0.1)
				(type default)
			)
			(layer "F.SilkS")
		)
		(fp_line
			(start 3.792474 -0.383794)
			(end 4.35483 -0.923036)
			(stroke
				(width 0.1)
				(type default)
			)
			(layer "F.SilkS")
		)
		(fp_line
			(start 3.792474 -0.383794)
			(end 4.35483 -0.923036)
			(stroke
				(width 0.1)
				(type default)
			)
			(layer "F.SilkS")
		)
		(fp_line
			(start 3.828288 -5.381498)
			(end 2.992628 -4.57962)
			(stroke
				(width 0.1)
				(type default)
			)
			(layer "F.SilkS")
		)
		(fp_line
			(start 3.828288 -5.381498)
			(end 2.992628 -4.57962)
			(stroke
				(width 0.1)
				(type default)
			)
			(layer "F.SilkS")
		)
		(fp_line
			(start 3.8354 -0.36703)
			(end 4.389374 -0.898398)
			(stroke
				(width 0.1)
				(type default)
			)
			(layer "F.SilkS")
		)
		(fp_line
			(start 3.8354 -0.36703)
			(end 4.389374 -0.898398)
			(stroke
				(width 0.1)
				(type default)
			)
			(layer "F.SilkS")
		)
		(fp_line
			(start 3.870198 -5.363464)
			(end 3.036824 -4.56438)
			(stroke
				(width 0.1)
				(type default)
			)
			(layer "F.SilkS")
		)
		(fp_line
			(start 3.870198 -5.363464)
			(end 3.036824 -4.56438)
			(stroke
				(width 0.1)
				(type default)
			)
			(layer "F.SilkS")
		)
		(fp_line
			(start 3.878326 -0.35052)
			(end 4.423918 -0.874014)
			(stroke
				(width 0.1)
				(type default)
			)
			(layer "F.SilkS")
		)
		(fp_line
			(start 3.878326 -0.35052)
			(end 4.423918 -0.874014)
			(stroke
				(width 0.1)
				(type default)
			)
			(layer "F.SilkS")
		)
		(fp_line
			(start 3.908552 -5.34289)
			(end 3.080766 -4.548886)
			(stroke
				(width 0.1)
				(type default)
			)
			(layer "F.SilkS")
		)
		(fp_line
			(start 3.908552 -5.34289)
			(end 3.080766 -4.548886)
			(stroke
				(width 0.1)
				(type default)
			)
			(layer "F.SilkS")
		)
		(fp_line
			(start 3.921252 -0.33401)
			(end 4.458462 -0.849376)
			(stroke
				(width 0.1)
				(type default)
			)
			(layer "F.SilkS")
		)
		(fp_line
			(start 3.921252 -0.33401)
			(end 4.458462 -0.849376)
			(stroke
				(width 0.1)
				(type default)
			)
			(layer "F.SilkS")
		)
		(fp_line
			(start 3.946652 -5.321808)
			(end 3.12039 -4.529074)
			(stroke
				(width 0.1)
				(type default)
			)
			(layer "F.SilkS")
		)
		(fp_line
			(start 3.946652 -5.321808)
			(end 3.12039 -4.529074)
			(stroke
				(width 0.1)
				(type default)
			)
			(layer "F.SilkS")
		)
		(fp_line
			(start 3.964178 -0.3175)
			(end 4.493006 -0.824738)
			(stroke
				(width 0.1)
				(type default)
			)
			(layer "F.SilkS")
		)
		(fp_line
			(start 3.964178 -0.3175)
			(end 4.493006 -0.824738)
			(stroke
				(width 0.1)
				(type default)
			)
			(layer "F.SilkS")
		)
		(fp_line
			(start 3.984752 -5.300472)
			(end 3.15722 -4.506722)
			(stroke
				(width 0.1)
				(type default)
			)
			(layer "F.SilkS")
		)
		(fp_line
			(start 3.984752 -5.300472)
			(end 3.15722 -4.506722)
			(stroke
				(width 0.1)
				(type default)
			)
			(layer "F.SilkS")
		)
		(fp_line
			(start 4.00685 -0.30099)
			(end 4.52755 -0.800608)
			(stroke
				(width 0.1)
				(type default)
			)
			(layer "F.SilkS")
		)
		(fp_line
			(start 4.00685 -0.30099)
			(end 4.52755 -0.800608)
			(stroke
				(width 0.1)
				(type default)
			)
			(layer "F.SilkS")
		)
		(fp_line
			(start 4.022852 -5.27939)
			(end 3.193796 -4.484116)
			(stroke
				(width 0.1)
				(type default)
			)
			(layer "F.SilkS")
		)
		(fp_line
			(start 4.022852 -5.27939)
			(end 3.193796 -4.484116)
			(stroke
				(width 0.1)
				(type default)
			)
			(layer "F.SilkS")
		)
		(fp_line
			(start 4.049776 -0.284226)
			(end 4.562094 -0.775716)
			(stroke
				(width 0.1)
				(type default)
			)
			(layer "F.SilkS")
		)
		(fp_line
			(start 4.049776 -0.284226)
			(end 4.562094 -0.775716)
			(stroke
				(width 0.1)
				(type default)
			)
			(layer "F.SilkS")
		)
		(fp_line
			(start 4.060952 -5.258054)
			(end 3.230372 -4.461256)
			(stroke
				(width 0.1)
				(type default)
			)
			(layer "F.SilkS")
		)
		(fp_line
			(start 4.060952 -5.258054)
			(end 3.230372 -4.461256)
			(stroke
				(width 0.1)
				(type default)
			)
			(layer "F.SilkS")
		)
		(fp_line
			(start 4.092448 -0.267462)
			(end 4.596892 -0.751332)
			(stroke
				(width 0.1)
				(type default)
			)
			(layer "F.SilkS")
		)
		(fp_line
			(start 4.092448 -0.267462)
			(end 4.596892 -0.751332)
			(stroke
				(width 0.1)
				(type default)
			)
			(layer "F.SilkS")
		)
		(fp_line
			(start 4.09829 -5.23621)
			(end 3.266948 -4.438904)
			(stroke
				(width 0.1)
				(type default)
			)
			(layer "F.SilkS")
		)
		(fp_line
			(start 4.09829 -5.23621)
			(end 3.266948 -4.438904)
			(stroke
				(width 0.1)
				(type default)
			)
			(layer "F.SilkS")
		)
		(fp_line
			(start 4.133088 -5.21208)
			(end 3.303524 -4.416044)
			(stroke
				(width 0.1)
				(type default)
			)
			(layer "F.SilkS")
		)
		(fp_line
			(start 4.133088 -5.21208)
			(end 3.303524 -4.416044)
			(stroke
				(width 0.1)
				(type default)
			)
			(layer "F.SilkS")
		)
		(fp_line
			(start 4.135374 -0.250698)
			(end 4.631436 -0.726694)
			(stroke
				(width 0.1)
				(type default)
			)
			(layer "F.SilkS")
		)
		(fp_line
			(start 4.135374 -0.250698)
			(end 4.631436 -0.726694)
			(stroke
				(width 0.1)
				(type default)
			)
			(layer "F.SilkS")
		)
		(fp_line
			(start 4.16814 -5.187696)
			(end 3.337052 -4.390644)
			(stroke
				(width 0.1)
				(type default)
			)
			(layer "F.SilkS")
		)
		(fp_line
			(start 4.16814 -5.187696)
			(end 3.337052 -4.390644)
			(stroke
				(width 0.1)
				(type default)
			)
			(layer "F.SilkS")
		)
		(fp_line
			(start 4.178046 -0.234188)
			(end 4.66598 -0.702056)
			(stroke
				(width 0.1)
				(type default)
			)
			(layer "F.SilkS")
		)
		(fp_line
			(start 4.178046 -0.234188)
			(end 4.66598 -0.702056)
			(stroke
				(width 0.1)
				(type default)
			)
			(layer "F.SilkS")
		)
		(fp_line
			(start 4.181856 -1.045718)
			(end 3.576828 -0.465582)
			(stroke
				(width 0.1)
				(type default)
			)
			(layer "F.SilkS")
		)
		(fp_line
			(start 4.181856 -1.045718)
			(end 3.576828 -0.465582)
			(stroke
				(width 0.1)
				(type default)
			)
			(layer "F.SilkS")
		)
		(fp_line
			(start 4.202938 -5.163312)
			(end 3.367532 -4.362196)
			(stroke
				(width 0.1)
				(type default)
			)
			(layer "F.SilkS")
		)
		(fp_line
			(start 4.202938 -5.163312)
			(end 3.367532 -4.362196)
			(stroke
				(width 0.1)
				(type default)
			)
			(layer "F.SilkS")
		)
		(fp_line
			(start 4.220718 -0.217678)
			(end 4.700524 -0.677926)
			(stroke
				(width 0.1)
				(type default)
			)
			(layer "F.SilkS")
		)
		(fp_line
			(start 4.220718 -0.217678)
			(end 4.700524 -0.677926)
			(stroke
				(width 0.1)
				(type default)
			)
			(layer "F.SilkS")
		)
		(fp_line
			(start 4.237736 -5.139182)
			(end 3.397504 -4.33324)
			(stroke
				(width 0.1)
				(type default)
			)
			(layer "F.SilkS")
		)
		(fp_line
			(start 4.237736 -5.139182)
			(end 3.397504 -4.33324)
			(stroke
				(width 0.1)
				(type default)
			)
			(layer "F.SilkS")
		)
		(fp_line
			(start 4.26339 -0.200406)
			(end 4.735068 -0.653034)
			(stroke
				(width 0.1)
				(type default)
			)
			(layer "F.SilkS")
		)
		(fp_line
			(start 4.26339 -0.200406)
			(end 4.735068 -0.653034)
			(stroke
				(width 0.1)
				(type default)
			)
			(layer "F.SilkS")
		)
		(fp_line
			(start 4.272534 -5.115052)
			(end 3.427984 -4.304792)
			(stroke
				(width 0.1)
				(type default)
			)
			(layer "F.SilkS")
		)
		(fp_line
			(start 4.272534 -5.115052)
			(end 3.427984 -4.304792)
			(stroke
				(width 0.1)
				(type default)
			)
			(layer "F.SilkS")
		)
		(fp_line
			(start 4.306062 -0.183896)
			(end 4.769866 -0.62865)
			(stroke
				(width 0.1)
				(type default)
			)
			(layer "F.SilkS")
		)
		(fp_line
			(start 4.306062 -0.183896)
			(end 4.769866 -0.62865)
			(stroke
				(width 0.1)
				(type default)
			)
			(layer "F.SilkS")
		)
		(fp_line
			(start 4.306316 -5.089398)
			(end 3.45821 -4.275836)
			(stroke
				(width 0.1)
				(type default)
			)
			(layer "F.SilkS")
		)
		(fp_line
			(start 4.306316 -5.089398)
			(end 3.45821 -4.275836)
			(stroke
				(width 0.1)
				(type default)
			)
			(layer "F.SilkS")
		)
		(fp_line
			(start 4.338066 -5.06222)
			(end 3.488436 -4.247388)
			(stroke
				(width 0.1)
				(type default)
			)
			(layer "F.SilkS")
		)
		(fp_line
			(start 4.338066 -5.06222)
			(end 3.488436 -4.247388)
			(stroke
				(width 0.1)
				(type default)
			)
			(layer "F.SilkS")
		)
		(fp_line
			(start 4.348734 -0.166878)
			(end 4.80441 -0.604266)
			(stroke
				(width 0.1)
				(type default)
			)
			(layer "F.SilkS")
		)
		(fp_line
			(start 4.348734 -0.166878)
			(end 4.80441 -0.604266)
			(stroke
				(width 0.1)
				(type default)
			)
			(layer "F.SilkS")
		)
		(fp_line
			(start 4.37007 -5.035296)
			(end 3.518408 -4.218432)
			(stroke
				(width 0.1)
				(type default)
			)
			(layer "F.SilkS")
		)
		(fp_line
			(start 4.37007 -5.035296)
			(end 3.518408 -4.218432)
			(stroke
				(width 0.1)
				(type default)
			)
			(layer "F.SilkS")
		)
		(fp_line
			(start 4.391406 -0.150114)
			(end 4.838954 -0.579628)
			(stroke
				(width 0.1)
				(type default)
			)
			(layer "F.SilkS")
		)
		(fp_line
			(start 4.391406 -0.150114)
			(end 4.838954 -0.579628)
			(stroke
				(width 0.1)
				(type default)
			)
			(layer "F.SilkS")
		)
		(fp_line
			(start 4.401566 -5.008118)
			(end 3.542792 -4.183888)
			(stroke
				(width 0.1)
				(type default)
			)
			(layer "F.SilkS")
		)
		(fp_line
			(start 4.401566 -5.008118)
			(end 3.542792 -4.183888)
			(stroke
				(width 0.1)
				(type default)
			)
			(layer "F.SilkS")
		)
		(fp_line
			(start 4.43357 -4.98094)
			(end 3.567176 -4.149598)
			(stroke
				(width 0.1)
				(type default)
			)
			(layer "F.SilkS")
		)
		(fp_line
			(start 4.43357 -4.98094)
			(end 3.567176 -4.149598)
			(stroke
				(width 0.1)
				(type default)
			)
			(layer "F.SilkS")
		)
		(fp_line
			(start 4.433824 -0.133604)
			(end 4.873752 -0.555244)
			(stroke
				(width 0.1)
				(type default)
			)
			(layer "F.SilkS")
		)
		(fp_line
			(start 4.433824 -0.133604)
			(end 4.873752 -0.555244)
			(stroke
				(width 0.1)
				(type default)
			)
			(layer "F.SilkS")
		)
		(fp_line
			(start 4.46532 -4.953508)
			(end 3.59156 -4.115308)
			(stroke
				(width 0.1)
				(type default)
			)
			(layer "F.SilkS")
		)
		(fp_line
			(start 4.46532 -4.953508)
			(end 3.59156 -4.115308)
			(stroke
				(width 0.1)
				(type default)
			)
			(layer "F.SilkS")
		)
		(fp_line
			(start 4.476496 -0.116332)
			(end 4.908296 -0.530352)
			(stroke
				(width 0.1)
				(type default)
			)
			(layer "F.SilkS")
		)
		(fp_line
			(start 4.476496 -0.116332)
			(end 4.908296 -0.530352)
			(stroke
				(width 0.1)
				(type default)
			)
			(layer "F.SilkS")
		)
		(fp_line
			(start 4.4958 -4.92506)
			(end 3.615944 -4.081018)
			(stroke
				(width 0.1)
				(type default)
			)
			(layer "F.SilkS")
		)
		(fp_line
			(start 4.4958 -4.92506)
			(end 3.615944 -4.081018)
			(stroke
				(width 0.1)
				(type default)
			)
			(layer "F.SilkS")
		)
		(fp_line
			(start 4.519168 -0.099822)
			(end 4.94284 -0.506222)
			(stroke
				(width 0.1)
				(type default)
			)
			(layer "F.SilkS")
		)
		(fp_line
			(start 4.519168 -0.099822)
			(end 4.94284 -0.506222)
			(stroke
				(width 0.1)
				(type default)
			)
			(layer "F.SilkS")
		)
		(fp_line
			(start 4.52374 -4.894072)
			(end 3.640328 -4.046728)
			(stroke
				(width 0.1)
				(type default)
			)
			(layer "F.SilkS")
		)
		(fp_line
			(start 4.52374 -4.894072)
			(end 3.640328 -4.046728)
			(stroke
				(width 0.1)
				(type default)
			)
			(layer "F.SilkS")
		)
		(fp_line
			(start 4.55168 -4.863338)
			(end 3.664712 -4.012438)
			(stroke
				(width 0.1)
				(type default)
			)
			(layer "F.SilkS")
		)
		(fp_line
			(start 4.55168 -4.863338)
			(end 3.664712 -4.012438)
			(stroke
				(width 0.1)
				(type default)
			)
			(layer "F.SilkS")
		)
		(fp_line
			(start 4.561586 -0.08255)
			(end 4.977384 -0.481584)
			(stroke
				(width 0.1)
				(type default)
			)
			(layer "F.SilkS")
		)
		(fp_line
			(start 4.561586 -0.08255)
			(end 4.977384 -0.481584)
			(stroke
				(width 0.1)
				(type default)
			)
			(layer "F.SilkS")
		)
		(fp_line
			(start 4.57962 -4.83235)
			(end 3.686556 -3.975608)
			(stroke
				(width 0.1)
				(type default)
			)
			(layer "F.SilkS")
		)
		(fp_line
			(start 4.57962 -4.83235)
			(end 3.686556 -3.975608)
			(stroke
				(width 0.1)
				(type default)
			)
			(layer "F.SilkS")
		)
		(fp_line
			(start 4.60756 -4.801362)
			(end 3.704844 -3.935476)
			(stroke
				(width 0.1)
				(type default)
			)
			(layer "F.SilkS")
		)
		(fp_line
			(start 4.60756 -4.801362)
			(end 3.704844 -3.935476)
			(stroke
				(width 0.1)
				(type default)
			)
			(layer "F.SilkS")
		)
		(fp_line
			(start 4.631182 -0.091948)
			(end 4.713478 -0.112776)
			(stroke
				(width 0.1)
				(type default)
			)
			(layer "F.SilkS")
		)
		(fp_line
			(start 4.631182 -0.091948)
			(end 4.713478 -0.112776)
			(stroke
				(width 0.1)
				(type default)
			)
			(layer "F.SilkS")
		)
		(fp_line
			(start 4.631182 -0.091948)
			(end 5.012182 -0.456946)
			(stroke
				(width 0.1)
				(type default)
			)
			(layer "F.SilkS")
		)
		(fp_line
			(start 4.631182 -0.091948)
			(end 5.012182 -0.456946)
			(stroke
				(width 0.1)
				(type default)
			)
			(layer "F.SilkS")
		)
		(fp_line
			(start 4.635246 -4.770374)
			(end 3.723386 -3.895598)
			(stroke
				(width 0.1)
				(type default)
			)
			(layer "F.SilkS")
		)
		(fp_line
			(start 4.635246 -4.770374)
			(end 3.723386 -3.895598)
			(stroke
				(width 0.1)
				(type default)
			)
			(layer "F.SilkS")
		)
		(fp_line
			(start 4.663186 -4.739386)
			(end 3.741928 -3.85572)
			(stroke
				(width 0.1)
				(type default)
			)
			(layer "F.SilkS")
		)
		(fp_line
			(start 4.663186 -4.739386)
			(end 3.741928 -3.85572)
			(stroke
				(width 0.1)
				(type default)
			)
			(layer "F.SilkS")
		)
		(fp_line
			(start 4.690618 -4.70789)
			(end 3.76047 -3.815588)
			(stroke
				(width 0.1)
				(type default)
			)
			(layer "F.SilkS")
		)
		(fp_line
			(start 4.690618 -4.70789)
			(end 3.76047 -3.815588)
			(stroke
				(width 0.1)
				(type default)
			)
			(layer "F.SilkS")
		)
		(fp_line
			(start 4.713478 -0.112776)
			(end 4.795266 -0.133604)
			(stroke
				(width 0.1)
				(type default)
			)
			(layer "F.SilkS")
		)
		(fp_line
			(start 4.713478 -0.112776)
			(end 4.795266 -0.133604)
			(stroke
				(width 0.1)
				(type default)
			)
			(layer "F.SilkS")
		)
		(fp_line
			(start 4.713478 -0.112776)
			(end 5.046726 -0.432562)
			(stroke
				(width 0.1)
				(type default)
			)
			(layer "F.SilkS")
		)
		(fp_line
			(start 4.713478 -0.112776)
			(end 5.046726 -0.432562)
			(stroke
				(width 0.1)
				(type default)
			)
			(layer "F.SilkS")
		)
		(fp_line
			(start 4.713732 -4.672584)
			(end 3.778758 -3.775456)
			(stroke
				(width 0.1)
				(type default)
			)
			(layer "F.SilkS")
		)
		(fp_line
			(start 4.713732 -4.672584)
			(end 3.778758 -3.775456)
			(stroke
				(width 0.1)
				(type default)
			)
			(layer "F.SilkS")
		)
		(fp_line
			(start 4.7371 -4.637278)
			(end 3.7973 -3.735578)
			(stroke
				(width 0.1)
				(type default)
			)
			(layer "F.SilkS")
		)
		(fp_line
			(start 4.7371 -4.637278)
			(end 3.7973 -3.735578)
			(stroke
				(width 0.1)
				(type default)
			)
			(layer "F.SilkS")
		)
		(fp_line
			(start 4.760214 -4.601718)
			(end 3.81 -3.689858)
			(stroke
				(width 0.1)
				(type default)
			)
			(layer "F.SilkS")
		)
		(fp_line
			(start 4.760214 -4.601718)
			(end 3.81 -3.689858)
			(stroke
				(width 0.1)
				(type default)
			)
			(layer "F.SilkS")
		)
		(fp_line
			(start 4.783582 -4.566158)
			(end 3.821938 -3.643884)
			(stroke
				(width 0.1)
				(type default)
			)
			(layer "F.SilkS")
		)
		(fp_line
			(start 4.783582 -4.566158)
			(end 3.821938 -3.643884)
			(stroke
				(width 0.1)
				(type default)
			)
			(layer "F.SilkS")
		)
		(fp_line
			(start 4.795266 -0.133604)
			(end 4.877308 -0.15494)
			(stroke
				(width 0.1)
				(type default)
			)
			(layer "F.SilkS")
		)
		(fp_line
			(start 4.795266 -0.133604)
			(end 4.877308 -0.15494)
			(stroke
				(width 0.1)
				(type default)
			)
			(layer "F.SilkS")
		)
		(fp_line
			(start 4.795266 -0.133604)
			(end 5.08127 -0.408178)
			(stroke
				(width 0.1)
				(type default)
			)
			(layer "F.SilkS")
		)
		(fp_line
			(start 4.795266 -0.133604)
			(end 5.08127 -0.408178)
			(stroke
				(width 0.1)
				(type default)
			)
			(layer "F.SilkS")
		)
		(fp_line
			(start 4.806696 -4.530852)
			(end 3.83413 -3.59791)
			(stroke
				(width 0.1)
				(type default)
			)
			(layer "F.SilkS")
		)
		(fp_line
			(start 4.806696 -4.530852)
			(end 3.83413 -3.59791)
			(stroke
				(width 0.1)
				(type default)
			)
			(layer "F.SilkS")
		)
		(fp_line
			(start 4.82981 -4.495292)
			(end 3.846068 -3.551682)
			(stroke
				(width 0.1)
				(type default)
			)
			(layer "F.SilkS")
		)
		(fp_line
			(start 4.82981 -4.495292)
			(end 3.846068 -3.551682)
			(stroke
				(width 0.1)
				(type default)
			)
			(layer "F.SilkS")
		)
		(fp_line
			(start 4.851654 -4.458462)
			(end 3.858006 -3.505454)
			(stroke
				(width 0.1)
				(type default)
			)
			(layer "F.SilkS")
		)
		(fp_line
			(start 4.851654 -4.458462)
			(end 3.858006 -3.505454)
			(stroke
				(width 0.1)
				(type default)
			)
			(layer "F.SilkS")
		)
		(fp_line
			(start 4.870958 -4.419092)
			(end 3.870198 -3.459226)
			(stroke
				(width 0.1)
				(type default)
			)
			(layer "F.SilkS")
		)
		(fp_line
			(start 4.870958 -4.419092)
			(end 3.870198 -3.459226)
			(stroke
				(width 0.1)
				(type default)
			)
			(layer "F.SilkS")
		)
		(fp_line
			(start 4.877308 -0.15494)
			(end 4.95935 -0.175514)
			(stroke
				(width 0.1)
				(type default)
			)
			(layer "F.SilkS")
		)
		(fp_line
			(start 4.877308 -0.15494)
			(end 4.95935 -0.175514)
			(stroke
				(width 0.1)
				(type default)
			)
			(layer "F.SilkS")
		)
		(fp_line
			(start 4.877308 -0.15494)
			(end 5.115814 -0.383794)
			(stroke
				(width 0.1)
				(type default)
			)
			(layer "F.SilkS")
		)
		(fp_line
			(start 4.877308 -0.15494)
			(end 5.115814 -0.383794)
			(stroke
				(width 0.1)
				(type default)
			)
			(layer "F.SilkS")
		)
		(fp_line
			(start 4.889754 -4.379722)
			(end 3.878072 -3.409188)
			(stroke
				(width 0.1)
				(type default)
			)
			(layer "F.SilkS")
		)
		(fp_line
			(start 4.889754 -4.379722)
			(end 3.878072 -3.409188)
			(stroke
				(width 0.1)
				(type default)
			)
			(layer "F.SilkS")
		)
		(fp_line
			(start 4.908804 -4.340098)
			(end 3.88239 -3.355848)
			(stroke
				(width 0.1)
				(type default)
			)
			(layer "F.SilkS")
		)
		(fp_line
			(start 4.908804 -4.340098)
			(end 3.88239 -3.355848)
			(stroke
				(width 0.1)
				(type default)
			)
			(layer "F.SilkS")
		)
		(fp_line
			(start 4.927854 -4.300728)
			(end 3.886962 -3.302254)
			(stroke
				(width 0.1)
				(type default)
			)
			(layer "F.SilkS")
		)
		(fp_line
			(start 4.927854 -4.300728)
			(end 3.886962 -3.302254)
			(stroke
				(width 0.1)
				(type default)
			)
			(layer "F.SilkS")
		)
		(fp_line
			(start 4.946904 -4.261358)
			(end 3.891534 -3.248914)
			(stroke
				(width 0.1)
				(type default)
			)
			(layer "F.SilkS")
		)
		(fp_line
			(start 4.946904 -4.261358)
			(end 3.891534 -3.248914)
			(stroke
				(width 0.1)
				(type default)
			)
			(layer "F.SilkS")
		)
		(fp_line
			(start 4.95935 -0.175514)
			(end 5.041392 -0.196596)
			(stroke
				(width 0.1)
				(type default)
			)
			(layer "F.SilkS")
		)
		(fp_line
			(start 4.95935 -0.175514)
			(end 5.041392 -0.196596)
			(stroke
				(width 0.1)
				(type default)
			)
			(layer "F.SilkS")
		)
		(fp_line
			(start 4.95935 -0.175514)
			(end 5.150612 -0.359156)
			(stroke
				(width 0.1)
				(type default)
			)
			(layer "F.SilkS")
		)
		(fp_line
			(start 4.95935 -0.175514)
			(end 5.150612 -0.359156)
			(stroke
				(width 0.1)
				(type default)
			)
			(layer "F.SilkS")
		)
		(fp_line
			(start 4.965446 -4.221226)
			(end 3.895852 -3.19532)
			(stroke
				(width 0.1)
				(type default)
			)
			(layer "F.SilkS")
		)
		(fp_line
			(start 4.965446 -4.221226)
			(end 3.895852 -3.19532)
			(stroke
				(width 0.1)
				(type default)
			)
			(layer "F.SilkS")
		)
		(fp_line
			(start 4.980686 -4.1783)
			(end 3.900424 -3.14198)
			(stroke
				(width 0.1)
				(type default)
			)
			(layer "F.SilkS")
		)
		(fp_line
			(start 4.980686 -4.1783)
			(end 3.900424 -3.14198)
			(stroke
				(width 0.1)
				(type default)
			)
			(layer "F.SilkS")
		)
		(fp_line
			(start 4.995672 -4.13512)
			(end 3.899408 -3.083306)
			(stroke
				(width 0.1)
				(type default)
			)
			(layer "F.SilkS")
		)
		(fp_line
			(start 4.995672 -4.13512)
			(end 3.899408 -3.083306)
			(stroke
				(width 0.1)
				(type default)
			)
			(layer "F.SilkS")
		)
		(fp_line
			(start 5.011166 -4.09194)
			(end 3.894328 -3.020822)
			(stroke
				(width 0.1)
				(type default)
			)
			(layer "F.SilkS")
		)
		(fp_line
			(start 5.011166 -4.09194)
			(end 3.894328 -3.020822)
			(stroke
				(width 0.1)
				(type default)
			)
			(layer "F.SilkS")
		)
		(fp_line
			(start 5.026152 -4.04876)
			(end 3.889248 -2.958084)
			(stroke
				(width 0.1)
				(type default)
			)
			(layer "F.SilkS")
		)
		(fp_line
			(start 5.026152 -4.04876)
			(end 3.889248 -2.958084)
			(stroke
				(width 0.1)
				(type default)
			)
			(layer "F.SilkS")
		)
		(fp_line
			(start 5.041392 -4.00558)
			(end 3.884168 -2.8956)
			(stroke
				(width 0.1)
				(type default)
			)
			(layer "F.SilkS")
		)
		(fp_line
			(start 5.041392 -4.00558)
			(end 3.884168 -2.8956)
			(stroke
				(width 0.1)
				(type default)
			)
			(layer "F.SilkS")
		)
		(fp_line
			(start 5.041392 -0.196596)
			(end 5.12318 -0.217678)
			(stroke
				(width 0.1)
				(type default)
			)
			(layer "F.SilkS")
		)
		(fp_line
			(start 5.041392 -0.196596)
			(end 5.12318 -0.217678)
			(stroke
				(width 0.1)
				(type default)
			)
			(layer "F.SilkS")
		)
		(fp_line
			(start 5.041392 -0.196596)
			(end 5.185156 -0.334772)
			(stroke
				(width 0.1)
				(type default)
			)
			(layer "F.SilkS")
		)
		(fp_line
			(start 5.041392 -0.196596)
			(end 5.185156 -0.334772)
			(stroke
				(width 0.1)
				(type default)
			)
			(layer "F.SilkS")
		)
		(fp_line
			(start 5.0546 -3.960622)
			(end 3.879088 -2.832862)
			(stroke
				(width 0.1)
				(type default)
			)
			(layer "F.SilkS")
		)
		(fp_line
			(start 5.0546 -3.960622)
			(end 3.879088 -2.832862)
			(stroke
				(width 0.1)
				(type default)
			)
			(layer "F.SilkS")
		)
		(fp_line
			(start 5.066284 -3.91414)
			(end 3.863086 -2.75971)
			(stroke
				(width 0.1)
				(type default)
			)
			(layer "F.SilkS")
		)
		(fp_line
			(start 5.066284 -3.91414)
			(end 3.863086 -2.75971)
			(stroke
				(width 0.1)
				(type default)
			)
			(layer "F.SilkS")
		)
		(fp_line
			(start 5.078222 -3.867658)
			(end 3.843782 -2.68351)
			(stroke
				(width 0.1)
				(type default)
			)
			(layer "F.SilkS")
		)
		(fp_line
			(start 5.078222 -3.867658)
			(end 3.843782 -2.68351)
			(stroke
				(width 0.1)
				(type default)
			)
			(layer "F.SilkS")
		)
		(fp_line
			(start 5.089652 -3.821176)
			(end 3.824478 -2.607564)
			(stroke
				(width 0.1)
				(type default)
			)
			(layer "F.SilkS")
		)
		(fp_line
			(start 5.089652 -3.821176)
			(end 3.824478 -2.607564)
			(stroke
				(width 0.1)
				(type default)
			)
			(layer "F.SilkS")
		)
		(fp_line
			(start 5.101336 -3.774694)
			(end 3.802126 -2.528316)
			(stroke
				(width 0.1)
				(type default)
			)
			(layer "F.SilkS")
		)
		(fp_line
			(start 5.101336 -3.774694)
			(end 3.802126 -2.528316)
			(stroke
				(width 0.1)
				(type default)
			)
			(layer "F.SilkS")
		)
		(fp_line
			(start 5.110734 -3.72618)
			(end 3.756406 -2.426716)
			(stroke
				(width 0.1)
				(type default)
			)
			(layer "F.SilkS")
		)
		(fp_line
			(start 5.110734 -3.72618)
			(end 3.756406 -2.426716)
			(stroke
				(width 0.1)
				(type default)
			)
			(layer "F.SilkS")
		)
		(fp_line
			(start 5.11937 -3.676396)
			(end 3.710686 -2.32537)
			(stroke
				(width 0.1)
				(type default)
			)
			(layer "F.SilkS")
		)
		(fp_line
			(start 5.11937 -3.676396)
			(end 3.710686 -2.32537)
			(stroke
				(width 0.1)
				(type default)
			)
			(layer "F.SilkS")
		)
		(fp_line
			(start 5.12318 -0.217678)
			(end 5.205222 -0.238252)
			(stroke
				(width 0.1)
				(type default)
			)
			(layer "F.SilkS")
		)
		(fp_line
			(start 5.12318 -0.217678)
			(end 5.205222 -0.238252)
			(stroke
				(width 0.1)
				(type default)
			)
			(layer "F.SilkS")
		)
		(fp_line
			(start 5.12318 -0.217678)
			(end 5.219954 -0.310388)
			(stroke
				(width 0.1)
				(type default)
			)
			(layer "F.SilkS")
		)
		(fp_line
			(start 5.12318 -0.217678)
			(end 5.219954 -0.310388)
			(stroke
				(width 0.1)
				(type default)
			)
			(layer "F.SilkS")
		)
		(fp_line
			(start 5.127498 -3.626612)
			(end 3.618992 -2.17932)
			(stroke
				(width 0.1)
				(type default)
			)
			(layer "F.SilkS")
		)
		(fp_line
			(start 5.127498 -3.626612)
			(end 3.618992 -2.17932)
			(stroke
				(width 0.1)
				(type default)
			)
			(layer "F.SilkS")
		)
		(fp_line
			(start 5.13588 -3.576828)
			(end 2.15773 -0.719836)
			(stroke
				(width 0.1)
				(type default)
			)
			(layer "F.SilkS")
		)
		(fp_line
			(start 5.13588 -3.576828)
			(end 2.15773 -0.719836)
			(stroke
				(width 0.1)
				(type default)
			)
			(layer "F.SilkS")
		)
		(fp_line
			(start 5.205222 -0.238252)
			(end 5.254752 -0.28575)
			(stroke
				(width 0.1)
				(type default)
			)
			(layer "F.SilkS")
		)
		(fp_line
			(start 5.205222 -0.238252)
			(end 5.254752 -0.28575)
			(stroke
				(width 0.1)
				(type default)
			)
			(layer "F.SilkS")
		)
		(fp_line
			(start 5.287264 -0.259588)
			(end 5.205222 -0.238252)
			(stroke
				(width 0.1)
				(type default)
			)
			(layer "F.SilkS")
		)
		(fp_line
			(start 5.287264 -0.259588)
			(end 5.205222 -0.238252)
			(stroke
				(width 0.1)
				(type default)
			)
			(layer "F.SilkS")
		)
		(fp_line
			(start 5.287264 -0.259588)
			(end 5.289296 -0.261366)
			(stroke
				(width 0.1)
				(type default)
			)
			(layer "F.SilkS")
		)
		(fp_line
			(start 5.287264 -0.259588)
			(end 5.289296 -0.261366)
			(stroke
				(width 0.1)
				(type default)
			)
			(layer "F.SilkS")
		)
		(fp_line
			(start 5.507482 -2.281682)
			(end 6.825488 -3.54584)
			(stroke
				(width 0.1)
				(type default)
			)
			(layer "F.SilkS")
		)
		(fp_line
			(start 5.507482 -2.281682)
			(end 6.825488 -3.54584)
			(stroke
				(width 0.1)
				(type default)
			)
			(layer "F.SilkS")
		)
		(fp_line
			(start 5.50799 -2.224278)
			(end 6.81355 -3.476498)
			(stroke
				(width 0.1)
				(type default)
			)
			(layer "F.SilkS")
		)
		(fp_line
			(start 5.50799 -2.224278)
			(end 6.81355 -3.476498)
			(stroke
				(width 0.1)
				(type default)
			)
			(layer "F.SilkS")
		)
		(fp_line
			(start 5.508498 -2.167128)
			(end 6.801104 -3.407156)
			(stroke
				(width 0.1)
				(type default)
			)
			(layer "F.SilkS")
		)
		(fp_line
			(start 5.508498 -2.167128)
			(end 6.801104 -3.407156)
			(stroke
				(width 0.1)
				(type default)
			)
			(layer "F.SilkS")
		)
		(fp_line
			(start 5.508752 -2.109724)
			(end 6.788912 -3.337814)
			(stroke
				(width 0.1)
				(type default)
			)
			(layer "F.SilkS")
		)
		(fp_line
			(start 5.508752 -2.109724)
			(end 6.788912 -3.337814)
			(stroke
				(width 0.1)
				(type default)
			)
			(layer "F.SilkS")
		)
		(fp_line
			(start 5.50926 -2.052574)
			(end 6.776974 -3.268472)
			(stroke
				(width 0.1)
				(type default)
			)
			(layer "F.SilkS")
		)
		(fp_line
			(start 5.50926 -2.052574)
			(end 6.776974 -3.268472)
			(stroke
				(width 0.1)
				(type default)
			)
			(layer "F.SilkS")
		)
		(fp_line
			(start 5.509768 -1.99517)
			(end 6.764782 -3.19913)
			(stroke
				(width 0.1)
				(type default)
			)
			(layer "F.SilkS")
		)
		(fp_line
			(start 5.509768 -1.99517)
			(end 6.764782 -3.19913)
			(stroke
				(width 0.1)
				(type default)
			)
			(layer "F.SilkS")
		)
		(fp_line
			(start 5.510276 -1.937766)
			(end 6.75259 -3.129534)
			(stroke
				(width 0.1)
				(type default)
			)
			(layer "F.SilkS")
		)
		(fp_line
			(start 5.510276 -1.937766)
			(end 6.75259 -3.129534)
			(stroke
				(width 0.1)
				(type default)
			)
			(layer "F.SilkS")
		)
		(fp_line
			(start 5.518912 -1.88849)
			(end 6.740144 -3.060192)
			(stroke
				(width 0.1)
				(type default)
			)
			(layer "F.SilkS")
		)
		(fp_line
			(start 5.518912 -1.88849)
			(end 6.740144 -3.060192)
			(stroke
				(width 0.1)
				(type default)
			)
			(layer "F.SilkS")
		)
		(fp_line
			(start 5.527802 -1.839214)
			(end 6.728206 -2.99085)
			(stroke
				(width 0.1)
				(type default)
			)
			(layer "F.SilkS")
		)
		(fp_line
			(start 5.527802 -1.839214)
			(end 6.728206 -2.99085)
			(stroke
				(width 0.1)
				(type default)
			)
			(layer "F.SilkS")
		)
		(fp_line
			(start 5.536438 -1.789938)
			(end 6.716014 -2.921254)
			(stroke
				(width 0.1)
				(type default)
			)
			(layer "F.SilkS")
		)
		(fp_line
			(start 5.536438 -1.789938)
			(end 6.716014 -2.921254)
			(stroke
				(width 0.1)
				(type default)
			)
			(layer "F.SilkS")
		)
		(fp_line
			(start 5.545582 -1.740916)
			(end 6.703822 -2.852166)
			(stroke
				(width 0.1)
				(type default)
			)
			(layer "F.SilkS")
		)
		(fp_line
			(start 5.545582 -1.740916)
			(end 6.703822 -2.852166)
			(stroke
				(width 0.1)
				(type default)
			)
			(layer "F.SilkS")
		)
		(fp_line
			(start 5.554218 -1.69164)
			(end 6.695186 -2.786126)
			(stroke
				(width 0.1)
				(type default)
			)
			(layer "F.SilkS")
		)
		(fp_line
			(start 5.554218 -1.69164)
			(end 6.695186 -2.786126)
			(stroke
				(width 0.1)
				(type default)
			)
			(layer "F.SilkS")
		)
		(fp_line
			(start 5.563108 -1.642364)
			(end 6.68655 -2.720086)
			(stroke
				(width 0.1)
				(type default)
			)
			(layer "F.SilkS")
		)
		(fp_line
			(start 5.563108 -1.642364)
			(end 6.68655 -2.720086)
			(stroke
				(width 0.1)
				(type default)
			)
			(layer "F.SilkS")
		)
		(fp_line
			(start 5.573522 -1.594612)
			(end 6.678168 -2.6543)
			(stroke
				(width 0.1)
				(type default)
			)
			(layer "F.SilkS")
		)
		(fp_line
			(start 5.573522 -1.594612)
			(end 6.678168 -2.6543)
			(stroke
				(width 0.1)
				(type default)
			)
			(layer "F.SilkS")
		)
		(fp_line
			(start 5.58038 -2.870962)
			(end 5.568188 -2.801366)
			(stroke
				(width 0.1)
				(type default)
			)
			(layer "F.SilkS")
		)
		(fp_line
			(start 5.58038 -2.870962)
			(end 5.568188 -2.801366)
			(stroke
				(width 0.1)
				(type default)
			)
			(layer "F.SilkS")
		)
		(fp_line
			(start 5.591048 -1.553718)
			(end 6.669532 -2.58826)
			(stroke
				(width 0.1)
				(type default)
			)
			(layer "F.SilkS")
		)
		(fp_line
			(start 5.591048 -1.553718)
			(end 6.669532 -2.58826)
			(stroke
				(width 0.1)
				(type default)
			)
			(layer "F.SilkS")
		)
		(fp_line
			(start 5.592572 -2.940304)
			(end 5.58038 -2.870962)
			(stroke
				(width 0.1)
				(type default)
			)
			(layer "F.SilkS")
		)
		(fp_line
			(start 5.592572 -2.940304)
			(end 5.58038 -2.870962)
			(stroke
				(width 0.1)
				(type default)
			)
			(layer "F.SilkS")
		)
		(fp_line
			(start 5.604764 -3.009646)
			(end 5.592572 -2.940304)
			(stroke
				(width 0.1)
				(type default)
			)
			(layer "F.SilkS")
		)
		(fp_line
			(start 5.604764 -3.009646)
			(end 5.592572 -2.940304)
			(stroke
				(width 0.1)
				(type default)
			)
			(layer "F.SilkS")
		)
		(fp_line
			(start 5.60832 -1.51257)
			(end 6.669024 -2.530094)
			(stroke
				(width 0.1)
				(type default)
			)
			(layer "F.SilkS")
		)
		(fp_line
			(start 5.60832 -1.51257)
			(end 6.669024 -2.530094)
			(stroke
				(width 0.1)
				(type default)
			)
			(layer "F.SilkS")
		)
		(fp_line
			(start 5.616956 -3.079242)
			(end 5.604764 -3.009646)
			(stroke
				(width 0.1)
				(type default)
			)
			(layer "F.SilkS")
		)
		(fp_line
			(start 5.616956 -3.079242)
			(end 5.604764 -3.009646)
			(stroke
				(width 0.1)
				(type default)
			)
			(layer "F.SilkS")
		)
		(fp_line
			(start 5.625846 -1.471676)
			(end 6.668516 -2.471928)
			(stroke
				(width 0.1)
				(type default)
			)
			(layer "F.SilkS")
		)
		(fp_line
			(start 5.625846 -1.471676)
			(end 6.668516 -2.471928)
			(stroke
				(width 0.1)
				(type default)
			)
			(layer "F.SilkS")
		)
		(fp_line
			(start 5.629148 -3.148584)
			(end 5.616956 -3.079242)
			(stroke
				(width 0.1)
				(type default)
			)
			(layer "F.SilkS")
		)
		(fp_line
			(start 5.629148 -3.148584)
			(end 5.616956 -3.079242)
			(stroke
				(width 0.1)
				(type default)
			)
			(layer "F.SilkS")
		)
		(fp_line
			(start 5.64134 -3.217926)
			(end 5.629148 -3.148584)
			(stroke
				(width 0.1)
				(type default)
			)
			(layer "F.SilkS")
		)
		(fp_line
			(start 5.64134 -3.217926)
			(end 5.629148 -3.148584)
			(stroke
				(width 0.1)
				(type default)
			)
			(layer "F.SilkS")
		)
		(fp_line
			(start 5.643118 -1.430528)
			(end 6.668008 -2.413762)
			(stroke
				(width 0.1)
				(type default)
			)
			(layer "F.SilkS")
		)
		(fp_line
			(start 5.643118 -1.430528)
			(end 6.668008 -2.413762)
			(stroke
				(width 0.1)
				(type default)
			)
			(layer "F.SilkS")
		)
		(fp_line
			(start 5.653532 -3.287268)
			(end 5.64134 -3.217926)
			(stroke
				(width 0.1)
				(type default)
			)
			(layer "F.SilkS")
		)
		(fp_line
			(start 5.653532 -3.287268)
			(end 5.64134 -3.217926)
			(stroke
				(width 0.1)
				(type default)
			)
			(layer "F.SilkS")
		)
		(fp_line
			(start 5.660644 -1.389634)
			(end 6.67004 -2.357882)
			(stroke
				(width 0.1)
				(type default)
			)
			(layer "F.SilkS")
		)
		(fp_line
			(start 5.660644 -1.389634)
			(end 6.67004 -2.357882)
			(stroke
				(width 0.1)
				(type default)
			)
			(layer "F.SilkS")
		)
		(fp_line
			(start 5.665724 -3.35661)
			(end 5.653532 -3.287268)
			(stroke
				(width 0.1)
				(type default)
			)
			(layer "F.SilkS")
		)
		(fp_line
			(start 5.665724 -3.35661)
			(end 5.653532 -3.287268)
			(stroke
				(width 0.1)
				(type default)
			)
			(layer "F.SilkS")
		)
		(fp_line
			(start 5.677662 -3.425952)
			(end 5.665724 -3.35661)
			(stroke
				(width 0.1)
				(type default)
			)
			(layer "F.SilkS")
		)
		(fp_line
			(start 5.677662 -3.425952)
			(end 5.665724 -3.35661)
			(stroke
				(width 0.1)
				(type default)
			)
			(layer "F.SilkS")
		)
		(fp_line
			(start 5.677916 -1.34874)
			(end 6.678168 -2.308352)
			(stroke
				(width 0.1)
				(type default)
			)
			(layer "F.SilkS")
		)
		(fp_line
			(start 5.677916 -1.34874)
			(end 6.678168 -2.308352)
			(stroke
				(width 0.1)
				(type default)
			)
			(layer "F.SilkS")
		)
		(fp_line
			(start 5.690108 -3.495548)
			(end 5.677662 -3.425952)
			(stroke
				(width 0.1)
				(type default)
			)
			(layer "F.SilkS")
		)
		(fp_line
			(start 5.690108 -3.495548)
			(end 5.677662 -3.425952)
			(stroke
				(width 0.1)
				(type default)
			)
			(layer "F.SilkS")
		)
		(fp_line
			(start 5.697982 -1.310132)
			(end 6.68655 -2.258568)
			(stroke
				(width 0.1)
				(type default)
			)
			(layer "F.SilkS")
		)
		(fp_line
			(start 5.697982 -1.310132)
			(end 6.68655 -2.258568)
			(stroke
				(width 0.1)
				(type default)
			)
			(layer "F.SilkS")
		)
		(fp_line
			(start 5.7023 -3.56489)
			(end 5.690108 -3.495548)
			(stroke
				(width 0.1)
				(type default)
			)
			(layer "F.SilkS")
		)
		(fp_line
			(start 5.7023 -3.56489)
			(end 5.690108 -3.495548)
			(stroke
				(width 0.1)
				(type default)
			)
			(layer "F.SilkS")
		)
		(fp_line
			(start 5.714238 -3.634232)
			(end 5.7023 -3.56489)
			(stroke
				(width 0.1)
				(type default)
			)
			(layer "F.SilkS")
		)
		(fp_line
			(start 5.714238 -3.634232)
			(end 5.7023 -3.56489)
			(stroke
				(width 0.1)
				(type default)
			)
			(layer "F.SilkS")
		)
		(fp_line
			(start 5.724398 -1.27762)
			(end 6.694932 -2.20853)
			(stroke
				(width 0.1)
				(type default)
			)
			(layer "F.SilkS")
		)
		(fp_line
			(start 5.724398 -1.27762)
			(end 6.694932 -2.20853)
			(stroke
				(width 0.1)
				(type default)
			)
			(layer "F.SilkS")
		)
		(fp_line
			(start 5.72643 -3.703828)
			(end 5.714238 -3.634232)
			(stroke
				(width 0.1)
				(type default)
			)
			(layer "F.SilkS")
		)
		(fp_line
			(start 5.72643 -3.703828)
			(end 5.714238 -3.634232)
			(stroke
				(width 0.1)
				(type default)
			)
			(layer "F.SilkS")
		)
		(fp_line
			(start 5.738876 -3.772916)
			(end 5.72643 -3.703828)
			(stroke
				(width 0.1)
				(type default)
			)
			(layer "F.SilkS")
		)
		(fp_line
			(start 5.738876 -3.772916)
			(end 5.72643 -3.703828)
			(stroke
				(width 0.1)
				(type default)
			)
			(layer "F.SilkS")
		)
		(fp_line
			(start 5.750306 -1.244854)
			(end 6.710934 -2.166366)
			(stroke
				(width 0.1)
				(type default)
			)
			(layer "F.SilkS")
		)
		(fp_line
			(start 5.750306 -1.244854)
			(end 6.710934 -2.166366)
			(stroke
				(width 0.1)
				(type default)
			)
			(layer "F.SilkS")
		)
		(fp_line
			(start 5.751068 -3.842512)
			(end 5.738876 -3.772916)
			(stroke
				(width 0.1)
				(type default)
			)
			(layer "F.SilkS")
		)
		(fp_line
			(start 5.751068 -3.842512)
			(end 5.738876 -3.772916)
			(stroke
				(width 0.1)
				(type default)
			)
			(layer "F.SilkS")
		)
		(fp_line
			(start 5.763006 -3.911854)
			(end 5.751068 -3.842512)
			(stroke
				(width 0.1)
				(type default)
			)
			(layer "F.SilkS")
		)
		(fp_line
			(start 5.763006 -3.911854)
			(end 5.751068 -3.842512)
			(stroke
				(width 0.1)
				(type default)
			)
			(layer "F.SilkS")
		)
		(fp_line
			(start 5.775198 -3.98145)
			(end 5.763006 -3.911854)
			(stroke
				(width 0.1)
				(type default)
			)
			(layer "F.SilkS")
		)
		(fp_line
			(start 5.775198 -3.98145)
			(end 5.763006 -3.911854)
			(stroke
				(width 0.1)
				(type default)
			)
			(layer "F.SilkS")
		)
		(fp_line
			(start 5.776468 -1.212342)
			(end 6.728714 -2.125726)
			(stroke
				(width 0.1)
				(type default)
			)
			(layer "F.SilkS")
		)
		(fp_line
			(start 5.776468 -1.212342)
			(end 6.728714 -2.125726)
			(stroke
				(width 0.1)
				(type default)
			)
			(layer "F.SilkS")
		)
		(fp_line
			(start 5.78739 -4.050538)
			(end 5.775198 -3.98145)
			(stroke
				(width 0.1)
				(type default)
			)
			(layer "F.SilkS")
		)
		(fp_line
			(start 5.78739 -4.050538)
			(end 5.775198 -3.98145)
			(stroke
				(width 0.1)
				(type default)
			)
			(layer "F.SilkS")
		)
		(fp_line
			(start 5.799582 -4.11988)
			(end 5.78739 -4.050538)
			(stroke
				(width 0.1)
				(type default)
			)
			(layer "F.SilkS")
		)
		(fp_line
			(start 5.799582 -4.11988)
			(end 5.78739 -4.050538)
			(stroke
				(width 0.1)
				(type default)
			)
			(layer "F.SilkS")
		)
		(fp_line
			(start 5.80263 -1.179576)
			(end 6.746494 -2.084832)
			(stroke
				(width 0.1)
				(type default)
			)
			(layer "F.SilkS")
		)
		(fp_line
			(start 5.80263 -1.179576)
			(end 6.746494 -2.084832)
			(stroke
				(width 0.1)
				(type default)
			)
			(layer "F.SilkS")
		)
		(fp_line
			(start 5.811774 -4.189476)
			(end 5.799582 -4.11988)
			(stroke
				(width 0.1)
				(type default)
			)
			(layer "F.SilkS")
		)
		(fp_line
			(start 5.811774 -4.189476)
			(end 5.799582 -4.11988)
			(stroke
				(width 0.1)
				(type default)
			)
			(layer "F.SilkS")
		)
		(fp_line
			(start 5.823966 -4.258818)
			(end 5.811774 -4.189476)
			(stroke
				(width 0.1)
				(type default)
			)
			(layer "F.SilkS")
		)
		(fp_line
			(start 5.823966 -4.258818)
			(end 5.811774 -4.189476)
			(stroke
				(width 0.1)
				(type default)
			)
			(layer "F.SilkS")
		)
		(fp_line
			(start 5.828792 -1.147064)
			(end 6.769608 -2.049272)
			(stroke
				(width 0.1)
				(type default)
			)
			(layer "F.SilkS")
		)
		(fp_line
			(start 5.828792 -1.147064)
			(end 6.769608 -2.049272)
			(stroke
				(width 0.1)
				(type default)
			)
			(layer "F.SilkS")
		)
		(fp_line
			(start 5.836158 -4.328414)
			(end 5.823966 -4.258818)
			(stroke
				(width 0.1)
				(type default)
			)
			(layer "F.SilkS")
		)
		(fp_line
			(start 5.836158 -4.328414)
			(end 5.823966 -4.258818)
			(stroke
				(width 0.1)
				(type default)
			)
			(layer "F.SilkS")
		)
		(fp_line
			(start 5.84835 -4.397502)
			(end 5.836158 -4.328414)
			(stroke
				(width 0.1)
				(type default)
			)
			(layer "F.SilkS")
		)
		(fp_line
			(start 5.84835 -4.397502)
			(end 5.836158 -4.328414)
			(stroke
				(width 0.1)
				(type default)
			)
			(layer "F.SilkS")
		)
		(fp_line
			(start 5.854954 -1.114298)
			(end 6.79704 -2.018284)
			(stroke
				(width 0.1)
				(type default)
			)
			(layer "F.SilkS")
		)
		(fp_line
			(start 5.854954 -1.114298)
			(end 6.79704 -2.018284)
			(stroke
				(width 0.1)
				(type default)
			)
			(layer "F.SilkS")
		)
		(fp_line
			(start 5.860542 -4.467098)
			(end 5.84835 -4.397502)
			(stroke
				(width 0.1)
				(type default)
			)
			(layer "F.SilkS")
		)
		(fp_line
			(start 5.860542 -4.467098)
			(end 5.84835 -4.397502)
			(stroke
				(width 0.1)
				(type default)
			)
			(layer "F.SilkS")
		)
		(fp_line
			(start 5.872734 -4.53644)
			(end 5.860542 -4.467098)
			(stroke
				(width 0.1)
				(type default)
			)
			(layer "F.SilkS")
		)
		(fp_line
			(start 5.872734 -4.53644)
			(end 5.860542 -4.467098)
			(stroke
				(width 0.1)
				(type default)
			)
			(layer "F.SilkS")
		)
		(fp_line
			(start 5.872734 -4.53644)
			(end 5.884926 -4.605782)
			(stroke
				(width 0.1)
				(type default)
			)
			(layer "F.SilkS")
		)
		(fp_line
			(start 5.872734 -4.53644)
			(end 5.884926 -4.605782)
			(stroke
				(width 0.1)
				(type default)
			)
			(layer "F.SilkS")
		)
		(fp_line
			(start 5.884926 -4.605782)
			(end 5.897118 -4.675124)
			(stroke
				(width 0.1)
				(type default)
			)
			(layer "F.SilkS")
		)
		(fp_line
			(start 5.884926 -4.605782)
			(end 5.897118 -4.675124)
			(stroke
				(width 0.1)
				(type default)
			)
			(layer "F.SilkS")
		)
		(fp_line
			(start 5.884926 -1.085342)
			(end 6.824726 -1.987042)
			(stroke
				(width 0.1)
				(type default)
			)
			(layer "F.SilkS")
		)
		(fp_line
			(start 5.884926 -1.085342)
			(end 6.824726 -1.987042)
			(stroke
				(width 0.1)
				(type default)
			)
			(layer "F.SilkS")
		)
		(fp_line
			(start 5.897118 -4.675124)
			(end 5.90931 -4.74472)
			(stroke
				(width 0.1)
				(type default)
			)
			(layer "F.SilkS")
		)
		(fp_line
			(start 5.897118 -4.675124)
			(end 5.90931 -4.74472)
			(stroke
				(width 0.1)
				(type default)
			)
			(layer "F.SilkS")
		)
		(fp_line
			(start 5.90931 -4.74472)
			(end 5.921502 -4.814062)
			(stroke
				(width 0.1)
				(type default)
			)
			(layer "F.SilkS")
		)
		(fp_line
			(start 5.90931 -4.74472)
			(end 5.921502 -4.814062)
			(stroke
				(width 0.1)
				(type default)
			)
			(layer "F.SilkS")
		)
		(fp_line
			(start 5.919978 -1.061212)
			(end 6.856222 -1.95961)
			(stroke
				(width 0.1)
				(type default)
			)
			(layer "F.SilkS")
		)
		(fp_line
			(start 5.919978 -1.061212)
			(end 6.856222 -1.95961)
			(stroke
				(width 0.1)
				(type default)
			)
			(layer "F.SilkS")
		)
		(fp_line
			(start 5.921502 -4.814062)
			(end 5.933694 -4.883404)
			(stroke
				(width 0.1)
				(type default)
			)
			(layer "F.SilkS")
		)
		(fp_line
			(start 5.921502 -4.814062)
			(end 5.933694 -4.883404)
			(stroke
				(width 0.1)
				(type default)
			)
			(layer "F.SilkS")
		)
		(fp_line
			(start 5.933694 -4.883404)
			(end 5.945886 -4.952746)
			(stroke
				(width 0.1)
				(type default)
			)
			(layer "F.SilkS")
		)
		(fp_line
			(start 5.933694 -4.883404)
			(end 5.945886 -4.952746)
			(stroke
				(width 0.1)
				(type default)
			)
			(layer "F.SilkS")
		)
		(fp_line
			(start 5.945886 -4.952746)
			(end 5.958078 -5.022088)
			(stroke
				(width 0.1)
				(type default)
			)
			(layer "F.SilkS")
		)
		(fp_line
			(start 5.945886 -4.952746)
			(end 5.958078 -5.022088)
			(stroke
				(width 0.1)
				(type default)
			)
			(layer "F.SilkS")
		)
		(fp_line
			(start 5.955284 -1.03759)
			(end 6.894068 -1.93802)
			(stroke
				(width 0.1)
				(type default)
			)
			(layer "F.SilkS")
		)
		(fp_line
			(start 5.955284 -1.03759)
			(end 6.894068 -1.93802)
			(stroke
				(width 0.1)
				(type default)
			)
			(layer "F.SilkS")
		)
		(fp_line
			(start 5.958078 -5.022088)
			(end 5.97027 -5.091684)
			(stroke
				(width 0.1)
				(type default)
			)
			(layer "F.SilkS")
		)
		(fp_line
			(start 5.958078 -5.022088)
			(end 5.97027 -5.091684)
			(stroke
				(width 0.1)
				(type default)
			)
			(layer "F.SilkS")
		)
		(fp_line
			(start 5.97027 -5.091684)
			(end 5.982208 -5.161026)
			(stroke
				(width 0.1)
				(type default)
			)
			(layer "F.SilkS")
		)
		(fp_line
			(start 5.97027 -5.091684)
			(end 5.982208 -5.161026)
			(stroke
				(width 0.1)
				(type default)
			)
			(layer "F.SilkS")
		)
		(fp_line
			(start 5.98424 -5.171694)
			(end 5.982208 -5.161026)
			(stroke
				(width 0.1)
				(type default)
			)
			(layer "F.SilkS")
		)
		(fp_line
			(start 5.98424 -5.171694)
			(end 5.982208 -5.161026)
			(stroke
				(width 0.1)
				(type default)
			)
			(layer "F.SilkS")
		)
		(fp_line
			(start 5.99059 -1.013714)
			(end 6.93166 -1.91643)
			(stroke
				(width 0.1)
				(type default)
			)
			(layer "F.SilkS")
		)
		(fp_line
			(start 5.99059 -1.013714)
			(end 6.93166 -1.91643)
			(stroke
				(width 0.1)
				(type default)
			)
			(layer "F.SilkS")
		)
		(fp_line
			(start 5.993638 -5.171694)
			(end 5.982208 -5.161026)
			(stroke
				(width 0.1)
				(type default)
			)
			(layer "F.SilkS")
		)
		(fp_line
			(start 5.993638 -5.171694)
			(end 5.982208 -5.161026)
			(stroke
				(width 0.1)
				(type default)
			)
			(layer "F.SilkS")
		)
		(fp_line
			(start 5.993638 -5.171694)
			(end 5.98424 -5.171694)
			(stroke
				(width 0.1)
				(type default)
			)
			(layer "F.SilkS")
		)
		(fp_line
			(start 5.993638 -5.171694)
			(end 5.98424 -5.171694)
			(stroke
				(width 0.1)
				(type default)
			)
			(layer "F.SilkS")
		)
		(fp_line
			(start 6.025642 -0.989584)
			(end 6.973062 -1.898396)
			(stroke
				(width 0.1)
				(type default)
			)
			(layer "F.SilkS")
		)
		(fp_line
			(start 6.025642 -0.989584)
			(end 6.973062 -1.898396)
			(stroke
				(width 0.1)
				(type default)
			)
			(layer "F.SilkS")
		)
		(fp_line
			(start 6.053582 -5.171694)
			(end 5.97027 -5.091684)
			(stroke
				(width 0.1)
				(type default)
			)
			(layer "F.SilkS")
		)
		(fp_line
			(start 6.053582 -5.171694)
			(end 5.97027 -5.091684)
			(stroke
				(width 0.1)
				(type default)
			)
			(layer "F.SilkS")
		)
		(fp_line
			(start 6.053582 -5.171694)
			(end 5.993638 -5.171694)
			(stroke
				(width 0.1)
				(type default)
			)
			(layer "F.SilkS")
		)
		(fp_line
			(start 6.053582 -5.171694)
			(end 5.993638 -5.171694)
			(stroke
				(width 0.1)
				(type default)
			)
			(layer "F.SilkS")
		)
		(fp_line
			(start 6.060948 -0.965962)
			(end 7.020306 -1.88595)
			(stroke
				(width 0.1)
				(type default)
			)
			(layer "F.SilkS")
		)
		(fp_line
			(start 6.060948 -0.965962)
			(end 7.020306 -1.88595)
			(stroke
				(width 0.1)
				(type default)
			)
			(layer "F.SilkS")
		)
		(fp_line
			(start 6.096254 -0.942086)
			(end 7.06755 -1.873504)
			(stroke
				(width 0.1)
				(type default)
			)
			(layer "F.SilkS")
		)
		(fp_line
			(start 6.096254 -0.942086)
			(end 7.06755 -1.873504)
			(stroke
				(width 0.1)
				(type default)
			)
			(layer "F.SilkS")
		)
		(fp_line
			(start 6.11378 -5.171694)
			(end 5.958078 -5.022088)
			(stroke
				(width 0.1)
				(type default)
			)
			(layer "F.SilkS")
		)
		(fp_line
			(start 6.11378 -5.171694)
			(end 5.958078 -5.022088)
			(stroke
				(width 0.1)
				(type default)
			)
			(layer "F.SilkS")
		)
		(fp_line
			(start 6.11378 -5.171694)
			(end 6.053582 -5.171694)
			(stroke
				(width 0.1)
				(type default)
			)
			(layer "F.SilkS")
		)
		(fp_line
			(start 6.11378 -5.171694)
			(end 6.053582 -5.171694)
			(stroke
				(width 0.1)
				(type default)
			)
			(layer "F.SilkS")
		)
		(fp_line
			(start 6.136132 -0.922528)
			(end 7.118604 -1.865122)
			(stroke
				(width 0.1)
				(type default)
			)
			(layer "F.SilkS")
		)
		(fp_line
			(start 6.136132 -0.922528)
			(end 7.118604 -1.865122)
			(stroke
				(width 0.1)
				(type default)
			)
			(layer "F.SilkS")
		)
		(fp_line
			(start 6.173978 -5.171694)
			(end 5.945886 -4.952746)
			(stroke
				(width 0.1)
				(type default)
			)
			(layer "F.SilkS")
		)
		(fp_line
			(start 6.173978 -5.171694)
			(end 5.945886 -4.952746)
			(stroke
				(width 0.1)
				(type default)
			)
			(layer "F.SilkS")
		)
		(fp_line
			(start 6.173978 -5.171694)
			(end 6.11378 -5.171694)
			(stroke
				(width 0.1)
				(type default)
			)
			(layer "F.SilkS")
		)
		(fp_line
			(start 6.173978 -5.171694)
			(end 6.11378 -5.171694)
			(stroke
				(width 0.1)
				(type default)
			)
			(layer "F.SilkS")
		)
		(fp_line
			(start 6.180836 -0.907796)
			(end 7.174738 -1.861058)
			(stroke
				(width 0.1)
				(type default)
			)
			(layer "F.SilkS")
		)
		(fp_line
			(start 6.180836 -0.907796)
			(end 7.174738 -1.861058)
			(stroke
				(width 0.1)
				(type default)
			)
			(layer "F.SilkS")
		)
		(fp_line
			(start 6.225794 -0.89281)
			(end 7.231126 -1.857248)
			(stroke
				(width 0.1)
				(type default)
			)
			(layer "F.SilkS")
		)
		(fp_line
			(start 6.225794 -0.89281)
			(end 7.231126 -1.857248)
			(stroke
				(width 0.1)
				(type default)
			)
			(layer "F.SilkS")
		)
		(fp_line
			(start 6.234176 -5.171694)
			(end 5.933694 -4.883404)
			(stroke
				(width 0.1)
				(type default)
			)
			(layer "F.SilkS")
		)
		(fp_line
			(start 6.234176 -5.171694)
			(end 5.933694 -4.883404)
			(stroke
				(width 0.1)
				(type default)
			)
			(layer "F.SilkS")
		)
		(fp_line
			(start 6.234176 -5.171694)
			(end 6.173978 -5.171694)
			(stroke
				(width 0.1)
				(type default)
			)
			(layer "F.SilkS")
		)
		(fp_line
			(start 6.234176 -5.171694)
			(end 6.173978 -5.171694)
			(stroke
				(width 0.1)
				(type default)
			)
			(layer "F.SilkS")
		)
		(fp_line
			(start 6.270752 -0.878332)
			(end 7.291832 -1.857756)
			(stroke
				(width 0.1)
				(type default)
			)
			(layer "F.SilkS")
		)
		(fp_line
			(start 6.270752 -0.878332)
			(end 7.291832 -1.857756)
			(stroke
				(width 0.1)
				(type default)
			)
			(layer "F.SilkS")
		)
		(fp_line
			(start 6.294374 -5.171694)
			(end 5.921502 -4.814062)
			(stroke
				(width 0.1)
				(type default)
			)
			(layer "F.SilkS")
		)
		(fp_line
			(start 6.294374 -5.171694)
			(end 5.921502 -4.814062)
			(stroke
				(width 0.1)
				(type default)
			)
			(layer "F.SilkS")
		)
		(fp_line
			(start 6.294374 -5.171694)
			(end 6.234176 -5.171694)
			(stroke
				(width 0.1)
				(type default)
			)
			(layer "F.SilkS")
		)
		(fp_line
			(start 6.294374 -5.171694)
			(end 6.234176 -5.171694)
			(stroke
				(width 0.1)
				(type default)
			)
			(layer "F.SilkS")
		)
		(fp_line
			(start 6.315456 -0.8636)
			(end 7.356348 -1.862074)
			(stroke
				(width 0.1)
				(type default)
			)
			(layer "F.SilkS")
		)
		(fp_line
			(start 6.315456 -0.8636)
			(end 7.356348 -1.862074)
			(stroke
				(width 0.1)
				(type default)
			)
			(layer "F.SilkS")
		)
		(fp_line
			(start 6.354318 -5.171694)
			(end 5.90931 -4.74472)
			(stroke
				(width 0.1)
				(type default)
			)
			(layer "F.SilkS")
		)
		(fp_line
			(start 6.354318 -5.171694)
			(end 5.90931 -4.74472)
			(stroke
				(width 0.1)
				(type default)
			)
			(layer "F.SilkS")
		)
		(fp_line
			(start 6.354318 -5.171694)
			(end 6.294374 -5.171694)
			(stroke
				(width 0.1)
				(type default)
			)
			(layer "F.SilkS")
		)
		(fp_line
			(start 6.354318 -5.171694)
			(end 6.294374 -5.171694)
			(stroke
				(width 0.1)
				(type default)
			)
			(layer "F.SilkS")
		)
		(fp_line
			(start 6.36016 -0.848868)
			(end 7.421118 -1.866392)
			(stroke
				(width 0.1)
				(type default)
			)
			(layer "F.SilkS")
		)
		(fp_line
			(start 6.36016 -0.848868)
			(end 7.421118 -1.866392)
			(stroke
				(width 0.1)
				(type default)
			)
			(layer "F.SilkS")
		)
		(fp_line
			(start 6.405118 -0.833882)
			(end 7.500366 -1.884934)
			(stroke
				(width 0.1)
				(type default)
			)
			(layer "F.SilkS")
		)
		(fp_line
			(start 6.405118 -0.833882)
			(end 7.500366 -1.884934)
			(stroke
				(width 0.1)
				(type default)
			)
			(layer "F.SilkS")
		)
		(fp_line
			(start 6.41477 -5.171694)
			(end 5.897118 -4.675124)
			(stroke
				(width 0.1)
				(type default)
			)
			(layer "F.SilkS")
		)
		(fp_line
			(start 6.41477 -5.171694)
			(end 5.897118 -4.675124)
			(stroke
				(width 0.1)
				(type default)
			)
			(layer "F.SilkS")
		)
		(fp_line
			(start 6.41477 -5.171694)
			(end 6.354318 -5.171694)
			(stroke
				(width 0.1)
				(type default)
			)
			(layer "F.SilkS")
		)
		(fp_line
			(start 6.41477 -5.171694)
			(end 6.354318 -5.171694)
			(stroke
				(width 0.1)
				(type default)
			)
			(layer "F.SilkS")
		)
		(fp_line
			(start 6.455664 -0.824738)
			(end 7.582662 -1.906016)
			(stroke
				(width 0.1)
				(type default)
			)
			(layer "F.SilkS")
		)
		(fp_line
			(start 6.455664 -0.824738)
			(end 7.582662 -1.906016)
			(stroke
				(width 0.1)
				(type default)
			)
			(layer "F.SilkS")
		)
		(fp_line
			(start 6.474714 -5.171694)
			(end 5.884926 -4.605782)
			(stroke
				(width 0.1)
				(type default)
			)
			(layer "F.SilkS")
		)
		(fp_line
			(start 6.474714 -5.171694)
			(end 5.884926 -4.605782)
			(stroke
				(width 0.1)
				(type default)
			)
			(layer "F.SilkS")
		)
		(fp_line
			(start 6.474714 -5.171694)
			(end 6.41477 -5.171694)
			(stroke
				(width 0.1)
				(type default)
			)
			(layer "F.SilkS")
		)
		(fp_line
			(start 6.474714 -5.171694)
			(end 6.41477 -5.171694)
			(stroke
				(width 0.1)
				(type default)
			)
			(layer "F.SilkS")
		)
		(fp_line
			(start 6.510528 -0.819912)
			(end 7.699756 -1.96088)
			(stroke
				(width 0.1)
				(type default)
			)
			(layer "F.SilkS")
		)
		(fp_line
			(start 6.510528 -0.819912)
			(end 7.699756 -1.96088)
			(stroke
				(width 0.1)
				(type default)
			)
			(layer "F.SilkS")
		)
		(fp_line
			(start 6.534912 -5.171694)
			(end 5.872734 -4.53644)
			(stroke
				(width 0.1)
				(type default)
			)
			(layer "F.SilkS")
		)
		(fp_line
			(start 6.534912 -5.171694)
			(end 5.872734 -4.53644)
			(stroke
				(width 0.1)
				(type default)
			)
			(layer "F.SilkS")
		)
		(fp_line
			(start 6.534912 -5.171694)
			(end 6.474714 -5.171694)
			(stroke
				(width 0.1)
				(type default)
			)
			(layer "F.SilkS")
		)
		(fp_line
			(start 6.534912 -5.171694)
			(end 6.474714 -5.171694)
			(stroke
				(width 0.1)
				(type default)
			)
			(layer "F.SilkS")
		)
		(fp_line
			(start 6.59511 -5.171694)
			(end 5.860542 -4.467098)
			(stroke
				(width 0.1)
				(type default)
			)
			(layer "F.SilkS")
		)
		(fp_line
			(start 6.59511 -5.171694)
			(end 5.860542 -4.467098)
			(stroke
				(width 0.1)
				(type default)
			)
			(layer "F.SilkS")
		)
		(fp_line
			(start 6.59511 -5.171694)
			(end 6.534912 -5.171694)
			(stroke
				(width 0.1)
				(type default)
			)
			(layer "F.SilkS")
		)
		(fp_line
			(start 6.59511 -5.171694)
			(end 6.534912 -5.171694)
			(stroke
				(width 0.1)
				(type default)
			)
			(layer "F.SilkS")
		)
		(fp_line
			(start 6.620256 -0.809498)
			(end 9.404096 -3.480054)
			(stroke
				(width 0.1)
				(type default)
			)
			(layer "F.SilkS")
		)
		(fp_line
			(start 6.620256 -0.809498)
			(end 9.404096 -3.480054)
			(stroke
				(width 0.1)
				(type default)
			)
			(layer "F.SilkS")
		)
		(fp_line
			(start 6.655308 -5.171694)
			(end 5.84835 -4.397502)
			(stroke
				(width 0.1)
				(type default)
			)
			(layer "F.SilkS")
		)
		(fp_line
			(start 6.655308 -5.171694)
			(end 5.84835 -4.397502)
			(stroke
				(width 0.1)
				(type default)
			)
			(layer "F.SilkS")
		)
		(fp_line
			(start 6.655308 -5.171694)
			(end 6.59511 -5.171694)
			(stroke
				(width 0.1)
				(type default)
			)
			(layer "F.SilkS")
		)
		(fp_line
			(start 6.655308 -5.171694)
			(end 6.59511 -5.171694)
			(stroke
				(width 0.1)
				(type default)
			)
			(layer "F.SilkS")
		)
		(fp_line
			(start 6.67512 -0.804672)
			(end 9.391904 -3.410712)
			(stroke
				(width 0.1)
				(type default)
			)
			(layer "F.SilkS")
		)
		(fp_line
			(start 6.67512 -0.804672)
			(end 9.391904 -3.410712)
			(stroke
				(width 0.1)
				(type default)
			)
			(layer "F.SilkS")
		)
		(fp_line
			(start 6.703822 -2.852166)
			(end 6.716014 -2.921254)
			(stroke
				(width 0.1)
				(type default)
			)
			(layer "F.SilkS")
		)
		(fp_line
			(start 6.703822 -2.852166)
			(end 6.716014 -2.921254)
			(stroke
				(width 0.1)
				(type default)
			)
			(layer "F.SilkS")
		)
		(fp_line
			(start 6.715506 -5.171694)
			(end 5.836158 -4.328414)
			(stroke
				(width 0.1)
				(type default)
			)
			(layer "F.SilkS")
		)
		(fp_line
			(start 6.715506 -5.171694)
			(end 5.836158 -4.328414)
			(stroke
				(width 0.1)
				(type default)
			)
			(layer "F.SilkS")
		)
		(fp_line
			(start 6.715506 -5.171694)
			(end 6.655308 -5.171694)
			(stroke
				(width 0.1)
				(type default)
			)
			(layer "F.SilkS")
		)
		(fp_line
			(start 6.715506 -5.171694)
			(end 6.655308 -5.171694)
			(stroke
				(width 0.1)
				(type default)
			)
			(layer "F.SilkS")
		)
		(fp_line
			(start 6.716014 -2.921254)
			(end 6.728206 -2.99085)
			(stroke
				(width 0.1)
				(type default)
			)
			(layer "F.SilkS")
		)
		(fp_line
			(start 6.716014 -2.921254)
			(end 6.728206 -2.99085)
			(stroke
				(width 0.1)
				(type default)
			)
			(layer "F.SilkS")
		)
		(fp_line
			(start 6.728206 -2.99085)
			(end 6.740144 -3.060192)
			(stroke
				(width 0.1)
				(type default)
			)
			(layer "F.SilkS")
		)
		(fp_line
			(start 6.728206 -2.99085)
			(end 6.740144 -3.060192)
			(stroke
				(width 0.1)
				(type default)
			)
			(layer "F.SilkS")
		)
		(fp_line
			(start 6.729984 -0.799592)
			(end 9.379712 -3.34137)
			(stroke
				(width 0.1)
				(type default)
			)
			(layer "F.SilkS")
		)
		(fp_line
			(start 6.729984 -0.799592)
			(end 9.379712 -3.34137)
			(stroke
				(width 0.1)
				(type default)
			)
			(layer "F.SilkS")
		)
		(fp_line
			(start 6.740144 -3.060192)
			(end 6.75259 -3.129534)
			(stroke
				(width 0.1)
				(type default)
			)
			(layer "F.SilkS")
		)
		(fp_line
			(start 6.740144 -3.060192)
			(end 6.75259 -3.129534)
			(stroke
				(width 0.1)
				(type default)
			)
			(layer "F.SilkS")
		)
		(fp_line
			(start 6.75259 -3.129534)
			(end 6.764782 -3.19913)
			(stroke
				(width 0.1)
				(type default)
			)
			(layer "F.SilkS")
		)
		(fp_line
			(start 6.75259 -3.129534)
			(end 6.764782 -3.19913)
			(stroke
				(width 0.1)
				(type default)
			)
			(layer "F.SilkS")
		)
		(fp_line
			(start 6.764782 -3.19913)
			(end 6.776974 -3.268472)
			(stroke
				(width 0.1)
				(type default)
			)
			(layer "F.SilkS")
		)
		(fp_line
			(start 6.764782 -3.19913)
			(end 6.776974 -3.268472)
			(stroke
				(width 0.1)
				(type default)
			)
			(layer "F.SilkS")
		)
		(fp_line
			(start 6.77545 -5.171694)
			(end 5.823966 -4.258818)
			(stroke
				(width 0.1)
				(type default)
			)
			(layer "F.SilkS")
		)
		(fp_line
			(start 6.77545 -5.171694)
			(end 5.823966 -4.258818)
			(stroke
				(width 0.1)
				(type default)
			)
			(layer "F.SilkS")
		)
		(fp_line
			(start 6.77545 -5.171694)
			(end 6.715506 -5.171694)
			(stroke
				(width 0.1)
				(type default)
			)
			(layer "F.SilkS")
		)
		(fp_line
			(start 6.77545 -5.171694)
			(end 6.715506 -5.171694)
			(stroke
				(width 0.1)
				(type default)
			)
			(layer "F.SilkS")
		)
		(fp_line
			(start 6.776974 -3.268472)
			(end 6.788912 -3.337814)
			(stroke
				(width 0.1)
				(type default)
			)
			(layer "F.SilkS")
		)
		(fp_line
			(start 6.776974 -3.268472)
			(end 6.788912 -3.337814)
			(stroke
				(width 0.1)
				(type default)
			)
			(layer "F.SilkS")
		)
		(fp_line
			(start 6.784848 -0.794258)
			(end 9.36752 -3.272028)
			(stroke
				(width 0.1)
				(type default)
			)
			(layer "F.SilkS")
		)
		(fp_line
			(start 6.784848 -0.794258)
			(end 9.36752 -3.272028)
			(stroke
				(width 0.1)
				(type default)
			)
			(layer "F.SilkS")
		)
		(fp_line
			(start 6.788912 -3.337814)
			(end 6.801104 -3.407156)
			(stroke
				(width 0.1)
				(type default)
			)
			(layer "F.SilkS")
		)
		(fp_line
			(start 6.788912 -3.337814)
			(end 6.801104 -3.407156)
			(stroke
				(width 0.1)
				(type default)
			)
			(layer "F.SilkS")
		)
		(fp_line
			(start 6.801104 -3.407156)
			(end 6.81355 -3.476498)
			(stroke
				(width 0.1)
				(type default)
			)
			(layer "F.SilkS")
		)
		(fp_line
			(start 6.801104 -3.407156)
			(end 6.81355 -3.476498)
			(stroke
				(width 0.1)
				(type default)
			)
			(layer "F.SilkS")
		)
		(fp_line
			(start 6.825488 -3.54584)
			(end 6.81355 -3.476498)
			(stroke
				(width 0.1)
				(type default)
			)
			(layer "F.SilkS")
		)
		(fp_line
			(start 6.825488 -3.54584)
			(end 6.81355 -3.476498)
			(stroke
				(width 0.1)
				(type default)
			)
			(layer "F.SilkS")
		)
		(fp_line
			(start 6.825488 -3.54584)
			(end 6.83768 -3.615436)
			(stroke
				(width 0.1)
				(type default)
			)
			(layer "F.SilkS")
		)
		(fp_line
			(start 6.825488 -3.54584)
			(end 6.83768 -3.615436)
			(stroke
				(width 0.1)
				(type default)
			)
			(layer "F.SilkS")
		)
		(fp_line
			(start 6.835648 -5.171694)
			(end 5.811774 -4.189476)
			(stroke
				(width 0.1)
				(type default)
			)
			(layer "F.SilkS")
		)
		(fp_line
			(start 6.835648 -5.171694)
			(end 5.811774 -4.189476)
			(stroke
				(width 0.1)
				(type default)
			)
			(layer "F.SilkS")
		)
		(fp_line
			(start 6.835648 -5.171694)
			(end 6.77545 -5.171694)
			(stroke
				(width 0.1)
				(type default)
			)
			(layer "F.SilkS")
		)
		(fp_line
			(start 6.835648 -5.171694)
			(end 6.77545 -5.171694)
			(stroke
				(width 0.1)
				(type default)
			)
			(layer "F.SilkS")
		)
		(fp_line
			(start 6.83768 -3.615436)
			(end 5.509514 -2.341372)
			(stroke
				(width 0.1)
				(type default)
			)
			(layer "F.SilkS")
		)
		(fp_line
			(start 6.83768 -3.615436)
			(end 5.509514 -2.341372)
			(stroke
				(width 0.1)
				(type default)
			)
			(layer "F.SilkS")
		)
		(fp_line
			(start 6.83768 -3.615436)
			(end 6.849872 -3.684778)
			(stroke
				(width 0.1)
				(type default)
			)
			(layer "F.SilkS")
		)
		(fp_line
			(start 6.83768 -3.615436)
			(end 6.849872 -3.684778)
			(stroke
				(width 0.1)
				(type default)
			)
			(layer "F.SilkS")
		)
		(fp_line
			(start 6.848348 -0.797814)
			(end 9.355328 -3.202432)
			(stroke
				(width 0.1)
				(type default)
			)
			(layer "F.SilkS")
		)
		(fp_line
			(start 6.848348 -0.797814)
			(end 9.355328 -3.202432)
			(stroke
				(width 0.1)
				(type default)
			)
			(layer "F.SilkS")
		)
		(fp_line
			(start 6.849872 -3.684778)
			(end 5.517642 -2.40665)
			(stroke
				(width 0.1)
				(type default)
			)
			(layer "F.SilkS")
		)
		(fp_line
			(start 6.849872 -3.684778)
			(end 5.517642 -2.40665)
			(stroke
				(width 0.1)
				(type default)
			)
			(layer "F.SilkS")
		)
		(fp_line
			(start 6.849872 -3.684778)
			(end 6.862318 -3.75412)
			(stroke
				(width 0.1)
				(type default)
			)
			(layer "F.SilkS")
		)
		(fp_line
			(start 6.849872 -3.684778)
			(end 6.862318 -3.75412)
			(stroke
				(width 0.1)
				(type default)
			)
			(layer "F.SilkS")
		)
		(fp_line
			(start 6.862318 -3.75412)
			(end 5.525516 -2.471928)
			(stroke
				(width 0.1)
				(type default)
			)
			(layer "F.SilkS")
		)
		(fp_line
			(start 6.862318 -3.75412)
			(end 5.525516 -2.471928)
			(stroke
				(width 0.1)
				(type default)
			)
			(layer "F.SilkS")
		)
		(fp_line
			(start 6.862318 -3.75412)
			(end 6.874256 -3.823716)
			(stroke
				(width 0.1)
				(type default)
			)
			(layer "F.SilkS")
		)
		(fp_line
			(start 6.862318 -3.75412)
			(end 6.874256 -3.823716)
			(stroke
				(width 0.1)
				(type default)
			)
			(layer "F.SilkS")
		)
		(fp_line
			(start 6.874256 -3.823716)
			(end 5.53339 -2.537206)
			(stroke
				(width 0.1)
				(type default)
			)
			(layer "F.SilkS")
		)
		(fp_line
			(start 6.874256 -3.823716)
			(end 5.53339 -2.537206)
			(stroke
				(width 0.1)
				(type default)
			)
			(layer "F.SilkS")
		)
		(fp_line
			(start 6.874256 -3.823716)
			(end 6.886448 -3.893058)
			(stroke
				(width 0.1)
				(type default)
			)
			(layer "F.SilkS")
		)
		(fp_line
			(start 6.874256 -3.823716)
			(end 6.886448 -3.893058)
			(stroke
				(width 0.1)
				(type default)
			)
			(layer "F.SilkS")
		)
		(fp_line
			(start 6.886448 -3.893058)
			(end 5.541264 -2.602738)
			(stroke
				(width 0.1)
				(type default)
			)
			(layer "F.SilkS")
		)
		(fp_line
			(start 6.886448 -3.893058)
			(end 5.541264 -2.602738)
			(stroke
				(width 0.1)
				(type default)
			)
			(layer "F.SilkS")
		)
		(fp_line
			(start 6.886448 -3.893058)
			(end 6.89864 -3.9624)
			(stroke
				(width 0.1)
				(type default)
			)
			(layer "F.SilkS")
		)
		(fp_line
			(start 6.886448 -3.893058)
			(end 6.89864 -3.9624)
			(stroke
				(width 0.1)
				(type default)
			)
			(layer "F.SilkS")
		)
		(fp_line
			(start 6.895846 -5.171694)
			(end 5.799582 -4.11988)
			(stroke
				(width 0.1)
				(type default)
			)
			(layer "F.SilkS")
		)
		(fp_line
			(start 6.895846 -5.171694)
			(end 5.799582 -4.11988)
			(stroke
				(width 0.1)
				(type default)
			)
			(layer "F.SilkS")
		)
		(fp_line
			(start 6.895846 -5.171694)
			(end 6.835648 -5.171694)
			(stroke
				(width 0.1)
				(type default)
			)
			(layer "F.SilkS")
		)
		(fp_line
			(start 6.895846 -5.171694)
			(end 6.835648 -5.171694)
			(stroke
				(width 0.1)
				(type default)
			)
			(layer "F.SilkS")
		)
		(fp_line
			(start 6.89864 -3.9624)
			(end 5.549392 -2.668016)
			(stroke
				(width 0.1)
				(type default)
			)
			(layer "F.SilkS")
		)
		(fp_line
			(start 6.89864 -3.9624)
			(end 5.549392 -2.668016)
			(stroke
				(width 0.1)
				(type default)
			)
			(layer "F.SilkS")
		)
		(fp_line
			(start 6.89864 -3.9624)
			(end 6.910832 -4.031742)
			(stroke
				(width 0.1)
				(type default)
			)
			(layer "F.SilkS")
		)
		(fp_line
			(start 6.89864 -3.9624)
			(end 6.910832 -4.031742)
			(stroke
				(width 0.1)
				(type default)
			)
			(layer "F.SilkS")
		)
		(fp_line
			(start 6.910832 -4.031742)
			(end 5.557266 -2.733294)
			(stroke
				(width 0.1)
				(type default)
			)
			(layer "F.SilkS")
		)
		(fp_line
			(start 6.910832 -4.031742)
			(end 5.557266 -2.733294)
			(stroke
				(width 0.1)
				(type default)
			)
			(layer "F.SilkS")
		)
		(fp_line
			(start 6.910832 -4.031742)
			(end 6.923024 -4.101084)
			(stroke
				(width 0.1)
				(type default)
			)
			(layer "F.SilkS")
		)
		(fp_line
			(start 6.910832 -4.031742)
			(end 6.923024 -4.101084)
			(stroke
				(width 0.1)
				(type default)
			)
			(layer "F.SilkS")
		)
		(fp_line
			(start 6.914896 -0.80391)
			(end 9.343136 -3.13309)
			(stroke
				(width 0.1)
				(type default)
			)
			(layer "F.SilkS")
		)
		(fp_line
			(start 6.914896 -0.80391)
			(end 9.343136 -3.13309)
			(stroke
				(width 0.1)
				(type default)
			)
			(layer "F.SilkS")
		)
		(fp_line
			(start 6.923024 -4.101084)
			(end 5.568188 -2.801366)
			(stroke
				(width 0.1)
				(type default)
			)
			(layer "F.SilkS")
		)
		(fp_line
			(start 6.923024 -4.101084)
			(end 5.568188 -2.801366)
			(stroke
				(width 0.1)
				(type default)
			)
			(layer "F.SilkS")
		)
		(fp_line
			(start 6.923024 -4.101084)
			(end 6.935216 -4.170426)
			(stroke
				(width 0.1)
				(type default)
			)
			(layer "F.SilkS")
		)
		(fp_line
			(start 6.923024 -4.101084)
			(end 6.935216 -4.170426)
			(stroke
				(width 0.1)
				(type default)
			)
			(layer "F.SilkS")
		)
		(fp_line
			(start 6.935216 -4.170426)
			(end 5.58038 -2.870962)
			(stroke
				(width 0.1)
				(type default)
			)
			(layer "F.SilkS")
		)
		(fp_line
			(start 6.935216 -4.170426)
			(end 5.58038 -2.870962)
			(stroke
				(width 0.1)
				(type default)
			)
			(layer "F.SilkS")
		)
		(fp_line
			(start 6.935216 -4.170426)
			(end 6.947408 -4.240022)
			(stroke
				(width 0.1)
				(type default)
			)
			(layer "F.SilkS")
		)
		(fp_line
			(start 6.935216 -4.170426)
			(end 6.947408 -4.240022)
			(stroke
				(width 0.1)
				(type default)
			)
			(layer "F.SilkS")
		)
		(fp_line
			(start 6.947408 -4.240022)
			(end 5.592572 -2.940304)
			(stroke
				(width 0.1)
				(type default)
			)
			(layer "F.SilkS")
		)
		(fp_line
			(start 6.947408 -4.240022)
			(end 5.592572 -2.940304)
			(stroke
				(width 0.1)
				(type default)
			)
			(layer "F.SilkS")
		)
		(fp_line
			(start 6.947408 -4.240022)
			(end 6.9596 -4.309364)
			(stroke
				(width 0.1)
				(type default)
			)
			(layer "F.SilkS")
		)
		(fp_line
			(start 6.947408 -4.240022)
			(end 6.9596 -4.309364)
			(stroke
				(width 0.1)
				(type default)
			)
			(layer "F.SilkS")
		)
		(fp_line
			(start 6.956044 -5.171694)
			(end 5.78739 -4.050538)
			(stroke
				(width 0.1)
				(type default)
			)
			(layer "F.SilkS")
		)
		(fp_line
			(start 6.956044 -5.171694)
			(end 5.78739 -4.050538)
			(stroke
				(width 0.1)
				(type default)
			)
			(layer "F.SilkS")
		)
		(fp_line
			(start 6.956044 -5.171694)
			(end 6.895846 -5.171694)
			(stroke
				(width 0.1)
				(type default)
			)
			(layer "F.SilkS")
		)
		(fp_line
			(start 6.956044 -5.171694)
			(end 6.895846 -5.171694)
			(stroke
				(width 0.1)
				(type default)
			)
			(layer "F.SilkS")
		)
		(fp_line
			(start 6.9596 -4.309364)
			(end 5.604764 -3.009646)
			(stroke
				(width 0.1)
				(type default)
			)
			(layer "F.SilkS")
		)
		(fp_line
			(start 6.9596 -4.309364)
			(end 5.604764 -3.009646)
			(stroke
				(width 0.1)
				(type default)
			)
			(layer "F.SilkS")
		)
		(fp_line
			(start 6.9596 -4.309364)
			(end 6.971792 -4.378706)
			(stroke
				(width 0.1)
				(type default)
			)
			(layer "F.SilkS")
		)
		(fp_line
			(start 6.9596 -4.309364)
			(end 6.971792 -4.378706)
			(stroke
				(width 0.1)
				(type default)
			)
			(layer "F.SilkS")
		)
		(fp_line
			(start 6.971792 -4.378706)
			(end 5.616956 -3.079242)
			(stroke
				(width 0.1)
				(type default)
			)
			(layer "F.SilkS")
		)
		(fp_line
			(start 6.971792 -4.378706)
			(end 5.616956 -3.079242)
			(stroke
				(width 0.1)
				(type default)
			)
			(layer "F.SilkS")
		)
		(fp_line
			(start 6.971792 -4.378706)
			(end 6.983984 -4.448302)
			(stroke
				(width 0.1)
				(type default)
			)
			(layer "F.SilkS")
		)
		(fp_line
			(start 6.971792 -4.378706)
			(end 6.983984 -4.448302)
			(stroke
				(width 0.1)
				(type default)
			)
			(layer "F.SilkS")
		)
		(fp_line
			(start 6.981444 -0.809752)
			(end 9.330944 -3.063748)
			(stroke
				(width 0.1)
				(type default)
			)
			(layer "F.SilkS")
		)
		(fp_line
			(start 6.981444 -0.809752)
			(end 9.330944 -3.063748)
			(stroke
				(width 0.1)
				(type default)
			)
			(layer "F.SilkS")
		)
		(fp_line
			(start 6.983984 -4.448302)
			(end 5.629148 -3.148584)
			(stroke
				(width 0.1)
				(type default)
			)
			(layer "F.SilkS")
		)
		(fp_line
			(start 6.983984 -4.448302)
			(end 5.629148 -3.148584)
			(stroke
				(width 0.1)
				(type default)
			)
			(layer "F.SilkS")
		)
		(fp_line
			(start 6.983984 -4.448302)
			(end 6.996176 -4.51739)
			(stroke
				(width 0.1)
				(type default)
			)
			(layer "F.SilkS")
		)
		(fp_line
			(start 6.983984 -4.448302)
			(end 6.996176 -4.51739)
			(stroke
				(width 0.1)
				(type default)
			)
			(layer "F.SilkS")
		)
		(fp_line
			(start 6.996176 -4.51739)
			(end 5.64134 -3.217926)
			(stroke
				(width 0.1)
				(type default)
			)
			(layer "F.SilkS")
		)
		(fp_line
			(start 6.996176 -4.51739)
			(end 5.64134 -3.217926)
			(stroke
				(width 0.1)
				(type default)
			)
			(layer "F.SilkS")
		)
		(fp_line
			(start 6.996176 -4.51739)
			(end 7.008368 -4.586986)
			(stroke
				(width 0.1)
				(type default)
			)
			(layer "F.SilkS")
		)
		(fp_line
			(start 6.996176 -4.51739)
			(end 7.008368 -4.586986)
			(stroke
				(width 0.1)
				(type default)
			)
			(layer "F.SilkS")
		)
		(fp_line
			(start 7.008368 -4.586986)
			(end 5.653532 -3.287268)
			(stroke
				(width 0.1)
				(type default)
			)
			(layer "F.SilkS")
		)
		(fp_line
			(start 7.008368 -4.586986)
			(end 5.653532 -3.287268)
			(stroke
				(width 0.1)
				(type default)
			)
			(layer "F.SilkS")
		)
		(fp_line
			(start 7.008368 -4.586986)
			(end 7.02056 -4.656328)
			(stroke
				(width 0.1)
				(type default)
			)
			(layer "F.SilkS")
		)
		(fp_line
			(start 7.008368 -4.586986)
			(end 7.02056 -4.656328)
			(stroke
				(width 0.1)
				(type default)
			)
			(layer "F.SilkS")
		)
		(fp_line
			(start 7.016242 -5.171694)
			(end 5.775198 -3.98145)
			(stroke
				(width 0.1)
				(type default)
			)
			(layer "F.SilkS")
		)
		(fp_line
			(start 7.016242 -5.171694)
			(end 5.775198 -3.98145)
			(stroke
				(width 0.1)
				(type default)
			)
			(layer "F.SilkS")
		)
		(fp_line
			(start 7.016242 -5.171694)
			(end 6.956044 -5.171694)
			(stroke
				(width 0.1)
				(type default)
			)
			(layer "F.SilkS")
		)
		(fp_line
			(start 7.016242 -5.171694)
			(end 6.956044 -5.171694)
			(stroke
				(width 0.1)
				(type default)
			)
			(layer "F.SilkS")
		)
		(fp_line
			(start 7.02056 -4.656328)
			(end 5.665724 -3.35661)
			(stroke
				(width 0.1)
				(type default)
			)
			(layer "F.SilkS")
		)
		(fp_line
			(start 7.02056 -4.656328)
			(end 5.665724 -3.35661)
			(stroke
				(width 0.1)
				(type default)
			)
			(layer "F.SilkS")
		)
		(fp_line
			(start 7.02056 -4.656328)
			(end 7.032752 -4.725924)
			(stroke
				(width 0.1)
				(type default)
			)
			(layer "F.SilkS")
		)
		(fp_line
			(start 7.02056 -4.656328)
			(end 7.032752 -4.725924)
			(stroke
				(width 0.1)
				(type default)
			)
			(layer "F.SilkS")
		)
		(fp_line
			(start 7.032752 -4.725924)
			(end 5.677662 -3.425952)
			(stroke
				(width 0.1)
				(type default)
			)
			(layer "F.SilkS")
		)
		(fp_line
			(start 7.032752 -4.725924)
			(end 5.677662 -3.425952)
			(stroke
				(width 0.1)
				(type default)
			)
			(layer "F.SilkS")
		)
		(fp_line
			(start 7.032752 -4.725924)
			(end 7.04469 -4.795012)
			(stroke
				(width 0.1)
				(type default)
			)
			(layer "F.SilkS")
		)
		(fp_line
			(start 7.032752 -4.725924)
			(end 7.04469 -4.795012)
			(stroke
				(width 0.1)
				(type default)
			)
			(layer "F.SilkS")
		)
		(fp_line
			(start 7.04469 -4.795012)
			(end 5.690108 -3.495548)
			(stroke
				(width 0.1)
				(type default)
			)
			(layer "F.SilkS")
		)
		(fp_line
			(start 7.04469 -4.795012)
			(end 5.690108 -3.495548)
			(stroke
				(width 0.1)
				(type default)
			)
			(layer "F.SilkS")
		)
		(fp_line
			(start 7.04469 -4.795012)
			(end 7.057136 -4.864354)
			(stroke
				(width 0.1)
				(type default)
			)
			(layer "F.SilkS")
		)
		(fp_line
			(start 7.04469 -4.795012)
			(end 7.057136 -4.864354)
			(stroke
				(width 0.1)
				(type default)
			)
			(layer "F.SilkS")
		)
		(fp_line
			(start 7.047992 -0.816102)
			(end 9.318752 -2.994406)
			(stroke
				(width 0.1)
				(type default)
			)
			(layer "F.SilkS")
		)
		(fp_line
			(start 7.047992 -0.816102)
			(end 9.318752 -2.994406)
			(stroke
				(width 0.1)
				(type default)
			)
			(layer "F.SilkS")
		)
		(fp_line
			(start 7.057136 -4.864354)
			(end 5.7023 -3.56489)
			(stroke
				(width 0.1)
				(type default)
			)
			(layer "F.SilkS")
		)
		(fp_line
			(start 7.057136 -4.864354)
			(end 5.7023 -3.56489)
			(stroke
				(width 0.1)
				(type default)
			)
			(layer "F.SilkS")
		)
		(fp_line
			(start 7.057136 -4.864354)
			(end 7.069328 -4.93395)
			(stroke
				(width 0.1)
				(type default)
			)
			(layer "F.SilkS")
		)
		(fp_line
			(start 7.057136 -4.864354)
			(end 7.069328 -4.93395)
			(stroke
				(width 0.1)
				(type default)
			)
			(layer "F.SilkS")
		)
		(fp_line
			(start 7.069328 -4.93395)
			(end 5.714238 -3.634232)
			(stroke
				(width 0.1)
				(type default)
			)
			(layer "F.SilkS")
		)
		(fp_line
			(start 7.069328 -4.93395)
			(end 5.714238 -3.634232)
			(stroke
				(width 0.1)
				(type default)
			)
			(layer "F.SilkS")
		)
		(fp_line
			(start 7.069328 -4.93395)
			(end 7.081266 -5.003292)
			(stroke
				(width 0.1)
				(type default)
			)
			(layer "F.SilkS")
		)
		(fp_line
			(start 7.069328 -4.93395)
			(end 7.081266 -5.003292)
			(stroke
				(width 0.1)
				(type default)
			)
			(layer "F.SilkS")
		)
		(fp_line
			(start 7.07644 -5.171694)
			(end 5.763006 -3.911854)
			(stroke
				(width 0.1)
				(type default)
			)
			(layer "F.SilkS")
		)
		(fp_line
			(start 7.07644 -5.171694)
			(end 5.763006 -3.911854)
			(stroke
				(width 0.1)
				(type default)
			)
			(layer "F.SilkS")
		)
		(fp_line
			(start 7.07644 -5.171694)
			(end 7.016242 -5.171694)
			(stroke
				(width 0.1)
				(type default)
			)
			(layer "F.SilkS")
		)
		(fp_line
			(start 7.07644 -5.171694)
			(end 7.016242 -5.171694)
			(stroke
				(width 0.1)
				(type default)
			)
			(layer "F.SilkS")
		)
		(fp_line
			(start 7.081266 -5.003292)
			(end 5.72643 -3.703828)
			(stroke
				(width 0.1)
				(type default)
			)
			(layer "F.SilkS")
		)
		(fp_line
			(start 7.081266 -5.003292)
			(end 5.72643 -3.703828)
			(stroke
				(width 0.1)
				(type default)
			)
			(layer "F.SilkS")
		)
		(fp_line
			(start 7.081266 -5.003292)
			(end 7.093458 -5.072888)
			(stroke
				(width 0.1)
				(type default)
			)
			(layer "F.SilkS")
		)
		(fp_line
			(start 7.081266 -5.003292)
			(end 7.093458 -5.072888)
			(stroke
				(width 0.1)
				(type default)
			)
			(layer "F.SilkS")
		)
		(fp_line
			(start 7.093458 -5.072888)
			(end 5.738876 -3.772916)
			(stroke
				(width 0.1)
				(type default)
			)
			(layer "F.SilkS")
		)
		(fp_line
			(start 7.093458 -5.072888)
			(end 5.738876 -3.772916)
			(stroke
				(width 0.1)
				(type default)
			)
			(layer "F.SilkS")
		)
		(fp_line
			(start 7.093458 -5.072888)
			(end 7.10565 -5.141976)
			(stroke
				(width 0.1)
				(type default)
			)
			(layer "F.SilkS")
		)
		(fp_line
			(start 7.093458 -5.072888)
			(end 7.10565 -5.141976)
			(stroke
				(width 0.1)
				(type default)
			)
			(layer "F.SilkS")
		)
		(fp_line
			(start 7.10565 -5.141976)
			(end 5.751068 -3.842512)
			(stroke
				(width 0.1)
				(type default)
			)
			(layer "F.SilkS")
		)
		(fp_line
			(start 7.10565 -5.141976)
			(end 5.751068 -3.842512)
			(stroke
				(width 0.1)
				(type default)
			)
			(layer "F.SilkS")
		)
		(fp_line
			(start 7.10565 -5.141976)
			(end 7.110984 -5.171694)
			(stroke
				(width 0.1)
				(type default)
			)
			(layer "F.SilkS")
		)
		(fp_line
			(start 7.10565 -5.141976)
			(end 7.110984 -5.171694)
			(stroke
				(width 0.1)
				(type default)
			)
			(layer "F.SilkS")
		)
		(fp_line
			(start 7.110984 -5.171694)
			(end 7.07644 -5.171694)
			(stroke
				(width 0.1)
				(type default)
			)
			(layer "F.SilkS")
		)
		(fp_line
			(start 7.110984 -5.171694)
			(end 7.07644 -5.171694)
			(stroke
				(width 0.1)
				(type default)
			)
			(layer "F.SilkS")
		)
		(fp_line
			(start 7.11454 -0.822198)
			(end 9.30656 -2.925064)
			(stroke
				(width 0.1)
				(type default)
			)
			(layer "F.SilkS")
		)
		(fp_line
			(start 7.11454 -0.822198)
			(end 9.30656 -2.925064)
			(stroke
				(width 0.1)
				(type default)
			)
			(layer "F.SilkS")
		)
		(fp_line
			(start 7.196582 -0.84328)
			(end 9.294368 -2.855468)
			(stroke
				(width 0.1)
				(type default)
			)
			(layer "F.SilkS")
		)
		(fp_line
			(start 7.196582 -0.84328)
			(end 9.294368 -2.855468)
			(stroke
				(width 0.1)
				(type default)
			)
			(layer "F.SilkS")
		)
		(fp_line
			(start 7.281418 -0.866648)
			(end 9.281922 -2.786126)
			(stroke
				(width 0.1)
				(type default)
			)
			(layer "F.SilkS")
		)
		(fp_line
			(start 7.281418 -0.866648)
			(end 9.281922 -2.786126)
			(stroke
				(width 0.1)
				(type default)
			)
			(layer "F.SilkS")
		)
		(fp_line
			(start 7.366 -0.890016)
			(end 9.269984 -2.716784)
			(stroke
				(width 0.1)
				(type default)
			)
			(layer "F.SilkS")
		)
		(fp_line
			(start 7.366 -0.890016)
			(end 9.269984 -2.716784)
			(stroke
				(width 0.1)
				(type default)
			)
			(layer "F.SilkS")
		)
		(fp_line
			(start 7.464298 -0.926846)
			(end 9.257792 -2.647188)
			(stroke
				(width 0.1)
				(type default)
			)
			(layer "F.SilkS")
		)
		(fp_line
			(start 7.464298 -0.926846)
			(end 9.257792 -2.647188)
			(stroke
				(width 0.1)
				(type default)
			)
			(layer "F.SilkS")
		)
		(fp_line
			(start 7.583678 -0.983488)
			(end 9.2456 -2.577592)
			(stroke
				(width 0.1)
				(type default)
			)
			(layer "F.SilkS")
		)
		(fp_line
			(start 7.583678 -0.983488)
			(end 9.2456 -2.577592)
			(stroke
				(width 0.1)
				(type default)
			)
			(layer "F.SilkS")
		)
		(fp_line
			(start 7.737348 -1.07315)
			(end 9.233408 -2.508504)
			(stroke
				(width 0.1)
				(type default)
			)
			(layer "F.SilkS")
		)
		(fp_line
			(start 7.737348 -1.07315)
			(end 9.233408 -2.508504)
			(stroke
				(width 0.1)
				(type default)
			)
			(layer "F.SilkS")
		)
		(fp_line
			(start 7.82066 -0.882904)
			(end 7.839456 -0.882904)
			(stroke
				(width 0.1)
				(type default)
			)
			(layer "F.SilkS")
		)
		(fp_line
			(start 7.82066 -0.882904)
			(end 7.839456 -0.882904)
			(stroke
				(width 0.1)
				(type default)
			)
			(layer "F.SilkS")
		)
		(fp_line
			(start 7.828788 -0.930148)
			(end 7.82066 -0.882904)
			(stroke
				(width 0.1)
				(type default)
			)
			(layer "F.SilkS")
		)
		(fp_line
			(start 7.828788 -0.930148)
			(end 7.82066 -0.882904)
			(stroke
				(width 0.1)
				(type default)
			)
			(layer "F.SilkS")
		)
		(fp_line
			(start 7.828788 -0.930148)
			(end 9.18464 -2.230882)
			(stroke
				(width 0.1)
				(type default)
			)
			(layer "F.SilkS")
		)
		(fp_line
			(start 7.828788 -0.930148)
			(end 9.18464 -2.230882)
			(stroke
				(width 0.1)
				(type default)
			)
			(layer "F.SilkS")
		)
		(fp_line
			(start 7.839456 -0.882904)
			(end 7.899908 -0.882904)
			(stroke
				(width 0.1)
				(type default)
			)
			(layer "F.SilkS")
		)
		(fp_line
			(start 7.839456 -0.882904)
			(end 7.899908 -0.882904)
			(stroke
				(width 0.1)
				(type default)
			)
			(layer "F.SilkS")
		)
		(fp_line
			(start 7.839456 -0.882904)
			(end 9.172194 -2.161286)
			(stroke
				(width 0.1)
				(type default)
			)
			(layer "F.SilkS")
		)
		(fp_line
			(start 7.839456 -0.882904)
			(end 9.172194 -2.161286)
			(stroke
				(width 0.1)
				(type default)
			)
			(layer "F.SilkS")
		)
		(fp_line
			(start 7.84098 -0.999744)
			(end 7.828788 -0.930148)
			(stroke
				(width 0.1)
				(type default)
			)
			(layer "F.SilkS")
		)
		(fp_line
			(start 7.84098 -0.999744)
			(end 7.828788 -0.930148)
			(stroke
				(width 0.1)
				(type default)
			)
			(layer "F.SilkS")
		)
		(fp_line
			(start 7.84098 -0.999744)
			(end 9.196832 -2.300224)
			(stroke
				(width 0.1)
				(type default)
			)
			(layer "F.SilkS")
		)
		(fp_line
			(start 7.84098 -0.999744)
			(end 9.196832 -2.300224)
			(stroke
				(width 0.1)
				(type default)
			)
			(layer "F.SilkS")
		)
		(fp_line
			(start 7.852918 -1.068832)
			(end 7.84098 -0.999744)
			(stroke
				(width 0.1)
				(type default)
			)
			(layer "F.SilkS")
		)
		(fp_line
			(start 7.852918 -1.068832)
			(end 7.84098 -0.999744)
			(stroke
				(width 0.1)
				(type default)
			)
			(layer "F.SilkS")
		)
		(fp_line
			(start 7.852918 -1.068832)
			(end 9.209024 -2.369566)
			(stroke
				(width 0.1)
				(type default)
			)
			(layer "F.SilkS")
		)
		(fp_line
			(start 7.852918 -1.068832)
			(end 9.209024 -2.369566)
			(stroke
				(width 0.1)
				(type default)
			)
			(layer "F.SilkS")
		)
		(fp_line
			(start 7.865364 -1.138428)
			(end 7.852918 -1.068832)
			(stroke
				(width 0.1)
				(type default)
			)
			(layer "F.SilkS")
		)
		(fp_line
			(start 7.865364 -1.138428)
			(end 7.852918 -1.068832)
			(stroke
				(width 0.1)
				(type default)
			)
			(layer "F.SilkS")
		)
		(fp_line
			(start 7.865364 -1.138428)
			(end 9.220962 -2.438908)
			(stroke
				(width 0.1)
				(type default)
			)
			(layer "F.SilkS")
		)
		(fp_line
			(start 7.865364 -1.138428)
			(end 9.220962 -2.438908)
			(stroke
				(width 0.1)
				(type default)
			)
			(layer "F.SilkS")
		)
		(fp_line
			(start 7.899908 -0.882904)
			(end 7.960106 -0.882904)
			(stroke
				(width 0.1)
				(type default)
			)
			(layer "F.SilkS")
		)
		(fp_line
			(start 7.899908 -0.882904)
			(end 7.960106 -0.882904)
			(stroke
				(width 0.1)
				(type default)
			)
			(layer "F.SilkS")
		)
		(fp_line
			(start 7.899908 -0.882904)
			(end 9.160002 -2.091944)
			(stroke
				(width 0.1)
				(type default)
			)
			(layer "F.SilkS")
		)
		(fp_line
			(start 7.899908 -0.882904)
			(end 9.160002 -2.091944)
			(stroke
				(width 0.1)
				(type default)
			)
			(layer "F.SilkS")
		)
		(fp_line
			(start 7.936484 -2.187702)
			(end 9.42848 -3.618992)
			(stroke
				(width 0.1)
				(type default)
			)
			(layer "F.SilkS")
		)
		(fp_line
			(start 7.936484 -2.187702)
			(end 9.42848 -3.618992)
			(stroke
				(width 0.1)
				(type default)
			)
			(layer "F.SilkS")
		)
		(fp_line
			(start 7.960106 -0.882904)
			(end 8.02005 -0.882904)
			(stroke
				(width 0.1)
				(type default)
			)
			(layer "F.SilkS")
		)
		(fp_line
			(start 7.960106 -0.882904)
			(end 8.02005 -0.882904)
			(stroke
				(width 0.1)
				(type default)
			)
			(layer "F.SilkS")
		)
		(fp_line
			(start 7.960106 -0.882904)
			(end 9.148064 -2.022602)
			(stroke
				(width 0.1)
				(type default)
			)
			(layer "F.SilkS")
		)
		(fp_line
			(start 7.960106 -0.882904)
			(end 9.148064 -2.022602)
			(stroke
				(width 0.1)
				(type default)
			)
			(layer "F.SilkS")
		)
		(fp_line
			(start 8.002778 -2.30886)
			(end 9.440672 -3.688334)
			(stroke
				(width 0.1)
				(type default)
			)
			(layer "F.SilkS")
		)
		(fp_line
			(start 8.002778 -2.30886)
			(end 9.440672 -3.688334)
			(stroke
				(width 0.1)
				(type default)
			)
			(layer "F.SilkS")
		)
		(fp_line
			(start 8.02005 -0.882904)
			(end 8.080248 -0.882904)
			(stroke
				(width 0.1)
				(type default)
			)
			(layer "F.SilkS")
		)
		(fp_line
			(start 8.02005 -0.882904)
			(end 8.080248 -0.882904)
			(stroke
				(width 0.1)
				(type default)
			)
			(layer "F.SilkS")
		)
		(fp_line
			(start 8.02005 -0.882904)
			(end 9.135872 -1.953006)
			(stroke
				(width 0.1)
				(type default)
			)
			(layer "F.SilkS")
		)
		(fp_line
			(start 8.02005 -0.882904)
			(end 9.135872 -1.953006)
			(stroke
				(width 0.1)
				(type default)
			)
			(layer "F.SilkS")
		)
		(fp_line
			(start 8.04799 -2.410206)
			(end 9.452864 -3.75793)
			(stroke
				(width 0.1)
				(type default)
			)
			(layer "F.SilkS")
		)
		(fp_line
			(start 8.04799 -2.410206)
			(end 9.452864 -3.75793)
			(stroke
				(width 0.1)
				(type default)
			)
			(layer "F.SilkS")
		)
		(fp_line
			(start 8.078724 -2.497328)
			(end 9.465056 -3.827526)
			(stroke
				(width 0.1)
				(type default)
			)
			(layer "F.SilkS")
		)
		(fp_line
			(start 8.078724 -2.497328)
			(end 9.465056 -3.827526)
			(stroke
				(width 0.1)
				(type default)
			)
			(layer "F.SilkS")
		)
		(fp_line
			(start 8.080248 -0.882904)
			(end 8.140446 -0.882904)
			(stroke
				(width 0.1)
				(type default)
			)
			(layer "F.SilkS")
		)
		(fp_line
			(start 8.080248 -0.882904)
			(end 8.140446 -0.882904)
			(stroke
				(width 0.1)
				(type default)
			)
			(layer "F.SilkS")
		)
		(fp_line
			(start 8.080248 -0.882904)
			(end 9.12368 -1.883664)
			(stroke
				(width 0.1)
				(type default)
			)
			(layer "F.SilkS")
		)
		(fp_line
			(start 8.080248 -0.882904)
			(end 9.12368 -1.883664)
			(stroke
				(width 0.1)
				(type default)
			)
			(layer "F.SilkS")
		)
		(fp_line
			(start 8.140446 -0.882904)
			(end 8.200644 -0.882904)
			(stroke
				(width 0.1)
				(type default)
			)
			(layer "F.SilkS")
		)
		(fp_line
			(start 8.140446 -0.882904)
			(end 8.200644 -0.882904)
			(stroke
				(width 0.1)
				(type default)
			)
			(layer "F.SilkS")
		)
		(fp_line
			(start 8.140446 -0.882904)
			(end 9.111234 -1.814322)
			(stroke
				(width 0.1)
				(type default)
			)
			(layer "F.SilkS")
		)
		(fp_line
			(start 8.140446 -0.882904)
			(end 9.111234 -1.814322)
			(stroke
				(width 0.1)
				(type default)
			)
			(layer "F.SilkS")
		)
		(fp_line
			(start 8.18261 -2.943352)
			(end 8.170418 -2.87401)
			(stroke
				(width 0.1)
				(type default)
			)
			(layer "F.SilkS")
		)
		(fp_line
			(start 8.18261 -2.943352)
			(end 8.170418 -2.87401)
			(stroke
				(width 0.1)
				(type default)
			)
			(layer "F.SilkS")
		)
		(fp_line
			(start 8.194802 -3.012694)
			(end 8.18261 -2.943352)
			(stroke
				(width 0.1)
				(type default)
			)
			(layer "F.SilkS")
		)
		(fp_line
			(start 8.194802 -3.012694)
			(end 8.18261 -2.943352)
			(stroke
				(width 0.1)
				(type default)
			)
			(layer "F.SilkS")
		)
		(fp_line
			(start 8.200644 -0.882904)
			(end 8.260842 -0.882904)
			(stroke
				(width 0.1)
				(type default)
			)
			(layer "F.SilkS")
		)
		(fp_line
			(start 8.200644 -0.882904)
			(end 8.260842 -0.882904)
			(stroke
				(width 0.1)
				(type default)
			)
			(layer "F.SilkS")
		)
		(fp_line
			(start 8.200644 -0.882904)
			(end 9.099042 -1.744726)
			(stroke
				(width 0.1)
				(type default)
			)
			(layer "F.SilkS")
		)
		(fp_line
			(start 8.200644 -0.882904)
			(end 9.099042 -1.744726)
			(stroke
				(width 0.1)
				(type default)
			)
			(layer "F.SilkS")
		)
		(fp_line
			(start 8.206994 -3.08229)
			(end 8.194802 -3.012694)
			(stroke
				(width 0.1)
				(type default)
			)
			(layer "F.SilkS")
		)
		(fp_line
			(start 8.206994 -3.08229)
			(end 8.194802 -3.012694)
			(stroke
				(width 0.1)
				(type default)
			)
			(layer "F.SilkS")
		)
		(fp_line
			(start 8.219186 -3.151378)
			(end 8.206994 -3.08229)
			(stroke
				(width 0.1)
				(type default)
			)
			(layer "F.SilkS")
		)
		(fp_line
			(start 8.219186 -3.151378)
			(end 8.206994 -3.08229)
			(stroke
				(width 0.1)
				(type default)
			)
			(layer "F.SilkS")
		)
		(fp_line
			(start 8.231378 -3.22072)
			(end 8.219186 -3.151378)
			(stroke
				(width 0.1)
				(type default)
			)
			(layer "F.SilkS")
		)
		(fp_line
			(start 8.231378 -3.22072)
			(end 8.219186 -3.151378)
			(stroke
				(width 0.1)
				(type default)
			)
			(layer "F.SilkS")
		)
		(fp_line
			(start 8.24357 -3.290316)
			(end 8.231378 -3.22072)
			(stroke
				(width 0.1)
				(type default)
			)
			(layer "F.SilkS")
		)
		(fp_line
			(start 8.24357 -3.290316)
			(end 8.231378 -3.22072)
			(stroke
				(width 0.1)
				(type default)
			)
			(layer "F.SilkS")
		)
		(fp_line
			(start 8.255762 -3.359658)
			(end 8.24357 -3.290316)
			(stroke
				(width 0.1)
				(type default)
			)
			(layer "F.SilkS")
		)
		(fp_line
			(start 8.255762 -3.359658)
			(end 8.24357 -3.290316)
			(stroke
				(width 0.1)
				(type default)
			)
			(layer "F.SilkS")
		)
		(fp_line
			(start 8.260842 -0.882904)
			(end 8.320786 -0.882904)
			(stroke
				(width 0.1)
				(type default)
			)
			(layer "F.SilkS")
		)
		(fp_line
			(start 8.260842 -0.882904)
			(end 8.320786 -0.882904)
			(stroke
				(width 0.1)
				(type default)
			)
			(layer "F.SilkS")
		)
		(fp_line
			(start 8.260842 -0.882904)
			(end 9.087104 -1.675384)
			(stroke
				(width 0.1)
				(type default)
			)
			(layer "F.SilkS")
		)
		(fp_line
			(start 8.260842 -0.882904)
			(end 9.087104 -1.675384)
			(stroke
				(width 0.1)
				(type default)
			)
			(layer "F.SilkS")
		)
		(fp_line
			(start 8.2677 -3.429)
			(end 8.255762 -3.359658)
			(stroke
				(width 0.1)
				(type default)
			)
			(layer "F.SilkS")
		)
		(fp_line
			(start 8.2677 -3.429)
			(end 8.255762 -3.359658)
			(stroke
				(width 0.1)
				(type default)
			)
			(layer "F.SilkS")
		)
		(fp_line
			(start 8.279892 -3.498342)
			(end 8.2677 -3.429)
			(stroke
				(width 0.1)
				(type default)
			)
			(layer "F.SilkS")
		)
		(fp_line
			(start 8.279892 -3.498342)
			(end 8.2677 -3.429)
			(stroke
				(width 0.1)
				(type default)
			)
			(layer "F.SilkS")
		)
		(fp_line
			(start 8.292084 -3.567684)
			(end 8.279892 -3.498342)
			(stroke
				(width 0.1)
				(type default)
			)
			(layer "F.SilkS")
		)
		(fp_line
			(start 8.292084 -3.567684)
			(end 8.279892 -3.498342)
			(stroke
				(width 0.1)
				(type default)
			)
			(layer "F.SilkS")
		)
		(fp_line
			(start 8.304276 -3.63728)
			(end 8.292084 -3.567684)
			(stroke
				(width 0.1)
				(type default)
			)
			(layer "F.SilkS")
		)
		(fp_line
			(start 8.304276 -3.63728)
			(end 8.292084 -3.567684)
			(stroke
				(width 0.1)
				(type default)
			)
			(layer "F.SilkS")
		)
		(fp_line
			(start 8.316468 -3.706368)
			(end 8.304276 -3.63728)
			(stroke
				(width 0.1)
				(type default)
			)
			(layer "F.SilkS")
		)
		(fp_line
			(start 8.316468 -3.706368)
			(end 8.304276 -3.63728)
			(stroke
				(width 0.1)
				(type default)
			)
			(layer "F.SilkS")
		)
		(fp_line
			(start 8.320786 -0.882904)
			(end 8.381238 -0.882904)
			(stroke
				(width 0.1)
				(type default)
			)
			(layer "F.SilkS")
		)
		(fp_line
			(start 8.320786 -0.882904)
			(end 8.381238 -0.882904)
			(stroke
				(width 0.1)
				(type default)
			)
			(layer "F.SilkS")
		)
		(fp_line
			(start 8.320786 -0.882904)
			(end 9.074912 -1.606296)
			(stroke
				(width 0.1)
				(type default)
			)
			(layer "F.SilkS")
		)
		(fp_line
			(start 8.320786 -0.882904)
			(end 9.074912 -1.606296)
			(stroke
				(width 0.1)
				(type default)
			)
			(layer "F.SilkS")
		)
		(fp_line
			(start 8.32866 -3.77571)
			(end 8.316468 -3.706368)
			(stroke
				(width 0.1)
				(type default)
			)
			(layer "F.SilkS")
		)
		(fp_line
			(start 8.32866 -3.77571)
			(end 8.316468 -3.706368)
			(stroke
				(width 0.1)
				(type default)
			)
			(layer "F.SilkS")
		)
		(fp_line
			(start 8.340852 -3.845306)
			(end 8.32866 -3.77571)
			(stroke
				(width 0.1)
				(type default)
			)
			(layer "F.SilkS")
		)
		(fp_line
			(start 8.340852 -3.845306)
			(end 8.32866 -3.77571)
			(stroke
				(width 0.1)
				(type default)
			)
			(layer "F.SilkS")
		)
		(fp_line
			(start 8.35279 -3.914648)
			(end 8.340852 -3.845306)
			(stroke
				(width 0.1)
				(type default)
			)
			(layer "F.SilkS")
		)
		(fp_line
			(start 8.35279 -3.914648)
			(end 8.340852 -3.845306)
			(stroke
				(width 0.1)
				(type default)
			)
			(layer "F.SilkS")
		)
		(fp_line
			(start 8.365236 -3.98399)
			(end 8.35279 -3.914648)
			(stroke
				(width 0.1)
				(type default)
			)
			(layer "F.SilkS")
		)
		(fp_line
			(start 8.365236 -3.98399)
			(end 8.35279 -3.914648)
			(stroke
				(width 0.1)
				(type default)
			)
			(layer "F.SilkS")
		)
		(fp_line
			(start 8.377174 -4.053332)
			(end 8.365236 -3.98399)
			(stroke
				(width 0.1)
				(type default)
			)
			(layer "F.SilkS")
		)
		(fp_line
			(start 8.377174 -4.053332)
			(end 8.365236 -3.98399)
			(stroke
				(width 0.1)
				(type default)
			)
			(layer "F.SilkS")
		)
		(fp_line
			(start 8.381238 -0.882904)
			(end 8.441182 -0.882904)
			(stroke
				(width 0.1)
				(type default)
			)
			(layer "F.SilkS")
		)
		(fp_line
			(start 8.381238 -0.882904)
			(end 8.441182 -0.882904)
			(stroke
				(width 0.1)
				(type default)
			)
			(layer "F.SilkS")
		)
		(fp_line
			(start 8.381238 -0.882904)
			(end 9.062466 -1.5367)
			(stroke
				(width 0.1)
				(type default)
			)
			(layer "F.SilkS")
		)
		(fp_line
			(start 8.381238 -0.882904)
			(end 9.062466 -1.5367)
			(stroke
				(width 0.1)
				(type default)
			)
			(layer "F.SilkS")
		)
		(fp_line
			(start 8.389366 -4.122674)
			(end 8.377174 -4.053332)
			(stroke
				(width 0.1)
				(type default)
			)
			(layer "F.SilkS")
		)
		(fp_line
			(start 8.389366 -4.122674)
			(end 8.377174 -4.053332)
			(stroke
				(width 0.1)
				(type default)
			)
			(layer "F.SilkS")
		)
		(fp_line
			(start 8.401558 -4.19227)
			(end 8.389366 -4.122674)
			(stroke
				(width 0.1)
				(type default)
			)
			(layer "F.SilkS")
		)
		(fp_line
			(start 8.401558 -4.19227)
			(end 8.389366 -4.122674)
			(stroke
				(width 0.1)
				(type default)
			)
			(layer "F.SilkS")
		)
		(fp_line
			(start 8.41375 -4.261612)
			(end 8.401558 -4.19227)
			(stroke
				(width 0.1)
				(type default)
			)
			(layer "F.SilkS")
		)
		(fp_line
			(start 8.41375 -4.261612)
			(end 8.401558 -4.19227)
			(stroke
				(width 0.1)
				(type default)
			)
			(layer "F.SilkS")
		)
		(fp_line
			(start 8.425942 -4.3307)
			(end 8.41375 -4.261612)
			(stroke
				(width 0.1)
				(type default)
			)
			(layer "F.SilkS")
		)
		(fp_line
			(start 8.425942 -4.3307)
			(end 8.41375 -4.261612)
			(stroke
				(width 0.1)
				(type default)
			)
			(layer "F.SilkS")
		)
		(fp_line
			(start 8.43788 -4.400296)
			(end 8.425942 -4.3307)
			(stroke
				(width 0.1)
				(type default)
			)
			(layer "F.SilkS")
		)
		(fp_line
			(start 8.43788 -4.400296)
			(end 8.425942 -4.3307)
			(stroke
				(width 0.1)
				(type default)
			)
			(layer "F.SilkS")
		)
		(fp_line
			(start 8.441182 -0.882904)
			(end 8.50138 -0.882904)
			(stroke
				(width 0.1)
				(type default)
			)
			(layer "F.SilkS")
		)
		(fp_line
			(start 8.441182 -0.882904)
			(end 8.50138 -0.882904)
			(stroke
				(width 0.1)
				(type default)
			)
			(layer "F.SilkS")
		)
		(fp_line
			(start 8.441182 -0.882904)
			(end 9.050274 -1.467104)
			(stroke
				(width 0.1)
				(type default)
			)
			(layer "F.SilkS")
		)
		(fp_line
			(start 8.441182 -0.882904)
			(end 9.050274 -1.467104)
			(stroke
				(width 0.1)
				(type default)
			)
			(layer "F.SilkS")
		)
		(fp_line
			(start 8.450326 -4.469638)
			(end 8.43788 -4.400296)
			(stroke
				(width 0.1)
				(type default)
			)
			(layer "F.SilkS")
		)
		(fp_line
			(start 8.450326 -4.469638)
			(end 8.43788 -4.400296)
			(stroke
				(width 0.1)
				(type default)
			)
			(layer "F.SilkS")
		)
		(fp_line
			(start 8.450326 -4.469638)
			(end 8.462264 -4.53898)
			(stroke
				(width 0.1)
				(type default)
			)
			(layer "F.SilkS")
		)
		(fp_line
			(start 8.450326 -4.469638)
			(end 8.462264 -4.53898)
			(stroke
				(width 0.1)
				(type default)
			)
			(layer "F.SilkS")
		)
		(fp_line
			(start 8.462264 -4.53898)
			(end 8.474456 -4.608322)
			(stroke
				(width 0.1)
				(type default)
			)
			(layer "F.SilkS")
		)
		(fp_line
			(start 8.462264 -4.53898)
			(end 8.474456 -4.608322)
			(stroke
				(width 0.1)
				(type default)
			)
			(layer "F.SilkS")
		)
		(fp_line
			(start 8.474456 -4.608322)
			(end 8.486648 -4.677664)
			(stroke
				(width 0.1)
				(type default)
			)
			(layer "F.SilkS")
		)
		(fp_line
			(start 8.474456 -4.608322)
			(end 8.486648 -4.677664)
			(stroke
				(width 0.1)
				(type default)
			)
			(layer "F.SilkS")
		)
		(fp_line
			(start 8.486648 -4.677664)
			(end 8.49884 -4.74726)
			(stroke
				(width 0.1)
				(type default)
			)
			(layer "F.SilkS")
		)
		(fp_line
			(start 8.486648 -4.677664)
			(end 8.49884 -4.74726)
			(stroke
				(width 0.1)
				(type default)
			)
			(layer "F.SilkS")
		)
		(fp_line
			(start 8.49884 -4.74726)
			(end 8.511032 -4.816602)
			(stroke
				(width 0.1)
				(type default)
			)
			(layer "F.SilkS")
		)
		(fp_line
			(start 8.49884 -4.74726)
			(end 8.511032 -4.816602)
			(stroke
				(width 0.1)
				(type default)
			)
			(layer "F.SilkS")
		)
		(fp_line
			(start 8.50138 -0.882904)
			(end 8.561578 -0.882904)
			(stroke
				(width 0.1)
				(type default)
			)
			(layer "F.SilkS")
		)
		(fp_line
			(start 8.50138 -0.882904)
			(end 8.561578 -0.882904)
			(stroke
				(width 0.1)
				(type default)
			)
			(layer "F.SilkS")
		)
		(fp_line
			(start 8.50138 -0.882904)
			(end 9.038082 -1.397762)
			(stroke
				(width 0.1)
				(type default)
			)
			(layer "F.SilkS")
		)
		(fp_line
			(start 8.50138 -0.882904)
			(end 9.038082 -1.397762)
			(stroke
				(width 0.1)
				(type default)
			)
			(layer "F.SilkS")
		)
		(fp_line
			(start 8.511032 -4.816602)
			(end 8.52297 -4.88569)
			(stroke
				(width 0.1)
				(type default)
			)
			(layer "F.SilkS")
		)
		(fp_line
			(start 8.511032 -4.816602)
			(end 8.52297 -4.88569)
			(stroke
				(width 0.1)
				(type default)
			)
			(layer "F.SilkS")
		)
		(fp_line
			(start 8.52297 -4.88569)
			(end 8.535416 -4.955286)
			(stroke
				(width 0.1)
				(type default)
			)
			(layer "F.SilkS")
		)
		(fp_line
			(start 8.52297 -4.88569)
			(end 8.535416 -4.955286)
			(stroke
				(width 0.1)
				(type default)
			)
			(layer "F.SilkS")
		)
		(fp_line
			(start 8.535416 -4.955286)
			(end 8.547608 -5.024628)
			(stroke
				(width 0.1)
				(type default)
			)
			(layer "F.SilkS")
		)
		(fp_line
			(start 8.535416 -4.955286)
			(end 8.547608 -5.024628)
			(stroke
				(width 0.1)
				(type default)
			)
			(layer "F.SilkS")
		)
		(fp_line
			(start 8.547608 -5.024628)
			(end 8.559546 -5.09397)
			(stroke
				(width 0.1)
				(type default)
			)
			(layer "F.SilkS")
		)
		(fp_line
			(start 8.547608 -5.024628)
			(end 8.559546 -5.09397)
			(stroke
				(width 0.1)
				(type default)
			)
			(layer "F.SilkS")
		)
		(fp_line
			(start 8.559546 -5.09397)
			(end 8.571738 -5.163312)
			(stroke
				(width 0.1)
				(type default)
			)
			(layer "F.SilkS")
		)
		(fp_line
			(start 8.559546 -5.09397)
			(end 8.571738 -5.163312)
			(stroke
				(width 0.1)
				(type default)
			)
			(layer "F.SilkS")
		)
		(fp_line
			(start 8.561578 -0.882904)
			(end 8.621522 -0.882904)
			(stroke
				(width 0.1)
				(type default)
			)
			(layer "F.SilkS")
		)
		(fp_line
			(start 8.561578 -0.882904)
			(end 8.621522 -0.882904)
			(stroke
				(width 0.1)
				(type default)
			)
			(layer "F.SilkS")
		)
		(fp_line
			(start 8.561578 -0.882904)
			(end 9.026144 -1.32842)
			(stroke
				(width 0.1)
				(type default)
			)
			(layer "F.SilkS")
		)
		(fp_line
			(start 8.561578 -0.882904)
			(end 9.026144 -1.32842)
			(stroke
				(width 0.1)
				(type default)
			)
			(layer "F.SilkS")
		)
		(fp_line
			(start 8.573262 -5.171694)
			(end 8.571738 -5.163312)
			(stroke
				(width 0.1)
				(type default)
			)
			(layer "F.SilkS")
		)
		(fp_line
			(start 8.573262 -5.171694)
			(end 8.571738 -5.163312)
			(stroke
				(width 0.1)
				(type default)
			)
			(layer "F.SilkS")
		)
		(fp_line
			(start 8.580374 -5.171694)
			(end 8.571738 -5.163312)
			(stroke
				(width 0.1)
				(type default)
			)
			(layer "F.SilkS")
		)
		(fp_line
			(start 8.580374 -5.171694)
			(end 8.571738 -5.163312)
			(stroke
				(width 0.1)
				(type default)
			)
			(layer "F.SilkS")
		)
		(fp_line
			(start 8.580374 -5.171694)
			(end 8.573262 -5.171694)
			(stroke
				(width 0.1)
				(type default)
			)
			(layer "F.SilkS")
		)
		(fp_line
			(start 8.580374 -5.171694)
			(end 8.573262 -5.171694)
			(stroke
				(width 0.1)
				(type default)
			)
			(layer "F.SilkS")
		)
		(fp_line
			(start 8.621522 -0.882904)
			(end 8.681974 -0.882904)
			(stroke
				(width 0.1)
				(type default)
			)
			(layer "F.SilkS")
		)
		(fp_line
			(start 8.621522 -0.882904)
			(end 8.681974 -0.882904)
			(stroke
				(width 0.1)
				(type default)
			)
			(layer "F.SilkS")
		)
		(fp_line
			(start 8.621522 -0.882904)
			(end 9.013952 -1.259078)
			(stroke
				(width 0.1)
				(type default)
			)
			(layer "F.SilkS")
		)
		(fp_line
			(start 8.621522 -0.882904)
			(end 9.013952 -1.259078)
			(stroke
				(width 0.1)
				(type default)
			)
			(layer "F.SilkS")
		)
		(fp_line
			(start 8.640572 -5.171694)
			(end 8.559546 -5.09397)
			(stroke
				(width 0.1)
				(type default)
			)
			(layer "F.SilkS")
		)
		(fp_line
			(start 8.640572 -5.171694)
			(end 8.559546 -5.09397)
			(stroke
				(width 0.1)
				(type default)
			)
			(layer "F.SilkS")
		)
		(fp_line
			(start 8.640572 -5.171694)
			(end 8.580374 -5.171694)
			(stroke
				(width 0.1)
				(type default)
			)
			(layer "F.SilkS")
		)
		(fp_line
			(start 8.640572 -5.171694)
			(end 8.580374 -5.171694)
			(stroke
				(width 0.1)
				(type default)
			)
			(layer "F.SilkS")
		)
		(fp_line
			(start 8.681974 -0.882904)
			(end 8.741918 -0.882904)
			(stroke
				(width 0.1)
				(type default)
			)
			(layer "F.SilkS")
		)
		(fp_line
			(start 8.681974 -0.882904)
			(end 8.741918 -0.882904)
			(stroke
				(width 0.1)
				(type default)
			)
			(layer "F.SilkS")
		)
		(fp_line
			(start 8.681974 -0.882904)
			(end 9.001506 -1.189482)
			(stroke
				(width 0.1)
				(type default)
			)
			(layer "F.SilkS")
		)
		(fp_line
			(start 8.681974 -0.882904)
			(end 9.001506 -1.189482)
			(stroke
				(width 0.1)
				(type default)
			)
			(layer "F.SilkS")
		)
		(fp_line
			(start 8.70077 -5.171694)
			(end 8.547608 -5.024628)
			(stroke
				(width 0.1)
				(type default)
			)
			(layer "F.SilkS")
		)
		(fp_line
			(start 8.70077 -5.171694)
			(end 8.547608 -5.024628)
			(stroke
				(width 0.1)
				(type default)
			)
			(layer "F.SilkS")
		)
		(fp_line
			(start 8.70077 -5.171694)
			(end 8.640572 -5.171694)
			(stroke
				(width 0.1)
				(type default)
			)
			(layer "F.SilkS")
		)
		(fp_line
			(start 8.70077 -5.171694)
			(end 8.640572 -5.171694)
			(stroke
				(width 0.1)
				(type default)
			)
			(layer "F.SilkS")
		)
		(fp_line
			(start 8.741918 -0.882904)
			(end 8.802116 -0.882904)
			(stroke
				(width 0.1)
				(type default)
			)
			(layer "F.SilkS")
		)
		(fp_line
			(start 8.741918 -0.882904)
			(end 8.802116 -0.882904)
			(stroke
				(width 0.1)
				(type default)
			)
			(layer "F.SilkS")
		)
		(fp_line
			(start 8.741918 -0.882904)
			(end 8.989314 -1.12014)
			(stroke
				(width 0.1)
				(type default)
			)
			(layer "F.SilkS")
		)
		(fp_line
			(start 8.741918 -0.882904)
			(end 8.989314 -1.12014)
			(stroke
				(width 0.1)
				(type default)
			)
			(layer "F.SilkS")
		)
		(fp_line
			(start 8.760968 -5.171694)
			(end 8.535416 -4.955286)
			(stroke
				(width 0.1)
				(type default)
			)
			(layer "F.SilkS")
		)
		(fp_line
			(start 8.760968 -5.171694)
			(end 8.535416 -4.955286)
			(stroke
				(width 0.1)
				(type default)
			)
			(layer "F.SilkS")
		)
		(fp_line
			(start 8.760968 -5.171694)
			(end 8.70077 -5.171694)
			(stroke
				(width 0.1)
				(type default)
			)
			(layer "F.SilkS")
		)
		(fp_line
			(start 8.760968 -5.171694)
			(end 8.70077 -5.171694)
			(stroke
				(width 0.1)
				(type default)
			)
			(layer "F.SilkS")
		)
		(fp_line
			(start 8.802116 -0.882904)
			(end 8.862314 -0.882904)
			(stroke
				(width 0.1)
				(type default)
			)
			(layer "F.SilkS")
		)
		(fp_line
			(start 8.802116 -0.882904)
			(end 8.862314 -0.882904)
			(stroke
				(width 0.1)
				(type default)
			)
			(layer "F.SilkS")
		)
		(fp_line
			(start 8.802116 -0.882904)
			(end 8.977122 -1.050798)
			(stroke
				(width 0.1)
				(type default)
			)
			(layer "F.SilkS")
		)
		(fp_line
			(start 8.802116 -0.882904)
			(end 8.977122 -1.050798)
			(stroke
				(width 0.1)
				(type default)
			)
			(layer "F.SilkS")
		)
		(fp_line
			(start 8.821166 -5.171694)
			(end 8.52297 -4.88569)
			(stroke
				(width 0.1)
				(type default)
			)
			(layer "F.SilkS")
		)
		(fp_line
			(start 8.821166 -5.171694)
			(end 8.52297 -4.88569)
			(stroke
				(width 0.1)
				(type default)
			)
			(layer "F.SilkS")
		)
		(fp_line
			(start 8.821166 -5.171694)
			(end 8.760968 -5.171694)
			(stroke
				(width 0.1)
				(type default)
			)
			(layer "F.SilkS")
		)
		(fp_line
			(start 8.821166 -5.171694)
			(end 8.760968 -5.171694)
			(stroke
				(width 0.1)
				(type default)
			)
			(layer "F.SilkS")
		)
		(fp_line
			(start 8.862314 -0.882904)
			(end 8.922512 -0.882904)
			(stroke
				(width 0.1)
				(type default)
			)
			(layer "F.SilkS")
		)
		(fp_line
			(start 8.862314 -0.882904)
			(end 8.922512 -0.882904)
			(stroke
				(width 0.1)
				(type default)
			)
			(layer "F.SilkS")
		)
		(fp_line
			(start 8.862314 -0.882904)
			(end 8.965184 -0.981456)
			(stroke
				(width 0.1)
				(type default)
			)
			(layer "F.SilkS")
		)
		(fp_line
			(start 8.862314 -0.882904)
			(end 8.965184 -0.981456)
			(stroke
				(width 0.1)
				(type default)
			)
			(layer "F.SilkS")
		)
		(fp_line
			(start 8.88111 -5.171694)
			(end 8.511032 -4.816602)
			(stroke
				(width 0.1)
				(type default)
			)
			(layer "F.SilkS")
		)
		(fp_line
			(start 8.88111 -5.171694)
			(end 8.511032 -4.816602)
			(stroke
				(width 0.1)
				(type default)
			)
			(layer "F.SilkS")
		)
		(fp_line
			(start 8.88111 -5.171694)
			(end 8.821166 -5.171694)
			(stroke
				(width 0.1)
				(type default)
			)
			(layer "F.SilkS")
		)
		(fp_line
			(start 8.88111 -5.171694)
			(end 8.821166 -5.171694)
			(stroke
				(width 0.1)
				(type default)
			)
			(layer "F.SilkS")
		)
		(fp_line
			(start 8.922512 -0.882904)
			(end 8.947658 -0.882904)
			(stroke
				(width 0.1)
				(type default)
			)
			(layer "F.SilkS")
		)
		(fp_line
			(start 8.922512 -0.882904)
			(end 8.947658 -0.882904)
			(stroke
				(width 0.1)
				(type default)
			)
			(layer "F.SilkS")
		)
		(fp_line
			(start 8.922512 -0.882904)
			(end 8.952738 -0.91186)
			(stroke
				(width 0.1)
				(type default)
			)
			(layer "F.SilkS")
		)
		(fp_line
			(start 8.922512 -0.882904)
			(end 8.952738 -0.91186)
			(stroke
				(width 0.1)
				(type default)
			)
			(layer "F.SilkS")
		)
		(fp_line
			(start 8.941308 -5.171694)
			(end 8.49884 -4.74726)
			(stroke
				(width 0.1)
				(type default)
			)
			(layer "F.SilkS")
		)
		(fp_line
			(start 8.941308 -5.171694)
			(end 8.49884 -4.74726)
			(stroke
				(width 0.1)
				(type default)
			)
			(layer "F.SilkS")
		)
		(fp_line
			(start 8.941308 -5.171694)
			(end 8.88111 -5.171694)
			(stroke
				(width 0.1)
				(type default)
			)
			(layer "F.SilkS")
		)
		(fp_line
			(start 8.941308 -5.171694)
			(end 8.88111 -5.171694)
			(stroke
				(width 0.1)
				(type default)
			)
			(layer "F.SilkS")
		)
		(fp_line
			(start 8.947658 -0.882904)
			(end 8.952738 -0.91186)
			(stroke
				(width 0.1)
				(type default)
			)
			(layer "F.SilkS")
		)
		(fp_line
			(start 8.947658 -0.882904)
			(end 8.952738 -0.91186)
			(stroke
				(width 0.1)
				(type default)
			)
			(layer "F.SilkS")
		)
		(fp_line
			(start 8.965184 -0.981456)
			(end 8.952738 -0.91186)
			(stroke
				(width 0.1)
				(type default)
			)
			(layer "F.SilkS")
		)
		(fp_line
			(start 8.965184 -0.981456)
			(end 8.952738 -0.91186)
			(stroke
				(width 0.1)
				(type default)
			)
			(layer "F.SilkS")
		)
		(fp_line
			(start 8.977122 -1.050798)
			(end 8.965184 -0.981456)
			(stroke
				(width 0.1)
				(type default)
			)
			(layer "F.SilkS")
		)
		(fp_line
			(start 8.977122 -1.050798)
			(end 8.965184 -0.981456)
			(stroke
				(width 0.1)
				(type default)
			)
			(layer "F.SilkS")
		)
		(fp_line
			(start 8.989314 -1.12014)
			(end 8.977122 -1.050798)
			(stroke
				(width 0.1)
				(type default)
			)
			(layer "F.SilkS")
		)
		(fp_line
			(start 8.989314 -1.12014)
			(end 8.977122 -1.050798)
			(stroke
				(width 0.1)
				(type default)
			)
			(layer "F.SilkS")
		)
		(fp_line
			(start 9.001506 -5.171694)
			(end 8.486648 -4.677664)
			(stroke
				(width 0.1)
				(type default)
			)
			(layer "F.SilkS")
		)
		(fp_line
			(start 9.001506 -5.171694)
			(end 8.486648 -4.677664)
			(stroke
				(width 0.1)
				(type default)
			)
			(layer "F.SilkS")
		)
		(fp_line
			(start 9.001506 -5.171694)
			(end 8.941308 -5.171694)
			(stroke
				(width 0.1)
				(type default)
			)
			(layer "F.SilkS")
		)
		(fp_line
			(start 9.001506 -5.171694)
			(end 8.941308 -5.171694)
			(stroke
				(width 0.1)
				(type default)
			)
			(layer "F.SilkS")
		)
		(fp_line
			(start 9.001506 -1.189482)
			(end 8.989314 -1.12014)
			(stroke
				(width 0.1)
				(type default)
			)
			(layer "F.SilkS")
		)
		(fp_line
			(start 9.001506 -1.189482)
			(end 8.989314 -1.12014)
			(stroke
				(width 0.1)
				(type default)
			)
			(layer "F.SilkS")
		)
		(fp_line
			(start 9.013952 -1.259078)
			(end 9.001506 -1.189482)
			(stroke
				(width 0.1)
				(type default)
			)
			(layer "F.SilkS")
		)
		(fp_line
			(start 9.013952 -1.259078)
			(end 9.001506 -1.189482)
			(stroke
				(width 0.1)
				(type default)
			)
			(layer "F.SilkS")
		)
		(fp_line
			(start 9.026144 -1.32842)
			(end 9.013952 -1.259078)
			(stroke
				(width 0.1)
				(type default)
			)
			(layer "F.SilkS")
		)
		(fp_line
			(start 9.026144 -1.32842)
			(end 9.013952 -1.259078)
			(stroke
				(width 0.1)
				(type default)
			)
			(layer "F.SilkS")
		)
		(fp_line
			(start 9.038082 -1.397762)
			(end 9.026144 -1.32842)
			(stroke
				(width 0.1)
				(type default)
			)
			(layer "F.SilkS")
		)
		(fp_line
			(start 9.038082 -1.397762)
			(end 9.026144 -1.32842)
			(stroke
				(width 0.1)
				(type default)
			)
			(layer "F.SilkS")
		)
		(fp_line
			(start 9.050274 -1.467104)
			(end 9.038082 -1.397762)
			(stroke
				(width 0.1)
				(type default)
			)
			(layer "F.SilkS")
		)
		(fp_line
			(start 9.050274 -1.467104)
			(end 9.038082 -1.397762)
			(stroke
				(width 0.1)
				(type default)
			)
			(layer "F.SilkS")
		)
		(fp_line
			(start 9.061704 -5.171694)
			(end 8.474456 -4.608322)
			(stroke
				(width 0.1)
				(type default)
			)
			(layer "F.SilkS")
		)
		(fp_line
			(start 9.061704 -5.171694)
			(end 8.474456 -4.608322)
			(stroke
				(width 0.1)
				(type default)
			)
			(layer "F.SilkS")
		)
		(fp_line
			(start 9.061704 -5.171694)
			(end 9.001506 -5.171694)
			(stroke
				(width 0.1)
				(type default)
			)
			(layer "F.SilkS")
		)
		(fp_line
			(start 9.061704 -5.171694)
			(end 9.001506 -5.171694)
			(stroke
				(width 0.1)
				(type default)
			)
			(layer "F.SilkS")
		)
		(fp_line
			(start 9.062466 -1.5367)
			(end 9.050274 -1.467104)
			(stroke
				(width 0.1)
				(type default)
			)
			(layer "F.SilkS")
		)
		(fp_line
			(start 9.062466 -1.5367)
			(end 9.050274 -1.467104)
			(stroke
				(width 0.1)
				(type default)
			)
			(layer "F.SilkS")
		)
		(fp_line
			(start 9.074912 -1.606296)
			(end 9.062466 -1.5367)
			(stroke
				(width 0.1)
				(type default)
			)
			(layer "F.SilkS")
		)
		(fp_line
			(start 9.074912 -1.606296)
			(end 9.062466 -1.5367)
			(stroke
				(width 0.1)
				(type default)
			)
			(layer "F.SilkS")
		)
		(fp_line
			(start 9.087104 -1.675384)
			(end 9.074912 -1.606296)
			(stroke
				(width 0.1)
				(type default)
			)
			(layer "F.SilkS")
		)
		(fp_line
			(start 9.087104 -1.675384)
			(end 9.074912 -1.606296)
			(stroke
				(width 0.1)
				(type default)
			)
			(layer "F.SilkS")
		)
		(fp_line
			(start 9.099042 -1.744726)
			(end 9.087104 -1.675384)
			(stroke
				(width 0.1)
				(type default)
			)
			(layer "F.SilkS")
		)
		(fp_line
			(start 9.099042 -1.744726)
			(end 9.087104 -1.675384)
			(stroke
				(width 0.1)
				(type default)
			)
			(layer "F.SilkS")
		)
		(fp_line
			(start 9.111234 -1.814322)
			(end 9.099042 -1.744726)
			(stroke
				(width 0.1)
				(type default)
			)
			(layer "F.SilkS")
		)
		(fp_line
			(start 9.111234 -1.814322)
			(end 9.099042 -1.744726)
			(stroke
				(width 0.1)
				(type default)
			)
			(layer "F.SilkS")
		)
		(fp_line
			(start 9.121902 -5.171694)
			(end 8.462264 -4.53898)
			(stroke
				(width 0.1)
				(type default)
			)
			(layer "F.SilkS")
		)
		(fp_line
			(start 9.121902 -5.171694)
			(end 8.462264 -4.53898)
			(stroke
				(width 0.1)
				(type default)
			)
			(layer "F.SilkS")
		)
		(fp_line
			(start 9.121902 -5.171694)
			(end 9.061704 -5.171694)
			(stroke
				(width 0.1)
				(type default)
			)
			(layer "F.SilkS")
		)
		(fp_line
			(start 9.121902 -5.171694)
			(end 9.061704 -5.171694)
			(stroke
				(width 0.1)
				(type default)
			)
			(layer "F.SilkS")
		)
		(fp_line
			(start 9.12368 -1.883664)
			(end 9.111234 -1.814322)
			(stroke
				(width 0.1)
				(type default)
			)
			(layer "F.SilkS")
		)
		(fp_line
			(start 9.12368 -1.883664)
			(end 9.111234 -1.814322)
			(stroke
				(width 0.1)
				(type default)
			)
			(layer "F.SilkS")
		)
		(fp_line
			(start 9.135872 -1.953006)
			(end 9.12368 -1.883664)
			(stroke
				(width 0.1)
				(type default)
			)
			(layer "F.SilkS")
		)
		(fp_line
			(start 9.135872 -1.953006)
			(end 9.12368 -1.883664)
			(stroke
				(width 0.1)
				(type default)
			)
			(layer "F.SilkS")
		)
		(fp_line
			(start 9.148064 -2.022602)
			(end 9.135872 -1.953006)
			(stroke
				(width 0.1)
				(type default)
			)
			(layer "F.SilkS")
		)
		(fp_line
			(start 9.148064 -2.022602)
			(end 9.135872 -1.953006)
			(stroke
				(width 0.1)
				(type default)
			)
			(layer "F.SilkS")
		)
		(fp_line
			(start 9.160002 -2.091944)
			(end 9.148064 -2.022602)
			(stroke
				(width 0.1)
				(type default)
			)
			(layer "F.SilkS")
		)
		(fp_line
			(start 9.160002 -2.091944)
			(end 9.148064 -2.022602)
			(stroke
				(width 0.1)
				(type default)
			)
			(layer "F.SilkS")
		)
		(fp_line
			(start 9.172194 -2.161286)
			(end 9.160002 -2.091944)
			(stroke
				(width 0.1)
				(type default)
			)
			(layer "F.SilkS")
		)
		(fp_line
			(start 9.172194 -2.161286)
			(end 9.160002 -2.091944)
			(stroke
				(width 0.1)
				(type default)
			)
			(layer "F.SilkS")
		)
		(fp_line
			(start 9.172194 -2.161286)
			(end 9.18464 -2.230882)
			(stroke
				(width 0.1)
				(type default)
			)
			(layer "F.SilkS")
		)
		(fp_line
			(start 9.172194 -2.161286)
			(end 9.18464 -2.230882)
			(stroke
				(width 0.1)
				(type default)
			)
			(layer "F.SilkS")
		)
		(fp_line
			(start 9.181846 -5.171694)
			(end 8.450326 -4.469638)
			(stroke
				(width 0.1)
				(type default)
			)
			(layer "F.SilkS")
		)
		(fp_line
			(start 9.181846 -5.171694)
			(end 8.450326 -4.469638)
			(stroke
				(width 0.1)
				(type default)
			)
			(layer "F.SilkS")
		)
		(fp_line
			(start 9.181846 -5.171694)
			(end 9.121902 -5.171694)
			(stroke
				(width 0.1)
				(type default)
			)
			(layer "F.SilkS")
		)
		(fp_line
			(start 9.181846 -5.171694)
			(end 9.121902 -5.171694)
			(stroke
				(width 0.1)
				(type default)
			)
			(layer "F.SilkS")
		)
		(fp_line
			(start 9.18464 -2.230882)
			(end 9.196832 -2.300224)
			(stroke
				(width 0.1)
				(type default)
			)
			(layer "F.SilkS")
		)
		(fp_line
			(start 9.18464 -2.230882)
			(end 9.196832 -2.300224)
			(stroke
				(width 0.1)
				(type default)
			)
			(layer "F.SilkS")
		)
		(fp_line
			(start 9.196832 -2.300224)
			(end 9.209024 -2.369566)
			(stroke
				(width 0.1)
				(type default)
			)
			(layer "F.SilkS")
		)
		(fp_line
			(start 9.196832 -2.300224)
			(end 9.209024 -2.369566)
			(stroke
				(width 0.1)
				(type default)
			)
			(layer "F.SilkS")
		)
		(fp_line
			(start 9.209024 -2.369566)
			(end 9.220962 -2.438908)
			(stroke
				(width 0.1)
				(type default)
			)
			(layer "F.SilkS")
		)
		(fp_line
			(start 9.209024 -2.369566)
			(end 9.220962 -2.438908)
			(stroke
				(width 0.1)
				(type default)
			)
			(layer "F.SilkS")
		)
		(fp_line
			(start 9.220962 -2.438908)
			(end 9.233408 -2.508504)
			(stroke
				(width 0.1)
				(type default)
			)
			(layer "F.SilkS")
		)
		(fp_line
			(start 9.220962 -2.438908)
			(end 9.233408 -2.508504)
			(stroke
				(width 0.1)
				(type default)
			)
			(layer "F.SilkS")
		)
		(fp_line
			(start 9.233408 -2.508504)
			(end 9.2456 -2.577592)
			(stroke
				(width 0.1)
				(type default)
			)
			(layer "F.SilkS")
		)
		(fp_line
			(start 9.233408 -2.508504)
			(end 9.2456 -2.577592)
			(stroke
				(width 0.1)
				(type default)
			)
			(layer "F.SilkS")
		)
		(fp_line
			(start 9.242298 -5.171694)
			(end 8.43788 -4.400296)
			(stroke
				(width 0.1)
				(type default)
			)
			(layer "F.SilkS")
		)
		(fp_line
			(start 9.242298 -5.171694)
			(end 8.43788 -4.400296)
			(stroke
				(width 0.1)
				(type default)
			)
			(layer "F.SilkS")
		)
		(fp_line
			(start 9.242298 -5.171694)
			(end 9.181846 -5.171694)
			(stroke
				(width 0.1)
				(type default)
			)
			(layer "F.SilkS")
		)
		(fp_line
			(start 9.242298 -5.171694)
			(end 9.181846 -5.171694)
			(stroke
				(width 0.1)
				(type default)
			)
			(layer "F.SilkS")
		)
		(fp_line
			(start 9.2456 -2.577592)
			(end 9.257792 -2.647188)
			(stroke
				(width 0.1)
				(type default)
			)
			(layer "F.SilkS")
		)
		(fp_line
			(start 9.2456 -2.577592)
			(end 9.257792 -2.647188)
			(stroke
				(width 0.1)
				(type default)
			)
			(layer "F.SilkS")
		)
		(fp_line
			(start 9.257792 -2.647188)
			(end 9.269984 -2.716784)
			(stroke
				(width 0.1)
				(type default)
			)
			(layer "F.SilkS")
		)
		(fp_line
			(start 9.257792 -2.647188)
			(end 9.269984 -2.716784)
			(stroke
				(width 0.1)
				(type default)
			)
			(layer "F.SilkS")
		)
		(fp_line
			(start 9.269984 -2.716784)
			(end 9.281922 -2.786126)
			(stroke
				(width 0.1)
				(type default)
			)
			(layer "F.SilkS")
		)
		(fp_line
			(start 9.269984 -2.716784)
			(end 9.281922 -2.786126)
			(stroke
				(width 0.1)
				(type default)
			)
			(layer "F.SilkS")
		)
		(fp_line
			(start 9.281922 -2.786126)
			(end 9.294368 -2.855468)
			(stroke
				(width 0.1)
				(type default)
			)
			(layer "F.SilkS")
		)
		(fp_line
			(start 9.281922 -2.786126)
			(end 9.294368 -2.855468)
			(stroke
				(width 0.1)
				(type default)
			)
			(layer "F.SilkS")
		)
		(fp_line
			(start 9.294368 -2.855468)
			(end 9.30656 -2.925064)
			(stroke
				(width 0.1)
				(type default)
			)
			(layer "F.SilkS")
		)
		(fp_line
			(start 9.294368 -2.855468)
			(end 9.30656 -2.925064)
			(stroke
				(width 0.1)
				(type default)
			)
			(layer "F.SilkS")
		)
		(fp_line
			(start 9.302242 -5.171694)
			(end 8.425942 -4.3307)
			(stroke
				(width 0.1)
				(type default)
			)
			(layer "F.SilkS")
		)
		(fp_line
			(start 9.302242 -5.171694)
			(end 8.425942 -4.3307)
			(stroke
				(width 0.1)
				(type default)
			)
			(layer "F.SilkS")
		)
		(fp_line
			(start 9.302242 -5.171694)
			(end 9.242298 -5.171694)
			(stroke
				(width 0.1)
				(type default)
			)
			(layer "F.SilkS")
		)
		(fp_line
			(start 9.302242 -5.171694)
			(end 9.242298 -5.171694)
			(stroke
				(width 0.1)
				(type default)
			)
			(layer "F.SilkS")
		)
		(fp_line
			(start 9.30656 -2.925064)
			(end 9.318752 -2.994406)
			(stroke
				(width 0.1)
				(type default)
			)
			(layer "F.SilkS")
		)
		(fp_line
			(start 9.30656 -2.925064)
			(end 9.318752 -2.994406)
			(stroke
				(width 0.1)
				(type default)
			)
			(layer "F.SilkS")
		)
		(fp_line
			(start 9.318752 -2.994406)
			(end 9.330944 -3.063748)
			(stroke
				(width 0.1)
				(type default)
			)
			(layer "F.SilkS")
		)
		(fp_line
			(start 9.318752 -2.994406)
			(end 9.330944 -3.063748)
			(stroke
				(width 0.1)
				(type default)
			)
			(layer "F.SilkS")
		)
		(fp_line
			(start 9.330944 -3.063748)
			(end 9.343136 -3.13309)
			(stroke
				(width 0.1)
				(type default)
			)
			(layer "F.SilkS")
		)
		(fp_line
			(start 9.330944 -3.063748)
			(end 9.343136 -3.13309)
			(stroke
				(width 0.1)
				(type default)
			)
			(layer "F.SilkS")
		)
		(fp_line
			(start 9.343136 -3.13309)
			(end 9.355328 -3.202432)
			(stroke
				(width 0.1)
				(type default)
			)
			(layer "F.SilkS")
		)
		(fp_line
			(start 9.343136 -3.13309)
			(end 9.355328 -3.202432)
			(stroke
				(width 0.1)
				(type default)
			)
			(layer "F.SilkS")
		)
		(fp_line
			(start 9.355328 -3.202432)
			(end 9.36752 -3.272028)
			(stroke
				(width 0.1)
				(type default)
			)
			(layer "F.SilkS")
		)
		(fp_line
			(start 9.355328 -3.202432)
			(end 9.36752 -3.272028)
			(stroke
				(width 0.1)
				(type default)
			)
			(layer "F.SilkS")
		)
		(fp_line
			(start 9.36244 -5.171694)
			(end 8.41375 -4.261612)
			(stroke
				(width 0.1)
				(type default)
			)
			(layer "F.SilkS")
		)
		(fp_line
			(start 9.36244 -5.171694)
			(end 8.41375 -4.261612)
			(stroke
				(width 0.1)
				(type default)
			)
			(layer "F.SilkS")
		)
		(fp_line
			(start 9.36244 -5.171694)
			(end 9.302242 -5.171694)
			(stroke
				(width 0.1)
				(type default)
			)
			(layer "F.SilkS")
		)
		(fp_line
			(start 9.36244 -5.171694)
			(end 9.302242 -5.171694)
			(stroke
				(width 0.1)
				(type default)
			)
			(layer "F.SilkS")
		)
		(fp_line
			(start 9.36752 -3.272028)
			(end 9.379712 -3.34137)
			(stroke
				(width 0.1)
				(type default)
			)
			(layer "F.SilkS")
		)
		(fp_line
			(start 9.36752 -3.272028)
			(end 9.379712 -3.34137)
			(stroke
				(width 0.1)
				(type default)
			)
			(layer "F.SilkS")
		)
		(fp_line
			(start 9.379712 -3.34137)
			(end 9.391904 -3.410712)
			(stroke
				(width 0.1)
				(type default)
			)
			(layer "F.SilkS")
		)
		(fp_line
			(start 9.379712 -3.34137)
			(end 9.391904 -3.410712)
			(stroke
				(width 0.1)
				(type default)
			)
			(layer "F.SilkS")
		)
		(fp_line
			(start 9.404096 -3.480054)
			(end 9.391904 -3.410712)
			(stroke
				(width 0.1)
				(type default)
			)
			(layer "F.SilkS")
		)
		(fp_line
			(start 9.404096 -3.480054)
			(end 9.391904 -3.410712)
			(stroke
				(width 0.1)
				(type default)
			)
			(layer "F.SilkS")
		)
		(fp_line
			(start 9.416288 -3.54965)
			(end 6.565392 -0.815086)
			(stroke
				(width 0.1)
				(type default)
			)
			(layer "F.SilkS")
		)
		(fp_line
			(start 9.416288 -3.54965)
			(end 6.565392 -0.815086)
			(stroke
				(width 0.1)
				(type default)
			)
			(layer "F.SilkS")
		)
		(fp_line
			(start 9.416288 -3.54965)
			(end 9.404096 -3.480054)
			(stroke
				(width 0.1)
				(type default)
			)
			(layer "F.SilkS")
		)
		(fp_line
			(start 9.416288 -3.54965)
			(end 9.404096 -3.480054)
			(stroke
				(width 0.1)
				(type default)
			)
			(layer "F.SilkS")
		)
		(fp_line
			(start 9.416288 -3.54965)
			(end 9.42848 -3.618992)
			(stroke
				(width 0.1)
				(type default)
			)
			(layer "F.SilkS")
		)
		(fp_line
			(start 9.416288 -3.54965)
			(end 9.42848 -3.618992)
			(stroke
				(width 0.1)
				(type default)
			)
			(layer "F.SilkS")
		)
		(fp_line
			(start 9.422638 -5.171694)
			(end 8.401558 -4.19227)
			(stroke
				(width 0.1)
				(type default)
			)
			(layer "F.SilkS")
		)
		(fp_line
			(start 9.422638 -5.171694)
			(end 8.401558 -4.19227)
			(stroke
				(width 0.1)
				(type default)
			)
			(layer "F.SilkS")
		)
		(fp_line
			(start 9.422638 -5.171694)
			(end 9.36244 -5.171694)
			(stroke
				(width 0.1)
				(type default)
			)
			(layer "F.SilkS")
		)
		(fp_line
			(start 9.422638 -5.171694)
			(end 9.36244 -5.171694)
			(stroke
				(width 0.1)
				(type default)
			)
			(layer "F.SilkS")
		)
		(fp_line
			(start 9.42848 -3.618992)
			(end 9.440672 -3.688334)
			(stroke
				(width 0.1)
				(type default)
			)
			(layer "F.SilkS")
		)
		(fp_line
			(start 9.42848 -3.618992)
			(end 9.440672 -3.688334)
			(stroke
				(width 0.1)
				(type default)
			)
			(layer "F.SilkS")
		)
		(fp_line
			(start 9.440672 -3.688334)
			(end 9.452864 -3.75793)
			(stroke
				(width 0.1)
				(type default)
			)
			(layer "F.SilkS")
		)
		(fp_line
			(start 9.440672 -3.688334)
			(end 9.452864 -3.75793)
			(stroke
				(width 0.1)
				(type default)
			)
			(layer "F.SilkS")
		)
		(fp_line
			(start 9.465056 -3.827526)
			(end 9.452864 -3.75793)
			(stroke
				(width 0.1)
				(type default)
			)
			(layer "F.SilkS")
		)
		(fp_line
			(start 9.465056 -3.827526)
			(end 9.452864 -3.75793)
			(stroke
				(width 0.1)
				(type default)
			)
			(layer "F.SilkS")
		)
		(fp_line
			(start 9.465056 -3.827526)
			(end 9.477248 -3.896614)
			(stroke
				(width 0.1)
				(type default)
			)
			(layer "F.SilkS")
		)
		(fp_line
			(start 9.465056 -3.827526)
			(end 9.477248 -3.896614)
			(stroke
				(width 0.1)
				(type default)
			)
			(layer "F.SilkS")
		)
		(fp_line
			(start 9.477248 -3.896614)
			(end 8.107172 -2.582418)
			(stroke
				(width 0.1)
				(type default)
			)
			(layer "F.SilkS")
		)
		(fp_line
			(start 9.477248 -3.896614)
			(end 8.107172 -2.582418)
			(stroke
				(width 0.1)
				(type default)
			)
			(layer "F.SilkS")
		)
		(fp_line
			(start 9.477248 -3.896614)
			(end 9.48944 -3.965956)
			(stroke
				(width 0.1)
				(type default)
			)
			(layer "F.SilkS")
		)
		(fp_line
			(start 9.477248 -3.896614)
			(end 9.48944 -3.965956)
			(stroke
				(width 0.1)
				(type default)
			)
			(layer "F.SilkS")
		)
		(fp_line
			(start 9.482836 -5.171694)
			(end 8.389366 -4.122674)
			(stroke
				(width 0.1)
				(type default)
			)
			(layer "F.SilkS")
		)
		(fp_line
			(start 9.482836 -5.171694)
			(end 8.389366 -4.122674)
			(stroke
				(width 0.1)
				(type default)
			)
			(layer "F.SilkS")
		)
		(fp_line
			(start 9.482836 -5.171694)
			(end 9.422638 -5.171694)
			(stroke
				(width 0.1)
				(type default)
			)
			(layer "F.SilkS")
		)
		(fp_line
			(start 9.482836 -5.171694)
			(end 9.422638 -5.171694)
			(stroke
				(width 0.1)
				(type default)
			)
			(layer "F.SilkS")
		)
		(fp_line
			(start 9.48944 -3.965956)
			(end 8.123682 -2.655824)
			(stroke
				(width 0.1)
				(type default)
			)
			(layer "F.SilkS")
		)
		(fp_line
			(start 9.48944 -3.965956)
			(end 8.123682 -2.655824)
			(stroke
				(width 0.1)
				(type default)
			)
			(layer "F.SilkS")
		)
		(fp_line
			(start 9.48944 -3.965956)
			(end 9.501632 -4.035552)
			(stroke
				(width 0.1)
				(type default)
			)
			(layer "F.SilkS")
		)
		(fp_line
			(start 9.48944 -3.965956)
			(end 9.501632 -4.035552)
			(stroke
				(width 0.1)
				(type default)
			)
			(layer "F.SilkS")
		)
		(fp_line
			(start 9.501632 -4.035552)
			(end 8.140446 -2.729738)
			(stroke
				(width 0.1)
				(type default)
			)
			(layer "F.SilkS")
		)
		(fp_line
			(start 9.501632 -4.035552)
			(end 8.140446 -2.729738)
			(stroke
				(width 0.1)
				(type default)
			)
			(layer "F.SilkS")
		)
		(fp_line
			(start 9.501632 -4.035552)
			(end 9.513824 -4.104894)
			(stroke
				(width 0.1)
				(type default)
			)
			(layer "F.SilkS")
		)
		(fp_line
			(start 9.501632 -4.035552)
			(end 9.513824 -4.104894)
			(stroke
				(width 0.1)
				(type default)
			)
			(layer "F.SilkS")
		)
		(fp_line
			(start 9.513824 -4.104894)
			(end 8.156956 -2.803398)
			(stroke
				(width 0.1)
				(type default)
			)
			(layer "F.SilkS")
		)
		(fp_line
			(start 9.513824 -4.104894)
			(end 8.156956 -2.803398)
			(stroke
				(width 0.1)
				(type default)
			)
			(layer "F.SilkS")
		)
		(fp_line
			(start 9.513824 -4.104894)
			(end 9.526016 -4.174236)
			(stroke
				(width 0.1)
				(type default)
			)
			(layer "F.SilkS")
		)
		(fp_line
			(start 9.513824 -4.104894)
			(end 9.526016 -4.174236)
			(stroke
				(width 0.1)
				(type default)
			)
			(layer "F.SilkS")
		)
		(fp_line
			(start 9.526016 -4.174236)
			(end 8.170418 -2.87401)
			(stroke
				(width 0.1)
				(type default)
			)
			(layer "F.SilkS")
		)
		(fp_line
			(start 9.526016 -4.174236)
			(end 8.170418 -2.87401)
			(stroke
				(width 0.1)
				(type default)
			)
			(layer "F.SilkS")
		)
		(fp_line
			(start 9.526016 -4.174236)
			(end 9.538208 -4.243578)
			(stroke
				(width 0.1)
				(type default)
			)
			(layer "F.SilkS")
		)
		(fp_line
			(start 9.526016 -4.174236)
			(end 9.538208 -4.243578)
			(stroke
				(width 0.1)
				(type default)
			)
			(layer "F.SilkS")
		)
		(fp_line
			(start 9.538208 -4.243578)
			(end 8.18261 -2.943352)
			(stroke
				(width 0.1)
				(type default)
			)
			(layer "F.SilkS")
		)
		(fp_line
			(start 9.538208 -4.243578)
			(end 8.18261 -2.943352)
			(stroke
				(width 0.1)
				(type default)
			)
			(layer "F.SilkS")
		)
		(fp_line
			(start 9.538208 -4.243578)
			(end 9.5504 -4.313174)
			(stroke
				(width 0.1)
				(type default)
			)
			(layer "F.SilkS")
		)
		(fp_line
			(start 9.538208 -4.243578)
			(end 9.5504 -4.313174)
			(stroke
				(width 0.1)
				(type default)
			)
			(layer "F.SilkS")
		)
		(fp_line
			(start 9.543034 -5.171694)
			(end 8.377174 -4.053332)
			(stroke
				(width 0.1)
				(type default)
			)
			(layer "F.SilkS")
		)
		(fp_line
			(start 9.543034 -5.171694)
			(end 8.377174 -4.053332)
			(stroke
				(width 0.1)
				(type default)
			)
			(layer "F.SilkS")
		)
		(fp_line
			(start 9.543034 -5.171694)
			(end 9.482836 -5.171694)
			(stroke
				(width 0.1)
				(type default)
			)
			(layer "F.SilkS")
		)
		(fp_line
			(start 9.543034 -5.171694)
			(end 9.482836 -5.171694)
			(stroke
				(width 0.1)
				(type default)
			)
			(layer "F.SilkS")
		)
		(fp_line
			(start 9.5504 -4.313174)
			(end 8.194802 -3.012694)
			(stroke
				(width 0.1)
				(type default)
			)
			(layer "F.SilkS")
		)
		(fp_line
			(start 9.5504 -4.313174)
			(end 8.194802 -3.012694)
			(stroke
				(width 0.1)
				(type default)
			)
			(layer "F.SilkS")
		)
		(fp_line
			(start 9.5504 -4.313174)
			(end 9.562592 -4.382516)
			(stroke
				(width 0.1)
				(type default)
			)
			(layer "F.SilkS")
		)
		(fp_line
			(start 9.5504 -4.313174)
			(end 9.562592 -4.382516)
			(stroke
				(width 0.1)
				(type default)
			)
			(layer "F.SilkS")
		)
		(fp_line
			(start 9.562592 -4.382516)
			(end 8.206994 -3.08229)
			(stroke
				(width 0.1)
				(type default)
			)
			(layer "F.SilkS")
		)
		(fp_line
			(start 9.562592 -4.382516)
			(end 8.206994 -3.08229)
			(stroke
				(width 0.1)
				(type default)
			)
			(layer "F.SilkS")
		)
		(fp_line
			(start 9.562592 -4.382516)
			(end 9.574784 -4.452112)
			(stroke
				(width 0.1)
				(type default)
			)
			(layer "F.SilkS")
		)
		(fp_line
			(start 9.562592 -4.382516)
			(end 9.574784 -4.452112)
			(stroke
				(width 0.1)
				(type default)
			)
			(layer "F.SilkS")
		)
		(fp_line
			(start 9.574784 -4.452112)
			(end 8.219186 -3.151378)
			(stroke
				(width 0.1)
				(type default)
			)
			(layer "F.SilkS")
		)
		(fp_line
			(start 9.574784 -4.452112)
			(end 8.219186 -3.151378)
			(stroke
				(width 0.1)
				(type default)
			)
			(layer "F.SilkS")
		)
		(fp_line
			(start 9.574784 -4.452112)
			(end 9.586976 -4.5212)
			(stroke
				(width 0.1)
				(type default)
			)
			(layer "F.SilkS")
		)
		(fp_line
			(start 9.574784 -4.452112)
			(end 9.586976 -4.5212)
			(stroke
				(width 0.1)
				(type default)
			)
			(layer "F.SilkS")
		)
		(fp_line
			(start 9.586976 -4.5212)
			(end 8.231378 -3.22072)
			(stroke
				(width 0.1)
				(type default)
			)
			(layer "F.SilkS")
		)
		(fp_line
			(start 9.586976 -4.5212)
			(end 8.231378 -3.22072)
			(stroke
				(width 0.1)
				(type default)
			)
			(layer "F.SilkS")
		)
		(fp_line
			(start 9.586976 -4.5212)
			(end 9.599168 -4.590796)
			(stroke
				(width 0.1)
				(type default)
			)
			(layer "F.SilkS")
		)
		(fp_line
			(start 9.586976 -4.5212)
			(end 9.599168 -4.590796)
			(stroke
				(width 0.1)
				(type default)
			)
			(layer "F.SilkS")
		)
		(fp_line
			(start 9.599168 -4.590796)
			(end 8.24357 -3.290316)
			(stroke
				(width 0.1)
				(type default)
			)
			(layer "F.SilkS")
		)
		(fp_line
			(start 9.599168 -4.590796)
			(end 8.24357 -3.290316)
			(stroke
				(width 0.1)
				(type default)
			)
			(layer "F.SilkS")
		)
		(fp_line
			(start 9.599168 -4.590796)
			(end 9.61136 -4.660138)
			(stroke
				(width 0.1)
				(type default)
			)
			(layer "F.SilkS")
		)
		(fp_line
			(start 9.599168 -4.590796)
			(end 9.61136 -4.660138)
			(stroke
				(width 0.1)
				(type default)
			)
			(layer "F.SilkS")
		)
		(fp_line
			(start 9.603232 -5.171694)
			(end 8.365236 -3.98399)
			(stroke
				(width 0.1)
				(type default)
			)
			(layer "F.SilkS")
		)
		(fp_line
			(start 9.603232 -5.171694)
			(end 8.365236 -3.98399)
			(stroke
				(width 0.1)
				(type default)
			)
			(layer "F.SilkS")
		)
		(fp_line
			(start 9.603232 -5.171694)
			(end 9.543034 -5.171694)
			(stroke
				(width 0.1)
				(type default)
			)
			(layer "F.SilkS")
		)
		(fp_line
			(start 9.603232 -5.171694)
			(end 9.543034 -5.171694)
			(stroke
				(width 0.1)
				(type default)
			)
			(layer "F.SilkS")
		)
		(fp_line
			(start 9.61136 -4.660138)
			(end 8.255762 -3.359658)
			(stroke
				(width 0.1)
				(type default)
			)
			(layer "F.SilkS")
		)
		(fp_line
			(start 9.61136 -4.660138)
			(end 8.255762 -3.359658)
			(stroke
				(width 0.1)
				(type default)
			)
			(layer "F.SilkS")
		)
		(fp_line
			(start 9.61136 -4.660138)
			(end 9.623552 -4.729734)
			(stroke
				(width 0.1)
				(type default)
			)
			(layer "F.SilkS")
		)
		(fp_line
			(start 9.61136 -4.660138)
			(end 9.623552 -4.729734)
			(stroke
				(width 0.1)
				(type default)
			)
			(layer "F.SilkS")
		)
		(fp_line
			(start 9.623552 -4.729734)
			(end 8.2677 -3.429)
			(stroke
				(width 0.1)
				(type default)
			)
			(layer "F.SilkS")
		)
		(fp_line
			(start 9.623552 -4.729734)
			(end 8.2677 -3.429)
			(stroke
				(width 0.1)
				(type default)
			)
			(layer "F.SilkS")
		)
		(fp_line
			(start 9.623552 -4.729734)
			(end 9.635744 -4.798822)
			(stroke
				(width 0.1)
				(type default)
			)
			(layer "F.SilkS")
		)
		(fp_line
			(start 9.623552 -4.729734)
			(end 9.635744 -4.798822)
			(stroke
				(width 0.1)
				(type default)
			)
			(layer "F.SilkS")
		)
		(fp_line
			(start 9.635744 -4.798822)
			(end 8.279892 -3.498342)
			(stroke
				(width 0.1)
				(type default)
			)
			(layer "F.SilkS")
		)
		(fp_line
			(start 9.635744 -4.798822)
			(end 8.279892 -3.498342)
			(stroke
				(width 0.1)
				(type default)
			)
			(layer "F.SilkS")
		)
		(fp_line
			(start 9.635744 -4.798822)
			(end 9.64819 -4.868418)
			(stroke
				(width 0.1)
				(type default)
			)
			(layer "F.SilkS")
		)
		(fp_line
			(start 9.635744 -4.798822)
			(end 9.64819 -4.868418)
			(stroke
				(width 0.1)
				(type default)
			)
			(layer "F.SilkS")
		)
		(fp_line
			(start 9.64819 -4.868418)
			(end 8.292084 -3.567684)
			(stroke
				(width 0.1)
				(type default)
			)
			(layer "F.SilkS")
		)
		(fp_line
			(start 9.64819 -4.868418)
			(end 8.292084 -3.567684)
			(stroke
				(width 0.1)
				(type default)
			)
			(layer "F.SilkS")
		)
		(fp_line
			(start 9.64819 -4.868418)
			(end 9.660382 -4.938014)
			(stroke
				(width 0.1)
				(type default)
			)
			(layer "F.SilkS")
		)
		(fp_line
			(start 9.64819 -4.868418)
			(end 9.660382 -4.938014)
			(stroke
				(width 0.1)
				(type default)
			)
			(layer "F.SilkS")
		)
		(fp_line
			(start 9.660382 -4.938014)
			(end 8.304276 -3.63728)
			(stroke
				(width 0.1)
				(type default)
			)
			(layer "F.SilkS")
		)
		(fp_line
			(start 9.660382 -4.938014)
			(end 8.304276 -3.63728)
			(stroke
				(width 0.1)
				(type default)
			)
			(layer "F.SilkS")
		)
		(fp_line
			(start 9.660382 -4.938014)
			(end 9.67232 -5.007356)
			(stroke
				(width 0.1)
				(type default)
			)
			(layer "F.SilkS")
		)
		(fp_line
			(start 9.660382 -4.938014)
			(end 9.67232 -5.007356)
			(stroke
				(width 0.1)
				(type default)
			)
			(layer "F.SilkS")
		)
		(fp_line
			(start 9.663176 -5.171694)
			(end 8.35279 -3.914648)
			(stroke
				(width 0.1)
				(type default)
			)
			(layer "F.SilkS")
		)
		(fp_line
			(start 9.663176 -5.171694)
			(end 8.35279 -3.914648)
			(stroke
				(width 0.1)
				(type default)
			)
			(layer "F.SilkS")
		)
		(fp_line
			(start 9.663176 -5.171694)
			(end 9.603232 -5.171694)
			(stroke
				(width 0.1)
				(type default)
			)
			(layer "F.SilkS")
		)
		(fp_line
			(start 9.663176 -5.171694)
			(end 9.603232 -5.171694)
			(stroke
				(width 0.1)
				(type default)
			)
			(layer "F.SilkS")
		)
		(fp_line
			(start 9.67232 -5.007356)
			(end 8.316468 -3.706368)
			(stroke
				(width 0.1)
				(type default)
			)
			(layer "F.SilkS")
		)
		(fp_line
			(start 9.67232 -5.007356)
			(end 8.316468 -3.706368)
			(stroke
				(width 0.1)
				(type default)
			)
			(layer "F.SilkS")
		)
		(fp_line
			(start 9.67232 -5.007356)
			(end 9.684512 -5.076698)
			(stroke
				(width 0.1)
				(type default)
			)
			(layer "F.SilkS")
		)
		(fp_line
			(start 9.67232 -5.007356)
			(end 9.684512 -5.076698)
			(stroke
				(width 0.1)
				(type default)
			)
			(layer "F.SilkS")
		)
		(fp_line
			(start 9.684512 -5.076698)
			(end 8.32866 -3.77571)
			(stroke
				(width 0.1)
				(type default)
			)
			(layer "F.SilkS")
		)
		(fp_line
			(start 9.684512 -5.076698)
			(end 8.32866 -3.77571)
			(stroke
				(width 0.1)
				(type default)
			)
			(layer "F.SilkS")
		)
		(fp_line
			(start 9.684512 -5.076698)
			(end 9.696704 -5.14604)
			(stroke
				(width 0.1)
				(type default)
			)
			(layer "F.SilkS")
		)
		(fp_line
			(start 9.684512 -5.076698)
			(end 9.696704 -5.14604)
			(stroke
				(width 0.1)
				(type default)
			)
			(layer "F.SilkS")
		)
		(fp_line
			(start 9.696704 -5.14604)
			(end 8.340852 -3.845306)
			(stroke
				(width 0.1)
				(type default)
			)
			(layer "F.SilkS")
		)
		(fp_line
			(start 9.696704 -5.14604)
			(end 8.340852 -3.845306)
			(stroke
				(width 0.1)
				(type default)
			)
			(layer "F.SilkS")
		)
		(fp_line
			(start 9.696704 -5.14604)
			(end 9.701276 -5.171694)
			(stroke
				(width 0.1)
				(type default)
			)
			(layer "F.SilkS")
		)
		(fp_line
			(start 9.696704 -5.14604)
			(end 9.701276 -5.171694)
			(stroke
				(width 0.1)
				(type default)
			)
			(layer "F.SilkS")
		)
		(fp_line
			(start 9.701276 -5.171694)
			(end 9.663176 -5.171694)
			(stroke
				(width 0.1)
				(type default)
			)
			(layer "F.SilkS")
		)
		(fp_line
			(start 9.701276 -5.171694)
			(end 9.663176 -5.171694)
			(stroke
				(width 0.1)
				(type default)
			)
			(layer "F.SilkS")
		)
		(fp_line
			(start 9.754616 -1.96977)
			(end 11.590528 -3.730752)
			(stroke
				(width 0.1)
				(type default)
			)
			(layer "F.SilkS")
		)
		(fp_line
			(start 9.754616 -1.96977)
			(end 11.590528 -3.730752)
			(stroke
				(width 0.1)
				(type default)
			)
			(layer "F.SilkS")
		)
		(fp_line
			(start 9.75614 -2.028698)
			(end 11.526012 -3.726688)
			(stroke
				(width 0.1)
				(type default)
			)
			(layer "F.SilkS")
		)
		(fp_line
			(start 9.75614 -2.028698)
			(end 11.526012 -3.726688)
			(stroke
				(width 0.1)
				(type default)
			)
			(layer "F.SilkS")
		)
		(fp_line
			(start 9.75741 -2.08788)
			(end 11.46175 -3.722878)
			(stroke
				(width 0.1)
				(type default)
			)
			(layer "F.SilkS")
		)
		(fp_line
			(start 9.75741 -2.08788)
			(end 11.46175 -3.722878)
			(stroke
				(width 0.1)
				(type default)
			)
			(layer "F.SilkS")
		)
		(fp_line
			(start 9.758172 -1.915414)
			(end 11.65479 -3.734816)
			(stroke
				(width 0.1)
				(type default)
			)
			(layer "F.SilkS")
		)
		(fp_line
			(start 9.758172 -1.915414)
			(end 11.65479 -3.734816)
			(stroke
				(width 0.1)
				(type default)
			)
			(layer "F.SilkS")
		)
		(fp_line
			(start 9.760458 -2.148332)
			(end 11.394694 -3.71602)
			(stroke
				(width 0.1)
				(type default)
			)
			(layer "F.SilkS")
		)
		(fp_line
			(start 9.760458 -2.148332)
			(end 11.394694 -3.71602)
			(stroke
				(width 0.1)
				(type default)
			)
			(layer "F.SilkS")
		)
		(fp_line
			(start 9.762998 -1.862074)
			(end 11.719052 -3.738626)
			(stroke
				(width 0.1)
				(type default)
			)
			(layer "F.SilkS")
		)
		(fp_line
			(start 9.762998 -1.862074)
			(end 11.719052 -3.738626)
			(stroke
				(width 0.1)
				(type default)
			)
			(layer "F.SilkS")
		)
		(fp_line
			(start 9.76757 -1.808988)
			(end 11.782044 -3.74142)
			(stroke
				(width 0.1)
				(type default)
			)
			(layer "F.SilkS")
		)
		(fp_line
			(start 9.76757 -1.808988)
			(end 11.782044 -3.74142)
			(stroke
				(width 0.1)
				(type default)
			)
			(layer "F.SilkS")
		)
		(fp_line
			(start 9.768586 -2.214118)
			(end 11.319002 -3.701288)
			(stroke
				(width 0.1)
				(type default)
			)
			(layer "F.SilkS")
		)
		(fp_line
			(start 9.768586 -2.214118)
			(end 11.319002 -3.701288)
			(stroke
				(width 0.1)
				(type default)
			)
			(layer "F.SilkS")
		)
		(fp_line
			(start 9.77646 -1.759712)
			(end 11.83894 -3.738372)
			(stroke
				(width 0.1)
				(type default)
			)
			(layer "F.SilkS")
		)
		(fp_line
			(start 9.77646 -1.759712)
			(end 11.83894 -3.738372)
			(stroke
				(width 0.1)
				(type default)
			)
			(layer "F.SilkS")
		)
		(fp_line
			(start 9.777222 -2.279904)
			(end 11.24331 -3.686556)
			(stroke
				(width 0.1)
				(type default)
			)
			(layer "F.SilkS")
		)
		(fp_line
			(start 9.777222 -2.279904)
			(end 11.24331 -3.686556)
			(stroke
				(width 0.1)
				(type default)
			)
			(layer "F.SilkS")
		)
		(fp_line
			(start 9.78662 -1.711706)
			(end 11.89609 -3.735324)
			(stroke
				(width 0.1)
				(type default)
			)
			(layer "F.SilkS")
		)
		(fp_line
			(start 9.78662 -1.711706)
			(end 11.89609 -3.735324)
			(stroke
				(width 0.1)
				(type default)
			)
			(layer "F.SilkS")
		)
		(fp_line
			(start 9.79043 -2.350262)
			(end 11.167872 -3.67157)
			(stroke
				(width 0.1)
				(type default)
			)
			(layer "F.SilkS")
		)
		(fp_line
			(start 9.79043 -2.350262)
			(end 11.167872 -3.67157)
			(stroke
				(width 0.1)
				(type default)
			)
			(layer "F.SilkS")
		)
		(fp_line
			(start 9.797034 -1.663954)
			(end 11.952986 -3.732276)
			(stroke
				(width 0.1)
				(type default)
			)
			(layer "F.SilkS")
		)
		(fp_line
			(start 9.797034 -1.663954)
			(end 11.952986 -3.732276)
			(stroke
				(width 0.1)
				(type default)
			)
			(layer "F.SilkS")
		)
		(fp_line
			(start 9.809988 -1.618742)
			(end 12.010136 -3.729482)
			(stroke
				(width 0.1)
				(type default)
			)
			(layer "F.SilkS")
		)
		(fp_line
			(start 9.809988 -1.618742)
			(end 12.010136 -3.729482)
			(stroke
				(width 0.1)
				(type default)
			)
			(layer "F.SilkS")
		)
		(fp_line
			(start 9.812528 -2.429256)
			(end 11.09218 -3.656838)
			(stroke
				(width 0.1)
				(type default)
			)
			(layer "F.SilkS")
		)
		(fp_line
			(start 9.812528 -2.429256)
			(end 11.09218 -3.656838)
			(stroke
				(width 0.1)
				(type default)
			)
			(layer "F.SilkS")
		)
		(fp_line
			(start 9.825228 -1.575562)
			(end 12.063984 -3.723132)
			(stroke
				(width 0.1)
				(type default)
			)
			(layer "F.SilkS")
		)
		(fp_line
			(start 9.825228 -1.575562)
			(end 12.063984 -3.723132)
			(stroke
				(width 0.1)
				(type default)
			)
			(layer "F.SilkS")
		)
		(fp_line
			(start 9.834626 -2.507996)
			(end 11.00201 -3.627882)
			(stroke
				(width 0.1)
				(type default)
			)
			(layer "F.SilkS")
		)
		(fp_line
			(start 9.834626 -2.507996)
			(end 11.00201 -3.627882)
			(stroke
				(width 0.1)
				(type default)
			)
			(layer "F.SilkS")
		)
		(fp_line
			(start 9.840214 -1.532382)
			(end 12.115038 -3.714496)
			(stroke
				(width 0.1)
				(type default)
			)
			(layer "F.SilkS")
		)
		(fp_line
			(start 9.840214 -1.532382)
			(end 12.115038 -3.714496)
			(stroke
				(width 0.1)
				(type default)
			)
			(layer "F.SilkS")
		)
		(fp_line
			(start 9.856978 -2.587244)
			(end 10.90676 -3.594354)
			(stroke
				(width 0.1)
				(type default)
			)
			(layer "F.SilkS")
		)
		(fp_line
			(start 9.856978 -2.587244)
			(end 10.90676 -3.594354)
			(stroke
				(width 0.1)
				(type default)
			)
			(layer "F.SilkS")
		)
		(fp_line
			(start 9.857232 -1.49098)
			(end 12.165838 -3.705352)
			(stroke
				(width 0.1)
				(type default)
			)
			(layer "F.SilkS")
		)
		(fp_line
			(start 9.857232 -1.49098)
			(end 12.165838 -3.705352)
			(stroke
				(width 0.1)
				(type default)
			)
			(layer "F.SilkS")
		)
		(fp_line
			(start 9.87679 -1.452118)
			(end 10.97661 -2.50698)
			(stroke
				(width 0.1)
				(type default)
			)
			(layer "F.SilkS")
		)
		(fp_line
			(start 9.87679 -1.452118)
			(end 10.97661 -2.50698)
			(stroke
				(width 0.1)
				(type default)
			)
			(layer "F.SilkS")
		)
		(fp_line
			(start 9.884664 -2.671572)
			(end 10.811764 -3.560826)
			(stroke
				(width 0.1)
				(type default)
			)
			(layer "F.SilkS")
		)
		(fp_line
			(start 9.884664 -2.671572)
			(end 10.811764 -3.560826)
			(stroke
				(width 0.1)
				(type default)
			)
			(layer "F.SilkS")
		)
		(fp_line
			(start 9.896602 -1.413256)
			(end 10.944606 -2.418588)
			(stroke
				(width 0.1)
				(type default)
			)
			(layer "F.SilkS")
		)
		(fp_line
			(start 9.896602 -1.413256)
			(end 10.944606 -2.418588)
			(stroke
				(width 0.1)
				(type default)
			)
			(layer "F.SilkS")
		)
		(fp_line
			(start 9.916922 -1.375156)
			(end 10.912856 -2.33045)
			(stroke
				(width 0.1)
				(type default)
			)
			(layer "F.SilkS")
		)
		(fp_line
			(start 9.916922 -1.375156)
			(end 10.912856 -2.33045)
			(stroke
				(width 0.1)
				(type default)
			)
			(layer "F.SilkS")
		)
		(fp_line
			(start 9.940798 -1.340358)
			(end 10.903712 -2.263902)
			(stroke
				(width 0.1)
				(type default)
			)
			(layer "F.SilkS")
		)
		(fp_line
			(start 9.940798 -1.340358)
			(end 10.903712 -2.263902)
			(stroke
				(width 0.1)
				(type default)
			)
			(layer "F.SilkS")
		)
		(fp_line
			(start 9.945116 -2.787142)
			(end 10.69721 -3.508502)
			(stroke
				(width 0.1)
				(type default)
			)
			(layer "F.SilkS")
		)
		(fp_line
			(start 9.945116 -2.787142)
			(end 10.69721 -3.508502)
			(stroke
				(width 0.1)
				(type default)
			)
			(layer "F.SilkS")
		)
		(fp_line
			(start 9.964674 -1.30556)
			(end 10.898632 -2.201418)
			(stroke
				(width 0.1)
				(type default)
			)
			(layer "F.SilkS")
		)
		(fp_line
			(start 9.964674 -1.30556)
			(end 10.898632 -2.201418)
			(stroke
				(width 0.1)
				(type default)
			)
			(layer "F.SilkS")
		)
		(fp_line
			(start 9.98855 -1.270508)
			(end 10.902442 -2.147316)
			(stroke
				(width 0.1)
				(type default)
			)
			(layer "F.SilkS")
		)
		(fp_line
			(start 9.98855 -1.270508)
			(end 10.902442 -2.147316)
			(stroke
				(width 0.1)
				(type default)
			)
			(layer "F.SilkS")
		)
		(fp_line
			(start 10.005568 -2.902966)
			(end 10.557002 -3.431794)
			(stroke
				(width 0.1)
				(type default)
			)
			(layer "F.SilkS")
		)
		(fp_line
			(start 10.005568 -2.902966)
			(end 10.557002 -3.431794)
			(stroke
				(width 0.1)
				(type default)
			)
			(layer "F.SilkS")
		)
		(fp_line
			(start 10.015982 -1.239266)
			(end 10.90803 -2.094992)
			(stroke
				(width 0.1)
				(type default)
			)
			(layer "F.SilkS")
		)
		(fp_line
			(start 10.015982 -1.239266)
			(end 10.90803 -2.094992)
			(stroke
				(width 0.1)
				(type default)
			)
			(layer "F.SilkS")
		)
		(fp_line
			(start 10.043668 -1.208278)
			(end 10.921238 -2.04978)
			(stroke
				(width 0.1)
				(type default)
			)
			(layer "F.SilkS")
		)
		(fp_line
			(start 10.043668 -1.208278)
			(end 10.921238 -2.04978)
			(stroke
				(width 0.1)
				(type default)
			)
			(layer "F.SilkS")
		)
		(fp_line
			(start 10.071608 -1.17729)
			(end 10.9347 -2.00533)
			(stroke
				(width 0.1)
				(type default)
			)
			(layer "F.SilkS")
		)
		(fp_line
			(start 10.071608 -1.17729)
			(end 10.9347 -2.00533)
			(stroke
				(width 0.1)
				(type default)
			)
			(layer "F.SilkS")
		)
		(fp_line
			(start 10.102088 -1.148588)
			(end 10.956798 -1.9685)
			(stroke
				(width 0.1)
				(type default)
			)
			(layer "F.SilkS")
		)
		(fp_line
			(start 10.102088 -1.148588)
			(end 10.956798 -1.9685)
			(stroke
				(width 0.1)
				(type default)
			)
			(layer "F.SilkS")
		)
		(fp_line
			(start 10.133584 -1.121156)
			(end 10.978642 -1.931924)
			(stroke
				(width 0.1)
				(type default)
			)
			(layer "F.SilkS")
		)
		(fp_line
			(start 10.133584 -1.121156)
			(end 10.978642 -1.931924)
			(stroke
				(width 0.1)
				(type default)
			)
			(layer "F.SilkS")
		)
		(fp_line
			(start 10.16508 -1.093724)
			(end 11.006582 -1.90119)
			(stroke
				(width 0.1)
				(type default)
			)
			(layer "F.SilkS")
		)
		(fp_line
			(start 10.16508 -1.093724)
			(end 11.006582 -1.90119)
			(stroke
				(width 0.1)
				(type default)
			)
			(layer "F.SilkS")
		)
		(fp_line
			(start 10.198354 -1.067816)
			(end 11.037062 -1.872742)
			(stroke
				(width 0.1)
				(type default)
			)
			(layer "F.SilkS")
		)
		(fp_line
			(start 10.198354 -1.067816)
			(end 11.037062 -1.872742)
			(stroke
				(width 0.1)
				(type default)
			)
			(layer "F.SilkS")
		)
		(fp_line
			(start 10.233406 -1.043686)
			(end 11.06932 -1.845818)
			(stroke
				(width 0.1)
				(type default)
			)
			(layer "F.SilkS")
		)
		(fp_line
			(start 10.233406 -1.043686)
			(end 11.06932 -1.845818)
			(stroke
				(width 0.1)
				(type default)
			)
			(layer "F.SilkS")
		)
		(fp_line
			(start 10.268458 -1.01981)
			(end 11.108182 -1.825244)
			(stroke
				(width 0.1)
				(type default)
			)
			(layer "F.SilkS")
		)
		(fp_line
			(start 10.268458 -1.01981)
			(end 11.108182 -1.825244)
			(stroke
				(width 0.1)
				(type default)
			)
			(layer "F.SilkS")
		)
		(fp_line
			(start 10.30478 -0.99695)
			(end 11.147044 -1.804924)
			(stroke
				(width 0.1)
				(type default)
			)
			(layer "F.SilkS")
		)
		(fp_line
			(start 10.30478 -0.99695)
			(end 11.147044 -1.804924)
			(stroke
				(width 0.1)
				(type default)
			)
			(layer "F.SilkS")
		)
		(fp_line
			(start 10.343388 -0.976122)
			(end 11.190478 -1.788922)
			(stroke
				(width 0.1)
				(type default)
			)
			(layer "F.SilkS")
		)
		(fp_line
			(start 10.343388 -0.976122)
			(end 11.190478 -1.788922)
			(stroke
				(width 0.1)
				(type default)
			)
			(layer "F.SilkS")
		)
		(fp_line
			(start 10.381996 -0.955548)
			(end 11.237722 -1.776476)
			(stroke
				(width 0.1)
				(type default)
			)
			(layer "F.SilkS")
		)
		(fp_line
			(start 10.381996 -0.955548)
			(end 11.237722 -1.776476)
			(stroke
				(width 0.1)
				(type default)
			)
			(layer "F.SilkS")
		)
		(fp_line
			(start 10.421366 -0.935482)
			(end 11.28522 -1.76403)
			(stroke
				(width 0.1)
				(type default)
			)
			(layer "F.SilkS")
		)
		(fp_line
			(start 10.421366 -0.935482)
			(end 11.28522 -1.76403)
			(stroke
				(width 0.1)
				(type default)
			)
			(layer "F.SilkS")
		)
		(fp_line
			(start 10.46353 -0.918464)
			(end 11.33856 -1.75768)
			(stroke
				(width 0.1)
				(type default)
			)
			(layer "F.SilkS")
		)
		(fp_line
			(start 10.46353 -0.918464)
			(end 11.33856 -1.75768)
			(stroke
				(width 0.1)
				(type default)
			)
			(layer "F.SilkS")
		)
		(fp_line
			(start 10.505694 -0.901192)
			(end 11.39444 -1.753616)
			(stroke
				(width 0.1)
				(type default)
			)
			(layer "F.SilkS")
		)
		(fp_line
			(start 10.505694 -0.901192)
			(end 11.39444 -1.753616)
			(stroke
				(width 0.1)
				(type default)
			)
			(layer "F.SilkS")
		)
		(fp_line
			(start 10.548366 -0.884682)
			(end 11.45032 -1.749552)
			(stroke
				(width 0.1)
				(type default)
			)
			(layer "F.SilkS")
		)
		(fp_line
			(start 10.548366 -0.884682)
			(end 11.45032 -1.749552)
			(stroke
				(width 0.1)
				(type default)
			)
			(layer "F.SilkS")
		)
		(fp_line
			(start 10.572496 -4.831842)
			(end 10.566146 -4.825746)
			(stroke
				(width 0.1)
				(type default)
			)
			(layer "F.SilkS")
		)
		(fp_line
			(start 10.572496 -4.831842)
			(end 10.566146 -4.825746)
			(stroke
				(width 0.1)
				(type default)
			)
			(layer "F.SilkS")
		)
		(fp_line
			(start 10.582148 -4.783328)
			(end 10.566146 -4.825746)
			(stroke
				(width 0.1)
				(type default)
			)
			(layer "F.SilkS")
		)
		(fp_line
			(start 10.582148 -4.783328)
			(end 10.566146 -4.825746)
			(stroke
				(width 0.1)
				(type default)
			)
			(layer "F.SilkS")
		)
		(fp_line
			(start 10.59434 -0.870712)
			(end 11.516614 -1.75514)
			(stroke
				(width 0.1)
				(type default)
			)
			(layer "F.SilkS")
		)
		(fp_line
			(start 10.59434 -0.870712)
			(end 11.516614 -1.75514)
			(stroke
				(width 0.1)
				(type default)
			)
			(layer "F.SilkS")
		)
		(fp_line
			(start 10.59815 -4.74091)
			(end 10.582148 -4.783328)
			(stroke
				(width 0.1)
				(type default)
			)
			(layer "F.SilkS")
		)
		(fp_line
			(start 10.59815 -4.74091)
			(end 10.582148 -4.783328)
			(stroke
				(width 0.1)
				(type default)
			)
			(layer "F.SilkS")
		)
		(fp_line
			(start 10.613898 -4.698746)
			(end 10.59815 -4.74091)
			(stroke
				(width 0.1)
				(type default)
			)
			(layer "F.SilkS")
		)
		(fp_line
			(start 10.613898 -4.698746)
			(end 10.59815 -4.74091)
			(stroke
				(width 0.1)
				(type default)
			)
			(layer "F.SilkS")
		)
		(fp_line
			(start 10.613898 -4.698746)
			(end 10.6299 -4.656074)
			(stroke
				(width 0.1)
				(type default)
			)
			(layer "F.SilkS")
		)
		(fp_line
			(start 10.613898 -4.698746)
			(end 10.6299 -4.656074)
			(stroke
				(width 0.1)
				(type default)
			)
			(layer "F.SilkS")
		)
		(fp_line
			(start 10.6299 -4.656074)
			(end 10.645902 -4.613656)
			(stroke
				(width 0.1)
				(type default)
			)
			(layer "F.SilkS")
		)
		(fp_line
			(start 10.6299 -4.656074)
			(end 10.645902 -4.613656)
			(stroke
				(width 0.1)
				(type default)
			)
			(layer "F.SilkS")
		)
		(fp_line
			(start 10.64006 -0.856996)
			(end 11.585448 -1.763522)
			(stroke
				(width 0.1)
				(type default)
			)
			(layer "F.SilkS")
		)
		(fp_line
			(start 10.64006 -0.856996)
			(end 11.585448 -1.763522)
			(stroke
				(width 0.1)
				(type default)
			)
			(layer "F.SilkS")
		)
		(fp_line
			(start 10.645902 -4.613656)
			(end 10.661904 -4.571492)
			(stroke
				(width 0.1)
				(type default)
			)
			(layer "F.SilkS")
		)
		(fp_line
			(start 10.645902 -4.613656)
			(end 10.661904 -4.571492)
			(stroke
				(width 0.1)
				(type default)
			)
			(layer "F.SilkS")
		)
		(fp_line
			(start 10.661904 -4.571492)
			(end 10.677906 -4.529074)
			(stroke
				(width 0.1)
				(type default)
			)
			(layer "F.SilkS")
		)
		(fp_line
			(start 10.661904 -4.571492)
			(end 10.677906 -4.529074)
			(stroke
				(width 0.1)
				(type default)
			)
			(layer "F.SilkS")
		)
		(fp_line
			(start 10.677906 -4.529074)
			(end 10.693908 -4.486402)
			(stroke
				(width 0.1)
				(type default)
			)
			(layer "F.SilkS")
		)
		(fp_line
			(start 10.677906 -4.529074)
			(end 10.693908 -4.486402)
			(stroke
				(width 0.1)
				(type default)
			)
			(layer "F.SilkS")
		)
		(fp_line
			(start 10.686542 -0.843534)
			(end 11.654282 -1.772158)
			(stroke
				(width 0.1)
				(type default)
			)
			(layer "F.SilkS")
		)
		(fp_line
			(start 10.686542 -0.843534)
			(end 11.654282 -1.772158)
			(stroke
				(width 0.1)
				(type default)
			)
			(layer "F.SilkS")
		)
		(fp_line
			(start 10.693908 -4.486402)
			(end 10.709656 -4.443984)
			(stroke
				(width 0.1)
				(type default)
			)
			(layer "F.SilkS")
		)
		(fp_line
			(start 10.693908 -4.486402)
			(end 10.709656 -4.443984)
			(stroke
				(width 0.1)
				(type default)
			)
			(layer "F.SilkS")
		)
		(fp_line
			(start 10.698734 -4.895088)
			(end 10.582148 -4.783328)
			(stroke
				(width 0.1)
				(type default)
			)
			(layer "F.SilkS")
		)
		(fp_line
			(start 10.698734 -4.895088)
			(end 10.582148 -4.783328)
			(stroke
				(width 0.1)
				(type default)
			)
			(layer "F.SilkS")
		)
		(fp_line
			(start 10.709656 -4.443984)
			(end 10.725658 -4.40182)
			(stroke
				(width 0.1)
				(type default)
			)
			(layer "F.SilkS")
		)
		(fp_line
			(start 10.709656 -4.443984)
			(end 10.725658 -4.40182)
			(stroke
				(width 0.1)
				(type default)
			)
			(layer "F.SilkS")
		)
		(fp_line
			(start 10.725658 -4.40182)
			(end 10.74166 -4.359402)
			(stroke
				(width 0.1)
				(type default)
			)
			(layer "F.SilkS")
		)
		(fp_line
			(start 10.725658 -4.40182)
			(end 10.74166 -4.359402)
			(stroke
				(width 0.1)
				(type default)
			)
			(layer "F.SilkS")
		)
		(fp_line
			(start 10.736072 -0.833628)
			(end 11.723116 -1.78054)
			(stroke
				(width 0.1)
				(type default)
			)
			(layer "F.SilkS")
		)
		(fp_line
			(start 10.736072 -0.833628)
			(end 11.723116 -1.78054)
			(stroke
				(width 0.1)
				(type default)
			)
			(layer "F.SilkS")
		)
		(fp_line
			(start 10.74166 -4.359402)
			(end 10.757662 -4.316984)
			(stroke
				(width 0.1)
				(type default)
			)
			(layer "F.SilkS")
		)
		(fp_line
			(start 10.74166 -4.359402)
			(end 10.757662 -4.316984)
			(stroke
				(width 0.1)
				(type default)
			)
			(layer "F.SilkS")
		)
		(fp_line
			(start 10.757662 -4.316984)
			(end 10.773664 -4.274566)
			(stroke
				(width 0.1)
				(type default)
			)
			(layer "F.SilkS")
		)
		(fp_line
			(start 10.757662 -4.316984)
			(end 10.773664 -4.274566)
			(stroke
				(width 0.1)
				(type default)
			)
			(layer "F.SilkS")
		)
		(fp_line
			(start 10.773664 -4.274566)
			(end 10.789666 -4.232148)
			(stroke
				(width 0.1)
				(type default)
			)
			(layer "F.SilkS")
		)
		(fp_line
			(start 10.773664 -4.274566)
			(end 10.789666 -4.232148)
			(stroke
				(width 0.1)
				(type default)
			)
			(layer "F.SilkS")
		)
		(fp_line
			(start 10.785602 -0.823214)
			(end 11.818112 -1.813814)
			(stroke
				(width 0.1)
				(type default)
			)
			(layer "F.SilkS")
		)
		(fp_line
			(start 10.785602 -0.823214)
			(end 11.818112 -1.813814)
			(stroke
				(width 0.1)
				(type default)
			)
			(layer "F.SilkS")
		)
		(fp_line
			(start 10.789666 -4.232148)
			(end 10.805414 -4.18973)
			(stroke
				(width 0.1)
				(type default)
			)
			(layer "F.SilkS")
		)
		(fp_line
			(start 10.789666 -4.232148)
			(end 10.805414 -4.18973)
			(stroke
				(width 0.1)
				(type default)
			)
			(layer "F.SilkS")
		)
		(fp_line
			(start 10.805414 -4.18973)
			(end 10.821416 -4.147312)
			(stroke
				(width 0.1)
				(type default)
			)
			(layer "F.SilkS")
		)
		(fp_line
			(start 10.805414 -4.18973)
			(end 10.821416 -4.147312)
			(stroke
				(width 0.1)
				(type default)
			)
			(layer "F.SilkS")
		)
		(fp_line
			(start 10.818368 -4.952492)
			(end 10.59815 -4.74091)
			(stroke
				(width 0.1)
				(type default)
			)
			(layer "F.SilkS")
		)
		(fp_line
			(start 10.818368 -4.952492)
			(end 10.59815 -4.74091)
			(stroke
				(width 0.1)
				(type default)
			)
			(layer "F.SilkS")
		)
		(fp_line
			(start 10.821416 -4.147312)
			(end 10.837418 -4.104894)
			(stroke
				(width 0.1)
				(type default)
			)
			(layer "F.SilkS")
		)
		(fp_line
			(start 10.821416 -4.147312)
			(end 10.837418 -4.104894)
			(stroke
				(width 0.1)
				(type default)
			)
			(layer "F.SilkS")
		)
		(fp_line
			(start 10.836402 -0.814324)
			(end 11.91514 -1.84912)
			(stroke
				(width 0.1)
				(type default)
			)
			(layer "F.SilkS")
		)
		(fp_line
			(start 10.836402 -0.814324)
			(end 11.91514 -1.84912)
			(stroke
				(width 0.1)
				(type default)
			)
			(layer "F.SilkS")
		)
		(fp_line
			(start 10.837418 -4.104894)
			(end 10.85342 -4.062476)
			(stroke
				(width 0.1)
				(type default)
			)
			(layer "F.SilkS")
		)
		(fp_line
			(start 10.837418 -4.104894)
			(end 10.85342 -4.062476)
			(stroke
				(width 0.1)
				(type default)
			)
			(layer "F.SilkS")
		)
		(fp_line
			(start 10.889742 -0.808228)
			(end 12.047474 -1.918462)
			(stroke
				(width 0.1)
				(type default)
			)
			(layer "F.SilkS")
		)
		(fp_line
			(start 10.889742 -0.808228)
			(end 12.047474 -1.918462)
			(stroke
				(width 0.1)
				(type default)
			)
			(layer "F.SilkS")
		)
		(fp_line
			(start 10.931144 -5.002784)
			(end 10.613898 -4.698746)
			(stroke
				(width 0.1)
				(type default)
			)
			(layer "F.SilkS")
		)
		(fp_line
			(start 10.931144 -5.002784)
			(end 10.613898 -4.698746)
			(stroke
				(width 0.1)
				(type default)
			)
			(layer "F.SilkS")
		)
		(fp_line
			(start 10.99947 -0.797814)
			(end 13.653516 -3.343402)
			(stroke
				(width 0.1)
				(type default)
			)
			(layer "F.SilkS")
		)
		(fp_line
			(start 10.99947 -0.797814)
			(end 13.653516 -3.343402)
			(stroke
				(width 0.1)
				(type default)
			)
			(layer "F.SilkS")
		)
		(fp_line
			(start 11.03503 -5.044694)
			(end 10.6299 -4.656074)
			(stroke
				(width 0.1)
				(type default)
			)
			(layer "F.SilkS")
		)
		(fp_line
			(start 11.03503 -5.044694)
			(end 10.6299 -4.656074)
			(stroke
				(width 0.1)
				(type default)
			)
			(layer "F.SilkS")
		)
		(fp_line
			(start 11.057382 -0.795274)
			(end 13.64107 -3.27406)
			(stroke
				(width 0.1)
				(type default)
			)
			(layer "F.SilkS")
		)
		(fp_line
			(start 11.057382 -0.795274)
			(end 13.64107 -3.27406)
			(stroke
				(width 0.1)
				(type default)
			)
			(layer "F.SilkS")
		)
		(fp_line
			(start 11.11504 -0.792988)
			(end 13.629132 -3.204972)
			(stroke
				(width 0.1)
				(type default)
			)
			(layer "F.SilkS")
		)
		(fp_line
			(start 11.11504 -0.792988)
			(end 13.629132 -3.204972)
			(stroke
				(width 0.1)
				(type default)
			)
			(layer "F.SilkS")
		)
		(fp_line
			(start 11.13536 -5.083048)
			(end 10.645902 -4.613656)
			(stroke
				(width 0.1)
				(type default)
			)
			(layer "F.SilkS")
		)
		(fp_line
			(start 11.13536 -5.083048)
			(end 10.645902 -4.613656)
			(stroke
				(width 0.1)
				(type default)
			)
			(layer "F.SilkS")
		)
		(fp_line
			(start 11.182096 -0.799846)
			(end 13.61694 -3.135376)
			(stroke
				(width 0.1)
				(type default)
			)
			(layer "F.SilkS")
		)
		(fp_line
			(start 11.182096 -0.799846)
			(end 13.61694 -3.135376)
			(stroke
				(width 0.1)
				(type default)
			)
			(layer "F.SilkS")
		)
		(fp_line
			(start 11.226546 -5.11302)
			(end 10.661904 -4.571492)
			(stroke
				(width 0.1)
				(type default)
			)
			(layer "F.SilkS")
		)
		(fp_line
			(start 11.226546 -5.11302)
			(end 10.661904 -4.571492)
			(stroke
				(width 0.1)
				(type default)
			)
			(layer "F.SilkS")
		)
		(fp_line
			(start 11.246612 -2.76606)
			(end 12.216638 -3.696716)
			(stroke
				(width 0.1)
				(type default)
			)
			(layer "F.SilkS")
		)
		(fp_line
			(start 11.246612 -2.76606)
			(end 12.216638 -3.696716)
			(stroke
				(width 0.1)
				(type default)
			)
			(layer "F.SilkS")
		)
		(fp_line
			(start 11.248898 -0.805942)
			(end 13.604494 -3.06578)
			(stroke
				(width 0.1)
				(type default)
			)
			(layer "F.SilkS")
		)
		(fp_line
			(start 11.248898 -0.805942)
			(end 13.604494 -3.06578)
			(stroke
				(width 0.1)
				(type default)
			)
			(layer "F.SilkS")
		)
		(fp_line
			(start 11.315446 -5.140706)
			(end 10.677906 -4.529074)
			(stroke
				(width 0.1)
				(type default)
			)
			(layer "F.SilkS")
		)
		(fp_line
			(start 11.315446 -5.140706)
			(end 10.677906 -4.529074)
			(stroke
				(width 0.1)
				(type default)
			)
			(layer "F.SilkS")
		)
		(fp_line
			(start 11.315954 -0.813054)
			(end 13.592556 -2.996692)
			(stroke
				(width 0.1)
				(type default)
			)
			(layer "F.SilkS")
		)
		(fp_line
			(start 11.315954 -0.813054)
			(end 13.592556 -2.996692)
			(stroke
				(width 0.1)
				(type default)
			)
			(layer "F.SilkS")
		)
		(fp_line
			(start 11.364722 -2.821686)
			(end 12.265914 -3.686302)
			(stroke
				(width 0.1)
				(type default)
			)
			(layer "F.SilkS")
		)
		(fp_line
			(start 11.364722 -2.821686)
			(end 12.265914 -3.686302)
			(stroke
				(width 0.1)
				(type default)
			)
			(layer "F.SilkS")
		)
		(fp_line
			(start 11.382756 -0.81915)
			(end 13.580364 -2.927096)
			(stroke
				(width 0.1)
				(type default)
			)
			(layer "F.SilkS")
		)
		(fp_line
			(start 11.382756 -0.81915)
			(end 13.580364 -2.927096)
			(stroke
				(width 0.1)
				(type default)
			)
			(layer "F.SilkS")
		)
		(fp_line
			(start 11.398758 -5.163058)
			(end 10.693908 -4.486402)
			(stroke
				(width 0.1)
				(type default)
			)
			(layer "F.SilkS")
		)
		(fp_line
			(start 11.398758 -5.163058)
			(end 10.693908 -4.486402)
			(stroke
				(width 0.1)
				(type default)
			)
			(layer "F.SilkS")
		)
		(fp_line
			(start 11.436096 -2.832354)
			(end 12.31138 -3.672078)
			(stroke
				(width 0.1)
				(type default)
			)
			(layer "F.SilkS")
		)
		(fp_line
			(start 11.436096 -2.832354)
			(end 12.31138 -3.672078)
			(stroke
				(width 0.1)
				(type default)
			)
			(layer "F.SilkS")
		)
		(fp_line
			(start 11.460734 -0.836422)
			(end 13.568172 -2.857754)
			(stroke
				(width 0.1)
				(type default)
			)
			(layer "F.SilkS")
		)
		(fp_line
			(start 11.460734 -0.836422)
			(end 13.568172 -2.857754)
			(stroke
				(width 0.1)
				(type default)
			)
			(layer "F.SilkS")
		)
		(fp_line
			(start 11.478514 -5.1816)
			(end 10.709656 -4.443984)
			(stroke
				(width 0.1)
				(type default)
			)
			(layer "F.SilkS")
		)
		(fp_line
			(start 11.478514 -5.1816)
			(end 10.709656 -4.443984)
			(stroke
				(width 0.1)
				(type default)
			)
			(layer "F.SilkS")
		)
		(fp_line
			(start 11.505184 -2.84099)
			(end 12.356592 -3.657854)
			(stroke
				(width 0.1)
				(type default)
			)
			(layer "F.SilkS")
		)
		(fp_line
			(start 11.505184 -2.84099)
			(end 12.356592 -3.657854)
			(stroke
				(width 0.1)
				(type default)
			)
			(layer "F.SilkS")
		)
		(fp_line
			(start 11.546332 -0.860552)
			(end 13.55598 -2.788412)
			(stroke
				(width 0.1)
				(type default)
			)
			(layer "F.SilkS")
		)
		(fp_line
			(start 11.546332 -0.860552)
			(end 13.55598 -2.788412)
			(stroke
				(width 0.1)
				(type default)
			)
			(layer "F.SilkS")
		)
		(fp_line
			(start 11.557762 -5.199888)
			(end 10.725658 -4.40182)
			(stroke
				(width 0.1)
				(type default)
			)
			(layer "F.SilkS")
		)
		(fp_line
			(start 11.557762 -5.199888)
			(end 10.725658 -4.40182)
			(stroke
				(width 0.1)
				(type default)
			)
			(layer "F.SilkS")
		)
		(fp_line
			(start 11.629898 -5.211572)
			(end 10.74166 -4.359402)
			(stroke
				(width 0.1)
				(type default)
			)
			(layer "F.SilkS")
		)
		(fp_line
			(start 11.629898 -5.211572)
			(end 10.74166 -4.359402)
			(stroke
				(width 0.1)
				(type default)
			)
			(layer "F.SilkS")
		)
		(fp_line
			(start 11.63193 -0.884936)
			(end 13.544042 -2.71907)
			(stroke
				(width 0.1)
				(type default)
			)
			(layer "F.SilkS")
		)
		(fp_line
			(start 11.63193 -0.884936)
			(end 13.544042 -2.71907)
			(stroke
				(width 0.1)
				(type default)
			)
			(layer "F.SilkS")
		)
		(fp_line
			(start 11.702034 -5.223002)
			(end 10.757662 -4.316984)
			(stroke
				(width 0.1)
				(type default)
			)
			(layer "F.SilkS")
		)
		(fp_line
			(start 11.702034 -5.223002)
			(end 10.757662 -4.316984)
			(stroke
				(width 0.1)
				(type default)
			)
			(layer "F.SilkS")
		)
		(fp_line
			(start 11.728704 -0.919988)
			(end 13.531596 -2.649728)
			(stroke
				(width 0.1)
				(type default)
			)
			(layer "F.SilkS")
		)
		(fp_line
			(start 11.728704 -0.919988)
			(end 13.531596 -2.649728)
			(stroke
				(width 0.1)
				(type default)
			)
			(layer "F.SilkS")
		)
		(fp_line
			(start 11.77417 -5.234178)
			(end 10.773664 -4.274566)
			(stroke
				(width 0.1)
				(type default)
			)
			(layer "F.SilkS")
		)
		(fp_line
			(start 11.77417 -5.234178)
			(end 10.773664 -4.274566)
			(stroke
				(width 0.1)
				(type default)
			)
			(layer "F.SilkS")
		)
		(fp_line
			(start 11.84021 -5.24002)
			(end 10.789666 -4.232148)
			(stroke
				(width 0.1)
				(type default)
			)
			(layer "F.SilkS")
		)
		(fp_line
			(start 11.84021 -5.24002)
			(end 10.789666 -4.232148)
			(stroke
				(width 0.1)
				(type default)
			)
			(layer "F.SilkS")
		)
		(fp_line
			(start 11.8491 -0.9779)
			(end 13.519404 -2.580386)
			(stroke
				(width 0.1)
				(type default)
			)
			(layer "F.SilkS")
		)
		(fp_line
			(start 11.8491 -0.9779)
			(end 13.519404 -2.580386)
			(stroke
				(width 0.1)
				(type default)
			)
			(layer "F.SilkS")
		)
		(fp_line
			(start 11.906504 -5.245862)
			(end 10.805414 -4.18973)
			(stroke
				(width 0.1)
				(type default)
			)
			(layer "F.SilkS")
		)
		(fp_line
			(start 11.906504 -5.245862)
			(end 10.805414 -4.18973)
			(stroke
				(width 0.1)
				(type default)
			)
			(layer "F.SilkS")
		)
		(fp_line
			(start 11.972798 -5.251958)
			(end 10.821416 -4.147312)
			(stroke
				(width 0.1)
				(type default)
			)
			(layer "F.SilkS")
		)
		(fp_line
			(start 11.972798 -5.251958)
			(end 10.821416 -4.147312)
			(stroke
				(width 0.1)
				(type default)
			)
			(layer "F.SilkS")
		)
		(fp_line
			(start 12.000738 -1.06553)
			(end 13.507466 -2.51079)
			(stroke
				(width 0.1)
				(type default)
			)
			(layer "F.SilkS")
		)
		(fp_line
			(start 12.000738 -1.06553)
			(end 13.507466 -2.51079)
			(stroke
				(width 0.1)
				(type default)
			)
			(layer "F.SilkS")
		)
		(fp_line
			(start 12.036806 -5.255514)
			(end 10.837418 -4.104894)
			(stroke
				(width 0.1)
				(type default)
			)
			(layer "F.SilkS")
		)
		(fp_line
			(start 12.036806 -5.255514)
			(end 10.837418 -4.104894)
			(stroke
				(width 0.1)
				(type default)
			)
			(layer "F.SilkS")
		)
		(fp_line
			(start 12.093956 -0.882904)
			(end 12.111228 -0.882904)
			(stroke
				(width 0.1)
				(type default)
			)
			(layer "F.SilkS")
		)
		(fp_line
			(start 12.093956 -0.882904)
			(end 12.111228 -0.882904)
			(stroke
				(width 0.1)
				(type default)
			)
			(layer "F.SilkS")
		)
		(fp_line
			(start 12.098528 -5.257038)
			(end 10.85342 -4.062476)
			(stroke
				(width 0.1)
				(type default)
			)
			(layer "F.SilkS")
		)
		(fp_line
			(start 12.098528 -5.257038)
			(end 10.85342 -4.062476)
			(stroke
				(width 0.1)
				(type default)
			)
			(layer "F.SilkS")
		)
		(fp_line
			(start 12.102592 -0.932434)
			(end 12.093956 -0.882904)
			(stroke
				(width 0.1)
				(type default)
			)
			(layer "F.SilkS")
		)
		(fp_line
			(start 12.102592 -0.932434)
			(end 12.093956 -0.882904)
			(stroke
				(width 0.1)
				(type default)
			)
			(layer "F.SilkS")
		)
		(fp_line
			(start 12.102592 -0.932434)
			(end 13.458444 -2.233422)
			(stroke
				(width 0.1)
				(type default)
			)
			(layer "F.SilkS")
		)
		(fp_line
			(start 12.102592 -0.932434)
			(end 13.458444 -2.233422)
			(stroke
				(width 0.1)
				(type default)
			)
			(layer "F.SilkS")
		)
		(fp_line
			(start 12.111228 -0.882904)
			(end 12.171172 -0.882904)
			(stroke
				(width 0.1)
				(type default)
			)
			(layer "F.SilkS")
		)
		(fp_line
			(start 12.111228 -0.882904)
			(end 12.171172 -0.882904)
			(stroke
				(width 0.1)
				(type default)
			)
			(layer "F.SilkS")
		)
		(fp_line
			(start 12.111228 -0.882904)
			(end 13.446506 -2.163826)
			(stroke
				(width 0.1)
				(type default)
			)
			(layer "F.SilkS")
		)
		(fp_line
			(start 12.111228 -0.882904)
			(end 13.446506 -2.163826)
			(stroke
				(width 0.1)
				(type default)
			)
			(layer "F.SilkS")
		)
		(fp_line
			(start 12.115038 -1.00203)
			(end 12.102592 -0.932434)
			(stroke
				(width 0.1)
				(type default)
			)
			(layer "F.SilkS")
		)
		(fp_line
			(start 12.115038 -1.00203)
			(end 12.102592 -0.932434)
			(stroke
				(width 0.1)
				(type default)
			)
			(layer "F.SilkS")
		)
		(fp_line
			(start 12.115038 -1.00203)
			(end 13.47089 -2.302764)
			(stroke
				(width 0.1)
				(type default)
			)
			(layer "F.SilkS")
		)
		(fp_line
			(start 12.115038 -1.00203)
			(end 13.47089 -2.302764)
			(stroke
				(width 0.1)
				(type default)
			)
			(layer "F.SilkS")
		)
		(fp_line
			(start 12.12723 -1.071626)
			(end 12.115038 -1.00203)
			(stroke
				(width 0.1)
				(type default)
			)
			(layer "F.SilkS")
		)
		(fp_line
			(start 12.12723 -1.071626)
			(end 12.115038 -1.00203)
			(stroke
				(width 0.1)
				(type default)
			)
			(layer "F.SilkS")
		)
		(fp_line
			(start 12.12723 -1.071626)
			(end 13.483082 -2.372106)
			(stroke
				(width 0.1)
				(type default)
			)
			(layer "F.SilkS")
		)
		(fp_line
			(start 12.12723 -1.071626)
			(end 13.483082 -2.372106)
			(stroke
				(width 0.1)
				(type default)
			)
			(layer "F.SilkS")
		)
		(fp_line
			(start 12.139676 -1.140968)
			(end 12.12723 -1.071626)
			(stroke
				(width 0.1)
				(type default)
			)
			(layer "F.SilkS")
		)
		(fp_line
			(start 12.139676 -1.140968)
			(end 12.12723 -1.071626)
			(stroke
				(width 0.1)
				(type default)
			)
			(layer "F.SilkS")
		)
		(fp_line
			(start 12.139676 -1.140968)
			(end 13.49502 -2.441448)
			(stroke
				(width 0.1)
				(type default)
			)
			(layer "F.SilkS")
		)
		(fp_line
			(start 12.139676 -1.140968)
			(end 13.49502 -2.441448)
			(stroke
				(width 0.1)
				(type default)
			)
			(layer "F.SilkS")
		)
		(fp_line
			(start 12.160504 -5.258816)
			(end 10.92708 -4.07543)
			(stroke
				(width 0.1)
				(type default)
			)
			(layer "F.SilkS")
		)
		(fp_line
			(start 12.160504 -5.258816)
			(end 10.92708 -4.07543)
			(stroke
				(width 0.1)
				(type default)
			)
			(layer "F.SilkS")
		)
		(fp_line
			(start 12.171172 -0.882904)
			(end 12.23137 -0.882904)
			(stroke
				(width 0.1)
				(type default)
			)
			(layer "F.SilkS")
		)
		(fp_line
			(start 12.171172 -0.882904)
			(end 12.23137 -0.882904)
			(stroke
				(width 0.1)
				(type default)
			)
			(layer "F.SilkS")
		)
		(fp_line
			(start 12.171172 -0.882904)
			(end 13.434314 -2.094738)
			(stroke
				(width 0.1)
				(type default)
			)
			(layer "F.SilkS")
		)
		(fp_line
			(start 12.171172 -0.882904)
			(end 13.434314 -2.094738)
			(stroke
				(width 0.1)
				(type default)
			)
			(layer "F.SilkS")
		)
		(fp_line
			(start 12.22248 -5.260594)
			(end 11.042904 -4.12877)
			(stroke
				(width 0.1)
				(type default)
			)
			(layer "F.SilkS")
		)
		(fp_line
			(start 12.22248 -5.260594)
			(end 11.042904 -4.12877)
			(stroke
				(width 0.1)
				(type default)
			)
			(layer "F.SilkS")
		)
		(fp_line
			(start 12.23137 -0.882904)
			(end 12.291568 -0.882904)
			(stroke
				(width 0.1)
				(type default)
			)
			(layer "F.SilkS")
		)
		(fp_line
			(start 12.23137 -0.882904)
			(end 12.291568 -0.882904)
			(stroke
				(width 0.1)
				(type default)
			)
			(layer "F.SilkS")
		)
		(fp_line
			(start 12.23137 -0.882904)
			(end 13.422122 -2.025396)
			(stroke
				(width 0.1)
				(type default)
			)
			(layer "F.SilkS")
		)
		(fp_line
			(start 12.23137 -0.882904)
			(end 13.422122 -2.025396)
			(stroke
				(width 0.1)
				(type default)
			)
			(layer "F.SilkS")
		)
		(fp_line
			(start 12.281408 -5.25907)
			(end 11.150092 -4.173728)
			(stroke
				(width 0.1)
				(type default)
			)
			(layer "F.SilkS")
		)
		(fp_line
			(start 12.281408 -5.25907)
			(end 11.150092 -4.173728)
			(stroke
				(width 0.1)
				(type default)
			)
			(layer "F.SilkS")
		)
		(fp_line
			(start 12.291568 -0.882904)
			(end 12.351512 -0.882904)
			(stroke
				(width 0.1)
				(type default)
			)
			(layer "F.SilkS")
		)
		(fp_line
			(start 12.291568 -0.882904)
			(end 12.351512 -0.882904)
			(stroke
				(width 0.1)
				(type default)
			)
			(layer "F.SilkS")
		)
		(fp_line
			(start 12.291568 -0.882904)
			(end 13.40993 -1.9558)
			(stroke
				(width 0.1)
				(type default)
			)
			(layer "F.SilkS")
		)
		(fp_line
			(start 12.291568 -0.882904)
			(end 13.40993 -1.9558)
			(stroke
				(width 0.1)
				(type default)
			)
			(layer "F.SilkS")
		)
		(fp_line
			(start 12.335002 -2.251964)
			(end 12.323064 -2.182622)
			(stroke
				(width 0.1)
				(type default)
			)
			(layer "F.SilkS")
		)
		(fp_line
			(start 12.335002 -2.251964)
			(end 12.323064 -2.182622)
			(stroke
				(width 0.1)
				(type default)
			)
			(layer "F.SilkS")
		)
		(fp_line
			(start 12.337542 -5.255514)
			(end 11.246358 -4.208526)
			(stroke
				(width 0.1)
				(type default)
			)
			(layer "F.SilkS")
		)
		(fp_line
			(start 12.337542 -5.255514)
			(end 11.246358 -4.208526)
			(stroke
				(width 0.1)
				(type default)
			)
			(layer "F.SilkS")
		)
		(fp_line
			(start 12.347194 -2.321306)
			(end 12.335002 -2.251964)
			(stroke
				(width 0.1)
				(type default)
			)
			(layer "F.SilkS")
		)
		(fp_line
			(start 12.347194 -2.321306)
			(end 12.335002 -2.251964)
			(stroke
				(width 0.1)
				(type default)
			)
			(layer "F.SilkS")
		)
		(fp_line
			(start 12.351512 -0.882904)
			(end 12.41171 -0.882904)
			(stroke
				(width 0.1)
				(type default)
			)
			(layer "F.SilkS")
		)
		(fp_line
			(start 12.351512 -0.882904)
			(end 12.41171 -0.882904)
			(stroke
				(width 0.1)
				(type default)
			)
			(layer "F.SilkS")
		)
		(fp_line
			(start 12.351512 -0.882904)
			(end 13.397992 -1.886458)
			(stroke
				(width 0.1)
				(type default)
			)
			(layer "F.SilkS")
		)
		(fp_line
			(start 12.351512 -0.882904)
			(end 13.397992 -1.886458)
			(stroke
				(width 0.1)
				(type default)
			)
			(layer "F.SilkS")
		)
		(fp_line
			(start 12.359386 -2.390902)
			(end 12.347194 -2.321306)
			(stroke
				(width 0.1)
				(type default)
			)
			(layer "F.SilkS")
		)
		(fp_line
			(start 12.359386 -2.390902)
			(end 12.347194 -2.321306)
			(stroke
				(width 0.1)
				(type default)
			)
			(layer "F.SilkS")
		)
		(fp_line
			(start 12.371578 -2.460244)
			(end 12.359386 -2.390902)
			(stroke
				(width 0.1)
				(type default)
			)
			(layer "F.SilkS")
		)
		(fp_line
			(start 12.371578 -2.460244)
			(end 12.359386 -2.390902)
			(stroke
				(width 0.1)
				(type default)
			)
			(layer "F.SilkS")
		)
		(fp_line
			(start 12.38377 -2.529586)
			(end 12.371578 -2.460244)
			(stroke
				(width 0.1)
				(type default)
			)
			(layer "F.SilkS")
		)
		(fp_line
			(start 12.38377 -2.529586)
			(end 12.371578 -2.460244)
			(stroke
				(width 0.1)
				(type default)
			)
			(layer "F.SilkS")
		)
		(fp_line
			(start 12.393676 -5.251704)
			(end 11.336782 -4.237736)
			(stroke
				(width 0.1)
				(type default)
			)
			(layer "F.SilkS")
		)
		(fp_line
			(start 12.393676 -5.251704)
			(end 11.336782 -4.237736)
			(stroke
				(width 0.1)
				(type default)
			)
			(layer "F.SilkS")
		)
		(fp_line
			(start 12.395962 -2.598928)
			(end 12.38377 -2.529586)
			(stroke
				(width 0.1)
				(type default)
			)
			(layer "F.SilkS")
		)
		(fp_line
			(start 12.395962 -2.598928)
			(end 12.38377 -2.529586)
			(stroke
				(width 0.1)
				(type default)
			)
			(layer "F.SilkS")
		)
		(fp_line
			(start 12.401804 -3.64363)
			(end 11.574526 -2.849626)
			(stroke
				(width 0.1)
				(type default)
			)
			(layer "F.SilkS")
		)
		(fp_line
			(start 12.401804 -3.64363)
			(end 11.574526 -2.849626)
			(stroke
				(width 0.1)
				(type default)
			)
			(layer "F.SilkS")
		)
		(fp_line
			(start 12.408154 -2.668524)
			(end 12.395962 -2.598928)
			(stroke
				(width 0.1)
				(type default)
			)
			(layer "F.SilkS")
		)
		(fp_line
			(start 12.408154 -2.668524)
			(end 12.395962 -2.598928)
			(stroke
				(width 0.1)
				(type default)
			)
			(layer "F.SilkS")
		)
		(fp_line
			(start 12.41171 -0.882904)
			(end 12.471908 -0.882904)
			(stroke
				(width 0.1)
				(type default)
			)
			(layer "F.SilkS")
		)
		(fp_line
			(start 12.41171 -0.882904)
			(end 12.471908 -0.882904)
			(stroke
				(width 0.1)
				(type default)
			)
			(layer "F.SilkS")
		)
		(fp_line
			(start 12.41171 -0.882904)
			(end 13.385546 -1.817116)
			(stroke
				(width 0.1)
				(type default)
			)
			(layer "F.SilkS")
		)
		(fp_line
			(start 12.41171 -0.882904)
			(end 13.385546 -1.817116)
			(stroke
				(width 0.1)
				(type default)
			)
			(layer "F.SilkS")
		)
		(fp_line
			(start 12.445238 -3.62712)
			(end 11.643614 -2.858262)
			(stroke
				(width 0.1)
				(type default)
			)
			(layer "F.SilkS")
		)
		(fp_line
			(start 12.445238 -3.62712)
			(end 11.643614 -2.858262)
			(stroke
				(width 0.1)
				(type default)
			)
			(layer "F.SilkS")
		)
		(fp_line
			(start 12.44981 -5.24764)
			(end 11.421364 -4.261104)
			(stroke
				(width 0.1)
				(type default)
			)
			(layer "F.SilkS")
		)
		(fp_line
			(start 12.44981 -5.24764)
			(end 11.421364 -4.261104)
			(stroke
				(width 0.1)
				(type default)
			)
			(layer "F.SilkS")
		)
		(fp_line
			(start 12.471908 -0.882904)
			(end 12.53236 -0.882904)
			(stroke
				(width 0.1)
				(type default)
			)
			(layer "F.SilkS")
		)
		(fp_line
			(start 12.471908 -0.882904)
			(end 12.53236 -0.882904)
			(stroke
				(width 0.1)
				(type default)
			)
			(layer "F.SilkS")
		)
		(fp_line
			(start 12.471908 -0.882904)
			(end 13.373354 -1.74752)
			(stroke
				(width 0.1)
				(type default)
			)
			(layer "F.SilkS")
		)
		(fp_line
			(start 12.471908 -0.882904)
			(end 13.373354 -1.74752)
			(stroke
				(width 0.1)
				(type default)
			)
			(layer "F.SilkS")
		)
		(fp_line
			(start 12.485624 -3.608324)
			(end 11.704574 -2.859278)
			(stroke
				(width 0.1)
				(type default)
			)
			(layer "F.SilkS")
		)
		(fp_line
			(start 12.485624 -3.608324)
			(end 11.704574 -2.859278)
			(stroke
				(width 0.1)
				(type default)
			)
			(layer "F.SilkS")
		)
		(fp_line
			(start 12.506198 -5.24383)
			(end 11.499596 -4.278376)
			(stroke
				(width 0.1)
				(type default)
			)
			(layer "F.SilkS")
		)
		(fp_line
			(start 12.506198 -5.24383)
			(end 11.499596 -4.278376)
			(stroke
				(width 0.1)
				(type default)
			)
			(layer "F.SilkS")
		)
		(fp_line
			(start 12.52601 -3.589274)
			(end 11.763502 -2.858008)
			(stroke
				(width 0.1)
				(type default)
			)
			(layer "F.SilkS")
		)
		(fp_line
			(start 12.52601 -3.589274)
			(end 11.763502 -2.858008)
			(stroke
				(width 0.1)
				(type default)
			)
			(layer "F.SilkS")
		)
		(fp_line
			(start 12.53236 -0.882904)
			(end 12.592558 -0.882904)
			(stroke
				(width 0.1)
				(type default)
			)
			(layer "F.SilkS")
		)
		(fp_line
			(start 12.53236 -0.882904)
			(end 12.592558 -0.882904)
			(stroke
				(width 0.1)
				(type default)
			)
			(layer "F.SilkS")
		)
		(fp_line
			(start 12.53236 -0.882904)
			(end 13.361416 -1.678178)
			(stroke
				(width 0.1)
				(type default)
			)
			(layer "F.SilkS")
		)
		(fp_line
			(start 12.53236 -0.882904)
			(end 13.361416 -1.678178)
			(stroke
				(width 0.1)
				(type default)
			)
			(layer "F.SilkS")
		)
		(fp_line
			(start 12.562078 -5.24002)
			(end 11.575542 -4.293616)
			(stroke
				(width 0.1)
				(type default)
			)
			(layer "F.SilkS")
		)
		(fp_line
			(start 12.562078 -5.24002)
			(end 11.575542 -4.293616)
			(stroke
				(width 0.1)
				(type default)
			)
			(layer "F.SilkS")
		)
		(fp_line
			(start 12.590018 -3.708654)
			(end 12.57808 -3.639312)
			(stroke
				(width 0.1)
				(type default)
			)
			(layer "F.SilkS")
		)
		(fp_line
			(start 12.590018 -3.708654)
			(end 12.57808 -3.639312)
			(stroke
				(width 0.1)
				(type default)
			)
			(layer "F.SilkS")
		)
		(fp_line
			(start 12.592558 -0.882904)
			(end 12.652502 -0.882904)
			(stroke
				(width 0.1)
				(type default)
			)
			(layer "F.SilkS")
		)
		(fp_line
			(start 12.592558 -0.882904)
			(end 12.652502 -0.882904)
			(stroke
				(width 0.1)
				(type default)
			)
			(layer "F.SilkS")
		)
		(fp_line
			(start 12.592558 -0.882904)
			(end 13.34897 -1.608836)
			(stroke
				(width 0.1)
				(type default)
			)
			(layer "F.SilkS")
		)
		(fp_line
			(start 12.592558 -0.882904)
			(end 13.34897 -1.608836)
			(stroke
				(width 0.1)
				(type default)
			)
			(layer "F.SilkS")
		)
		(fp_line
			(start 12.601956 -3.777996)
			(end 12.590018 -3.708654)
			(stroke
				(width 0.1)
				(type default)
			)
			(layer "F.SilkS")
		)
		(fp_line
			(start 12.601956 -3.777996)
			(end 12.590018 -3.708654)
			(stroke
				(width 0.1)
				(type default)
			)
			(layer "F.SilkS")
		)
		(fp_line
			(start 12.618212 -5.23621)
			(end 11.6459 -4.303268)
			(stroke
				(width 0.1)
				(type default)
			)
			(layer "F.SilkS")
		)
		(fp_line
			(start 12.618212 -5.23621)
			(end 11.6459 -4.303268)
			(stroke
				(width 0.1)
				(type default)
			)
			(layer "F.SilkS")
		)
		(fp_line
			(start 12.652502 -0.882904)
			(end 12.7127 -0.882904)
			(stroke
				(width 0.1)
				(type default)
			)
			(layer "F.SilkS")
		)
		(fp_line
			(start 12.652502 -0.882904)
			(end 12.7127 -0.882904)
			(stroke
				(width 0.1)
				(type default)
			)
			(layer "F.SilkS")
		)
		(fp_line
			(start 12.652502 -0.882904)
			(end 13.337286 -1.539494)
			(stroke
				(width 0.1)
				(type default)
			)
			(layer "F.SilkS")
		)
		(fp_line
			(start 12.652502 -0.882904)
			(end 13.337286 -1.539494)
			(stroke
				(width 0.1)
				(type default)
			)
			(layer "F.SilkS")
		)
		(fp_line
			(start 12.666726 -5.225034)
			(end 11.715242 -4.312412)
			(stroke
				(width 0.1)
				(type default)
			)
			(layer "F.SilkS")
		)
		(fp_line
			(start 12.666726 -5.225034)
			(end 11.715242 -4.312412)
			(stroke
				(width 0.1)
				(type default)
			)
			(layer "F.SilkS")
		)
		(fp_line
			(start 12.7127 -0.882904)
			(end 12.772898 -0.882904)
			(stroke
				(width 0.1)
				(type default)
			)
			(layer "F.SilkS")
		)
		(fp_line
			(start 12.7127 -0.882904)
			(end 12.772898 -0.882904)
			(stroke
				(width 0.1)
				(type default)
			)
			(layer "F.SilkS")
		)
		(fp_line
			(start 12.7127 -0.882904)
			(end 13.32484 -1.470152)
			(stroke
				(width 0.1)
				(type default)
			)
			(layer "F.SilkS")
		)
		(fp_line
			(start 12.7127 -0.882904)
			(end 13.32484 -1.470152)
			(stroke
				(width 0.1)
				(type default)
			)
			(layer "F.SilkS")
		)
		(fp_line
			(start 12.715494 -5.214112)
			(end 11.78179 -4.318254)
			(stroke
				(width 0.1)
				(type default)
			)
			(layer "F.SilkS")
		)
		(fp_line
			(start 12.715494 -5.214112)
			(end 11.78179 -4.318254)
			(stroke
				(width 0.1)
				(type default)
			)
			(layer "F.SilkS")
		)
		(fp_line
			(start 12.764008 -5.202936)
			(end 11.846306 -4.322572)
			(stroke
				(width 0.1)
				(type default)
			)
			(layer "F.SilkS")
		)
		(fp_line
			(start 12.764008 -5.202936)
			(end 11.846306 -4.322572)
			(stroke
				(width 0.1)
				(type default)
			)
			(layer "F.SilkS")
		)
		(fp_line
			(start 12.772898 -0.882904)
			(end 12.832842 -0.882904)
			(stroke
				(width 0.1)
				(type default)
			)
			(layer "F.SilkS")
		)
		(fp_line
			(start 12.772898 -0.882904)
			(end 12.832842 -0.882904)
			(stroke
				(width 0.1)
				(type default)
			)
			(layer "F.SilkS")
		)
		(fp_line
			(start 12.772898 -0.882904)
			(end 13.312394 -1.400556)
			(stroke
				(width 0.1)
				(type default)
			)
			(layer "F.SilkS")
		)
		(fp_line
			(start 12.772898 -0.882904)
			(end 13.312394 -1.400556)
			(stroke
				(width 0.1)
				(type default)
			)
			(layer "F.SilkS")
		)
		(fp_line
			(start 12.812522 -5.19176)
			(end 11.910568 -4.326636)
			(stroke
				(width 0.1)
				(type default)
			)
			(layer "F.SilkS")
		)
		(fp_line
			(start 12.812522 -5.19176)
			(end 11.910568 -4.326636)
			(stroke
				(width 0.1)
				(type default)
			)
			(layer "F.SilkS")
		)
		(fp_line
			(start 12.832842 -0.882904)
			(end 12.89304 -0.882904)
			(stroke
				(width 0.1)
				(type default)
			)
			(layer "F.SilkS")
		)
		(fp_line
			(start 12.832842 -0.882904)
			(end 12.89304 -0.882904)
			(stroke
				(width 0.1)
				(type default)
			)
			(layer "F.SilkS")
		)
		(fp_line
			(start 12.832842 -0.882904)
			(end 13.30071 -1.331468)
			(stroke
				(width 0.1)
				(type default)
			)
			(layer "F.SilkS")
		)
		(fp_line
			(start 12.832842 -0.882904)
			(end 13.30071 -1.331468)
			(stroke
				(width 0.1)
				(type default)
			)
			(layer "F.SilkS")
		)
		(fp_line
			(start 12.861036 -5.180584)
			(end 11.972036 -4.327906)
			(stroke
				(width 0.1)
				(type default)
			)
			(layer "F.SilkS")
		)
		(fp_line
			(start 12.861036 -5.180584)
			(end 11.972036 -4.327906)
			(stroke
				(width 0.1)
				(type default)
			)
			(layer "F.SilkS")
		)
		(fp_line
			(start 12.89304 -0.882904)
			(end 12.953238 -0.882904)
			(stroke
				(width 0.1)
				(type default)
			)
			(layer "F.SilkS")
		)
		(fp_line
			(start 12.89304 -0.882904)
			(end 12.953238 -0.882904)
			(stroke
				(width 0.1)
				(type default)
			)
			(layer "F.SilkS")
		)
		(fp_line
			(start 12.89304 -0.882904)
			(end 13.288264 -1.262126)
			(stroke
				(width 0.1)
				(type default)
			)
			(layer "F.SilkS")
		)
		(fp_line
			(start 12.89304 -0.882904)
			(end 13.288264 -1.262126)
			(stroke
				(width 0.1)
				(type default)
			)
			(layer "F.SilkS")
		)
		(fp_line
			(start 12.909804 -5.169408)
			(end 12.033758 -4.328922)
			(stroke
				(width 0.1)
				(type default)
			)
			(layer "F.SilkS")
		)
		(fp_line
			(start 12.909804 -5.169408)
			(end 12.033758 -4.328922)
			(stroke
				(width 0.1)
				(type default)
			)
			(layer "F.SilkS")
		)
		(fp_line
			(start 12.953238 -0.882904)
			(end 13.01369 -0.882904)
			(stroke
				(width 0.1)
				(type default)
			)
			(layer "F.SilkS")
		)
		(fp_line
			(start 12.953238 -0.882904)
			(end 13.01369 -0.882904)
			(stroke
				(width 0.1)
				(type default)
			)
			(layer "F.SilkS")
		)
		(fp_line
			(start 12.953238 -0.882904)
			(end 13.275818 -1.19253)
			(stroke
				(width 0.1)
				(type default)
			)
			(layer "F.SilkS")
		)
		(fp_line
			(start 12.953238 -0.882904)
			(end 13.275818 -1.19253)
			(stroke
				(width 0.1)
				(type default)
			)
			(layer "F.SilkS")
		)
		(fp_line
			(start 12.955778 -5.155946)
			(end 12.09421 -4.32943)
			(stroke
				(width 0.1)
				(type default)
			)
			(layer "F.SilkS")
		)
		(fp_line
			(start 12.955778 -5.155946)
			(end 12.09421 -4.32943)
			(stroke
				(width 0.1)
				(type default)
			)
			(layer "F.SilkS")
		)
		(fp_line
			(start 12.996926 -5.137658)
			(end 12.149836 -4.325112)
			(stroke
				(width 0.1)
				(type default)
			)
			(layer "F.SilkS")
		)
		(fp_line
			(start 12.996926 -5.137658)
			(end 12.149836 -4.325112)
			(stroke
				(width 0.1)
				(type default)
			)
			(layer "F.SilkS")
		)
		(fp_line
			(start 13.01369 -0.882904)
			(end 13.073634 -0.882904)
			(stroke
				(width 0.1)
				(type default)
			)
			(layer "F.SilkS")
		)
		(fp_line
			(start 13.01369 -0.882904)
			(end 13.073634 -0.882904)
			(stroke
				(width 0.1)
				(type default)
			)
			(layer "F.SilkS")
		)
		(fp_line
			(start 13.01369 -0.882904)
			(end 13.264134 -1.123188)
			(stroke
				(width 0.1)
				(type default)
			)
			(layer "F.SilkS")
		)
		(fp_line
			(start 13.01369 -0.882904)
			(end 13.264134 -1.123188)
			(stroke
				(width 0.1)
				(type default)
			)
			(layer "F.SilkS")
		)
		(fp_line
			(start 13.038074 -5.11937)
			(end 12.205462 -4.320794)
			(stroke
				(width 0.1)
				(type default)
			)
			(layer "F.SilkS")
		)
		(fp_line
			(start 13.038074 -5.11937)
			(end 12.205462 -4.320794)
			(stroke
				(width 0.1)
				(type default)
			)
			(layer "F.SilkS")
		)
		(fp_line
			(start 13.073634 -0.882904)
			(end 13.133578 -0.882904)
			(stroke
				(width 0.1)
				(type default)
			)
			(layer "F.SilkS")
		)
		(fp_line
			(start 13.073634 -0.882904)
			(end 13.133578 -0.882904)
			(stroke
				(width 0.1)
				(type default)
			)
			(layer "F.SilkS")
		)
		(fp_line
			(start 13.073634 -0.882904)
			(end 13.251942 -1.053846)
			(stroke
				(width 0.1)
				(type default)
			)
			(layer "F.SilkS")
		)
		(fp_line
			(start 13.073634 -0.882904)
			(end 13.251942 -1.053846)
			(stroke
				(width 0.1)
				(type default)
			)
			(layer "F.SilkS")
		)
		(fp_line
			(start 13.079222 -5.101336)
			(end 12.256008 -4.311396)
			(stroke
				(width 0.1)
				(type default)
			)
			(layer "F.SilkS")
		)
		(fp_line
			(start 13.079222 -5.101336)
			(end 12.256008 -4.311396)
			(stroke
				(width 0.1)
				(type default)
			)
			(layer "F.SilkS")
		)
		(fp_line
			(start 13.120116 -5.083048)
			(end 12.302998 -4.29895)
			(stroke
				(width 0.1)
				(type default)
			)
			(layer "F.SilkS")
		)
		(fp_line
			(start 13.120116 -5.083048)
			(end 12.302998 -4.29895)
			(stroke
				(width 0.1)
				(type default)
			)
			(layer "F.SilkS")
		)
		(fp_line
			(start 13.133578 -0.882904)
			(end 13.19403 -0.882904)
			(stroke
				(width 0.1)
				(type default)
			)
			(layer "F.SilkS")
		)
		(fp_line
			(start 13.133578 -0.882904)
			(end 13.19403 -0.882904)
			(stroke
				(width 0.1)
				(type default)
			)
			(layer "F.SilkS")
		)
		(fp_line
			(start 13.133578 -0.882904)
			(end 13.23975 -0.984504)
			(stroke
				(width 0.1)
				(type default)
			)
			(layer "F.SilkS")
		)
		(fp_line
			(start 13.133578 -0.882904)
			(end 13.23975 -0.984504)
			(stroke
				(width 0.1)
				(type default)
			)
			(layer "F.SilkS")
		)
		(fp_line
			(start 13.161518 -5.06476)
			(end 12.34948 -4.285742)
			(stroke
				(width 0.1)
				(type default)
			)
			(layer "F.SilkS")
		)
		(fp_line
			(start 13.161518 -5.06476)
			(end 12.34948 -4.285742)
			(stroke
				(width 0.1)
				(type default)
			)
			(layer "F.SilkS")
		)
		(fp_line
			(start 13.19403 -0.882904)
			(end 13.22197 -0.882904)
			(stroke
				(width 0.1)
				(type default)
			)
			(layer "F.SilkS")
		)
		(fp_line
			(start 13.19403 -0.882904)
			(end 13.22197 -0.882904)
			(stroke
				(width 0.1)
				(type default)
			)
			(layer "F.SilkS")
		)
		(fp_line
			(start 13.19403 -0.882904)
			(end 13.227812 -0.914908)
			(stroke
				(width 0.1)
				(type default)
			)
			(layer "F.SilkS")
		)
		(fp_line
			(start 13.19403 -0.882904)
			(end 13.227812 -0.914908)
			(stroke
				(width 0.1)
				(type default)
			)
			(layer "F.SilkS")
		)
		(fp_line
			(start 13.20292 -5.046472)
			(end 12.388596 -4.265422)
			(stroke
				(width 0.1)
				(type default)
			)
			(layer "F.SilkS")
		)
		(fp_line
			(start 13.20292 -5.046472)
			(end 12.388596 -4.265422)
			(stroke
				(width 0.1)
				(type default)
			)
			(layer "F.SilkS")
		)
		(fp_line
			(start 13.22197 -0.882904)
			(end 13.227812 -0.914908)
			(stroke
				(width 0.1)
				(type default)
			)
			(layer "F.SilkS")
		)
		(fp_line
			(start 13.22197 -0.882904)
			(end 13.227812 -0.914908)
			(stroke
				(width 0.1)
				(type default)
			)
			(layer "F.SilkS")
		)
		(fp_line
			(start 13.227812 -0.914908)
			(end 13.23975 -0.984504)
			(stroke
				(width 0.1)
				(type default)
			)
			(layer "F.SilkS")
		)
		(fp_line
			(start 13.227812 -0.914908)
			(end 13.23975 -0.984504)
			(stroke
				(width 0.1)
				(type default)
			)
			(layer "F.SilkS")
		)
		(fp_line
			(start 13.238988 -5.023612)
			(end 12.427458 -4.245102)
			(stroke
				(width 0.1)
				(type default)
			)
			(layer "F.SilkS")
		)
		(fp_line
			(start 13.238988 -5.023612)
			(end 12.427458 -4.245102)
			(stroke
				(width 0.1)
				(type default)
			)
			(layer "F.SilkS")
		)
		(fp_line
			(start 13.23975 -0.984504)
			(end 13.251942 -1.053846)
			(stroke
				(width 0.1)
				(type default)
			)
			(layer "F.SilkS")
		)
		(fp_line
			(start 13.23975 -0.984504)
			(end 13.251942 -1.053846)
			(stroke
				(width 0.1)
				(type default)
			)
			(layer "F.SilkS")
		)
		(fp_line
			(start 13.251942 -1.053846)
			(end 13.264134 -1.123188)
			(stroke
				(width 0.1)
				(type default)
			)
			(layer "F.SilkS")
		)
		(fp_line
			(start 13.251942 -1.053846)
			(end 13.264134 -1.123188)
			(stroke
				(width 0.1)
				(type default)
			)
			(layer "F.SilkS")
		)
		(fp_line
			(start 13.264134 -1.123188)
			(end 13.275818 -1.19253)
			(stroke
				(width 0.1)
				(type default)
			)
			(layer "F.SilkS")
		)
		(fp_line
			(start 13.264134 -1.123188)
			(end 13.275818 -1.19253)
			(stroke
				(width 0.1)
				(type default)
			)
			(layer "F.SilkS")
		)
		(fp_line
			(start 13.272516 -4.998212)
			(end 12.461748 -4.22021)
			(stroke
				(width 0.1)
				(type default)
			)
			(layer "F.SilkS")
		)
		(fp_line
			(start 13.272516 -4.998212)
			(end 12.461748 -4.22021)
			(stroke
				(width 0.1)
				(type default)
			)
			(layer "F.SilkS")
		)
		(fp_line
			(start 13.275818 -1.19253)
			(end 13.288264 -1.262126)
			(stroke
				(width 0.1)
				(type default)
			)
			(layer "F.SilkS")
		)
		(fp_line
			(start 13.275818 -1.19253)
			(end 13.288264 -1.262126)
			(stroke
				(width 0.1)
				(type default)
			)
			(layer "F.SilkS")
		)
		(fp_line
			(start 13.288264 -1.262126)
			(end 13.30071 -1.331468)
			(stroke
				(width 0.1)
				(type default)
			)
			(layer "F.SilkS")
		)
		(fp_line
			(start 13.288264 -1.262126)
			(end 13.30071 -1.331468)
			(stroke
				(width 0.1)
				(type default)
			)
			(layer "F.SilkS")
		)
		(fp_line
			(start 13.30071 -1.331468)
			(end 13.312394 -1.400556)
			(stroke
				(width 0.1)
				(type default)
			)
			(layer "F.SilkS")
		)
		(fp_line
			(start 13.30071 -1.331468)
			(end 13.312394 -1.400556)
			(stroke
				(width 0.1)
				(type default)
			)
			(layer "F.SilkS")
		)
		(fp_line
			(start 13.306298 -4.972812)
			(end 12.49299 -4.192524)
			(stroke
				(width 0.1)
				(type default)
			)
			(layer "F.SilkS")
		)
		(fp_line
			(start 13.306298 -4.972812)
			(end 12.49299 -4.192524)
			(stroke
				(width 0.1)
				(type default)
			)
			(layer "F.SilkS")
		)
		(fp_line
			(start 13.312394 -1.400556)
			(end 13.32484 -1.470152)
			(stroke
				(width 0.1)
				(type default)
			)
			(layer "F.SilkS")
		)
		(fp_line
			(start 13.312394 -1.400556)
			(end 13.32484 -1.470152)
			(stroke
				(width 0.1)
				(type default)
			)
			(layer "F.SilkS")
		)
		(fp_line
			(start 13.32484 -1.470152)
			(end 13.337286 -1.539494)
			(stroke
				(width 0.1)
				(type default)
			)
			(layer "F.SilkS")
		)
		(fp_line
			(start 13.32484 -1.470152)
			(end 13.337286 -1.539494)
			(stroke
				(width 0.1)
				(type default)
			)
			(layer "F.SilkS")
		)
		(fp_line
			(start 13.337286 -1.539494)
			(end 13.34897 -1.608836)
			(stroke
				(width 0.1)
				(type default)
			)
			(layer "F.SilkS")
		)
		(fp_line
			(start 13.337286 -1.539494)
			(end 13.34897 -1.608836)
			(stroke
				(width 0.1)
				(type default)
			)
			(layer "F.SilkS")
		)
		(fp_line
			(start 13.34008 -4.947412)
			(end 12.522454 -4.16306)
			(stroke
				(width 0.1)
				(type default)
			)
			(layer "F.SilkS")
		)
		(fp_line
			(start 13.34008 -4.947412)
			(end 12.522454 -4.16306)
			(stroke
				(width 0.1)
				(type default)
			)
			(layer "F.SilkS")
		)
		(fp_line
			(start 13.34897 -1.608836)
			(end 13.361416 -1.678178)
			(stroke
				(width 0.1)
				(type default)
			)
			(layer "F.SilkS")
		)
		(fp_line
			(start 13.34897 -1.608836)
			(end 13.361416 -1.678178)
			(stroke
				(width 0.1)
				(type default)
			)
			(layer "F.SilkS")
		)
		(fp_line
			(start 13.361416 -1.678178)
			(end 13.373354 -1.74752)
			(stroke
				(width 0.1)
				(type default)
			)
			(layer "F.SilkS")
		)
		(fp_line
			(start 13.361416 -1.678178)
			(end 13.373354 -1.74752)
			(stroke
				(width 0.1)
				(type default)
			)
			(layer "F.SilkS")
		)
		(fp_line
			(start 13.373354 -1.74752)
			(end 13.385546 -1.817116)
			(stroke
				(width 0.1)
				(type default)
			)
			(layer "F.SilkS")
		)
		(fp_line
			(start 13.373354 -1.74752)
			(end 13.385546 -1.817116)
			(stroke
				(width 0.1)
				(type default)
			)
			(layer "F.SilkS")
		)
		(fp_line
			(start 13.373862 -4.922012)
			(end 12.545822 -4.127754)
			(stroke
				(width 0.1)
				(type default)
			)
			(layer "F.SilkS")
		)
		(fp_line
			(start 13.373862 -4.922012)
			(end 12.545822 -4.127754)
			(stroke
				(width 0.1)
				(type default)
			)
			(layer "F.SilkS")
		)
		(fp_line
			(start 13.385546 -1.817116)
			(end 13.397992 -1.886458)
			(stroke
				(width 0.1)
				(type default)
			)
			(layer "F.SilkS")
		)
		(fp_line
			(start 13.385546 -1.817116)
			(end 13.397992 -1.886458)
			(stroke
				(width 0.1)
				(type default)
			)
			(layer "F.SilkS")
		)
		(fp_line
			(start 13.397992 -1.886458)
			(end 13.40993 -1.9558)
			(stroke
				(width 0.1)
				(type default)
			)
			(layer "F.SilkS")
		)
		(fp_line
			(start 13.397992 -1.886458)
			(end 13.40993 -1.9558)
			(stroke
				(width 0.1)
				(type default)
			)
			(layer "F.SilkS")
		)
		(fp_line
			(start 13.407136 -4.896358)
			(end 12.568936 -4.092194)
			(stroke
				(width 0.1)
				(type default)
			)
			(layer "F.SilkS")
		)
		(fp_line
			(start 13.407136 -4.896358)
			(end 12.568936 -4.092194)
			(stroke
				(width 0.1)
				(type default)
			)
			(layer "F.SilkS")
		)
		(fp_line
			(start 13.40993 -1.9558)
			(end 13.422122 -2.025396)
			(stroke
				(width 0.1)
				(type default)
			)
			(layer "F.SilkS")
		)
		(fp_line
			(start 13.40993 -1.9558)
			(end 13.422122 -2.025396)
			(stroke
				(width 0.1)
				(type default)
			)
			(layer "F.SilkS")
		)
		(fp_line
			(start 13.422122 -2.025396)
			(end 13.434314 -2.094738)
			(stroke
				(width 0.1)
				(type default)
			)
			(layer "F.SilkS")
		)
		(fp_line
			(start 13.422122 -2.025396)
			(end 13.434314 -2.094738)
			(stroke
				(width 0.1)
				(type default)
			)
			(layer "F.SilkS")
		)
		(fp_line
			(start 13.434314 -2.094738)
			(end 13.446506 -2.163826)
			(stroke
				(width 0.1)
				(type default)
			)
			(layer "F.SilkS")
		)
		(fp_line
			(start 13.434314 -2.094738)
			(end 13.446506 -2.163826)
			(stroke
				(width 0.1)
				(type default)
			)
			(layer "F.SilkS")
		)
		(fp_line
			(start 13.440664 -4.871212)
			(end 12.58443 -4.049522)
			(stroke
				(width 0.1)
				(type default)
			)
			(layer "F.SilkS")
		)
		(fp_line
			(start 13.440664 -4.871212)
			(end 12.58443 -4.049522)
			(stroke
				(width 0.1)
				(type default)
			)
			(layer "F.SilkS")
		)
		(fp_line
			(start 13.446506 -2.163826)
			(end 13.458444 -2.233422)
			(stroke
				(width 0.1)
				(type default)
			)
			(layer "F.SilkS")
		)
		(fp_line
			(start 13.446506 -2.163826)
			(end 13.458444 -2.233422)
			(stroke
				(width 0.1)
				(type default)
			)
			(layer "F.SilkS")
		)
		(fp_line
			(start 13.458444 -2.233422)
			(end 13.47089 -2.302764)
			(stroke
				(width 0.1)
				(type default)
			)
			(layer "F.SilkS")
		)
		(fp_line
			(start 13.458444 -2.233422)
			(end 13.47089 -2.302764)
			(stroke
				(width 0.1)
				(type default)
			)
			(layer "F.SilkS")
		)
		(fp_line
			(start 13.466826 -4.837938)
			(end 12.599162 -4.005834)
			(stroke
				(width 0.1)
				(type default)
			)
			(layer "F.SilkS")
		)
		(fp_line
			(start 13.466826 -4.837938)
			(end 12.599162 -4.005834)
			(stroke
				(width 0.1)
				(type default)
			)
			(layer "F.SilkS")
		)
		(fp_line
			(start 13.47089 -2.302764)
			(end 13.483082 -2.372106)
			(stroke
				(width 0.1)
				(type default)
			)
			(layer "F.SilkS")
		)
		(fp_line
			(start 13.47089 -2.302764)
			(end 13.483082 -2.372106)
			(stroke
				(width 0.1)
				(type default)
			)
			(layer "F.SilkS")
		)
		(fp_line
			(start 13.483082 -2.372106)
			(end 13.49502 -2.441448)
			(stroke
				(width 0.1)
				(type default)
			)
			(layer "F.SilkS")
		)
		(fp_line
			(start 13.483082 -2.372106)
			(end 13.49502 -2.441448)
			(stroke
				(width 0.1)
				(type default)
			)
			(layer "F.SilkS")
		)
		(fp_line
			(start 13.492226 -4.804918)
			(end 12.606782 -3.955288)
			(stroke
				(width 0.1)
				(type default)
			)
			(layer "F.SilkS")
		)
		(fp_line
			(start 13.492226 -4.804918)
			(end 12.606782 -3.955288)
			(stroke
				(width 0.1)
				(type default)
			)
			(layer "F.SilkS")
		)
		(fp_line
			(start 13.49502 -2.441448)
			(end 13.507466 -2.51079)
			(stroke
				(width 0.1)
				(type default)
			)
			(layer "F.SilkS")
		)
		(fp_line
			(start 13.49502 -2.441448)
			(end 13.507466 -2.51079)
			(stroke
				(width 0.1)
				(type default)
			)
			(layer "F.SilkS")
		)
		(fp_line
			(start 13.507466 -2.51079)
			(end 13.519404 -2.580386)
			(stroke
				(width 0.1)
				(type default)
			)
			(layer "F.SilkS")
		)
		(fp_line
			(start 13.507466 -2.51079)
			(end 13.519404 -2.580386)
			(stroke
				(width 0.1)
				(type default)
			)
			(layer "F.SilkS")
		)
		(fp_line
			(start 13.518134 -4.771898)
			(end 12.612116 -3.902964)
			(stroke
				(width 0.1)
				(type default)
			)
			(layer "F.SilkS")
		)
		(fp_line
			(start 13.518134 -4.771898)
			(end 12.612116 -3.902964)
			(stroke
				(width 0.1)
				(type default)
			)
			(layer "F.SilkS")
		)
		(fp_line
			(start 13.519404 -2.580386)
			(end 13.531596 -2.649728)
			(stroke
				(width 0.1)
				(type default)
			)
			(layer "F.SilkS")
		)
		(fp_line
			(start 13.519404 -2.580386)
			(end 13.531596 -2.649728)
			(stroke
				(width 0.1)
				(type default)
			)
			(layer "F.SilkS")
		)
		(fp_line
			(start 13.531596 -2.649728)
			(end 13.544042 -2.71907)
			(stroke
				(width 0.1)
				(type default)
			)
			(layer "F.SilkS")
		)
		(fp_line
			(start 13.531596 -2.649728)
			(end 13.544042 -2.71907)
			(stroke
				(width 0.1)
				(type default)
			)
			(layer "F.SilkS")
		)
		(fp_line
			(start 13.544042 -4.738878)
			(end 12.60856 -3.84175)
			(stroke
				(width 0.1)
				(type default)
			)
			(layer "F.SilkS")
		)
		(fp_line
			(start 13.544042 -4.738878)
			(end 12.60856 -3.84175)
			(stroke
				(width 0.1)
				(type default)
			)
			(layer "F.SilkS")
		)
		(fp_line
			(start 13.544042 -2.71907)
			(end 13.55598 -2.788412)
			(stroke
				(width 0.1)
				(type default)
			)
			(layer "F.SilkS")
		)
		(fp_line
			(start 13.544042 -2.71907)
			(end 13.55598 -2.788412)
			(stroke
				(width 0.1)
				(type default)
			)
			(layer "F.SilkS")
		)
		(fp_line
			(start 13.55598 -2.788412)
			(end 13.568172 -2.857754)
			(stroke
				(width 0.1)
				(type default)
			)
			(layer "F.SilkS")
		)
		(fp_line
			(start 13.55598 -2.788412)
			(end 13.568172 -2.857754)
			(stroke
				(width 0.1)
				(type default)
			)
			(layer "F.SilkS")
		)
		(fp_line
			(start 13.568172 -2.857754)
			(end 13.580364 -2.927096)
			(stroke
				(width 0.1)
				(type default)
			)
			(layer "F.SilkS")
		)
		(fp_line
			(start 13.568172 -2.857754)
			(end 13.580364 -2.927096)
			(stroke
				(width 0.1)
				(type default)
			)
			(layer "F.SilkS")
		)
		(fp_line
			(start 13.569442 -4.705858)
			(end 12.601956 -3.777996)
			(stroke
				(width 0.1)
				(type default)
			)
			(layer "F.SilkS")
		)
		(fp_line
			(start 13.569442 -4.705858)
			(end 12.601956 -3.777996)
			(stroke
				(width 0.1)
				(type default)
			)
			(layer "F.SilkS")
		)
		(fp_line
			(start 13.580364 -2.927096)
			(end 13.592556 -2.996692)
			(stroke
				(width 0.1)
				(type default)
			)
			(layer "F.SilkS")
		)
		(fp_line
			(start 13.580364 -2.927096)
			(end 13.592556 -2.996692)
			(stroke
				(width 0.1)
				(type default)
			)
			(layer "F.SilkS")
		)
		(fp_line
			(start 13.592556 -2.996692)
			(end 13.604494 -3.06578)
			(stroke
				(width 0.1)
				(type default)
			)
			(layer "F.SilkS")
		)
		(fp_line
			(start 13.592556 -2.996692)
			(end 13.604494 -3.06578)
			(stroke
				(width 0.1)
				(type default)
			)
			(layer "F.SilkS")
		)
		(fp_line
			(start 13.59535 -4.672838)
			(end 12.590018 -3.708654)
			(stroke
				(width 0.1)
				(type default)
			)
			(layer "F.SilkS")
		)
		(fp_line
			(start 13.59535 -4.672838)
			(end 12.590018 -3.708654)
			(stroke
				(width 0.1)
				(type default)
			)
			(layer "F.SilkS")
		)
		(fp_line
			(start 13.604494 -3.06578)
			(end 13.61694 -3.135376)
			(stroke
				(width 0.1)
				(type default)
			)
			(layer "F.SilkS")
		)
		(fp_line
			(start 13.604494 -3.06578)
			(end 13.61694 -3.135376)
			(stroke
				(width 0.1)
				(type default)
			)
			(layer "F.SilkS")
		)
		(fp_line
			(start 13.616432 -4.635246)
			(end 12.57808 -3.639312)
			(stroke
				(width 0.1)
				(type default)
			)
			(layer "F.SilkS")
		)
		(fp_line
			(start 13.616432 -4.635246)
			(end 12.57808 -3.639312)
			(stroke
				(width 0.1)
				(type default)
			)
			(layer "F.SilkS")
		)
		(fp_line
			(start 13.61694 -3.135376)
			(end 13.629132 -3.204972)
			(stroke
				(width 0.1)
				(type default)
			)
			(layer "F.SilkS")
		)
		(fp_line
			(start 13.61694 -3.135376)
			(end 13.629132 -3.204972)
			(stroke
				(width 0.1)
				(type default)
			)
			(layer "F.SilkS")
		)
		(fp_line
			(start 13.629132 -3.204972)
			(end 13.64107 -3.27406)
			(stroke
				(width 0.1)
				(type default)
			)
			(layer "F.SilkS")
		)
		(fp_line
			(start 13.629132 -3.204972)
			(end 13.64107 -3.27406)
			(stroke
				(width 0.1)
				(type default)
			)
			(layer "F.SilkS")
		)
		(fp_line
			(start 13.633196 -4.593844)
			(end 11.82116 -2.855722)
			(stroke
				(width 0.1)
				(type default)
			)
			(layer "F.SilkS")
		)
		(fp_line
			(start 13.633196 -4.593844)
			(end 11.82116 -2.855722)
			(stroke
				(width 0.1)
				(type default)
			)
			(layer "F.SilkS")
		)
		(fp_line
			(start 13.64996 -4.552442)
			(end 11.877548 -2.851912)
			(stroke
				(width 0.1)
				(type default)
			)
			(layer "F.SilkS")
		)
		(fp_line
			(start 13.64996 -4.552442)
			(end 11.877548 -2.851912)
			(stroke
				(width 0.1)
				(type default)
			)
			(layer "F.SilkS")
		)
		(fp_line
			(start 13.653516 -3.343402)
			(end 13.64107 -3.27406)
			(stroke
				(width 0.1)
				(type default)
			)
			(layer "F.SilkS")
		)
		(fp_line
			(start 13.653516 -3.343402)
			(end 13.64107 -3.27406)
			(stroke
				(width 0.1)
				(type default)
			)
			(layer "F.SilkS")
		)
		(fp_line
			(start 13.665708 -3.412998)
			(end 10.943336 -0.801624)
			(stroke
				(width 0.1)
				(type default)
			)
			(layer "F.SilkS")
		)
		(fp_line
			(start 13.665708 -3.412998)
			(end 10.943336 -0.801624)
			(stroke
				(width 0.1)
				(type default)
			)
			(layer "F.SilkS")
		)
		(fp_line
			(start 13.665708 -3.412998)
			(end 13.653516 -3.343402)
			(stroke
				(width 0.1)
				(type default)
			)
			(layer "F.SilkS")
		)
		(fp_line
			(start 13.665708 -3.412998)
			(end 13.653516 -3.343402)
			(stroke
				(width 0.1)
				(type default)
			)
			(layer "F.SilkS")
		)
		(fp_line
			(start 13.667232 -4.51104)
			(end 11.93292 -2.84734)
			(stroke
				(width 0.1)
				(type default)
			)
			(layer "F.SilkS")
		)
		(fp_line
			(start 13.667232 -4.51104)
			(end 11.93292 -2.84734)
			(stroke
				(width 0.1)
				(type default)
			)
			(layer "F.SilkS")
		)
		(fp_line
			(start 13.677646 -3.48234)
			(end 12.323064 -2.182622)
			(stroke
				(width 0.1)
				(type default)
			)
			(layer "F.SilkS")
		)
		(fp_line
			(start 13.677646 -3.48234)
			(end 12.323064 -2.182622)
			(stroke
				(width 0.1)
				(type default)
			)
			(layer "F.SilkS")
		)
		(fp_line
			(start 13.677646 -3.48234)
			(end 13.665708 -3.412998)
			(stroke
				(width 0.1)
				(type default)
			)
			(layer "F.SilkS")
		)
		(fp_line
			(start 13.677646 -3.48234)
			(end 13.665708 -3.412998)
			(stroke
				(width 0.1)
				(type default)
			)
			(layer "F.SilkS")
		)
		(fp_line
			(start 13.684504 -4.469638)
			(end 11.986006 -2.840482)
			(stroke
				(width 0.1)
				(type default)
			)
			(layer "F.SilkS")
		)
		(fp_line
			(start 13.684504 -4.469638)
			(end 11.986006 -2.840482)
			(stroke
				(width 0.1)
				(type default)
			)
			(layer "F.SilkS")
		)
		(fp_line
			(start 13.690092 -3.551682)
			(end 12.335002 -2.251964)
			(stroke
				(width 0.1)
				(type default)
			)
			(layer "F.SilkS")
		)
		(fp_line
			(start 13.690092 -3.551682)
			(end 12.335002 -2.251964)
			(stroke
				(width 0.1)
				(type default)
			)
			(layer "F.SilkS")
		)
		(fp_line
			(start 13.690092 -3.551682)
			(end 13.677646 -3.48234)
			(stroke
				(width 0.1)
				(type default)
			)
			(layer "F.SilkS")
		)
		(fp_line
			(start 13.690092 -3.551682)
			(end 13.677646 -3.48234)
			(stroke
				(width 0.1)
				(type default)
			)
			(layer "F.SilkS")
		)
		(fp_line
			(start 13.701014 -4.42849)
			(end 12.037822 -2.832862)
			(stroke
				(width 0.1)
				(type default)
			)
			(layer "F.SilkS")
		)
		(fp_line
			(start 13.701014 -4.42849)
			(end 12.037822 -2.832862)
			(stroke
				(width 0.1)
				(type default)
			)
			(layer "F.SilkS")
		)
		(fp_line
			(start 13.70203 -3.621024)
			(end 12.347194 -2.321306)
			(stroke
				(width 0.1)
				(type default)
			)
			(layer "F.SilkS")
		)
		(fp_line
			(start 13.70203 -3.621024)
			(end 12.347194 -2.321306)
			(stroke
				(width 0.1)
				(type default)
			)
			(layer "F.SilkS")
		)
		(fp_line
			(start 13.70203 -3.621024)
			(end 13.690092 -3.551682)
			(stroke
				(width 0.1)
				(type default)
			)
			(layer "F.SilkS")
		)
		(fp_line
			(start 13.70203 -3.621024)
			(end 13.690092 -3.551682)
			(stroke
				(width 0.1)
				(type default)
			)
			(layer "F.SilkS")
		)
		(fp_line
			(start 13.714222 -3.690366)
			(end 12.359386 -2.390902)
			(stroke
				(width 0.1)
				(type default)
			)
			(layer "F.SilkS")
		)
		(fp_line
			(start 13.714222 -3.690366)
			(end 12.359386 -2.390902)
			(stroke
				(width 0.1)
				(type default)
			)
			(layer "F.SilkS")
		)
		(fp_line
			(start 13.714222 -3.690366)
			(end 13.70203 -3.621024)
			(stroke
				(width 0.1)
				(type default)
			)
			(layer "F.SilkS")
		)
		(fp_line
			(start 13.714222 -3.690366)
			(end 13.70203 -3.621024)
			(stroke
				(width 0.1)
				(type default)
			)
			(layer "F.SilkS")
		)
		(fp_line
			(start 13.715238 -4.383786)
			(end 12.087352 -2.822448)
			(stroke
				(width 0.1)
				(type default)
			)
			(layer "F.SilkS")
		)
		(fp_line
			(start 13.715238 -4.383786)
			(end 12.087352 -2.822448)
			(stroke
				(width 0.1)
				(type default)
			)
			(layer "F.SilkS")
		)
		(fp_line
			(start 13.722096 -4.332732)
			(end 12.135612 -2.810764)
			(stroke
				(width 0.1)
				(type default)
			)
			(layer "F.SilkS")
		)
		(fp_line
			(start 13.722096 -4.332732)
			(end 12.135612 -2.810764)
			(stroke
				(width 0.1)
				(type default)
			)
			(layer "F.SilkS")
		)
		(fp_line
			(start 13.72616 -3.759962)
			(end 12.371578 -2.460244)
			(stroke
				(width 0.1)
				(type default)
			)
			(layer "F.SilkS")
		)
		(fp_line
			(start 13.72616 -3.759962)
			(end 12.371578 -2.460244)
			(stroke
				(width 0.1)
				(type default)
			)
			(layer "F.SilkS")
		)
		(fp_line
			(start 13.729208 -4.281932)
			(end 12.181078 -2.796794)
			(stroke
				(width 0.1)
				(type default)
			)
			(layer "F.SilkS")
		)
		(fp_line
			(start 13.729208 -4.281932)
			(end 12.181078 -2.796794)
			(stroke
				(width 0.1)
				(type default)
			)
			(layer "F.SilkS")
		)
		(fp_line
			(start 13.731494 -3.822446)
			(end 12.38377 -2.529586)
			(stroke
				(width 0.1)
				(type default)
			)
			(layer "F.SilkS")
		)
		(fp_line
			(start 13.731494 -3.822446)
			(end 12.38377 -2.529586)
			(stroke
				(width 0.1)
				(type default)
			)
			(layer "F.SilkS")
		)
		(fp_line
			(start 13.73632 -4.230878)
			(end 12.224766 -2.781046)
			(stroke
				(width 0.1)
				(type default)
			)
			(layer "F.SilkS")
		)
		(fp_line
			(start 13.73632 -4.230878)
			(end 12.224766 -2.781046)
			(stroke
				(width 0.1)
				(type default)
			)
			(layer "F.SilkS")
		)
		(fp_line
			(start 13.736574 -3.88493)
			(end 12.395962 -2.598928)
			(stroke
				(width 0.1)
				(type default)
			)
			(layer "F.SilkS")
		)
		(fp_line
			(start 13.736574 -3.88493)
			(end 12.395962 -2.598928)
			(stroke
				(width 0.1)
				(type default)
			)
			(layer "F.SilkS")
		)
		(fp_line
			(start 13.741654 -3.947668)
			(end 12.408154 -2.668524)
			(stroke
				(width 0.1)
				(type default)
			)
			(layer "F.SilkS")
		)
		(fp_line
			(start 13.741654 -3.947668)
			(end 12.408154 -2.668524)
			(stroke
				(width 0.1)
				(type default)
			)
			(layer "F.SilkS")
		)
		(fp_line
			(start 13.743178 -4.179824)
			(end 12.266422 -2.76352)
			(stroke
				(width 0.1)
				(type default)
			)
			(layer "F.SilkS")
		)
		(fp_line
			(start 13.743178 -4.179824)
			(end 12.266422 -2.76352)
			(stroke
				(width 0.1)
				(type default)
			)
			(layer "F.SilkS")
		)
		(fp_line
			(start 13.74648 -4.010152)
			(end 12.380214 -2.699512)
			(stroke
				(width 0.1)
				(type default)
			)
			(layer "F.SilkS")
		)
		(fp_line
			(start 13.74648 -4.010152)
			(end 12.380214 -2.699512)
			(stroke
				(width 0.1)
				(type default)
			)
			(layer "F.SilkS")
		)
		(fp_line
			(start 13.750036 -4.12877)
			(end 12.306046 -2.743454)
			(stroke
				(width 0.1)
				(type default)
			)
			(layer "F.SilkS")
		)
		(fp_line
			(start 13.750036 -4.12877)
			(end 12.306046 -2.743454)
			(stroke
				(width 0.1)
				(type default)
			)
			(layer "F.SilkS")
		)
		(fp_line
			(start 13.751814 -4.072636)
			(end 12.344654 -2.722626)
			(stroke
				(width 0.1)
				(type default)
			)
			(layer "F.SilkS")
		)
		(fp_line
			(start 13.751814 -4.072636)
			(end 12.344654 -2.722626)
			(stroke
				(width 0.1)
				(type default)
			)
			(layer "F.SilkS")
		)
		(fp_line
			(start 13.944854 -0.882904)
			(end 13.976096 -0.882904)
			(stroke
				(width 0.1)
				(type default)
			)
			(layer "F.SilkS")
		)
		(fp_line
			(start 13.944854 -0.882904)
			(end 13.976096 -0.882904)
			(stroke
				(width 0.1)
				(type default)
			)
			(layer "F.SilkS")
		)
		(fp_line
			(start 13.95095 -0.916178)
			(end 13.944854 -0.882904)
			(stroke
				(width 0.1)
				(type default)
			)
			(layer "F.SilkS")
		)
		(fp_line
			(start 13.95095 -0.916178)
			(end 13.944854 -0.882904)
			(stroke
				(width 0.1)
				(type default)
			)
			(layer "F.SilkS")
		)
		(fp_line
			(start 13.95095 -0.916178)
			(end 15.307056 -2.21742)
			(stroke
				(width 0.1)
				(type default)
			)
			(layer "F.SilkS")
		)
		(fp_line
			(start 13.95095 -0.916178)
			(end 15.307056 -2.21742)
			(stroke
				(width 0.1)
				(type default)
			)
			(layer "F.SilkS")
		)
		(fp_line
			(start 13.962888 -0.985774)
			(end 13.95095 -0.916178)
			(stroke
				(width 0.1)
				(type default)
			)
			(layer "F.SilkS")
		)
		(fp_line
			(start 13.962888 -0.985774)
			(end 13.95095 -0.916178)
			(stroke
				(width 0.1)
				(type default)
			)
			(layer "F.SilkS")
		)
		(fp_line
			(start 13.962888 -0.985774)
			(end 15.319248 -2.286762)
			(stroke
				(width 0.1)
				(type default)
			)
			(layer "F.SilkS")
		)
		(fp_line
			(start 13.962888 -0.985774)
			(end 15.319248 -2.286762)
			(stroke
				(width 0.1)
				(type default)
			)
			(layer "F.SilkS")
		)
		(fp_line
			(start 13.975334 -1.055116)
			(end 13.962888 -0.985774)
			(stroke
				(width 0.1)
				(type default)
			)
			(layer "F.SilkS")
		)
		(fp_line
			(start 13.975334 -1.055116)
			(end 13.962888 -0.985774)
			(stroke
				(width 0.1)
				(type default)
			)
			(layer "F.SilkS")
		)
		(fp_line
			(start 13.975334 -1.055116)
			(end 15.331186 -2.356104)
			(stroke
				(width 0.1)
				(type default)
			)
			(layer "F.SilkS")
		)
		(fp_line
			(start 13.975334 -1.055116)
			(end 15.331186 -2.356104)
			(stroke
				(width 0.1)
				(type default)
			)
			(layer "F.SilkS")
		)
		(fp_line
			(start 13.976096 -0.882904)
			(end 14.036294 -0.882904)
			(stroke
				(width 0.1)
				(type default)
			)
			(layer "F.SilkS")
		)
		(fp_line
			(start 13.976096 -0.882904)
			(end 14.036294 -0.882904)
			(stroke
				(width 0.1)
				(type default)
			)
			(layer "F.SilkS")
		)
		(fp_line
			(start 13.976096 -0.882904)
			(end 15.294864 -2.147824)
			(stroke
				(width 0.1)
				(type default)
			)
			(layer "F.SilkS")
		)
		(fp_line
			(start 13.976096 -0.882904)
			(end 15.294864 -2.147824)
			(stroke
				(width 0.1)
				(type default)
			)
			(layer "F.SilkS")
		)
		(fp_line
			(start 13.987272 -1.124458)
			(end 13.975334 -1.055116)
			(stroke
				(width 0.1)
				(type default)
			)
			(layer "F.SilkS")
		)
		(fp_line
			(start 13.987272 -1.124458)
			(end 13.975334 -1.055116)
			(stroke
				(width 0.1)
				(type default)
			)
			(layer "F.SilkS")
		)
		(fp_line
			(start 13.987272 -1.124458)
			(end 15.343632 -2.425446)
			(stroke
				(width 0.1)
				(type default)
			)
			(layer "F.SilkS")
		)
		(fp_line
			(start 13.987272 -1.124458)
			(end 15.343632 -2.425446)
			(stroke
				(width 0.1)
				(type default)
			)
			(layer "F.SilkS")
		)
		(fp_line
			(start 13.999464 -1.194054)
			(end 13.987272 -1.124458)
			(stroke
				(width 0.1)
				(type default)
			)
			(layer "F.SilkS")
		)
		(fp_line
			(start 13.999464 -1.194054)
			(end 13.987272 -1.124458)
			(stroke
				(width 0.1)
				(type default)
			)
			(layer "F.SilkS")
		)
		(fp_line
			(start 13.999464 -1.194054)
			(end 15.355824 -2.495042)
			(stroke
				(width 0.1)
				(type default)
			)
			(layer "F.SilkS")
		)
		(fp_line
			(start 13.999464 -1.194054)
			(end 15.355824 -2.495042)
			(stroke
				(width 0.1)
				(type default)
			)
			(layer "F.SilkS")
		)
		(fp_line
			(start 14.01191 -1.26365)
			(end 13.999464 -1.194054)
			(stroke
				(width 0.1)
				(type default)
			)
			(layer "F.SilkS")
		)
		(fp_line
			(start 14.01191 -1.26365)
			(end 13.999464 -1.194054)
			(stroke
				(width 0.1)
				(type default)
			)
			(layer "F.SilkS")
		)
		(fp_line
			(start 14.01191 -1.26365)
			(end 15.367762 -2.564384)
			(stroke
				(width 0.1)
				(type default)
			)
			(layer "F.SilkS")
		)
		(fp_line
			(start 14.01191 -1.26365)
			(end 15.367762 -2.564384)
			(stroke
				(width 0.1)
				(type default)
			)
			(layer "F.SilkS")
		)
		(fp_line
			(start 14.023848 -1.332738)
			(end 14.01191 -1.26365)
			(stroke
				(width 0.1)
				(type default)
			)
			(layer "F.SilkS")
		)
		(fp_line
			(start 14.023848 -1.332738)
			(end 14.01191 -1.26365)
			(stroke
				(width 0.1)
				(type default)
			)
			(layer "F.SilkS")
		)
		(fp_line
			(start 14.023848 -1.332738)
			(end 15.380208 -2.633726)
			(stroke
				(width 0.1)
				(type default)
			)
			(layer "F.SilkS")
		)
		(fp_line
			(start 14.023848 -1.332738)
			(end 15.380208 -2.633726)
			(stroke
				(width 0.1)
				(type default)
			)
			(layer "F.SilkS")
		)
		(fp_line
			(start 14.03604 -1.40208)
			(end 14.023848 -1.332738)
			(stroke
				(width 0.1)
				(type default)
			)
			(layer "F.SilkS")
		)
		(fp_line
			(start 14.03604 -1.40208)
			(end 14.023848 -1.332738)
			(stroke
				(width 0.1)
				(type default)
			)
			(layer "F.SilkS")
		)
		(fp_line
			(start 14.03604 -1.40208)
			(end 15.392654 -2.703322)
			(stroke
				(width 0.1)
				(type default)
			)
			(layer "F.SilkS")
		)
		(fp_line
			(start 14.03604 -1.40208)
			(end 15.392654 -2.703322)
			(stroke
				(width 0.1)
				(type default)
			)
			(layer "F.SilkS")
		)
		(fp_line
			(start 14.036294 -0.882904)
			(end 14.096238 -0.882904)
			(stroke
				(width 0.1)
				(type default)
			)
			(layer "F.SilkS")
		)
		(fp_line
			(start 14.036294 -0.882904)
			(end 14.096238 -0.882904)
			(stroke
				(width 0.1)
				(type default)
			)
			(layer "F.SilkS")
		)
		(fp_line
			(start 14.036294 -0.882904)
			(end 15.282418 -2.078482)
			(stroke
				(width 0.1)
				(type default)
			)
			(layer "F.SilkS")
		)
		(fp_line
			(start 14.036294 -0.882904)
			(end 15.282418 -2.078482)
			(stroke
				(width 0.1)
				(type default)
			)
			(layer "F.SilkS")
		)
		(fp_line
			(start 14.048232 -1.471676)
			(end 14.03604 -1.40208)
			(stroke
				(width 0.1)
				(type default)
			)
			(layer "F.SilkS")
		)
		(fp_line
			(start 14.048232 -1.471676)
			(end 14.03604 -1.40208)
			(stroke
				(width 0.1)
				(type default)
			)
			(layer "F.SilkS")
		)
		(fp_line
			(start 14.048232 -1.471676)
			(end 15.404592 -2.772664)
			(stroke
				(width 0.1)
				(type default)
			)
			(layer "F.SilkS")
		)
		(fp_line
			(start 14.048232 -1.471676)
			(end 15.404592 -2.772664)
			(stroke
				(width 0.1)
				(type default)
			)
			(layer "F.SilkS")
		)
		(fp_line
			(start 14.060678 -1.541018)
			(end 14.048232 -1.471676)
			(stroke
				(width 0.1)
				(type default)
			)
			(layer "F.SilkS")
		)
		(fp_line
			(start 14.060678 -1.541018)
			(end 14.048232 -1.471676)
			(stroke
				(width 0.1)
				(type default)
			)
			(layer "F.SilkS")
		)
		(fp_line
			(start 14.060678 -1.541018)
			(end 15.416784 -2.84226)
			(stroke
				(width 0.1)
				(type default)
			)
			(layer "F.SilkS")
		)
		(fp_line
			(start 14.060678 -1.541018)
			(end 15.416784 -2.84226)
			(stroke
				(width 0.1)
				(type default)
			)
			(layer "F.SilkS")
		)
		(fp_line
			(start 14.072362 -1.61036)
			(end 14.060678 -1.541018)
			(stroke
				(width 0.1)
				(type default)
			)
			(layer "F.SilkS")
		)
		(fp_line
			(start 14.072362 -1.61036)
			(end 14.060678 -1.541018)
			(stroke
				(width 0.1)
				(type default)
			)
			(layer "F.SilkS")
		)
		(fp_line
			(start 14.072362 -1.61036)
			(end 15.42923 -2.911602)
			(stroke
				(width 0.1)
				(type default)
			)
			(layer "F.SilkS")
		)
		(fp_line
			(start 14.072362 -1.61036)
			(end 15.42923 -2.911602)
			(stroke
				(width 0.1)
				(type default)
			)
			(layer "F.SilkS")
		)
		(fp_line
			(start 14.084808 -1.679702)
			(end 14.072362 -1.61036)
			(stroke
				(width 0.1)
				(type default)
			)
			(layer "F.SilkS")
		)
		(fp_line
			(start 14.084808 -1.679702)
			(end 14.072362 -1.61036)
			(stroke
				(width 0.1)
				(type default)
			)
			(layer "F.SilkS")
		)
		(fp_line
			(start 14.084808 -1.679702)
			(end 14.097254 -1.749044)
			(stroke
				(width 0.1)
				(type default)
			)
			(layer "F.SilkS")
		)
		(fp_line
			(start 14.084808 -1.679702)
			(end 14.097254 -1.749044)
			(stroke
				(width 0.1)
				(type default)
			)
			(layer "F.SilkS")
		)
		(fp_line
			(start 14.096238 -0.882904)
			(end 14.156436 -0.882904)
			(stroke
				(width 0.1)
				(type default)
			)
			(layer "F.SilkS")
		)
		(fp_line
			(start 14.096238 -0.882904)
			(end 14.156436 -0.882904)
			(stroke
				(width 0.1)
				(type default)
			)
			(layer "F.SilkS")
		)
		(fp_line
			(start 14.096238 -0.882904)
			(end 15.270226 -2.00914)
			(stroke
				(width 0.1)
				(type default)
			)
			(layer "F.SilkS")
		)
		(fp_line
			(start 14.096238 -0.882904)
			(end 15.270226 -2.00914)
			(stroke
				(width 0.1)
				(type default)
			)
			(layer "F.SilkS")
		)
		(fp_line
			(start 14.109192 -1.81864)
			(end 14.097254 -1.749044)
			(stroke
				(width 0.1)
				(type default)
			)
			(layer "F.SilkS")
		)
		(fp_line
			(start 14.109192 -1.81864)
			(end 14.097254 -1.749044)
			(stroke
				(width 0.1)
				(type default)
			)
			(layer "F.SilkS")
		)
		(fp_line
			(start 14.121384 -1.887982)
			(end 14.109192 -1.81864)
			(stroke
				(width 0.1)
				(type default)
			)
			(layer "F.SilkS")
		)
		(fp_line
			(start 14.121384 -1.887982)
			(end 14.109192 -1.81864)
			(stroke
				(width 0.1)
				(type default)
			)
			(layer "F.SilkS")
		)
		(fp_line
			(start 14.13383 -1.957324)
			(end 14.121384 -1.887982)
			(stroke
				(width 0.1)
				(type default)
			)
			(layer "F.SilkS")
		)
		(fp_line
			(start 14.13383 -1.957324)
			(end 14.121384 -1.887982)
			(stroke
				(width 0.1)
				(type default)
			)
			(layer "F.SilkS")
		)
		(fp_line
			(start 14.145768 -2.02692)
			(end 14.13383 -1.957324)
			(stroke
				(width 0.1)
				(type default)
			)
			(layer "F.SilkS")
		)
		(fp_line
			(start 14.145768 -2.02692)
			(end 14.13383 -1.957324)
			(stroke
				(width 0.1)
				(type default)
			)
			(layer "F.SilkS")
		)
		(fp_line
			(start 14.156436 -0.882904)
			(end 14.216888 -0.882904)
			(stroke
				(width 0.1)
				(type default)
			)
			(layer "F.SilkS")
		)
		(fp_line
			(start 14.156436 -0.882904)
			(end 14.216888 -0.882904)
			(stroke
				(width 0.1)
				(type default)
			)
			(layer "F.SilkS")
		)
		(fp_line
			(start 14.156436 -0.882904)
			(end 15.258288 -1.939544)
			(stroke
				(width 0.1)
				(type default)
			)
			(layer "F.SilkS")
		)
		(fp_line
			(start 14.156436 -0.882904)
			(end 15.258288 -1.939544)
			(stroke
				(width 0.1)
				(type default)
			)
			(layer "F.SilkS")
		)
		(fp_line
			(start 14.15796 -2.096262)
			(end 14.145768 -2.02692)
			(stroke
				(width 0.1)
				(type default)
			)
			(layer "F.SilkS")
		)
		(fp_line
			(start 14.15796 -2.096262)
			(end 14.145768 -2.02692)
			(stroke
				(width 0.1)
				(type default)
			)
			(layer "F.SilkS")
		)
		(fp_line
			(start 14.170406 -2.165604)
			(end 14.15796 -2.096262)
			(stroke
				(width 0.1)
				(type default)
			)
			(layer "F.SilkS")
		)
		(fp_line
			(start 14.170406 -2.165604)
			(end 14.15796 -2.096262)
			(stroke
				(width 0.1)
				(type default)
			)
			(layer "F.SilkS")
		)
		(fp_line
			(start 14.182344 -2.234946)
			(end 14.170406 -2.165604)
			(stroke
				(width 0.1)
				(type default)
			)
			(layer "F.SilkS")
		)
		(fp_line
			(start 14.182344 -2.234946)
			(end 14.170406 -2.165604)
			(stroke
				(width 0.1)
				(type default)
			)
			(layer "F.SilkS")
		)
		(fp_line
			(start 14.194282 -2.304288)
			(end 14.182344 -2.234946)
			(stroke
				(width 0.1)
				(type default)
			)
			(layer "F.SilkS")
		)
		(fp_line
			(start 14.194282 -2.304288)
			(end 14.182344 -2.234946)
			(stroke
				(width 0.1)
				(type default)
			)
			(layer "F.SilkS")
		)
		(fp_line
			(start 14.206728 -2.373884)
			(end 14.194282 -2.304288)
			(stroke
				(width 0.1)
				(type default)
			)
			(layer "F.SilkS")
		)
		(fp_line
			(start 14.206728 -2.373884)
			(end 14.194282 -2.304288)
			(stroke
				(width 0.1)
				(type default)
			)
			(layer "F.SilkS")
		)
		(fp_line
			(start 14.216888 -0.882904)
			(end 14.277086 -0.882904)
			(stroke
				(width 0.1)
				(type default)
			)
			(layer "F.SilkS")
		)
		(fp_line
			(start 14.216888 -0.882904)
			(end 14.277086 -0.882904)
			(stroke
				(width 0.1)
				(type default)
			)
			(layer "F.SilkS")
		)
		(fp_line
			(start 14.216888 -0.882904)
			(end 15.245842 -1.869948)
			(stroke
				(width 0.1)
				(type default)
			)
			(layer "F.SilkS")
		)
		(fp_line
			(start 14.216888 -0.882904)
			(end 15.245842 -1.869948)
			(stroke
				(width 0.1)
				(type default)
			)
			(layer "F.SilkS")
		)
		(fp_line
			(start 14.21892 -2.443226)
			(end 14.206728 -2.373884)
			(stroke
				(width 0.1)
				(type default)
			)
			(layer "F.SilkS")
		)
		(fp_line
			(start 14.21892 -2.443226)
			(end 14.206728 -2.373884)
			(stroke
				(width 0.1)
				(type default)
			)
			(layer "F.SilkS")
		)
		(fp_line
			(start 14.230858 -2.512314)
			(end 14.21892 -2.443226)
			(stroke
				(width 0.1)
				(type default)
			)
			(layer "F.SilkS")
		)
		(fp_line
			(start 14.230858 -2.512314)
			(end 14.21892 -2.443226)
			(stroke
				(width 0.1)
				(type default)
			)
			(layer "F.SilkS")
		)
		(fp_line
			(start 14.243304 -2.58191)
			(end 14.230858 -2.512314)
			(stroke
				(width 0.1)
				(type default)
			)
			(layer "F.SilkS")
		)
		(fp_line
			(start 14.243304 -2.58191)
			(end 14.230858 -2.512314)
			(stroke
				(width 0.1)
				(type default)
			)
			(layer "F.SilkS")
		)
		(fp_line
			(start 14.255496 -2.651506)
			(end 14.243304 -2.58191)
			(stroke
				(width 0.1)
				(type default)
			)
			(layer "F.SilkS")
		)
		(fp_line
			(start 14.255496 -2.651506)
			(end 14.243304 -2.58191)
			(stroke
				(width 0.1)
				(type default)
			)
			(layer "F.SilkS")
		)
		(fp_line
			(start 14.267434 -2.720594)
			(end 14.255496 -2.651506)
			(stroke
				(width 0.1)
				(type default)
			)
			(layer "F.SilkS")
		)
		(fp_line
			(start 14.267434 -2.720594)
			(end 14.255496 -2.651506)
			(stroke
				(width 0.1)
				(type default)
			)
			(layer "F.SilkS")
		)
		(fp_line
			(start 14.277086 -0.882904)
			(end 14.33703 -0.882904)
			(stroke
				(width 0.1)
				(type default)
			)
			(layer "F.SilkS")
		)
		(fp_line
			(start 14.277086 -0.882904)
			(end 14.33703 -0.882904)
			(stroke
				(width 0.1)
				(type default)
			)
			(layer "F.SilkS")
		)
		(fp_line
			(start 14.277086 -0.882904)
			(end 15.233396 -1.800606)
			(stroke
				(width 0.1)
				(type default)
			)
			(layer "F.SilkS")
		)
		(fp_line
			(start 14.277086 -0.882904)
			(end 15.233396 -1.800606)
			(stroke
				(width 0.1)
				(type default)
			)
			(layer "F.SilkS")
		)
		(fp_line
			(start 14.27988 -2.79019)
			(end 14.267434 -2.720594)
			(stroke
				(width 0.1)
				(type default)
			)
			(layer "F.SilkS")
		)
		(fp_line
			(start 14.27988 -2.79019)
			(end 14.267434 -2.720594)
			(stroke
				(width 0.1)
				(type default)
			)
			(layer "F.SilkS")
		)
		(fp_line
			(start 14.291818 -2.859532)
			(end 14.27988 -2.79019)
			(stroke
				(width 0.1)
				(type default)
			)
			(layer "F.SilkS")
		)
		(fp_line
			(start 14.291818 -2.859532)
			(end 14.27988 -2.79019)
			(stroke
				(width 0.1)
				(type default)
			)
			(layer "F.SilkS")
		)
		(fp_line
			(start 14.30401 -2.928874)
			(end 14.291818 -2.859532)
			(stroke
				(width 0.1)
				(type default)
			)
			(layer "F.SilkS")
		)
		(fp_line
			(start 14.30401 -2.928874)
			(end 14.291818 -2.859532)
			(stroke
				(width 0.1)
				(type default)
			)
			(layer "F.SilkS")
		)
		(fp_line
			(start 14.316456 -2.998216)
			(end 14.30401 -2.928874)
			(stroke
				(width 0.1)
				(type default)
			)
			(layer "F.SilkS")
		)
		(fp_line
			(start 14.316456 -2.998216)
			(end 14.30401 -2.928874)
			(stroke
				(width 0.1)
				(type default)
			)
			(layer "F.SilkS")
		)
		(fp_line
			(start 14.328394 -3.067558)
			(end 14.316456 -2.998216)
			(stroke
				(width 0.1)
				(type default)
			)
			(layer "F.SilkS")
		)
		(fp_line
			(start 14.328394 -3.067558)
			(end 14.316456 -2.998216)
			(stroke
				(width 0.1)
				(type default)
			)
			(layer "F.SilkS")
		)
		(fp_line
			(start 14.33703 -0.882904)
			(end 14.396974 -0.882904)
			(stroke
				(width 0.1)
				(type default)
			)
			(layer "F.SilkS")
		)
		(fp_line
			(start 14.33703 -0.882904)
			(end 14.396974 -0.882904)
			(stroke
				(width 0.1)
				(type default)
			)
			(layer "F.SilkS")
		)
		(fp_line
			(start 14.33703 -0.882904)
			(end 15.221458 -1.731518)
			(stroke
				(width 0.1)
				(type default)
			)
			(layer "F.SilkS")
		)
		(fp_line
			(start 14.33703 -0.882904)
			(end 15.221458 -1.731518)
			(stroke
				(width 0.1)
				(type default)
			)
			(layer "F.SilkS")
		)
		(fp_line
			(start 14.340586 -3.137154)
			(end 14.328394 -3.067558)
			(stroke
				(width 0.1)
				(type default)
			)
			(layer "F.SilkS")
		)
		(fp_line
			(start 14.340586 -3.137154)
			(end 14.328394 -3.067558)
			(stroke
				(width 0.1)
				(type default)
			)
			(layer "F.SilkS")
		)
		(fp_line
			(start 14.352778 -3.206496)
			(end 14.340586 -3.137154)
			(stroke
				(width 0.1)
				(type default)
			)
			(layer "F.SilkS")
		)
		(fp_line
			(start 14.352778 -3.206496)
			(end 14.340586 -3.137154)
			(stroke
				(width 0.1)
				(type default)
			)
			(layer "F.SilkS")
		)
		(fp_line
			(start 14.36497 -3.275838)
			(end 14.352778 -3.206496)
			(stroke
				(width 0.1)
				(type default)
			)
			(layer "F.SilkS")
		)
		(fp_line
			(start 14.36497 -3.275838)
			(end 14.352778 -3.206496)
			(stroke
				(width 0.1)
				(type default)
			)
			(layer "F.SilkS")
		)
		(fp_line
			(start 14.376908 -3.34518)
			(end 14.36497 -3.275838)
			(stroke
				(width 0.1)
				(type default)
			)
			(layer "F.SilkS")
		)
		(fp_line
			(start 14.376908 -3.34518)
			(end 14.36497 -3.275838)
			(stroke
				(width 0.1)
				(type default)
			)
			(layer "F.SilkS")
		)
		(fp_line
			(start 14.389354 -3.414776)
			(end 14.376908 -3.34518)
			(stroke
				(width 0.1)
				(type default)
			)
			(layer "F.SilkS")
		)
		(fp_line
			(start 14.389354 -3.414776)
			(end 14.376908 -3.34518)
			(stroke
				(width 0.1)
				(type default)
			)
			(layer "F.SilkS")
		)
		(fp_line
			(start 14.396974 -0.882904)
			(end 14.45768 -0.882904)
			(stroke
				(width 0.1)
				(type default)
			)
			(layer "F.SilkS")
		)
		(fp_line
			(start 14.396974 -0.882904)
			(end 14.45768 -0.882904)
			(stroke
				(width 0.1)
				(type default)
			)
			(layer "F.SilkS")
		)
		(fp_line
			(start 14.396974 -0.882904)
			(end 15.209266 -1.661922)
			(stroke
				(width 0.1)
				(type default)
			)
			(layer "F.SilkS")
		)
		(fp_line
			(start 14.396974 -0.882904)
			(end 15.209266 -1.661922)
			(stroke
				(width 0.1)
				(type default)
			)
			(layer "F.SilkS")
		)
		(fp_line
			(start 14.401546 -3.484118)
			(end 14.389354 -3.414776)
			(stroke
				(width 0.1)
				(type default)
			)
			(layer "F.SilkS")
		)
		(fp_line
			(start 14.401546 -3.484118)
			(end 14.389354 -3.414776)
			(stroke
				(width 0.1)
				(type default)
			)
			(layer "F.SilkS")
		)
		(fp_line
			(start 14.413484 -3.55346)
			(end 14.401546 -3.484118)
			(stroke
				(width 0.1)
				(type default)
			)
			(layer "F.SilkS")
		)
		(fp_line
			(start 14.413484 -3.55346)
			(end 14.401546 -3.484118)
			(stroke
				(width 0.1)
				(type default)
			)
			(layer "F.SilkS")
		)
		(fp_line
			(start 14.42593 -3.622802)
			(end 14.413484 -3.55346)
			(stroke
				(width 0.1)
				(type default)
			)
			(layer "F.SilkS")
		)
		(fp_line
			(start 14.42593 -3.622802)
			(end 14.413484 -3.55346)
			(stroke
				(width 0.1)
				(type default)
			)
			(layer "F.SilkS")
		)
		(fp_line
			(start 14.438376 -3.692398)
			(end 14.42593 -3.622802)
			(stroke
				(width 0.1)
				(type default)
			)
			(layer "F.SilkS")
		)
		(fp_line
			(start 14.438376 -3.692398)
			(end 14.42593 -3.622802)
			(stroke
				(width 0.1)
				(type default)
			)
			(layer "F.SilkS")
		)
		(fp_line
			(start 14.45006 -3.76174)
			(end 14.438376 -3.692398)
			(stroke
				(width 0.1)
				(type default)
			)
			(layer "F.SilkS")
		)
		(fp_line
			(start 14.45006 -3.76174)
			(end 14.438376 -3.692398)
			(stroke
				(width 0.1)
				(type default)
			)
			(layer "F.SilkS")
		)
		(fp_line
			(start 14.45768 -0.882904)
			(end 14.517624 -0.882904)
			(stroke
				(width 0.1)
				(type default)
			)
			(layer "F.SilkS")
		)
		(fp_line
			(start 14.45768 -0.882904)
			(end 14.517624 -0.882904)
			(stroke
				(width 0.1)
				(type default)
			)
			(layer "F.SilkS")
		)
		(fp_line
			(start 14.45768 -0.882904)
			(end 15.19682 -1.592326)
			(stroke
				(width 0.1)
				(type default)
			)
			(layer "F.SilkS")
		)
		(fp_line
			(start 14.45768 -0.882904)
			(end 15.19682 -1.592326)
			(stroke
				(width 0.1)
				(type default)
			)
			(layer "F.SilkS")
		)
		(fp_line
			(start 14.462506 -3.831082)
			(end 14.45006 -3.76174)
			(stroke
				(width 0.1)
				(type default)
			)
			(layer "F.SilkS")
		)
		(fp_line
			(start 14.462506 -3.831082)
			(end 14.45006 -3.76174)
			(stroke
				(width 0.1)
				(type default)
			)
			(layer "F.SilkS")
		)
		(fp_line
			(start 14.474952 -3.900424)
			(end 14.462506 -3.831082)
			(stroke
				(width 0.1)
				(type default)
			)
			(layer "F.SilkS")
		)
		(fp_line
			(start 14.474952 -3.900424)
			(end 14.462506 -3.831082)
			(stroke
				(width 0.1)
				(type default)
			)
			(layer "F.SilkS")
		)
		(fp_line
			(start 14.486636 -3.969766)
			(end 14.474952 -3.900424)
			(stroke
				(width 0.1)
				(type default)
			)
			(layer "F.SilkS")
		)
		(fp_line
			(start 14.486636 -3.969766)
			(end 14.474952 -3.900424)
			(stroke
				(width 0.1)
				(type default)
			)
			(layer "F.SilkS")
		)
		(fp_line
			(start 14.498828 -4.039362)
			(end 14.486636 -3.969766)
			(stroke
				(width 0.1)
				(type default)
			)
			(layer "F.SilkS")
		)
		(fp_line
			(start 14.498828 -4.039362)
			(end 14.486636 -3.969766)
			(stroke
				(width 0.1)
				(type default)
			)
			(layer "F.SilkS")
		)
		(fp_line
			(start 14.511274 -4.108704)
			(end 14.498828 -4.039362)
			(stroke
				(width 0.1)
				(type default)
			)
			(layer "F.SilkS")
		)
		(fp_line
			(start 14.511274 -4.108704)
			(end 14.498828 -4.039362)
			(stroke
				(width 0.1)
				(type default)
			)
			(layer "F.SilkS")
		)
		(fp_line
			(start 14.517624 -0.882904)
			(end 14.577568 -0.882904)
			(stroke
				(width 0.1)
				(type default)
			)
			(layer "F.SilkS")
		)
		(fp_line
			(start 14.517624 -0.882904)
			(end 14.577568 -0.882904)
			(stroke
				(width 0.1)
				(type default)
			)
			(layer "F.SilkS")
		)
		(fp_line
			(start 14.517624 -0.882904)
			(end 15.184882 -1.522984)
			(stroke
				(width 0.1)
				(type default)
			)
			(layer "F.SilkS")
		)
		(fp_line
			(start 14.517624 -0.882904)
			(end 15.184882 -1.522984)
			(stroke
				(width 0.1)
				(type default)
			)
			(layer "F.SilkS")
		)
		(fp_line
			(start 14.523466 -4.178046)
			(end 14.511274 -4.108704)
			(stroke
				(width 0.1)
				(type default)
			)
			(layer "F.SilkS")
		)
		(fp_line
			(start 14.523466 -4.178046)
			(end 14.511274 -4.108704)
			(stroke
				(width 0.1)
				(type default)
			)
			(layer "F.SilkS")
		)
		(fp_line
			(start 14.523466 -4.178046)
			(end 14.535404 -4.247388)
			(stroke
				(width 0.1)
				(type default)
			)
			(layer "F.SilkS")
		)
		(fp_line
			(start 14.523466 -4.178046)
			(end 14.535404 -4.247388)
			(stroke
				(width 0.1)
				(type default)
			)
			(layer "F.SilkS")
		)
		(fp_line
			(start 14.535404 -4.247388)
			(end 14.54785 -4.316984)
			(stroke
				(width 0.1)
				(type default)
			)
			(layer "F.SilkS")
		)
		(fp_line
			(start 14.535404 -4.247388)
			(end 14.54785 -4.316984)
			(stroke
				(width 0.1)
				(type default)
			)
			(layer "F.SilkS")
		)
		(fp_line
			(start 14.54785 -4.316984)
			(end 14.560042 -4.386326)
			(stroke
				(width 0.1)
				(type default)
			)
			(layer "F.SilkS")
		)
		(fp_line
			(start 14.54785 -4.316984)
			(end 14.560042 -4.386326)
			(stroke
				(width 0.1)
				(type default)
			)
			(layer "F.SilkS")
		)
		(fp_line
			(start 14.560042 -4.386326)
			(end 14.57198 -4.455668)
			(stroke
				(width 0.1)
				(type default)
			)
			(layer "F.SilkS")
		)
		(fp_line
			(start 14.560042 -4.386326)
			(end 14.57198 -4.455668)
			(stroke
				(width 0.1)
				(type default)
			)
			(layer "F.SilkS")
		)
		(fp_line
			(start 14.57198 -4.455668)
			(end 14.584426 -4.52501)
			(stroke
				(width 0.1)
				(type default)
			)
			(layer "F.SilkS")
		)
		(fp_line
			(start 14.57198 -4.455668)
			(end 14.584426 -4.52501)
			(stroke
				(width 0.1)
				(type default)
			)
			(layer "F.SilkS")
		)
		(fp_line
			(start 14.577568 -0.882904)
			(end 14.637766 -0.882904)
			(stroke
				(width 0.1)
				(type default)
			)
			(layer "F.SilkS")
		)
		(fp_line
			(start 14.577568 -0.882904)
			(end 14.637766 -0.882904)
			(stroke
				(width 0.1)
				(type default)
			)
			(layer "F.SilkS")
		)
		(fp_line
			(start 14.577568 -0.882904)
			(end 15.17269 -1.453642)
			(stroke
				(width 0.1)
				(type default)
			)
			(layer "F.SilkS")
		)
		(fp_line
			(start 14.577568 -0.882904)
			(end 15.17269 -1.453642)
			(stroke
				(width 0.1)
				(type default)
			)
			(layer "F.SilkS")
		)
		(fp_line
			(start 14.584426 -4.52501)
			(end 14.596364 -4.594352)
			(stroke
				(width 0.1)
				(type default)
			)
			(layer "F.SilkS")
		)
		(fp_line
			(start 14.584426 -4.52501)
			(end 14.596364 -4.594352)
			(stroke
				(width 0.1)
				(type default)
			)
			(layer "F.SilkS")
		)
		(fp_line
			(start 14.596364 -4.594352)
			(end 14.608556 -4.663948)
			(stroke
				(width 0.1)
				(type default)
			)
			(layer "F.SilkS")
		)
		(fp_line
			(start 14.596364 -4.594352)
			(end 14.608556 -4.663948)
			(stroke
				(width 0.1)
				(type default)
			)
			(layer "F.SilkS")
		)
		(fp_line
			(start 14.608556 -4.663948)
			(end 14.621002 -4.733036)
			(stroke
				(width 0.1)
				(type default)
			)
			(layer "F.SilkS")
		)
		(fp_line
			(start 14.608556 -4.663948)
			(end 14.621002 -4.733036)
			(stroke
				(width 0.1)
				(type default)
			)
			(layer "F.SilkS")
		)
		(fp_line
			(start 14.621002 -4.733036)
			(end 14.63294 -4.802632)
			(stroke
				(width 0.1)
				(type default)
			)
			(layer "F.SilkS")
		)
		(fp_line
			(start 14.621002 -4.733036)
			(end 14.63294 -4.802632)
			(stroke
				(width 0.1)
				(type default)
			)
			(layer "F.SilkS")
		)
		(fp_line
			(start 14.63294 -4.802632)
			(end 14.645132 -4.872228)
			(stroke
				(width 0.1)
				(type default)
			)
			(layer "F.SilkS")
		)
		(fp_line
			(start 14.63294 -4.802632)
			(end 14.645132 -4.872228)
			(stroke
				(width 0.1)
				(type default)
			)
			(layer "F.SilkS")
		)
		(fp_line
			(start 14.637766 -0.882904)
			(end 14.697964 -0.882904)
			(stroke
				(width 0.1)
				(type default)
			)
			(layer "F.SilkS")
		)
		(fp_line
			(start 14.637766 -0.882904)
			(end 14.697964 -0.882904)
			(stroke
				(width 0.1)
				(type default)
			)
			(layer "F.SilkS")
		)
		(fp_line
			(start 14.637766 -0.882904)
			(end 15.160498 -1.384046)
			(stroke
				(width 0.1)
				(type default)
			)
			(layer "F.SilkS")
		)
		(fp_line
			(start 14.637766 -0.882904)
			(end 15.160498 -1.384046)
			(stroke
				(width 0.1)
				(type default)
			)
			(layer "F.SilkS")
		)
		(fp_line
			(start 14.645132 -4.872228)
			(end 14.657324 -4.941316)
			(stroke
				(width 0.1)
				(type default)
			)
			(layer "F.SilkS")
		)
		(fp_line
			(start 14.645132 -4.872228)
			(end 14.657324 -4.941316)
			(stroke
				(width 0.1)
				(type default)
			)
			(layer "F.SilkS")
		)
		(fp_line
			(start 14.657324 -4.941316)
			(end 14.669516 -5.010912)
			(stroke
				(width 0.1)
				(type default)
			)
			(layer "F.SilkS")
		)
		(fp_line
			(start 14.657324 -4.941316)
			(end 14.669516 -5.010912)
			(stroke
				(width 0.1)
				(type default)
			)
			(layer "F.SilkS")
		)
		(fp_line
			(start 14.669516 -5.010912)
			(end 14.681454 -5.080254)
			(stroke
				(width 0.1)
				(type default)
			)
			(layer "F.SilkS")
		)
		(fp_line
			(start 14.669516 -5.010912)
			(end 14.681454 -5.080254)
			(stroke
				(width 0.1)
				(type default)
			)
			(layer "F.SilkS")
		)
		(fp_line
			(start 14.681454 -5.080254)
			(end 14.6939 -5.149596)
			(stroke
				(width 0.1)
				(type default)
			)
			(layer "F.SilkS")
		)
		(fp_line
			(start 14.681454 -5.080254)
			(end 14.6939 -5.149596)
			(stroke
				(width 0.1)
				(type default)
			)
			(layer "F.SilkS")
		)
		(fp_line
			(start 14.69771 -5.171694)
			(end 14.6939 -5.149596)
			(stroke
				(width 0.1)
				(type default)
			)
			(layer "F.SilkS")
		)
		(fp_line
			(start 14.69771 -5.171694)
			(end 14.6939 -5.149596)
			(stroke
				(width 0.1)
				(type default)
			)
			(layer "F.SilkS")
		)
		(fp_line
			(start 14.697964 -0.882904)
			(end 14.757908 -0.882904)
			(stroke
				(width 0.1)
				(type default)
			)
			(layer "F.SilkS")
		)
		(fp_line
			(start 14.697964 -0.882904)
			(end 14.757908 -0.882904)
			(stroke
				(width 0.1)
				(type default)
			)
			(layer "F.SilkS")
		)
		(fp_line
			(start 14.697964 -0.882904)
			(end 15.148052 -1.314704)
			(stroke
				(width 0.1)
				(type default)
			)
			(layer "F.SilkS")
		)
		(fp_line
			(start 14.697964 -0.882904)
			(end 15.148052 -1.314704)
			(stroke
				(width 0.1)
				(type default)
			)
			(layer "F.SilkS")
		)
		(fp_line
			(start 14.71676 -5.171694)
			(end 14.6939 -5.149596)
			(stroke
				(width 0.1)
				(type default)
			)
			(layer "F.SilkS")
		)
		(fp_line
			(start 14.71676 -5.171694)
			(end 14.6939 -5.149596)
			(stroke
				(width 0.1)
				(type default)
			)
			(layer "F.SilkS")
		)
		(fp_line
			(start 14.71676 -5.171694)
			(end 14.69771 -5.171694)
			(stroke
				(width 0.1)
				(type default)
			)
			(layer "F.SilkS")
		)
		(fp_line
			(start 14.71676 -5.171694)
			(end 14.69771 -5.171694)
			(stroke
				(width 0.1)
				(type default)
			)
			(layer "F.SilkS")
		)
		(fp_line
			(start 14.757908 -0.882904)
			(end 14.81836 -0.882904)
			(stroke
				(width 0.1)
				(type default)
			)
			(layer "F.SilkS")
		)
		(fp_line
			(start 14.757908 -0.882904)
			(end 14.81836 -0.882904)
			(stroke
				(width 0.1)
				(type default)
			)
			(layer "F.SilkS")
		)
		(fp_line
			(start 14.757908 -0.882904)
			(end 15.13586 -1.245362)
			(stroke
				(width 0.1)
				(type default)
			)
			(layer "F.SilkS")
		)
		(fp_line
			(start 14.757908 -0.882904)
			(end 15.13586 -1.245362)
			(stroke
				(width 0.1)
				(type default)
			)
			(layer "F.SilkS")
		)
		(fp_line
			(start 14.776958 -5.171694)
			(end 14.681454 -5.080254)
			(stroke
				(width 0.1)
				(type default)
			)
			(layer "F.SilkS")
		)
		(fp_line
			(start 14.776958 -5.171694)
			(end 14.681454 -5.080254)
			(stroke
				(width 0.1)
				(type default)
			)
			(layer "F.SilkS")
		)
		(fp_line
			(start 14.776958 -5.171694)
			(end 14.71676 -5.171694)
			(stroke
				(width 0.1)
				(type default)
			)
			(layer "F.SilkS")
		)
		(fp_line
			(start 14.776958 -5.171694)
			(end 14.71676 -5.171694)
			(stroke
				(width 0.1)
				(type default)
			)
			(layer "F.SilkS")
		)
		(fp_line
			(start 14.81836 -0.882904)
			(end 14.878558 -0.882904)
			(stroke
				(width 0.1)
				(type default)
			)
			(layer "F.SilkS")
		)
		(fp_line
			(start 14.81836 -0.882904)
			(end 14.878558 -0.882904)
			(stroke
				(width 0.1)
				(type default)
			)
			(layer "F.SilkS")
		)
		(fp_line
			(start 14.81836 -0.882904)
			(end 15.123922 -1.17602)
			(stroke
				(width 0.1)
				(type default)
			)
			(layer "F.SilkS")
		)
		(fp_line
			(start 14.81836 -0.882904)
			(end 15.123922 -1.17602)
			(stroke
				(width 0.1)
				(type default)
			)
			(layer "F.SilkS")
		)
		(fp_line
			(start 14.837156 -5.171694)
			(end 14.669516 -5.010912)
			(stroke
				(width 0.1)
				(type default)
			)
			(layer "F.SilkS")
		)
		(fp_line
			(start 14.837156 -5.171694)
			(end 14.669516 -5.010912)
			(stroke
				(width 0.1)
				(type default)
			)
			(layer "F.SilkS")
		)
		(fp_line
			(start 14.837156 -5.171694)
			(end 14.776958 -5.171694)
			(stroke
				(width 0.1)
				(type default)
			)
			(layer "F.SilkS")
		)
		(fp_line
			(start 14.837156 -5.171694)
			(end 14.776958 -5.171694)
			(stroke
				(width 0.1)
				(type default)
			)
			(layer "F.SilkS")
		)
		(fp_line
			(start 14.878558 -0.882904)
			(end 14.938502 -0.882904)
			(stroke
				(width 0.1)
				(type default)
			)
			(layer "F.SilkS")
		)
		(fp_line
			(start 14.878558 -0.882904)
			(end 14.938502 -0.882904)
			(stroke
				(width 0.1)
				(type default)
			)
			(layer "F.SilkS")
		)
		(fp_line
			(start 14.878558 -0.882904)
			(end 15.111476 -1.106424)
			(stroke
				(width 0.1)
				(type default)
			)
			(layer "F.SilkS")
		)
		(fp_line
			(start 14.878558 -0.882904)
			(end 15.111476 -1.106424)
			(stroke
				(width 0.1)
				(type default)
			)
			(layer "F.SilkS")
		)
		(fp_line
			(start 14.8971 -5.171694)
			(end 14.657324 -4.941316)
			(stroke
				(width 0.1)
				(type default)
			)
			(layer "F.SilkS")
		)
		(fp_line
			(start 14.8971 -5.171694)
			(end 14.657324 -4.941316)
			(stroke
				(width 0.1)
				(type default)
			)
			(layer "F.SilkS")
		)
		(fp_line
			(start 14.8971 -5.171694)
			(end 14.837156 -5.171694)
			(stroke
				(width 0.1)
				(type default)
			)
			(layer "F.SilkS")
		)
		(fp_line
			(start 14.8971 -5.171694)
			(end 14.837156 -5.171694)
			(stroke
				(width 0.1)
				(type default)
			)
			(layer "F.SilkS")
		)
		(fp_line
			(start 14.938502 -0.882904)
			(end 14.998954 -0.882904)
			(stroke
				(width 0.1)
				(type default)
			)
			(layer "F.SilkS")
		)
		(fp_line
			(start 14.938502 -0.882904)
			(end 14.998954 -0.882904)
			(stroke
				(width 0.1)
				(type default)
			)
			(layer "F.SilkS")
		)
		(fp_line
			(start 14.938502 -0.882904)
			(end 15.09903 -1.036828)
			(stroke
				(width 0.1)
				(type default)
			)
			(layer "F.SilkS")
		)
		(fp_line
			(start 14.938502 -0.882904)
			(end 15.09903 -1.036828)
			(stroke
				(width 0.1)
				(type default)
			)
			(layer "F.SilkS")
		)
		(fp_line
			(start 14.957552 -5.171694)
			(end 14.645132 -4.872228)
			(stroke
				(width 0.1)
				(type default)
			)
			(layer "F.SilkS")
		)
		(fp_line
			(start 14.957552 -5.171694)
			(end 14.645132 -4.872228)
			(stroke
				(width 0.1)
				(type default)
			)
			(layer "F.SilkS")
		)
		(fp_line
			(start 14.957552 -5.171694)
			(end 14.8971 -5.171694)
			(stroke
				(width 0.1)
				(type default)
			)
			(layer "F.SilkS")
		)
		(fp_line
			(start 14.957552 -5.171694)
			(end 14.8971 -5.171694)
			(stroke
				(width 0.1)
				(type default)
			)
			(layer "F.SilkS")
		)
		(fp_line
			(start 14.998954 -0.882904)
			(end 15.059152 -0.882904)
			(stroke
				(width 0.1)
				(type default)
			)
			(layer "F.SilkS")
		)
		(fp_line
			(start 14.998954 -0.882904)
			(end 15.059152 -0.882904)
			(stroke
				(width 0.1)
				(type default)
			)
			(layer "F.SilkS")
		)
		(fp_line
			(start 14.998954 -0.882904)
			(end 15.087092 -0.96774)
			(stroke
				(width 0.1)
				(type default)
			)
			(layer "F.SilkS")
		)
		(fp_line
			(start 14.998954 -0.882904)
			(end 15.087092 -0.96774)
			(stroke
				(width 0.1)
				(type default)
			)
			(layer "F.SilkS")
		)
		(fp_line
			(start 15.01775 -5.171694)
			(end 14.63294 -4.802632)
			(stroke
				(width 0.1)
				(type default)
			)
			(layer "F.SilkS")
		)
		(fp_line
			(start 15.01775 -5.171694)
			(end 14.63294 -4.802632)
			(stroke
				(width 0.1)
				(type default)
			)
			(layer "F.SilkS")
		)
		(fp_line
			(start 15.01775 -5.171694)
			(end 14.957552 -5.171694)
			(stroke
				(width 0.1)
				(type default)
			)
			(layer "F.SilkS")
		)
		(fp_line
			(start 15.01775 -5.171694)
			(end 14.957552 -5.171694)
			(stroke
				(width 0.1)
				(type default)
			)
			(layer "F.SilkS")
		)
		(fp_line
			(start 15.059152 -0.882904)
			(end 15.072106 -0.882904)
			(stroke
				(width 0.1)
				(type default)
			)
			(layer "F.SilkS")
		)
		(fp_line
			(start 15.059152 -0.882904)
			(end 15.072106 -0.882904)
			(stroke
				(width 0.1)
				(type default)
			)
			(layer "F.SilkS")
		)
		(fp_line
			(start 15.059152 -0.882904)
			(end 15.0749 -0.898398)
			(stroke
				(width 0.1)
				(type default)
			)
			(layer "F.SilkS")
		)
		(fp_line
			(start 15.059152 -0.882904)
			(end 15.0749 -0.898398)
			(stroke
				(width 0.1)
				(type default)
			)
			(layer "F.SilkS")
		)
		(fp_line
			(start 15.072106 -0.882904)
			(end 15.0749 -0.898398)
			(stroke
				(width 0.1)
				(type default)
			)
			(layer "F.SilkS")
		)
		(fp_line
			(start 15.072106 -0.882904)
			(end 15.0749 -0.898398)
			(stroke
				(width 0.1)
				(type default)
			)
			(layer "F.SilkS")
		)
		(fp_line
			(start 15.077694 -5.171694)
			(end 14.621002 -4.733036)
			(stroke
				(width 0.1)
				(type default)
			)
			(layer "F.SilkS")
		)
		(fp_line
			(start 15.077694 -5.171694)
			(end 14.621002 -4.733036)
			(stroke
				(width 0.1)
				(type default)
			)
			(layer "F.SilkS")
		)
		(fp_line
			(start 15.077694 -5.171694)
			(end 15.01775 -5.171694)
			(stroke
				(width 0.1)
				(type default)
			)
			(layer "F.SilkS")
		)
		(fp_line
			(start 15.077694 -5.171694)
			(end 15.01775 -5.171694)
			(stroke
				(width 0.1)
				(type default)
			)
			(layer "F.SilkS")
		)
		(fp_line
			(start 15.087092 -0.96774)
			(end 15.0749 -0.898398)
			(stroke
				(width 0.1)
				(type default)
			)
			(layer "F.SilkS")
		)
		(fp_line
			(start 15.087092 -0.96774)
			(end 15.0749 -0.898398)
			(stroke
				(width 0.1)
				(type default)
			)
			(layer "F.SilkS")
		)
		(fp_line
			(start 15.09903 -1.036828)
			(end 15.087092 -0.96774)
			(stroke
				(width 0.1)
				(type default)
			)
			(layer "F.SilkS")
		)
		(fp_line
			(start 15.09903 -1.036828)
			(end 15.087092 -0.96774)
			(stroke
				(width 0.1)
				(type default)
			)
			(layer "F.SilkS")
		)
		(fp_line
			(start 15.111476 -1.106424)
			(end 15.09903 -1.036828)
			(stroke
				(width 0.1)
				(type default)
			)
			(layer "F.SilkS")
		)
		(fp_line
			(start 15.111476 -1.106424)
			(end 15.09903 -1.036828)
			(stroke
				(width 0.1)
				(type default)
			)
			(layer "F.SilkS")
		)
		(fp_line
			(start 15.123922 -1.17602)
			(end 15.111476 -1.106424)
			(stroke
				(width 0.1)
				(type default)
			)
			(layer "F.SilkS")
		)
		(fp_line
			(start 15.123922 -1.17602)
			(end 15.111476 -1.106424)
			(stroke
				(width 0.1)
				(type default)
			)
			(layer "F.SilkS")
		)
		(fp_line
			(start 15.13586 -1.245362)
			(end 15.123922 -1.17602)
			(stroke
				(width 0.1)
				(type default)
			)
			(layer "F.SilkS")
		)
		(fp_line
			(start 15.13586 -1.245362)
			(end 15.123922 -1.17602)
			(stroke
				(width 0.1)
				(type default)
			)
			(layer "F.SilkS")
		)
		(fp_line
			(start 15.137892 -5.171694)
			(end 14.608556 -4.663948)
			(stroke
				(width 0.1)
				(type default)
			)
			(layer "F.SilkS")
		)
		(fp_line
			(start 15.137892 -5.171694)
			(end 14.608556 -4.663948)
			(stroke
				(width 0.1)
				(type default)
			)
			(layer "F.SilkS")
		)
		(fp_line
			(start 15.137892 -5.171694)
			(end 15.077694 -5.171694)
			(stroke
				(width 0.1)
				(type default)
			)
			(layer "F.SilkS")
		)
		(fp_line
			(start 15.137892 -5.171694)
			(end 15.077694 -5.171694)
			(stroke
				(width 0.1)
				(type default)
			)
			(layer "F.SilkS")
		)
		(fp_line
			(start 15.148052 -1.314704)
			(end 15.13586 -1.245362)
			(stroke
				(width 0.1)
				(type default)
			)
			(layer "F.SilkS")
		)
		(fp_line
			(start 15.148052 -1.314704)
			(end 15.13586 -1.245362)
			(stroke
				(width 0.1)
				(type default)
			)
			(layer "F.SilkS")
		)
		(fp_line
			(start 15.160498 -1.384046)
			(end 15.148052 -1.314704)
			(stroke
				(width 0.1)
				(type default)
			)
			(layer "F.SilkS")
		)
		(fp_line
			(start 15.160498 -1.384046)
			(end 15.148052 -1.314704)
			(stroke
				(width 0.1)
				(type default)
			)
			(layer "F.SilkS")
		)
		(fp_line
			(start 15.17269 -1.453642)
			(end 15.160498 -1.384046)
			(stroke
				(width 0.1)
				(type default)
			)
			(layer "F.SilkS")
		)
		(fp_line
			(start 15.17269 -1.453642)
			(end 15.160498 -1.384046)
			(stroke
				(width 0.1)
				(type default)
			)
			(layer "F.SilkS")
		)
		(fp_line
			(start 15.184882 -1.522984)
			(end 15.17269 -1.453642)
			(stroke
				(width 0.1)
				(type default)
			)
			(layer "F.SilkS")
		)
		(fp_line
			(start 15.184882 -1.522984)
			(end 15.17269 -1.453642)
			(stroke
				(width 0.1)
				(type default)
			)
			(layer "F.SilkS")
		)
		(fp_line
			(start 15.184882 -1.522984)
			(end 15.19682 -1.592326)
			(stroke
				(width 0.1)
				(type default)
			)
			(layer "F.SilkS")
		)
		(fp_line
			(start 15.184882 -1.522984)
			(end 15.19682 -1.592326)
			(stroke
				(width 0.1)
				(type default)
			)
			(layer "F.SilkS")
		)
		(fp_line
			(start 15.19682 -1.592326)
			(end 15.209266 -1.661922)
			(stroke
				(width 0.1)
				(type default)
			)
			(layer "F.SilkS")
		)
		(fp_line
			(start 15.19682 -1.592326)
			(end 15.209266 -1.661922)
			(stroke
				(width 0.1)
				(type default)
			)
			(layer "F.SilkS")
		)
		(fp_line
			(start 15.198344 -5.171694)
			(end 14.596364 -4.594352)
			(stroke
				(width 0.1)
				(type default)
			)
			(layer "F.SilkS")
		)
		(fp_line
			(start 15.198344 -5.171694)
			(end 14.596364 -4.594352)
			(stroke
				(width 0.1)
				(type default)
			)
			(layer "F.SilkS")
		)
		(fp_line
			(start 15.198344 -5.171694)
			(end 15.137892 -5.171694)
			(stroke
				(width 0.1)
				(type default)
			)
			(layer "F.SilkS")
		)
		(fp_line
			(start 15.198344 -5.171694)
			(end 15.137892 -5.171694)
			(stroke
				(width 0.1)
				(type default)
			)
			(layer "F.SilkS")
		)
		(fp_line
			(start 15.209266 -1.661922)
			(end 15.221458 -1.731518)
			(stroke
				(width 0.1)
				(type default)
			)
			(layer "F.SilkS")
		)
		(fp_line
			(start 15.209266 -1.661922)
			(end 15.221458 -1.731518)
			(stroke
				(width 0.1)
				(type default)
			)
			(layer "F.SilkS")
		)
		(fp_line
			(start 15.221458 -1.731518)
			(end 15.233396 -1.800606)
			(stroke
				(width 0.1)
				(type default)
			)
			(layer "F.SilkS")
		)
		(fp_line
			(start 15.221458 -1.731518)
			(end 15.233396 -1.800606)
			(stroke
				(width 0.1)
				(type default)
			)
			(layer "F.SilkS")
		)
		(fp_line
			(start 15.233396 -1.800606)
			(end 15.245842 -1.869948)
			(stroke
				(width 0.1)
				(type default)
			)
			(layer "F.SilkS")
		)
		(fp_line
			(start 15.233396 -1.800606)
			(end 15.245842 -1.869948)
			(stroke
				(width 0.1)
				(type default)
			)
			(layer "F.SilkS")
		)
		(fp_line
			(start 15.245842 -1.869948)
			(end 15.258288 -1.939544)
			(stroke
				(width 0.1)
				(type default)
			)
			(layer "F.SilkS")
		)
		(fp_line
			(start 15.245842 -1.869948)
			(end 15.258288 -1.939544)
			(stroke
				(width 0.1)
				(type default)
			)
			(layer "F.SilkS")
		)
		(fp_line
			(start 15.258288 -5.171694)
			(end 14.584426 -4.52501)
			(stroke
				(width 0.1)
				(type default)
			)
			(layer "F.SilkS")
		)
		(fp_line
			(start 15.258288 -5.171694)
			(end 14.584426 -4.52501)
			(stroke
				(width 0.1)
				(type default)
			)
			(layer "F.SilkS")
		)
		(fp_line
			(start 15.258288 -5.171694)
			(end 15.198344 -5.171694)
			(stroke
				(width 0.1)
				(type default)
			)
			(layer "F.SilkS")
		)
		(fp_line
			(start 15.258288 -5.171694)
			(end 15.198344 -5.171694)
			(stroke
				(width 0.1)
				(type default)
			)
			(layer "F.SilkS")
		)
		(fp_line
			(start 15.258288 -1.939544)
			(end 15.270226 -2.00914)
			(stroke
				(width 0.1)
				(type default)
			)
			(layer "F.SilkS")
		)
		(fp_line
			(start 15.258288 -1.939544)
			(end 15.270226 -2.00914)
			(stroke
				(width 0.1)
				(type default)
			)
			(layer "F.SilkS")
		)
		(fp_line
			(start 15.270226 -2.00914)
			(end 15.282418 -2.078482)
			(stroke
				(width 0.1)
				(type default)
			)
			(layer "F.SilkS")
		)
		(fp_line
			(start 15.270226 -2.00914)
			(end 15.282418 -2.078482)
			(stroke
				(width 0.1)
				(type default)
			)
			(layer "F.SilkS")
		)
		(fp_line
			(start 15.282418 -2.078482)
			(end 15.294864 -2.147824)
			(stroke
				(width 0.1)
				(type default)
			)
			(layer "F.SilkS")
		)
		(fp_line
			(start 15.282418 -2.078482)
			(end 15.294864 -2.147824)
			(stroke
				(width 0.1)
				(type default)
			)
			(layer "F.SilkS")
		)
		(fp_line
			(start 15.294864 -2.147824)
			(end 15.307056 -2.21742)
			(stroke
				(width 0.1)
				(type default)
			)
			(layer "F.SilkS")
		)
		(fp_line
			(start 15.294864 -2.147824)
			(end 15.307056 -2.21742)
			(stroke
				(width 0.1)
				(type default)
			)
			(layer "F.SilkS")
		)
		(fp_line
			(start 15.307056 -2.21742)
			(end 15.319248 -2.286762)
			(stroke
				(width 0.1)
				(type default)
			)
			(layer "F.SilkS")
		)
		(fp_line
			(start 15.307056 -2.21742)
			(end 15.319248 -2.286762)
			(stroke
				(width 0.1)
				(type default)
			)
			(layer "F.SilkS")
		)
		(fp_line
			(start 15.318486 -5.171694)
			(end 14.57198 -4.455668)
			(stroke
				(width 0.1)
				(type default)
			)
			(layer "F.SilkS")
		)
		(fp_line
			(start 15.318486 -5.171694)
			(end 14.57198 -4.455668)
			(stroke
				(width 0.1)
				(type default)
			)
			(layer "F.SilkS")
		)
		(fp_line
			(start 15.318486 -5.171694)
			(end 15.258288 -5.171694)
			(stroke
				(width 0.1)
				(type default)
			)
			(layer "F.SilkS")
		)
		(fp_line
			(start 15.318486 -5.171694)
			(end 15.258288 -5.171694)
			(stroke
				(width 0.1)
				(type default)
			)
			(layer "F.SilkS")
		)
		(fp_line
			(start 15.319248 -2.286762)
			(end 15.331186 -2.356104)
			(stroke
				(width 0.1)
				(type default)
			)
			(layer "F.SilkS")
		)
		(fp_line
			(start 15.319248 -2.286762)
			(end 15.331186 -2.356104)
			(stroke
				(width 0.1)
				(type default)
			)
			(layer "F.SilkS")
		)
		(fp_line
			(start 15.331186 -2.356104)
			(end 15.343632 -2.425446)
			(stroke
				(width 0.1)
				(type default)
			)
			(layer "F.SilkS")
		)
		(fp_line
			(start 15.331186 -2.356104)
			(end 15.343632 -2.425446)
			(stroke
				(width 0.1)
				(type default)
			)
			(layer "F.SilkS")
		)
		(fp_line
			(start 15.343632 -2.425446)
			(end 15.355824 -2.495042)
			(stroke
				(width 0.1)
				(type default)
			)
			(layer "F.SilkS")
		)
		(fp_line
			(start 15.343632 -2.425446)
			(end 15.355824 -2.495042)
			(stroke
				(width 0.1)
				(type default)
			)
			(layer "F.SilkS")
		)
		(fp_line
			(start 15.355824 -2.495042)
			(end 15.367762 -2.564384)
			(stroke
				(width 0.1)
				(type default)
			)
			(layer "F.SilkS")
		)
		(fp_line
			(start 15.355824 -2.495042)
			(end 15.367762 -2.564384)
			(stroke
				(width 0.1)
				(type default)
			)
			(layer "F.SilkS")
		)
		(fp_line
			(start 15.367762 -2.564384)
			(end 15.380208 -2.633726)
			(stroke
				(width 0.1)
				(type default)
			)
			(layer "F.SilkS")
		)
		(fp_line
			(start 15.367762 -2.564384)
			(end 15.380208 -2.633726)
			(stroke
				(width 0.1)
				(type default)
			)
			(layer "F.SilkS")
		)
		(fp_line
			(start 15.378938 -5.171694)
			(end 14.560042 -4.386326)
			(stroke
				(width 0.1)
				(type default)
			)
			(layer "F.SilkS")
		)
		(fp_line
			(start 15.378938 -5.171694)
			(end 14.560042 -4.386326)
			(stroke
				(width 0.1)
				(type default)
			)
			(layer "F.SilkS")
		)
		(fp_line
			(start 15.378938 -5.171694)
			(end 15.318486 -5.171694)
			(stroke
				(width 0.1)
				(type default)
			)
			(layer "F.SilkS")
		)
		(fp_line
			(start 15.378938 -5.171694)
			(end 15.318486 -5.171694)
			(stroke
				(width 0.1)
				(type default)
			)
			(layer "F.SilkS")
		)
		(fp_line
			(start 15.380208 -2.633726)
			(end 15.392654 -2.703322)
			(stroke
				(width 0.1)
				(type default)
			)
			(layer "F.SilkS")
		)
		(fp_line
			(start 15.380208 -2.633726)
			(end 15.392654 -2.703322)
			(stroke
				(width 0.1)
				(type default)
			)
			(layer "F.SilkS")
		)
		(fp_line
			(start 15.392654 -2.703322)
			(end 15.404592 -2.772664)
			(stroke
				(width 0.1)
				(type default)
			)
			(layer "F.SilkS")
		)
		(fp_line
			(start 15.392654 -2.703322)
			(end 15.404592 -2.772664)
			(stroke
				(width 0.1)
				(type default)
			)
			(layer "F.SilkS")
		)
		(fp_line
			(start 15.404592 -2.772664)
			(end 15.416784 -2.84226)
			(stroke
				(width 0.1)
				(type default)
			)
			(layer "F.SilkS")
		)
		(fp_line
			(start 15.404592 -2.772664)
			(end 15.416784 -2.84226)
			(stroke
				(width 0.1)
				(type default)
			)
			(layer "F.SilkS")
		)
		(fp_line
			(start 15.42923 -2.911602)
			(end 15.416784 -2.84226)
			(stroke
				(width 0.1)
				(type default)
			)
			(layer "F.SilkS")
		)
		(fp_line
			(start 15.42923 -2.911602)
			(end 15.416784 -2.84226)
			(stroke
				(width 0.1)
				(type default)
			)
			(layer "F.SilkS")
		)
		(fp_line
			(start 15.438882 -5.171694)
			(end 14.54785 -4.316984)
			(stroke
				(width 0.1)
				(type default)
			)
			(layer "F.SilkS")
		)
		(fp_line
			(start 15.438882 -5.171694)
			(end 14.54785 -4.316984)
			(stroke
				(width 0.1)
				(type default)
			)
			(layer "F.SilkS")
		)
		(fp_line
			(start 15.438882 -5.171694)
			(end 15.378938 -5.171694)
			(stroke
				(width 0.1)
				(type default)
			)
			(layer "F.SilkS")
		)
		(fp_line
			(start 15.438882 -5.171694)
			(end 15.378938 -5.171694)
			(stroke
				(width 0.1)
				(type default)
			)
			(layer "F.SilkS")
		)
		(fp_line
			(start 15.441168 -2.980944)
			(end 14.084808 -1.679702)
			(stroke
				(width 0.1)
				(type default)
			)
			(layer "F.SilkS")
		)
		(fp_line
			(start 15.441168 -2.980944)
			(end 14.084808 -1.679702)
			(stroke
				(width 0.1)
				(type default)
			)
			(layer "F.SilkS")
		)
		(fp_line
			(start 15.441168 -2.980944)
			(end 15.42923 -2.911602)
			(stroke
				(width 0.1)
				(type default)
			)
			(layer "F.SilkS")
		)
		(fp_line
			(start 15.441168 -2.980944)
			(end 15.42923 -2.911602)
			(stroke
				(width 0.1)
				(type default)
			)
			(layer "F.SilkS")
		)
		(fp_line
			(start 15.45336 -3.050286)
			(end 14.097254 -1.749044)
			(stroke
				(width 0.1)
				(type default)
			)
			(layer "F.SilkS")
		)
		(fp_line
			(start 15.45336 -3.050286)
			(end 14.097254 -1.749044)
			(stroke
				(width 0.1)
				(type default)
			)
			(layer "F.SilkS")
		)
		(fp_line
			(start 15.45336 -3.050286)
			(end 15.441168 -2.980944)
			(stroke
				(width 0.1)
				(type default)
			)
			(layer "F.SilkS")
		)
		(fp_line
			(start 15.45336 -3.050286)
			(end 15.441168 -2.980944)
			(stroke
				(width 0.1)
				(type default)
			)
			(layer "F.SilkS")
		)
		(fp_line
			(start 15.465552 -3.119882)
			(end 14.109192 -1.81864)
			(stroke
				(width 0.1)
				(type default)
			)
			(layer "F.SilkS")
		)
		(fp_line
			(start 15.465552 -3.119882)
			(end 14.109192 -1.81864)
			(stroke
				(width 0.1)
				(type default)
			)
			(layer "F.SilkS")
		)
		(fp_line
			(start 15.465552 -3.119882)
			(end 15.45336 -3.050286)
			(stroke
				(width 0.1)
				(type default)
			)
			(layer "F.SilkS")
		)
		(fp_line
			(start 15.465552 -3.119882)
			(end 15.45336 -3.050286)
			(stroke
				(width 0.1)
				(type default)
			)
			(layer "F.SilkS")
		)
		(fp_line
			(start 15.477998 -3.189224)
			(end 14.121384 -1.887982)
			(stroke
				(width 0.1)
				(type default)
			)
			(layer "F.SilkS")
		)
		(fp_line
			(start 15.477998 -3.189224)
			(end 14.121384 -1.887982)
			(stroke
				(width 0.1)
				(type default)
			)
			(layer "F.SilkS")
		)
		(fp_line
			(start 15.477998 -3.189224)
			(end 15.465552 -3.119882)
			(stroke
				(width 0.1)
				(type default)
			)
			(layer "F.SilkS")
		)
		(fp_line
			(start 15.477998 -3.189224)
			(end 15.465552 -3.119882)
			(stroke
				(width 0.1)
				(type default)
			)
			(layer "F.SilkS")
		)
		(fp_line
			(start 15.491714 -3.260344)
			(end 14.13383 -1.957324)
			(stroke
				(width 0.1)
				(type default)
			)
			(layer "F.SilkS")
		)
		(fp_line
			(start 15.491714 -3.260344)
			(end 14.13383 -1.957324)
			(stroke
				(width 0.1)
				(type default)
			)
			(layer "F.SilkS")
		)
		(fp_line
			(start 15.49908 -5.171694)
			(end 14.535404 -4.247388)
			(stroke
				(width 0.1)
				(type default)
			)
			(layer "F.SilkS")
		)
		(fp_line
			(start 15.49908 -5.171694)
			(end 14.535404 -4.247388)
			(stroke
				(width 0.1)
				(type default)
			)
			(layer "F.SilkS")
		)
		(fp_line
			(start 15.49908 -5.171694)
			(end 15.438882 -5.171694)
			(stroke
				(width 0.1)
				(type default)
			)
			(layer "F.SilkS")
		)
		(fp_line
			(start 15.49908 -5.171694)
			(end 15.438882 -5.171694)
			(stroke
				(width 0.1)
				(type default)
			)
			(layer "F.SilkS")
		)
		(fp_line
			(start 15.508478 -3.334004)
			(end 14.145768 -2.02692)
			(stroke
				(width 0.1)
				(type default)
			)
			(layer "F.SilkS")
		)
		(fp_line
			(start 15.508478 -3.334004)
			(end 14.145768 -2.02692)
			(stroke
				(width 0.1)
				(type default)
			)
			(layer "F.SilkS")
		)
		(fp_line
			(start 15.524988 -3.40741)
			(end 14.15796 -2.096262)
			(stroke
				(width 0.1)
				(type default)
			)
			(layer "F.SilkS")
		)
		(fp_line
			(start 15.524988 -3.40741)
			(end 14.15796 -2.096262)
			(stroke
				(width 0.1)
				(type default)
			)
			(layer "F.SilkS")
		)
		(fp_line
			(start 15.54099 -3.480562)
			(end 14.170406 -2.165604)
			(stroke
				(width 0.1)
				(type default)
			)
			(layer "F.SilkS")
		)
		(fp_line
			(start 15.54099 -3.480562)
			(end 14.170406 -2.165604)
			(stroke
				(width 0.1)
				(type default)
			)
			(layer "F.SilkS")
		)
		(fp_line
			(start 15.559278 -5.171694)
			(end 14.523466 -4.178046)
			(stroke
				(width 0.1)
				(type default)
			)
			(layer "F.SilkS")
		)
		(fp_line
			(start 15.559278 -5.171694)
			(end 14.523466 -4.178046)
			(stroke
				(width 0.1)
				(type default)
			)
			(layer "F.SilkS")
		)
		(fp_line
			(start 15.559278 -5.171694)
			(end 15.49908 -5.171694)
			(stroke
				(width 0.1)
				(type default)
			)
			(layer "F.SilkS")
		)
		(fp_line
			(start 15.559278 -5.171694)
			(end 15.49908 -5.171694)
			(stroke
				(width 0.1)
				(type default)
			)
			(layer "F.SilkS")
		)
		(fp_line
			(start 15.570962 -3.566922)
			(end 14.182344 -2.234946)
			(stroke
				(width 0.1)
				(type default)
			)
			(layer "F.SilkS")
		)
		(fp_line
			(start 15.570962 -3.566922)
			(end 14.182344 -2.234946)
			(stroke
				(width 0.1)
				(type default)
			)
			(layer "F.SilkS")
		)
		(fp_line
			(start 15.601442 -3.654044)
			(end 14.194282 -2.304288)
			(stroke
				(width 0.1)
				(type default)
			)
			(layer "F.SilkS")
		)
		(fp_line
			(start 15.601442 -3.654044)
			(end 14.194282 -2.304288)
			(stroke
				(width 0.1)
				(type default)
			)
			(layer "F.SilkS")
		)
		(fp_line
			(start 15.619222 -5.171694)
			(end 14.511274 -4.108704)
			(stroke
				(width 0.1)
				(type default)
			)
			(layer "F.SilkS")
		)
		(fp_line
			(start 15.619222 -5.171694)
			(end 14.511274 -4.108704)
			(stroke
				(width 0.1)
				(type default)
			)
			(layer "F.SilkS")
		)
		(fp_line
			(start 15.619222 -5.171694)
			(end 15.559278 -5.171694)
			(stroke
				(width 0.1)
				(type default)
			)
			(layer "F.SilkS")
		)
		(fp_line
			(start 15.619222 -5.171694)
			(end 15.559278 -5.171694)
			(stroke
				(width 0.1)
				(type default)
			)
			(layer "F.SilkS")
		)
		(fp_line
			(start 15.649702 -3.75793)
			(end 14.206728 -2.373884)
			(stroke
				(width 0.1)
				(type default)
			)
			(layer "F.SilkS")
		)
		(fp_line
			(start 15.649702 -3.75793)
			(end 14.206728 -2.373884)
			(stroke
				(width 0.1)
				(type default)
			)
			(layer "F.SilkS")
		)
		(fp_line
			(start 15.679166 -5.171694)
			(end 14.498828 -4.039362)
			(stroke
				(width 0.1)
				(type default)
			)
			(layer "F.SilkS")
		)
		(fp_line
			(start 15.679166 -5.171694)
			(end 14.498828 -4.039362)
			(stroke
				(width 0.1)
				(type default)
			)
			(layer "F.SilkS")
		)
		(fp_line
			(start 15.679166 -5.171694)
			(end 15.619222 -5.171694)
			(stroke
				(width 0.1)
				(type default)
			)
			(layer "F.SilkS")
		)
		(fp_line
			(start 15.679166 -5.171694)
			(end 15.619222 -5.171694)
			(stroke
				(width 0.1)
				(type default)
			)
			(layer "F.SilkS")
		)
		(fp_line
			(start 15.729458 -3.892296)
			(end 14.21892 -2.443226)
			(stroke
				(width 0.1)
				(type default)
			)
			(layer "F.SilkS")
		)
		(fp_line
			(start 15.729458 -3.892296)
			(end 14.21892 -2.443226)
			(stroke
				(width 0.1)
				(type default)
			)
			(layer "F.SilkS")
		)
		(fp_line
			(start 15.739618 -5.171694)
			(end 14.486636 -3.969766)
			(stroke
				(width 0.1)
				(type default)
			)
			(layer "F.SilkS")
		)
		(fp_line
			(start 15.739618 -5.171694)
			(end 14.486636 -3.969766)
			(stroke
				(width 0.1)
				(type default)
			)
			(layer "F.SilkS")
		)
		(fp_line
			(start 15.739618 -5.171694)
			(end 15.679166 -5.171694)
			(stroke
				(width 0.1)
				(type default)
			)
			(layer "F.SilkS")
		)
		(fp_line
			(start 15.739618 -5.171694)
			(end 15.679166 -5.171694)
			(stroke
				(width 0.1)
				(type default)
			)
			(layer "F.SilkS")
		)
		(fp_line
			(start 15.781274 -4.923028)
			(end 14.42593 -3.622802)
			(stroke
				(width 0.1)
				(type default)
			)
			(layer "F.SilkS")
		)
		(fp_line
			(start 15.781274 -4.923028)
			(end 14.42593 -3.622802)
			(stroke
				(width 0.1)
				(type default)
			)
			(layer "F.SilkS")
		)
		(fp_line
			(start 15.781274 -4.923028)
			(end 15.79372 -4.992624)
			(stroke
				(width 0.1)
				(type default)
			)
			(layer "F.SilkS")
		)
		(fp_line
			(start 15.781274 -4.923028)
			(end 15.79372 -4.992624)
			(stroke
				(width 0.1)
				(type default)
			)
			(layer "F.SilkS")
		)
		(fp_line
			(start 15.79372 -4.992624)
			(end 14.438376 -3.692398)
			(stroke
				(width 0.1)
				(type default)
			)
			(layer "F.SilkS")
		)
		(fp_line
			(start 15.79372 -4.992624)
			(end 14.438376 -3.692398)
			(stroke
				(width 0.1)
				(type default)
			)
			(layer "F.SilkS")
		)
		(fp_line
			(start 15.79372 -4.992624)
			(end 15.805658 -5.061966)
			(stroke
				(width 0.1)
				(type default)
			)
			(layer "F.SilkS")
		)
		(fp_line
			(start 15.79372 -4.992624)
			(end 15.805658 -5.061966)
			(stroke
				(width 0.1)
				(type default)
			)
			(layer "F.SilkS")
		)
		(fp_line
			(start 15.799816 -5.171694)
			(end 14.474952 -3.900424)
			(stroke
				(width 0.1)
				(type default)
			)
			(layer "F.SilkS")
		)
		(fp_line
			(start 15.799816 -5.171694)
			(end 14.474952 -3.900424)
			(stroke
				(width 0.1)
				(type default)
			)
			(layer "F.SilkS")
		)
		(fp_line
			(start 15.799816 -5.171694)
			(end 15.739618 -5.171694)
			(stroke
				(width 0.1)
				(type default)
			)
			(layer "F.SilkS")
		)
		(fp_line
			(start 15.799816 -5.171694)
			(end 15.739618 -5.171694)
			(stroke
				(width 0.1)
				(type default)
			)
			(layer "F.SilkS")
		)
		(fp_line
			(start 15.805658 -5.061966)
			(end 14.45006 -3.76174)
			(stroke
				(width 0.1)
				(type default)
			)
			(layer "F.SilkS")
		)
		(fp_line
			(start 15.805658 -5.061966)
			(end 14.45006 -3.76174)
			(stroke
				(width 0.1)
				(type default)
			)
			(layer "F.SilkS")
		)
		(fp_line
			(start 15.805658 -5.061966)
			(end 15.81785 -5.131308)
			(stroke
				(width 0.1)
				(type default)
			)
			(layer "F.SilkS")
		)
		(fp_line
			(start 15.805658 -5.061966)
			(end 15.81785 -5.131308)
			(stroke
				(width 0.1)
				(type default)
			)
			(layer "F.SilkS")
		)
		(fp_line
			(start 15.81785 -5.131308)
			(end 14.462506 -3.831082)
			(stroke
				(width 0.1)
				(type default)
			)
			(layer "F.SilkS")
		)
		(fp_line
			(start 15.81785 -5.131308)
			(end 14.462506 -3.831082)
			(stroke
				(width 0.1)
				(type default)
			)
			(layer "F.SilkS")
		)
		(fp_line
			(start 15.81785 -5.131308)
			(end 15.824962 -5.171694)
			(stroke
				(width 0.1)
				(type default)
			)
			(layer "F.SilkS")
		)
		(fp_line
			(start 15.81785 -5.131308)
			(end 15.824962 -5.171694)
			(stroke
				(width 0.1)
				(type default)
			)
			(layer "F.SilkS")
		)
		(fp_line
			(start 15.824962 -5.171694)
			(end 15.799816 -5.171694)
			(stroke
				(width 0.1)
				(type default)
			)
			(layer "F.SilkS")
		)
		(fp_line
			(start 15.824962 -5.171694)
			(end 15.799816 -5.171694)
			(stroke
				(width 0.1)
				(type default)
			)
			(layer "F.SilkS")
		)
		(fp_line
			(start 15.884652 -4.96443)
			(end 14.413484 -3.55346)
			(stroke
				(width 0.1)
				(type default)
			)
			(layer "F.SilkS")
		)
		(fp_line
			(start 15.884652 -4.96443)
			(end 14.413484 -3.55346)
			(stroke
				(width 0.1)
				(type default)
			)
			(layer "F.SilkS")
		)
		(fp_line
			(start 16.049498 -5.065268)
			(end 14.401546 -3.484118)
			(stroke
				(width 0.1)
				(type default)
			)
			(layer "F.SilkS")
		)
		(fp_line
			(start 16.049498 -5.065268)
			(end 14.401546 -3.484118)
			(stroke
				(width 0.1)
				(type default)
			)
			(layer "F.SilkS")
		)
		(fp_line
			(start 16.169132 -5.12191)
			(end 14.389354 -3.414776)
			(stroke
				(width 0.1)
				(type default)
			)
			(layer "F.SilkS")
		)
		(fp_line
			(start 16.169132 -5.12191)
			(end 14.389354 -3.414776)
			(stroke
				(width 0.1)
				(type default)
			)
			(layer "F.SilkS")
		)
		(fp_line
			(start 16.270986 -5.161788)
			(end 14.376908 -3.34518)
			(stroke
				(width 0.1)
				(type default)
			)
			(layer "F.SilkS")
		)
		(fp_line
			(start 16.270986 -5.161788)
			(end 14.376908 -3.34518)
			(stroke
				(width 0.1)
				(type default)
			)
			(layer "F.SilkS")
		)
		(fp_line
			(start 16.355568 -5.18541)
			(end 14.36497 -3.275838)
			(stroke
				(width 0.1)
				(type default)
			)
			(layer "F.SilkS")
		)
		(fp_line
			(start 16.355568 -5.18541)
			(end 14.36497 -3.275838)
			(stroke
				(width 0.1)
				(type default)
			)
			(layer "F.SilkS")
		)
		(fp_line
			(start 16.439896 -5.208778)
			(end 14.352778 -3.206496)
			(stroke
				(width 0.1)
				(type default)
			)
			(layer "F.SilkS")
		)
		(fp_line
			(start 16.439896 -5.208778)
			(end 14.352778 -3.206496)
			(stroke
				(width 0.1)
				(type default)
			)
			(layer "F.SilkS")
		)
		(fp_line
			(start 16.52397 -5.231638)
			(end 14.340586 -3.137154)
			(stroke
				(width 0.1)
				(type default)
			)
			(layer "F.SilkS")
		)
		(fp_line
			(start 16.52397 -5.231638)
			(end 14.340586 -3.137154)
			(stroke
				(width 0.1)
				(type default)
			)
			(layer "F.SilkS")
		)
		(fp_line
			(start 16.533622 -0.882904)
			(end 16.562832 -0.882904)
			(stroke
				(width 0.1)
				(type default)
			)
			(layer "F.SilkS")
		)
		(fp_line
			(start 16.533622 -0.882904)
			(end 16.562832 -0.882904)
			(stroke
				(width 0.1)
				(type default)
			)
			(layer "F.SilkS")
		)
		(fp_line
			(start 16.539718 -0.918464)
			(end 16.533622 -0.882904)
			(stroke
				(width 0.1)
				(type default)
			)
			(layer "F.SilkS")
		)
		(fp_line
			(start 16.539718 -0.918464)
			(end 16.533622 -0.882904)
			(stroke
				(width 0.1)
				(type default)
			)
			(layer "F.SilkS")
		)
		(fp_line
			(start 16.539718 -0.918464)
			(end 17.896586 -2.21996)
			(stroke
				(width 0.1)
				(type default)
			)
			(layer "F.SilkS")
		)
		(fp_line
			(start 16.539718 -0.918464)
			(end 17.896586 -2.21996)
			(stroke
				(width 0.1)
				(type default)
			)
			(layer "F.SilkS")
		)
		(fp_line
			(start 16.552164 -0.987806)
			(end 16.539718 -0.918464)
			(stroke
				(width 0.1)
				(type default)
			)
			(layer "F.SilkS")
		)
		(fp_line
			(start 16.552164 -0.987806)
			(end 16.539718 -0.918464)
			(stroke
				(width 0.1)
				(type default)
			)
			(layer "F.SilkS")
		)
		(fp_line
			(start 16.552164 -0.987806)
			(end 17.908524 -2.289048)
			(stroke
				(width 0.1)
				(type default)
			)
			(layer "F.SilkS")
		)
		(fp_line
			(start 16.552164 -0.987806)
			(end 17.908524 -2.289048)
			(stroke
				(width 0.1)
				(type default)
			)
			(layer "F.SilkS")
		)
		(fp_line
			(start 16.562832 -0.882904)
			(end 16.623284 -0.882904)
			(stroke
				(width 0.1)
				(type default)
			)
			(layer "F.SilkS")
		)
		(fp_line
			(start 16.562832 -0.882904)
			(end 16.623284 -0.882904)
			(stroke
				(width 0.1)
				(type default)
			)
			(layer "F.SilkS")
		)
		(fp_line
			(start 16.562832 -0.882904)
			(end 17.88414 -2.150364)
			(stroke
				(width 0.1)
				(type default)
			)
			(layer "F.SilkS")
		)
		(fp_line
			(start 16.562832 -0.882904)
			(end 17.88414 -2.150364)
			(stroke
				(width 0.1)
				(type default)
			)
			(layer "F.SilkS")
		)
		(fp_line
			(start 16.564356 -1.057148)
			(end 16.552164 -0.987806)
			(stroke
				(width 0.1)
				(type default)
			)
			(layer "F.SilkS")
		)
		(fp_line
			(start 16.564356 -1.057148)
			(end 16.552164 -0.987806)
			(stroke
				(width 0.1)
				(type default)
			)
			(layer "F.SilkS")
		)
		(fp_line
			(start 16.564356 -1.057148)
			(end 17.920716 -2.35839)
			(stroke
				(width 0.1)
				(type default)
			)
			(layer "F.SilkS")
		)
		(fp_line
			(start 16.564356 -1.057148)
			(end 17.920716 -2.35839)
			(stroke
				(width 0.1)
				(type default)
			)
			(layer "F.SilkS")
		)
		(fp_line
			(start 16.576294 -1.126744)
			(end 16.564356 -1.057148)
			(stroke
				(width 0.1)
				(type default)
			)
			(layer "F.SilkS")
		)
		(fp_line
			(start 16.576294 -1.126744)
			(end 16.564356 -1.057148)
			(stroke
				(width 0.1)
				(type default)
			)
			(layer "F.SilkS")
		)
		(fp_line
			(start 16.576294 -1.126744)
			(end 17.932908 -2.427732)
			(stroke
				(width 0.1)
				(type default)
			)
			(layer "F.SilkS")
		)
		(fp_line
			(start 16.576294 -1.126744)
			(end 17.932908 -2.427732)
			(stroke
				(width 0.1)
				(type default)
			)
			(layer "F.SilkS")
		)
		(fp_line
			(start 16.58874 -1.196086)
			(end 16.576294 -1.126744)
			(stroke
				(width 0.1)
				(type default)
			)
			(layer "F.SilkS")
		)
		(fp_line
			(start 16.58874 -1.196086)
			(end 16.576294 -1.126744)
			(stroke
				(width 0.1)
				(type default)
			)
			(layer "F.SilkS")
		)
		(fp_line
			(start 16.58874 -1.196086)
			(end 17.9451 -2.497328)
			(stroke
				(width 0.1)
				(type default)
			)
			(layer "F.SilkS")
		)
		(fp_line
			(start 16.58874 -1.196086)
			(end 17.9451 -2.497328)
			(stroke
				(width 0.1)
				(type default)
			)
			(layer "F.SilkS")
		)
		(fp_line
			(start 16.590772 -5.237734)
			(end 14.328394 -3.067558)
			(stroke
				(width 0.1)
				(type default)
			)
			(layer "F.SilkS")
		)
		(fp_line
			(start 16.590772 -5.237734)
			(end 14.328394 -3.067558)
			(stroke
				(width 0.1)
				(type default)
			)
			(layer "F.SilkS")
		)
		(fp_line
			(start 16.600932 -1.265428)
			(end 16.58874 -1.196086)
			(stroke
				(width 0.1)
				(type default)
			)
			(layer "F.SilkS")
		)
		(fp_line
			(start 16.600932 -1.265428)
			(end 16.58874 -1.196086)
			(stroke
				(width 0.1)
				(type default)
			)
			(layer "F.SilkS")
		)
		(fp_line
			(start 16.600932 -1.265428)
			(end 17.957038 -2.56667)
			(stroke
				(width 0.1)
				(type default)
			)
			(layer "F.SilkS")
		)
		(fp_line
			(start 16.600932 -1.265428)
			(end 17.957038 -2.56667)
			(stroke
				(width 0.1)
				(type default)
			)
			(layer "F.SilkS")
		)
		(fp_line
			(start 16.61287 -1.33477)
			(end 16.600932 -1.265428)
			(stroke
				(width 0.1)
				(type default)
			)
			(layer "F.SilkS")
		)
		(fp_line
			(start 16.61287 -1.33477)
			(end 16.600932 -1.265428)
			(stroke
				(width 0.1)
				(type default)
			)
			(layer "F.SilkS")
		)
		(fp_line
			(start 16.61287 -1.33477)
			(end 17.969484 -2.636012)
			(stroke
				(width 0.1)
				(type default)
			)
			(layer "F.SilkS")
		)
		(fp_line
			(start 16.61287 -1.33477)
			(end 17.969484 -2.636012)
			(stroke
				(width 0.1)
				(type default)
			)
			(layer "F.SilkS")
		)
		(fp_line
			(start 16.623284 -0.882904)
			(end 16.683228 -0.882904)
			(stroke
				(width 0.1)
				(type default)
			)
			(layer "F.SilkS")
		)
		(fp_line
			(start 16.623284 -0.882904)
			(end 16.683228 -0.882904)
			(stroke
				(width 0.1)
				(type default)
			)
			(layer "F.SilkS")
		)
		(fp_line
			(start 16.623284 -0.882904)
			(end 17.871948 -2.081022)
			(stroke
				(width 0.1)
				(type default)
			)
			(layer "F.SilkS")
		)
		(fp_line
			(start 16.623284 -0.882904)
			(end 17.871948 -2.081022)
			(stroke
				(width 0.1)
				(type default)
			)
			(layer "F.SilkS")
		)
		(fp_line
			(start 16.625316 -1.404366)
			(end 16.61287 -1.33477)
			(stroke
				(width 0.1)
				(type default)
			)
			(layer "F.SilkS")
		)
		(fp_line
			(start 16.625316 -1.404366)
			(end 16.61287 -1.33477)
			(stroke
				(width 0.1)
				(type default)
			)
			(layer "F.SilkS")
		)
		(fp_line
			(start 16.625316 -1.404366)
			(end 17.981676 -2.705608)
			(stroke
				(width 0.1)
				(type default)
			)
			(layer "F.SilkS")
		)
		(fp_line
			(start 16.625316 -1.404366)
			(end 17.981676 -2.705608)
			(stroke
				(width 0.1)
				(type default)
			)
			(layer "F.SilkS")
		)
		(fp_line
			(start 16.637762 -1.473962)
			(end 16.625316 -1.404366)
			(stroke
				(width 0.1)
				(type default)
			)
			(layer "F.SilkS")
		)
		(fp_line
			(start 16.637762 -1.473962)
			(end 16.625316 -1.404366)
			(stroke
				(width 0.1)
				(type default)
			)
			(layer "F.SilkS")
		)
		(fp_line
			(start 16.637762 -1.473962)
			(end 17.993614 -2.77495)
			(stroke
				(width 0.1)
				(type default)
			)
			(layer "F.SilkS")
		)
		(fp_line
			(start 16.637762 -1.473962)
			(end 17.993614 -2.77495)
			(stroke
				(width 0.1)
				(type default)
			)
			(layer "F.SilkS")
		)
		(fp_line
			(start 16.6497 -1.54305)
			(end 16.637762 -1.473962)
			(stroke
				(width 0.1)
				(type default)
			)
			(layer "F.SilkS")
		)
		(fp_line
			(start 16.6497 -1.54305)
			(end 16.637762 -1.473962)
			(stroke
				(width 0.1)
				(type default)
			)
			(layer "F.SilkS")
		)
		(fp_line
			(start 16.6497 -1.54305)
			(end 18.00606 -2.844292)
			(stroke
				(width 0.1)
				(type default)
			)
			(layer "F.SilkS")
		)
		(fp_line
			(start 16.6497 -1.54305)
			(end 18.00606 -2.844292)
			(stroke
				(width 0.1)
				(type default)
			)
			(layer "F.SilkS")
		)
		(fp_line
			(start 16.657066 -5.24383)
			(end 14.316456 -2.998216)
			(stroke
				(width 0.1)
				(type default)
			)
			(layer "F.SilkS")
		)
		(fp_line
			(start 16.657066 -5.24383)
			(end 14.316456 -2.998216)
			(stroke
				(width 0.1)
				(type default)
			)
			(layer "F.SilkS")
		)
		(fp_line
			(start 16.661892 -1.612646)
			(end 16.6497 -1.54305)
			(stroke
				(width 0.1)
				(type default)
			)
			(layer "F.SilkS")
		)
		(fp_line
			(start 16.661892 -1.612646)
			(end 16.6497 -1.54305)
			(stroke
				(width 0.1)
				(type default)
			)
			(layer "F.SilkS")
		)
		(fp_line
			(start 16.661892 -1.612646)
			(end 18.017998 -2.913634)
			(stroke
				(width 0.1)
				(type default)
			)
			(layer "F.SilkS")
		)
		(fp_line
			(start 16.661892 -1.612646)
			(end 18.017998 -2.913634)
			(stroke
				(width 0.1)
				(type default)
			)
			(layer "F.SilkS")
		)
		(fp_line
			(start 16.674084 -1.681988)
			(end 16.661892 -1.612646)
			(stroke
				(width 0.1)
				(type default)
			)
			(layer "F.SilkS")
		)
		(fp_line
			(start 16.674084 -1.681988)
			(end 16.661892 -1.612646)
			(stroke
				(width 0.1)
				(type default)
			)
			(layer "F.SilkS")
		)
		(fp_line
			(start 16.674084 -1.681988)
			(end 18.03019 -2.982976)
			(stroke
				(width 0.1)
				(type default)
			)
			(layer "F.SilkS")
		)
		(fp_line
			(start 16.674084 -1.681988)
			(end 18.03019 -2.982976)
			(stroke
				(width 0.1)
				(type default)
			)
			(layer "F.SilkS")
		)
		(fp_line
			(start 16.683228 -0.882904)
			(end 16.743426 -0.882904)
			(stroke
				(width 0.1)
				(type default)
			)
			(layer "F.SilkS")
		)
		(fp_line
			(start 16.683228 -0.882904)
			(end 16.743426 -0.882904)
			(stroke
				(width 0.1)
				(type default)
			)
			(layer "F.SilkS")
		)
		(fp_line
			(start 16.683228 -0.882904)
			(end 17.86001 -2.011426)
			(stroke
				(width 0.1)
				(type default)
			)
			(layer "F.SilkS")
		)
		(fp_line
			(start 16.683228 -0.882904)
			(end 17.86001 -2.011426)
			(stroke
				(width 0.1)
				(type default)
			)
			(layer "F.SilkS")
		)
		(fp_line
			(start 16.686276 -1.751584)
			(end 16.674084 -1.681988)
			(stroke
				(width 0.1)
				(type default)
			)
			(layer "F.SilkS")
		)
		(fp_line
			(start 16.686276 -1.751584)
			(end 16.674084 -1.681988)
			(stroke
				(width 0.1)
				(type default)
			)
			(layer "F.SilkS")
		)
		(fp_line
			(start 16.686276 -1.751584)
			(end 18.042636 -3.052572)
			(stroke
				(width 0.1)
				(type default)
			)
			(layer "F.SilkS")
		)
		(fp_line
			(start 16.686276 -1.751584)
			(end 18.042636 -3.052572)
			(stroke
				(width 0.1)
				(type default)
			)
			(layer "F.SilkS")
		)
		(fp_line
			(start 16.698214 -1.820926)
			(end 16.686276 -1.751584)
			(stroke
				(width 0.1)
				(type default)
			)
			(layer "F.SilkS")
		)
		(fp_line
			(start 16.698214 -1.820926)
			(end 16.686276 -1.751584)
			(stroke
				(width 0.1)
				(type default)
			)
			(layer "F.SilkS")
		)
		(fp_line
			(start 16.698214 -1.820926)
			(end 18.054574 -3.121914)
			(stroke
				(width 0.1)
				(type default)
			)
			(layer "F.SilkS")
		)
		(fp_line
			(start 16.698214 -1.820926)
			(end 18.054574 -3.121914)
			(stroke
				(width 0.1)
				(type default)
			)
			(layer "F.SilkS")
		)
		(fp_line
			(start 16.71066 -1.890268)
			(end 16.698214 -1.820926)
			(stroke
				(width 0.1)
				(type default)
			)
			(layer "F.SilkS")
		)
		(fp_line
			(start 16.71066 -1.890268)
			(end 16.698214 -1.820926)
			(stroke
				(width 0.1)
				(type default)
			)
			(layer "F.SilkS")
		)
		(fp_line
			(start 16.71066 -1.890268)
			(end 18.066766 -3.191002)
			(stroke
				(width 0.1)
				(type default)
			)
			(layer "F.SilkS")
		)
		(fp_line
			(start 16.71066 -1.890268)
			(end 18.066766 -3.191002)
			(stroke
				(width 0.1)
				(type default)
			)
			(layer "F.SilkS")
		)
		(fp_line
			(start 16.723106 -1.95961)
			(end 16.71066 -1.890268)
			(stroke
				(width 0.1)
				(type default)
			)
			(layer "F.SilkS")
		)
		(fp_line
			(start 16.723106 -1.95961)
			(end 16.71066 -1.890268)
			(stroke
				(width 0.1)
				(type default)
			)
			(layer "F.SilkS")
		)
		(fp_line
			(start 16.723106 -1.95961)
			(end 18.079212 -3.260598)
			(stroke
				(width 0.1)
				(type default)
			)
			(layer "F.SilkS")
		)
		(fp_line
			(start 16.723106 -1.95961)
			(end 18.079212 -3.260598)
			(stroke
				(width 0.1)
				(type default)
			)
			(layer "F.SilkS")
		)
		(fp_line
			(start 16.723868 -5.25018)
			(end 14.30401 -2.928874)
			(stroke
				(width 0.1)
				(type default)
			)
			(layer "F.SilkS")
		)
		(fp_line
			(start 16.723868 -5.25018)
			(end 14.30401 -2.928874)
			(stroke
				(width 0.1)
				(type default)
			)
			(layer "F.SilkS")
		)
		(fp_line
			(start 16.735044 -2.028952)
			(end 16.723106 -1.95961)
			(stroke
				(width 0.1)
				(type default)
			)
			(layer "F.SilkS")
		)
		(fp_line
			(start 16.735044 -2.028952)
			(end 16.723106 -1.95961)
			(stroke
				(width 0.1)
				(type default)
			)
			(layer "F.SilkS")
		)
		(fp_line
			(start 16.735044 -2.028952)
			(end 18.089372 -3.328416)
			(stroke
				(width 0.1)
				(type default)
			)
			(layer "F.SilkS")
		)
		(fp_line
			(start 16.735044 -2.028952)
			(end 18.089372 -3.328416)
			(stroke
				(width 0.1)
				(type default)
			)
			(layer "F.SilkS")
		)
		(fp_line
			(start 16.743426 -0.882904)
			(end 16.803624 -0.882904)
			(stroke
				(width 0.1)
				(type default)
			)
			(layer "F.SilkS")
		)
		(fp_line
			(start 16.743426 -0.882904)
			(end 16.803624 -0.882904)
			(stroke
				(width 0.1)
				(type default)
			)
			(layer "F.SilkS")
		)
		(fp_line
			(start 16.743426 -0.882904)
			(end 17.847564 -1.942338)
			(stroke
				(width 0.1)
				(type default)
			)
			(layer "F.SilkS")
		)
		(fp_line
			(start 16.743426 -0.882904)
			(end 17.847564 -1.942338)
			(stroke
				(width 0.1)
				(type default)
			)
			(layer "F.SilkS")
		)
		(fp_line
			(start 16.747236 -2.098548)
			(end 16.735044 -2.028952)
			(stroke
				(width 0.1)
				(type default)
			)
			(layer "F.SilkS")
		)
		(fp_line
			(start 16.747236 -2.098548)
			(end 16.735044 -2.028952)
			(stroke
				(width 0.1)
				(type default)
			)
			(layer "F.SilkS")
		)
		(fp_line
			(start 16.747236 -2.098548)
			(end 18.097246 -3.393694)
			(stroke
				(width 0.1)
				(type default)
			)
			(layer "F.SilkS")
		)
		(fp_line
			(start 16.747236 -2.098548)
			(end 18.097246 -3.393694)
			(stroke
				(width 0.1)
				(type default)
			)
			(layer "F.SilkS")
		)
		(fp_line
			(start 16.759682 -2.16789)
			(end 16.747236 -2.098548)
			(stroke
				(width 0.1)
				(type default)
			)
			(layer "F.SilkS")
		)
		(fp_line
			(start 16.759682 -2.16789)
			(end 16.747236 -2.098548)
			(stroke
				(width 0.1)
				(type default)
			)
			(layer "F.SilkS")
		)
		(fp_line
			(start 16.759682 -2.16789)
			(end 18.105374 -3.458718)
			(stroke
				(width 0.1)
				(type default)
			)
			(layer "F.SilkS")
		)
		(fp_line
			(start 16.759682 -2.16789)
			(end 18.105374 -3.458718)
			(stroke
				(width 0.1)
				(type default)
			)
			(layer "F.SilkS")
		)
		(fp_line
			(start 16.77162 -2.237232)
			(end 16.759682 -2.16789)
			(stroke
				(width 0.1)
				(type default)
			)
			(layer "F.SilkS")
		)
		(fp_line
			(start 16.77162 -2.237232)
			(end 16.759682 -2.16789)
			(stroke
				(width 0.1)
				(type default)
			)
			(layer "F.SilkS")
		)
		(fp_line
			(start 16.77162 -2.237232)
			(end 18.113248 -3.52425)
			(stroke
				(width 0.1)
				(type default)
			)
			(layer "F.SilkS")
		)
		(fp_line
			(start 16.77162 -2.237232)
			(end 18.113248 -3.52425)
			(stroke
				(width 0.1)
				(type default)
			)
			(layer "F.SilkS")
		)
		(fp_line
			(start 16.783812 -2.306828)
			(end 16.77162 -2.237232)
			(stroke
				(width 0.1)
				(type default)
			)
			(layer "F.SilkS")
		)
		(fp_line
			(start 16.783812 -2.306828)
			(end 16.77162 -2.237232)
			(stroke
				(width 0.1)
				(type default)
			)
			(layer "F.SilkS")
		)
		(fp_line
			(start 16.783812 -2.306828)
			(end 18.121122 -3.589782)
			(stroke
				(width 0.1)
				(type default)
			)
			(layer "F.SilkS")
		)
		(fp_line
			(start 16.783812 -2.306828)
			(end 18.121122 -3.589782)
			(stroke
				(width 0.1)
				(type default)
			)
			(layer "F.SilkS")
		)
		(fp_line
			(start 16.790162 -5.256022)
			(end 14.291818 -2.859532)
			(stroke
				(width 0.1)
				(type default)
			)
			(layer "F.SilkS")
		)
		(fp_line
			(start 16.790162 -5.256022)
			(end 14.291818 -2.859532)
			(stroke
				(width 0.1)
				(type default)
			)
			(layer "F.SilkS")
		)
		(fp_line
			(start 16.796258 -2.37617)
			(end 16.783812 -2.306828)
			(stroke
				(width 0.1)
				(type default)
			)
			(layer "F.SilkS")
		)
		(fp_line
			(start 16.796258 -2.37617)
			(end 16.783812 -2.306828)
			(stroke
				(width 0.1)
				(type default)
			)
			(layer "F.SilkS")
		)
		(fp_line
			(start 16.796258 -2.37617)
			(end 18.129504 -3.65506)
			(stroke
				(width 0.1)
				(type default)
			)
			(layer "F.SilkS")
		)
		(fp_line
			(start 16.796258 -2.37617)
			(end 18.129504 -3.65506)
			(stroke
				(width 0.1)
				(type default)
			)
			(layer "F.SilkS")
		)
		(fp_line
			(start 16.803624 -0.882904)
			(end 16.863568 -0.882904)
			(stroke
				(width 0.1)
				(type default)
			)
			(layer "F.SilkS")
		)
		(fp_line
			(start 16.803624 -0.882904)
			(end 16.863568 -0.882904)
			(stroke
				(width 0.1)
				(type default)
			)
			(layer "F.SilkS")
		)
		(fp_line
			(start 16.803624 -0.882904)
			(end 17.835626 -1.872742)
			(stroke
				(width 0.1)
				(type default)
			)
			(layer "F.SilkS")
		)
		(fp_line
			(start 16.803624 -0.882904)
			(end 17.835626 -1.872742)
			(stroke
				(width 0.1)
				(type default)
			)
			(layer "F.SilkS")
		)
		(fp_line
			(start 16.808196 -2.445512)
			(end 16.796258 -2.37617)
			(stroke
				(width 0.1)
				(type default)
			)
			(layer "F.SilkS")
		)
		(fp_line
			(start 16.808196 -2.445512)
			(end 16.796258 -2.37617)
			(stroke
				(width 0.1)
				(type default)
			)
			(layer "F.SilkS")
		)
		(fp_line
			(start 16.808196 -2.445512)
			(end 18.13687 -3.720338)
			(stroke
				(width 0.1)
				(type default)
			)
			(layer "F.SilkS")
		)
		(fp_line
			(start 16.808196 -2.445512)
			(end 18.13687 -3.720338)
			(stroke
				(width 0.1)
				(type default)
			)
			(layer "F.SilkS")
		)
		(fp_line
			(start 16.820134 -2.515108)
			(end 16.808196 -2.445512)
			(stroke
				(width 0.1)
				(type default)
			)
			(layer "F.SilkS")
		)
		(fp_line
			(start 16.820134 -2.515108)
			(end 16.808196 -2.445512)
			(stroke
				(width 0.1)
				(type default)
			)
			(layer "F.SilkS")
		)
		(fp_line
			(start 16.820134 -2.515108)
			(end 16.83258 -2.58445)
			(stroke
				(width 0.1)
				(type default)
			)
			(layer "F.SilkS")
		)
		(fp_line
			(start 16.820134 -2.515108)
			(end 16.83258 -2.58445)
			(stroke
				(width 0.1)
				(type default)
			)
			(layer "F.SilkS")
		)
		(fp_line
			(start 16.820134 -2.515108)
			(end 18.138394 -3.779266)
			(stroke
				(width 0.1)
				(type default)
			)
			(layer "F.SilkS")
		)
		(fp_line
			(start 16.820134 -2.515108)
			(end 18.138394 -3.779266)
			(stroke
				(width 0.1)
				(type default)
			)
			(layer "F.SilkS")
		)
		(fp_line
			(start 16.845026 -2.653792)
			(end 16.83258 -2.58445)
			(stroke
				(width 0.1)
				(type default)
			)
			(layer "F.SilkS")
		)
		(fp_line
			(start 16.845026 -2.653792)
			(end 16.83258 -2.58445)
			(stroke
				(width 0.1)
				(type default)
			)
			(layer "F.SilkS")
		)
		(fp_line
			(start 16.845026 -2.653792)
			(end 18.137378 -3.89382)
			(stroke
				(width 0.1)
				(type default)
			)
			(layer "F.SilkS")
		)
		(fp_line
			(start 16.845026 -2.653792)
			(end 18.137378 -3.89382)
			(stroke
				(width 0.1)
				(type default)
			)
			(layer "F.SilkS")
		)
		(fp_line
			(start 16.854678 -5.26034)
			(end 14.27988 -2.79019)
			(stroke
				(width 0.1)
				(type default)
			)
			(layer "F.SilkS")
		)
		(fp_line
			(start 16.854678 -5.26034)
			(end 14.27988 -2.79019)
			(stroke
				(width 0.1)
				(type default)
			)
			(layer "F.SilkS")
		)
		(fp_line
			(start 16.857218 -2.723134)
			(end 16.845026 -2.653792)
			(stroke
				(width 0.1)
				(type default)
			)
			(layer "F.SilkS")
		)
		(fp_line
			(start 16.857218 -2.723134)
			(end 16.845026 -2.653792)
			(stroke
				(width 0.1)
				(type default)
			)
			(layer "F.SilkS")
		)
		(fp_line
			(start 16.857218 -2.723134)
			(end 18.13687 -3.95097)
			(stroke
				(width 0.1)
				(type default)
			)
			(layer "F.SilkS")
		)
		(fp_line
			(start 16.857218 -2.723134)
			(end 18.13687 -3.95097)
			(stroke
				(width 0.1)
				(type default)
			)
			(layer "F.SilkS")
		)
		(fp_line
			(start 16.863568 -0.882904)
			(end 16.92402 -0.882904)
			(stroke
				(width 0.1)
				(type default)
			)
			(layer "F.SilkS")
		)
		(fp_line
			(start 16.863568 -0.882904)
			(end 16.92402 -0.882904)
			(stroke
				(width 0.1)
				(type default)
			)
			(layer "F.SilkS")
		)
		(fp_line
			(start 16.863568 -0.882904)
			(end 17.823434 -1.8034)
			(stroke
				(width 0.1)
				(type default)
			)
			(layer "F.SilkS")
		)
		(fp_line
			(start 16.863568 -0.882904)
			(end 17.823434 -1.8034)
			(stroke
				(width 0.1)
				(type default)
			)
			(layer "F.SilkS")
		)
		(fp_line
			(start 16.869156 -2.79273)
			(end 16.857218 -2.723134)
			(stroke
				(width 0.1)
				(type default)
			)
			(layer "F.SilkS")
		)
		(fp_line
			(start 16.869156 -2.79273)
			(end 16.857218 -2.723134)
			(stroke
				(width 0.1)
				(type default)
			)
			(layer "F.SilkS")
		)
		(fp_line
			(start 16.869156 -2.79273)
			(end 18.136362 -4.008374)
			(stroke
				(width 0.1)
				(type default)
			)
			(layer "F.SilkS")
		)
		(fp_line
			(start 16.869156 -2.79273)
			(end 18.136362 -4.008374)
			(stroke
				(width 0.1)
				(type default)
			)
			(layer "F.SilkS")
		)
		(fp_line
			(start 16.881602 -2.862072)
			(end 16.869156 -2.79273)
			(stroke
				(width 0.1)
				(type default)
			)
			(layer "F.SilkS")
		)
		(fp_line
			(start 16.881602 -2.862072)
			(end 16.869156 -2.79273)
			(stroke
				(width 0.1)
				(type default)
			)
			(layer "F.SilkS")
		)
		(fp_line
			(start 16.881602 -2.862072)
			(end 18.136362 -4.065524)
			(stroke
				(width 0.1)
				(type default)
			)
			(layer "F.SilkS")
		)
		(fp_line
			(start 16.881602 -2.862072)
			(end 18.136362 -4.065524)
			(stroke
				(width 0.1)
				(type default)
			)
			(layer "F.SilkS")
		)
		(fp_line
			(start 16.89354 -2.931414)
			(end 16.881602 -2.862072)
			(stroke
				(width 0.1)
				(type default)
			)
			(layer "F.SilkS")
		)
		(fp_line
			(start 16.89354 -2.931414)
			(end 16.881602 -2.862072)
			(stroke
				(width 0.1)
				(type default)
			)
			(layer "F.SilkS")
		)
		(fp_line
			(start 16.89354 -2.931414)
			(end 18.134838 -4.121912)
			(stroke
				(width 0.1)
				(type default)
			)
			(layer "F.SilkS")
		)
		(fp_line
			(start 16.89354 -2.931414)
			(end 18.134838 -4.121912)
			(stroke
				(width 0.1)
				(type default)
			)
			(layer "F.SilkS")
		)
		(fp_line
			(start 16.905732 -3.000756)
			(end 16.89354 -2.931414)
			(stroke
				(width 0.1)
				(type default)
			)
			(layer "F.SilkS")
		)
		(fp_line
			(start 16.905732 -3.000756)
			(end 16.89354 -2.931414)
			(stroke
				(width 0.1)
				(type default)
			)
			(layer "F.SilkS")
		)
		(fp_line
			(start 16.905732 -3.000756)
			(end 18.125948 -4.171188)
			(stroke
				(width 0.1)
				(type default)
			)
			(layer "F.SilkS")
		)
		(fp_line
			(start 16.905732 -3.000756)
			(end 18.125948 -4.171188)
			(stroke
				(width 0.1)
				(type default)
			)
			(layer "F.SilkS")
		)
		(fp_line
			(start 16.909796 -5.255514)
			(end 14.267434 -2.720594)
			(stroke
				(width 0.1)
				(type default)
			)
			(layer "F.SilkS")
		)
		(fp_line
			(start 16.909796 -5.255514)
			(end 14.267434 -2.720594)
			(stroke
				(width 0.1)
				(type default)
			)
			(layer "F.SilkS")
		)
		(fp_line
			(start 16.918178 -3.070352)
			(end 16.905732 -3.000756)
			(stroke
				(width 0.1)
				(type default)
			)
			(layer "F.SilkS")
		)
		(fp_line
			(start 16.918178 -3.070352)
			(end 16.905732 -3.000756)
			(stroke
				(width 0.1)
				(type default)
			)
			(layer "F.SilkS")
		)
		(fp_line
			(start 16.918178 -3.070352)
			(end 18.117058 -4.220464)
			(stroke
				(width 0.1)
				(type default)
			)
			(layer "F.SilkS")
		)
		(fp_line
			(start 16.918178 -3.070352)
			(end 18.117058 -4.220464)
			(stroke
				(width 0.1)
				(type default)
			)
			(layer "F.SilkS")
		)
		(fp_line
			(start 16.92402 -0.882904)
			(end 16.984218 -0.882904)
			(stroke
				(width 0.1)
				(type default)
			)
			(layer "F.SilkS")
		)
		(fp_line
			(start 16.92402 -0.882904)
			(end 16.984218 -0.882904)
			(stroke
				(width 0.1)
				(type default)
			)
			(layer "F.SilkS")
		)
		(fp_line
			(start 16.92402 -0.882904)
			(end 17.810988 -1.734058)
			(stroke
				(width 0.1)
				(type default)
			)
			(layer "F.SilkS")
		)
		(fp_line
			(start 16.92402 -0.882904)
			(end 17.810988 -1.734058)
			(stroke
				(width 0.1)
				(type default)
			)
			(layer "F.SilkS")
		)
		(fp_line
			(start 16.930624 -3.139694)
			(end 16.918178 -3.070352)
			(stroke
				(width 0.1)
				(type default)
			)
			(layer "F.SilkS")
		)
		(fp_line
			(start 16.930624 -3.139694)
			(end 16.918178 -3.070352)
			(stroke
				(width 0.1)
				(type default)
			)
			(layer "F.SilkS")
		)
		(fp_line
			(start 16.96466 -5.25018)
			(end 14.255496 -2.651506)
			(stroke
				(width 0.1)
				(type default)
			)
			(layer "F.SilkS")
		)
		(fp_line
			(start 16.96466 -5.25018)
			(end 14.255496 -2.651506)
			(stroke
				(width 0.1)
				(type default)
			)
			(layer "F.SilkS")
		)
		(fp_line
			(start 16.984218 -0.882904)
			(end 17.044162 -0.882904)
			(stroke
				(width 0.1)
				(type default)
			)
			(layer "F.SilkS")
		)
		(fp_line
			(start 16.984218 -0.882904)
			(end 17.044162 -0.882904)
			(stroke
				(width 0.1)
				(type default)
			)
			(layer "F.SilkS")
		)
		(fp_line
			(start 16.984218 -0.882904)
			(end 17.79905 -1.664716)
			(stroke
				(width 0.1)
				(type default)
			)
			(layer "F.SilkS")
		)
		(fp_line
			(start 16.984218 -0.882904)
			(end 17.79905 -1.664716)
			(stroke
				(width 0.1)
				(type default)
			)
			(layer "F.SilkS")
		)
		(fp_line
			(start 17.01927 -5.245354)
			(end 14.243304 -2.58191)
			(stroke
				(width 0.1)
				(type default)
			)
			(layer "F.SilkS")
		)
		(fp_line
			(start 17.01927 -5.245354)
			(end 14.243304 -2.58191)
			(stroke
				(width 0.1)
				(type default)
			)
			(layer "F.SilkS")
		)
		(fp_line
			(start 17.044162 -0.882904)
			(end 17.10436 -0.882904)
			(stroke
				(width 0.1)
				(type default)
			)
			(layer "F.SilkS")
		)
		(fp_line
			(start 17.044162 -0.882904)
			(end 17.10436 -0.882904)
			(stroke
				(width 0.1)
				(type default)
			)
			(layer "F.SilkS")
		)
		(fp_line
			(start 17.044162 -0.882904)
			(end 17.786858 -1.595374)
			(stroke
				(width 0.1)
				(type default)
			)
			(layer "F.SilkS")
		)
		(fp_line
			(start 17.044162 -0.882904)
			(end 17.786858 -1.595374)
			(stroke
				(width 0.1)
				(type default)
			)
			(layer "F.SilkS")
		)
		(fp_line
			(start 17.074388 -5.240274)
			(end 14.230858 -2.512314)
			(stroke
				(width 0.1)
				(type default)
			)
			(layer "F.SilkS")
		)
		(fp_line
			(start 17.074388 -5.240274)
			(end 14.230858 -2.512314)
			(stroke
				(width 0.1)
				(type default)
			)
			(layer "F.SilkS")
		)
		(fp_line
			(start 17.10436 -0.882904)
			(end 17.164812 -0.882904)
			(stroke
				(width 0.1)
				(type default)
			)
			(layer "F.SilkS")
		)
		(fp_line
			(start 17.10436 -0.882904)
			(end 17.164812 -0.882904)
			(stroke
				(width 0.1)
				(type default)
			)
			(layer "F.SilkS")
		)
		(fp_line
			(start 17.10436 -0.882904)
			(end 17.774666 -1.525778)
			(stroke
				(width 0.1)
				(type default)
			)
			(layer "F.SilkS")
		)
		(fp_line
			(start 17.10436 -0.882904)
			(end 17.774666 -1.525778)
			(stroke
				(width 0.1)
				(type default)
			)
			(layer "F.SilkS")
		)
		(fp_line
			(start 17.129252 -5.235194)
			(end 15.934944 -4.0894)
			(stroke
				(width 0.1)
				(type default)
			)
			(layer "F.SilkS")
		)
		(fp_line
			(start 17.129252 -5.235194)
			(end 15.934944 -4.0894)
			(stroke
				(width 0.1)
				(type default)
			)
			(layer "F.SilkS")
		)
		(fp_line
			(start 17.164812 -0.882904)
			(end 17.224756 -0.882904)
			(stroke
				(width 0.1)
				(type default)
			)
			(layer "F.SilkS")
		)
		(fp_line
			(start 17.164812 -0.882904)
			(end 17.224756 -0.882904)
			(stroke
				(width 0.1)
				(type default)
			)
			(layer "F.SilkS")
		)
		(fp_line
			(start 17.164812 -0.882904)
			(end 17.762474 -1.456436)
			(stroke
				(width 0.1)
				(type default)
			)
			(layer "F.SilkS")
		)
		(fp_line
			(start 17.164812 -0.882904)
			(end 17.762474 -1.456436)
			(stroke
				(width 0.1)
				(type default)
			)
			(layer "F.SilkS")
		)
		(fp_line
			(start 17.184116 -5.230114)
			(end 16.052292 -4.144264)
			(stroke
				(width 0.1)
				(type default)
			)
			(layer "F.SilkS")
		)
		(fp_line
			(start 17.184116 -5.230114)
			(end 16.052292 -4.144264)
			(stroke
				(width 0.1)
				(type default)
			)
			(layer "F.SilkS")
		)
		(fp_line
			(start 17.224756 -0.882904)
			(end 17.284954 -0.882904)
			(stroke
				(width 0.1)
				(type default)
			)
			(layer "F.SilkS")
		)
		(fp_line
			(start 17.224756 -0.882904)
			(end 17.284954 -0.882904)
			(stroke
				(width 0.1)
				(type default)
			)
			(layer "F.SilkS")
		)
		(fp_line
			(start 17.224756 -0.882904)
			(end 17.750536 -1.387348)
			(stroke
				(width 0.1)
				(type default)
			)
			(layer "F.SilkS")
		)
		(fp_line
			(start 17.224756 -0.882904)
			(end 17.750536 -1.387348)
			(stroke
				(width 0.1)
				(type default)
			)
			(layer "F.SilkS")
		)
		(fp_line
			(start 17.235678 -5.221986)
			(end 16.13789 -4.168648)
			(stroke
				(width 0.1)
				(type default)
			)
			(layer "F.SilkS")
		)
		(fp_line
			(start 17.235678 -5.221986)
			(end 16.13789 -4.168648)
			(stroke
				(width 0.1)
				(type default)
			)
			(layer "F.SilkS")
		)
		(fp_line
			(start 17.280636 -5.207254)
			(end 16.218154 -4.187698)
			(stroke
				(width 0.1)
				(type default)
			)
			(layer "F.SilkS")
		)
		(fp_line
			(start 17.280636 -5.207254)
			(end 16.218154 -4.187698)
			(stroke
				(width 0.1)
				(type default)
			)
			(layer "F.SilkS")
		)
		(fp_line
			(start 17.284954 -0.882904)
			(end 17.345406 -0.882904)
			(stroke
				(width 0.1)
				(type default)
			)
			(layer "F.SilkS")
		)
		(fp_line
			(start 17.284954 -0.882904)
			(end 17.345406 -0.882904)
			(stroke
				(width 0.1)
				(type default)
			)
			(layer "F.SilkS")
		)
		(fp_line
			(start 17.284954 -0.882904)
			(end 17.73809 -1.317752)
			(stroke
				(width 0.1)
				(type default)
			)
			(layer "F.SilkS")
		)
		(fp_line
			(start 17.284954 -0.882904)
			(end 17.73809 -1.317752)
			(stroke
				(width 0.1)
				(type default)
			)
			(layer "F.SilkS")
		)
		(fp_line
			(start 17.32534 -5.192522)
			(end 16.283178 -4.192524)
			(stroke
				(width 0.1)
				(type default)
			)
			(layer "F.SilkS")
		)
		(fp_line
			(start 17.32534 -5.192522)
			(end 16.283178 -4.192524)
			(stroke
				(width 0.1)
				(type default)
			)
			(layer "F.SilkS")
		)
		(fp_line
			(start 17.345406 -0.882904)
			(end 17.40535 -0.882904)
			(stroke
				(width 0.1)
				(type default)
			)
			(layer "F.SilkS")
		)
		(fp_line
			(start 17.345406 -0.882904)
			(end 17.40535 -0.882904)
			(stroke
				(width 0.1)
				(type default)
			)
			(layer "F.SilkS")
		)
		(fp_line
			(start 17.345406 -0.882904)
			(end 17.725898 -1.248156)
			(stroke
				(width 0.1)
				(type default)
			)
			(layer "F.SilkS")
		)
		(fp_line
			(start 17.345406 -0.882904)
			(end 17.725898 -1.248156)
			(stroke
				(width 0.1)
				(type default)
			)
			(layer "F.SilkS")
		)
		(fp_line
			(start 17.370044 -5.17779)
			(end 16.347948 -4.197096)
			(stroke
				(width 0.1)
				(type default)
			)
			(layer "F.SilkS")
		)
		(fp_line
			(start 17.370044 -5.17779)
			(end 16.347948 -4.197096)
			(stroke
				(width 0.1)
				(type default)
			)
			(layer "F.SilkS")
		)
		(fp_line
			(start 17.40535 -0.882904)
			(end 17.465294 -0.882904)
			(stroke
				(width 0.1)
				(type default)
			)
			(layer "F.SilkS")
		)
		(fp_line
			(start 17.40535 -0.882904)
			(end 17.465294 -0.882904)
			(stroke
				(width 0.1)
				(type default)
			)
			(layer "F.SilkS")
		)
		(fp_line
			(start 17.40535 -0.882904)
			(end 17.71396 -1.178814)
			(stroke
				(width 0.1)
				(type default)
			)
			(layer "F.SilkS")
		)
		(fp_line
			(start 17.40535 -0.882904)
			(end 17.71396 -1.178814)
			(stroke
				(width 0.1)
				(type default)
			)
			(layer "F.SilkS")
		)
		(fp_line
			(start 17.415002 -5.163058)
			(end 16.40967 -4.198366)
			(stroke
				(width 0.1)
				(type default)
			)
			(layer "F.SilkS")
		)
		(fp_line
			(start 17.415002 -5.163058)
			(end 16.40967 -4.198366)
			(stroke
				(width 0.1)
				(type default)
			)
			(layer "F.SilkS")
		)
		(fp_line
			(start 17.45996 -5.148326)
			(end 16.465804 -4.194556)
			(stroke
				(width 0.1)
				(type default)
			)
			(layer "F.SilkS")
		)
		(fp_line
			(start 17.45996 -5.148326)
			(end 16.465804 -4.194556)
			(stroke
				(width 0.1)
				(type default)
			)
			(layer "F.SilkS")
		)
		(fp_line
			(start 17.465294 -0.882904)
			(end 17.525746 -0.882904)
			(stroke
				(width 0.1)
				(type default)
			)
			(layer "F.SilkS")
		)
		(fp_line
			(start 17.465294 -0.882904)
			(end 17.525746 -0.882904)
			(stroke
				(width 0.1)
				(type default)
			)
			(layer "F.SilkS")
		)
		(fp_line
			(start 17.465294 -0.882904)
			(end 17.701514 -1.109472)
			(stroke
				(width 0.1)
				(type default)
			)
			(layer "F.SilkS")
		)
		(fp_line
			(start 17.465294 -0.882904)
			(end 17.701514 -1.109472)
			(stroke
				(width 0.1)
				(type default)
			)
			(layer "F.SilkS")
		)
		(fp_line
			(start 17.50441 -5.13334)
			(end 16.521938 -4.190746)
			(stroke
				(width 0.1)
				(type default)
			)
			(layer "F.SilkS")
		)
		(fp_line
			(start 17.50441 -5.13334)
			(end 16.521938 -4.190746)
			(stroke
				(width 0.1)
				(type default)
			)
			(layer "F.SilkS")
		)
		(fp_line
			(start 17.525746 -0.882904)
			(end 17.58569 -0.882904)
			(stroke
				(width 0.1)
				(type default)
			)
			(layer "F.SilkS")
		)
		(fp_line
			(start 17.525746 -0.882904)
			(end 17.58569 -0.882904)
			(stroke
				(width 0.1)
				(type default)
			)
			(layer "F.SilkS")
		)
		(fp_line
			(start 17.525746 -0.882904)
			(end 17.689576 -1.04013)
			(stroke
				(width 0.1)
				(type default)
			)
			(layer "F.SilkS")
		)
		(fp_line
			(start 17.525746 -0.882904)
			(end 17.689576 -1.04013)
			(stroke
				(width 0.1)
				(type default)
			)
			(layer "F.SilkS")
		)
		(fp_line
			(start 17.545558 -5.115052)
			(end 16.5735 -4.182872)
			(stroke
				(width 0.1)
				(type default)
			)
			(layer "F.SilkS")
		)
		(fp_line
			(start 17.545558 -5.115052)
			(end 16.5735 -4.182872)
			(stroke
				(width 0.1)
				(type default)
			)
			(layer "F.SilkS")
		)
		(fp_line
			(start 17.580864 -5.091176)
			(end 16.621252 -4.170426)
			(stroke
				(width 0.1)
				(type default)
			)
			(layer "F.SilkS")
		)
		(fp_line
			(start 17.580864 -5.091176)
			(end 16.621252 -4.170426)
			(stroke
				(width 0.1)
				(type default)
			)
			(layer "F.SilkS")
		)
		(fp_line
			(start 17.58569 -0.882904)
			(end 17.645634 -0.882904)
			(stroke
				(width 0.1)
				(type default)
			)
			(layer "F.SilkS")
		)
		(fp_line
			(start 17.58569 -0.882904)
			(end 17.645634 -0.882904)
			(stroke
				(width 0.1)
				(type default)
			)
			(layer "F.SilkS")
		)
		(fp_line
			(start 17.58569 -0.882904)
			(end 17.677384 -0.970788)
			(stroke
				(width 0.1)
				(type default)
			)
			(layer "F.SilkS")
		)
		(fp_line
			(start 17.58569 -0.882904)
			(end 17.677384 -0.970788)
			(stroke
				(width 0.1)
				(type default)
			)
			(layer "F.SilkS")
		)
		(fp_line
			(start 17.61617 -5.067046)
			(end 16.668242 -4.15798)
			(stroke
				(width 0.1)
				(type default)
			)
			(layer "F.SilkS")
		)
		(fp_line
			(start 17.61617 -5.067046)
			(end 16.668242 -4.15798)
			(stroke
				(width 0.1)
				(type default)
			)
			(layer "F.SilkS")
		)
		(fp_line
			(start 17.645634 -0.882904)
			(end 17.66189 -0.882904)
			(stroke
				(width 0.1)
				(type default)
			)
			(layer "F.SilkS")
		)
		(fp_line
			(start 17.645634 -0.882904)
			(end 17.66189 -0.882904)
			(stroke
				(width 0.1)
				(type default)
			)
			(layer "F.SilkS")
		)
		(fp_line
			(start 17.645634 -0.882904)
			(end 17.664938 -0.901192)
			(stroke
				(width 0.1)
				(type default)
			)
			(layer "F.SilkS")
		)
		(fp_line
			(start 17.645634 -0.882904)
			(end 17.664938 -0.901192)
			(stroke
				(width 0.1)
				(type default)
			)
			(layer "F.SilkS")
		)
		(fp_line
			(start 17.651222 -5.043424)
			(end 16.71066 -4.140962)
			(stroke
				(width 0.1)
				(type default)
			)
			(layer "F.SilkS")
		)
		(fp_line
			(start 17.651222 -5.043424)
			(end 16.71066 -4.140962)
			(stroke
				(width 0.1)
				(type default)
			)
			(layer "F.SilkS")
		)
		(fp_line
			(start 17.66189 -0.882904)
			(end 17.664938 -0.901192)
			(stroke
				(width 0.1)
				(type default)
			)
			(layer "F.SilkS")
		)
		(fp_line
			(start 17.66189 -0.882904)
			(end 17.664938 -0.901192)
			(stroke
				(width 0.1)
				(type default)
			)
			(layer "F.SilkS")
		)
		(fp_line
			(start 17.677384 -0.970788)
			(end 17.664938 -0.901192)
			(stroke
				(width 0.1)
				(type default)
			)
			(layer "F.SilkS")
		)
		(fp_line
			(start 17.677384 -0.970788)
			(end 17.664938 -0.901192)
			(stroke
				(width 0.1)
				(type default)
			)
			(layer "F.SilkS")
		)
		(fp_line
			(start 17.686274 -5.019294)
			(end 16.747998 -4.119118)
			(stroke
				(width 0.1)
				(type default)
			)
			(layer "F.SilkS")
		)
		(fp_line
			(start 17.686274 -5.019294)
			(end 16.747998 -4.119118)
			(stroke
				(width 0.1)
				(type default)
			)
			(layer "F.SilkS")
		)
		(fp_line
			(start 17.689576 -1.04013)
			(end 17.677384 -0.970788)
			(stroke
				(width 0.1)
				(type default)
			)
			(layer "F.SilkS")
		)
		(fp_line
			(start 17.689576 -1.04013)
			(end 17.677384 -0.970788)
			(stroke
				(width 0.1)
				(type default)
			)
			(layer "F.SilkS")
		)
		(fp_line
			(start 17.701514 -1.109472)
			(end 17.689576 -1.04013)
			(stroke
				(width 0.1)
				(type default)
			)
			(layer "F.SilkS")
		)
		(fp_line
			(start 17.701514 -1.109472)
			(end 17.689576 -1.04013)
			(stroke
				(width 0.1)
				(type default)
			)
			(layer "F.SilkS")
		)
		(fp_line
			(start 17.71396 -1.178814)
			(end 17.701514 -1.109472)
			(stroke
				(width 0.1)
				(type default)
			)
			(layer "F.SilkS")
		)
		(fp_line
			(start 17.71396 -1.178814)
			(end 17.701514 -1.109472)
			(stroke
				(width 0.1)
				(type default)
			)
			(layer "F.SilkS")
		)
		(fp_line
			(start 17.721834 -4.995672)
			(end 16.785844 -4.097782)
			(stroke
				(width 0.1)
				(type default)
			)
			(layer "F.SilkS")
		)
		(fp_line
			(start 17.721834 -4.995672)
			(end 16.785844 -4.097782)
			(stroke
				(width 0.1)
				(type default)
			)
			(layer "F.SilkS")
		)
		(fp_line
			(start 17.725898 -1.248156)
			(end 17.71396 -1.178814)
			(stroke
				(width 0.1)
				(type default)
			)
			(layer "F.SilkS")
		)
		(fp_line
			(start 17.725898 -1.248156)
			(end 17.71396 -1.178814)
			(stroke
				(width 0.1)
				(type default)
			)
			(layer "F.SilkS")
		)
		(fp_line
			(start 17.73809 -1.317752)
			(end 17.725898 -1.248156)
			(stroke
				(width 0.1)
				(type default)
			)
			(layer "F.SilkS")
		)
		(fp_line
			(start 17.73809 -1.317752)
			(end 17.725898 -1.248156)
			(stroke
				(width 0.1)
				(type default)
			)
			(layer "F.SilkS")
		)
		(fp_line
			(start 17.750536 -1.387348)
			(end 17.73809 -1.317752)
			(stroke
				(width 0.1)
				(type default)
			)
			(layer "F.SilkS")
		)
		(fp_line
			(start 17.750536 -1.387348)
			(end 17.73809 -1.317752)
			(stroke
				(width 0.1)
				(type default)
			)
			(layer "F.SilkS")
		)
		(fp_line
			(start 17.757394 -4.971796)
			(end 16.818102 -4.071112)
			(stroke
				(width 0.1)
				(type default)
			)
			(layer "F.SilkS")
		)
		(fp_line
			(start 17.757394 -4.971796)
			(end 16.818102 -4.071112)
			(stroke
				(width 0.1)
				(type default)
			)
			(layer "F.SilkS")
		)
		(fp_line
			(start 17.762474 -1.456436)
			(end 17.750536 -1.387348)
			(stroke
				(width 0.1)
				(type default)
			)
			(layer "F.SilkS")
		)
		(fp_line
			(start 17.762474 -1.456436)
			(end 17.750536 -1.387348)
			(stroke
				(width 0.1)
				(type default)
			)
			(layer "F.SilkS")
		)
		(fp_line
			(start 17.774666 -1.525778)
			(end 17.762474 -1.456436)
			(stroke
				(width 0.1)
				(type default)
			)
			(layer "F.SilkS")
		)
		(fp_line
			(start 17.774666 -1.525778)
			(end 17.762474 -1.456436)
			(stroke
				(width 0.1)
				(type default)
			)
			(layer "F.SilkS")
		)
		(fp_line
			(start 17.786858 -1.595374)
			(end 17.774666 -1.525778)
			(stroke
				(width 0.1)
				(type default)
			)
			(layer "F.SilkS")
		)
		(fp_line
			(start 17.786858 -1.595374)
			(end 17.774666 -1.525778)
			(stroke
				(width 0.1)
				(type default)
			)
			(layer "F.SilkS")
		)
		(fp_line
			(start 17.78762 -4.943348)
			(end 16.845788 -4.03987)
			(stroke
				(width 0.1)
				(type default)
			)
			(layer "F.SilkS")
		)
		(fp_line
			(start 17.78762 -4.943348)
			(end 16.845788 -4.03987)
			(stroke
				(width 0.1)
				(type default)
			)
			(layer "F.SilkS")
		)
		(fp_line
			(start 17.79905 -1.664716)
			(end 17.786858 -1.595374)
			(stroke
				(width 0.1)
				(type default)
			)
			(layer "F.SilkS")
		)
		(fp_line
			(start 17.79905 -1.664716)
			(end 17.786858 -1.595374)
			(stroke
				(width 0.1)
				(type default)
			)
			(layer "F.SilkS")
		)
		(fp_line
			(start 17.810988 -1.734058)
			(end 17.79905 -1.664716)
			(stroke
				(width 0.1)
				(type default)
			)
			(layer "F.SilkS")
		)
		(fp_line
			(start 17.810988 -1.734058)
			(end 17.79905 -1.664716)
			(stroke
				(width 0.1)
				(type default)
			)
			(layer "F.SilkS")
		)
		(fp_line
			(start 17.813782 -4.910836)
			(end 16.87322 -4.008882)
			(stroke
				(width 0.1)
				(type default)
			)
			(layer "F.SilkS")
		)
		(fp_line
			(start 17.813782 -4.910836)
			(end 16.87322 -4.008882)
			(stroke
				(width 0.1)
				(type default)
			)
			(layer "F.SilkS")
		)
		(fp_line
			(start 17.823434 -1.8034)
			(end 17.810988 -1.734058)
			(stroke
				(width 0.1)
				(type default)
			)
			(layer "F.SilkS")
		)
		(fp_line
			(start 17.823434 -1.8034)
			(end 17.810988 -1.734058)
			(stroke
				(width 0.1)
				(type default)
			)
			(layer "F.SilkS")
		)
		(fp_line
			(start 17.835626 -1.872742)
			(end 17.823434 -1.8034)
			(stroke
				(width 0.1)
				(type default)
			)
			(layer "F.SilkS")
		)
		(fp_line
			(start 17.835626 -1.872742)
			(end 17.823434 -1.8034)
			(stroke
				(width 0.1)
				(type default)
			)
			(layer "F.SilkS")
		)
		(fp_line
			(start 17.839944 -4.878324)
			(end 16.89735 -3.97383)
			(stroke
				(width 0.1)
				(type default)
			)
			(layer "F.SilkS")
		)
		(fp_line
			(start 17.839944 -4.878324)
			(end 16.89735 -3.97383)
			(stroke
				(width 0.1)
				(type default)
			)
			(layer "F.SilkS")
		)
		(fp_line
			(start 17.847564 -1.942338)
			(end 17.835626 -1.872742)
			(stroke
				(width 0.1)
				(type default)
			)
			(layer "F.SilkS")
		)
		(fp_line
			(start 17.847564 -1.942338)
			(end 17.835626 -1.872742)
			(stroke
				(width 0.1)
				(type default)
			)
			(layer "F.SilkS")
		)
		(fp_line
			(start 17.86001 -2.011426)
			(end 17.847564 -1.942338)
			(stroke
				(width 0.1)
				(type default)
			)
			(layer "F.SilkS")
		)
		(fp_line
			(start 17.86001 -2.011426)
			(end 17.847564 -1.942338)
			(stroke
				(width 0.1)
				(type default)
			)
			(layer "F.SilkS")
		)
		(fp_line
			(start 17.866106 -4.845558)
			(end 16.915384 -3.93319)
			(stroke
				(width 0.1)
				(type default)
			)
			(layer "F.SilkS")
		)
		(fp_line
			(start 17.866106 -4.845558)
			(end 16.915384 -3.93319)
			(stroke
				(width 0.1)
				(type default)
			)
			(layer "F.SilkS")
		)
		(fp_line
			(start 17.871948 -2.081022)
			(end 17.86001 -2.011426)
			(stroke
				(width 0.1)
				(type default)
			)
			(layer "F.SilkS")
		)
		(fp_line
			(start 17.871948 -2.081022)
			(end 17.86001 -2.011426)
			(stroke
				(width 0.1)
				(type default)
			)
			(layer "F.SilkS")
		)
		(fp_line
			(start 17.88414 -2.150364)
			(end 17.871948 -2.081022)
			(stroke
				(width 0.1)
				(type default)
			)
			(layer "F.SilkS")
		)
		(fp_line
			(start 17.88414 -2.150364)
			(end 17.871948 -2.081022)
			(stroke
				(width 0.1)
				(type default)
			)
			(layer "F.SilkS")
		)
		(fp_line
			(start 17.892268 -4.813046)
			(end 16.93291 -3.89255)
			(stroke
				(width 0.1)
				(type default)
			)
			(layer "F.SilkS")
		)
		(fp_line
			(start 17.892268 -4.813046)
			(end 16.93291 -3.89255)
			(stroke
				(width 0.1)
				(type default)
			)
			(layer "F.SilkS")
		)
		(fp_line
			(start 17.896586 -2.21996)
			(end 17.88414 -2.150364)
			(stroke
				(width 0.1)
				(type default)
			)
			(layer "F.SilkS")
		)
		(fp_line
			(start 17.896586 -2.21996)
			(end 17.88414 -2.150364)
			(stroke
				(width 0.1)
				(type default)
			)
			(layer "F.SilkS")
		)
		(fp_line
			(start 17.908524 -2.289048)
			(end 17.896586 -2.21996)
			(stroke
				(width 0.1)
				(type default)
			)
			(layer "F.SilkS")
		)
		(fp_line
			(start 17.908524 -2.289048)
			(end 17.896586 -2.21996)
			(stroke
				(width 0.1)
				(type default)
			)
			(layer "F.SilkS")
		)
		(fp_line
			(start 17.91843 -4.780534)
			(end 16.949674 -3.850894)
			(stroke
				(width 0.1)
				(type default)
			)
			(layer "F.SilkS")
		)
		(fp_line
			(start 17.91843 -4.780534)
			(end 16.949674 -3.850894)
			(stroke
				(width 0.1)
				(type default)
			)
			(layer "F.SilkS")
		)
		(fp_line
			(start 17.920716 -2.35839)
			(end 17.908524 -2.289048)
			(stroke
				(width 0.1)
				(type default)
			)
			(layer "F.SilkS")
		)
		(fp_line
			(start 17.920716 -2.35839)
			(end 17.908524 -2.289048)
			(stroke
				(width 0.1)
				(type default)
			)
			(layer "F.SilkS")
		)
		(fp_line
			(start 17.932908 -2.427732)
			(end 17.920716 -2.35839)
			(stroke
				(width 0.1)
				(type default)
			)
			(layer "F.SilkS")
		)
		(fp_line
			(start 17.932908 -2.427732)
			(end 17.920716 -2.35839)
			(stroke
				(width 0.1)
				(type default)
			)
			(layer "F.SilkS")
		)
		(fp_line
			(start 17.944846 -4.748022)
			(end 16.958056 -3.80111)
			(stroke
				(width 0.1)
				(type default)
			)
			(layer "F.SilkS")
		)
		(fp_line
			(start 17.944846 -4.748022)
			(end 16.958056 -3.80111)
			(stroke
				(width 0.1)
				(type default)
			)
			(layer "F.SilkS")
		)
		(fp_line
			(start 17.9451 -2.497328)
			(end 17.932908 -2.427732)
			(stroke
				(width 0.1)
				(type default)
			)
			(layer "F.SilkS")
		)
		(fp_line
			(start 17.9451 -2.497328)
			(end 17.932908 -2.427732)
			(stroke
				(width 0.1)
				(type default)
			)
			(layer "F.SilkS")
		)
		(fp_line
			(start 17.957038 -2.56667)
			(end 17.9451 -2.497328)
			(stroke
				(width 0.1)
				(type default)
			)
			(layer "F.SilkS")
		)
		(fp_line
			(start 17.957038 -2.56667)
			(end 17.9451 -2.497328)
			(stroke
				(width 0.1)
				(type default)
			)
			(layer "F.SilkS")
		)
		(fp_line
			(start 17.966182 -4.710176)
			(end 16.966438 -3.751326)
			(stroke
				(width 0.1)
				(type default)
			)
			(layer "F.SilkS")
		)
		(fp_line
			(start 17.966182 -4.710176)
			(end 16.966438 -3.751326)
			(stroke
				(width 0.1)
				(type default)
			)
			(layer "F.SilkS")
		)
		(fp_line
			(start 17.969484 -2.636012)
			(end 17.957038 -2.56667)
			(stroke
				(width 0.1)
				(type default)
			)
			(layer "F.SilkS")
		)
		(fp_line
			(start 17.969484 -2.636012)
			(end 17.957038 -2.56667)
			(stroke
				(width 0.1)
				(type default)
			)
			(layer "F.SilkS")
		)
		(fp_line
			(start 17.981676 -2.705608)
			(end 17.969484 -2.636012)
			(stroke
				(width 0.1)
				(type default)
			)
			(layer "F.SilkS")
		)
		(fp_line
			(start 17.981676 -2.705608)
			(end 17.969484 -2.636012)
			(stroke
				(width 0.1)
				(type default)
			)
			(layer "F.SilkS")
		)
		(fp_line
			(start 17.9832 -4.669282)
			(end 16.974566 -3.701542)
			(stroke
				(width 0.1)
				(type default)
			)
			(layer "F.SilkS")
		)
		(fp_line
			(start 17.9832 -4.669282)
			(end 16.974566 -3.701542)
			(stroke
				(width 0.1)
				(type default)
			)
			(layer "F.SilkS")
		)
		(fp_line
			(start 17.993614 -2.77495)
			(end 17.981676 -2.705608)
			(stroke
				(width 0.1)
				(type default)
			)
			(layer "F.SilkS")
		)
		(fp_line
			(start 17.993614 -2.77495)
			(end 17.981676 -2.705608)
			(stroke
				(width 0.1)
				(type default)
			)
			(layer "F.SilkS")
		)
		(fp_line
			(start 18.000472 -4.628388)
			(end 16.97736 -3.646424)
			(stroke
				(width 0.1)
				(type default)
			)
			(layer "F.SilkS")
		)
		(fp_line
			(start 18.000472 -4.628388)
			(end 16.97736 -3.646424)
			(stroke
				(width 0.1)
				(type default)
			)
			(layer "F.SilkS")
		)
		(fp_line
			(start 18.00606 -2.844292)
			(end 17.993614 -2.77495)
			(stroke
				(width 0.1)
				(type default)
			)
			(layer "F.SilkS")
		)
		(fp_line
			(start 18.00606 -2.844292)
			(end 17.993614 -2.77495)
			(stroke
				(width 0.1)
				(type default)
			)
			(layer "F.SilkS")
		)
		(fp_line
			(start 18.017998 -4.58724)
			(end 16.976598 -3.588258)
			(stroke
				(width 0.1)
				(type default)
			)
			(layer "F.SilkS")
		)
		(fp_line
			(start 18.017998 -4.58724)
			(end 16.976598 -3.588258)
			(stroke
				(width 0.1)
				(type default)
			)
			(layer "F.SilkS")
		)
		(fp_line
			(start 18.017998 -2.913634)
			(end 18.00606 -2.844292)
			(stroke
				(width 0.1)
				(type default)
			)
			(layer "F.SilkS")
		)
		(fp_line
			(start 18.017998 -2.913634)
			(end 18.00606 -2.844292)
			(stroke
				(width 0.1)
				(type default)
			)
			(layer "F.SilkS")
		)
		(fp_line
			(start 18.03019 -2.982976)
			(end 18.017998 -2.913634)
			(stroke
				(width 0.1)
				(type default)
			)
			(layer "F.SilkS")
		)
		(fp_line
			(start 18.03019 -2.982976)
			(end 18.017998 -2.913634)
			(stroke
				(width 0.1)
				(type default)
			)
			(layer "F.SilkS")
		)
		(fp_line
			(start 18.035778 -4.546346)
			(end 16.97609 -3.529838)
			(stroke
				(width 0.1)
				(type default)
			)
			(layer "F.SilkS")
		)
		(fp_line
			(start 18.035778 -4.546346)
			(end 16.97609 -3.529838)
			(stroke
				(width 0.1)
				(type default)
			)
			(layer "F.SilkS")
		)
		(fp_line
			(start 18.042636 -3.052572)
			(end 18.03019 -2.982976)
			(stroke
				(width 0.1)
				(type default)
			)
			(layer "F.SilkS")
		)
		(fp_line
			(start 18.042636 -3.052572)
			(end 18.03019 -2.982976)
			(stroke
				(width 0.1)
				(type default)
			)
			(layer "F.SilkS")
		)
		(fp_line
			(start 18.052796 -4.505198)
			(end 16.975582 -3.471672)
			(stroke
				(width 0.1)
				(type default)
			)
			(layer "F.SilkS")
		)
		(fp_line
			(start 18.052796 -4.505198)
			(end 16.975582 -3.471672)
			(stroke
				(width 0.1)
				(type default)
			)
			(layer "F.SilkS")
		)
		(fp_line
			(start 18.054574 -3.121914)
			(end 18.042636 -3.052572)
			(stroke
				(width 0.1)
				(type default)
			)
			(layer "F.SilkS")
		)
		(fp_line
			(start 18.054574 -3.121914)
			(end 18.042636 -3.052572)
			(stroke
				(width 0.1)
				(type default)
			)
			(layer "F.SilkS")
		)
		(fp_line
			(start 18.066766 -3.191002)
			(end 18.054574 -3.121914)
			(stroke
				(width 0.1)
				(type default)
			)
			(layer "F.SilkS")
		)
		(fp_line
			(start 18.066766 -3.191002)
			(end 18.054574 -3.121914)
			(stroke
				(width 0.1)
				(type default)
			)
			(layer "F.SilkS")
		)
		(fp_line
			(start 18.070068 -4.464304)
			(end 16.967708 -3.406648)
			(stroke
				(width 0.1)
				(type default)
			)
			(layer "F.SilkS")
		)
		(fp_line
			(start 18.070068 -4.464304)
			(end 16.967708 -3.406648)
			(stroke
				(width 0.1)
				(type default)
			)
			(layer "F.SilkS")
		)
		(fp_line
			(start 18.079212 -3.260598)
			(end 18.066766 -3.191002)
			(stroke
				(width 0.1)
				(type default)
			)
			(layer "F.SilkS")
		)
		(fp_line
			(start 18.079212 -3.260598)
			(end 18.066766 -3.191002)
			(stroke
				(width 0.1)
				(type default)
			)
			(layer "F.SilkS")
		)
		(fp_line
			(start 18.081752 -4.417314)
			(end 16.959326 -3.340608)
			(stroke
				(width 0.1)
				(type default)
			)
			(layer "F.SilkS")
		)
		(fp_line
			(start 18.081752 -4.417314)
			(end 16.959326 -3.340608)
			(stroke
				(width 0.1)
				(type default)
			)
			(layer "F.SilkS")
		)
		(fp_line
			(start 18.090388 -4.368038)
			(end 16.950436 -3.274568)
			(stroke
				(width 0.1)
				(type default)
			)
			(layer "F.SilkS")
		)
		(fp_line
			(start 18.090388 -4.368038)
			(end 16.950436 -3.274568)
			(stroke
				(width 0.1)
				(type default)
			)
			(layer "F.SilkS")
		)
		(fp_line
			(start 18.099532 -4.318762)
			(end 16.942308 -3.208782)
			(stroke
				(width 0.1)
				(type default)
			)
			(layer "F.SilkS")
		)
		(fp_line
			(start 18.099532 -4.318762)
			(end 16.942308 -3.208782)
			(stroke
				(width 0.1)
				(type default)
			)
			(layer "F.SilkS")
		)
		(fp_line
			(start 18.107914 -4.26974)
			(end 16.930624 -3.139694)
			(stroke
				(width 0.1)
				(type default)
			)
			(layer "F.SilkS")
		)
		(fp_line
			(start 18.107914 -4.26974)
			(end 16.930624 -3.139694)
			(stroke
				(width 0.1)
				(type default)
			)
			(layer "F.SilkS")
		)
		(fp_line
			(start 18.137632 -3.836416)
			(end 16.83258 -2.58445)
			(stroke
				(width 0.1)
				(type default)
			)
			(layer "F.SilkS")
		)
		(fp_line
			(start 18.137632 -3.836416)
			(end 16.83258 -2.58445)
			(stroke
				(width 0.1)
				(type default)
			)
			(layer "F.SilkS")
		)
		(fp_line
			(start 18.736818 -4.109466)
			(end 18.783554 -4.109466)
			(stroke
				(width 0.1)
				(type default)
			)
			(layer "F.SilkS")
		)
		(fp_line
			(start 18.736818 -4.109466)
			(end 18.783554 -4.109466)
			(stroke
				(width 0.1)
				(type default)
			)
			(layer "F.SilkS")
		)
		(fp_line
			(start 18.739612 -4.12496)
			(end 18.736818 -4.109466)
			(stroke
				(width 0.1)
				(type default)
			)
			(layer "F.SilkS")
		)
		(fp_line
			(start 18.739612 -4.12496)
			(end 18.736818 -4.109466)
			(stroke
				(width 0.1)
				(type default)
			)
			(layer "F.SilkS")
		)
		(fp_line
			(start 18.739612 -4.12496)
			(end 20.959318 -6.254496)
			(stroke
				(width 0.1)
				(type default)
			)
			(layer "F.SilkS")
		)
		(fp_line
			(start 18.739612 -4.12496)
			(end 20.959318 -6.254496)
			(stroke
				(width 0.1)
				(type default)
			)
			(layer "F.SilkS")
		)
		(fp_line
			(start 18.75155 -4.194556)
			(end 18.739612 -4.12496)
			(stroke
				(width 0.1)
				(type default)
			)
			(layer "F.SilkS")
		)
		(fp_line
			(start 18.75155 -4.194556)
			(end 18.739612 -4.12496)
			(stroke
				(width 0.1)
				(type default)
			)
			(layer "F.SilkS")
		)
		(fp_line
			(start 18.763996 -4.263898)
			(end 18.75155 -4.194556)
			(stroke
				(width 0.1)
				(type default)
			)
			(layer "F.SilkS")
		)
		(fp_line
			(start 18.763996 -4.263898)
			(end 18.75155 -4.194556)
			(stroke
				(width 0.1)
				(type default)
			)
			(layer "F.SilkS")
		)
		(fp_line
			(start 18.775934 -4.33324)
			(end 18.763996 -4.263898)
			(stroke
				(width 0.1)
				(type default)
			)
			(layer "F.SilkS")
		)
		(fp_line
			(start 18.775934 -4.33324)
			(end 18.763996 -4.263898)
			(stroke
				(width 0.1)
				(type default)
			)
			(layer "F.SilkS")
		)
		(fp_line
			(start 18.775934 -4.33324)
			(end 18.78838 -4.402836)
			(stroke
				(width 0.1)
				(type default)
			)
			(layer "F.SilkS")
		)
		(fp_line
			(start 18.775934 -4.33324)
			(end 18.78838 -4.402836)
			(stroke
				(width 0.1)
				(type default)
			)
			(layer "F.SilkS")
		)
		(fp_line
			(start 18.783554 -4.109466)
			(end 18.843498 -4.109466)
			(stroke
				(width 0.1)
				(type default)
			)
			(layer "F.SilkS")
		)
		(fp_line
			(start 18.783554 -4.109466)
			(end 18.843498 -4.109466)
			(stroke
				(width 0.1)
				(type default)
			)
			(layer "F.SilkS")
		)
		(fp_line
			(start 18.783554 -4.109466)
			(end 20.947126 -6.1849)
			(stroke
				(width 0.1)
				(type default)
			)
			(layer "F.SilkS")
		)
		(fp_line
			(start 18.783554 -4.109466)
			(end 20.947126 -6.1849)
			(stroke
				(width 0.1)
				(type default)
			)
			(layer "F.SilkS")
		)
		(fp_line
			(start 18.78838 -4.402836)
			(end 18.800572 -4.472178)
			(stroke
				(width 0.1)
				(type default)
			)
			(layer "F.SilkS")
		)
		(fp_line
			(start 18.78838 -4.402836)
			(end 18.800572 -4.472178)
			(stroke
				(width 0.1)
				(type default)
			)
			(layer "F.SilkS")
		)
		(fp_line
			(start 18.78838 -4.402836)
			(end 19.58975 -5.171694)
			(stroke
				(width 0.1)
				(type default)
			)
			(layer "F.SilkS")
		)
		(fp_line
			(start 18.78838 -4.402836)
			(end 19.58975 -5.171694)
			(stroke
				(width 0.1)
				(type default)
			)
			(layer "F.SilkS")
		)
		(fp_line
			(start 18.800572 -4.472178)
			(end 18.81251 -4.54152)
			(stroke
				(width 0.1)
				(type default)
			)
			(layer "F.SilkS")
		)
		(fp_line
			(start 18.800572 -4.472178)
			(end 18.81251 -4.54152)
			(stroke
				(width 0.1)
				(type default)
			)
			(layer "F.SilkS")
		)
		(fp_line
			(start 18.800572 -4.472178)
			(end 19.529806 -5.171694)
			(stroke
				(width 0.1)
				(type default)
			)
			(layer "F.SilkS")
		)
		(fp_line
			(start 18.800572 -4.472178)
			(end 19.529806 -5.171694)
			(stroke
				(width 0.1)
				(type default)
			)
			(layer "F.SilkS")
		)
		(fp_line
			(start 18.81251 -4.54152)
			(end 18.824956 -4.610862)
			(stroke
				(width 0.1)
				(type default)
			)
			(layer "F.SilkS")
		)
		(fp_line
			(start 18.81251 -4.54152)
			(end 18.824956 -4.610862)
			(stroke
				(width 0.1)
				(type default)
			)
			(layer "F.SilkS")
		)
		(fp_line
			(start 18.81251 -4.54152)
			(end 19.469608 -5.171694)
			(stroke
				(width 0.1)
				(type default)
			)
			(layer "F.SilkS")
		)
		(fp_line
			(start 18.81251 -4.54152)
			(end 19.469608 -5.171694)
			(stroke
				(width 0.1)
				(type default)
			)
			(layer "F.SilkS")
		)
		(fp_line
			(start 18.824956 -4.610862)
			(end 18.836894 -4.680458)
			(stroke
				(width 0.1)
				(type default)
			)
			(layer "F.SilkS")
		)
		(fp_line
			(start 18.824956 -4.610862)
			(end 18.836894 -4.680458)
			(stroke
				(width 0.1)
				(type default)
			)
			(layer "F.SilkS")
		)
		(fp_line
			(start 18.824956 -4.610862)
			(end 19.409664 -5.171694)
			(stroke
				(width 0.1)
				(type default)
			)
			(layer "F.SilkS")
		)
		(fp_line
			(start 18.824956 -4.610862)
			(end 19.409664 -5.171694)
			(stroke
				(width 0.1)
				(type default)
			)
			(layer "F.SilkS")
		)
		(fp_line
			(start 18.836894 -4.680458)
			(end 18.84934 -4.7498)
			(stroke
				(width 0.1)
				(type default)
			)
			(layer "F.SilkS")
		)
		(fp_line
			(start 18.836894 -4.680458)
			(end 18.84934 -4.7498)
			(stroke
				(width 0.1)
				(type default)
			)
			(layer "F.SilkS")
		)
		(fp_line
			(start 18.836894 -4.680458)
			(end 19.349212 -5.171694)
			(stroke
				(width 0.1)
				(type default)
			)
			(layer "F.SilkS")
		)
		(fp_line
			(start 18.836894 -4.680458)
			(end 19.349212 -5.171694)
			(stroke
				(width 0.1)
				(type default)
			)
			(layer "F.SilkS")
		)
		(fp_line
			(start 18.843498 -4.109466)
			(end 18.90395 -4.109466)
			(stroke
				(width 0.1)
				(type default)
			)
			(layer "F.SilkS")
		)
		(fp_line
			(start 18.843498 -4.109466)
			(end 18.90395 -4.109466)
			(stroke
				(width 0.1)
				(type default)
			)
			(layer "F.SilkS")
		)
		(fp_line
			(start 18.843498 -4.109466)
			(end 20.93468 -6.115558)
			(stroke
				(width 0.1)
				(type default)
			)
			(layer "F.SilkS")
		)
		(fp_line
			(start 18.843498 -4.109466)
			(end 20.93468 -6.115558)
			(stroke
				(width 0.1)
				(type default)
			)
			(layer "F.SilkS")
		)
		(fp_line
			(start 18.84934 -4.7498)
			(end 18.861532 -4.819142)
			(stroke
				(width 0.1)
				(type default)
			)
			(layer "F.SilkS")
		)
		(fp_line
			(start 18.84934 -4.7498)
			(end 18.861532 -4.819142)
			(stroke
				(width 0.1)
				(type default)
			)
			(layer "F.SilkS")
		)
		(fp_line
			(start 18.84934 -4.7498)
			(end 19.289014 -5.171694)
			(stroke
				(width 0.1)
				(type default)
			)
			(layer "F.SilkS")
		)
		(fp_line
			(start 18.84934 -4.7498)
			(end 19.289014 -5.171694)
			(stroke
				(width 0.1)
				(type default)
			)
			(layer "F.SilkS")
		)
		(fp_line
			(start 18.861532 -4.819142)
			(end 18.873978 -4.888484)
			(stroke
				(width 0.1)
				(type default)
			)
			(layer "F.SilkS")
		)
		(fp_line
			(start 18.861532 -4.819142)
			(end 18.873978 -4.888484)
			(stroke
				(width 0.1)
				(type default)
			)
			(layer "F.SilkS")
		)
		(fp_line
			(start 18.861532 -4.819142)
			(end 19.22907 -5.171694)
			(stroke
				(width 0.1)
				(type default)
			)
			(layer "F.SilkS")
		)
		(fp_line
			(start 18.861532 -4.819142)
			(end 19.22907 -5.171694)
			(stroke
				(width 0.1)
				(type default)
			)
			(layer "F.SilkS")
		)
		(fp_line
			(start 18.873978 -4.888484)
			(end 19.168872 -5.171694)
			(stroke
				(width 0.1)
				(type default)
			)
			(layer "F.SilkS")
		)
		(fp_line
			(start 18.873978 -4.888484)
			(end 19.168872 -5.171694)
			(stroke
				(width 0.1)
				(type default)
			)
			(layer "F.SilkS")
		)
		(fp_line
			(start 18.885916 -4.95808)
			(end 18.873978 -4.888484)
			(stroke
				(width 0.1)
				(type default)
			)
			(layer "F.SilkS")
		)
		(fp_line
			(start 18.885916 -4.95808)
			(end 18.873978 -4.888484)
			(stroke
				(width 0.1)
				(type default)
			)
			(layer "F.SilkS")
		)
		(fp_line
			(start 18.898108 -5.027422)
			(end 18.885916 -4.95808)
			(stroke
				(width 0.1)
				(type default)
			)
			(layer "F.SilkS")
		)
		(fp_line
			(start 18.898108 -5.027422)
			(end 18.885916 -4.95808)
			(stroke
				(width 0.1)
				(type default)
			)
			(layer "F.SilkS")
		)
		(fp_line
			(start 18.898108 -5.027422)
			(end 18.9103 -5.097018)
			(stroke
				(width 0.1)
				(type default)
			)
			(layer "F.SilkS")
		)
		(fp_line
			(start 18.898108 -5.027422)
			(end 18.9103 -5.097018)
			(stroke
				(width 0.1)
				(type default)
			)
			(layer "F.SilkS")
		)
		(fp_line
			(start 18.898108 -5.027422)
			(end 19.048476 -5.171694)
			(stroke
				(width 0.1)
				(type default)
			)
			(layer "F.SilkS")
		)
		(fp_line
			(start 18.898108 -5.027422)
			(end 19.048476 -5.171694)
			(stroke
				(width 0.1)
				(type default)
			)
			(layer "F.SilkS")
		)
		(fp_line
			(start 18.90395 -4.109466)
			(end 18.964148 -4.109466)
			(stroke
				(width 0.1)
				(type default)
			)
			(layer "F.SilkS")
		)
		(fp_line
			(start 18.90395 -4.109466)
			(end 18.964148 -4.109466)
			(stroke
				(width 0.1)
				(type default)
			)
			(layer "F.SilkS")
		)
		(fp_line
			(start 18.90395 -4.109466)
			(end 20.922742 -6.04647)
			(stroke
				(width 0.1)
				(type default)
			)
			(layer "F.SilkS")
		)
		(fp_line
			(start 18.90395 -4.109466)
			(end 20.922742 -6.04647)
			(stroke
				(width 0.1)
				(type default)
			)
			(layer "F.SilkS")
		)
		(fp_line
			(start 18.9103 -5.097018)
			(end 18.922492 -5.166106)
			(stroke
				(width 0.1)
				(type default)
			)
			(layer "F.SilkS")
		)
		(fp_line
			(start 18.9103 -5.097018)
			(end 18.922492 -5.166106)
			(stroke
				(width 0.1)
				(type default)
			)
			(layer "F.SilkS")
		)
		(fp_line
			(start 18.9103 -5.097018)
			(end 18.988278 -5.171694)
			(stroke
				(width 0.1)
				(type default)
			)
			(layer "F.SilkS")
		)
		(fp_line
			(start 18.9103 -5.097018)
			(end 18.988278 -5.171694)
			(stroke
				(width 0.1)
				(type default)
			)
			(layer "F.SilkS")
		)
		(fp_line
			(start 18.922492 -5.166106)
			(end 18.923508 -5.171694)
			(stroke
				(width 0.1)
				(type default)
			)
			(layer "F.SilkS")
		)
		(fp_line
			(start 18.922492 -5.166106)
			(end 18.923508 -5.171694)
			(stroke
				(width 0.1)
				(type default)
			)
			(layer "F.SilkS")
		)
		(fp_line
			(start 18.922492 -5.166106)
			(end 18.928334 -5.171694)
			(stroke
				(width 0.1)
				(type default)
			)
			(layer "F.SilkS")
		)
		(fp_line
			(start 18.922492 -5.166106)
			(end 18.928334 -5.171694)
			(stroke
				(width 0.1)
				(type default)
			)
			(layer "F.SilkS")
		)
		(fp_line
			(start 18.923508 -5.171694)
			(end 18.928334 -5.171694)
			(stroke
				(width 0.1)
				(type default)
			)
			(layer "F.SilkS")
		)
		(fp_line
			(start 18.923508 -5.171694)
			(end 18.928334 -5.171694)
			(stroke
				(width 0.1)
				(type default)
			)
			(layer "F.SilkS")
		)
		(fp_line
			(start 18.964148 -4.109466)
			(end 19.024092 -4.109466)
			(stroke
				(width 0.1)
				(type default)
			)
			(layer "F.SilkS")
		)
		(fp_line
			(start 18.964148 -4.109466)
			(end 19.024092 -4.109466)
			(stroke
				(width 0.1)
				(type default)
			)
			(layer "F.SilkS")
		)
		(fp_line
			(start 18.964148 -4.109466)
			(end 20.91055 -5.976874)
			(stroke
				(width 0.1)
				(type default)
			)
			(layer "F.SilkS")
		)
		(fp_line
			(start 18.964148 -4.109466)
			(end 20.91055 -5.976874)
			(stroke
				(width 0.1)
				(type default)
			)
			(layer "F.SilkS")
		)
		(fp_line
			(start 18.988278 -5.171694)
			(end 18.928334 -5.171694)
			(stroke
				(width 0.1)
				(type default)
			)
			(layer "F.SilkS")
		)
		(fp_line
			(start 18.988278 -5.171694)
			(end 18.928334 -5.171694)
			(stroke
				(width 0.1)
				(type default)
			)
			(layer "F.SilkS")
		)
		(fp_line
			(start 19.024092 -4.109466)
			(end 19.08429 -4.109466)
			(stroke
				(width 0.1)
				(type default)
			)
			(layer "F.SilkS")
		)
		(fp_line
			(start 19.024092 -4.109466)
			(end 19.08429 -4.109466)
			(stroke
				(width 0.1)
				(type default)
			)
			(layer "F.SilkS")
		)
		(fp_line
			(start 19.024092 -4.109466)
			(end 20.898104 -5.907278)
			(stroke
				(width 0.1)
				(type default)
			)
			(layer "F.SilkS")
		)
		(fp_line
			(start 19.024092 -4.109466)
			(end 20.898104 -5.907278)
			(stroke
				(width 0.1)
				(type default)
			)
			(layer "F.SilkS")
		)
		(fp_line
			(start 19.048476 -5.171694)
			(end 18.988278 -5.171694)
			(stroke
				(width 0.1)
				(type default)
			)
			(layer "F.SilkS")
		)
		(fp_line
			(start 19.048476 -5.171694)
			(end 18.988278 -5.171694)
			(stroke
				(width 0.1)
				(type default)
			)
			(layer "F.SilkS")
		)
		(fp_line
			(start 19.048476 -5.171694)
			(end 19.10842 -5.171694)
			(stroke
				(width 0.1)
				(type default)
			)
			(layer "F.SilkS")
		)
		(fp_line
			(start 19.048476 -5.171694)
			(end 19.10842 -5.171694)
			(stroke
				(width 0.1)
				(type default)
			)
			(layer "F.SilkS")
		)
		(fp_line
			(start 19.074638 -1.79197)
			(end 20.399248 -3.062478)
			(stroke
				(width 0.1)
				(type default)
			)
			(layer "F.SilkS")
		)
		(fp_line
			(start 19.074638 -1.79197)
			(end 20.399248 -3.062478)
			(stroke
				(width 0.1)
				(type default)
			)
			(layer "F.SilkS")
		)
		(fp_line
			(start 19.077178 -1.851914)
			(end 20.41144 -3.13182)
			(stroke
				(width 0.1)
				(type default)
			)
			(layer "F.SilkS")
		)
		(fp_line
			(start 19.077178 -1.851914)
			(end 20.41144 -3.13182)
			(stroke
				(width 0.1)
				(type default)
			)
			(layer "F.SilkS")
		)
		(fp_line
			(start 19.078448 -1.737868)
			(end 20.38731 -2.99339)
			(stroke
				(width 0.1)
				(type default)
			)
			(layer "F.SilkS")
		)
		(fp_line
			(start 19.078448 -1.737868)
			(end 20.38731 -2.99339)
			(stroke
				(width 0.1)
				(type default)
			)
			(layer "F.SilkS")
		)
		(fp_line
			(start 19.082258 -1.683512)
			(end 20.374864 -2.923794)
			(stroke
				(width 0.1)
				(type default)
			)
			(layer "F.SilkS")
		)
		(fp_line
			(start 19.082258 -1.683512)
			(end 20.374864 -2.923794)
			(stroke
				(width 0.1)
				(type default)
			)
			(layer "F.SilkS")
		)
		(fp_line
			(start 19.083274 -1.915668)
			(end 20.423886 -3.201416)
			(stroke
				(width 0.1)
				(type default)
			)
			(layer "F.SilkS")
		)
		(fp_line
			(start 19.083274 -1.915668)
			(end 20.423886 -3.201416)
			(stroke
				(width 0.1)
				(type default)
			)
			(layer "F.SilkS")
		)
		(fp_line
			(start 19.08429 -4.109466)
			(end 19.144234 -4.109466)
			(stroke
				(width 0.1)
				(type default)
			)
			(layer "F.SilkS")
		)
		(fp_line
			(start 19.08429 -4.109466)
			(end 19.144234 -4.109466)
			(stroke
				(width 0.1)
				(type default)
			)
			(layer "F.SilkS")
		)
		(fp_line
			(start 19.08429 -4.109466)
			(end 20.886166 -5.837936)
			(stroke
				(width 0.1)
				(type default)
			)
			(layer "F.SilkS")
		)
		(fp_line
			(start 19.08429 -4.109466)
			(end 20.886166 -5.837936)
			(stroke
				(width 0.1)
				(type default)
			)
			(layer "F.SilkS")
		)
		(fp_line
			(start 19.086068 -1.62941)
			(end 20.362926 -2.854198)
			(stroke
				(width 0.1)
				(type default)
			)
			(layer "F.SilkS")
		)
		(fp_line
			(start 19.086068 -1.62941)
			(end 20.362926 -2.854198)
			(stroke
				(width 0.1)
				(type default)
			)
			(layer "F.SilkS")
		)
		(fp_line
			(start 19.089624 -1.575308)
			(end 20.35048 -2.784856)
			(stroke
				(width 0.1)
				(type default)
			)
			(layer "F.SilkS")
		)
		(fp_line
			(start 19.089624 -1.575308)
			(end 20.35048 -2.784856)
			(stroke
				(width 0.1)
				(type default)
			)
			(layer "F.SilkS")
		)
		(fp_line
			(start 19.089878 -1.979676)
			(end 20.435824 -3.270758)
			(stroke
				(width 0.1)
				(type default)
			)
			(layer "F.SilkS")
		)
		(fp_line
			(start 19.089878 -1.979676)
			(end 20.435824 -3.270758)
			(stroke
				(width 0.1)
				(type default)
			)
			(layer "F.SilkS")
		)
		(fp_line
			(start 19.095974 -2.043176)
			(end 20.44827 -3.340354)
			(stroke
				(width 0.1)
				(type default)
			)
			(layer "F.SilkS")
		)
		(fp_line
			(start 19.095974 -2.043176)
			(end 20.44827 -3.340354)
			(stroke
				(width 0.1)
				(type default)
			)
			(layer "F.SilkS")
		)
		(fp_line
			(start 19.100292 -1.528064)
			(end 20.338288 -2.715768)
			(stroke
				(width 0.1)
				(type default)
			)
			(layer "F.SilkS")
		)
		(fp_line
			(start 19.100292 -1.528064)
			(end 20.338288 -2.715768)
			(stroke
				(width 0.1)
				(type default)
			)
			(layer "F.SilkS")
		)
		(fp_line
			(start 19.10461 -2.108962)
			(end 20.460462 -3.409442)
			(stroke
				(width 0.1)
				(type default)
			)
			(layer "F.SilkS")
		)
		(fp_line
			(start 19.10461 -2.108962)
			(end 20.460462 -3.409442)
			(stroke
				(width 0.1)
				(type default)
			)
			(layer "F.SilkS")
		)
		(fp_line
			(start 19.10842 -5.171694)
			(end 18.885916 -4.95808)
			(stroke
				(width 0.1)
				(type default)
			)
			(layer "F.SilkS")
		)
		(fp_line
			(start 19.10842 -5.171694)
			(end 18.885916 -4.95808)
			(stroke
				(width 0.1)
				(type default)
			)
			(layer "F.SilkS")
		)
		(fp_line
			(start 19.10842 -5.171694)
			(end 19.168872 -5.171694)
			(stroke
				(width 0.1)
				(type default)
			)
			(layer "F.SilkS")
		)
		(fp_line
			(start 19.10842 -5.171694)
			(end 19.168872 -5.171694)
			(stroke
				(width 0.1)
				(type default)
			)
			(layer "F.SilkS")
		)
		(fp_line
			(start 19.112738 -1.48209)
			(end 20.32635 -2.646172)
			(stroke
				(width 0.1)
				(type default)
			)
			(layer "F.SilkS")
		)
		(fp_line
			(start 19.112738 -1.48209)
			(end 20.32635 -2.646172)
			(stroke
				(width 0.1)
				(type default)
			)
			(layer "F.SilkS")
		)
		(fp_line
			(start 19.116802 -2.178304)
			(end 19.10461 -2.108962)
			(stroke
				(width 0.1)
				(type default)
			)
			(layer "F.SilkS")
		)
		(fp_line
			(start 19.116802 -2.178304)
			(end 19.10461 -2.108962)
			(stroke
				(width 0.1)
				(type default)
			)
			(layer "F.SilkS")
		)
		(fp_line
			(start 19.116802 -2.178304)
			(end 20.4724 -3.479038)
			(stroke
				(width 0.1)
				(type default)
			)
			(layer "F.SilkS")
		)
		(fp_line
			(start 19.116802 -2.178304)
			(end 20.4724 -3.479038)
			(stroke
				(width 0.1)
				(type default)
			)
			(layer "F.SilkS")
		)
		(fp_line
			(start 19.12493 -1.436116)
			(end 20.313904 -2.576576)
			(stroke
				(width 0.1)
				(type default)
			)
			(layer "F.SilkS")
		)
		(fp_line
			(start 19.12493 -1.436116)
			(end 20.313904 -2.576576)
			(stroke
				(width 0.1)
				(type default)
			)
			(layer "F.SilkS")
		)
		(fp_line
			(start 19.12874 -2.2479)
			(end 19.116802 -2.178304)
			(stroke
				(width 0.1)
				(type default)
			)
			(layer "F.SilkS")
		)
		(fp_line
			(start 19.12874 -2.2479)
			(end 19.116802 -2.178304)
			(stroke
				(width 0.1)
				(type default)
			)
			(layer "F.SilkS")
		)
		(fp_line
			(start 19.12874 -2.2479)
			(end 19.141186 -2.317242)
			(stroke
				(width 0.1)
				(type default)
			)
			(layer "F.SilkS")
		)
		(fp_line
			(start 19.12874 -2.2479)
			(end 19.141186 -2.317242)
			(stroke
				(width 0.1)
				(type default)
			)
			(layer "F.SilkS")
		)
		(fp_line
			(start 19.12874 -2.2479)
			(end 20.484846 -3.548634)
			(stroke
				(width 0.1)
				(type default)
			)
			(layer "F.SilkS")
		)
		(fp_line
			(start 19.12874 -2.2479)
			(end 20.484846 -3.548634)
			(stroke
				(width 0.1)
				(type default)
			)
			(layer "F.SilkS")
		)
		(fp_line
			(start 19.137376 -1.390396)
			(end 20.301966 -2.507234)
			(stroke
				(width 0.1)
				(type default)
			)
			(layer "F.SilkS")
		)
		(fp_line
			(start 19.137376 -1.390396)
			(end 20.301966 -2.507234)
			(stroke
				(width 0.1)
				(type default)
			)
			(layer "F.SilkS")
		)
		(fp_line
			(start 19.144234 -4.109466)
			(end 19.204686 -4.109466)
			(stroke
				(width 0.1)
				(type default)
			)
			(layer "F.SilkS")
		)
		(fp_line
			(start 19.144234 -4.109466)
			(end 19.204686 -4.109466)
			(stroke
				(width 0.1)
				(type default)
			)
			(layer "F.SilkS")
		)
		(fp_line
			(start 19.144234 -4.109466)
			(end 20.874228 -5.768594)
			(stroke
				(width 0.1)
				(type default)
			)
			(layer "F.SilkS")
		)
		(fp_line
			(start 19.144234 -4.109466)
			(end 20.874228 -5.768594)
			(stroke
				(width 0.1)
				(type default)
			)
			(layer "F.SilkS")
		)
		(fp_line
			(start 19.149822 -1.344676)
			(end 20.28952 -2.437892)
			(stroke
				(width 0.1)
				(type default)
			)
			(layer "F.SilkS")
		)
		(fp_line
			(start 19.149822 -1.344676)
			(end 20.28952 -2.437892)
			(stroke
				(width 0.1)
				(type default)
			)
			(layer "F.SilkS")
		)
		(fp_line
			(start 19.153378 -2.386584)
			(end 19.141186 -2.317242)
			(stroke
				(width 0.1)
				(type default)
			)
			(layer "F.SilkS")
		)
		(fp_line
			(start 19.153378 -2.386584)
			(end 19.141186 -2.317242)
			(stroke
				(width 0.1)
				(type default)
			)
			(layer "F.SilkS")
		)
		(fp_line
			(start 19.153378 -2.386584)
			(end 20.50923 -3.687064)
			(stroke
				(width 0.1)
				(type default)
			)
			(layer "F.SilkS")
		)
		(fp_line
			(start 19.153378 -2.386584)
			(end 20.50923 -3.687064)
			(stroke
				(width 0.1)
				(type default)
			)
			(layer "F.SilkS")
		)
		(fp_line
			(start 19.165316 -2.455926)
			(end 19.153378 -2.386584)
			(stroke
				(width 0.1)
				(type default)
			)
			(layer "F.SilkS")
		)
		(fp_line
			(start 19.165316 -2.455926)
			(end 19.153378 -2.386584)
			(stroke
				(width 0.1)
				(type default)
			)
			(layer "F.SilkS")
		)
		(fp_line
			(start 19.165316 -2.455926)
			(end 20.521422 -3.75666)
			(stroke
				(width 0.1)
				(type default)
			)
			(layer "F.SilkS")
		)
		(fp_line
			(start 19.165316 -2.455926)
			(end 20.521422 -3.75666)
			(stroke
				(width 0.1)
				(type default)
			)
			(layer "F.SilkS")
		)
		(fp_line
			(start 19.170142 -1.306322)
			(end 20.278344 -2.369312)
			(stroke
				(width 0.1)
				(type default)
			)
			(layer "F.SilkS")
		)
		(fp_line
			(start 19.170142 -1.306322)
			(end 20.278344 -2.369312)
			(stroke
				(width 0.1)
				(type default)
			)
			(layer "F.SilkS")
		)
		(fp_line
			(start 19.177762 -2.525522)
			(end 19.165316 -2.455926)
			(stroke
				(width 0.1)
				(type default)
			)
			(layer "F.SilkS")
		)
		(fp_line
			(start 19.177762 -2.525522)
			(end 19.165316 -2.455926)
			(stroke
				(width 0.1)
				(type default)
			)
			(layer "F.SilkS")
		)
		(fp_line
			(start 19.177762 -2.525522)
			(end 20.533614 -3.826256)
			(stroke
				(width 0.1)
				(type default)
			)
			(layer "F.SilkS")
		)
		(fp_line
			(start 19.177762 -2.525522)
			(end 20.533614 -3.826256)
			(stroke
				(width 0.1)
				(type default)
			)
			(layer "F.SilkS")
		)
		(fp_line
			(start 19.1897 -2.594864)
			(end 19.177762 -2.525522)
			(stroke
				(width 0.1)
				(type default)
			)
			(layer "F.SilkS")
		)
		(fp_line
			(start 19.1897 -2.594864)
			(end 19.177762 -2.525522)
			(stroke
				(width 0.1)
				(type default)
			)
			(layer "F.SilkS")
		)
		(fp_line
			(start 19.1897 -2.594864)
			(end 20.545806 -3.895344)
			(stroke
				(width 0.1)
				(type default)
			)
			(layer "F.SilkS")
		)
		(fp_line
			(start 19.1897 -2.594864)
			(end 20.545806 -3.895344)
			(stroke
				(width 0.1)
				(type default)
			)
			(layer "F.SilkS")
		)
		(fp_line
			(start 19.190462 -1.267968)
			(end 20.270216 -2.303526)
			(stroke
				(width 0.1)
				(type default)
			)
			(layer "F.SilkS")
		)
		(fp_line
			(start 19.190462 -1.267968)
			(end 20.270216 -2.303526)
			(stroke
				(width 0.1)
				(type default)
			)
			(layer "F.SilkS")
		)
		(fp_line
			(start 19.201892 -2.663952)
			(end 19.1897 -2.594864)
			(stroke
				(width 0.1)
				(type default)
			)
			(layer "F.SilkS")
		)
		(fp_line
			(start 19.201892 -2.663952)
			(end 19.1897 -2.594864)
			(stroke
				(width 0.1)
				(type default)
			)
			(layer "F.SilkS")
		)
		(fp_line
			(start 19.201892 -2.663952)
			(end 20.557744 -3.96494)
			(stroke
				(width 0.1)
				(type default)
			)
			(layer "F.SilkS")
		)
		(fp_line
			(start 19.201892 -2.663952)
			(end 20.557744 -3.96494)
			(stroke
				(width 0.1)
				(type default)
			)
			(layer "F.SilkS")
		)
		(fp_line
			(start 19.204686 -4.109466)
			(end 19.264884 -4.109466)
			(stroke
				(width 0.1)
				(type default)
			)
			(layer "F.SilkS")
		)
		(fp_line
			(start 19.204686 -4.109466)
			(end 19.264884 -4.109466)
			(stroke
				(width 0.1)
				(type default)
			)
			(layer "F.SilkS")
		)
		(fp_line
			(start 19.204686 -4.109466)
			(end 20.861782 -5.699252)
			(stroke
				(width 0.1)
				(type default)
			)
			(layer "F.SilkS")
		)
		(fp_line
			(start 19.204686 -4.109466)
			(end 20.861782 -5.699252)
			(stroke
				(width 0.1)
				(type default)
			)
			(layer "F.SilkS")
		)
		(fp_line
			(start 19.210782 -1.229868)
			(end 20.26285 -2.239264)
			(stroke
				(width 0.1)
				(type default)
			)
			(layer "F.SilkS")
		)
		(fp_line
			(start 19.210782 -1.229868)
			(end 20.26285 -2.239264)
			(stroke
				(width 0.1)
				(type default)
			)
			(layer "F.SilkS")
		)
		(fp_line
			(start 19.21383 -2.733548)
			(end 19.201892 -2.663952)
			(stroke
				(width 0.1)
				(type default)
			)
			(layer "F.SilkS")
		)
		(fp_line
			(start 19.21383 -2.733548)
			(end 19.201892 -2.663952)
			(stroke
				(width 0.1)
				(type default)
			)
			(layer "F.SilkS")
		)
		(fp_line
			(start 19.21383 -2.733548)
			(end 20.57019 -4.034282)
			(stroke
				(width 0.1)
				(type default)
			)
			(layer "F.SilkS")
		)
		(fp_line
			(start 19.21383 -2.733548)
			(end 20.57019 -4.034282)
			(stroke
				(width 0.1)
				(type default)
			)
			(layer "F.SilkS")
		)
		(fp_line
			(start 19.226276 -2.80289)
			(end 19.21383 -2.733548)
			(stroke
				(width 0.1)
				(type default)
			)
			(layer "F.SilkS")
		)
		(fp_line
			(start 19.226276 -2.80289)
			(end 19.21383 -2.733548)
			(stroke
				(width 0.1)
				(type default)
			)
			(layer "F.SilkS")
		)
		(fp_line
			(start 19.226276 -2.80289)
			(end 20.582382 -4.103878)
			(stroke
				(width 0.1)
				(type default)
			)
			(layer "F.SilkS")
		)
		(fp_line
			(start 19.226276 -2.80289)
			(end 20.582382 -4.103878)
			(stroke
				(width 0.1)
				(type default)
			)
			(layer "F.SilkS")
		)
		(fp_line
			(start 19.22907 -5.171694)
			(end 19.168872 -5.171694)
			(stroke
				(width 0.1)
				(type default)
			)
			(layer "F.SilkS")
		)
		(fp_line
			(start 19.22907 -5.171694)
			(end 19.168872 -5.171694)
			(stroke
				(width 0.1)
				(type default)
			)
			(layer "F.SilkS")
		)
		(fp_line
			(start 19.230848 -1.191514)
			(end 20.263358 -2.181606)
			(stroke
				(width 0.1)
				(type default)
			)
			(layer "F.SilkS")
		)
		(fp_line
			(start 19.230848 -1.191514)
			(end 20.263358 -2.181606)
			(stroke
				(width 0.1)
				(type default)
			)
			(layer "F.SilkS")
		)
		(fp_line
			(start 19.238468 -2.872232)
			(end 19.226276 -2.80289)
			(stroke
				(width 0.1)
				(type default)
			)
			(layer "F.SilkS")
		)
		(fp_line
			(start 19.238468 -2.872232)
			(end 19.226276 -2.80289)
			(stroke
				(width 0.1)
				(type default)
			)
			(layer "F.SilkS")
		)
		(fp_line
			(start 19.238468 -2.872232)
			(end 21.635466 -5.171694)
			(stroke
				(width 0.1)
				(type default)
			)
			(layer "F.SilkS")
		)
		(fp_line
			(start 19.238468 -2.872232)
			(end 21.635466 -5.171694)
			(stroke
				(width 0.1)
				(type default)
			)
			(layer "F.SilkS")
		)
		(fp_line
			(start 19.250406 -2.941574)
			(end 19.238468 -2.872232)
			(stroke
				(width 0.1)
				(type default)
			)
			(layer "F.SilkS")
		)
		(fp_line
			(start 19.250406 -2.941574)
			(end 19.238468 -2.872232)
			(stroke
				(width 0.1)
				(type default)
			)
			(layer "F.SilkS")
		)
		(fp_line
			(start 19.25193 -1.153922)
			(end 20.265136 -2.125726)
			(stroke
				(width 0.1)
				(type default)
			)
			(layer "F.SilkS")
		)
		(fp_line
			(start 19.25193 -1.153922)
			(end 20.265136 -2.125726)
			(stroke
				(width 0.1)
				(type default)
			)
			(layer "F.SilkS")
		)
		(fp_line
			(start 19.262852 -3.01117)
			(end 19.250406 -2.941574)
			(stroke
				(width 0.1)
				(type default)
			)
			(layer "F.SilkS")
		)
		(fp_line
			(start 19.262852 -3.01117)
			(end 19.250406 -2.941574)
			(stroke
				(width 0.1)
				(type default)
			)
			(layer "F.SilkS")
		)
		(fp_line
			(start 19.264884 -4.109466)
			(end 19.324828 -4.109466)
			(stroke
				(width 0.1)
				(type default)
			)
			(layer "F.SilkS")
		)
		(fp_line
			(start 19.264884 -4.109466)
			(end 19.324828 -4.109466)
			(stroke
				(width 0.1)
				(type default)
			)
			(layer "F.SilkS")
		)
		(fp_line
			(start 19.264884 -4.109466)
			(end 20.84959 -5.629656)
			(stroke
				(width 0.1)
				(type default)
			)
			(layer "F.SilkS")
		)
		(fp_line
			(start 19.264884 -4.109466)
			(end 20.84959 -5.629656)
			(stroke
				(width 0.1)
				(type default)
			)
			(layer "F.SilkS")
		)
		(fp_line
			(start 19.27479 -3.080512)
			(end 19.262852 -3.01117)
			(stroke
				(width 0.1)
				(type default)
			)
			(layer "F.SilkS")
		)
		(fp_line
			(start 19.27479 -3.080512)
			(end 19.262852 -3.01117)
			(stroke
				(width 0.1)
				(type default)
			)
			(layer "F.SilkS")
		)
		(fp_line
			(start 19.279616 -1.122934)
			(end 20.274534 -2.077212)
			(stroke
				(width 0.1)
				(type default)
			)
			(layer "F.SilkS")
		)
		(fp_line
			(start 19.279616 -1.122934)
			(end 20.274534 -2.077212)
			(stroke
				(width 0.1)
				(type default)
			)
			(layer "F.SilkS")
		)
		(fp_line
			(start 19.286982 -3.149854)
			(end 19.27479 -3.080512)
			(stroke
				(width 0.1)
				(type default)
			)
			(layer "F.SilkS")
		)
		(fp_line
			(start 19.286982 -3.149854)
			(end 19.27479 -3.080512)
			(stroke
				(width 0.1)
				(type default)
			)
			(layer "F.SilkS")
		)
		(fp_line
			(start 19.289014 -5.171694)
			(end 19.22907 -5.171694)
			(stroke
				(width 0.1)
				(type default)
			)
			(layer "F.SilkS")
		)
		(fp_line
			(start 19.289014 -5.171694)
			(end 19.22907 -5.171694)
			(stroke
				(width 0.1)
				(type default)
			)
			(layer "F.SilkS")
		)
		(fp_line
			(start 19.299428 -3.218942)
			(end 19.286982 -3.149854)
			(stroke
				(width 0.1)
				(type default)
			)
			(layer "F.SilkS")
		)
		(fp_line
			(start 19.299428 -3.218942)
			(end 19.286982 -3.149854)
			(stroke
				(width 0.1)
				(type default)
			)
			(layer "F.SilkS")
		)
		(fp_line
			(start 19.307556 -1.091946)
			(end 20.287488 -2.031746)
			(stroke
				(width 0.1)
				(type default)
			)
			(layer "F.SilkS")
		)
		(fp_line
			(start 19.307556 -1.091946)
			(end 20.287488 -2.031746)
			(stroke
				(width 0.1)
				(type default)
			)
			(layer "F.SilkS")
		)
		(fp_line
			(start 19.311366 -3.288538)
			(end 19.299428 -3.218942)
			(stroke
				(width 0.1)
				(type default)
			)
			(layer "F.SilkS")
		)
		(fp_line
			(start 19.311366 -3.288538)
			(end 19.299428 -3.218942)
			(stroke
				(width 0.1)
				(type default)
			)
			(layer "F.SilkS")
		)
		(fp_line
			(start 19.323558 -3.358134)
			(end 19.311366 -3.288538)
			(stroke
				(width 0.1)
				(type default)
			)
			(layer "F.SilkS")
		)
		(fp_line
			(start 19.323558 -3.358134)
			(end 19.311366 -3.288538)
			(stroke
				(width 0.1)
				(type default)
			)
			(layer "F.SilkS")
		)
		(fp_line
			(start 19.324828 -4.109466)
			(end 19.385026 -4.109466)
			(stroke
				(width 0.1)
				(type default)
			)
			(layer "F.SilkS")
		)
		(fp_line
			(start 19.324828 -4.109466)
			(end 19.385026 -4.109466)
			(stroke
				(width 0.1)
				(type default)
			)
			(layer "F.SilkS")
		)
		(fp_line
			(start 19.324828 -4.109466)
			(end 20.837144 -5.560314)
			(stroke
				(width 0.1)
				(type default)
			)
			(layer "F.SilkS")
		)
		(fp_line
			(start 19.324828 -4.109466)
			(end 20.837144 -5.560314)
			(stroke
				(width 0.1)
				(type default)
			)
			(layer "F.SilkS")
		)
		(fp_line
			(start 19.335496 -1.061212)
			(end 20.307046 -1.992884)
			(stroke
				(width 0.1)
				(type default)
			)
			(layer "F.SilkS")
		)
		(fp_line
			(start 19.335496 -1.061212)
			(end 20.307046 -1.992884)
			(stroke
				(width 0.1)
				(type default)
			)
			(layer "F.SilkS")
		)
		(fp_line
			(start 19.33575 -3.427476)
			(end 19.323558 -3.358134)
			(stroke
				(width 0.1)
				(type default)
			)
			(layer "F.SilkS")
		)
		(fp_line
			(start 19.33575 -3.427476)
			(end 19.323558 -3.358134)
			(stroke
				(width 0.1)
				(type default)
			)
			(layer "F.SilkS")
		)
		(fp_line
			(start 19.347942 -3.496564)
			(end 19.33575 -3.427476)
			(stroke
				(width 0.1)
				(type default)
			)
			(layer "F.SilkS")
		)
		(fp_line
			(start 19.347942 -3.496564)
			(end 19.33575 -3.427476)
			(stroke
				(width 0.1)
				(type default)
			)
			(layer "F.SilkS")
		)
		(fp_line
			(start 19.349212 -5.171694)
			(end 19.289014 -5.171694)
			(stroke
				(width 0.1)
				(type default)
			)
			(layer "F.SilkS")
		)
		(fp_line
			(start 19.349212 -5.171694)
			(end 19.289014 -5.171694)
			(stroke
				(width 0.1)
				(type default)
			)
			(layer "F.SilkS")
		)
		(fp_line
			(start 19.35988 -3.56616)
			(end 19.347942 -3.496564)
			(stroke
				(width 0.1)
				(type default)
			)
			(layer "F.SilkS")
		)
		(fp_line
			(start 19.35988 -3.56616)
			(end 19.347942 -3.496564)
			(stroke
				(width 0.1)
				(type default)
			)
			(layer "F.SilkS")
		)
		(fp_line
			(start 19.363436 -1.030224)
			(end 20.332446 -1.959356)
			(stroke
				(width 0.1)
				(type default)
			)
			(layer "F.SilkS")
		)
		(fp_line
			(start 19.363436 -1.030224)
			(end 20.332446 -1.959356)
			(stroke
				(width 0.1)
				(type default)
			)
			(layer "F.SilkS")
		)
		(fp_line
			(start 19.372326 -3.635502)
			(end 19.35988 -3.56616)
			(stroke
				(width 0.1)
				(type default)
			)
			(layer "F.SilkS")
		)
		(fp_line
			(start 19.372326 -3.635502)
			(end 19.35988 -3.56616)
			(stroke
				(width 0.1)
				(type default)
			)
			(layer "F.SilkS")
		)
		(fp_line
			(start 19.384518 -3.704844)
			(end 19.372326 -3.635502)
			(stroke
				(width 0.1)
				(type default)
			)
			(layer "F.SilkS")
		)
		(fp_line
			(start 19.384518 -3.704844)
			(end 19.372326 -3.635502)
			(stroke
				(width 0.1)
				(type default)
			)
			(layer "F.SilkS")
		)
		(fp_line
			(start 19.385026 -4.109466)
			(end 19.445478 -4.109466)
			(stroke
				(width 0.1)
				(type default)
			)
			(layer "F.SilkS")
		)
		(fp_line
			(start 19.385026 -4.109466)
			(end 19.445478 -4.109466)
			(stroke
				(width 0.1)
				(type default)
			)
			(layer "F.SilkS")
		)
		(fp_line
			(start 19.385026 -4.109466)
			(end 20.825206 -5.490972)
			(stroke
				(width 0.1)
				(type default)
			)
			(layer "F.SilkS")
		)
		(fp_line
			(start 19.385026 -4.109466)
			(end 20.825206 -5.490972)
			(stroke
				(width 0.1)
				(type default)
			)
			(layer "F.SilkS")
		)
		(fp_line
			(start 19.392646 -1.000252)
			(end 20.362164 -1.9304)
			(stroke
				(width 0.1)
				(type default)
			)
			(layer "F.SilkS")
		)
		(fp_line
			(start 19.392646 -1.000252)
			(end 20.362164 -1.9304)
			(stroke
				(width 0.1)
				(type default)
			)
			(layer "F.SilkS")
		)
		(fp_line
			(start 19.396456 -3.774186)
			(end 19.384518 -3.704844)
			(stroke
				(width 0.1)
				(type default)
			)
			(layer "F.SilkS")
		)
		(fp_line
			(start 19.396456 -3.774186)
			(end 19.384518 -3.704844)
			(stroke
				(width 0.1)
				(type default)
			)
			(layer "F.SilkS")
		)
		(fp_line
			(start 19.408902 -3.843528)
			(end 19.396456 -3.774186)
			(stroke
				(width 0.1)
				(type default)
			)
			(layer "F.SilkS")
		)
		(fp_line
			(start 19.408902 -3.843528)
			(end 19.396456 -3.774186)
			(stroke
				(width 0.1)
				(type default)
			)
			(layer "F.SilkS")
		)
		(fp_line
			(start 19.409664 -5.171694)
			(end 19.349212 -5.171694)
			(stroke
				(width 0.1)
				(type default)
			)
			(layer "F.SilkS")
		)
		(fp_line
			(start 19.409664 -5.171694)
			(end 19.349212 -5.171694)
			(stroke
				(width 0.1)
				(type default)
			)
			(layer "F.SilkS")
		)
		(fp_line
			(start 19.42084 -3.913124)
			(end 19.408902 -3.843528)
			(stroke
				(width 0.1)
				(type default)
			)
			(layer "F.SilkS")
		)
		(fp_line
			(start 19.42084 -3.913124)
			(end 19.408902 -3.843528)
			(stroke
				(width 0.1)
				(type default)
			)
			(layer "F.SilkS")
		)
		(fp_line
			(start 19.42084 -3.913124)
			(end 20.776184 -5.21335)
			(stroke
				(width 0.1)
				(type default)
			)
			(layer "F.SilkS")
		)
		(fp_line
			(start 19.42084 -3.913124)
			(end 20.776184 -5.21335)
			(stroke
				(width 0.1)
				(type default)
			)
			(layer "F.SilkS")
		)
		(fp_line
			(start 19.42846 -0.976884)
			(end 20.400772 -1.909572)
			(stroke
				(width 0.1)
				(type default)
			)
			(layer "F.SilkS")
		)
		(fp_line
			(start 19.42846 -0.976884)
			(end 20.400772 -1.909572)
			(stroke
				(width 0.1)
				(type default)
			)
			(layer "F.SilkS")
		)
		(fp_line
			(start 19.433032 -3.982466)
			(end 19.42084 -3.913124)
			(stroke
				(width 0.1)
				(type default)
			)
			(layer "F.SilkS")
		)
		(fp_line
			(start 19.433032 -3.982466)
			(end 19.42084 -3.913124)
			(stroke
				(width 0.1)
				(type default)
			)
			(layer "F.SilkS")
		)
		(fp_line
			(start 19.445478 -4.109466)
			(end 19.455384 -4.109466)
			(stroke
				(width 0.1)
				(type default)
			)
			(layer "F.SilkS")
		)
		(fp_line
			(start 19.445478 -4.109466)
			(end 19.455384 -4.109466)
			(stroke
				(width 0.1)
				(type default)
			)
			(layer "F.SilkS")
		)
		(fp_line
			(start 19.445478 -4.109466)
			(end 20.81276 -5.421376)
			(stroke
				(width 0.1)
				(type default)
			)
			(layer "F.SilkS")
		)
		(fp_line
			(start 19.445478 -4.109466)
			(end 20.81276 -5.421376)
			(stroke
				(width 0.1)
				(type default)
			)
			(layer "F.SilkS")
		)
		(fp_line
			(start 19.445478 -4.051554)
			(end 19.433032 -3.982466)
			(stroke
				(width 0.1)
				(type default)
			)
			(layer "F.SilkS")
		)
		(fp_line
			(start 19.445478 -4.051554)
			(end 19.433032 -3.982466)
			(stroke
				(width 0.1)
				(type default)
			)
			(layer "F.SilkS")
		)
		(fp_line
			(start 19.455384 -4.109466)
			(end 19.445478 -4.051554)
			(stroke
				(width 0.1)
				(type default)
			)
			(layer "F.SilkS")
		)
		(fp_line
			(start 19.455384 -4.109466)
			(end 19.445478 -4.051554)
			(stroke
				(width 0.1)
				(type default)
			)
			(layer "F.SilkS")
		)
		(fp_line
			(start 19.46402 -0.953516)
			(end 20.442428 -1.892046)
			(stroke
				(width 0.1)
				(type default)
			)
			(layer "F.SilkS")
		)
		(fp_line
			(start 19.46402 -0.953516)
			(end 20.442428 -1.892046)
			(stroke
				(width 0.1)
				(type default)
			)
			(layer "F.SilkS")
		)
		(fp_line
			(start 19.469608 -5.171694)
			(end 19.409664 -5.171694)
			(stroke
				(width 0.1)
				(type default)
			)
			(layer "F.SilkS")
		)
		(fp_line
			(start 19.469608 -5.171694)
			(end 19.409664 -5.171694)
			(stroke
				(width 0.1)
				(type default)
			)
			(layer "F.SilkS")
		)
		(fp_line
			(start 19.500088 -0.930148)
			(end 20.491704 -1.881378)
			(stroke
				(width 0.1)
				(type default)
			)
			(layer "F.SilkS")
		)
		(fp_line
			(start 19.500088 -0.930148)
			(end 20.491704 -1.881378)
			(stroke
				(width 0.1)
				(type default)
			)
			(layer "F.SilkS")
		)
		(fp_line
			(start 19.529806 -5.171694)
			(end 19.469608 -5.171694)
			(stroke
				(width 0.1)
				(type default)
			)
			(layer "F.SilkS")
		)
		(fp_line
			(start 19.529806 -5.171694)
			(end 19.469608 -5.171694)
			(stroke
				(width 0.1)
				(type default)
			)
			(layer "F.SilkS")
		)
		(fp_line
			(start 19.536156 -0.906526)
			(end 20.545044 -1.874774)
			(stroke
				(width 0.1)
				(type default)
			)
			(layer "F.SilkS")
		)
		(fp_line
			(start 19.536156 -0.906526)
			(end 20.545044 -1.874774)
			(stroke
				(width 0.1)
				(type default)
			)
			(layer "F.SilkS")
		)
		(fp_line
			(start 19.574002 -0.88519)
			(end 20.60194 -1.871726)
			(stroke
				(width 0.1)
				(type default)
			)
			(layer "F.SilkS")
		)
		(fp_line
			(start 19.574002 -0.88519)
			(end 20.60194 -1.871726)
			(stroke
				(width 0.1)
				(type default)
			)
			(layer "F.SilkS")
		)
		(fp_line
			(start 19.58975 -5.171694)
			(end 19.529806 -5.171694)
			(stroke
				(width 0.1)
				(type default)
			)
			(layer "F.SilkS")
		)
		(fp_line
			(start 19.58975 -5.171694)
			(end 19.529806 -5.171694)
			(stroke
				(width 0.1)
				(type default)
			)
			(layer "F.SilkS")
		)
		(fp_line
			(start 19.58975 -5.171694)
			(end 19.641566 -5.171694)
			(stroke
				(width 0.1)
				(type default)
			)
			(layer "F.SilkS")
		)
		(fp_line
			(start 19.58975 -5.171694)
			(end 19.641566 -5.171694)
			(stroke
				(width 0.1)
				(type default)
			)
			(layer "F.SilkS")
		)
		(fp_line
			(start 19.617944 -0.870458)
			(end 20.669504 -1.878838)
			(stroke
				(width 0.1)
				(type default)
			)
			(layer "F.SilkS")
		)
		(fp_line
			(start 19.617944 -0.870458)
			(end 20.669504 -1.878838)
			(stroke
				(width 0.1)
				(type default)
			)
			(layer "F.SilkS")
		)
		(fp_line
			(start 19.641566 -5.171694)
			(end 19.651726 -5.23113)
			(stroke
				(width 0.1)
				(type default)
			)
			(layer "F.SilkS")
		)
		(fp_line
			(start 19.641566 -5.171694)
			(end 19.651726 -5.23113)
			(stroke
				(width 0.1)
				(type default)
			)
			(layer "F.SilkS")
		)
		(fp_line
			(start 19.662902 -0.855218)
			(end 20.738084 -1.886966)
			(stroke
				(width 0.1)
				(type default)
			)
			(layer "F.SilkS")
		)
		(fp_line
			(start 19.662902 -0.855218)
			(end 20.738084 -1.886966)
			(stroke
				(width 0.1)
				(type default)
			)
			(layer "F.SilkS")
		)
		(fp_line
			(start 19.664172 -5.300472)
			(end 19.651726 -5.23113)
			(stroke
				(width 0.1)
				(type default)
			)
			(layer "F.SilkS")
		)
		(fp_line
			(start 19.664172 -5.300472)
			(end 19.651726 -5.23113)
			(stroke
				(width 0.1)
				(type default)
			)
			(layer "F.SilkS")
		)
		(fp_line
			(start 19.676364 -5.370068)
			(end 19.664172 -5.300472)
			(stroke
				(width 0.1)
				(type default)
			)
			(layer "F.SilkS")
		)
		(fp_line
			(start 19.676364 -5.370068)
			(end 19.664172 -5.300472)
			(stroke
				(width 0.1)
				(type default)
			)
			(layer "F.SilkS")
		)
		(fp_line
			(start 19.688302 -5.439156)
			(end 19.676364 -5.370068)
			(stroke
				(width 0.1)
				(type default)
			)
			(layer "F.SilkS")
		)
		(fp_line
			(start 19.688302 -5.439156)
			(end 19.676364 -5.370068)
			(stroke
				(width 0.1)
				(type default)
			)
			(layer "F.SilkS")
		)
		(fp_line
			(start 19.700748 -5.508752)
			(end 19.688302 -5.439156)
			(stroke
				(width 0.1)
				(type default)
			)
			(layer "F.SilkS")
		)
		(fp_line
			(start 19.700748 -5.508752)
			(end 19.688302 -5.439156)
			(stroke
				(width 0.1)
				(type default)
			)
			(layer "F.SilkS")
		)
		(fp_line
			(start 19.707352 -0.840486)
			(end 20.828 -1.915414)
			(stroke
				(width 0.1)
				(type default)
			)
			(layer "F.SilkS")
		)
		(fp_line
			(start 19.707352 -0.840486)
			(end 20.828 -1.915414)
			(stroke
				(width 0.1)
				(type default)
			)
			(layer "F.SilkS")
		)
		(fp_line
			(start 19.712686 -5.578094)
			(end 19.700748 -5.508752)
			(stroke
				(width 0.1)
				(type default)
			)
			(layer "F.SilkS")
		)
		(fp_line
			(start 19.712686 -5.578094)
			(end 19.700748 -5.508752)
			(stroke
				(width 0.1)
				(type default)
			)
			(layer "F.SilkS")
		)
		(fp_line
			(start 19.725132 -5.647436)
			(end 19.712686 -5.578094)
			(stroke
				(width 0.1)
				(type default)
			)
			(layer "F.SilkS")
		)
		(fp_line
			(start 19.725132 -5.647436)
			(end 19.712686 -5.578094)
			(stroke
				(width 0.1)
				(type default)
			)
			(layer "F.SilkS")
		)
		(fp_line
			(start 19.737324 -5.716778)
			(end 19.725132 -5.647436)
			(stroke
				(width 0.1)
				(type default)
			)
			(layer "F.SilkS")
		)
		(fp_line
			(start 19.737324 -5.716778)
			(end 19.725132 -5.647436)
			(stroke
				(width 0.1)
				(type default)
			)
			(layer "F.SilkS")
		)
		(fp_line
			(start 19.749262 -5.786374)
			(end 19.737324 -5.716778)
			(stroke
				(width 0.1)
				(type default)
			)
			(layer "F.SilkS")
		)
		(fp_line
			(start 19.749262 -5.786374)
			(end 19.737324 -5.716778)
			(stroke
				(width 0.1)
				(type default)
			)
			(layer "F.SilkS")
		)
		(fp_line
			(start 19.751802 -0.825246)
			(end 20.932902 -1.95834)
			(stroke
				(width 0.1)
				(type default)
			)
			(layer "F.SilkS")
		)
		(fp_line
			(start 19.751802 -0.825246)
			(end 20.932902 -1.95834)
			(stroke
				(width 0.1)
				(type default)
			)
			(layer "F.SilkS")
		)
		(fp_line
			(start 19.761708 -5.85597)
			(end 19.749262 -5.786374)
			(stroke
				(width 0.1)
				(type default)
			)
			(layer "F.SilkS")
		)
		(fp_line
			(start 19.761708 -5.85597)
			(end 19.749262 -5.786374)
			(stroke
				(width 0.1)
				(type default)
			)
			(layer "F.SilkS")
		)
		(fp_line
			(start 19.773646 -5.925058)
			(end 19.761708 -5.85597)
			(stroke
				(width 0.1)
				(type default)
			)
			(layer "F.SilkS")
		)
		(fp_line
			(start 19.773646 -5.925058)
			(end 19.761708 -5.85597)
			(stroke
				(width 0.1)
				(type default)
			)
			(layer "F.SilkS")
		)
		(fp_line
			(start 19.785838 -5.9944)
			(end 19.773646 -5.925058)
			(stroke
				(width 0.1)
				(type default)
			)
			(layer "F.SilkS")
		)
		(fp_line
			(start 19.785838 -5.9944)
			(end 19.773646 -5.925058)
			(stroke
				(width 0.1)
				(type default)
			)
			(layer "F.SilkS")
		)
		(fp_line
			(start 19.798284 -6.063996)
			(end 19.785838 -5.9944)
			(stroke
				(width 0.1)
				(type default)
			)
			(layer "F.SilkS")
		)
		(fp_line
			(start 19.798284 -6.063996)
			(end 19.785838 -5.9944)
			(stroke
				(width 0.1)
				(type default)
			)
			(layer "F.SilkS")
		)
		(fp_line
			(start 19.798284 -6.063996)
			(end 19.810222 -6.133338)
			(stroke
				(width 0.1)
				(type default)
			)
			(layer "F.SilkS")
		)
		(fp_line
			(start 19.798284 -6.063996)
			(end 19.810222 -6.133338)
			(stroke
				(width 0.1)
				(type default)
			)
			(layer "F.SilkS")
		)
		(fp_line
			(start 19.801078 -0.815086)
			(end 21.08327 -2.044954)
			(stroke
				(width 0.1)
				(type default)
			)
			(layer "F.SilkS")
		)
		(fp_line
			(start 19.801078 -0.815086)
			(end 21.08327 -2.044954)
			(stroke
				(width 0.1)
				(type default)
			)
			(layer "F.SilkS")
		)
		(fp_line
			(start 19.810222 -6.133338)
			(end 19.822668 -6.20268)
			(stroke
				(width 0.1)
				(type default)
			)
			(layer "F.SilkS")
		)
		(fp_line
			(start 19.810222 -6.133338)
			(end 19.822668 -6.20268)
			(stroke
				(width 0.1)
				(type default)
			)
			(layer "F.SilkS")
		)
		(fp_line
			(start 19.822668 -6.20268)
			(end 19.834606 -6.272022)
			(stroke
				(width 0.1)
				(type default)
			)
			(layer "F.SilkS")
		)
		(fp_line
			(start 19.822668 -6.20268)
			(end 19.834606 -6.272022)
			(stroke
				(width 0.1)
				(type default)
			)
			(layer "F.SilkS")
		)
		(fp_line
			(start 19.835114 -6.274308)
			(end 19.834606 -6.272022)
			(stroke
				(width 0.1)
				(type default)
			)
			(layer "F.SilkS")
		)
		(fp_line
			(start 19.835114 -6.274308)
			(end 19.834606 -6.272022)
			(stroke
				(width 0.1)
				(type default)
			)
			(layer "F.SilkS")
		)
		(fp_line
			(start 19.838924 -6.276086)
			(end 19.834606 -6.272022)
			(stroke
				(width 0.1)
				(type default)
			)
			(layer "F.SilkS")
		)
		(fp_line
			(start 19.838924 -6.276086)
			(end 19.834606 -6.272022)
			(stroke
				(width 0.1)
				(type default)
			)
			(layer "F.SilkS")
		)
		(fp_line
			(start 19.838924 -6.276086)
			(end 19.835114 -6.274308)
			(stroke
				(width 0.1)
				(type default)
			)
			(layer "F.SilkS")
		)
		(fp_line
			(start 19.838924 -6.276086)
			(end 19.835114 -6.274308)
			(stroke
				(width 0.1)
				(type default)
			)
			(layer "F.SilkS")
		)
		(fp_line
			(start 19.855434 -0.809498)
			(end 21.299932 -2.195068)
			(stroke
				(width 0.1)
				(type default)
			)
			(layer "F.SilkS")
		)
		(fp_line
			(start 19.855434 -0.809498)
			(end 21.299932 -2.195068)
			(stroke
				(width 0.1)
				(type default)
			)
			(layer "F.SilkS")
		)
		(fp_line
			(start 19.910044 -0.80391)
			(end 21.273516 -2.11201)
			(stroke
				(width 0.1)
				(type default)
			)
			(layer "F.SilkS")
		)
		(fp_line
			(start 19.910044 -0.80391)
			(end 21.273516 -2.11201)
			(stroke
				(width 0.1)
				(type default)
			)
			(layer "F.SilkS")
		)
		(fp_line
			(start 19.95424 -6.329172)
			(end 19.822668 -6.20268)
			(stroke
				(width 0.1)
				(type default)
			)
			(layer "F.SilkS")
		)
		(fp_line
			(start 19.95424 -6.329172)
			(end 19.822668 -6.20268)
			(stroke
				(width 0.1)
				(type default)
			)
			(layer "F.SilkS")
		)
		(fp_line
			(start 19.95424 -6.329172)
			(end 19.838924 -6.276086)
			(stroke
				(width 0.1)
				(type default)
			)
			(layer "F.SilkS")
		)
		(fp_line
			(start 19.95424 -6.329172)
			(end 19.838924 -6.276086)
			(stroke
				(width 0.1)
				(type default)
			)
			(layer "F.SilkS")
		)
		(fp_line
			(start 19.964654 -0.798576)
			(end 21.2471 -2.028952)
			(stroke
				(width 0.1)
				(type default)
			)
			(layer "F.SilkS")
		)
		(fp_line
			(start 19.964654 -0.798576)
			(end 21.2471 -2.028952)
			(stroke
				(width 0.1)
				(type default)
			)
			(layer "F.SilkS")
		)
		(fp_line
			(start 20.01901 -0.792988)
			(end 21.220684 -1.946148)
			(stroke
				(width 0.1)
				(type default)
			)
			(layer "F.SilkS")
		)
		(fp_line
			(start 20.01901 -0.792988)
			(end 21.220684 -1.946148)
			(stroke
				(width 0.1)
				(type default)
			)
			(layer "F.SilkS")
		)
		(fp_line
			(start 20.069302 -6.382004)
			(end 19.810222 -6.133338)
			(stroke
				(width 0.1)
				(type default)
			)
			(layer "F.SilkS")
		)
		(fp_line
			(start 20.069302 -6.382004)
			(end 19.810222 -6.133338)
			(stroke
				(width 0.1)
				(type default)
			)
			(layer "F.SilkS")
		)
		(fp_line
			(start 20.069302 -6.382004)
			(end 19.95424 -6.329172)
			(stroke
				(width 0.1)
				(type default)
			)
			(layer "F.SilkS")
		)
		(fp_line
			(start 20.069302 -6.382004)
			(end 19.95424 -6.329172)
			(stroke
				(width 0.1)
				(type default)
			)
			(layer "F.SilkS")
		)
		(fp_line
			(start 20.084542 -0.798576)
			(end 21.194268 -1.862836)
			(stroke
				(width 0.1)
				(type default)
			)
			(layer "F.SilkS")
		)
		(fp_line
			(start 20.084542 -0.798576)
			(end 21.194268 -1.862836)
			(stroke
				(width 0.1)
				(type default)
			)
			(layer "F.SilkS")
		)
		(fp_line
			(start 20.14982 -0.803402)
			(end 21.167852 -1.779778)
			(stroke
				(width 0.1)
				(type default)
			)
			(layer "F.SilkS")
		)
		(fp_line
			(start 20.14982 -0.803402)
			(end 21.167852 -1.779778)
			(stroke
				(width 0.1)
				(type default)
			)
			(layer "F.SilkS")
		)
		(fp_line
			(start 20.185126 -6.43509)
			(end 19.798284 -6.063996)
			(stroke
				(width 0.1)
				(type default)
			)
			(layer "F.SilkS")
		)
		(fp_line
			(start 20.185126 -6.43509)
			(end 19.798284 -6.063996)
			(stroke
				(width 0.1)
				(type default)
			)
			(layer "F.SilkS")
		)
		(fp_line
			(start 20.185126 -6.43509)
			(end 20.069302 -6.382004)
			(stroke
				(width 0.1)
				(type default)
			)
			(layer "F.SilkS")
		)
		(fp_line
			(start 20.185126 -6.43509)
			(end 20.069302 -6.382004)
			(stroke
				(width 0.1)
				(type default)
			)
			(layer "F.SilkS")
		)
		(fp_line
			(start 20.215352 -0.808228)
			(end 21.141436 -1.69672)
			(stroke
				(width 0.1)
				(type default)
			)
			(layer "F.SilkS")
		)
		(fp_line
			(start 20.215352 -0.808228)
			(end 21.141436 -1.69672)
			(stroke
				(width 0.1)
				(type default)
			)
			(layer "F.SilkS")
		)
		(fp_line
			(start 20.280884 -0.813562)
			(end 21.115274 -1.613916)
			(stroke
				(width 0.1)
				(type default)
			)
			(layer "F.SilkS")
		)
		(fp_line
			(start 20.280884 -0.813562)
			(end 21.115274 -1.613916)
			(stroke
				(width 0.1)
				(type default)
			)
			(layer "F.SilkS")
		)
		(fp_line
			(start 20.30095 -6.488176)
			(end 19.785838 -5.9944)
			(stroke
				(width 0.1)
				(type default)
			)
			(layer "F.SilkS")
		)
		(fp_line
			(start 20.30095 -6.488176)
			(end 19.785838 -5.9944)
			(stroke
				(width 0.1)
				(type default)
			)
			(layer "F.SilkS")
		)
		(fp_line
			(start 20.30095 -6.488176)
			(end 20.185126 -6.43509)
			(stroke
				(width 0.1)
				(type default)
			)
			(layer "F.SilkS")
		)
		(fp_line
			(start 20.30095 -6.488176)
			(end 20.185126 -6.43509)
			(stroke
				(width 0.1)
				(type default)
			)
			(layer "F.SilkS")
		)
		(fp_line
			(start 20.301966 -2.507234)
			(end 20.28952 -2.437892)
			(stroke
				(width 0.1)
				(type default)
			)
			(layer "F.SilkS")
		)
		(fp_line
			(start 20.301966 -2.507234)
			(end 20.28952 -2.437892)
			(stroke
				(width 0.1)
				(type default)
			)
			(layer "F.SilkS")
		)
		(fp_line
			(start 20.313904 -2.576576)
			(end 20.301966 -2.507234)
			(stroke
				(width 0.1)
				(type default)
			)
			(layer "F.SilkS")
		)
		(fp_line
			(start 20.313904 -2.576576)
			(end 20.301966 -2.507234)
			(stroke
				(width 0.1)
				(type default)
			)
			(layer "F.SilkS")
		)
		(fp_line
			(start 20.32635 -2.646172)
			(end 20.313904 -2.576576)
			(stroke
				(width 0.1)
				(type default)
			)
			(layer "F.SilkS")
		)
		(fp_line
			(start 20.32635 -2.646172)
			(end 20.313904 -2.576576)
			(stroke
				(width 0.1)
				(type default)
			)
			(layer "F.SilkS")
		)
		(fp_line
			(start 20.32635 -2.646172)
			(end 20.338288 -2.715768)
			(stroke
				(width 0.1)
				(type default)
			)
			(layer "F.SilkS")
		)
		(fp_line
			(start 20.32635 -2.646172)
			(end 20.338288 -2.715768)
			(stroke
				(width 0.1)
				(type default)
			)
			(layer "F.SilkS")
		)
		(fp_line
			(start 20.338288 -2.715768)
			(end 20.35048 -2.784856)
			(stroke
				(width 0.1)
				(type default)
			)
			(layer "F.SilkS")
		)
		(fp_line
			(start 20.338288 -2.715768)
			(end 20.35048 -2.784856)
			(stroke
				(width 0.1)
				(type default)
			)
			(layer "F.SilkS")
		)
		(fp_line
			(start 20.35048 -2.784856)
			(end 20.362926 -2.854198)
			(stroke
				(width 0.1)
				(type default)
			)
			(layer "F.SilkS")
		)
		(fp_line
			(start 20.35048 -2.784856)
			(end 20.362926 -2.854198)
			(stroke
				(width 0.1)
				(type default)
			)
			(layer "F.SilkS")
		)
		(fp_line
			(start 20.359116 -0.830834)
			(end 21.088858 -1.530604)
			(stroke
				(width 0.1)
				(type default)
			)
			(layer "F.SilkS")
		)
		(fp_line
			(start 20.359116 -0.830834)
			(end 21.088858 -1.530604)
			(stroke
				(width 0.1)
				(type default)
			)
			(layer "F.SilkS")
		)
		(fp_line
			(start 20.362926 -2.854198)
			(end 20.374864 -2.923794)
			(stroke
				(width 0.1)
				(type default)
			)
			(layer "F.SilkS")
		)
		(fp_line
			(start 20.362926 -2.854198)
			(end 20.374864 -2.923794)
			(stroke
				(width 0.1)
				(type default)
			)
			(layer "F.SilkS")
		)
		(fp_line
			(start 20.374864 -2.923794)
			(end 20.38731 -2.99339)
			(stroke
				(width 0.1)
				(type default)
			)
			(layer "F.SilkS")
		)
		(fp_line
			(start 20.374864 -2.923794)
			(end 20.38731 -2.99339)
			(stroke
				(width 0.1)
				(type default)
			)
			(layer "F.SilkS")
		)
		(fp_line
			(start 20.38731 -2.99339)
			(end 20.399248 -3.062478)
			(stroke
				(width 0.1)
				(type default)
			)
			(layer "F.SilkS")
		)
		(fp_line
			(start 20.38731 -2.99339)
			(end 20.399248 -3.062478)
			(stroke
				(width 0.1)
				(type default)
			)
			(layer "F.SilkS")
		)
		(fp_line
			(start 20.399248 -3.062478)
			(end 20.41144 -3.13182)
			(stroke
				(width 0.1)
				(type default)
			)
			(layer "F.SilkS")
		)
		(fp_line
			(start 20.399248 -3.062478)
			(end 20.41144 -3.13182)
			(stroke
				(width 0.1)
				(type default)
			)
			(layer "F.SilkS")
		)
		(fp_line
			(start 20.41144 -3.13182)
			(end 20.423886 -3.201416)
			(stroke
				(width 0.1)
				(type default)
			)
			(layer "F.SilkS")
		)
		(fp_line
			(start 20.41144 -3.13182)
			(end 20.423886 -3.201416)
			(stroke
				(width 0.1)
				(type default)
			)
			(layer "F.SilkS")
		)
		(fp_line
			(start 20.416012 -6.541262)
			(end 19.773646 -5.925058)
			(stroke
				(width 0.1)
				(type default)
			)
			(layer "F.SilkS")
		)
		(fp_line
			(start 20.416012 -6.541262)
			(end 19.773646 -5.925058)
			(stroke
				(width 0.1)
				(type default)
			)
			(layer "F.SilkS")
		)
		(fp_line
			(start 20.416012 -6.541262)
			(end 20.30095 -6.488176)
			(stroke
				(width 0.1)
				(type default)
			)
			(layer "F.SilkS")
		)
		(fp_line
			(start 20.416012 -6.541262)
			(end 20.30095 -6.488176)
			(stroke
				(width 0.1)
				(type default)
			)
			(layer "F.SilkS")
		)
		(fp_line
			(start 20.423886 -3.201416)
			(end 20.435824 -3.270758)
			(stroke
				(width 0.1)
				(type default)
			)
			(layer "F.SilkS")
		)
		(fp_line
			(start 20.423886 -3.201416)
			(end 20.435824 -3.270758)
			(stroke
				(width 0.1)
				(type default)
			)
			(layer "F.SilkS")
		)
		(fp_line
			(start 20.435824 -3.270758)
			(end 20.44827 -3.340354)
			(stroke
				(width 0.1)
				(type default)
			)
			(layer "F.SilkS")
		)
		(fp_line
			(start 20.435824 -3.270758)
			(end 20.44827 -3.340354)
			(stroke
				(width 0.1)
				(type default)
			)
			(layer "F.SilkS")
		)
		(fp_line
			(start 20.437602 -0.848106)
			(end 21.062188 -1.447546)
			(stroke
				(width 0.1)
				(type default)
			)
			(layer "F.SilkS")
		)
		(fp_line
			(start 20.437602 -0.848106)
			(end 21.062188 -1.447546)
			(stroke
				(width 0.1)
				(type default)
			)
			(layer "F.SilkS")
		)
		(fp_line
			(start 20.44827 -3.340354)
			(end 20.460462 -3.409442)
			(stroke
				(width 0.1)
				(type default)
			)
			(layer "F.SilkS")
		)
		(fp_line
			(start 20.44827 -3.340354)
			(end 20.460462 -3.409442)
			(stroke
				(width 0.1)
				(type default)
			)
			(layer "F.SilkS")
		)
		(fp_line
			(start 20.460462 -3.409442)
			(end 20.4724 -3.479038)
			(stroke
				(width 0.1)
				(type default)
			)
			(layer "F.SilkS")
		)
		(fp_line
			(start 20.460462 -3.409442)
			(end 20.4724 -3.479038)
			(stroke
				(width 0.1)
				(type default)
			)
			(layer "F.SilkS")
		)
		(fp_line
			(start 20.484846 -3.548634)
			(end 20.4724 -3.479038)
			(stroke
				(width 0.1)
				(type default)
			)
			(layer "F.SilkS")
		)
		(fp_line
			(start 20.484846 -3.548634)
			(end 20.4724 -3.479038)
			(stroke
				(width 0.1)
				(type default)
			)
			(layer "F.SilkS")
		)
		(fp_line
			(start 20.496784 -3.617976)
			(end 19.141186 -2.317242)
			(stroke
				(width 0.1)
				(type default)
			)
			(layer "F.SilkS")
		)
		(fp_line
			(start 20.496784 -3.617976)
			(end 19.141186 -2.317242)
			(stroke
				(width 0.1)
				(type default)
			)
			(layer "F.SilkS")
		)
		(fp_line
			(start 20.496784 -3.617976)
			(end 20.484846 -3.548634)
			(stroke
				(width 0.1)
				(type default)
			)
			(layer "F.SilkS")
		)
		(fp_line
			(start 20.496784 -3.617976)
			(end 20.484846 -3.548634)
			(stroke
				(width 0.1)
				(type default)
			)
			(layer "F.SilkS")
		)
		(fp_line
			(start 20.496784 -3.617976)
			(end 20.50923 -3.687064)
			(stroke
				(width 0.1)
				(type default)
			)
			(layer "F.SilkS")
		)
		(fp_line
			(start 20.496784 -3.617976)
			(end 20.50923 -3.687064)
			(stroke
				(width 0.1)
				(type default)
			)
			(layer "F.SilkS")
		)
		(fp_line
			(start 20.50923 -3.687064)
			(end 20.521422 -3.75666)
			(stroke
				(width 0.1)
				(type default)
			)
			(layer "F.SilkS")
		)
		(fp_line
			(start 20.50923 -3.687064)
			(end 20.521422 -3.75666)
			(stroke
				(width 0.1)
				(type default)
			)
			(layer "F.SilkS")
		)
		(fp_line
			(start 20.515834 -0.865632)
			(end 21.035772 -1.364742)
			(stroke
				(width 0.1)
				(type default)
			)
			(layer "F.SilkS")
		)
		(fp_line
			(start 20.515834 -0.865632)
			(end 21.035772 -1.364742)
			(stroke
				(width 0.1)
				(type default)
			)
			(layer "F.SilkS")
		)
		(fp_line
			(start 20.521422 -3.75666)
			(end 20.533614 -3.826256)
			(stroke
				(width 0.1)
				(type default)
			)
			(layer "F.SilkS")
		)
		(fp_line
			(start 20.521422 -3.75666)
			(end 20.533614 -3.826256)
			(stroke
				(width 0.1)
				(type default)
			)
			(layer "F.SilkS")
		)
		(fp_line
			(start 20.531328 -6.594348)
			(end 19.761708 -5.85597)
			(stroke
				(width 0.1)
				(type default)
			)
			(layer "F.SilkS")
		)
		(fp_line
			(start 20.531328 -6.594348)
			(end 19.761708 -5.85597)
			(stroke
				(width 0.1)
				(type default)
			)
			(layer "F.SilkS")
		)
		(fp_line
			(start 20.531328 -6.594348)
			(end 20.416012 -6.541262)
			(stroke
				(width 0.1)
				(type default)
			)
			(layer "F.SilkS")
		)
		(fp_line
			(start 20.531328 -6.594348)
			(end 20.416012 -6.541262)
			(stroke
				(width 0.1)
				(type default)
			)
			(layer "F.SilkS")
		)
		(fp_line
			(start 20.533614 -3.826256)
			(end 20.545806 -3.895344)
			(stroke
				(width 0.1)
				(type default)
			)
			(layer "F.SilkS")
		)
		(fp_line
			(start 20.533614 -3.826256)
			(end 20.545806 -3.895344)
			(stroke
				(width 0.1)
				(type default)
			)
			(layer "F.SilkS")
		)
		(fp_line
			(start 20.545806 -3.895344)
			(end 20.557744 -3.96494)
			(stroke
				(width 0.1)
				(type default)
			)
			(layer "F.SilkS")
		)
		(fp_line
			(start 20.545806 -3.895344)
			(end 20.557744 -3.96494)
			(stroke
				(width 0.1)
				(type default)
			)
			(layer "F.SilkS")
		)
		(fp_line
			(start 20.557744 -3.96494)
			(end 20.57019 -4.034282)
			(stroke
				(width 0.1)
				(type default)
			)
			(layer "F.SilkS")
		)
		(fp_line
			(start 20.557744 -3.96494)
			(end 20.57019 -4.034282)
			(stroke
				(width 0.1)
				(type default)
			)
			(layer "F.SilkS")
		)
		(fp_line
			(start 20.57019 -4.034282)
			(end 20.582382 -4.103878)
			(stroke
				(width 0.1)
				(type default)
			)
			(layer "F.SilkS")
		)
		(fp_line
			(start 20.57019 -4.034282)
			(end 20.582382 -4.103878)
			(stroke
				(width 0.1)
				(type default)
			)
			(layer "F.SilkS")
		)
		(fp_line
			(start 20.582382 -4.103878)
			(end 20.583398 -4.109466)
			(stroke
				(width 0.1)
				(type default)
			)
			(layer "F.SilkS")
		)
		(fp_line
			(start 20.582382 -4.103878)
			(end 20.583398 -4.109466)
			(stroke
				(width 0.1)
				(type default)
			)
			(layer "F.SilkS")
		)
		(fp_line
			(start 20.582382 -4.103878)
			(end 20.588224 -4.109466)
			(stroke
				(width 0.1)
				(type default)
			)
			(layer "F.SilkS")
		)
		(fp_line
			(start 20.582382 -4.103878)
			(end 20.588224 -4.109466)
			(stroke
				(width 0.1)
				(type default)
			)
			(layer "F.SilkS")
		)
		(fp_line
			(start 20.583398 -4.109466)
			(end 20.588224 -4.109466)
			(stroke
				(width 0.1)
				(type default)
			)
			(layer "F.SilkS")
		)
		(fp_line
			(start 20.583398 -4.109466)
			(end 20.588224 -4.109466)
			(stroke
				(width 0.1)
				(type default)
			)
			(layer "F.SilkS")
		)
		(fp_line
			(start 20.610322 -0.898652)
			(end 21.00961 -1.281684)
			(stroke
				(width 0.1)
				(type default)
			)
			(layer "F.SilkS")
		)
		(fp_line
			(start 20.610322 -0.898652)
			(end 21.00961 -1.281684)
			(stroke
				(width 0.1)
				(type default)
			)
			(layer "F.SilkS")
		)
		(fp_line
			(start 20.647152 -6.647434)
			(end 19.749262 -5.786374)
			(stroke
				(width 0.1)
				(type default)
			)
			(layer "F.SilkS")
		)
		(fp_line
			(start 20.647152 -6.647434)
			(end 19.749262 -5.786374)
			(stroke
				(width 0.1)
				(type default)
			)
			(layer "F.SilkS")
		)
		(fp_line
			(start 20.647152 -6.647434)
			(end 20.531328 -6.594348)
			(stroke
				(width 0.1)
				(type default)
			)
			(layer "F.SilkS")
		)
		(fp_line
			(start 20.647152 -6.647434)
			(end 20.531328 -6.594348)
			(stroke
				(width 0.1)
				(type default)
			)
			(layer "F.SilkS")
		)
		(fp_line
			(start 20.648422 -4.109466)
			(end 20.588224 -4.109466)
			(stroke
				(width 0.1)
				(type default)
			)
			(layer "F.SilkS")
		)
		(fp_line
			(start 20.648422 -4.109466)
			(end 20.588224 -4.109466)
			(stroke
				(width 0.1)
				(type default)
			)
			(layer "F.SilkS")
		)
		(fp_line
			(start 20.708366 -0.934974)
			(end 20.98294 -1.198626)
			(stroke
				(width 0.1)
				(type default)
			)
			(layer "F.SilkS")
		)
		(fp_line
			(start 20.708366 -0.934974)
			(end 20.98294 -1.198626)
			(stroke
				(width 0.1)
				(type default)
			)
			(layer "F.SilkS")
		)
		(fp_line
			(start 20.70862 -4.109466)
			(end 20.648422 -4.109466)
			(stroke
				(width 0.1)
				(type default)
			)
			(layer "F.SilkS")
		)
		(fp_line
			(start 20.70862 -4.109466)
			(end 20.648422 -4.109466)
			(stroke
				(width 0.1)
				(type default)
			)
			(layer "F.SilkS")
		)
		(fp_line
			(start 20.762722 -6.70052)
			(end 19.737324 -5.716778)
			(stroke
				(width 0.1)
				(type default)
			)
			(layer "F.SilkS")
		)
		(fp_line
			(start 20.762722 -6.70052)
			(end 19.737324 -5.716778)
			(stroke
				(width 0.1)
				(type default)
			)
			(layer "F.SilkS")
		)
		(fp_line
			(start 20.762722 -6.70052)
			(end 20.647152 -6.647434)
			(stroke
				(width 0.1)
				(type default)
			)
			(layer "F.SilkS")
		)
		(fp_line
			(start 20.762722 -6.70052)
			(end 20.647152 -6.647434)
			(stroke
				(width 0.1)
				(type default)
			)
			(layer "F.SilkS")
		)
		(fp_line
			(start 20.768564 -4.109466)
			(end 20.70862 -4.109466)
			(stroke
				(width 0.1)
				(type default)
			)
			(layer "F.SilkS")
		)
		(fp_line
			(start 20.768564 -4.109466)
			(end 20.70862 -4.109466)
			(stroke
				(width 0.1)
				(type default)
			)
			(layer "F.SilkS")
		)
		(fp_line
			(start 20.769072 -5.171694)
			(end 20.793202 -5.171694)
			(stroke
				(width 0.1)
				(type default)
			)
			(layer "F.SilkS")
		)
		(fp_line
			(start 20.769072 -5.171694)
			(end 20.793202 -5.171694)
			(stroke
				(width 0.1)
				(type default)
			)
			(layer "F.SilkS")
		)
		(fp_line
			(start 20.776184 -5.21335)
			(end 20.769072 -5.171694)
			(stroke
				(width 0.1)
				(type default)
			)
			(layer "F.SilkS")
		)
		(fp_line
			(start 20.776184 -5.21335)
			(end 20.769072 -5.171694)
			(stroke
				(width 0.1)
				(type default)
			)
			(layer "F.SilkS")
		)
		(fp_line
			(start 20.776184 -5.21335)
			(end 20.78863 -5.282692)
			(stroke
				(width 0.1)
				(type default)
			)
			(layer "F.SilkS")
		)
		(fp_line
			(start 20.776184 -5.21335)
			(end 20.78863 -5.282692)
			(stroke
				(width 0.1)
				(type default)
			)
			(layer "F.SilkS")
		)
		(fp_line
			(start 20.78863 -5.282692)
			(end 19.433032 -3.982466)
			(stroke
				(width 0.1)
				(type default)
			)
			(layer "F.SilkS")
		)
		(fp_line
			(start 20.78863 -5.282692)
			(end 19.433032 -3.982466)
			(stroke
				(width 0.1)
				(type default)
			)
			(layer "F.SilkS")
		)
		(fp_line
			(start 20.78863 -5.282692)
			(end 20.800822 -5.352034)
			(stroke
				(width 0.1)
				(type default)
			)
			(layer "F.SilkS")
		)
		(fp_line
			(start 20.78863 -5.282692)
			(end 20.800822 -5.352034)
			(stroke
				(width 0.1)
				(type default)
			)
			(layer "F.SilkS")
		)
		(fp_line
			(start 20.793202 -5.171694)
			(end 19.408902 -3.843528)
			(stroke
				(width 0.1)
				(type default)
			)
			(layer "F.SilkS")
		)
		(fp_line
			(start 20.793202 -5.171694)
			(end 19.408902 -3.843528)
			(stroke
				(width 0.1)
				(type default)
			)
			(layer "F.SilkS")
		)
		(fp_line
			(start 20.800822 -5.352034)
			(end 19.445478 -4.051554)
			(stroke
				(width 0.1)
				(type default)
			)
			(layer "F.SilkS")
		)
		(fp_line
			(start 20.800822 -5.352034)
			(end 19.445478 -4.051554)
			(stroke
				(width 0.1)
				(type default)
			)
			(layer "F.SilkS")
		)
		(fp_line
			(start 20.800822 -5.352034)
			(end 20.81276 -5.421376)
			(stroke
				(width 0.1)
				(type default)
			)
			(layer "F.SilkS")
		)
		(fp_line
			(start 20.800822 -5.352034)
			(end 20.81276 -5.421376)
			(stroke
				(width 0.1)
				(type default)
			)
			(layer "F.SilkS")
		)
		(fp_line
			(start 20.81276 -5.421376)
			(end 20.825206 -5.490972)
			(stroke
				(width 0.1)
				(type default)
			)
			(layer "F.SilkS")
		)
		(fp_line
			(start 20.81276 -5.421376)
			(end 20.825206 -5.490972)
			(stroke
				(width 0.1)
				(type default)
			)
			(layer "F.SilkS")
		)
		(fp_line
			(start 20.825206 -5.490972)
			(end 20.837144 -5.560314)
			(stroke
				(width 0.1)
				(type default)
			)
			(layer "F.SilkS")
		)
		(fp_line
			(start 20.825206 -5.490972)
			(end 20.837144 -5.560314)
			(stroke
				(width 0.1)
				(type default)
			)
			(layer "F.SilkS")
		)
		(fp_line
			(start 20.829016 -4.109466)
			(end 20.768564 -4.109466)
			(stroke
				(width 0.1)
				(type default)
			)
			(layer "F.SilkS")
		)
		(fp_line
			(start 20.829016 -4.109466)
			(end 20.768564 -4.109466)
			(stroke
				(width 0.1)
				(type default)
			)
			(layer "F.SilkS")
		)
		(fp_line
			(start 20.831302 -0.995426)
			(end 20.956524 -1.115314)
			(stroke
				(width 0.1)
				(type default)
			)
			(layer "F.SilkS")
		)
		(fp_line
			(start 20.831302 -0.995426)
			(end 20.956524 -1.115314)
			(stroke
				(width 0.1)
				(type default)
			)
			(layer "F.SilkS")
		)
		(fp_line
			(start 20.837144 -5.560314)
			(end 20.84959 -5.629656)
			(stroke
				(width 0.1)
				(type default)
			)
			(layer "F.SilkS")
		)
		(fp_line
			(start 20.837144 -5.560314)
			(end 20.84959 -5.629656)
			(stroke
				(width 0.1)
				(type default)
			)
			(layer "F.SilkS")
		)
		(fp_line
			(start 20.84959 -5.629656)
			(end 20.861782 -5.699252)
			(stroke
				(width 0.1)
				(type default)
			)
			(layer "F.SilkS")
		)
		(fp_line
			(start 20.84959 -5.629656)
			(end 20.861782 -5.699252)
			(stroke
				(width 0.1)
				(type default)
			)
			(layer "F.SilkS")
		)
		(fp_line
			(start 20.8534 -5.171694)
			(end 19.396456 -3.774186)
			(stroke
				(width 0.1)
				(type default)
			)
			(layer "F.SilkS")
		)
		(fp_line
			(start 20.8534 -5.171694)
			(end 19.396456 -3.774186)
			(stroke
				(width 0.1)
				(type default)
			)
			(layer "F.SilkS")
		)
		(fp_line
			(start 20.8534 -5.171694)
			(end 20.793202 -5.171694)
			(stroke
				(width 0.1)
				(type default)
			)
			(layer "F.SilkS")
		)
		(fp_line
			(start 20.8534 -5.171694)
			(end 20.793202 -5.171694)
			(stroke
				(width 0.1)
				(type default)
			)
			(layer "F.SilkS")
		)
		(fp_line
			(start 20.861782 -5.699252)
			(end 20.874228 -5.768594)
			(stroke
				(width 0.1)
				(type default)
			)
			(layer "F.SilkS")
		)
		(fp_line
			(start 20.861782 -5.699252)
			(end 20.874228 -5.768594)
			(stroke
				(width 0.1)
				(type default)
			)
			(layer "F.SilkS")
		)
		(fp_line
			(start 20.874228 -5.768594)
			(end 20.886166 -5.837936)
			(stroke
				(width 0.1)
				(type default)
			)
			(layer "F.SilkS")
		)
		(fp_line
			(start 20.874228 -5.768594)
			(end 20.886166 -5.837936)
			(stroke
				(width 0.1)
				(type default)
			)
			(layer "F.SilkS")
		)
		(fp_line
			(start 20.877784 -6.753606)
			(end 19.725132 -5.647436)
			(stroke
				(width 0.1)
				(type default)
			)
			(layer "F.SilkS")
		)
		(fp_line
			(start 20.877784 -6.753606)
			(end 19.725132 -5.647436)
			(stroke
				(width 0.1)
				(type default)
			)
			(layer "F.SilkS")
		)
		(fp_line
			(start 20.877784 -6.753606)
			(end 20.762722 -6.70052)
			(stroke
				(width 0.1)
				(type default)
			)
			(layer "F.SilkS")
		)
		(fp_line
			(start 20.877784 -6.753606)
			(end 20.762722 -6.70052)
			(stroke
				(width 0.1)
				(type default)
			)
			(layer "F.SilkS")
		)
		(fp_line
			(start 20.886166 -5.837936)
			(end 20.898104 -5.907278)
			(stroke
				(width 0.1)
				(type default)
			)
			(layer "F.SilkS")
		)
		(fp_line
			(start 20.886166 -5.837936)
			(end 20.898104 -5.907278)
			(stroke
				(width 0.1)
				(type default)
			)
			(layer "F.SilkS")
		)
		(fp_line
			(start 20.889214 -4.109466)
			(end 20.829016 -4.109466)
			(stroke
				(width 0.1)
				(type default)
			)
			(layer "F.SilkS")
		)
		(fp_line
			(start 20.889214 -4.109466)
			(end 20.829016 -4.109466)
			(stroke
				(width 0.1)
				(type default)
			)
			(layer "F.SilkS")
		)
		(fp_line
			(start 20.898104 -5.907278)
			(end 20.91055 -5.976874)
			(stroke
				(width 0.1)
				(type default)
			)
			(layer "F.SilkS")
		)
		(fp_line
			(start 20.898104 -5.907278)
			(end 20.91055 -5.976874)
			(stroke
				(width 0.1)
				(type default)
			)
			(layer "F.SilkS")
		)
		(fp_line
			(start 20.91055 -5.976874)
			(end 20.922742 -6.04647)
			(stroke
				(width 0.1)
				(type default)
			)
			(layer "F.SilkS")
		)
		(fp_line
			(start 20.91055 -5.976874)
			(end 20.922742 -6.04647)
			(stroke
				(width 0.1)
				(type default)
			)
			(layer "F.SilkS")
		)
		(fp_line
			(start 20.913344 -5.171694)
			(end 19.384518 -3.704844)
			(stroke
				(width 0.1)
				(type default)
			)
			(layer "F.SilkS")
		)
		(fp_line
			(start 20.913344 -5.171694)
			(end 19.384518 -3.704844)
			(stroke
				(width 0.1)
				(type default)
			)
			(layer "F.SilkS")
		)
		(fp_line
			(start 20.913344 -5.171694)
			(end 20.8534 -5.171694)
			(stroke
				(width 0.1)
				(type default)
			)
			(layer "F.SilkS")
		)
		(fp_line
			(start 20.913344 -5.171694)
			(end 20.8534 -5.171694)
			(stroke
				(width 0.1)
				(type default)
			)
			(layer "F.SilkS")
		)
		(fp_line
			(start 20.922742 -6.04647)
			(end 20.93468 -6.115558)
			(stroke
				(width 0.1)
				(type default)
			)
			(layer "F.SilkS")
		)
		(fp_line
			(start 20.922742 -6.04647)
			(end 20.93468 -6.115558)
			(stroke
				(width 0.1)
				(type default)
			)
			(layer "F.SilkS")
		)
		(fp_line
			(start 20.93468 -6.115558)
			(end 20.947126 -6.1849)
			(stroke
				(width 0.1)
				(type default)
			)
			(layer "F.SilkS")
		)
		(fp_line
			(start 20.93468 -6.115558)
			(end 20.947126 -6.1849)
			(stroke
				(width 0.1)
				(type default)
			)
			(layer "F.SilkS")
		)
		(fp_line
			(start 20.947126 -6.1849)
			(end 20.959318 -6.254496)
			(stroke
				(width 0.1)
				(type default)
			)
			(layer "F.SilkS")
		)
		(fp_line
			(start 20.947126 -6.1849)
			(end 20.959318 -6.254496)
			(stroke
				(width 0.1)
				(type default)
			)
			(layer "F.SilkS")
		)
		(fp_line
			(start 20.949666 -4.109466)
			(end 20.889214 -4.109466)
			(stroke
				(width 0.1)
				(type default)
			)
			(layer "F.SilkS")
		)
		(fp_line
			(start 20.949666 -4.109466)
			(end 20.889214 -4.109466)
			(stroke
				(width 0.1)
				(type default)
			)
			(layer "F.SilkS")
		)
		(fp_line
			(start 20.959318 -6.254496)
			(end 20.97151 -6.324092)
			(stroke
				(width 0.1)
				(type default)
			)
			(layer "F.SilkS")
		)
		(fp_line
			(start 20.959318 -6.254496)
			(end 20.97151 -6.324092)
			(stroke
				(width 0.1)
				(type default)
			)
			(layer "F.SilkS")
		)
		(fp_line
			(start 20.97151 -6.324092)
			(end 18.75155 -4.194556)
			(stroke
				(width 0.1)
				(type default)
			)
			(layer "F.SilkS")
		)
		(fp_line
			(start 20.97151 -6.324092)
			(end 18.75155 -4.194556)
			(stroke
				(width 0.1)
				(type default)
			)
			(layer "F.SilkS")
		)
		(fp_line
			(start 20.97151 -6.324092)
			(end 20.983702 -6.393434)
			(stroke
				(width 0.1)
				(type default)
			)
			(layer "F.SilkS")
		)
		(fp_line
			(start 20.97151 -6.324092)
			(end 20.983702 -6.393434)
			(stroke
				(width 0.1)
				(type default)
			)
			(layer "F.SilkS")
		)
		(fp_line
			(start 20.973542 -5.171694)
			(end 19.372326 -3.635502)
			(stroke
				(width 0.1)
				(type default)
			)
			(layer "F.SilkS")
		)
		(fp_line
			(start 20.973542 -5.171694)
			(end 19.372326 -3.635502)
			(stroke
				(width 0.1)
				(type default)
			)
			(layer "F.SilkS")
		)
		(fp_line
			(start 20.973542 -5.171694)
			(end 20.913344 -5.171694)
			(stroke
				(width 0.1)
				(type default)
			)
			(layer "F.SilkS")
		)
		(fp_line
			(start 20.973542 -5.171694)
			(end 20.913344 -5.171694)
			(stroke
				(width 0.1)
				(type default)
			)
			(layer "F.SilkS")
		)
		(fp_line
			(start 20.98294 -1.198626)
			(end 20.956524 -1.115314)
			(stroke
				(width 0.1)
				(type default)
			)
			(layer "F.SilkS")
		)
		(fp_line
			(start 20.98294 -1.198626)
			(end 20.956524 -1.115314)
			(stroke
				(width 0.1)
				(type default)
			)
			(layer "F.SilkS")
		)
		(fp_line
			(start 20.983702 -6.393434)
			(end 18.763996 -4.263898)
			(stroke
				(width 0.1)
				(type default)
			)
			(layer "F.SilkS")
		)
		(fp_line
			(start 20.983702 -6.393434)
			(end 18.763996 -4.263898)
			(stroke
				(width 0.1)
				(type default)
			)
			(layer "F.SilkS")
		)
		(fp_line
			(start 20.983702 -6.393434)
			(end 20.996148 -6.462522)
			(stroke
				(width 0.1)
				(type default)
			)
			(layer "F.SilkS")
		)
		(fp_line
			(start 20.983702 -6.393434)
			(end 20.996148 -6.462522)
			(stroke
				(width 0.1)
				(type default)
			)
			(layer "F.SilkS")
		)
		(fp_line
			(start 20.993354 -6.806438)
			(end 19.712686 -5.578094)
			(stroke
				(width 0.1)
				(type default)
			)
			(layer "F.SilkS")
		)
		(fp_line
			(start 20.993354 -6.806438)
			(end 19.712686 -5.578094)
			(stroke
				(width 0.1)
				(type default)
			)
			(layer "F.SilkS")
		)
		(fp_line
			(start 20.993354 -6.806438)
			(end 20.877784 -6.753606)
			(stroke
				(width 0.1)
				(type default)
			)
			(layer "F.SilkS")
		)
		(fp_line
			(start 20.993354 -6.806438)
			(end 20.877784 -6.753606)
			(stroke
				(width 0.1)
				(type default)
			)
			(layer "F.SilkS")
		)
		(fp_line
			(start 20.996148 -6.462522)
			(end 18.775934 -4.33324)
			(stroke
				(width 0.1)
				(type default)
			)
			(layer "F.SilkS")
		)
		(fp_line
			(start 20.996148 -6.462522)
			(end 18.775934 -4.33324)
			(stroke
				(width 0.1)
				(type default)
			)
			(layer "F.SilkS")
		)
		(fp_line
			(start 20.996148 -6.462522)
			(end 21.008086 -6.532118)
			(stroke
				(width 0.1)
				(type default)
			)
			(layer "F.SilkS")
		)
		(fp_line
			(start 20.996148 -6.462522)
			(end 21.008086 -6.532118)
			(stroke
				(width 0.1)
				(type default)
			)
			(layer "F.SilkS")
		)
		(fp_line
			(start 21.008086 -6.532118)
			(end 19.651726 -5.23113)
			(stroke
				(width 0.1)
				(type default)
			)
			(layer "F.SilkS")
		)
		(fp_line
			(start 21.008086 -6.532118)
			(end 19.651726 -5.23113)
			(stroke
				(width 0.1)
				(type default)
			)
			(layer "F.SilkS")
		)
		(fp_line
			(start 21.008086 -6.532118)
			(end 21.020278 -6.60146)
			(stroke
				(width 0.1)
				(type default)
			)
			(layer "F.SilkS")
		)
		(fp_line
			(start 21.008086 -6.532118)
			(end 21.020278 -6.60146)
			(stroke
				(width 0.1)
				(type default)
			)
			(layer "F.SilkS")
		)
		(fp_line
			(start 21.00961 -4.109466)
			(end 20.949666 -4.109466)
			(stroke
				(width 0.1)
				(type default)
			)
			(layer "F.SilkS")
		)
		(fp_line
			(start 21.00961 -4.109466)
			(end 20.949666 -4.109466)
			(stroke
				(width 0.1)
				(type default)
			)
			(layer "F.SilkS")
		)
		(fp_line
			(start 21.00961 -4.109466)
			(end 21.069554 -4.109466)
			(stroke
				(width 0.1)
				(type default)
			)
			(layer "F.SilkS")
		)
		(fp_line
			(start 21.00961 -4.109466)
			(end 21.069554 -4.109466)
			(stroke
				(width 0.1)
				(type default)
			)
			(layer "F.SilkS")
		)
		(fp_line
			(start 21.00961 -1.281684)
			(end 20.98294 -1.198626)
			(stroke
				(width 0.1)
				(type default)
			)
			(layer "F.SilkS")
		)
		(fp_line
			(start 21.00961 -1.281684)
			(end 20.98294 -1.198626)
			(stroke
				(width 0.1)
				(type default)
			)
			(layer "F.SilkS")
		)
		(fp_line
			(start 21.020278 -6.60146)
			(end 19.664172 -5.300472)
			(stroke
				(width 0.1)
				(type default)
			)
			(layer "F.SilkS")
		)
		(fp_line
			(start 21.020278 -6.60146)
			(end 19.664172 -5.300472)
			(stroke
				(width 0.1)
				(type default)
			)
			(layer "F.SilkS")
		)
		(fp_line
			(start 21.020278 -6.60146)
			(end 21.03247 -6.671056)
			(stroke
				(width 0.1)
				(type default)
			)
			(layer "F.SilkS")
		)
		(fp_line
			(start 21.020278 -6.60146)
			(end 21.03247 -6.671056)
			(stroke
				(width 0.1)
				(type default)
			)
			(layer "F.SilkS")
		)
		(fp_line
			(start 21.03247 -6.671056)
			(end 19.676364 -5.370068)
			(stroke
				(width 0.1)
				(type default)
			)
			(layer "F.SilkS")
		)
		(fp_line
			(start 21.03247 -6.671056)
			(end 19.676364 -5.370068)
			(stroke
				(width 0.1)
				(type default)
			)
			(layer "F.SilkS")
		)
		(fp_line
			(start 21.03247 -6.671056)
			(end 21.044662 -6.740144)
			(stroke
				(width 0.1)
				(type default)
			)
			(layer "F.SilkS")
		)
		(fp_line
			(start 21.03247 -6.671056)
			(end 21.044662 -6.740144)
			(stroke
				(width 0.1)
				(type default)
			)
			(layer "F.SilkS")
		)
		(fp_line
			(start 21.033994 -5.171694)
			(end 19.35988 -3.56616)
			(stroke
				(width 0.1)
				(type default)
			)
			(layer "F.SilkS")
		)
		(fp_line
			(start 21.033994 -5.171694)
			(end 19.35988 -3.56616)
			(stroke
				(width 0.1)
				(type default)
			)
			(layer "F.SilkS")
		)
		(fp_line
			(start 21.033994 -5.171694)
			(end 20.973542 -5.171694)
			(stroke
				(width 0.1)
				(type default)
			)
			(layer "F.SilkS")
		)
		(fp_line
			(start 21.033994 -5.171694)
			(end 20.973542 -5.171694)
			(stroke
				(width 0.1)
				(type default)
			)
			(layer "F.SilkS")
		)
		(fp_line
			(start 21.035772 -1.364742)
			(end 21.00961 -1.281684)
			(stroke
				(width 0.1)
				(type default)
			)
			(layer "F.SilkS")
		)
		(fp_line
			(start 21.035772 -1.364742)
			(end 21.00961 -1.281684)
			(stroke
				(width 0.1)
				(type default)
			)
			(layer "F.SilkS")
		)
		(fp_line
			(start 21.044662 -6.740144)
			(end 19.688302 -5.439156)
			(stroke
				(width 0.1)
				(type default)
			)
			(layer "F.SilkS")
		)
		(fp_line
			(start 21.044662 -6.740144)
			(end 19.688302 -5.439156)
			(stroke
				(width 0.1)
				(type default)
			)
			(layer "F.SilkS")
		)
		(fp_line
			(start 21.044662 -6.740144)
			(end 21.057108 -6.80974)
			(stroke
				(width 0.1)
				(type default)
			)
			(layer "F.SilkS")
		)
		(fp_line
			(start 21.044662 -6.740144)
			(end 21.057108 -6.80974)
			(stroke
				(width 0.1)
				(type default)
			)
			(layer "F.SilkS")
		)
		(fp_line
			(start 21.057108 -6.80974)
			(end 19.700748 -5.508752)
			(stroke
				(width 0.1)
				(type default)
			)
			(layer "F.SilkS")
		)
		(fp_line
			(start 21.057108 -6.80974)
			(end 19.700748 -5.508752)
			(stroke
				(width 0.1)
				(type default)
			)
			(layer "F.SilkS")
		)
		(fp_line
			(start 21.057108 -6.80974)
			(end 21.061934 -6.838188)
			(stroke
				(width 0.1)
				(type default)
			)
			(layer "F.SilkS")
		)
		(fp_line
			(start 21.057108 -6.80974)
			(end 21.061934 -6.838188)
			(stroke
				(width 0.1)
				(type default)
			)
			(layer "F.SilkS")
		)
		(fp_line
			(start 21.061934 -6.838188)
			(end 20.993354 -6.806438)
			(stroke
				(width 0.1)
				(type default)
			)
			(layer "F.SilkS")
		)
		(fp_line
			(start 21.061934 -6.838188)
			(end 20.993354 -6.806438)
			(stroke
				(width 0.1)
				(type default)
			)
			(layer "F.SilkS")
		)
		(fp_line
			(start 21.062188 -1.447546)
			(end 21.035772 -1.364742)
			(stroke
				(width 0.1)
				(type default)
			)
			(layer "F.SilkS")
		)
		(fp_line
			(start 21.062188 -1.447546)
			(end 21.035772 -1.364742)
			(stroke
				(width 0.1)
				(type default)
			)
			(layer "F.SilkS")
		)
		(fp_line
			(start 21.069554 -4.109466)
			(end 21.129752 -4.109466)
			(stroke
				(width 0.1)
				(type default)
			)
			(layer "F.SilkS")
		)
		(fp_line
			(start 21.069554 -4.109466)
			(end 21.129752 -4.109466)
			(stroke
				(width 0.1)
				(type default)
			)
			(layer "F.SilkS")
		)
		(fp_line
			(start 21.088858 -1.530604)
			(end 21.062188 -1.447546)
			(stroke
				(width 0.1)
				(type default)
			)
			(layer "F.SilkS")
		)
		(fp_line
			(start 21.088858 -1.530604)
			(end 21.062188 -1.447546)
			(stroke
				(width 0.1)
				(type default)
			)
			(layer "F.SilkS")
		)
		(fp_line
			(start 21.093938 -5.171694)
			(end 19.347942 -3.496564)
			(stroke
				(width 0.1)
				(type default)
			)
			(layer "F.SilkS")
		)
		(fp_line
			(start 21.093938 -5.171694)
			(end 19.347942 -3.496564)
			(stroke
				(width 0.1)
				(type default)
			)
			(layer "F.SilkS")
		)
		(fp_line
			(start 21.093938 -5.171694)
			(end 21.033994 -5.171694)
			(stroke
				(width 0.1)
				(type default)
			)
			(layer "F.SilkS")
		)
		(fp_line
			(start 21.093938 -5.171694)
			(end 21.033994 -5.171694)
			(stroke
				(width 0.1)
				(type default)
			)
			(layer "F.SilkS")
		)
		(fp_line
			(start 21.115274 -1.613916)
			(end 21.088858 -1.530604)
			(stroke
				(width 0.1)
				(type default)
			)
			(layer "F.SilkS")
		)
		(fp_line
			(start 21.115274 -1.613916)
			(end 21.088858 -1.530604)
			(stroke
				(width 0.1)
				(type default)
			)
			(layer "F.SilkS")
		)
		(fp_line
			(start 21.129752 -4.109466)
			(end 21.18995 -4.109466)
			(stroke
				(width 0.1)
				(type default)
			)
			(layer "F.SilkS")
		)
		(fp_line
			(start 21.129752 -4.109466)
			(end 21.18995 -4.109466)
			(stroke
				(width 0.1)
				(type default)
			)
			(layer "F.SilkS")
		)
		(fp_line
			(start 21.141436 -1.69672)
			(end 21.115274 -1.613916)
			(stroke
				(width 0.1)
				(type default)
			)
			(layer "F.SilkS")
		)
		(fp_line
			(start 21.141436 -1.69672)
			(end 21.115274 -1.613916)
			(stroke
				(width 0.1)
				(type default)
			)
			(layer "F.SilkS")
		)
		(fp_line
			(start 21.154136 -5.171694)
			(end 19.33575 -3.427476)
			(stroke
				(width 0.1)
				(type default)
			)
			(layer "F.SilkS")
		)
		(fp_line
			(start 21.154136 -5.171694)
			(end 19.33575 -3.427476)
			(stroke
				(width 0.1)
				(type default)
			)
			(layer "F.SilkS")
		)
		(fp_line
			(start 21.154136 -5.171694)
			(end 21.093938 -5.171694)
			(stroke
				(width 0.1)
				(type default)
			)
			(layer "F.SilkS")
		)
		(fp_line
			(start 21.154136 -5.171694)
			(end 21.093938 -5.171694)
			(stroke
				(width 0.1)
				(type default)
			)
			(layer "F.SilkS")
		)
		(fp_line
			(start 21.167852 -1.779778)
			(end 21.141436 -1.69672)
			(stroke
				(width 0.1)
				(type default)
			)
			(layer "F.SilkS")
		)
		(fp_line
			(start 21.167852 -1.779778)
			(end 21.141436 -1.69672)
			(stroke
				(width 0.1)
				(type default)
			)
			(layer "F.SilkS")
		)
		(fp_line
			(start 21.18995 -4.109466)
			(end 21.250402 -4.109466)
			(stroke
				(width 0.1)
				(type default)
			)
			(layer "F.SilkS")
		)
		(fp_line
			(start 21.18995 -4.109466)
			(end 21.250402 -4.109466)
			(stroke
				(width 0.1)
				(type default)
			)
			(layer "F.SilkS")
		)
		(fp_line
			(start 21.194268 -1.862836)
			(end 21.167852 -1.779778)
			(stroke
				(width 0.1)
				(type default)
			)
			(layer "F.SilkS")
		)
		(fp_line
			(start 21.194268 -1.862836)
			(end 21.167852 -1.779778)
			(stroke
				(width 0.1)
				(type default)
			)
			(layer "F.SilkS")
		)
		(fp_line
			(start 21.21408 -5.171694)
			(end 19.323558 -3.358134)
			(stroke
				(width 0.1)
				(type default)
			)
			(layer "F.SilkS")
		)
		(fp_line
			(start 21.21408 -5.171694)
			(end 19.323558 -3.358134)
			(stroke
				(width 0.1)
				(type default)
			)
			(layer "F.SilkS")
		)
		(fp_line
			(start 21.21408 -5.171694)
			(end 21.154136 -5.171694)
			(stroke
				(width 0.1)
				(type default)
			)
			(layer "F.SilkS")
		)
		(fp_line
			(start 21.21408 -5.171694)
			(end 21.154136 -5.171694)
			(stroke
				(width 0.1)
				(type default)
			)
			(layer "F.SilkS")
		)
		(fp_line
			(start 21.220684 -1.946148)
			(end 21.194268 -1.862836)
			(stroke
				(width 0.1)
				(type default)
			)
			(layer "F.SilkS")
		)
		(fp_line
			(start 21.220684 -1.946148)
			(end 21.194268 -1.862836)
			(stroke
				(width 0.1)
				(type default)
			)
			(layer "F.SilkS")
		)
		(fp_line
			(start 21.2471 -2.028952)
			(end 21.220684 -1.946148)
			(stroke
				(width 0.1)
				(type default)
			)
			(layer "F.SilkS")
		)
		(fp_line
			(start 21.2471 -2.028952)
			(end 21.220684 -1.946148)
			(stroke
				(width 0.1)
				(type default)
			)
			(layer "F.SilkS")
		)
		(fp_line
			(start 21.250402 -4.109466)
			(end 21.310346 -4.109466)
			(stroke
				(width 0.1)
				(type default)
			)
			(layer "F.SilkS")
		)
		(fp_line
			(start 21.250402 -4.109466)
			(end 21.310346 -4.109466)
			(stroke
				(width 0.1)
				(type default)
			)
			(layer "F.SilkS")
		)
		(fp_line
			(start 21.273516 -2.11201)
			(end 21.2471 -2.028952)
			(stroke
				(width 0.1)
				(type default)
			)
			(layer "F.SilkS")
		)
		(fp_line
			(start 21.273516 -2.11201)
			(end 21.2471 -2.028952)
			(stroke
				(width 0.1)
				(type default)
			)
			(layer "F.SilkS")
		)
		(fp_line
			(start 21.274532 -5.171694)
			(end 19.311366 -3.288538)
			(stroke
				(width 0.1)
				(type default)
			)
			(layer "F.SilkS")
		)
		(fp_line
			(start 21.274532 -5.171694)
			(end 19.311366 -3.288538)
			(stroke
				(width 0.1)
				(type default)
			)
			(layer "F.SilkS")
		)
		(fp_line
			(start 21.274532 -5.171694)
			(end 21.21408 -5.171694)
			(stroke
				(width 0.1)
				(type default)
			)
			(layer "F.SilkS")
		)
		(fp_line
			(start 21.274532 -5.171694)
			(end 21.21408 -5.171694)
			(stroke
				(width 0.1)
				(type default)
			)
			(layer "F.SilkS")
		)
		(fp_line
			(start 21.299932 -2.195068)
			(end 21.273516 -2.11201)
			(stroke
				(width 0.1)
				(type default)
			)
			(layer "F.SilkS")
		)
		(fp_line
			(start 21.299932 -2.195068)
			(end 21.273516 -2.11201)
			(stroke
				(width 0.1)
				(type default)
			)
			(layer "F.SilkS")
		)
		(fp_line
			(start 21.310346 -4.109466)
			(end 21.370544 -4.109466)
			(stroke
				(width 0.1)
				(type default)
			)
			(layer "F.SilkS")
		)
		(fp_line
			(start 21.310346 -4.109466)
			(end 21.370544 -4.109466)
			(stroke
				(width 0.1)
				(type default)
			)
			(layer "F.SilkS")
		)
		(fp_line
			(start 21.33473 -5.171694)
			(end 19.299428 -3.218942)
			(stroke
				(width 0.1)
				(type default)
			)
			(layer "F.SilkS")
		)
		(fp_line
			(start 21.33473 -5.171694)
			(end 19.299428 -3.218942)
			(stroke
				(width 0.1)
				(type default)
			)
			(layer "F.SilkS")
		)
		(fp_line
			(start 21.33473 -5.171694)
			(end 21.274532 -5.171694)
			(stroke
				(width 0.1)
				(type default)
			)
			(layer "F.SilkS")
		)
		(fp_line
			(start 21.33473 -5.171694)
			(end 21.274532 -5.171694)
			(stroke
				(width 0.1)
				(type default)
			)
			(layer "F.SilkS")
		)
		(fp_line
			(start 21.370544 -4.109466)
			(end 21.430742 -4.109466)
			(stroke
				(width 0.1)
				(type default)
			)
			(layer "F.SilkS")
		)
		(fp_line
			(start 21.370544 -4.109466)
			(end 21.430742 -4.109466)
			(stroke
				(width 0.1)
				(type default)
			)
			(layer "F.SilkS")
		)
		(fp_line
			(start 21.394674 -5.171694)
			(end 19.286982 -3.149854)
			(stroke
				(width 0.1)
				(type default)
			)
			(layer "F.SilkS")
		)
		(fp_line
			(start 21.394674 -5.171694)
			(end 19.286982 -3.149854)
			(stroke
				(width 0.1)
				(type default)
			)
			(layer "F.SilkS")
		)
		(fp_line
			(start 21.394674 -5.171694)
			(end 21.33473 -5.171694)
			(stroke
				(width 0.1)
				(type default)
			)
			(layer "F.SilkS")
		)
		(fp_line
			(start 21.394674 -5.171694)
			(end 21.33473 -5.171694)
			(stroke
				(width 0.1)
				(type default)
			)
			(layer "F.SilkS")
		)
		(fp_line
			(start 21.430742 -4.109466)
			(end 21.490686 -4.109466)
			(stroke
				(width 0.1)
				(type default)
			)
			(layer "F.SilkS")
		)
		(fp_line
			(start 21.430742 -4.109466)
			(end 21.490686 -4.109466)
			(stroke
				(width 0.1)
				(type default)
			)
			(layer "F.SilkS")
		)
		(fp_line
			(start 21.454872 -5.171694)
			(end 19.27479 -3.080512)
			(stroke
				(width 0.1)
				(type default)
			)
			(layer "F.SilkS")
		)
		(fp_line
			(start 21.454872 -5.171694)
			(end 19.27479 -3.080512)
			(stroke
				(width 0.1)
				(type default)
			)
			(layer "F.SilkS")
		)
		(fp_line
			(start 21.454872 -5.171694)
			(end 21.394674 -5.171694)
			(stroke
				(width 0.1)
				(type default)
			)
			(layer "F.SilkS")
		)
		(fp_line
			(start 21.454872 -5.171694)
			(end 21.394674 -5.171694)
			(stroke
				(width 0.1)
				(type default)
			)
			(layer "F.SilkS")
		)
		(fp_line
			(start 21.490686 -4.109466)
			(end 21.55063 -4.109466)
			(stroke
				(width 0.1)
				(type default)
			)
			(layer "F.SilkS")
		)
		(fp_line
			(start 21.490686 -4.109466)
			(end 21.55063 -4.109466)
			(stroke
				(width 0.1)
				(type default)
			)
			(layer "F.SilkS")
		)
		(fp_line
			(start 21.515324 -5.171694)
			(end 19.262852 -3.01117)
			(stroke
				(width 0.1)
				(type default)
			)
			(layer "F.SilkS")
		)
		(fp_line
			(start 21.515324 -5.171694)
			(end 19.262852 -3.01117)
			(stroke
				(width 0.1)
				(type default)
			)
			(layer "F.SilkS")
		)
		(fp_line
			(start 21.515324 -5.171694)
			(end 21.454872 -5.171694)
			(stroke
				(width 0.1)
				(type default)
			)
			(layer "F.SilkS")
		)
		(fp_line
			(start 21.515324 -5.171694)
			(end 21.454872 -5.171694)
			(stroke
				(width 0.1)
				(type default)
			)
			(layer "F.SilkS")
		)
		(fp_line
			(start 21.55063 -4.109466)
			(end 21.611082 -4.109466)
			(stroke
				(width 0.1)
				(type default)
			)
			(layer "F.SilkS")
		)
		(fp_line
			(start 21.55063 -4.109466)
			(end 21.611082 -4.109466)
			(stroke
				(width 0.1)
				(type default)
			)
			(layer "F.SilkS")
		)
		(fp_line
			(start 21.575522 -5.171694)
			(end 19.250406 -2.941574)
			(stroke
				(width 0.1)
				(type default)
			)
			(layer "F.SilkS")
		)
		(fp_line
			(start 21.575522 -5.171694)
			(end 19.250406 -2.941574)
			(stroke
				(width 0.1)
				(type default)
			)
			(layer "F.SilkS")
		)
		(fp_line
			(start 21.575522 -5.171694)
			(end 21.515324 -5.171694)
			(stroke
				(width 0.1)
				(type default)
			)
			(layer "F.SilkS")
		)
		(fp_line
			(start 21.575522 -5.171694)
			(end 21.515324 -5.171694)
			(stroke
				(width 0.1)
				(type default)
			)
			(layer "F.SilkS")
		)
		(fp_line
			(start 21.612352 -4.109466)
			(end 21.611082 -4.109466)
			(stroke
				(width 0.1)
				(type default)
			)
			(layer "F.SilkS")
		)
		(fp_line
			(start 21.612352 -4.109466)
			(end 21.611082 -4.109466)
			(stroke
				(width 0.1)
				(type default)
			)
			(layer "F.SilkS")
		)
		(fp_line
			(start 21.61286 -4.11099)
			(end 21.611082 -4.109466)
			(stroke
				(width 0.1)
				(type default)
			)
			(layer "F.SilkS")
		)
		(fp_line
			(start 21.61286 -4.11099)
			(end 21.611082 -4.109466)
			(stroke
				(width 0.1)
				(type default)
			)
			(layer "F.SilkS")
		)
		(fp_line
			(start 21.61286 -4.11099)
			(end 21.612352 -4.109466)
			(stroke
				(width 0.1)
				(type default)
			)
			(layer "F.SilkS")
		)
		(fp_line
			(start 21.61286 -4.11099)
			(end 21.612352 -4.109466)
			(stroke
				(width 0.1)
				(type default)
			)
			(layer "F.SilkS")
		)
		(fp_line
			(start 21.61286 -4.11099)
			(end 21.624798 -4.180586)
			(stroke
				(width 0.1)
				(type default)
			)
			(layer "F.SilkS")
		)
		(fp_line
			(start 21.61286 -4.11099)
			(end 21.624798 -4.180586)
			(stroke
				(width 0.1)
				(type default)
			)
			(layer "F.SilkS")
		)
		(fp_line
			(start 21.624798 -4.180586)
			(end 21.55063 -4.109466)
			(stroke
				(width 0.1)
				(type default)
			)
			(layer "F.SilkS")
		)
		(fp_line
			(start 21.624798 -4.180586)
			(end 21.55063 -4.109466)
			(stroke
				(width 0.1)
				(type default)
			)
			(layer "F.SilkS")
		)
		(fp_line
			(start 21.624798 -4.180586)
			(end 21.636736 -4.249674)
			(stroke
				(width 0.1)
				(type default)
			)
			(layer "F.SilkS")
		)
		(fp_line
			(start 21.624798 -4.180586)
			(end 21.636736 -4.249674)
			(stroke
				(width 0.1)
				(type default)
			)
			(layer "F.SilkS")
		)
		(fp_line
			(start 21.635466 -5.171694)
			(end 21.575522 -5.171694)
			(stroke
				(width 0.1)
				(type default)
			)
			(layer "F.SilkS")
		)
		(fp_line
			(start 21.635466 -5.171694)
			(end 21.575522 -5.171694)
			(stroke
				(width 0.1)
				(type default)
			)
			(layer "F.SilkS")
		)
		(fp_line
			(start 21.636736 -4.249674)
			(end 21.490686 -4.109466)
			(stroke
				(width 0.1)
				(type default)
			)
			(layer "F.SilkS")
		)
		(fp_line
			(start 21.636736 -4.249674)
			(end 21.490686 -4.109466)
			(stroke
				(width 0.1)
				(type default)
			)
			(layer "F.SilkS")
		)
		(fp_line
			(start 21.636736 -4.249674)
			(end 21.649182 -4.319016)
			(stroke
				(width 0.1)
				(type default)
			)
			(layer "F.SilkS")
		)
		(fp_line
			(start 21.636736 -4.249674)
			(end 21.649182 -4.319016)
			(stroke
				(width 0.1)
				(type default)
			)
			(layer "F.SilkS")
		)
		(fp_line
			(start 21.649182 -4.319016)
			(end 21.430742 -4.109466)
			(stroke
				(width 0.1)
				(type default)
			)
			(layer "F.SilkS")
		)
		(fp_line
			(start 21.649182 -4.319016)
			(end 21.430742 -4.109466)
			(stroke
				(width 0.1)
				(type default)
			)
			(layer "F.SilkS")
		)
		(fp_line
			(start 21.649182 -4.319016)
			(end 21.661374 -4.388358)
			(stroke
				(width 0.1)
				(type default)
			)
			(layer "F.SilkS")
		)
		(fp_line
			(start 21.649182 -4.319016)
			(end 21.661374 -4.388358)
			(stroke
				(width 0.1)
				(type default)
			)
			(layer "F.SilkS")
		)
		(fp_line
			(start 21.661374 -4.388358)
			(end 21.370544 -4.109466)
			(stroke
				(width 0.1)
				(type default)
			)
			(layer "F.SilkS")
		)
		(fp_line
			(start 21.661374 -4.388358)
			(end 21.370544 -4.109466)
			(stroke
				(width 0.1)
				(type default)
			)
			(layer "F.SilkS")
		)
		(fp_line
			(start 21.661374 -4.388358)
			(end 21.673312 -4.457954)
			(stroke
				(width 0.1)
				(type default)
			)
			(layer "F.SilkS")
		)
		(fp_line
			(start 21.661374 -4.388358)
			(end 21.673312 -4.457954)
			(stroke
				(width 0.1)
				(type default)
			)
			(layer "F.SilkS")
		)
		(fp_line
			(start 21.673312 -4.457954)
			(end 21.310346 -4.109466)
			(stroke
				(width 0.1)
				(type default)
			)
			(layer "F.SilkS")
		)
		(fp_line
			(start 21.673312 -4.457954)
			(end 21.310346 -4.109466)
			(stroke
				(width 0.1)
				(type default)
			)
			(layer "F.SilkS")
		)
		(fp_line
			(start 21.673312 -4.457954)
			(end 21.685504 -4.527296)
			(stroke
				(width 0.1)
				(type default)
			)
			(layer "F.SilkS")
		)
		(fp_line
			(start 21.673312 -4.457954)
			(end 21.685504 -4.527296)
			(stroke
				(width 0.1)
				(type default)
			)
			(layer "F.SilkS")
		)
		(fp_line
			(start 21.685504 -4.527296)
			(end 21.250402 -4.109466)
			(stroke
				(width 0.1)
				(type default)
			)
			(layer "F.SilkS")
		)
		(fp_line
			(start 21.685504 -4.527296)
			(end 21.250402 -4.109466)
			(stroke
				(width 0.1)
				(type default)
			)
			(layer "F.SilkS")
		)
		(fp_line
			(start 21.685504 -4.527296)
			(end 21.69795 -4.596638)
			(stroke
				(width 0.1)
				(type default)
			)
			(layer "F.SilkS")
		)
		(fp_line
			(start 21.685504 -4.527296)
			(end 21.69795 -4.596638)
			(stroke
				(width 0.1)
				(type default)
			)
			(layer "F.SilkS")
		)
		(fp_line
			(start 21.69541 -5.171694)
			(end 20.588224 -4.109466)
			(stroke
				(width 0.1)
				(type default)
			)
			(layer "F.SilkS")
		)
		(fp_line
			(start 21.69541 -5.171694)
			(end 20.588224 -4.109466)
			(stroke
				(width 0.1)
				(type default)
			)
			(layer "F.SilkS")
		)
		(fp_line
			(start 21.69541 -5.171694)
			(end 21.635466 -5.171694)
			(stroke
				(width 0.1)
				(type default)
			)
			(layer "F.SilkS")
		)
		(fp_line
			(start 21.69541 -5.171694)
			(end 21.635466 -5.171694)
			(stroke
				(width 0.1)
				(type default)
			)
			(layer "F.SilkS")
		)
		(fp_line
			(start 21.69795 -4.596638)
			(end 21.18995 -4.109466)
			(stroke
				(width 0.1)
				(type default)
			)
			(layer "F.SilkS")
		)
		(fp_line
			(start 21.69795 -4.596638)
			(end 21.18995 -4.109466)
			(stroke
				(width 0.1)
				(type default)
			)
			(layer "F.SilkS")
		)
		(fp_line
			(start 21.69795 -4.596638)
			(end 21.709888 -4.66598)
			(stroke
				(width 0.1)
				(type default)
			)
			(layer "F.SilkS")
		)
		(fp_line
			(start 21.69795 -4.596638)
			(end 21.709888 -4.66598)
			(stroke
				(width 0.1)
				(type default)
			)
			(layer "F.SilkS")
		)
		(fp_line
			(start 21.709888 -4.66598)
			(end 21.129752 -4.109466)
			(stroke
				(width 0.1)
				(type default)
			)
			(layer "F.SilkS")
		)
		(fp_line
			(start 21.709888 -4.66598)
			(end 21.129752 -4.109466)
			(stroke
				(width 0.1)
				(type default)
			)
			(layer "F.SilkS")
		)
		(fp_line
			(start 21.709888 -4.66598)
			(end 21.721826 -4.735576)
			(stroke
				(width 0.1)
				(type default)
			)
			(layer "F.SilkS")
		)
		(fp_line
			(start 21.709888 -4.66598)
			(end 21.721826 -4.735576)
			(stroke
				(width 0.1)
				(type default)
			)
			(layer "F.SilkS")
		)
		(fp_line
			(start 21.721826 -4.735576)
			(end 21.069554 -4.109466)
			(stroke
				(width 0.1)
				(type default)
			)
			(layer "F.SilkS")
		)
		(fp_line
			(start 21.721826 -4.735576)
			(end 21.069554 -4.109466)
			(stroke
				(width 0.1)
				(type default)
			)
			(layer "F.SilkS")
		)
		(fp_line
			(start 21.721826 -4.735576)
			(end 21.734018 -4.804664)
			(stroke
				(width 0.1)
				(type default)
			)
			(layer "F.SilkS")
		)
		(fp_line
			(start 21.721826 -4.735576)
			(end 21.734018 -4.804664)
			(stroke
				(width 0.1)
				(type default)
			)
			(layer "F.SilkS")
		)
		(fp_line
			(start 21.734018 -4.804664)
			(end 21.00961 -4.109466)
			(stroke
				(width 0.1)
				(type default)
			)
			(layer "F.SilkS")
		)
		(fp_line
			(start 21.734018 -4.804664)
			(end 21.00961 -4.109466)
			(stroke
				(width 0.1)
				(type default)
			)
			(layer "F.SilkS")
		)
		(fp_line
			(start 21.734018 -4.804664)
			(end 21.746464 -4.874006)
			(stroke
				(width 0.1)
				(type default)
			)
			(layer "F.SilkS")
		)
		(fp_line
			(start 21.734018 -4.804664)
			(end 21.746464 -4.874006)
			(stroke
				(width 0.1)
				(type default)
			)
			(layer "F.SilkS")
		)
		(fp_line
			(start 21.746464 -4.874006)
			(end 20.949666 -4.109466)
			(stroke
				(width 0.1)
				(type default)
			)
			(layer "F.SilkS")
		)
		(fp_line
			(start 21.746464 -4.874006)
			(end 20.949666 -4.109466)
			(stroke
				(width 0.1)
				(type default)
			)
			(layer "F.SilkS")
		)
		(fp_line
			(start 21.746464 -4.874006)
			(end 21.758402 -4.943348)
			(stroke
				(width 0.1)
				(type default)
			)
			(layer "F.SilkS")
		)
		(fp_line
			(start 21.746464 -4.874006)
			(end 21.758402 -4.943348)
			(stroke
				(width 0.1)
				(type default)
			)
			(layer "F.SilkS")
		)
		(fp_line
			(start 21.755608 -5.171694)
			(end 20.648422 -4.109466)
			(stroke
				(width 0.1)
				(type default)
			)
			(layer "F.SilkS")
		)
		(fp_line
			(start 21.755608 -5.171694)
			(end 20.648422 -4.109466)
			(stroke
				(width 0.1)
				(type default)
			)
			(layer "F.SilkS")
		)
		(fp_line
			(start 21.755608 -5.171694)
			(end 21.69541 -5.171694)
			(stroke
				(width 0.1)
				(type default)
			)
			(layer "F.SilkS")
		)
		(fp_line
			(start 21.755608 -5.171694)
			(end 21.69541 -5.171694)
			(stroke
				(width 0.1)
				(type default)
			)
			(layer "F.SilkS")
		)
		(fp_line
			(start 21.758402 -4.943348)
			(end 20.889214 -4.109466)
			(stroke
				(width 0.1)
				(type default)
			)
			(layer "F.SilkS")
		)
		(fp_line
			(start 21.758402 -4.943348)
			(end 20.889214 -4.109466)
			(stroke
				(width 0.1)
				(type default)
			)
			(layer "F.SilkS")
		)
		(fp_line
			(start 21.758402 -4.943348)
			(end 21.770594 -5.012944)
			(stroke
				(width 0.1)
				(type default)
			)
			(layer "F.SilkS")
		)
		(fp_line
			(start 21.758402 -4.943348)
			(end 21.770594 -5.012944)
			(stroke
				(width 0.1)
				(type default)
			)
			(layer "F.SilkS")
		)
		(fp_line
			(start 21.770594 -5.012944)
			(end 20.829016 -4.109466)
			(stroke
				(width 0.1)
				(type default)
			)
			(layer "F.SilkS")
		)
		(fp_line
			(start 21.770594 -5.012944)
			(end 20.829016 -4.109466)
			(stroke
				(width 0.1)
				(type default)
			)
			(layer "F.SilkS")
		)
		(fp_line
			(start 21.770594 -5.012944)
			(end 21.78304 -5.082032)
			(stroke
				(width 0.1)
				(type default)
			)
			(layer "F.SilkS")
		)
		(fp_line
			(start 21.770594 -5.012944)
			(end 21.78304 -5.082032)
			(stroke
				(width 0.1)
				(type default)
			)
			(layer "F.SilkS")
		)
		(fp_line
			(start 21.78304 -5.082032)
			(end 20.768564 -4.109466)
			(stroke
				(width 0.1)
				(type default)
			)
			(layer "F.SilkS")
		)
		(fp_line
			(start 21.78304 -5.082032)
			(end 20.768564 -4.109466)
			(stroke
				(width 0.1)
				(type default)
			)
			(layer "F.SilkS")
		)
		(fp_line
			(start 21.78304 -5.082032)
			(end 21.794978 -5.151374)
			(stroke
				(width 0.1)
				(type default)
			)
			(layer "F.SilkS")
		)
		(fp_line
			(start 21.78304 -5.082032)
			(end 21.794978 -5.151374)
			(stroke
				(width 0.1)
				(type default)
			)
			(layer "F.SilkS")
		)
		(fp_line
			(start 21.794978 -5.151374)
			(end 20.70862 -4.109466)
			(stroke
				(width 0.1)
				(type default)
			)
			(layer "F.SilkS")
		)
		(fp_line
			(start 21.794978 -5.151374)
			(end 20.70862 -4.109466)
			(stroke
				(width 0.1)
				(type default)
			)
			(layer "F.SilkS")
		)
		(fp_line
			(start 21.794978 -5.151374)
			(end 21.798534 -5.171694)
			(stroke
				(width 0.1)
				(type default)
			)
			(layer "F.SilkS")
		)
		(fp_line
			(start 21.794978 -5.151374)
			(end 21.798534 -5.171694)
			(stroke
				(width 0.1)
				(type default)
			)
			(layer "F.SilkS")
		)
		(fp_line
			(start 21.798534 -5.171694)
			(end 21.755608 -5.171694)
			(stroke
				(width 0.1)
				(type default)
			)
			(layer "F.SilkS")
		)
		(fp_line
			(start 21.798534 -5.171694)
			(end 21.755608 -5.171694)
			(stroke
				(width 0.1)
				(type default)
			)
			(layer "F.SilkS")
		)
		(fp_line
			(start 21.838158 -2.018792)
			(end 23.619206 -3.727196)
			(stroke
				(width 0.1)
				(type default)
			)
			(layer "F.SilkS")
		)
		(fp_line
			(start 21.838158 -2.018792)
			(end 23.619206 -3.727196)
			(stroke
				(width 0.1)
				(type default)
			)
			(layer "F.SilkS")
		)
		(fp_line
			(start 21.839428 -2.07772)
			(end 23.55469 -3.723386)
			(stroke
				(width 0.1)
				(type default)
			)
			(layer "F.SilkS")
		)
		(fp_line
			(start 21.839428 -2.07772)
			(end 23.55469 -3.723386)
			(stroke
				(width 0.1)
				(type default)
			)
			(layer "F.SilkS")
		)
		(fp_line
			(start 21.841206 -2.137156)
			(end 23.489666 -3.71856)
			(stroke
				(width 0.1)
				(type default)
			)
			(layer "F.SilkS")
		)
		(fp_line
			(start 21.841206 -2.137156)
			(end 23.489666 -3.71856)
			(stroke
				(width 0.1)
				(type default)
			)
			(layer "F.SilkS")
		)
		(fp_line
			(start 21.841206 -1.90627)
			(end 23.747984 -3.735324)
			(stroke
				(width 0.1)
				(type default)
			)
			(layer "F.SilkS")
		)
		(fp_line
			(start 21.841206 -1.90627)
			(end 23.747984 -3.735324)
			(stroke
				(width 0.1)
				(type default)
			)
			(layer "F.SilkS")
		)
		(fp_line
			(start 21.846032 -1.853184)
			(end 23.811992 -3.739388)
			(stroke
				(width 0.1)
				(type default)
			)
			(layer "F.SilkS")
		)
		(fp_line
			(start 21.846032 -1.853184)
			(end 23.811992 -3.739388)
			(stroke
				(width 0.1)
				(type default)
			)
			(layer "F.SilkS")
		)
		(fp_line
			(start 21.849334 -2.202942)
			(end 23.414228 -3.703828)
			(stroke
				(width 0.1)
				(type default)
			)
			(layer "F.SilkS")
		)
		(fp_line
			(start 21.849334 -2.202942)
			(end 23.414228 -3.703828)
			(stroke
				(width 0.1)
				(type default)
			)
			(layer "F.SilkS")
		)
		(fp_line
			(start 21.850858 -1.799844)
			(end 23.874222 -3.740912)
			(stroke
				(width 0.1)
				(type default)
			)
			(layer "F.SilkS")
		)
		(fp_line
			(start 21.850858 -1.799844)
			(end 23.874222 -3.740912)
			(stroke
				(width 0.1)
				(type default)
			)
			(layer "F.SilkS")
		)
		(fp_line
			(start 21.85797 -2.268728)
			(end 23.338282 -3.688842)
			(stroke
				(width 0.1)
				(type default)
			)
			(layer "F.SilkS")
		)
		(fp_line
			(start 21.85797 -2.268728)
			(end 23.338282 -3.688842)
			(stroke
				(width 0.1)
				(type default)
			)
			(layer "F.SilkS")
		)
		(fp_line
			(start 21.86051 -1.75133)
			(end 23.930864 -3.737864)
			(stroke
				(width 0.1)
				(type default)
			)
			(layer "F.SilkS")
		)
		(fp_line
			(start 21.86051 -1.75133)
			(end 23.930864 -3.737864)
			(stroke
				(width 0.1)
				(type default)
			)
			(layer "F.SilkS")
		)
		(fp_line
			(start 21.869146 -2.337308)
			(end 23.26259 -3.673856)
			(stroke
				(width 0.1)
				(type default)
			)
			(layer "F.SilkS")
		)
		(fp_line
			(start 21.869146 -2.337308)
			(end 23.26259 -3.673856)
			(stroke
				(width 0.1)
				(type default)
			)
			(layer "F.SilkS")
		)
		(fp_line
			(start 21.870416 -1.703578)
			(end 23.98776 -3.734816)
			(stroke
				(width 0.1)
				(type default)
			)
			(layer "F.SilkS")
		)
		(fp_line
			(start 21.870416 -1.703578)
			(end 23.98776 -3.734816)
			(stroke
				(width 0.1)
				(type default)
			)
			(layer "F.SilkS")
		)
		(fp_line
			(start 21.88083 -1.655826)
			(end 24.04491 -3.731768)
			(stroke
				(width 0.1)
				(type default)
			)
			(layer "F.SilkS")
		)
		(fp_line
			(start 21.88083 -1.655826)
			(end 24.04491 -3.731768)
			(stroke
				(width 0.1)
				(type default)
			)
			(layer "F.SilkS")
		)
		(fp_line
			(start 21.89099 -2.416048)
			(end 23.187152 -3.659124)
			(stroke
				(width 0.1)
				(type default)
			)
			(layer "F.SilkS")
		)
		(fp_line
			(start 21.89099 -2.416048)
			(end 23.187152 -3.659124)
			(stroke
				(width 0.1)
				(type default)
			)
			(layer "F.SilkS")
		)
		(fp_line
			(start 21.894546 -1.611376)
			(end 24.101806 -3.728974)
			(stroke
				(width 0.1)
				(type default)
			)
			(layer "F.SilkS")
		)
		(fp_line
			(start 21.894546 -1.611376)
			(end 24.101806 -3.728974)
			(stroke
				(width 0.1)
				(type default)
			)
			(layer "F.SilkS")
		)
		(fp_line
			(start 21.909786 -1.568196)
			(end 24.154892 -3.721862)
			(stroke
				(width 0.1)
				(type default)
			)
			(layer "F.SilkS")
		)
		(fp_line
			(start 21.909786 -1.568196)
			(end 24.154892 -3.721862)
			(stroke
				(width 0.1)
				(type default)
			)
			(layer "F.SilkS")
		)
		(fp_line
			(start 21.913088 -2.494788)
			(end 23.10003 -3.63347)
			(stroke
				(width 0.1)
				(type default)
			)
			(layer "F.SilkS")
		)
		(fp_line
			(start 21.913088 -2.494788)
			(end 23.10003 -3.63347)
			(stroke
				(width 0.1)
				(type default)
			)
			(layer "F.SilkS")
		)
		(fp_line
			(start 21.924772 -1.525016)
			(end 24.205946 -3.712972)
			(stroke
				(width 0.1)
				(type default)
			)
			(layer "F.SilkS")
		)
		(fp_line
			(start 21.924772 -1.525016)
			(end 24.205946 -3.712972)
			(stroke
				(width 0.1)
				(type default)
			)
			(layer "F.SilkS")
		)
		(fp_line
			(start 21.93544 -2.573782)
			(end 23.00478 -3.599942)
			(stroke
				(width 0.1)
				(type default)
			)
			(layer "F.SilkS")
		)
		(fp_line
			(start 21.93544 -2.573782)
			(end 23.00478 -3.599942)
			(stroke
				(width 0.1)
				(type default)
			)
			(layer "F.SilkS")
		)
		(fp_line
			(start 21.942806 -1.484376)
			(end 23.220934 -2.710688)
			(stroke
				(width 0.1)
				(type default)
			)
			(layer "F.SilkS")
		)
		(fp_line
			(start 21.942806 -1.484376)
			(end 23.220934 -2.710688)
			(stroke
				(width 0.1)
				(type default)
			)
			(layer "F.SilkS")
		)
		(fp_line
			(start 21.957538 -2.652776)
			(end 22.909784 -3.56616)
			(stroke
				(width 0.1)
				(type default)
			)
			(layer "F.SilkS")
		)
		(fp_line
			(start 21.957538 -2.652776)
			(end 22.909784 -3.56616)
			(stroke
				(width 0.1)
				(type default)
			)
			(layer "F.SilkS")
		)
		(fp_line
			(start 21.962364 -1.445514)
			(end 23.052786 -2.491486)
			(stroke
				(width 0.1)
				(type default)
			)
			(layer "F.SilkS")
		)
		(fp_line
			(start 21.962364 -1.445514)
			(end 23.052786 -2.491486)
			(stroke
				(width 0.1)
				(type default)
			)
			(layer "F.SilkS")
		)
		(fp_line
			(start 21.981922 -1.406652)
			(end 23.020782 -2.403094)
			(stroke
				(width 0.1)
				(type default)
			)
			(layer "F.SilkS")
		)
		(fp_line
			(start 21.981922 -1.406652)
			(end 23.020782 -2.403094)
			(stroke
				(width 0.1)
				(type default)
			)
			(layer "F.SilkS")
		)
		(fp_line
			(start 22.003004 -1.36906)
			(end 22.99081 -2.31648)
			(stroke
				(width 0.1)
				(type default)
			)
			(layer "F.SilkS")
		)
		(fp_line
			(start 22.003004 -1.36906)
			(end 22.99081 -2.31648)
			(stroke
				(width 0.1)
				(type default)
			)
			(layer "F.SilkS")
		)
		(fp_line
			(start 22.017228 -2.767838)
			(end 22.802342 -3.521202)
			(stroke
				(width 0.1)
				(type default)
			)
			(layer "F.SilkS")
		)
		(fp_line
			(start 22.017228 -2.767838)
			(end 22.802342 -3.521202)
			(stroke
				(width 0.1)
				(type default)
			)
			(layer "F.SilkS")
		)
		(fp_line
			(start 22.02688 -1.334262)
			(end 22.984206 -2.252726)
			(stroke
				(width 0.1)
				(type default)
			)
			(layer "F.SilkS")
		)
		(fp_line
			(start 22.02688 -1.334262)
			(end 22.984206 -2.252726)
			(stroke
				(width 0.1)
				(type default)
			)
			(layer "F.SilkS")
		)
		(fp_line
			(start 22.05101 -1.299464)
			(end 22.981158 -2.19202)
			(stroke
				(width 0.1)
				(type default)
			)
			(layer "F.SilkS")
		)
		(fp_line
			(start 22.05101 -1.299464)
			(end 22.981158 -2.19202)
			(stroke
				(width 0.1)
				(type default)
			)
			(layer "F.SilkS")
		)
		(fp_line
			(start 22.07514 -1.265174)
			(end 22.985222 -2.137918)
			(stroke
				(width 0.1)
				(type default)
			)
			(layer "F.SilkS")
		)
		(fp_line
			(start 22.07514 -1.265174)
			(end 22.985222 -2.137918)
			(stroke
				(width 0.1)
				(type default)
			)
			(layer "F.SilkS")
		)
		(fp_line
			(start 22.077934 -2.883408)
			(end 22.662896 -3.444748)
			(stroke
				(width 0.1)
				(type default)
			)
			(layer "F.SilkS")
		)
		(fp_line
			(start 22.077934 -2.883408)
			(end 22.662896 -3.444748)
			(stroke
				(width 0.1)
				(type default)
			)
			(layer "F.SilkS")
		)
		(fp_line
			(start 22.10308 -1.233932)
			(end 22.992588 -2.087372)
			(stroke
				(width 0.1)
				(type default)
			)
			(layer "F.SilkS")
		)
		(fp_line
			(start 22.10308 -1.233932)
			(end 22.992588 -2.087372)
			(stroke
				(width 0.1)
				(type default)
			)
			(layer "F.SilkS")
		)
		(fp_line
			(start 22.130512 -1.202944)
			(end 23.005542 -2.042414)
			(stroke
				(width 0.1)
				(type default)
			)
			(layer "F.SilkS")
		)
		(fp_line
			(start 22.130512 -1.202944)
			(end 23.005542 -2.042414)
			(stroke
				(width 0.1)
				(type default)
			)
			(layer "F.SilkS")
		)
		(fp_line
			(start 22.158452 -1.171956)
			(end 23.020782 -1.99898)
			(stroke
				(width 0.1)
				(type default)
			)
			(layer "F.SilkS")
		)
		(fp_line
			(start 22.158452 -1.171956)
			(end 23.020782 -1.99898)
			(stroke
				(width 0.1)
				(type default)
			)
			(layer "F.SilkS")
		)
		(fp_line
			(start 22.18944 -1.143762)
			(end 23.042372 -1.96215)
			(stroke
				(width 0.1)
				(type default)
			)
			(layer "F.SilkS")
		)
		(fp_line
			(start 22.18944 -1.143762)
			(end 23.042372 -1.96215)
			(stroke
				(width 0.1)
				(type default)
			)
			(layer "F.SilkS")
		)
		(fp_line
			(start 22.22119 -1.11633)
			(end 23.06447 -1.925828)
			(stroke
				(width 0.1)
				(type default)
			)
			(layer "F.SilkS")
		)
		(fp_line
			(start 22.22119 -1.11633)
			(end 23.06447 -1.925828)
			(stroke
				(width 0.1)
				(type default)
			)
			(layer "F.SilkS")
		)
		(fp_line
			(start 22.252432 -1.089152)
			(end 23.094188 -1.896364)
			(stroke
				(width 0.1)
				(type default)
			)
			(layer "F.SilkS")
		)
		(fp_line
			(start 22.252432 -1.089152)
			(end 23.094188 -1.896364)
			(stroke
				(width 0.1)
				(type default)
			)
			(layer "F.SilkS")
		)
		(fp_line
			(start 22.286214 -1.063752)
			(end 23.124414 -1.867916)
			(stroke
				(width 0.1)
				(type default)
			)
			(layer "F.SilkS")
		)
		(fp_line
			(start 22.286214 -1.063752)
			(end 23.124414 -1.867916)
			(stroke
				(width 0.1)
				(type default)
			)
			(layer "F.SilkS")
		)
		(fp_line
			(start 22.321774 -1.039622)
			(end 23.158196 -1.842262)
			(stroke
				(width 0.1)
				(type default)
			)
			(layer "F.SilkS")
		)
		(fp_line
			(start 22.321774 -1.039622)
			(end 23.158196 -1.842262)
			(stroke
				(width 0.1)
				(type default)
			)
			(layer "F.SilkS")
		)
		(fp_line
			(start 22.356572 -1.015746)
			(end 23.197058 -1.821942)
			(stroke
				(width 0.1)
				(type default)
			)
			(layer "F.SilkS")
		)
		(fp_line
			(start 22.356572 -1.015746)
			(end 23.197058 -1.821942)
			(stroke
				(width 0.1)
				(type default)
			)
			(layer "F.SilkS")
		)
		(fp_line
			(start 22.393402 -0.993394)
			(end 23.235666 -1.801622)
			(stroke
				(width 0.1)
				(type default)
			)
			(layer "F.SilkS")
		)
		(fp_line
			(start 22.393402 -0.993394)
			(end 23.235666 -1.801622)
			(stroke
				(width 0.1)
				(type default)
			)
			(layer "F.SilkS")
		)
		(fp_line
			(start 22.43201 -0.97282)
			(end 23.280878 -1.786636)
			(stroke
				(width 0.1)
				(type default)
			)
			(layer "F.SilkS")
		)
		(fp_line
			(start 22.43201 -0.97282)
			(end 23.280878 -1.786636)
			(stroke
				(width 0.1)
				(type default)
			)
			(layer "F.SilkS")
		)
		(fp_line
			(start 22.470872 -0.952246)
			(end 23.328122 -1.774444)
			(stroke
				(width 0.1)
				(type default)
			)
			(layer "F.SilkS")
		)
		(fp_line
			(start 22.470872 -0.952246)
			(end 23.328122 -1.774444)
			(stroke
				(width 0.1)
				(type default)
			)
			(layer "F.SilkS")
		)
		(fp_line
			(start 22.510496 -0.932688)
			(end 23.375366 -1.761998)
			(stroke
				(width 0.1)
				(type default)
			)
			(layer "F.SilkS")
		)
		(fp_line
			(start 22.510496 -0.932688)
			(end 23.375366 -1.761998)
			(stroke
				(width 0.1)
				(type default)
			)
			(layer "F.SilkS")
		)
		(fp_line
			(start 22.552914 -0.91567)
			(end 23.430484 -1.757172)
			(stroke
				(width 0.1)
				(type default)
			)
			(layer "F.SilkS")
		)
		(fp_line
			(start 22.552914 -0.91567)
			(end 23.430484 -1.757172)
			(stroke
				(width 0.1)
				(type default)
			)
			(layer "F.SilkS")
		)
		(fp_line
			(start 22.595332 -0.898398)
			(end 23.48611 -1.752854)
			(stroke
				(width 0.1)
				(type default)
			)
			(layer "F.SilkS")
		)
		(fp_line
			(start 22.595332 -0.898398)
			(end 23.48611 -1.752854)
			(stroke
				(width 0.1)
				(type default)
			)
			(layer "F.SilkS")
		)
		(fp_line
			(start 22.638258 -0.881888)
			(end 23.54199 -1.74879)
			(stroke
				(width 0.1)
				(type default)
			)
			(layer "F.SilkS")
		)
		(fp_line
			(start 22.638258 -0.881888)
			(end 23.54199 -1.74879)
			(stroke
				(width 0.1)
				(type default)
			)
			(layer "F.SilkS")
		)
		(fp_line
			(start 22.651212 -4.81838)
			(end 22.66696 -4.776216)
			(stroke
				(width 0.1)
				(type default)
			)
			(layer "F.SilkS")
		)
		(fp_line
			(start 22.651212 -4.81838)
			(end 22.66696 -4.776216)
			(stroke
				(width 0.1)
				(type default)
			)
			(layer "F.SilkS")
		)
		(fp_line
			(start 22.651212 -4.81838)
			(end 22.676358 -4.842764)
			(stroke
				(width 0.1)
				(type default)
			)
			(layer "F.SilkS")
		)
		(fp_line
			(start 22.651212 -4.81838)
			(end 22.676358 -4.842764)
			(stroke
				(width 0.1)
				(type default)
			)
			(layer "F.SilkS")
		)
		(fp_line
			(start 22.66696 -4.776216)
			(end 22.682708 -4.733798)
			(stroke
				(width 0.1)
				(type default)
			)
			(layer "F.SilkS")
		)
		(fp_line
			(start 22.66696 -4.776216)
			(end 22.682708 -4.733798)
			(stroke
				(width 0.1)
				(type default)
			)
			(layer "F.SilkS")
		)
		(fp_line
			(start 22.66696 -4.776216)
			(end 22.802088 -4.905756)
			(stroke
				(width 0.1)
				(type default)
			)
			(layer "F.SilkS")
		)
		(fp_line
			(start 22.66696 -4.776216)
			(end 22.802088 -4.905756)
			(stroke
				(width 0.1)
				(type default)
			)
			(layer "F.SilkS")
		)
		(fp_line
			(start 22.682708 -4.733798)
			(end 22.698964 -4.69138)
			(stroke
				(width 0.1)
				(type default)
			)
			(layer "F.SilkS")
		)
		(fp_line
			(start 22.682708 -4.733798)
			(end 22.698964 -4.69138)
			(stroke
				(width 0.1)
				(type default)
			)
			(layer "F.SilkS")
		)
		(fp_line
			(start 22.682708 -4.733798)
			(end 22.919436 -4.960874)
			(stroke
				(width 0.1)
				(type default)
			)
			(layer "F.SilkS")
		)
		(fp_line
			(start 22.682708 -4.733798)
			(end 22.919436 -4.960874)
			(stroke
				(width 0.1)
				(type default)
			)
			(layer "F.SilkS")
		)
		(fp_line
			(start 22.684232 -0.868172)
			(end 23.610316 -1.756664)
			(stroke
				(width 0.1)
				(type default)
			)
			(layer "F.SilkS")
		)
		(fp_line
			(start 22.684232 -0.868172)
			(end 23.610316 -1.756664)
			(stroke
				(width 0.1)
				(type default)
			)
			(layer "F.SilkS")
		)
		(fp_line
			(start 22.698964 -4.69138)
			(end 22.714712 -4.648962)
			(stroke
				(width 0.1)
				(type default)
			)
			(layer "F.SilkS")
		)
		(fp_line
			(start 22.698964 -4.69138)
			(end 22.714712 -4.648962)
			(stroke
				(width 0.1)
				(type default)
			)
			(layer "F.SilkS")
		)
		(fp_line
			(start 22.698964 -4.69138)
			(end 23.03272 -5.01142)
			(stroke
				(width 0.1)
				(type default)
			)
			(layer "F.SilkS")
		)
		(fp_line
			(start 22.698964 -4.69138)
			(end 23.03272 -5.01142)
			(stroke
				(width 0.1)
				(type default)
			)
			(layer "F.SilkS")
		)
		(fp_line
			(start 22.714712 -4.648962)
			(end 22.730714 -4.606544)
			(stroke
				(width 0.1)
				(type default)
			)
			(layer "F.SilkS")
		)
		(fp_line
			(start 22.714712 -4.648962)
			(end 22.730714 -4.606544)
			(stroke
				(width 0.1)
				(type default)
			)
			(layer "F.SilkS")
		)
		(fp_line
			(start 22.714712 -4.648962)
			(end 23.13432 -5.051298)
			(stroke
				(width 0.1)
				(type default)
			)
			(layer "F.SilkS")
		)
		(fp_line
			(start 22.714712 -4.648962)
			(end 23.13432 -5.051298)
			(stroke
				(width 0.1)
				(type default)
			)
			(layer "F.SilkS")
		)
		(fp_line
			(start 22.729952 -0.85471)
			(end 23.67915 -1.765046)
			(stroke
				(width 0.1)
				(type default)
			)
			(layer "F.SilkS")
		)
		(fp_line
			(start 22.729952 -0.85471)
			(end 23.67915 -1.765046)
			(stroke
				(width 0.1)
				(type default)
			)
			(layer "F.SilkS")
		)
		(fp_line
			(start 22.730714 -4.606544)
			(end 22.74697 -4.564126)
			(stroke
				(width 0.1)
				(type default)
			)
			(layer "F.SilkS")
		)
		(fp_line
			(start 22.730714 -4.606544)
			(end 22.74697 -4.564126)
			(stroke
				(width 0.1)
				(type default)
			)
			(layer "F.SilkS")
		)
		(fp_line
			(start 22.730714 -4.606544)
			(end 23.234396 -5.089652)
			(stroke
				(width 0.1)
				(type default)
			)
			(layer "F.SilkS")
		)
		(fp_line
			(start 22.730714 -4.606544)
			(end 23.234396 -5.089652)
			(stroke
				(width 0.1)
				(type default)
			)
			(layer "F.SilkS")
		)
		(fp_line
			(start 22.74697 -4.564126)
			(end 22.762718 -4.521708)
			(stroke
				(width 0.1)
				(type default)
			)
			(layer "F.SilkS")
		)
		(fp_line
			(start 22.74697 -4.564126)
			(end 22.762718 -4.521708)
			(stroke
				(width 0.1)
				(type default)
			)
			(layer "F.SilkS")
		)
		(fp_line
			(start 22.74697 -4.564126)
			(end 23.32355 -5.117592)
			(stroke
				(width 0.1)
				(type default)
			)
			(layer "F.SilkS")
		)
		(fp_line
			(start 22.74697 -4.564126)
			(end 23.32355 -5.117592)
			(stroke
				(width 0.1)
				(type default)
			)
			(layer "F.SilkS")
		)
		(fp_line
			(start 22.762718 -4.521708)
			(end 22.778466 -4.47929)
			(stroke
				(width 0.1)
				(type default)
			)
			(layer "F.SilkS")
		)
		(fp_line
			(start 22.762718 -4.521708)
			(end 22.778466 -4.47929)
			(stroke
				(width 0.1)
				(type default)
			)
			(layer "F.SilkS")
		)
		(fp_line
			(start 22.762718 -4.521708)
			(end 23.412704 -5.145278)
			(stroke
				(width 0.1)
				(type default)
			)
			(layer "F.SilkS")
		)
		(fp_line
			(start 22.762718 -4.521708)
			(end 23.412704 -5.145278)
			(stroke
				(width 0.1)
				(type default)
			)
			(layer "F.SilkS")
		)
		(fp_line
			(start 22.777196 -0.841756)
			(end 23.748238 -1.773682)
			(stroke
				(width 0.1)
				(type default)
			)
			(layer "F.SilkS")
		)
		(fp_line
			(start 22.777196 -0.841756)
			(end 23.748238 -1.773682)
			(stroke
				(width 0.1)
				(type default)
			)
			(layer "F.SilkS")
		)
		(fp_line
			(start 22.778466 -4.47929)
			(end 22.794722 -4.436872)
			(stroke
				(width 0.1)
				(type default)
			)
			(layer "F.SilkS")
		)
		(fp_line
			(start 22.778466 -4.47929)
			(end 22.794722 -4.436872)
			(stroke
				(width 0.1)
				(type default)
			)
			(layer "F.SilkS")
		)
		(fp_line
			(start 22.778466 -4.47929)
			(end 23.494746 -5.166106)
			(stroke
				(width 0.1)
				(type default)
			)
			(layer "F.SilkS")
		)
		(fp_line
			(start 22.778466 -4.47929)
			(end 23.494746 -5.166106)
			(stroke
				(width 0.1)
				(type default)
			)
			(layer "F.SilkS")
		)
		(fp_line
			(start 22.794722 -4.436872)
			(end 22.81047 -4.394708)
			(stroke
				(width 0.1)
				(type default)
			)
			(layer "F.SilkS")
		)
		(fp_line
			(start 22.794722 -4.436872)
			(end 22.81047 -4.394708)
			(stroke
				(width 0.1)
				(type default)
			)
			(layer "F.SilkS")
		)
		(fp_line
			(start 22.794722 -4.436872)
			(end 23.573994 -5.184648)
			(stroke
				(width 0.1)
				(type default)
			)
			(layer "F.SilkS")
		)
		(fp_line
			(start 22.794722 -4.436872)
			(end 23.573994 -5.184648)
			(stroke
				(width 0.1)
				(type default)
			)
			(layer "F.SilkS")
		)
		(fp_line
			(start 22.81047 -4.394708)
			(end 22.826472 -4.352036)
			(stroke
				(width 0.1)
				(type default)
			)
			(layer "F.SilkS")
		)
		(fp_line
			(start 22.81047 -4.394708)
			(end 22.826472 -4.352036)
			(stroke
				(width 0.1)
				(type default)
			)
			(layer "F.SilkS")
		)
		(fp_line
			(start 22.81047 -4.394708)
			(end 23.652226 -5.20192)
			(stroke
				(width 0.1)
				(type default)
			)
			(layer "F.SilkS")
		)
		(fp_line
			(start 22.81047 -4.394708)
			(end 23.652226 -5.20192)
			(stroke
				(width 0.1)
				(type default)
			)
			(layer "F.SilkS")
		)
		(fp_line
			(start 22.826472 -4.352036)
			(end 22.842728 -4.309618)
			(stroke
				(width 0.1)
				(type default)
			)
			(layer "F.SilkS")
		)
		(fp_line
			(start 22.826472 -4.352036)
			(end 22.842728 -4.309618)
			(stroke
				(width 0.1)
				(type default)
			)
			(layer "F.SilkS")
		)
		(fp_line
			(start 22.826472 -4.352036)
			(end 23.724616 -5.21335)
			(stroke
				(width 0.1)
				(type default)
			)
			(layer "F.SilkS")
		)
		(fp_line
			(start 22.826472 -4.352036)
			(end 23.724616 -5.21335)
			(stroke
				(width 0.1)
				(type default)
			)
			(layer "F.SilkS")
		)
		(fp_line
			(start 22.826726 -0.831596)
			(end 23.82012 -1.78435)
			(stroke
				(width 0.1)
				(type default)
			)
			(layer "F.SilkS")
		)
		(fp_line
			(start 22.826726 -0.831596)
			(end 23.82012 -1.78435)
			(stroke
				(width 0.1)
				(type default)
			)
			(layer "F.SilkS")
		)
		(fp_line
			(start 22.842728 -4.309618)
			(end 22.858476 -4.267454)
			(stroke
				(width 0.1)
				(type default)
			)
			(layer "F.SilkS")
		)
		(fp_line
			(start 22.842728 -4.309618)
			(end 22.858476 -4.267454)
			(stroke
				(width 0.1)
				(type default)
			)
			(layer "F.SilkS")
		)
		(fp_line
			(start 22.842728 -4.309618)
			(end 23.796498 -5.22478)
			(stroke
				(width 0.1)
				(type default)
			)
			(layer "F.SilkS")
		)
		(fp_line
			(start 22.842728 -4.309618)
			(end 23.796498 -5.22478)
			(stroke
				(width 0.1)
				(type default)
			)
			(layer "F.SilkS")
		)
		(fp_line
			(start 22.858476 -4.267454)
			(end 22.874224 -4.225036)
			(stroke
				(width 0.1)
				(type default)
			)
			(layer "F.SilkS")
		)
		(fp_line
			(start 22.858476 -4.267454)
			(end 22.874224 -4.225036)
			(stroke
				(width 0.1)
				(type default)
			)
			(layer "F.SilkS")
		)
		(fp_line
			(start 22.858476 -4.267454)
			(end 23.86711 -5.235194)
			(stroke
				(width 0.1)
				(type default)
			)
			(layer "F.SilkS")
		)
		(fp_line
			(start 22.858476 -4.267454)
			(end 23.86711 -5.235194)
			(stroke
				(width 0.1)
				(type default)
			)
			(layer "F.SilkS")
		)
		(fp_line
			(start 22.874224 -4.225036)
			(end 22.89048 -4.182618)
			(stroke
				(width 0.1)
				(type default)
			)
			(layer "F.SilkS")
		)
		(fp_line
			(start 22.874224 -4.225036)
			(end 22.89048 -4.182618)
			(stroke
				(width 0.1)
				(type default)
			)
			(layer "F.SilkS")
		)
		(fp_line
			(start 22.874224 -4.225036)
			(end 23.933658 -5.241036)
			(stroke
				(width 0.1)
				(type default)
			)
			(layer "F.SilkS")
		)
		(fp_line
			(start 22.874224 -4.225036)
			(end 23.933658 -5.241036)
			(stroke
				(width 0.1)
				(type default)
			)
			(layer "F.SilkS")
		)
		(fp_line
			(start 22.87651 -0.821436)
			(end 23.916894 -1.819656)
			(stroke
				(width 0.1)
				(type default)
			)
			(layer "F.SilkS")
		)
		(fp_line
			(start 22.87651 -0.821436)
			(end 23.916894 -1.819656)
			(stroke
				(width 0.1)
				(type default)
			)
			(layer "F.SilkS")
		)
		(fp_line
			(start 22.89048 -4.182618)
			(end 22.906482 -4.139946)
			(stroke
				(width 0.1)
				(type default)
			)
			(layer "F.SilkS")
		)
		(fp_line
			(start 22.89048 -4.182618)
			(end 22.906482 -4.139946)
			(stroke
				(width 0.1)
				(type default)
			)
			(layer "F.SilkS")
		)
		(fp_line
			(start 22.89048 -4.182618)
			(end 24.000206 -5.246878)
			(stroke
				(width 0.1)
				(type default)
			)
			(layer "F.SilkS")
		)
		(fp_line
			(start 22.89048 -4.182618)
			(end 24.000206 -5.246878)
			(stroke
				(width 0.1)
				(type default)
			)
			(layer "F.SilkS")
		)
		(fp_line
			(start 22.906482 -4.139946)
			(end 22.92223 -4.097782)
			(stroke
				(width 0.1)
				(type default)
			)
			(layer "F.SilkS")
		)
		(fp_line
			(start 22.906482 -4.139946)
			(end 22.92223 -4.097782)
			(stroke
				(width 0.1)
				(type default)
			)
			(layer "F.SilkS")
		)
		(fp_line
			(start 22.906482 -4.139946)
			(end 24.066246 -5.252974)
			(stroke
				(width 0.1)
				(type default)
			)
			(layer "F.SilkS")
		)
		(fp_line
			(start 22.906482 -4.139946)
			(end 24.066246 -5.252974)
			(stroke
				(width 0.1)
				(type default)
			)
			(layer "F.SilkS")
		)
		(fp_line
			(start 22.92223 -4.097782)
			(end 22.938486 -4.055364)
			(stroke
				(width 0.1)
				(type default)
			)
			(layer "F.SilkS")
		)
		(fp_line
			(start 22.92223 -4.097782)
			(end 22.938486 -4.055364)
			(stroke
				(width 0.1)
				(type default)
			)
			(layer "F.SilkS")
		)
		(fp_line
			(start 22.92223 -4.097782)
			(end 24.129492 -5.255768)
			(stroke
				(width 0.1)
				(type default)
			)
			(layer "F.SilkS")
		)
		(fp_line
			(start 22.92223 -4.097782)
			(end 24.129492 -5.255768)
			(stroke
				(width 0.1)
				(type default)
			)
			(layer "F.SilkS")
		)
		(fp_line
			(start 22.927818 -0.813308)
			(end 24.013668 -1.854962)
			(stroke
				(width 0.1)
				(type default)
			)
			(layer "F.SilkS")
		)
		(fp_line
			(start 22.927818 -0.813308)
			(end 24.013668 -1.854962)
			(stroke
				(width 0.1)
				(type default)
			)
			(layer "F.SilkS")
		)
		(fp_line
			(start 22.938486 -4.055364)
			(end 24.191468 -5.257546)
			(stroke
				(width 0.1)
				(type default)
			)
			(layer "F.SilkS")
		)
		(fp_line
			(start 22.938486 -4.055364)
			(end 24.191468 -5.257546)
			(stroke
				(width 0.1)
				(type default)
			)
			(layer "F.SilkS")
		)
		(fp_line
			(start 22.981158 -0.806704)
			(end 24.158956 -1.93675)
			(stroke
				(width 0.1)
				(type default)
			)
			(layer "F.SilkS")
		)
		(fp_line
			(start 22.981158 -0.806704)
			(end 24.158956 -1.93675)
			(stroke
				(width 0.1)
				(type default)
			)
			(layer "F.SilkS")
		)
		(fp_line
			(start 23.029672 -4.085336)
			(end 24.253444 -5.25907)
			(stroke
				(width 0.1)
				(type default)
			)
			(layer "F.SilkS")
		)
		(fp_line
			(start 23.029672 -4.085336)
			(end 24.253444 -5.25907)
			(stroke
				(width 0.1)
				(type default)
			)
			(layer "F.SilkS")
		)
		(fp_line
			(start 23.091394 -0.797052)
			(end 25.733502 -3.331464)
			(stroke
				(width 0.1)
				(type default)
			)
			(layer "F.SilkS")
		)
		(fp_line
			(start 23.091394 -0.797052)
			(end 25.733502 -3.331464)
			(stroke
				(width 0.1)
				(type default)
			)
			(layer "F.SilkS")
		)
		(fp_line
			(start 23.143718 -4.136898)
			(end 24.31542 -5.260848)
			(stroke
				(width 0.1)
				(type default)
			)
			(layer "F.SilkS")
		)
		(fp_line
			(start 23.143718 -4.136898)
			(end 24.31542 -5.260848)
			(stroke
				(width 0.1)
				(type default)
			)
			(layer "F.SilkS")
		)
		(fp_line
			(start 23.149306 -0.79502)
			(end 25.721056 -3.262122)
			(stroke
				(width 0.1)
				(type default)
			)
			(layer "F.SilkS")
		)
		(fp_line
			(start 23.149306 -0.79502)
			(end 25.721056 -3.262122)
			(stroke
				(width 0.1)
				(type default)
			)
			(layer "F.SilkS")
		)
		(fp_line
			(start 23.208488 -0.794258)
			(end 25.708864 -3.19278)
			(stroke
				(width 0.1)
				(type default)
			)
			(layer "F.SilkS")
		)
		(fp_line
			(start 23.208488 -0.794258)
			(end 25.708864 -3.19278)
			(stroke
				(width 0.1)
				(type default)
			)
			(layer "F.SilkS")
		)
		(fp_line
			(start 23.23084 -2.720086)
			(end 24.256492 -3.704082)
			(stroke
				(width 0.1)
				(type default)
			)
			(layer "F.SilkS")
		)
		(fp_line
			(start 23.23084 -2.720086)
			(end 24.256492 -3.704082)
			(stroke
				(width 0.1)
				(type default)
			)
			(layer "F.SilkS")
		)
		(fp_line
			(start 23.249382 -4.180586)
			(end 24.372824 -5.258562)
			(stroke
				(width 0.1)
				(type default)
			)
			(layer "F.SilkS")
		)
		(fp_line
			(start 23.249382 -4.180586)
			(end 24.372824 -5.258562)
			(stroke
				(width 0.1)
				(type default)
			)
			(layer "F.SilkS")
		)
		(fp_line
			(start 23.275798 -0.800608)
			(end 25.696926 -3.123184)
			(stroke
				(width 0.1)
				(type default)
			)
			(layer "F.SilkS")
		)
		(fp_line
			(start 23.275798 -0.800608)
			(end 25.696926 -3.123184)
			(stroke
				(width 0.1)
				(type default)
			)
			(layer "F.SilkS")
		)
		(fp_line
			(start 23.3426 -0.807466)
			(end 25.68448 -3.054096)
			(stroke
				(width 0.1)
				(type default)
			)
			(layer "F.SilkS")
		)
		(fp_line
			(start 23.3426 -0.807466)
			(end 25.68448 -3.054096)
			(stroke
				(width 0.1)
				(type default)
			)
			(layer "F.SilkS")
		)
		(fp_line
			(start 23.344632 -4.214114)
			(end 24.429212 -5.254752)
			(stroke
				(width 0.1)
				(type default)
			)
			(layer "F.SilkS")
		)
		(fp_line
			(start 23.344632 -4.214114)
			(end 24.429212 -5.254752)
			(stroke
				(width 0.1)
				(type default)
			)
			(layer "F.SilkS")
		)
		(fp_line
			(start 23.34895 -2.775712)
			(end 24.307546 -3.695192)
			(stroke
				(width 0.1)
				(type default)
			)
			(layer "F.SilkS")
		)
		(fp_line
			(start 23.34895 -2.775712)
			(end 24.307546 -3.695192)
			(stroke
				(width 0.1)
				(type default)
			)
			(layer "F.SilkS")
		)
		(fp_line
			(start 23.409402 -0.813562)
			(end 25.672542 -2.984754)
			(stroke
				(width 0.1)
				(type default)
			)
			(layer "F.SilkS")
		)
		(fp_line
			(start 23.409402 -0.813562)
			(end 25.672542 -2.984754)
			(stroke
				(width 0.1)
				(type default)
			)
			(layer "F.SilkS")
		)
		(fp_line
			(start 23.46071 -2.825242)
			(end 24.35606 -3.684016)
			(stroke
				(width 0.1)
				(type default)
			)
			(layer "F.SilkS")
		)
		(fp_line
			(start 23.46071 -2.825242)
			(end 24.35606 -3.684016)
			(stroke
				(width 0.1)
				(type default)
			)
			(layer "F.SilkS")
		)
		(fp_line
			(start 23.476458 -0.82042)
			(end 25.66035 -2.915412)
			(stroke
				(width 0.1)
				(type default)
			)
			(layer "F.SilkS")
		)
		(fp_line
			(start 23.476458 -0.82042)
			(end 25.66035 -2.915412)
			(stroke
				(width 0.1)
				(type default)
			)
			(layer "F.SilkS")
		)
		(fp_line
			(start 23.530052 -2.833878)
			(end 24.401272 -3.669538)
			(stroke
				(width 0.1)
				(type default)
			)
			(layer "F.SilkS")
		)
		(fp_line
			(start 23.530052 -2.833878)
			(end 24.401272 -3.669538)
			(stroke
				(width 0.1)
				(type default)
			)
			(layer "F.SilkS")
		)
		(fp_line
			(start 23.557484 -0.840232)
			(end 25.648412 -2.845816)
			(stroke
				(width 0.1)
				(type default)
			)
			(layer "F.SilkS")
		)
		(fp_line
			(start 23.557484 -0.840232)
			(end 25.648412 -2.845816)
			(stroke
				(width 0.1)
				(type default)
			)
			(layer "F.SilkS")
		)
		(fp_line
			(start 23.642828 -0.864616)
			(end 25.635966 -2.776474)
			(stroke
				(width 0.1)
				(type default)
			)
			(layer "F.SilkS")
		)
		(fp_line
			(start 23.642828 -0.864616)
			(end 25.635966 -2.776474)
			(stroke
				(width 0.1)
				(type default)
			)
			(layer "F.SilkS")
		)
		(fp_line
			(start 23.683468 -3.731514)
			(end 21.836634 -1.95961)
			(stroke
				(width 0.1)
				(type default)
			)
			(layer "F.SilkS")
		)
		(fp_line
			(start 23.683468 -3.731514)
			(end 21.836634 -1.95961)
			(stroke
				(width 0.1)
				(type default)
			)
			(layer "F.SilkS")
		)
		(fp_line
			(start 23.728426 -0.888746)
			(end 25.623774 -2.707132)
			(stroke
				(width 0.1)
				(type default)
			)
			(layer "F.SilkS")
		)
		(fp_line
			(start 23.728426 -0.888746)
			(end 25.623774 -2.707132)
			(stroke
				(width 0.1)
				(type default)
			)
			(layer "F.SilkS")
		)
		(fp_line
			(start 23.831296 -0.929894)
			(end 25.611836 -2.63779)
			(stroke
				(width 0.1)
				(type default)
			)
			(layer "F.SilkS")
		)
		(fp_line
			(start 23.831296 -0.929894)
			(end 25.611836 -2.63779)
			(stroke
				(width 0.1)
				(type default)
			)
			(layer "F.SilkS")
		)
		(fp_line
			(start 23.951692 -0.987552)
			(end 25.59939 -2.568194)
			(stroke
				(width 0.1)
				(type default)
			)
			(layer "F.SilkS")
		)
		(fp_line
			(start 23.951692 -0.987552)
			(end 25.59939 -2.568194)
			(stroke
				(width 0.1)
				(type default)
			)
			(layer "F.SilkS")
		)
		(fp_line
			(start 24.122888 -1.094232)
			(end 25.587452 -2.498852)
			(stroke
				(width 0.1)
				(type default)
			)
			(layer "F.SilkS")
		)
		(fp_line
			(start 24.122888 -1.094232)
			(end 25.587452 -2.498852)
			(stroke
				(width 0.1)
				(type default)
			)
			(layer "F.SilkS")
		)
		(fp_line
			(start 24.17699 -0.882904)
			(end 24.203406 -0.882904)
			(stroke
				(width 0.1)
				(type default)
			)
			(layer "F.SilkS")
		)
		(fp_line
			(start 24.17699 -0.882904)
			(end 24.203406 -0.882904)
			(stroke
				(width 0.1)
				(type default)
			)
			(layer "F.SilkS")
		)
		(fp_line
			(start 24.183848 -0.921512)
			(end 24.17699 -0.882904)
			(stroke
				(width 0.1)
				(type default)
			)
			(layer "F.SilkS")
		)
		(fp_line
			(start 24.183848 -0.921512)
			(end 24.17699 -0.882904)
			(stroke
				(width 0.1)
				(type default)
			)
			(layer "F.SilkS")
		)
		(fp_line
			(start 24.183848 -0.921512)
			(end 25.538684 -2.221484)
			(stroke
				(width 0.1)
				(type default)
			)
			(layer "F.SilkS")
		)
		(fp_line
			(start 24.183848 -0.921512)
			(end 25.538684 -2.221484)
			(stroke
				(width 0.1)
				(type default)
			)
			(layer "F.SilkS")
		)
		(fp_line
			(start 24.195786 -0.991108)
			(end 24.183848 -0.921512)
			(stroke
				(width 0.1)
				(type default)
			)
			(layer "F.SilkS")
		)
		(fp_line
			(start 24.195786 -0.991108)
			(end 24.183848 -0.921512)
			(stroke
				(width 0.1)
				(type default)
			)
			(layer "F.SilkS")
		)
		(fp_line
			(start 24.195786 -0.991108)
			(end 25.550876 -2.290826)
			(stroke
				(width 0.1)
				(type default)
			)
			(layer "F.SilkS")
		)
		(fp_line
			(start 24.195786 -0.991108)
			(end 25.550876 -2.290826)
			(stroke
				(width 0.1)
				(type default)
			)
			(layer "F.SilkS")
		)
		(fp_line
			(start 24.203406 -0.882904)
			(end 24.263858 -0.882904)
			(stroke
				(width 0.1)
				(type default)
			)
			(layer "F.SilkS")
		)
		(fp_line
			(start 24.203406 -0.882904)
			(end 24.263858 -0.882904)
			(stroke
				(width 0.1)
				(type default)
			)
			(layer "F.SilkS")
		)
		(fp_line
			(start 24.203406 -0.882904)
			(end 25.526746 -2.152142)
			(stroke
				(width 0.1)
				(type default)
			)
			(layer "F.SilkS")
		)
		(fp_line
			(start 24.203406 -0.882904)
			(end 25.526746 -2.152142)
			(stroke
				(width 0.1)
				(type default)
			)
			(layer "F.SilkS")
		)
		(fp_line
			(start 24.208232 -1.06045)
			(end 24.195786 -0.991108)
			(stroke
				(width 0.1)
				(type default)
			)
			(layer "F.SilkS")
		)
		(fp_line
			(start 24.208232 -1.06045)
			(end 24.195786 -0.991108)
			(stroke
				(width 0.1)
				(type default)
			)
			(layer "F.SilkS")
		)
		(fp_line
			(start 24.208232 -1.06045)
			(end 25.563322 -2.360422)
			(stroke
				(width 0.1)
				(type default)
			)
			(layer "F.SilkS")
		)
		(fp_line
			(start 24.208232 -1.06045)
			(end 25.563322 -2.360422)
			(stroke
				(width 0.1)
				(type default)
			)
			(layer "F.SilkS")
		)
		(fp_line
			(start 24.220424 -1.130046)
			(end 24.208232 -1.06045)
			(stroke
				(width 0.1)
				(type default)
			)
			(layer "F.SilkS")
		)
		(fp_line
			(start 24.220424 -1.130046)
			(end 24.208232 -1.06045)
			(stroke
				(width 0.1)
				(type default)
			)
			(layer "F.SilkS")
		)
		(fp_line
			(start 24.263858 -0.882904)
			(end 24.324056 -0.882904)
			(stroke
				(width 0.1)
				(type default)
			)
			(layer "F.SilkS")
		)
		(fp_line
			(start 24.263858 -0.882904)
			(end 24.324056 -0.882904)
			(stroke
				(width 0.1)
				(type default)
			)
			(layer "F.SilkS")
		)
		(fp_line
			(start 24.263858 -0.882904)
			(end 25.5143 -2.0828)
			(stroke
				(width 0.1)
				(type default)
			)
			(layer "F.SilkS")
		)
		(fp_line
			(start 24.263858 -0.882904)
			(end 25.5143 -2.0828)
			(stroke
				(width 0.1)
				(type default)
			)
			(layer "F.SilkS")
		)
		(fp_line
			(start 24.324056 -0.882904)
			(end 24.384 -0.882904)
			(stroke
				(width 0.1)
				(type default)
			)
			(layer "F.SilkS")
		)
		(fp_line
			(start 24.324056 -0.882904)
			(end 24.384 -0.882904)
			(stroke
				(width 0.1)
				(type default)
			)
			(layer "F.SilkS")
		)
		(fp_line
			(start 24.324056 -0.882904)
			(end 25.502362 -2.013204)
			(stroke
				(width 0.1)
				(type default)
			)
			(layer "F.SilkS")
		)
		(fp_line
			(start 24.324056 -0.882904)
			(end 25.502362 -2.013204)
			(stroke
				(width 0.1)
				(type default)
			)
			(layer "F.SilkS")
		)
		(fp_line
			(start 24.384 -0.882904)
			(end 24.443944 -0.882904)
			(stroke
				(width 0.1)
				(type default)
			)
			(layer "F.SilkS")
		)
		(fp_line
			(start 24.384 -0.882904)
			(end 24.443944 -0.882904)
			(stroke
				(width 0.1)
				(type default)
			)
			(layer "F.SilkS")
		)
		(fp_line
			(start 24.384 -0.882904)
			(end 25.49017 -1.943862)
			(stroke
				(width 0.1)
				(type default)
			)
			(layer "F.SilkS")
		)
		(fp_line
			(start 24.384 -0.882904)
			(end 25.49017 -1.943862)
			(stroke
				(width 0.1)
				(type default)
			)
			(layer "F.SilkS")
		)
		(fp_line
			(start 24.414988 -2.24028)
			(end 24.402796 -2.170938)
			(stroke
				(width 0.1)
				(type default)
			)
			(layer "F.SilkS")
		)
		(fp_line
			(start 24.414988 -2.24028)
			(end 24.402796 -2.170938)
			(stroke
				(width 0.1)
				(type default)
			)
			(layer "F.SilkS")
		)
		(fp_line
			(start 24.427434 -2.309368)
			(end 24.414988 -2.24028)
			(stroke
				(width 0.1)
				(type default)
			)
			(layer "F.SilkS")
		)
		(fp_line
			(start 24.427434 -2.309368)
			(end 24.414988 -2.24028)
			(stroke
				(width 0.1)
				(type default)
			)
			(layer "F.SilkS")
		)
		(fp_line
			(start 24.439372 -2.37871)
			(end 24.427434 -2.309368)
			(stroke
				(width 0.1)
				(type default)
			)
			(layer "F.SilkS")
		)
		(fp_line
			(start 24.439372 -2.37871)
			(end 24.427434 -2.309368)
			(stroke
				(width 0.1)
				(type default)
			)
			(layer "F.SilkS")
		)
		(fp_line
			(start 24.443944 -0.882904)
			(end 24.504142 -0.882904)
			(stroke
				(width 0.1)
				(type default)
			)
			(layer "F.SilkS")
		)
		(fp_line
			(start 24.443944 -0.882904)
			(end 24.504142 -0.882904)
			(stroke
				(width 0.1)
				(type default)
			)
			(layer "F.SilkS")
		)
		(fp_line
			(start 24.443944 -0.882904)
			(end 25.478232 -1.874774)
			(stroke
				(width 0.1)
				(type default)
			)
			(layer "F.SilkS")
		)
		(fp_line
			(start 24.443944 -0.882904)
			(end 25.478232 -1.874774)
			(stroke
				(width 0.1)
				(type default)
			)
			(layer "F.SilkS")
		)
		(fp_line
			(start 24.44623 -3.655568)
			(end 23.598886 -2.842514)
			(stroke
				(width 0.1)
				(type default)
			)
			(layer "F.SilkS")
		)
		(fp_line
			(start 24.44623 -3.655568)
			(end 23.598886 -2.842514)
			(stroke
				(width 0.1)
				(type default)
			)
			(layer "F.SilkS")
		)
		(fp_line
			(start 24.451564 -2.448306)
			(end 24.439372 -2.37871)
			(stroke
				(width 0.1)
				(type default)
			)
			(layer "F.SilkS")
		)
		(fp_line
			(start 24.451564 -2.448306)
			(end 24.439372 -2.37871)
			(stroke
				(width 0.1)
				(type default)
			)
			(layer "F.SilkS")
		)
		(fp_line
			(start 24.46401 -2.517648)
			(end 24.451564 -2.448306)
			(stroke
				(width 0.1)
				(type default)
			)
			(layer "F.SilkS")
		)
		(fp_line
			(start 24.46401 -2.517648)
			(end 24.451564 -2.448306)
			(stroke
				(width 0.1)
				(type default)
			)
			(layer "F.SilkS")
		)
		(fp_line
			(start 24.475948 -2.58699)
			(end 24.46401 -2.517648)
			(stroke
				(width 0.1)
				(type default)
			)
			(layer "F.SilkS")
		)
		(fp_line
			(start 24.475948 -2.58699)
			(end 24.46401 -2.517648)
			(stroke
				(width 0.1)
				(type default)
			)
			(layer "F.SilkS")
		)
		(fp_line
			(start 24.485346 -5.250942)
			(end 23.433532 -4.2418)
			(stroke
				(width 0.1)
				(type default)
			)
			(layer "F.SilkS")
		)
		(fp_line
			(start 24.485346 -5.250942)
			(end 23.433532 -4.2418)
			(stroke
				(width 0.1)
				(type default)
			)
			(layer "F.SilkS")
		)
		(fp_line
			(start 24.487886 -2.656332)
			(end 24.475948 -2.58699)
			(stroke
				(width 0.1)
				(type default)
			)
			(layer "F.SilkS")
		)
		(fp_line
			(start 24.487886 -2.656332)
			(end 24.475948 -2.58699)
			(stroke
				(width 0.1)
				(type default)
			)
			(layer "F.SilkS")
		)
		(fp_line
			(start 24.491696 -3.64109)
			(end 23.668482 -2.85115)
			(stroke
				(width 0.1)
				(type default)
			)
			(layer "F.SilkS")
		)
		(fp_line
			(start 24.491696 -3.64109)
			(end 23.668482 -2.85115)
			(stroke
				(width 0.1)
				(type default)
			)
			(layer "F.SilkS")
		)
		(fp_line
			(start 24.504142 -0.882904)
			(end 24.564594 -0.882904)
			(stroke
				(width 0.1)
				(type default)
			)
			(layer "F.SilkS")
		)
		(fp_line
			(start 24.504142 -0.882904)
			(end 24.564594 -0.882904)
			(stroke
				(width 0.1)
				(type default)
			)
			(layer "F.SilkS")
		)
		(fp_line
			(start 24.504142 -0.882904)
			(end 25.465786 -1.805178)
			(stroke
				(width 0.1)
				(type default)
			)
			(layer "F.SilkS")
		)
		(fp_line
			(start 24.504142 -0.882904)
			(end 25.465786 -1.805178)
			(stroke
				(width 0.1)
				(type default)
			)
			(layer "F.SilkS")
		)
		(fp_line
			(start 24.534114 -3.624072)
			(end 23.73757 -2.859786)
			(stroke
				(width 0.1)
				(type default)
			)
			(layer "F.SilkS")
		)
		(fp_line
			(start 24.534114 -3.624072)
			(end 23.73757 -2.859786)
			(stroke
				(width 0.1)
				(type default)
			)
			(layer "F.SilkS")
		)
		(fp_line
			(start 24.541734 -5.246878)
			(end 23.518114 -4.265168)
			(stroke
				(width 0.1)
				(type default)
			)
			(layer "F.SilkS")
		)
		(fp_line
			(start 24.541734 -5.246878)
			(end 23.518114 -4.265168)
			(stroke
				(width 0.1)
				(type default)
			)
			(layer "F.SilkS")
		)
		(fp_line
			(start 24.564594 -0.882904)
			(end 24.624538 -0.882904)
			(stroke
				(width 0.1)
				(type default)
			)
			(layer "F.SilkS")
		)
		(fp_line
			(start 24.564594 -0.882904)
			(end 24.624538 -0.882904)
			(stroke
				(width 0.1)
				(type default)
			)
			(layer "F.SilkS")
		)
		(fp_line
			(start 24.564594 -0.882904)
			(end 25.453594 -1.735836)
			(stroke
				(width 0.1)
				(type default)
			)
			(layer "F.SilkS")
		)
		(fp_line
			(start 24.564594 -0.882904)
			(end 25.453594 -1.735836)
			(stroke
				(width 0.1)
				(type default)
			)
			(layer "F.SilkS")
		)
		(fp_line
			(start 24.5745 -3.605276)
			(end 23.797006 -2.859024)
			(stroke
				(width 0.1)
				(type default)
			)
			(layer "F.SilkS")
		)
		(fp_line
			(start 24.5745 -3.605276)
			(end 23.797006 -2.859024)
			(stroke
				(width 0.1)
				(type default)
			)
			(layer "F.SilkS")
		)
		(fp_line
			(start 24.597614 -5.243068)
			(end 23.594822 -4.280916)
			(stroke
				(width 0.1)
				(type default)
			)
			(layer "F.SilkS")
		)
		(fp_line
			(start 24.597614 -5.243068)
			(end 23.594822 -4.280916)
			(stroke
				(width 0.1)
				(type default)
			)
			(layer "F.SilkS")
		)
		(fp_line
			(start 24.614886 -3.586226)
			(end 23.855426 -2.857754)
			(stroke
				(width 0.1)
				(type default)
			)
			(layer "F.SilkS")
		)
		(fp_line
			(start 24.614886 -3.586226)
			(end 23.855426 -2.857754)
			(stroke
				(width 0.1)
				(type default)
			)
			(layer "F.SilkS")
		)
		(fp_line
			(start 24.624538 -0.882904)
			(end 24.684736 -0.882904)
			(stroke
				(width 0.1)
				(type default)
			)
			(layer "F.SilkS")
		)
		(fp_line
			(start 24.624538 -0.882904)
			(end 24.684736 -0.882904)
			(stroke
				(width 0.1)
				(type default)
			)
			(layer "F.SilkS")
		)
		(fp_line
			(start 24.624538 -0.882904)
			(end 25.441656 -1.666494)
			(stroke
				(width 0.1)
				(type default)
			)
			(layer "F.SilkS")
		)
		(fp_line
			(start 24.624538 -0.882904)
			(end 25.441656 -1.666494)
			(stroke
				(width 0.1)
				(type default)
			)
			(layer "F.SilkS")
		)
		(fp_line
			(start 24.653748 -5.239258)
			(end 23.67026 -4.295902)
			(stroke
				(width 0.1)
				(type default)
			)
			(layer "F.SilkS")
		)
		(fp_line
			(start 24.653748 -5.239258)
			(end 23.67026 -4.295902)
			(stroke
				(width 0.1)
				(type default)
			)
			(layer "F.SilkS")
		)
		(fp_line
			(start 24.67102 -3.697478)
			(end 24.658574 -3.627882)
			(stroke
				(width 0.1)
				(type default)
			)
			(layer "F.SilkS")
		)
		(fp_line
			(start 24.67102 -3.697478)
			(end 24.658574 -3.627882)
			(stroke
				(width 0.1)
				(type default)
			)
			(layer "F.SilkS")
		)
		(fp_line
			(start 24.682958 -3.76682)
			(end 24.67102 -3.697478)
			(stroke
				(width 0.1)
				(type default)
			)
			(layer "F.SilkS")
		)
		(fp_line
			(start 24.682958 -3.76682)
			(end 24.67102 -3.697478)
			(stroke
				(width 0.1)
				(type default)
			)
			(layer "F.SilkS")
		)
		(fp_line
			(start 24.684736 -0.882904)
			(end 24.744934 -0.882904)
			(stroke
				(width 0.1)
				(type default)
			)
			(layer "F.SilkS")
		)
		(fp_line
			(start 24.684736 -0.882904)
			(end 24.744934 -0.882904)
			(stroke
				(width 0.1)
				(type default)
			)
			(layer "F.SilkS")
		)
		(fp_line
			(start 24.684736 -0.882904)
			(end 25.42921 -1.597406)
			(stroke
				(width 0.1)
				(type default)
			)
			(layer "F.SilkS")
		)
		(fp_line
			(start 24.684736 -0.882904)
			(end 25.42921 -1.597406)
			(stroke
				(width 0.1)
				(type default)
			)
			(layer "F.SilkS")
		)
		(fp_line
			(start 24.708866 -5.234432)
			(end 23.739856 -4.304792)
			(stroke
				(width 0.1)
				(type default)
			)
			(layer "F.SilkS")
		)
		(fp_line
			(start 24.708866 -5.234432)
			(end 23.739856 -4.304792)
			(stroke
				(width 0.1)
				(type default)
			)
			(layer "F.SilkS")
		)
		(fp_line
			(start 24.744934 -0.882904)
			(end 24.805386 -0.882904)
			(stroke
				(width 0.1)
				(type default)
			)
			(layer "F.SilkS")
		)
		(fp_line
			(start 24.744934 -0.882904)
			(end 24.805386 -0.882904)
			(stroke
				(width 0.1)
				(type default)
			)
			(layer "F.SilkS")
		)
		(fp_line
			(start 24.744934 -0.882904)
			(end 25.417272 -1.52781)
			(stroke
				(width 0.1)
				(type default)
			)
			(layer "F.SilkS")
		)
		(fp_line
			(start 24.744934 -0.882904)
			(end 25.417272 -1.52781)
			(stroke
				(width 0.1)
				(type default)
			)
			(layer "F.SilkS")
		)
		(fp_line
			(start 24.75738 -5.223256)
			(end 23.809452 -4.313936)
			(stroke
				(width 0.1)
				(type default)
			)
			(layer "F.SilkS")
		)
		(fp_line
			(start 24.75738 -5.223256)
			(end 23.809452 -4.313936)
			(stroke
				(width 0.1)
				(type default)
			)
			(layer "F.SilkS")
		)
		(fp_line
			(start 24.805386 -0.882904)
			(end 24.86533 -0.882904)
			(stroke
				(width 0.1)
				(type default)
			)
			(layer "F.SilkS")
		)
		(fp_line
			(start 24.805386 -0.882904)
			(end 24.86533 -0.882904)
			(stroke
				(width 0.1)
				(type default)
			)
			(layer "F.SilkS")
		)
		(fp_line
			(start 24.805386 -0.882904)
			(end 25.40508 -1.458214)
			(stroke
				(width 0.1)
				(type default)
			)
			(layer "F.SilkS")
		)
		(fp_line
			(start 24.805386 -0.882904)
			(end 25.40508 -1.458214)
			(stroke
				(width 0.1)
				(type default)
			)
			(layer "F.SilkS")
		)
		(fp_line
			(start 24.805894 -5.21208)
			(end 23.87473 -4.318762)
			(stroke
				(width 0.1)
				(type default)
			)
			(layer "F.SilkS")
		)
		(fp_line
			(start 24.805894 -5.21208)
			(end 23.87473 -4.318762)
			(stroke
				(width 0.1)
				(type default)
			)
			(layer "F.SilkS")
		)
		(fp_line
			(start 24.854154 -5.200904)
			(end 23.9395 -4.323334)
			(stroke
				(width 0.1)
				(type default)
			)
			(layer "F.SilkS")
		)
		(fp_line
			(start 24.854154 -5.200904)
			(end 23.9395 -4.323334)
			(stroke
				(width 0.1)
				(type default)
			)
			(layer "F.SilkS")
		)
		(fp_line
			(start 24.86533 -0.882904)
			(end 24.925274 -0.882904)
			(stroke
				(width 0.1)
				(type default)
			)
			(layer "F.SilkS")
		)
		(fp_line
			(start 24.86533 -0.882904)
			(end 24.925274 -0.882904)
			(stroke
				(width 0.1)
				(type default)
			)
			(layer "F.SilkS")
		)
		(fp_line
			(start 24.86533 -0.882904)
			(end 25.392634 -1.388872)
			(stroke
				(width 0.1)
				(type default)
			)
			(layer "F.SilkS")
		)
		(fp_line
			(start 24.86533 -0.882904)
			(end 25.392634 -1.388872)
			(stroke
				(width 0.1)
				(type default)
			)
			(layer "F.SilkS")
		)
		(fp_line
			(start 24.903176 -5.189728)
			(end 24.003254 -4.32689)
			(stroke
				(width 0.1)
				(type default)
			)
			(layer "F.SilkS")
		)
		(fp_line
			(start 24.903176 -5.189728)
			(end 24.003254 -4.32689)
			(stroke
				(width 0.1)
				(type default)
			)
			(layer "F.SilkS")
		)
		(fp_line
			(start 24.925274 -0.882904)
			(end 24.985472 -0.882904)
			(stroke
				(width 0.1)
				(type default)
			)
			(layer "F.SilkS")
		)
		(fp_line
			(start 24.925274 -0.882904)
			(end 24.985472 -0.882904)
			(stroke
				(width 0.1)
				(type default)
			)
			(layer "F.SilkS")
		)
		(fp_line
			(start 24.925274 -0.882904)
			(end 25.380696 -1.319784)
			(stroke
				(width 0.1)
				(type default)
			)
			(layer "F.SilkS")
		)
		(fp_line
			(start 24.925274 -0.882904)
			(end 25.380696 -1.319784)
			(stroke
				(width 0.1)
				(type default)
			)
			(layer "F.SilkS")
		)
		(fp_line
			(start 24.95169 -5.178552)
			(end 24.064976 -4.327906)
			(stroke
				(width 0.1)
				(type default)
			)
			(layer "F.SilkS")
		)
		(fp_line
			(start 24.95169 -5.178552)
			(end 24.064976 -4.327906)
			(stroke
				(width 0.1)
				(type default)
			)
			(layer "F.SilkS")
		)
		(fp_line
			(start 24.985472 -0.882904)
			(end 25.04567 -0.882904)
			(stroke
				(width 0.1)
				(type default)
			)
			(layer "F.SilkS")
		)
		(fp_line
			(start 24.985472 -0.882904)
			(end 25.04567 -0.882904)
			(stroke
				(width 0.1)
				(type default)
			)
			(layer "F.SilkS")
		)
		(fp_line
			(start 24.985472 -0.882904)
			(end 25.368504 -1.250188)
			(stroke
				(width 0.1)
				(type default)
			)
			(layer "F.SilkS")
		)
		(fp_line
			(start 24.985472 -0.882904)
			(end 25.368504 -1.250188)
			(stroke
				(width 0.1)
				(type default)
			)
			(layer "F.SilkS")
		)
		(fp_line
			(start 24.99995 -5.16763)
			(end 24.12619 -4.329176)
			(stroke
				(width 0.1)
				(type default)
			)
			(layer "F.SilkS")
		)
		(fp_line
			(start 24.99995 -5.16763)
			(end 24.12619 -4.329176)
			(stroke
				(width 0.1)
				(type default)
			)
			(layer "F.SilkS")
		)
		(fp_line
			(start 25.045162 -5.152898)
			(end 24.18588 -4.328922)
			(stroke
				(width 0.1)
				(type default)
			)
			(layer "F.SilkS")
		)
		(fp_line
			(start 25.045162 -5.152898)
			(end 24.18588 -4.328922)
			(stroke
				(width 0.1)
				(type default)
			)
			(layer "F.SilkS")
		)
		(fp_line
			(start 25.04567 -0.882904)
			(end 25.106122 -0.882904)
			(stroke
				(width 0.1)
				(type default)
			)
			(layer "F.SilkS")
		)
		(fp_line
			(start 25.04567 -0.882904)
			(end 25.106122 -0.882904)
			(stroke
				(width 0.1)
				(type default)
			)
			(layer "F.SilkS")
		)
		(fp_line
			(start 25.04567 -0.882904)
			(end 25.356058 -1.180592)
			(stroke
				(width 0.1)
				(type default)
			)
			(layer "F.SilkS")
		)
		(fp_line
			(start 25.04567 -0.882904)
			(end 25.356058 -1.180592)
			(stroke
				(width 0.1)
				(type default)
			)
			(layer "F.SilkS")
		)
		(fp_line
			(start 25.086056 -5.13461)
			(end 24.241252 -4.32435)
			(stroke
				(width 0.1)
				(type default)
			)
			(layer "F.SilkS")
		)
		(fp_line
			(start 25.086056 -5.13461)
			(end 24.241252 -4.32435)
			(stroke
				(width 0.1)
				(type default)
			)
			(layer "F.SilkS")
		)
		(fp_line
			(start 25.106122 -0.882904)
			(end 25.166066 -0.882904)
			(stroke
				(width 0.1)
				(type default)
			)
			(layer "F.SilkS")
		)
		(fp_line
			(start 25.106122 -0.882904)
			(end 25.166066 -0.882904)
			(stroke
				(width 0.1)
				(type default)
			)
			(layer "F.SilkS")
		)
		(fp_line
			(start 25.106122 -0.882904)
			(end 25.34412 -1.111504)
			(stroke
				(width 0.1)
				(type default)
			)
			(layer "F.SilkS")
		)
		(fp_line
			(start 25.106122 -0.882904)
			(end 25.34412 -1.111504)
			(stroke
				(width 0.1)
				(type default)
			)
			(layer "F.SilkS")
		)
		(fp_line
			(start 25.127458 -5.116322)
			(end 24.297132 -4.320032)
			(stroke
				(width 0.1)
				(type default)
			)
			(layer "F.SilkS")
		)
		(fp_line
			(start 25.127458 -5.116322)
			(end 24.297132 -4.320032)
			(stroke
				(width 0.1)
				(type default)
			)
			(layer "F.SilkS")
		)
		(fp_line
			(start 25.166066 -0.882904)
			(end 25.226264 -0.882904)
			(stroke
				(width 0.1)
				(type default)
			)
			(layer "F.SilkS")
		)
		(fp_line
			(start 25.166066 -0.882904)
			(end 25.226264 -0.882904)
			(stroke
				(width 0.1)
				(type default)
			)
			(layer "F.SilkS")
		)
		(fp_line
			(start 25.166066 -0.882904)
			(end 25.332182 -1.042416)
			(stroke
				(width 0.1)
				(type default)
			)
			(layer "F.SilkS")
		)
		(fp_line
			(start 25.166066 -0.882904)
			(end 25.332182 -1.042416)
			(stroke
				(width 0.1)
				(type default)
			)
			(layer "F.SilkS")
		)
		(fp_line
			(start 25.168352 -5.098034)
			(end 24.346408 -4.309618)
			(stroke
				(width 0.1)
				(type default)
			)
			(layer "F.SilkS")
		)
		(fp_line
			(start 25.168352 -5.098034)
			(end 24.346408 -4.309618)
			(stroke
				(width 0.1)
				(type default)
			)
			(layer "F.SilkS")
		)
		(fp_line
			(start 25.2095 -5.08)
			(end 24.393398 -4.296918)
			(stroke
				(width 0.1)
				(type default)
			)
			(layer "F.SilkS")
		)
		(fp_line
			(start 25.2095 -5.08)
			(end 24.393398 -4.296918)
			(stroke
				(width 0.1)
				(type default)
			)
			(layer "F.SilkS")
		)
		(fp_line
			(start 25.226264 -0.882904)
			(end 25.286462 -0.882904)
			(stroke
				(width 0.1)
				(type default)
			)
			(layer "F.SilkS")
		)
		(fp_line
			(start 25.226264 -0.882904)
			(end 25.286462 -0.882904)
			(stroke
				(width 0.1)
				(type default)
			)
			(layer "F.SilkS")
		)
		(fp_line
			(start 25.226264 -0.882904)
			(end 25.31999 -0.97282)
			(stroke
				(width 0.1)
				(type default)
			)
			(layer "F.SilkS")
		)
		(fp_line
			(start 25.226264 -0.882904)
			(end 25.31999 -0.97282)
			(stroke
				(width 0.1)
				(type default)
			)
			(layer "F.SilkS")
		)
		(fp_line
			(start 25.250648 -5.061712)
			(end 24.438356 -4.28244)
			(stroke
				(width 0.1)
				(type default)
			)
			(layer "F.SilkS")
		)
		(fp_line
			(start 25.250648 -5.061712)
			(end 24.438356 -4.28244)
			(stroke
				(width 0.1)
				(type default)
			)
			(layer "F.SilkS")
		)
		(fp_line
			(start 25.286462 -0.882904)
			(end 25.304242 -0.882904)
			(stroke
				(width 0.1)
				(type default)
			)
			(layer "F.SilkS")
		)
		(fp_line
			(start 25.286462 -0.882904)
			(end 25.304242 -0.882904)
			(stroke
				(width 0.1)
				(type default)
			)
			(layer "F.SilkS")
		)
		(fp_line
			(start 25.286462 -0.882904)
			(end 25.307544 -0.903224)
			(stroke
				(width 0.1)
				(type default)
			)
			(layer "F.SilkS")
		)
		(fp_line
			(start 25.286462 -0.882904)
			(end 25.307544 -0.903224)
			(stroke
				(width 0.1)
				(type default)
			)
			(layer "F.SilkS")
		)
		(fp_line
			(start 25.29205 -5.043424)
			(end 24.477726 -4.26212)
			(stroke
				(width 0.1)
				(type default)
			)
			(layer "F.SilkS")
		)
		(fp_line
			(start 25.29205 -5.043424)
			(end 24.477726 -4.26212)
			(stroke
				(width 0.1)
				(type default)
			)
			(layer "F.SilkS")
		)
		(fp_line
			(start 25.304242 -0.882904)
			(end 25.307544 -0.903224)
			(stroke
				(width 0.1)
				(type default)
			)
			(layer "F.SilkS")
		)
		(fp_line
			(start 25.304242 -0.882904)
			(end 25.307544 -0.903224)
			(stroke
				(width 0.1)
				(type default)
			)
			(layer "F.SilkS")
		)
		(fp_line
			(start 25.307544 -0.903224)
			(end 25.31999 -0.97282)
			(stroke
				(width 0.1)
				(type default)
			)
			(layer "F.SilkS")
		)
		(fp_line
			(start 25.307544 -0.903224)
			(end 25.31999 -0.97282)
			(stroke
				(width 0.1)
				(type default)
			)
			(layer "F.SilkS")
		)
		(fp_line
			(start 25.31999 -0.97282)
			(end 25.332182 -1.042416)
			(stroke
				(width 0.1)
				(type default)
			)
			(layer "F.SilkS")
		)
		(fp_line
			(start 25.31999 -0.97282)
			(end 25.332182 -1.042416)
			(stroke
				(width 0.1)
				(type default)
			)
			(layer "F.SilkS")
		)
		(fp_line
			(start 25.327356 -5.019294)
			(end 24.516334 -4.2418)
			(stroke
				(width 0.1)
				(type default)
			)
			(layer "F.SilkS")
		)
		(fp_line
			(start 25.327356 -5.019294)
			(end 24.516334 -4.2418)
			(stroke
				(width 0.1)
				(type default)
			)
			(layer "F.SilkS")
		)
		(fp_line
			(start 25.332182 -1.042416)
			(end 25.34412 -1.111504)
			(stroke
				(width 0.1)
				(type default)
			)
			(layer "F.SilkS")
		)
		(fp_line
			(start 25.332182 -1.042416)
			(end 25.34412 -1.111504)
			(stroke
				(width 0.1)
				(type default)
			)
			(layer "F.SilkS")
		)
		(fp_line
			(start 25.34412 -1.111504)
			(end 25.356058 -1.180592)
			(stroke
				(width 0.1)
				(type default)
			)
			(layer "F.SilkS")
		)
		(fp_line
			(start 25.34412 -1.111504)
			(end 25.356058 -1.180592)
			(stroke
				(width 0.1)
				(type default)
			)
			(layer "F.SilkS")
		)
		(fp_line
			(start 25.356058 -1.180592)
			(end 25.368504 -1.250188)
			(stroke
				(width 0.1)
				(type default)
			)
			(layer "F.SilkS")
		)
		(fp_line
			(start 25.356058 -1.180592)
			(end 25.368504 -1.250188)
			(stroke
				(width 0.1)
				(type default)
			)
			(layer "F.SilkS")
		)
		(fp_line
			(start 25.36063 -4.994148)
			(end 24.549354 -4.215892)
			(stroke
				(width 0.1)
				(type default)
			)
			(layer "F.SilkS")
		)
		(fp_line
			(start 25.36063 -4.994148)
			(end 24.549354 -4.215892)
			(stroke
				(width 0.1)
				(type default)
			)
			(layer "F.SilkS")
		)
		(fp_line
			(start 25.368504 -1.250188)
			(end 25.380696 -1.319784)
			(stroke
				(width 0.1)
				(type default)
			)
			(layer "F.SilkS")
		)
		(fp_line
			(start 25.368504 -1.250188)
			(end 25.380696 -1.319784)
			(stroke
				(width 0.1)
				(type default)
			)
			(layer "F.SilkS")
		)
		(fp_line
			(start 25.380696 -1.319784)
			(end 25.392634 -1.388872)
			(stroke
				(width 0.1)
				(type default)
			)
			(layer "F.SilkS")
		)
		(fp_line
			(start 25.380696 -1.319784)
			(end 25.392634 -1.388872)
			(stroke
				(width 0.1)
				(type default)
			)
			(layer "F.SilkS")
		)
		(fp_line
			(start 25.392634 -1.388872)
			(end 25.40508 -1.458214)
			(stroke
				(width 0.1)
				(type default)
			)
			(layer "F.SilkS")
		)
		(fp_line
			(start 25.392634 -1.388872)
			(end 25.40508 -1.458214)
			(stroke
				(width 0.1)
				(type default)
			)
			(layer "F.SilkS")
		)
		(fp_line
			(start 25.394412 -4.968494)
			(end 24.580596 -4.187952)
			(stroke
				(width 0.1)
				(type default)
			)
			(layer "F.SilkS")
		)
		(fp_line
			(start 25.394412 -4.968494)
			(end 24.580596 -4.187952)
			(stroke
				(width 0.1)
				(type default)
			)
			(layer "F.SilkS")
		)
		(fp_line
			(start 25.40508 -1.458214)
			(end 25.417272 -1.52781)
			(stroke
				(width 0.1)
				(type default)
			)
			(layer "F.SilkS")
		)
		(fp_line
			(start 25.40508 -1.458214)
			(end 25.417272 -1.52781)
			(stroke
				(width 0.1)
				(type default)
			)
			(layer "F.SilkS")
		)
		(fp_line
			(start 25.417272 -1.52781)
			(end 25.42921 -1.597406)
			(stroke
				(width 0.1)
				(type default)
			)
			(layer "F.SilkS")
		)
		(fp_line
			(start 25.417272 -1.52781)
			(end 25.42921 -1.597406)
			(stroke
				(width 0.1)
				(type default)
			)
			(layer "F.SilkS")
		)
		(fp_line
			(start 25.428194 -4.943094)
			(end 24.609044 -4.157218)
			(stroke
				(width 0.1)
				(type default)
			)
			(layer "F.SilkS")
		)
		(fp_line
			(start 25.428194 -4.943094)
			(end 24.609044 -4.157218)
			(stroke
				(width 0.1)
				(type default)
			)
			(layer "F.SilkS")
		)
		(fp_line
			(start 25.42921 -1.597406)
			(end 25.441656 -1.666494)
			(stroke
				(width 0.1)
				(type default)
			)
			(layer "F.SilkS")
		)
		(fp_line
			(start 25.42921 -1.597406)
			(end 25.441656 -1.666494)
			(stroke
				(width 0.1)
				(type default)
			)
			(layer "F.SilkS")
		)
		(fp_line
			(start 25.441656 -1.666494)
			(end 25.453594 -1.735836)
			(stroke
				(width 0.1)
				(type default)
			)
			(layer "F.SilkS")
		)
		(fp_line
			(start 25.441656 -1.666494)
			(end 25.453594 -1.735836)
			(stroke
				(width 0.1)
				(type default)
			)
			(layer "F.SilkS")
		)
		(fp_line
			(start 25.453594 -1.735836)
			(end 25.465786 -1.805178)
			(stroke
				(width 0.1)
				(type default)
			)
			(layer "F.SilkS")
		)
		(fp_line
			(start 25.453594 -1.735836)
			(end 25.465786 -1.805178)
			(stroke
				(width 0.1)
				(type default)
			)
			(layer "F.SilkS")
		)
		(fp_line
			(start 25.461722 -4.917694)
			(end 24.631904 -4.121912)
			(stroke
				(width 0.1)
				(type default)
			)
			(layer "F.SilkS")
		)
		(fp_line
			(start 25.461722 -4.917694)
			(end 24.631904 -4.121912)
			(stroke
				(width 0.1)
				(type default)
			)
			(layer "F.SilkS")
		)
		(fp_line
			(start 25.465786 -1.805178)
			(end 25.478232 -1.874774)
			(stroke
				(width 0.1)
				(type default)
			)
			(layer "F.SilkS")
		)
		(fp_line
			(start 25.465786 -1.805178)
			(end 25.478232 -1.874774)
			(stroke
				(width 0.1)
				(type default)
			)
			(layer "F.SilkS")
		)
		(fp_line
			(start 25.478232 -1.874774)
			(end 25.49017 -1.943862)
			(stroke
				(width 0.1)
				(type default)
			)
			(layer "F.SilkS")
		)
		(fp_line
			(start 25.478232 -1.874774)
			(end 25.49017 -1.943862)
			(stroke
				(width 0.1)
				(type default)
			)
			(layer "F.SilkS")
		)
		(fp_line
			(start 25.49017 -1.943862)
			(end 25.502362 -2.013204)
			(stroke
				(width 0.1)
				(type default)
			)
			(layer "F.SilkS")
		)
		(fp_line
			(start 25.49017 -1.943862)
			(end 25.502362 -2.013204)
			(stroke
				(width 0.1)
				(type default)
			)
			(layer "F.SilkS")
		)
		(fp_line
			(start 25.49525 -4.892294)
			(end 24.65451 -4.085844)
			(stroke
				(width 0.1)
				(type default)
			)
			(layer "F.SilkS")
		)
		(fp_line
			(start 25.49525 -4.892294)
			(end 24.65451 -4.085844)
			(stroke
				(width 0.1)
				(type default)
			)
			(layer "F.SilkS")
		)
		(fp_line
			(start 25.502362 -2.013204)
			(end 25.5143 -2.0828)
			(stroke
				(width 0.1)
				(type default)
			)
			(layer "F.SilkS")
		)
		(fp_line
			(start 25.502362 -2.013204)
			(end 25.5143 -2.0828)
			(stroke
				(width 0.1)
				(type default)
			)
			(layer "F.SilkS")
		)
		(fp_line
			(start 25.5143 -2.0828)
			(end 25.526746 -2.152142)
			(stroke
				(width 0.1)
				(type default)
			)
			(layer "F.SilkS")
		)
		(fp_line
			(start 25.5143 -2.0828)
			(end 25.526746 -2.152142)
			(stroke
				(width 0.1)
				(type default)
			)
			(layer "F.SilkS")
		)
		(fp_line
			(start 25.526746 -2.152142)
			(end 25.538684 -2.221484)
			(stroke
				(width 0.1)
				(type default)
			)
			(layer "F.SilkS")
		)
		(fp_line
			(start 25.526746 -2.152142)
			(end 25.538684 -2.221484)
			(stroke
				(width 0.1)
				(type default)
			)
			(layer "F.SilkS")
		)
		(fp_line
			(start 25.527508 -4.865624)
			(end 24.669242 -4.042156)
			(stroke
				(width 0.1)
				(type default)
			)
			(layer "F.SilkS")
		)
		(fp_line
			(start 25.527508 -4.865624)
			(end 24.669242 -4.042156)
			(stroke
				(width 0.1)
				(type default)
			)
			(layer "F.SilkS")
		)
		(fp_line
			(start 25.538684 -2.221484)
			(end 25.550876 -2.290826)
			(stroke
				(width 0.1)
				(type default)
			)
			(layer "F.SilkS")
		)
		(fp_line
			(start 25.538684 -2.221484)
			(end 25.550876 -2.290826)
			(stroke
				(width 0.1)
				(type default)
			)
			(layer "F.SilkS")
		)
		(fp_line
			(start 25.550876 -2.290826)
			(end 25.563322 -2.360422)
			(stroke
				(width 0.1)
				(type default)
			)
			(layer "F.SilkS")
		)
		(fp_line
			(start 25.550876 -2.290826)
			(end 25.563322 -2.360422)
			(stroke
				(width 0.1)
				(type default)
			)
			(layer "F.SilkS")
		)
		(fp_line
			(start 25.553162 -4.83235)
			(end 24.683974 -3.998722)
			(stroke
				(width 0.1)
				(type default)
			)
			(layer "F.SilkS")
		)
		(fp_line
			(start 25.553162 -4.83235)
			(end 24.683974 -3.998722)
			(stroke
				(width 0.1)
				(type default)
			)
			(layer "F.SilkS")
		)
		(fp_line
			(start 25.563322 -2.360422)
			(end 25.57526 -2.429764)
			(stroke
				(width 0.1)
				(type default)
			)
			(layer "F.SilkS")
		)
		(fp_line
			(start 25.563322 -2.360422)
			(end 25.57526 -2.429764)
			(stroke
				(width 0.1)
				(type default)
			)
			(layer "F.SilkS")
		)
		(fp_line
			(start 25.57526 -2.429764)
			(end 24.220424 -1.130046)
			(stroke
				(width 0.1)
				(type default)
			)
			(layer "F.SilkS")
		)
		(fp_line
			(start 25.57526 -2.429764)
			(end 24.220424 -1.130046)
			(stroke
				(width 0.1)
				(type default)
			)
			(layer "F.SilkS")
		)
		(fp_line
			(start 25.57526 -2.429764)
			(end 25.587452 -2.498852)
			(stroke
				(width 0.1)
				(type default)
			)
			(layer "F.SilkS")
		)
		(fp_line
			(start 25.57526 -2.429764)
			(end 25.587452 -2.498852)
			(stroke
				(width 0.1)
				(type default)
			)
			(layer "F.SilkS")
		)
		(fp_line
			(start 25.57907 -4.79933)
			(end 24.690324 -3.946652)
			(stroke
				(width 0.1)
				(type default)
			)
			(layer "F.SilkS")
		)
		(fp_line
			(start 25.57907 -4.79933)
			(end 24.690324 -3.946652)
			(stroke
				(width 0.1)
				(type default)
			)
			(layer "F.SilkS")
		)
		(fp_line
			(start 25.587452 -2.498852)
			(end 25.59939 -2.568194)
			(stroke
				(width 0.1)
				(type default)
			)
			(layer "F.SilkS")
		)
		(fp_line
			(start 25.587452 -2.498852)
			(end 25.59939 -2.568194)
			(stroke
				(width 0.1)
				(type default)
			)
			(layer "F.SilkS")
		)
		(fp_line
			(start 25.59939 -2.568194)
			(end 25.611836 -2.63779)
			(stroke
				(width 0.1)
				(type default)
			)
			(layer "F.SilkS")
		)
		(fp_line
			(start 25.59939 -2.568194)
			(end 25.611836 -2.63779)
			(stroke
				(width 0.1)
				(type default)
			)
			(layer "F.SilkS")
		)
		(fp_line
			(start 25.60447 -4.766564)
			(end 24.695658 -3.894328)
			(stroke
				(width 0.1)
				(type default)
			)
			(layer "F.SilkS")
		)
		(fp_line
			(start 25.60447 -4.766564)
			(end 24.695658 -3.894328)
			(stroke
				(width 0.1)
				(type default)
			)
			(layer "F.SilkS")
		)
		(fp_line
			(start 25.611836 -2.63779)
			(end 25.623774 -2.707132)
			(stroke
				(width 0.1)
				(type default)
			)
			(layer "F.SilkS")
		)
		(fp_line
			(start 25.611836 -2.63779)
			(end 25.623774 -2.707132)
			(stroke
				(width 0.1)
				(type default)
			)
			(layer "F.SilkS")
		)
		(fp_line
			(start 25.623774 -2.707132)
			(end 25.635966 -2.776474)
			(stroke
				(width 0.1)
				(type default)
			)
			(layer "F.SilkS")
		)
		(fp_line
			(start 25.623774 -2.707132)
			(end 25.635966 -2.776474)
			(stroke
				(width 0.1)
				(type default)
			)
			(layer "F.SilkS")
		)
		(fp_line
			(start 25.630378 -4.73329)
			(end 24.690324 -3.83159)
			(stroke
				(width 0.1)
				(type default)
			)
			(layer "F.SilkS")
		)
		(fp_line
			(start 25.630378 -4.73329)
			(end 24.690324 -3.83159)
			(stroke
				(width 0.1)
				(type default)
			)
			(layer "F.SilkS")
		)
		(fp_line
			(start 25.635966 -2.776474)
			(end 25.648412 -2.845816)
			(stroke
				(width 0.1)
				(type default)
			)
			(layer "F.SilkS")
		)
		(fp_line
			(start 25.635966 -2.776474)
			(end 25.648412 -2.845816)
			(stroke
				(width 0.1)
				(type default)
			)
			(layer "F.SilkS")
		)
		(fp_line
			(start 25.648412 -2.845816)
			(end 25.66035 -2.915412)
			(stroke
				(width 0.1)
				(type default)
			)
			(layer "F.SilkS")
		)
		(fp_line
			(start 25.648412 -2.845816)
			(end 25.66035 -2.915412)
			(stroke
				(width 0.1)
				(type default)
			)
			(layer "F.SilkS")
		)
		(fp_line
			(start 25.656286 -4.70027)
			(end 24.682958 -3.76682)
			(stroke
				(width 0.1)
				(type default)
			)
			(layer "F.SilkS")
		)
		(fp_line
			(start 25.656286 -4.70027)
			(end 24.682958 -3.76682)
			(stroke
				(width 0.1)
				(type default)
			)
			(layer "F.SilkS")
		)
		(fp_line
			(start 25.66035 -2.915412)
			(end 25.672542 -2.984754)
			(stroke
				(width 0.1)
				(type default)
			)
			(layer "F.SilkS")
		)
		(fp_line
			(start 25.66035 -2.915412)
			(end 25.672542 -2.984754)
			(stroke
				(width 0.1)
				(type default)
			)
			(layer "F.SilkS")
		)
		(fp_line
			(start 25.672542 -2.984754)
			(end 25.68448 -3.054096)
			(stroke
				(width 0.1)
				(type default)
			)
			(layer "F.SilkS")
		)
		(fp_line
			(start 25.672542 -2.984754)
			(end 25.68448 -3.054096)
			(stroke
				(width 0.1)
				(type default)
			)
			(layer "F.SilkS")
		)
		(fp_line
			(start 25.681686 -4.66725)
			(end 24.67102 -3.697478)
			(stroke
				(width 0.1)
				(type default)
			)
			(layer "F.SilkS")
		)
		(fp_line
			(start 25.681686 -4.66725)
			(end 24.67102 -3.697478)
			(stroke
				(width 0.1)
				(type default)
			)
			(layer "F.SilkS")
		)
		(fp_line
			(start 25.68448 -3.054096)
			(end 25.696926 -3.123184)
			(stroke
				(width 0.1)
				(type default)
			)
			(layer "F.SilkS")
		)
		(fp_line
			(start 25.68448 -3.054096)
			(end 25.696926 -3.123184)
			(stroke
				(width 0.1)
				(type default)
			)
			(layer "F.SilkS")
		)
		(fp_line
			(start 25.696926 -3.123184)
			(end 25.708864 -3.19278)
			(stroke
				(width 0.1)
				(type default)
			)
			(layer "F.SilkS")
		)
		(fp_line
			(start 25.696926 -3.123184)
			(end 25.708864 -3.19278)
			(stroke
				(width 0.1)
				(type default)
			)
			(layer "F.SilkS")
		)
		(fp_line
			(start 25.701498 -4.628388)
			(end 24.658574 -3.627882)
			(stroke
				(width 0.1)
				(type default)
			)
			(layer "F.SilkS")
		)
		(fp_line
			(start 25.701498 -4.628388)
			(end 24.658574 -3.627882)
			(stroke
				(width 0.1)
				(type default)
			)
			(layer "F.SilkS")
		)
		(fp_line
			(start 25.708864 -3.19278)
			(end 25.721056 -3.262122)
			(stroke
				(width 0.1)
				(type default)
			)
			(layer "F.SilkS")
		)
		(fp_line
			(start 25.708864 -3.19278)
			(end 25.721056 -3.262122)
			(stroke
				(width 0.1)
				(type default)
			)
			(layer "F.SilkS")
		)
		(fp_line
			(start 25.718516 -4.586986)
			(end 23.913084 -2.85496)
			(stroke
				(width 0.1)
				(type default)
			)
			(layer "F.SilkS")
		)
		(fp_line
			(start 25.718516 -4.586986)
			(end 23.913084 -2.85496)
			(stroke
				(width 0.1)
				(type default)
			)
			(layer "F.SilkS")
		)
		(fp_line
			(start 25.721056 -3.262122)
			(end 25.733502 -3.331464)
			(stroke
				(width 0.1)
				(type default)
			)
			(layer "F.SilkS")
		)
		(fp_line
			(start 25.721056 -3.262122)
			(end 25.733502 -3.331464)
			(stroke
				(width 0.1)
				(type default)
			)
			(layer "F.SilkS")
		)
		(fp_line
			(start 25.733502 -3.331464)
			(end 25.74544 -3.400806)
			(stroke
				(width 0.1)
				(type default)
			)
			(layer "F.SilkS")
		)
		(fp_line
			(start 25.733502 -3.331464)
			(end 25.74544 -3.400806)
			(stroke
				(width 0.1)
				(type default)
			)
			(layer "F.SilkS")
		)
		(fp_line
			(start 25.735534 -4.54533)
			(end 23.969472 -2.85115)
			(stroke
				(width 0.1)
				(type default)
			)
			(layer "F.SilkS")
		)
		(fp_line
			(start 25.735534 -4.54533)
			(end 23.969472 -2.85115)
			(stroke
				(width 0.1)
				(type default)
			)
			(layer "F.SilkS")
		)
		(fp_line
			(start 25.74544 -3.400806)
			(end 23.034752 -0.800608)
			(stroke
				(width 0.1)
				(type default)
			)
			(layer "F.SilkS")
		)
		(fp_line
			(start 25.74544 -3.400806)
			(end 23.034752 -0.800608)
			(stroke
				(width 0.1)
				(type default)
			)
			(layer "F.SilkS")
		)
		(fp_line
			(start 25.74544 -3.400806)
			(end 25.757632 -3.470402)
			(stroke
				(width 0.1)
				(type default)
			)
			(layer "F.SilkS")
		)
		(fp_line
			(start 25.74544 -3.400806)
			(end 25.757632 -3.470402)
			(stroke
				(width 0.1)
				(type default)
			)
			(layer "F.SilkS")
		)
		(fp_line
			(start 25.752298 -4.503928)
			(end 24.024336 -2.846324)
			(stroke
				(width 0.1)
				(type default)
			)
			(layer "F.SilkS")
		)
		(fp_line
			(start 25.752298 -4.503928)
			(end 24.024336 -2.846324)
			(stroke
				(width 0.1)
				(type default)
			)
			(layer "F.SilkS")
		)
		(fp_line
			(start 25.757632 -3.470402)
			(end 24.402796 -2.170938)
			(stroke
				(width 0.1)
				(type default)
			)
			(layer "F.SilkS")
		)
		(fp_line
			(start 25.757632 -3.470402)
			(end 24.402796 -2.170938)
			(stroke
				(width 0.1)
				(type default)
			)
			(layer "F.SilkS")
		)
		(fp_line
			(start 25.757632 -3.470402)
			(end 25.769824 -3.539744)
			(stroke
				(width 0.1)
				(type default)
			)
			(layer "F.SilkS")
		)
		(fp_line
			(start 25.757632 -3.470402)
			(end 25.769824 -3.539744)
			(stroke
				(width 0.1)
				(type default)
			)
			(layer "F.SilkS")
		)
		(fp_line
			(start 25.769316 -4.46278)
			(end 24.076914 -2.839466)
			(stroke
				(width 0.1)
				(type default)
			)
			(layer "F.SilkS")
		)
		(fp_line
			(start 25.769316 -4.46278)
			(end 24.076914 -2.839466)
			(stroke
				(width 0.1)
				(type default)
			)
			(layer "F.SilkS")
		)
		(fp_line
			(start 25.769824 -3.539744)
			(end 24.414988 -2.24028)
			(stroke
				(width 0.1)
				(type default)
			)
			(layer "F.SilkS")
		)
		(fp_line
			(start 25.769824 -3.539744)
			(end 24.414988 -2.24028)
			(stroke
				(width 0.1)
				(type default)
			)
			(layer "F.SilkS")
		)
		(fp_line
			(start 25.769824 -3.539744)
			(end 25.782016 -3.609086)
			(stroke
				(width 0.1)
				(type default)
			)
			(layer "F.SilkS")
		)
		(fp_line
			(start 25.769824 -3.539744)
			(end 25.782016 -3.609086)
			(stroke
				(width 0.1)
				(type default)
			)
			(layer "F.SilkS")
		)
		(fp_line
			(start 25.782016 -3.609086)
			(end 24.427434 -2.309368)
			(stroke
				(width 0.1)
				(type default)
			)
			(layer "F.SilkS")
		)
		(fp_line
			(start 25.782016 -3.609086)
			(end 24.427434 -2.309368)
			(stroke
				(width 0.1)
				(type default)
			)
			(layer "F.SilkS")
		)
		(fp_line
			(start 25.782016 -3.609086)
			(end 25.793954 -3.678174)
			(stroke
				(width 0.1)
				(type default)
			)
			(layer "F.SilkS")
		)
		(fp_line
			(start 25.782016 -3.609086)
			(end 25.793954 -3.678174)
			(stroke
				(width 0.1)
				(type default)
			)
			(layer "F.SilkS")
		)
		(fp_line
			(start 25.786588 -4.421378)
			(end 24.12873 -2.831084)
			(stroke
				(width 0.1)
				(type default)
			)
			(layer "F.SilkS")
		)
		(fp_line
			(start 25.786588 -4.421378)
			(end 24.12873 -2.831084)
			(stroke
				(width 0.1)
				(type default)
			)
			(layer "F.SilkS")
		)
		(fp_line
			(start 25.793954 -3.678174)
			(end 24.439372 -2.37871)
			(stroke
				(width 0.1)
				(type default)
			)
			(layer "F.SilkS")
		)
		(fp_line
			(start 25.793954 -3.678174)
			(end 24.439372 -2.37871)
			(stroke
				(width 0.1)
				(type default)
			)
			(layer "F.SilkS")
		)
		(fp_line
			(start 25.793954 -3.678174)
			(end 25.806146 -3.74777)
			(stroke
				(width 0.1)
				(type default)
			)
			(layer "F.SilkS")
		)
		(fp_line
			(start 25.793954 -3.678174)
			(end 25.806146 -3.74777)
			(stroke
				(width 0.1)
				(type default)
			)
			(layer "F.SilkS")
		)
		(fp_line
			(start 25.798526 -4.37515)
			(end 24.17826 -2.82067)
			(stroke
				(width 0.1)
				(type default)
			)
			(layer "F.SilkS")
		)
		(fp_line
			(start 25.798526 -4.37515)
			(end 24.17826 -2.82067)
			(stroke
				(width 0.1)
				(type default)
			)
			(layer "F.SilkS")
		)
		(fp_line
			(start 25.805384 -4.324096)
			(end 24.225504 -2.808478)
			(stroke
				(width 0.1)
				(type default)
			)
			(layer "F.SilkS")
		)
		(fp_line
			(start 25.805384 -4.324096)
			(end 24.225504 -2.808478)
			(stroke
				(width 0.1)
				(type default)
			)
			(layer "F.SilkS")
		)
		(fp_line
			(start 25.806146 -3.74777)
			(end 24.451564 -2.448306)
			(stroke
				(width 0.1)
				(type default)
			)
			(layer "F.SilkS")
		)
		(fp_line
			(start 25.806146 -3.74777)
			(end 24.451564 -2.448306)
			(stroke
				(width 0.1)
				(type default)
			)
			(layer "F.SilkS")
		)
		(fp_line
			(start 25.812242 -4.273296)
			(end 24.27097 -2.794508)
			(stroke
				(width 0.1)
				(type default)
			)
			(layer "F.SilkS")
		)
		(fp_line
			(start 25.812242 -4.273296)
			(end 24.27097 -2.794508)
			(stroke
				(width 0.1)
				(type default)
			)
			(layer "F.SilkS")
		)
		(fp_line
			(start 25.81275 -3.811524)
			(end 24.46401 -2.517648)
			(stroke
				(width 0.1)
				(type default)
			)
			(layer "F.SilkS")
		)
		(fp_line
			(start 25.81275 -3.811524)
			(end 24.46401 -2.517648)
			(stroke
				(width 0.1)
				(type default)
			)
			(layer "F.SilkS")
		)
		(fp_line
			(start 25.817576 -3.874008)
			(end 24.475948 -2.58699)
			(stroke
				(width 0.1)
				(type default)
			)
			(layer "F.SilkS")
		)
		(fp_line
			(start 25.817576 -3.874008)
			(end 24.475948 -2.58699)
			(stroke
				(width 0.1)
				(type default)
			)
			(layer "F.SilkS")
		)
		(fp_line
			(start 25.819608 -4.222242)
			(end 24.31415 -2.777998)
			(stroke
				(width 0.1)
				(type default)
			)
			(layer "F.SilkS")
		)
		(fp_line
			(start 25.819608 -4.222242)
			(end 24.31415 -2.777998)
			(stroke
				(width 0.1)
				(type default)
			)
			(layer "F.SilkS")
		)
		(fp_line
			(start 25.822656 -3.936492)
			(end 24.487886 -2.656332)
			(stroke
				(width 0.1)
				(type default)
			)
			(layer "F.SilkS")
		)
		(fp_line
			(start 25.822656 -3.936492)
			(end 24.487886 -2.656332)
			(stroke
				(width 0.1)
				(type default)
			)
			(layer "F.SilkS")
		)
		(fp_line
			(start 25.826466 -4.170934)
			(end 24.35606 -2.760472)
			(stroke
				(width 0.1)
				(type default)
			)
			(layer "F.SilkS")
		)
		(fp_line
			(start 25.826466 -4.170934)
			(end 24.35606 -2.760472)
			(stroke
				(width 0.1)
				(type default)
			)
			(layer "F.SilkS")
		)
		(fp_line
			(start 25.827736 -3.99923)
			(end 24.468836 -2.695448)
			(stroke
				(width 0.1)
				(type default)
			)
			(layer "F.SilkS")
		)
		(fp_line
			(start 25.827736 -3.99923)
			(end 24.468836 -2.695448)
			(stroke
				(width 0.1)
				(type default)
			)
			(layer "F.SilkS")
		)
		(fp_line
			(start 25.83307 -4.062222)
			(end 24.432514 -2.718816)
			(stroke
				(width 0.1)
				(type default)
			)
			(layer "F.SilkS")
		)
		(fp_line
			(start 25.83307 -4.062222)
			(end 24.432514 -2.718816)
			(stroke
				(width 0.1)
				(type default)
			)
			(layer "F.SilkS")
		)
		(fp_line
			(start 25.833324 -4.120134)
			(end 24.394668 -2.739898)
			(stroke
				(width 0.1)
				(type default)
			)
			(layer "F.SilkS")
		)
		(fp_line
			(start 25.833324 -4.120134)
			(end 24.394668 -2.739898)
			(stroke
				(width 0.1)
				(type default)
			)
			(layer "F.SilkS")
		)
	)
	(footprint ""
		(layer "F.Cu")
		(at 111.332772 -128.075182)
		(property "Reference" "R3536"
			(at 0 0 0)
			(layer "F.SilkS")
			(hide yes)
			(effects
				(font
					(size 1.27 1.27)
				)
			)
		)
		(property "Value" ""
			(at 0 0 0)
			(layer "F.Fab")
			(effects
				(font
					(size 1.27 1.27)
				)
			)
		)
		(duplicate_pad_numbers_are_jumpers no)
		(fp_line
			(start -0.7874 -0.4064)
			(end 0.7874 -0.4064)
			(stroke
				(width 0.1524)
				(type default)
			)
			(layer "F.SilkS")
		)
		(fp_line
			(start -0.7874 0.4064)
			(end -0.7874 -0.4064)
			(stroke
				(width 0.1524)
				(type default)
			)
			(layer "F.SilkS")
		)
		(fp_line
			(start 0.7874 -0.4064)
			(end 0.7874 0.4064)
			(stroke
				(width 0.1524)
				(type default)
			)
			(layer "F.SilkS")
		)
		(fp_line
			(start 0.7874 0.4064)
			(end -0.7874 0.4064)
			(stroke
				(width 0.1524)
				(type default)
			)
			(layer "F.SilkS")
		)
		(fp_line
			(start -0.67945 -0.305054)
			(end -0.12065 -0.305054)
			(stroke
				(width 0.1)
				(type default)
			)
			(layer "F.Fab")
		)
		(fp_line
			(start -0.67945 0.3048)
			(end -0.67945 -0.305054)
			(stroke
				(width 0.1)
				(type default)
			)
			(layer "F.Fab")
		)
		(fp_line
			(start -0.12065 -0.305054)
			(end -0.12065 -0.2794)
			(stroke
				(width 0.1)
				(type default)
			)
			(layer "F.Fab")
		)
		(fp_line
			(start -0.12065 -0.2794)
			(end 0.12065 -0.2794)
			(stroke
				(width 0.1)
				(type default)
			)
			(layer "F.Fab")
		)
		(fp_line
			(start -0.12065 0.2794)
			(end -0.12065 0.3048)
			(stroke
				(width 0.1)
				(type default)
			)
			(layer "F.Fab")
		)
		(fp_line
			(start -0.12065 0.3048)
			(end -0.67945 0.3048)
			(stroke
				(width 0.1)
				(type default)
			)
			(layer "F.Fab")
		)
		(fp_line
			(start 0.120396 0.2794)
			(end -0.12065 0.2794)
			(stroke
				(width 0.1)
				(type default)
			)
			(layer "F.Fab")
		)
		(fp_line
			(start 0.120396 0.3048)
			(end 0.120396 0.2794)
			(stroke
				(width 0.1)
				(type default)
			)
			(layer "F.Fab")
		)
		(fp_line
			(start 0.12065 -0.3048)
			(end 0.67945 -0.3048)
			(stroke
				(width 0.1)
				(type default)
			)
			(layer "F.Fab")
		)
		(fp_line
			(start 0.12065 -0.2794)
			(end 0.12065 -0.3048)
			(stroke
				(width 0.1)
				(type default)
			)
			(layer "F.Fab")
		)
		(fp_line
			(start 0.67945 -0.3048)
			(end 0.67945 0.3048)
			(stroke
				(width 0.1)
				(type default)
			)
			(layer "F.Fab")
		)
		(fp_line
			(start 0.67945 0.3048)
			(end 0.120396 0.3048)
			(stroke
				(width 0.1)
				(type default)
			)
			(layer "F.Fab")
		)
		(pad "1" smd circle
			(at -0.40005 0)
			(size 0 0)
			(layers "F.Cu" "F.Mask" "F.Paste")
			(net "P3V3_AUX")
		)
		(pad "2" smd circle
			(at 0.40005 0)
			(size 0 0)
			(layers "F.Cu" "F.Mask" "F.Paste")
			(net "SMB_SENSOR_E1S_3V3AUX_SDA")
		)
	)
	(footprint ""
		(layer "F.Cu")
		(at 239.152684 -53.821838 180)
		(property "Reference" "C1993"
			(at 0 0 180)
			(layer "F.SilkS")
			(hide yes)
			(effects
				(font
					(size 1.27 1.27)
				)
			)
		)
		(property "Value" ""
			(at 0 0 180)
			(layer "F.Fab")
			(effects
				(font
					(size 1.27 1.27)
				)
			)
		)
		(duplicate_pad_numbers_are_jumpers no)
		(fp_line
			(start 0.299974 0.150114)
			(end -0.299974 0.150114)
			(stroke
				(width 0.1)
				(type default)
			)
			(layer "F.Fab")
		)
		(fp_line
			(start 0.299974 -0.150114)
			(end 0.299974 0.150114)
			(stroke
				(width 0.1)
				(type default)
			)
			(layer "F.Fab")
		)
		(fp_line
			(start -0.299974 0.150114)
			(end -0.299974 -0.150114)
			(stroke
				(width 0.1)
				(type default)
			)
			(layer "F.Fab")
		)
		(fp_line
			(start -0.299974 -0.150114)
			(end 0.299974 -0.150114)
			(stroke
				(width 0.1)
				(type default)
			)
			(layer "F.Fab")
		)
		(pad "1" smd rect
			(at -0.2667 0 180)
			(size 0.3048 0.381)
			(layers "F.Cu" "F.Mask" "F.Paste")
			(net "P3E_PCH_E1S_TX_DP<1>")
		)
		(pad "2" smd rect
			(at 0.2667 0 180)
			(size 0.3048 0.381)
			(layers "F.Cu" "F.Mask" "F.Paste")
			(net "P3E_PCH_E1S_TX_C_DP<1>")
		)
		(zone
			(layer "In1.Cu")
			(hatch none 0.5)
			(connect_pads
				(clearance 0)
			)
			(min_thickness 0.25)
			(keepout
				(tracks not_allowed)
				(vias allowed)
				(pads allowed)
				(copperpour not_allowed)
				(footprints allowed)
			)
			(placement
				(enabled no)
				(sheetname "")
			)
			(fill
				(thermal_gap 0.5)
				(thermal_bridge_width 0.5)
				(island_removal_mode 0)
			)
			(polygon
				(pts
					(arc
						(start 239.012984 -54.062122)
						(mid 239.066866 -54.039804)
						(end 239.089184 -53.985922)
					)
					(arc
						(start 239.089184 -53.655722)
						(mid 239.066866 -53.60184)
						(end 239.012984 -53.579522)
					)
					(arc
						(start 238.758984 -53.579522)
						(mid 238.705102 -53.60184)
						(end 238.682784 -53.655722)
					)
					(arc
						(start 238.682784 -53.985922)
						(mid 238.705102 -54.039804)
						(end 238.758984 -54.062122)
					)
				)
			)
		)
		(zone
			(layer "In1.Cu")
			(hatch none 0.5)
			(connect_pads
				(clearance 0)
			)
			(min_thickness 0.25)
			(keepout
				(tracks not_allowed)
				(vias allowed)
				(pads allowed)
				(copperpour not_allowed)
				(footprints allowed)
			)
			(placement
				(enabled no)
				(sheetname "")
			)
			(fill
				(thermal_gap 0.5)
				(thermal_bridge_width 0.5)
				(island_removal_mode 0)
			)
			(polygon
				(pts
					(arc
						(start 239.546384 -54.062122)
						(mid 239.600266 -54.039804)
						(end 239.622584 -53.985922)
					)
					(arc
						(start 239.622584 -53.655722)
						(mid 239.600266 -53.60184)
						(end 239.546384 -53.579522)
					)
					(arc
						(start 239.292384 -53.579522)
						(mid 239.238502 -53.60184)
						(end 239.216184 -53.655722)
					)
					(arc
						(start 239.216184 -53.985922)
						(mid 239.238502 -54.039804)
						(end 239.292384 -54.062122)
					)
				)
			)
		)
	)
	(footprint ""
		(layer "F.Cu")
		(at 53.87848 -433.898548 -90)
		(property "Reference" "R3227"
			(at 0 0 270)
			(layer "F.SilkS")
			(hide yes)
			(effects
				(font
					(size 1.27 1.27)
				)
			)
		)
		(property "Value" ""
			(at 0 0 270)
			(layer "F.Fab")
			(effects
				(font
					(size 1.27 1.27)
				)
			)
		)
		(duplicate_pad_numbers_are_jumpers no)
		(fp_line
			(start -0.7874 0.4064)
			(end -0.7874 -0.4064)
			(stroke
				(width 0.1524)
				(type default)
			)
			(layer "F.SilkS")
		)
		(fp_line
			(start 0.7874 0.4064)
			(end -0.7874 0.4064)
			(stroke
				(width 0.1524)
				(type default)
			)
			(layer "F.SilkS")
		)
		(fp_line
			(start -0.7874 -0.4064)
			(end 0.7874 -0.4064)
			(stroke
				(width 0.1524)
				(type default)
			)
			(layer "F.SilkS")
		)
		(fp_line
			(start 0.7874 -0.4064)
			(end 0.7874 0.4064)
			(stroke
				(width 0.1524)
				(type default)
			)
			(layer "F.SilkS")
		)
		(fp_line
			(start -0.67945 0.3048)
			(end -0.67945 -0.305054)
			(stroke
				(width 0.1)
				(type default)
			)
			(layer "F.Fab")
		)
		(fp_line
			(start -0.12065 0.3048)
			(end -0.67945 0.3048)
			(stroke
				(width 0.1)
				(type default)
			)
			(layer "F.Fab")
		)
		(fp_line
			(start 0.120396 0.3048)
			(end 0.120396 0.2794)
			(stroke
				(width 0.1)
				(type default)
			)
			(layer "F.Fab")
		)
		(fp_line
			(start 0.67945 0.3048)
			(end 0.120396 0.3048)
			(stroke
				(width 0.1)
				(type default)
			)
			(layer "F.Fab")
		)
		(fp_line
			(start -0.12065 0.2794)
			(end -0.12065 0.3048)
			(stroke
				(width 0.1)
				(type default)
			)
			(layer "F.Fab")
		)
		(fp_line
			(start 0.120396 0.2794)
			(end -0.12065 0.2794)
			(stroke
				(width 0.1)
				(type default)
			)
			(layer "F.Fab")
		)
		(fp_line
			(start -0.12065 -0.2794)
			(end 0.12065 -0.2794)
			(stroke
				(width 0.1)
				(type default)
			)
			(layer "F.Fab")
		)
		(fp_line
			(start 0.12065 -0.2794)
			(end 0.12065 -0.3048)
			(stroke
				(width 0.1)
				(type default)
			)
			(layer "F.Fab")
		)
		(fp_line
			(start 0.12065 -0.3048)
			(end 0.67945 -0.3048)
			(stroke
				(width 0.1)
				(type default)
			)
			(layer "F.Fab")
		)
		(fp_line
			(start 0.67945 -0.3048)
			(end 0.67945 0.3048)
			(stroke
				(width 0.1)
				(type default)
			)
			(layer "F.Fab")
		)
		(fp_line
			(start -0.67945 -0.305054)
			(end -0.12065 -0.305054)
			(stroke
				(width 0.1)
				(type default)
			)
			(layer "F.Fab")
		)
		(fp_line
			(start -0.12065 -0.305054)
			(end -0.12065 -0.2794)
			(stroke
				(width 0.1)
				(type default)
			)
			(layer "F.Fab")
		)
		(pad "1" smd circle
			(at -0.40005 0 270)
			(size 0 0)
			(layers "F.Cu" "F.Mask" "F.Paste")
			(net "SMB_1_BMC_GPU_SDA")
		)
		(pad "2" smd circle
			(at 0.40005 0 270)
			(size 0 0)
			(layers "F.Cu" "F.Mask" "F.Paste")
			(net "P3V3_AUX")
		)
	)
	(footprint ""
		(layer "F.Cu")
		(at 385.716272 -66.704464 180)
		(property "Reference" "C547"
			(at 0 0 180)
			(layer "F.SilkS")
			(hide yes)
			(effects
				(font
					(size 1.27 1.27)
				)
			)
		)
		(property "Value" ""
			(at 0 0 180)
			(layer "F.Fab")
			(effects
				(font
					(size 1.27 1.27)
				)
			)
		)
		(duplicate_pad_numbers_are_jumpers no)
		(fp_line
			(start 0.7874 0.4064)
			(end -0.7874 0.4064)
			(stroke
				(width 0.1524)
				(type default)
			)
			(layer "F.SilkS")
		)
		(fp_line
			(start 0.7874 -0.4064)
			(end 0.7874 0.4064)
			(stroke
				(width 0.1524)
				(type default)
			)
			(layer "F.SilkS")
		)
		(fp_line
			(start -0.7874 0.4064)
			(end -0.7874 -0.4064)
			(stroke
				(width 0.1524)
				(type default)
			)
			(layer "F.SilkS")
		)
		(fp_line
			(start -0.7874 -0.4064)
			(end 0.7874 -0.4064)
			(stroke
				(width 0.1524)
				(type default)
			)
			(layer "F.SilkS")
		)
		(fp_line
			(start 0.67945 0.3048)
			(end 0.120396 0.3048)
			(stroke
				(width 0.1)
				(type default)
			)
			(layer "F.Fab")
		)
		(fp_line
			(start 0.67945 -0.3048)
			(end 0.67945 0.3048)
			(stroke
				(width 0.1)
				(type default)
			)
			(layer "F.Fab")
		)
		(fp_line
			(start 0.12065 -0.2794)
			(end 0.12065 -0.3048)
			(stroke
				(width 0.1)
				(type default)
			)
			(layer "F.Fab")
		)
		(fp_line
			(start 0.12065 -0.3048)
			(end 0.67945 -0.3048)
			(stroke
				(width 0.1)
				(type default)
			)
			(layer "F.Fab")
		)
		(fp_line
			(start 0.120396 0.3048)
			(end 0.120396 0.2794)
			(stroke
				(width 0.1)
				(type default)
			)
			(layer "F.Fab")
		)
		(fp_line
			(start 0.120396 0.2794)
			(end -0.12065 0.2794)
			(stroke
				(width 0.1)
				(type default)
			)
			(layer "F.Fab")
		)
		(fp_line
			(start -0.12065 0.3048)
			(end -0.67945 0.3048)
			(stroke
				(width 0.1)
				(type default)
			)
			(layer "F.Fab")
		)
		(fp_line
			(start -0.12065 0.2794)
			(end -0.12065 0.3048)
			(stroke
				(width 0.1)
				(type default)
			)
			(layer "F.Fab")
		)
		(fp_line
			(start -0.12065 -0.2794)
			(end 0.12065 -0.2794)
			(stroke
				(width 0.1)
				(type default)
			)
			(layer "F.Fab")
		)
		(fp_line
			(start -0.12065 -0.305054)
			(end -0.12065 -0.2794)
			(stroke
				(width 0.1)
				(type default)
			)
			(layer "F.Fab")
		)
		(fp_line
			(start -0.67945 0.3048)
			(end -0.67945 -0.305054)
			(stroke
				(width 0.1)
				(type default)
			)
			(layer "F.Fab")
		)
		(fp_line
			(start -0.67945 -0.305054)
			(end -0.12065 -0.305054)
			(stroke
				(width 0.1)
				(type default)
			)
			(layer "F.Fab")
		)
		(pad "1" smd circle
			(at -0.40005 0 180)
			(size 0 0)
			(layers "F.Cu" "F.Mask" "F.Paste")
			(net "P1V05_PCH_AUX")
		)
		(pad "2" smd circle
			(at 0.40005 0 180)
			(size 0 0)
			(layers "F.Cu" "F.Mask" "F.Paste")
			(net "GND")
		)
	)
	(footprint ""
		(layer "F.Cu")
		(at 9.58088 -61.051948)
		(property "Reference" "R3058"
			(at 0 0 0)
			(layer "F.SilkS")
			(hide yes)
			(effects
				(font
					(size 1.27 1.27)
				)
			)
		)
		(property "Value" ""
			(at 0 0 0)
			(layer "F.Fab")
			(effects
				(font
					(size 1.27 1.27)
				)
			)
		)
		(duplicate_pad_numbers_are_jumpers no)
		(fp_line
			(start -0.7874 -0.4064)
			(end 0.7874 -0.4064)
			(stroke
				(width 0.1524)
				(type default)
			)
			(layer "F.SilkS")
		)
		(fp_line
			(start -0.7874 0.4064)
			(end -0.7874 -0.4064)
			(stroke
				(width 0.1524)
				(type default)
			)
			(layer "F.SilkS")
		)
		(fp_line
			(start 0.7874 -0.4064)
			(end 0.7874 0.4064)
			(stroke
				(width 0.1524)
				(type default)
			)
			(layer "F.SilkS")
		)
		(fp_line
			(start 0.7874 0.4064)
			(end -0.7874 0.4064)
			(stroke
				(width 0.1524)
				(type default)
			)
			(layer "F.SilkS")
		)
		(fp_line
			(start -0.67945 -0.305054)
			(end -0.12065 -0.305054)
			(stroke
				(width 0.1)
				(type default)
			)
			(layer "F.Fab")
		)
		(fp_line
			(start -0.67945 0.3048)
			(end -0.67945 -0.305054)
			(stroke
				(width 0.1)
				(type default)
			)
			(layer "F.Fab")
		)
		(fp_line
			(start -0.12065 -0.305054)
			(end -0.12065 -0.2794)
			(stroke
				(width 0.1)
				(type default)
			)
			(layer "F.Fab")
		)
		(fp_line
			(start -0.12065 -0.2794)
			(end 0.12065 -0.2794)
			(stroke
				(width 0.1)
				(type default)
			)
			(layer "F.Fab")
		)
		(fp_line
			(start -0.12065 0.2794)
			(end -0.12065 0.3048)
			(stroke
				(width 0.1)
				(type default)
			)
			(layer "F.Fab")
		)
		(fp_line
			(start -0.12065 0.3048)
			(end -0.67945 0.3048)
			(stroke
				(width 0.1)
				(type default)
			)
			(layer "F.Fab")
		)
		(fp_line
			(start 0.120396 0.2794)
			(end -0.12065 0.2794)
			(stroke
				(width 0.1)
				(type default)
			)
			(layer "F.Fab")
		)
		(fp_line
			(start 0.120396 0.3048)
			(end 0.120396 0.2794)
			(stroke
				(width 0.1)
				(type default)
			)
			(layer "F.Fab")
		)
		(fp_line
			(start 0.12065 -0.3048)
			(end 0.67945 -0.3048)
			(stroke
				(width 0.1)
				(type default)
			)
			(layer "F.Fab")
		)
		(fp_line
			(start 0.12065 -0.2794)
			(end 0.12065 -0.3048)
			(stroke
				(width 0.1)
				(type default)
			)
			(layer "F.Fab")
		)
		(fp_line
			(start 0.67945 -0.3048)
			(end 0.67945 0.3048)
			(stroke
				(width 0.1)
				(type default)
			)
			(layer "F.Fab")
		)
		(fp_line
			(start 0.67945 0.3048)
			(end 0.120396 0.3048)
			(stroke
				(width 0.1)
				(type default)
			)
			(layer "F.Fab")
		)
		(pad "1" smd circle
			(at -0.40005 0)
			(size 0 0)
			(layers "F.Cu" "F.Mask" "F.Paste")
			(net "SMB_SML0_3V3AUX_SCL")
		)
		(pad "2" smd circle
			(at 0.40005 0)
			(size 0 0)
			(layers "F.Cu" "F.Mask" "F.Paste")
			(net "SMB_SML0_ME_SCL")
		)
	)
	(footprint ""
		(layer "F.Cu")
		(at 20.60956 -72.710548)
		(property "Reference" "R3134"
			(at 0 0 0)
			(layer "F.SilkS")
			(hide yes)
			(effects
				(font
					(size 1.27 1.27)
				)
			)
		)
		(property "Value" ""
			(at 0 0 0)
			(layer "F.Fab")
			(effects
				(font
					(size 1.27 1.27)
				)
			)
		)
		(duplicate_pad_numbers_are_jumpers no)
		(fp_line
			(start -0.7874 -0.4064)
			(end 0.7874 -0.4064)
			(stroke
				(width 0.1524)
				(type default)
			)
			(layer "F.SilkS")
		)
		(fp_line
			(start -0.7874 0.4064)
			(end -0.7874 -0.4064)
			(stroke
				(width 0.1524)
				(type default)
			)
			(layer "F.SilkS")
		)
		(fp_line
			(start 0.7874 -0.4064)
			(end 0.7874 0.4064)
			(stroke
				(width 0.1524)
				(type default)
			)
			(layer "F.SilkS")
		)
		(fp_line
			(start 0.7874 0.4064)
			(end -0.7874 0.4064)
			(stroke
				(width 0.1524)
				(type default)
			)
			(layer "F.SilkS")
		)
		(fp_line
			(start -0.67945 -0.305054)
			(end -0.12065 -0.305054)
			(stroke
				(width 0.1)
				(type default)
			)
			(layer "F.Fab")
		)
		(fp_line
			(start -0.67945 0.3048)
			(end -0.67945 -0.305054)
			(stroke
				(width 0.1)
				(type default)
			)
			(layer "F.Fab")
		)
		(fp_line
			(start -0.12065 -0.305054)
			(end -0.12065 -0.2794)
			(stroke
				(width 0.1)
				(type default)
			)
			(layer "F.Fab")
		)
		(fp_line
			(start -0.12065 -0.2794)
			(end 0.12065 -0.2794)
			(stroke
				(width 0.1)
				(type default)
			)
			(layer "F.Fab")
		)
		(fp_line
			(start -0.12065 0.2794)
			(end -0.12065 0.3048)
			(stroke
				(width 0.1)
				(type default)
			)
			(layer "F.Fab")
		)
		(fp_line
			(start -0.12065 0.3048)
			(end -0.67945 0.3048)
			(stroke
				(width 0.1)
				(type default)
			)
			(layer "F.Fab")
		)
		(fp_line
			(start 0.120396 0.2794)
			(end -0.12065 0.2794)
			(stroke
				(width 0.1)
				(type default)
			)
			(layer "F.Fab")
		)
		(fp_line
			(start 0.120396 0.3048)
			(end 0.120396 0.2794)
			(stroke
				(width 0.1)
				(type default)
			)
			(layer "F.Fab")
		)
		(fp_line
			(start 0.12065 -0.3048)
			(end 0.67945 -0.3048)
			(stroke
				(width 0.1)
				(type default)
			)
			(layer "F.Fab")
		)
		(fp_line
			(start 0.12065 -0.2794)
			(end 0.12065 -0.3048)
			(stroke
				(width 0.1)
				(type default)
			)
			(layer "F.Fab")
		)
		(fp_line
			(start 0.67945 -0.3048)
			(end 0.67945 0.3048)
			(stroke
				(width 0.1)
				(type default)
			)
			(layer "F.Fab")
		)
		(fp_line
			(start 0.67945 0.3048)
			(end 0.120396 0.3048)
			(stroke
				(width 0.1)
				(type default)
			)
			(layer "F.Fab")
		)
		(pad "1" smd circle
			(at -0.40005 0)
			(size 0 0)
			(layers "F.Cu" "F.Mask" "F.Paste")
			(net "P3V3_AUX")
		)
		(pad "2" smd circle
			(at 0.40005 0)
			(size 0 0)
			(layers "F.Cu" "F.Mask" "F.Paste")
			(net "OCP_V3_2_PRSNT2_R_N")
		)
	)
	(footprint ""
		(layer "F.Cu")
		(at 172.8724 -94.338648 90)
		(property "Reference" "R4581"
			(at 0 0 90)
			(layer "F.SilkS")
			(hide yes)
			(effects
				(font
					(size 1.27 1.27)
				)
			)
		)
		(property "Value" ""
			(at 0 0 90)
			(layer "F.Fab")
			(effects
				(font
					(size 1.27 1.27)
				)
			)
		)
		(duplicate_pad_numbers_are_jumpers no)
		(fp_line
			(start 0.7874 -0.4064)
			(end 0.7874 0.4064)
			(stroke
				(width 0.1524)
				(type default)
			)
			(layer "F.SilkS")
		)
		(fp_line
			(start -0.7874 -0.4064)
			(end 0.7874 -0.4064)
			(stroke
				(width 0.1524)
				(type default)
			)
			(layer "F.SilkS")
		)
		(fp_line
			(start 0.7874 0.4064)
			(end -0.7874 0.4064)
			(stroke
				(width 0.1524)
				(type default)
			)
			(layer "F.SilkS")
		)
		(fp_line
			(start -0.7874 0.4064)
			(end -0.7874 -0.4064)
			(stroke
				(width 0.1524)
				(type default)
			)
			(layer "F.SilkS")
		)
		(fp_line
			(start -0.12065 -0.305054)
			(end -0.12065 -0.2794)
			(stroke
				(width 0.1)
				(type default)
			)
			(layer "F.Fab")
		)
		(fp_line
			(start -0.67945 -0.305054)
			(end -0.12065 -0.305054)
			(stroke
				(width 0.1)
				(type default)
			)
			(layer "F.Fab")
		)
		(fp_line
			(start 0.67945 -0.3048)
			(end 0.67945 0.3048)
			(stroke
				(width 0.1)
				(type default)
			)
			(layer "F.Fab")
		)
		(fp_line
			(start 0.12065 -0.3048)
			(end 0.67945 -0.3048)
			(stroke
				(width 0.1)
				(type default)
			)
			(layer "F.Fab")
		)
		(fp_line
			(start 0.12065 -0.2794)
			(end 0.12065 -0.3048)
			(stroke
				(width 0.1)
				(type default)
			)
			(layer "F.Fab")
		)
		(fp_line
			(start -0.12065 -0.2794)
			(end 0.12065 -0.2794)
			(stroke
				(width 0.1)
				(type default)
			)
			(layer "F.Fab")
		)
		(fp_line
			(start 0.120396 0.2794)
			(end -0.12065 0.2794)
			(stroke
				(width 0.1)
				(type default)
			)
			(layer "F.Fab")
		)
		(fp_line
			(start -0.12065 0.2794)
			(end -0.12065 0.3048)
			(stroke
				(width 0.1)
				(type default)
			)
			(layer "F.Fab")
		)
		(fp_line
			(start 0.67945 0.3048)
			(end 0.120396 0.3048)
			(stroke
				(width 0.1)
				(type default)
			)
			(layer "F.Fab")
		)
		(fp_line
			(start 0.120396 0.3048)
			(end 0.120396 0.2794)
			(stroke
				(width 0.1)
				(type default)
			)
			(layer "F.Fab")
		)
		(fp_line
			(start -0.12065 0.3048)
			(end -0.67945 0.3048)
			(stroke
				(width 0.1)
				(type default)
			)
			(layer "F.Fab")
		)
		(fp_line
			(start -0.67945 0.3048)
			(end -0.67945 -0.305054)
			(stroke
				(width 0.1)
				(type default)
			)
			(layer "F.Fab")
		)
		(pad "1" smd rect
			(at -0.40005 0 270)
			(size 0.4572 0.508)
			(layers "F.Cu" "F.Mask" "F.Paste")
			(net "FM_BOARD_BMC_SKU_ID4")
		)
		(pad "2" smd rect
			(at 0.40005 0 270)
			(size 0.4572 0.508)
			(layers "F.Cu" "F.Mask" "F.Paste")
			(net "GND")
		)
	)
	(footprint ""
		(layer "F.Cu")
		(at 81.739486 -142.041372 180)
		(property "Reference" "R676"
			(at 0 0 180)
			(layer "F.SilkS")
			(hide yes)
			(effects
				(font
					(size 1.27 1.27)
				)
			)
		)
		(property "Value" ""
			(at 0 0 180)
			(layer "F.Fab")
			(effects
				(font
					(size 1.27 1.27)
				)
			)
		)
		(duplicate_pad_numbers_are_jumpers no)
		(fp_line
			(start 0.7874 0.4064)
			(end -0.7874 0.4064)
			(stroke
				(width 0.1524)
				(type default)
			)
			(layer "F.SilkS")
		)
		(fp_line
			(start 0.7874 -0.4064)
			(end 0.7874 0.4064)
			(stroke
				(width 0.1524)
				(type default)
			)
			(layer "F.SilkS")
		)
		(fp_line
			(start -0.7874 0.4064)
			(end -0.7874 -0.4064)
			(stroke
				(width 0.1524)
				(type default)
			)
			(layer "F.SilkS")
		)
		(fp_line
			(start -0.7874 -0.4064)
			(end 0.7874 -0.4064)
			(stroke
				(width 0.1524)
				(type default)
			)
			(layer "F.SilkS")
		)
		(fp_line
			(start 0.67945 0.3048)
			(end 0.120396 0.3048)
			(stroke
				(width 0.1)
				(type default)
			)
			(layer "F.Fab")
		)
		(fp_line
			(start 0.67945 -0.3048)
			(end 0.67945 0.3048)
			(stroke
				(width 0.1)
				(type default)
			)
			(layer "F.Fab")
		)
		(fp_line
			(start 0.12065 -0.2794)
			(end 0.12065 -0.3048)
			(stroke
				(width 0.1)
				(type default)
			)
			(layer "F.Fab")
		)
		(fp_line
			(start 0.12065 -0.3048)
			(end 0.67945 -0.3048)
			(stroke
				(width 0.1)
				(type default)
			)
			(layer "F.Fab")
		)
		(fp_line
			(start 0.120396 0.3048)
			(end 0.120396 0.2794)
			(stroke
				(width 0.1)
				(type default)
			)
			(layer "F.Fab")
		)
		(fp_line
			(start 0.120396 0.2794)
			(end -0.12065 0.2794)
			(stroke
				(width 0.1)
				(type default)
			)
			(layer "F.Fab")
		)
		(fp_line
			(start -0.12065 0.3048)
			(end -0.67945 0.3048)
			(stroke
				(width 0.1)
				(type default)
			)
			(layer "F.Fab")
		)
		(fp_line
			(start -0.12065 0.2794)
			(end -0.12065 0.3048)
			(stroke
				(width 0.1)
				(type default)
			)
			(layer "F.Fab")
		)
		(fp_line
			(start -0.12065 -0.2794)
			(end 0.12065 -0.2794)
			(stroke
				(width 0.1)
				(type default)
			)
			(layer "F.Fab")
		)
		(fp_line
			(start -0.12065 -0.305054)
			(end -0.12065 -0.2794)
			(stroke
				(width 0.1)
				(type default)
			)
			(layer "F.Fab")
		)
		(fp_line
			(start -0.67945 0.3048)
			(end -0.67945 -0.305054)
			(stroke
				(width 0.1)
				(type default)
			)
			(layer "F.Fab")
		)
		(fp_line
			(start -0.67945 -0.305054)
			(end -0.12065 -0.305054)
			(stroke
				(width 0.1)
				(type default)
			)
			(layer "F.Fab")
		)
		(pad "1" smd circle
			(at -0.40005 0 180)
			(size 0 0)
			(layers "F.Cu" "F.Mask" "F.Paste")
			(net "I3C_SPD_DDREFGH_CPU1_LVC1_R_SCL")
		)
		(pad "2" smd circle
			(at 0.40005 0 180)
			(size 0 0)
			(layers "F.Cu" "F.Mask" "F.Paste")
			(net "I3C_SPD_DDREFGH_CPU1_LVC1_SCL")
		)
	)
	(footprint ""
		(layer "F.Cu")
		(at 366.644428 -362.786422 -90)
		(property "Reference" "PU173"
			(at -3.372866 0.046482 0)
			(unlocked yes)
			(layer "F.SilkS")
			(effects
				(font
					(size 0.7874 0.5842)
					(thickness 0.1524)
				)
			)
		)
		(property "Value" ""
			(at 0 0 270)
			(layer "F.Fab")
			(effects
				(font
					(size 1.27 1.27)
				)
			)
		)
		(duplicate_pad_numbers_are_jumpers no)
		(fp_line
			(start -1.949958 1.610106)
			(end -1.949958 -1.610106)
			(stroke
				(width 0.1524)
				(type default)
			)
			(layer "F.SilkS")
		)
		(fp_line
			(start 1.105662 1.610106)
			(end -1.949958 1.610106)
			(stroke
				(width 0.1524)
				(type default)
			)
			(layer "F.SilkS")
		)
		(fp_line
			(start 1.949958 -1.560068)
			(end 1.949958 0.953008)
			(stroke
				(width 0.1524)
				(type default)
			)
			(layer "F.SilkS")
		)
		(fp_line
			(start -1.949958 -1.610106)
			(end 1.949958 -1.610106)
			(stroke
				(width 0.1524)
				(type default)
			)
			(layer "F.SilkS")
		)
		(fp_line
			(start -0.750062 1.560068)
			(end -0.750062 -1.560068)
			(stroke
				(width 0.1)
				(type default)
			)
			(layer "F.Fab")
		)
		(fp_line
			(start 0.750062 1.560068)
			(end -0.750062 1.560068)
			(stroke
				(width 0.1)
				(type default)
			)
			(layer "F.Fab")
		)
		(fp_line
			(start -0.750062 -1.560068)
			(end 0.750062 -1.560068)
			(stroke
				(width 0.1)
				(type default)
			)
			(layer "F.Fab")
		)
		(fp_line
			(start 0.750062 -1.560068)
			(end 0.750062 1.560068)
			(stroke
				(width 0.1)
				(type default)
			)
			(layer "F.Fab")
		)
		(pad "D" smd rect
			(at 1.100074 0 180)
			(size 1.016 1.4224)
			(layers "F.Cu" "F.Mask" "F.Paste")
			(net "FM_HBM_VPP_SEL_CPU0_D")
		)
		(pad "G" smd rect
			(at -1.100074 -0.94996 180)
			(size 1.016 1.4224)
			(layers "F.Cu" "F.Mask" "F.Paste")
			(net "FM_HBM2_HBM3_VPP_SEL")
		)
		(pad "S" smd rect
			(at -1.100074 0.94996 180)
			(size 1.016 1.4224)
			(layers "F.Cu" "F.Mask" "F.Paste")
			(net "SH_PVPP_HBM_CPU0_N")
		)
	)
	(footprint ""
		(layer "F.Cu")
		(at 168.338754 -408.517344 -90)
		(property "Reference" "C1546"
			(at 0 0 270)
			(layer "F.SilkS")
			(hide yes)
			(effects
				(font
					(size 1.27 1.27)
				)
			)
		)
		(property "Value" ""
			(at 0 0 270)
			(layer "F.Fab")
			(effects
				(font
					(size 1.27 1.27)
				)
			)
		)
		(duplicate_pad_numbers_are_jumpers no)
		(fp_line
			(start -0.299974 0.150114)
			(end -0.299974 -0.150114)
			(stroke
				(width 0.1)
				(type default)
			)
			(layer "F.Fab")
		)
		(fp_line
			(start 0.299974 0.150114)
			(end -0.299974 0.150114)
			(stroke
				(width 0.1)
				(type default)
			)
			(layer "F.Fab")
		)
		(fp_line
			(start -0.299974 -0.150114)
			(end 0.299974 -0.150114)
			(stroke
				(width 0.1)
				(type default)
			)
			(layer "F.Fab")
		)
		(fp_line
			(start 0.299974 -0.150114)
			(end 0.299974 0.150114)
			(stroke
				(width 0.1)
				(type default)
			)
			(layer "F.Fab")
		)
		(pad "1" smd rect
			(at -0.2667 0 270)
			(size 0.3048 0.381)
			(layers "F.Cu" "F.Mask" "F.Paste")
			(net "P5E_CPU1_PE3_TX_C_DN<0>")
		)
		(pad "2" smd rect
			(at 0.2667 0 270)
			(size 0.3048 0.381)
			(layers "F.Cu" "F.Mask" "F.Paste")
			(net "P5E_CPU1_PE3_TX_DN<0>")
		)
	)
	(footprint ""
		(layer "F.Cu")
		(at 10.873486 -92.687648 90)
		(property "Reference" "R3661"
			(at 0 0 90)
			(layer "F.SilkS")
			(hide yes)
			(effects
				(font
					(size 1.27 1.27)
				)
			)
		)
		(property "Value" ""
			(at 0 0 90)
			(layer "F.Fab")
			(effects
				(font
					(size 1.27 1.27)
				)
			)
		)
		(duplicate_pad_numbers_are_jumpers no)
		(fp_line
			(start 0.7874 -0.4064)
			(end 0.7874 0.4064)
			(stroke
				(width 0.1524)
				(type default)
			)
			(layer "F.SilkS")
		)
		(fp_line
			(start -0.7874 -0.4064)
			(end 0.7874 -0.4064)
			(stroke
				(width 0.1524)
				(type default)
			)
			(layer "F.SilkS")
		)
		(fp_line
			(start 0.7874 0.4064)
			(end -0.7874 0.4064)
			(stroke
				(width 0.1524)
				(type default)
			)
			(layer "F.SilkS")
		)
		(fp_line
			(start -0.7874 0.4064)
			(end -0.7874 -0.4064)
			(stroke
				(width 0.1524)
				(type default)
			)
			(layer "F.SilkS")
		)
		(fp_line
			(start -0.12065 -0.305054)
			(end -0.12065 -0.2794)
			(stroke
				(width 0.1)
				(type default)
			)
			(layer "F.Fab")
		)
		(fp_line
			(start -0.67945 -0.305054)
			(end -0.12065 -0.305054)
			(stroke
				(width 0.1)
				(type default)
			)
			(layer "F.Fab")
		)
		(fp_line
			(start 0.67945 -0.3048)
			(end 0.67945 0.3048)
			(stroke
				(width 0.1)
				(type default)
			)
			(layer "F.Fab")
		)
		(fp_line
			(start 0.12065 -0.3048)
			(end 0.67945 -0.3048)
			(stroke
				(width 0.1)
				(type default)
			)
			(layer "F.Fab")
		)
		(fp_line
			(start 0.12065 -0.2794)
			(end 0.12065 -0.3048)
			(stroke
				(width 0.1)
				(type default)
			)
			(layer "F.Fab")
		)
		(fp_line
			(start -0.12065 -0.2794)
			(end 0.12065 -0.2794)
			(stroke
				(width 0.1)
				(type default)
			)
			(layer "F.Fab")
		)
		(fp_line
			(start 0.120396 0.2794)
			(end -0.12065 0.2794)
			(stroke
				(width 0.1)
				(type default)
			)
			(layer "F.Fab")
		)
		(fp_line
			(start -0.12065 0.2794)
			(end -0.12065 0.3048)
			(stroke
				(width 0.1)
				(type default)
			)
			(layer "F.Fab")
		)
		(fp_line
			(start 0.67945 0.3048)
			(end 0.120396 0.3048)
			(stroke
				(width 0.1)
				(type default)
			)
			(layer "F.Fab")
		)
		(fp_line
			(start 0.120396 0.3048)
			(end 0.120396 0.2794)
			(stroke
				(width 0.1)
				(type default)
			)
			(layer "F.Fab")
		)
		(fp_line
			(start -0.12065 0.3048)
			(end -0.67945 0.3048)
			(stroke
				(width 0.1)
				(type default)
			)
			(layer "F.Fab")
		)
		(fp_line
			(start -0.67945 0.3048)
			(end -0.67945 -0.305054)
			(stroke
				(width 0.1)
				(type default)
			)
			(layer "F.Fab")
		)
		(pad "1" smd circle
			(at -0.40005 0 90)
			(size 0 0)
			(layers "F.Cu" "F.Mask" "F.Paste")
			(net "GND")
		)
		(pad "2" smd circle
			(at 0.40005 0 90)
			(size 0 0)
			(layers "F.Cu" "F.Mask" "F.Paste")
			(net "RST_USB_HUB_R_N")
		)
	)
	(footprint ""
		(layer "F.Cu")
		(at 19.37131 -180.522626 90)
		(property "Reference" "PC1281"
			(at 0 0 90)
			(layer "F.SilkS")
			(hide yes)
			(effects
				(font
					(size 1.27 1.27)
				)
			)
		)
		(property "Value" ""
			(at 0 0 90)
			(layer "F.Fab")
			(effects
				(font
					(size 1.27 1.27)
				)
			)
		)
		(duplicate_pad_numbers_are_jumpers no)
		(fp_line
			(start 1.524 -0.762)
			(end 1.524 0.762)
			(stroke
				(width 0.1524)
				(type default)
			)
			(layer "F.SilkS")
		)
		(fp_line
			(start -1.524 -0.762)
			(end 1.524 -0.762)
			(stroke
				(width 0.1524)
				(type default)
			)
			(layer "F.SilkS")
		)
		(fp_line
			(start 1.524 0.762)
			(end -1.524 0.762)
			(stroke
				(width 0.1524)
				(type default)
			)
			(layer "F.SilkS")
		)
		(fp_line
			(start -1.524 0.762)
			(end -1.524 -0.762)
			(stroke
				(width 0.1524)
				(type default)
			)
			(layer "F.SilkS")
		)
		(fp_line
			(start 1.1049 -0.724916)
			(end -1.1049 -0.724916)
			(stroke
				(width 0.1)
				(type default)
			)
			(layer "F.Fab")
		)
		(fp_line
			(start -1.1049 -0.724916)
			(end -1.1049 0.724916)
			(stroke
				(width 0.1)
				(type default)
			)
			(layer "F.Fab")
		)
		(fp_line
			(start 1.1049 0.724916)
			(end 1.1049 -0.724916)
			(stroke
				(width 0.1)
				(type default)
			)
			(layer "F.Fab")
		)
		(fp_line
			(start -1.1049 0.724916)
			(end 1.1049 0.724916)
			(stroke
				(width 0.1)
				(type default)
			)
			(layer "F.Fab")
		)
		(pad "1" smd rect
			(at -0.889 0 270)
			(size 1.016 1.27)
			(layers "F.Cu" "F.Mask" "F.Paste")
			(net "SW_P12V_PVCCINFAON_CPU1_FLT")
		)
		(pad "2" smd rect
			(at 0.889 0 270)
			(size 1.016 1.27)
			(layers "F.Cu" "F.Mask" "F.Paste")
			(net "GND")
		)
	)
	(footprint ""
		(layer "F.Cu")
		(at 355.247448 -247.715024 90)
		(property "Reference" "C979"
			(at 0 0 90)
			(layer "F.SilkS")
			(hide yes)
			(effects
				(font
					(size 1.27 1.27)
				)
			)
		)
		(property "Value" ""
			(at 0 0 90)
			(layer "F.Fab")
			(effects
				(font
					(size 1.27 1.27)
				)
			)
		)
		(duplicate_pad_numbers_are_jumpers no)
		(fp_line
			(start 0.7874 -0.4064)
			(end 0.7874 0.4064)
			(stroke
				(width 0.1524)
				(type default)
			)
			(layer "F.SilkS")
		)
		(fp_line
			(start -0.7874 -0.4064)
			(end 0.7874 -0.4064)
			(stroke
				(width 0.1524)
				(type default)
			)
			(layer "F.SilkS")
		)
		(fp_line
			(start 0.7874 0.4064)
			(end -0.7874 0.4064)
			(stroke
				(width 0.1524)
				(type default)
			)
			(layer "F.SilkS")
		)
		(fp_line
			(start -0.7874 0.4064)
			(end -0.7874 -0.4064)
			(stroke
				(width 0.1524)
				(type default)
			)
			(layer "F.SilkS")
		)
		(fp_line
			(start -0.12065 -0.305054)
			(end -0.12065 -0.2794)
			(stroke
				(width 0.1)
				(type default)
			)
			(layer "F.Fab")
		)
		(fp_line
			(start -0.67945 -0.305054)
			(end -0.12065 -0.305054)
			(stroke
				(width 0.1)
				(type default)
			)
			(layer "F.Fab")
		)
		(fp_line
			(start 0.67945 -0.3048)
			(end 0.67945 0.3048)
			(stroke
				(width 0.1)
				(type default)
			)
			(layer "F.Fab")
		)
		(fp_line
			(start 0.12065 -0.3048)
			(end 0.67945 -0.3048)
			(stroke
				(width 0.1)
				(type default)
			)
			(layer "F.Fab")
		)
		(fp_line
			(start 0.12065 -0.2794)
			(end 0.12065 -0.3048)
			(stroke
				(width 0.1)
				(type default)
			)
			(layer "F.Fab")
		)
		(fp_line
			(start -0.12065 -0.2794)
			(end 0.12065 -0.2794)
			(stroke
				(width 0.1)
				(type default)
			)
			(layer "F.Fab")
		)
		(fp_line
			(start 0.120396 0.2794)
			(end -0.12065 0.2794)
			(stroke
				(width 0.1)
				(type default)
			)
			(layer "F.Fab")
		)
		(fp_line
			(start -0.12065 0.2794)
			(end -0.12065 0.3048)
			(stroke
				(width 0.1)
				(type default)
			)
			(layer "F.Fab")
		)
		(fp_line
			(start 0.67945 0.3048)
			(end 0.120396 0.3048)
			(stroke
				(width 0.1)
				(type default)
			)
			(layer "F.Fab")
		)
		(fp_line
			(start 0.120396 0.3048)
			(end 0.120396 0.2794)
			(stroke
				(width 0.1)
				(type default)
			)
			(layer "F.Fab")
		)
		(fp_line
			(start -0.12065 0.3048)
			(end -0.67945 0.3048)
			(stroke
				(width 0.1)
				(type default)
			)
			(layer "F.Fab")
		)
		(fp_line
			(start -0.67945 0.3048)
			(end -0.67945 -0.305054)
			(stroke
				(width 0.1)
				(type default)
			)
			(layer "F.Fab")
		)
		(pad "1" smd circle
			(at -0.40005 0 90)
			(size 0 0)
			(layers "F.Cu" "F.Mask" "F.Paste")
			(net "PVCCIN_CPU0")
		)
		(pad "2" smd circle
			(at 0.40005 0 90)
			(size 0 0)
			(layers "F.Cu" "F.Mask" "F.Paste")
			(net "GND")
		)
	)
	(footprint ""
		(layer "F.Cu")
		(at 193.90868 -359.349548 180)
		(property "Reference" "R627"
			(at 0 0 180)
			(layer "F.SilkS")
			(hide yes)
			(effects
				(font
					(size 1.27 1.27)
				)
			)
		)
		(property "Value" ""
			(at 0 0 180)
			(layer "F.Fab")
			(effects
				(font
					(size 1.27 1.27)
				)
			)
		)
		(duplicate_pad_numbers_are_jumpers no)
		(fp_line
			(start 0.7874 0.4064)
			(end -0.7874 0.4064)
			(stroke
				(width 0.1524)
				(type default)
			)
			(layer "F.SilkS")
		)
		(fp_line
			(start 0.7874 -0.4064)
			(end 0.7874 0.4064)
			(stroke
				(width 0.1524)
				(type default)
			)
			(layer "F.SilkS")
		)
		(fp_line
			(start -0.7874 0.4064)
			(end -0.7874 -0.4064)
			(stroke
				(width 0.1524)
				(type default)
			)
			(layer "F.SilkS")
		)
		(fp_line
			(start -0.7874 -0.4064)
			(end 0.7874 -0.4064)
			(stroke
				(width 0.1524)
				(type default)
			)
			(layer "F.SilkS")
		)
		(fp_line
			(start 0.67945 0.3048)
			(end 0.120396 0.3048)
			(stroke
				(width 0.1)
				(type default)
			)
			(layer "F.Fab")
		)
		(fp_line
			(start 0.67945 -0.3048)
			(end 0.67945 0.3048)
			(stroke
				(width 0.1)
				(type default)
			)
			(layer "F.Fab")
		)
		(fp_line
			(start 0.12065 -0.2794)
			(end 0.12065 -0.3048)
			(stroke
				(width 0.1)
				(type default)
			)
			(layer "F.Fab")
		)
		(fp_line
			(start 0.12065 -0.3048)
			(end 0.67945 -0.3048)
			(stroke
				(width 0.1)
				(type default)
			)
			(layer "F.Fab")
		)
		(fp_line
			(start 0.120396 0.3048)
			(end 0.120396 0.2794)
			(stroke
				(width 0.1)
				(type default)
			)
			(layer "F.Fab")
		)
		(fp_line
			(start 0.120396 0.2794)
			(end -0.12065 0.2794)
			(stroke
				(width 0.1)
				(type default)
			)
			(layer "F.Fab")
		)
		(fp_line
			(start -0.12065 0.3048)
			(end -0.67945 0.3048)
			(stroke
				(width 0.1)
				(type default)
			)
			(layer "F.Fab")
		)
		(fp_line
			(start -0.12065 0.2794)
			(end -0.12065 0.3048)
			(stroke
				(width 0.1)
				(type default)
			)
			(layer "F.Fab")
		)
		(fp_line
			(start -0.12065 -0.2794)
			(end 0.12065 -0.2794)
			(stroke
				(width 0.1)
				(type default)
			)
			(layer "F.Fab")
		)
		(fp_line
			(start -0.12065 -0.305054)
			(end -0.12065 -0.2794)
			(stroke
				(width 0.1)
				(type default)
			)
			(layer "F.Fab")
		)
		(fp_line
			(start -0.67945 0.3048)
			(end -0.67945 -0.305054)
			(stroke
				(width 0.1)
				(type default)
			)
			(layer "F.Fab")
		)
		(fp_line
			(start -0.67945 -0.305054)
			(end -0.12065 -0.305054)
			(stroke
				(width 0.1)
				(type default)
			)
			(layer "F.Fab")
		)
		(pad "1" smd circle
			(at -0.40005 0 180)
			(size 0 0)
			(layers "F.Cu" "F.Mask" "F.Paste")
			(net "P3V3_AUX")
		)
		(pad "2" smd circle
			(at 0.40005 0 180)
			(size 0 0)
			(layers "F.Cu" "F.Mask" "F.Paste")
			(net "PD_PIROM_CPU1_ADDR1")
		)
	)
	(footprint ""
		(layer "F.Cu")
		(at 209.070956 -30.276292 90)
		(property "Reference" "R3624"
			(at 0 0 90)
			(layer "F.SilkS")
			(hide yes)
			(effects
				(font
					(size 1.27 1.27)
				)
			)
		)
		(property "Value" ""
			(at 0 0 90)
			(layer "F.Fab")
			(effects
				(font
					(size 1.27 1.27)
				)
			)
		)
		(duplicate_pad_numbers_are_jumpers no)
		(fp_line
			(start 0.7874 -0.4064)
			(end 0.7874 0.4064)
			(stroke
				(width 0.1524)
				(type default)
			)
			(layer "F.SilkS")
		)
		(fp_line
			(start -0.7874 -0.4064)
			(end 0.7874 -0.4064)
			(stroke
				(width 0.1524)
				(type default)
			)
			(layer "F.SilkS")
		)
		(fp_line
			(start 0.7874 0.4064)
			(end -0.7874 0.4064)
			(stroke
				(width 0.1524)
				(type default)
			)
			(layer "F.SilkS")
		)
		(fp_line
			(start -0.7874 0.4064)
			(end -0.7874 -0.4064)
			(stroke
				(width 0.1524)
				(type default)
			)
			(layer "F.SilkS")
		)
		(fp_line
			(start -0.12065 -0.305054)
			(end -0.12065 -0.2794)
			(stroke
				(width 0.1)
				(type default)
			)
			(layer "F.Fab")
		)
		(fp_line
			(start -0.67945 -0.305054)
			(end -0.12065 -0.305054)
			(stroke
				(width 0.1)
				(type default)
			)
			(layer "F.Fab")
		)
		(fp_line
			(start 0.67945 -0.3048)
			(end 0.67945 0.3048)
			(stroke
				(width 0.1)
				(type default)
			)
			(layer "F.Fab")
		)
		(fp_line
			(start 0.12065 -0.3048)
			(end 0.67945 -0.3048)
			(stroke
				(width 0.1)
				(type default)
			)
			(layer "F.Fab")
		)
		(fp_line
			(start 0.12065 -0.2794)
			(end 0.12065 -0.3048)
			(stroke
				(width 0.1)
				(type default)
			)
			(layer "F.Fab")
		)
		(fp_line
			(start -0.12065 -0.2794)
			(end 0.12065 -0.2794)
			(stroke
				(width 0.1)
				(type default)
			)
			(layer "F.Fab")
		)
		(fp_line
			(start 0.120396 0.2794)
			(end -0.12065 0.2794)
			(stroke
				(width 0.1)
				(type default)
			)
			(layer "F.Fab")
		)
		(fp_line
			(start -0.12065 0.2794)
			(end -0.12065 0.3048)
			(stroke
				(width 0.1)
				(type default)
			)
			(layer "F.Fab")
		)
		(fp_line
			(start 0.67945 0.3048)
			(end 0.120396 0.3048)
			(stroke
				(width 0.1)
				(type default)
			)
			(layer "F.Fab")
		)
		(fp_line
			(start 0.120396 0.3048)
			(end 0.120396 0.2794)
			(stroke
				(width 0.1)
				(type default)
			)
			(layer "F.Fab")
		)
		(fp_line
			(start -0.12065 0.3048)
			(end -0.67945 0.3048)
			(stroke
				(width 0.1)
				(type default)
			)
			(layer "F.Fab")
		)
		(fp_line
			(start -0.67945 0.3048)
			(end -0.67945 -0.305054)
			(stroke
				(width 0.1)
				(type default)
			)
			(layer "F.Fab")
		)
		(pad "1" smd circle
			(at -0.40005 0 90)
			(size 0 0)
			(layers "F.Cu" "F.Mask" "F.Paste")
			(net "P3V3_AUX")
		)
		(pad "2" smd circle
			(at 0.40005 0 90)
			(size 0 0)
			(layers "F.Cu" "F.Mask" "F.Paste")
			(net "INA230_5_A1")
		)
	)
	(footprint ""
		(layer "F.Cu")
		(at 354.282248 -247.715024 90)
		(property "Reference" "C975"
			(at 0 0 90)
			(layer "F.SilkS")
			(hide yes)
			(effects
				(font
					(size 1.27 1.27)
				)
			)
		)
		(property "Value" ""
			(at 0 0 90)
			(layer "F.Fab")
			(effects
				(font
					(size 1.27 1.27)
				)
			)
		)
		(duplicate_pad_numbers_are_jumpers no)
		(fp_line
			(start 0.7874 -0.4064)
			(end 0.7874 0.4064)
			(stroke
				(width 0.1524)
				(type default)
			)
			(layer "F.SilkS")
		)
		(fp_line
			(start -0.7874 -0.4064)
			(end 0.7874 -0.4064)
			(stroke
				(width 0.1524)
				(type default)
			)
			(layer "F.SilkS")
		)
		(fp_line
			(start 0.7874 0.4064)
			(end -0.7874 0.4064)
			(stroke
				(width 0.1524)
				(type default)
			)
			(layer "F.SilkS")
		)
		(fp_line
			(start -0.7874 0.4064)
			(end -0.7874 -0.4064)
			(stroke
				(width 0.1524)
				(type default)
			)
			(layer "F.SilkS")
		)
		(fp_line
			(start -0.12065 -0.305054)
			(end -0.12065 -0.2794)
			(stroke
				(width 0.1)
				(type default)
			)
			(layer "F.Fab")
		)
		(fp_line
			(start -0.67945 -0.305054)
			(end -0.12065 -0.305054)
			(stroke
				(width 0.1)
				(type default)
			)
			(layer "F.Fab")
		)
		(fp_line
			(start 0.67945 -0.3048)
			(end 0.67945 0.3048)
			(stroke
				(width 0.1)
				(type default)
			)
			(layer "F.Fab")
		)
		(fp_line
			(start 0.12065 -0.3048)
			(end 0.67945 -0.3048)
			(stroke
				(width 0.1)
				(type default)
			)
			(layer "F.Fab")
		)
		(fp_line
			(start 0.12065 -0.2794)
			(end 0.12065 -0.3048)
			(stroke
				(width 0.1)
				(type default)
			)
			(layer "F.Fab")
		)
		(fp_line
			(start -0.12065 -0.2794)
			(end 0.12065 -0.2794)
			(stroke
				(width 0.1)
				(type default)
			)
			(layer "F.Fab")
		)
		(fp_line
			(start 0.120396 0.2794)
			(end -0.12065 0.2794)
			(stroke
				(width 0.1)
				(type default)
			)
			(layer "F.Fab")
		)
		(fp_line
			(start -0.12065 0.2794)
			(end -0.12065 0.3048)
			(stroke
				(width 0.1)
				(type default)
			)
			(layer "F.Fab")
		)
		(fp_line
			(start 0.67945 0.3048)
			(end 0.120396 0.3048)
			(stroke
				(width 0.1)
				(type default)
			)
			(layer "F.Fab")
		)
		(fp_line
			(start 0.120396 0.3048)
			(end 0.120396 0.2794)
			(stroke
				(width 0.1)
				(type default)
			)
			(layer "F.Fab")
		)
		(fp_line
			(start -0.12065 0.3048)
			(end -0.67945 0.3048)
			(stroke
				(width 0.1)
				(type default)
			)
			(layer "F.Fab")
		)
		(fp_line
			(start -0.67945 0.3048)
			(end -0.67945 -0.305054)
			(stroke
				(width 0.1)
				(type default)
			)
			(layer "F.Fab")
		)
		(pad "1" smd circle
			(at -0.40005 0 90)
			(size 0 0)
			(layers "F.Cu" "F.Mask" "F.Paste")
			(net "PVCCIN_CPU0")
		)
		(pad "2" smd circle
			(at 0.40005 0 90)
			(size 0 0)
			(layers "F.Cu" "F.Mask" "F.Paste")
			(net "GND")
		)
	)
	(footprint ""
		(layer "F.Cu")
		(at 197.41388 -107.495848)
		(property "Reference" "R109"
			(at 0 0 0)
			(layer "F.SilkS")
			(hide yes)
			(effects
				(font
					(size 1.27 1.27)
				)
			)
		)
		(property "Value" ""
			(at 0 0 0)
			(layer "F.Fab")
			(effects
				(font
					(size 1.27 1.27)
				)
			)
		)
		(duplicate_pad_numbers_are_jumpers no)
		(fp_line
			(start -0.7874 -0.4064)
			(end 0.7874 -0.4064)
			(stroke
				(width 0.1524)
				(type default)
			)
			(layer "F.SilkS")
		)
		(fp_line
			(start -0.7874 0.4064)
			(end -0.7874 -0.4064)
			(stroke
				(width 0.1524)
				(type default)
			)
			(layer "F.SilkS")
		)
		(fp_line
			(start 0.7874 -0.4064)
			(end 0.7874 0.4064)
			(stroke
				(width 0.1524)
				(type default)
			)
			(layer "F.SilkS")
		)
		(fp_line
			(start 0.7874 0.4064)
			(end -0.7874 0.4064)
			(stroke
				(width 0.1524)
				(type default)
			)
			(layer "F.SilkS")
		)
		(fp_line
			(start -0.67945 -0.305054)
			(end -0.12065 -0.305054)
			(stroke
				(width 0.1)
				(type default)
			)
			(layer "F.Fab")
		)
		(fp_line
			(start -0.67945 0.3048)
			(end -0.67945 -0.305054)
			(stroke
				(width 0.1)
				(type default)
			)
			(layer "F.Fab")
		)
		(fp_line
			(start -0.12065 -0.305054)
			(end -0.12065 -0.2794)
			(stroke
				(width 0.1)
				(type default)
			)
			(layer "F.Fab")
		)
		(fp_line
			(start -0.12065 -0.2794)
			(end 0.12065 -0.2794)
			(stroke
				(width 0.1)
				(type default)
			)
			(layer "F.Fab")
		)
		(fp_line
			(start -0.12065 0.2794)
			(end -0.12065 0.3048)
			(stroke
				(width 0.1)
				(type default)
			)
			(layer "F.Fab")
		)
		(fp_line
			(start -0.12065 0.3048)
			(end -0.67945 0.3048)
			(stroke
				(width 0.1)
				(type default)
			)
			(layer "F.Fab")
		)
		(fp_line
			(start 0.120396 0.2794)
			(end -0.12065 0.2794)
			(stroke
				(width 0.1)
				(type default)
			)
			(layer "F.Fab")
		)
		(fp_line
			(start 0.120396 0.3048)
			(end 0.120396 0.2794)
			(stroke
				(width 0.1)
				(type default)
			)
			(layer "F.Fab")
		)
		(fp_line
			(start 0.12065 -0.3048)
			(end 0.67945 -0.3048)
			(stroke
				(width 0.1)
				(type default)
			)
			(layer "F.Fab")
		)
		(fp_line
			(start 0.12065 -0.2794)
			(end 0.12065 -0.3048)
			(stroke
				(width 0.1)
				(type default)
			)
			(layer "F.Fab")
		)
		(fp_line
			(start 0.67945 -0.3048)
			(end 0.67945 0.3048)
			(stroke
				(width 0.1)
				(type default)
			)
			(layer "F.Fab")
		)
		(fp_line
			(start 0.67945 0.3048)
			(end 0.120396 0.3048)
			(stroke
				(width 0.1)
				(type default)
			)
			(layer "F.Fab")
		)
		(pad "1" smd circle
			(at -0.40005 0)
			(size 0 0)
			(layers "F.Cu" "F.Mask" "F.Paste")
			(net "FM_PLD_CLK_25M_R_EN")
		)
		(pad "2" smd circle
			(at 0.40005 0)
			(size 0 0)
			(layers "F.Cu" "F.Mask" "F.Paste")
			(net "FM_PLD_CLK_25M_EN")
		)
	)
	(footprint ""
		(layer "F.Cu")
		(at 442.91123 -370.248434)
		(property "Reference" "C1331"
			(at 0 0 0)
			(layer "F.SilkS")
			(hide yes)
			(effects
				(font
					(size 1.27 1.27)
				)
			)
		)
		(property "Value" ""
			(at 0 0 0)
			(layer "F.Fab")
			(effects
				(font
					(size 1.27 1.27)
				)
			)
		)
		(duplicate_pad_numbers_are_jumpers no)
		(fp_line
			(start -1.524 -0.762)
			(end 1.524 -0.762)
			(stroke
				(width 0.1524)
				(type default)
			)
			(layer "F.SilkS")
		)
		(fp_line
			(start -1.524 0.762)
			(end -1.524 -0.762)
			(stroke
				(width 0.1524)
				(type default)
			)
			(layer "F.SilkS")
		)
		(fp_line
			(start 1.524 -0.762)
			(end 1.524 0.762)
			(stroke
				(width 0.1524)
				(type default)
			)
			(layer "F.SilkS")
		)
		(fp_line
			(start 1.524 0.762)
			(end -1.524 0.762)
			(stroke
				(width 0.1524)
				(type default)
			)
			(layer "F.SilkS")
		)
		(fp_line
			(start -1.1049 -0.724916)
			(end -1.1049 0.724916)
			(stroke
				(width 0.1)
				(type default)
			)
			(layer "F.Fab")
		)
		(fp_line
			(start -1.1049 0.724916)
			(end 1.1049 0.724916)
			(stroke
				(width 0.1)
				(type default)
			)
			(layer "F.Fab")
		)
		(fp_line
			(start 1.1049 -0.724916)
			(end -1.1049 -0.724916)
			(stroke
				(width 0.1)
				(type default)
			)
			(layer "F.Fab")
		)
		(fp_line
			(start 1.1049 0.724916)
			(end 1.1049 -0.724916)
			(stroke
				(width 0.1)
				(type default)
			)
			(layer "F.Fab")
		)
		(pad "1" smd rect
			(at -0.889 0 180)
			(size 1.016 1.27)
			(layers "F.Cu" "F.Mask" "F.Paste")
			(net "P5V")
		)
		(pad "2" smd rect
			(at 0.889 0 180)
			(size 1.016 1.27)
			(layers "F.Cu" "F.Mask" "F.Paste")
			(net "GND")
		)
	)
	(footprint ""
		(layer "F.Cu")
		(at 218.011502 -72.015858 180)
		(property "Reference" "PR3971"
			(at 0 0 180)
			(layer "F.SilkS")
			(hide yes)
			(effects
				(font
					(size 1.27 1.27)
				)
			)
		)
		(property "Value" ""
			(at 0 0 180)
			(layer "F.Fab")
			(effects
				(font
					(size 1.27 1.27)
				)
			)
		)
		(duplicate_pad_numbers_are_jumpers no)
		(fp_line
			(start 0.7874 0.4064)
			(end -0.7874 0.4064)
			(stroke
				(width 0.1524)
				(type default)
			)
			(layer "F.SilkS")
		)
		(fp_line
			(start 0.7874 -0.4064)
			(end 0.7874 0.4064)
			(stroke
				(width 0.1524)
				(type default)
			)
			(layer "F.SilkS")
		)
		(fp_line
			(start -0.7874 0.4064)
			(end -0.7874 -0.4064)
			(stroke
				(width 0.1524)
				(type default)
			)
			(layer "F.SilkS")
		)
		(fp_line
			(start -0.7874 -0.4064)
			(end 0.7874 -0.4064)
			(stroke
				(width 0.1524)
				(type default)
			)
			(layer "F.SilkS")
		)
		(fp_line
			(start 0.67945 0.3048)
			(end 0.120396 0.3048)
			(stroke
				(width 0.1)
				(type default)
			)
			(layer "F.Fab")
		)
		(fp_line
			(start 0.67945 -0.3048)
			(end 0.67945 0.3048)
			(stroke
				(width 0.1)
				(type default)
			)
			(layer "F.Fab")
		)
		(fp_line
			(start 0.12065 -0.2794)
			(end 0.12065 -0.3048)
			(stroke
				(width 0.1)
				(type default)
			)
			(layer "F.Fab")
		)
		(fp_line
			(start 0.12065 -0.3048)
			(end 0.67945 -0.3048)
			(stroke
				(width 0.1)
				(type default)
			)
			(layer "F.Fab")
		)
		(fp_line
			(start 0.120396 0.3048)
			(end 0.120396 0.2794)
			(stroke
				(width 0.1)
				(type default)
			)
			(layer "F.Fab")
		)
		(fp_line
			(start 0.120396 0.2794)
			(end -0.12065 0.2794)
			(stroke
				(width 0.1)
				(type default)
			)
			(layer "F.Fab")
		)
		(fp_line
			(start -0.12065 0.3048)
			(end -0.67945 0.3048)
			(stroke
				(width 0.1)
				(type default)
			)
			(layer "F.Fab")
		)
		(fp_line
			(start -0.12065 0.2794)
			(end -0.12065 0.3048)
			(stroke
				(width 0.1)
				(type default)
			)
			(layer "F.Fab")
		)
		(fp_line
			(start -0.12065 -0.2794)
			(end 0.12065 -0.2794)
			(stroke
				(width 0.1)
				(type default)
			)
			(layer "F.Fab")
		)
		(fp_line
			(start -0.12065 -0.305054)
			(end -0.12065 -0.2794)
			(stroke
				(width 0.1)
				(type default)
			)
			(layer "F.Fab")
		)
		(fp_line
			(start -0.67945 0.3048)
			(end -0.67945 -0.305054)
			(stroke
				(width 0.1)
				(type default)
			)
			(layer "F.Fab")
		)
		(fp_line
			(start -0.67945 -0.305054)
			(end -0.12065 -0.305054)
			(stroke
				(width 0.1)
				(type default)
			)
			(layer "F.Fab")
		)
		(pad "1" smd circle
			(at -0.40005 0 180)
			(size 0 0)
			(layers "F.Cu" "F.Mask" "F.Paste")
			(net "P3V3_E1S_SENSE_0")
		)
		(pad "2" smd circle
			(at 0.40005 0 180)
			(size 0 0)
			(layers "F.Cu" "F.Mask" "F.Paste")
			(net "GND")
		)
	)
	(footprint ""
		(layer "F.Cu")
		(at 326.743568 -408.517344 -90)
		(property "Reference" "C916"
			(at 0 0 270)
			(layer "F.SilkS")
			(hide yes)
			(effects
				(font
					(size 1.27 1.27)
				)
			)
		)
		(property "Value" ""
			(at 0 0 270)
			(layer "F.Fab")
			(effects
				(font
					(size 1.27 1.27)
				)
			)
		)
		(duplicate_pad_numbers_are_jumpers no)
		(fp_line
			(start -0.299974 0.150114)
			(end -0.299974 -0.150114)
			(stroke
				(width 0.1)
				(type default)
			)
			(layer "F.Fab")
		)
		(fp_line
			(start 0.299974 0.150114)
			(end -0.299974 0.150114)
			(stroke
				(width 0.1)
				(type default)
			)
			(layer "F.Fab")
		)
		(fp_line
			(start -0.299974 -0.150114)
			(end 0.299974 -0.150114)
			(stroke
				(width 0.1)
				(type default)
			)
			(layer "F.Fab")
		)
		(fp_line
			(start 0.299974 -0.150114)
			(end 0.299974 0.150114)
			(stroke
				(width 0.1)
				(type default)
			)
			(layer "F.Fab")
		)
		(pad "1" smd rect
			(at -0.2667 0 270)
			(size 0.3048 0.381)
			(layers "F.Cu" "F.Mask" "F.Paste")
			(net "P5E_CPU0_PE0_TX_C_DN<8>")
		)
		(pad "2" smd rect
			(at 0.2667 0 270)
			(size 0.3048 0.381)
			(layers "F.Cu" "F.Mask" "F.Paste")
			(net "P5E_CPU0_PE0_TX_DN<8>")
		)
	)
	(footprint ""
		(layer "F.Cu")
		(at 364.50143 -256.654046 -90)
		(property "Reference" "C984"
			(at 0 0 270)
			(layer "F.SilkS")
			(hide yes)
			(effects
				(font
					(size 1.27 1.27)
				)
			)
		)
		(property "Value" ""
			(at 0 0 270)
			(layer "F.Fab")
			(effects
				(font
					(size 1.27 1.27)
				)
			)
		)
		(duplicate_pad_numbers_are_jumpers no)
		(fp_line
			(start -0.7874 0.4064)
			(end -0.7874 -0.4064)
			(stroke
				(width 0.1524)
				(type default)
			)
			(layer "F.SilkS")
		)
		(fp_line
			(start 0.7874 0.4064)
			(end -0.7874 0.4064)
			(stroke
				(width 0.1524)
				(type default)
			)
			(layer "F.SilkS")
		)
		(fp_line
			(start -0.7874 -0.4064)
			(end 0.7874 -0.4064)
			(stroke
				(width 0.1524)
				(type default)
			)
			(layer "F.SilkS")
		)
		(fp_line
			(start 0.7874 -0.4064)
			(end 0.7874 0.4064)
			(stroke
				(width 0.1524)
				(type default)
			)
			(layer "F.SilkS")
		)
		(fp_line
			(start -0.67945 0.3048)
			(end -0.67945 -0.305054)
			(stroke
				(width 0.1)
				(type default)
			)
			(layer "F.Fab")
		)
		(fp_line
			(start -0.12065 0.3048)
			(end -0.67945 0.3048)
			(stroke
				(width 0.1)
				(type default)
			)
			(layer "F.Fab")
		)
		(fp_line
			(start 0.120396 0.3048)
			(end 0.120396 0.2794)
			(stroke
				(width 0.1)
				(type default)
			)
			(layer "F.Fab")
		)
		(fp_line
			(start 0.67945 0.3048)
			(end 0.120396 0.3048)
			(stroke
				(width 0.1)
				(type default)
			)
			(layer "F.Fab")
		)
		(fp_line
			(start -0.12065 0.2794)
			(end -0.12065 0.3048)
			(stroke
				(width 0.1)
				(type default)
			)
			(layer "F.Fab")
		)
		(fp_line
			(start 0.120396 0.2794)
			(end -0.12065 0.2794)
			(stroke
				(width 0.1)
				(type default)
			)
			(layer "F.Fab")
		)
		(fp_line
			(start -0.12065 -0.2794)
			(end 0.12065 -0.2794)
			(stroke
				(width 0.1)
				(type default)
			)
			(layer "F.Fab")
		)
		(fp_line
			(start 0.12065 -0.2794)
			(end 0.12065 -0.3048)
			(stroke
				(width 0.1)
				(type default)
			)
			(layer "F.Fab")
		)
		(fp_line
			(start 0.12065 -0.3048)
			(end 0.67945 -0.3048)
			(stroke
				(width 0.1)
				(type default)
			)
			(layer "F.Fab")
		)
		(fp_line
			(start 0.67945 -0.3048)
			(end 0.67945 0.3048)
			(stroke
				(width 0.1)
				(type default)
			)
			(layer "F.Fab")
		)
		(fp_line
			(start -0.67945 -0.305054)
			(end -0.12065 -0.305054)
			(stroke
				(width 0.1)
				(type default)
			)
			(layer "F.Fab")
		)
		(fp_line
			(start -0.12065 -0.305054)
			(end -0.12065 -0.2794)
			(stroke
				(width 0.1)
				(type default)
			)
			(layer "F.Fab")
		)
		(pad "1" smd circle
			(at -0.40005 0 270)
			(size 0 0)
			(layers "F.Cu" "F.Mask" "F.Paste")
			(net "PVCCIN_CPU0")
		)
		(pad "2" smd circle
			(at 0.40005 0 270)
			(size 0 0)
			(layers "F.Cu" "F.Mask" "F.Paste")
			(net "GND")
		)
	)
	(footprint ""
		(layer "F.Cu")
		(at 17.73428 -258.091686)
		(property "Reference" "J24"
			(at -3.0607 -81.901792 0)
			(unlocked yes)
			(layer "F.SilkS")
			(effects
				(font
					(size 0.7874 0.5842)
					(thickness 0.1524)
				)
				(justify left)
			)
		)
		(property "Value" ""
			(at 0 0 0)
			(layer "F.Fab")
			(effects
				(font
					(size 1.27 1.27)
				)
			)
		)
		(duplicate_pad_numbers_are_jumpers no)
		(fp_line
			(start -3.24993 -81.000092)
			(end -3.24993 -79.675482)
			(stroke
				(width 0.1524)
				(type default)
			)
			(layer "F.SilkS")
		)
		(fp_line
			(start -3.24993 -75.855322)
			(end -3.24993 81.000092)
			(stroke
				(width 0.1524)
				(type default)
			)
			(layer "F.SilkS")
		)
		(fp_line
			(start -3.24993 81.000092)
			(end 3.24993 81.000092)
			(stroke
				(width 0.1524)
				(type default)
			)
			(layer "F.SilkS")
		)
		(fp_line
			(start 1.52654 -81.000092)
			(end -3.24993 -81.000092)
			(stroke
				(width 0.1524)
				(type default)
			)
			(layer "F.SilkS")
		)
		(fp_line
			(start 3.24993 -76.218542)
			(end 3.24993 -79.528162)
			(stroke
				(width 0.1524)
				(type default)
			)
			(layer "F.SilkS")
		)
		(fp_line
			(start 3.24993 -72.00011)
			(end -3.24993 -72.00011)
			(stroke
				(width 0.1524)
				(type default)
			)
			(layer "F.SilkS")
		)
		(fp_line
			(start 3.24993 72.00011)
			(end -3.24993 72.00011)
			(stroke
				(width 0.1524)
				(type default)
			)
			(layer "F.SilkS")
		)
		(fp_line
			(start 3.24993 76.285598)
			(end 3.24993 -72.774302)
			(stroke
				(width 0.1524)
				(type default)
			)
			(layer "F.SilkS")
		)
		(fp_poly
			(pts
				(xy -4.180332 -63.701676) (xy -3.395472 -63.309246) (xy -4.180332 -62.916816)
			)
			(stroke
				(width 0)
				(type default)
			)
			(fill yes)
			(layer "F.SilkS")
		)
		(fp_line
			(start -3.24993 -81.000092)
			(end -3.24993 81.000092)
			(stroke
				(width 0.1)
				(type default)
			)
			(layer "F.Fab")
		)
		(fp_line
			(start -3.24993 81.000092)
			(end 3.24993 81.000092)
			(stroke
				(width 0.1)
				(type default)
			)
			(layer "F.Fab")
		)
		(fp_line
			(start 3.24993 -81.000092)
			(end -3.24993 -81.000092)
			(stroke
				(width 0.1)
				(type default)
			)
			(layer "F.Fab")
		)
		(fp_line
			(start 3.24993 -72.00011)
			(end -3.24993 -72.00011)
			(stroke
				(width 0.1)
				(type default)
			)
			(layer "F.Fab")
		)
		(fp_line
			(start 3.24993 -71.000112)
			(end -3.24993 -71.000112)
			(stroke
				(width 0.1)
				(type default)
			)
			(layer "F.Fab")
		)
		(fp_line
			(start 3.24993 71.000112)
			(end -3.24993 71.000112)
			(stroke
				(width 0.1)
				(type default)
			)
			(layer "F.Fab")
		)
		(fp_line
			(start 3.24993 72.00011)
			(end -3.24993 72.00011)
			(stroke
				(width 0.1)
				(type default)
			)
			(layer "F.Fab")
		)
		(fp_line
			(start 3.24993 81.000092)
			(end 3.24993 -81.000092)
			(stroke
				(width 0.1)
				(type default)
			)
			(layer "F.Fab")
		)
		(fp_poly
			(pts
				(xy -4.445 -63.832994) (xy -4.445 -62.816994) (xy -3.429 -63.324994)
			)
			(stroke
				(width 0)
				(type default)
			)
			(fill yes)
			(layer "F.Fab")
		)
		(pad "1" smd rect
			(at -2.050034 -63.324994 270)
			(size 0.519938 1.4986)
			(layers "F.Cu" "F.Mask" "F.Paste")
			(net "P12V_S3_AUX_CPU1_NVDIMM")
		)
		(pad "2" smd rect
			(at -2.050034 -62.47511 270)
			(size 0.519938 1.4986)
			(layers "F.Cu" "F.Mask" "F.Paste")
			(net "TP_CHD_CPU1_DIMM2_FRU_0")
		)
		(pad "3" smd rect
			(at -2.050034 -61.624972 270)
			(size 0.519938 1.4986)
			(layers "F.Cu" "F.Mask" "F.Paste")
			(net "P3V3_AUX")
		)
		(pad "4" smd rect
			(at -2.050034 -60.775088 270)
			(size 0.519938 1.4986)
			(layers "F.Cu" "F.Mask" "F.Paste")
			(net "I3C_SPD_DDRABCD_CPU1_LVC1_SCL_7")
		)
		(pad "5" smd rect
			(at -2.050034 -59.92495 270)
			(size 0.519938 1.4986)
			(layers "F.Cu" "F.Mask" "F.Paste")
			(net "I3C_SPD_DDRABCD_CPU1_LVC1_SDA")
		)
		(pad "6" smd rect
			(at -2.050034 -59.075066 270)
			(size 0.519938 1.4986)
			(layers "F.Cu" "F.Mask" "F.Paste")
			(net "GND")
		)
		(pad "7" smd rect
			(at -2.050034 -58.224928 270)
			(size 0.519938 1.4986)
			(layers "F.Cu" "F.Mask" "F.Paste")
			(net "M_D_CPU1_SA_DQ<0>")
		)
		(pad "8" smd rect
			(at -2.050034 -57.375044 270)
			(size 0.519938 1.4986)
			(layers "F.Cu" "F.Mask" "F.Paste")
			(net "GND")
		)
		(pad "9" smd rect
			(at -2.050034 -56.524906 270)
			(size 0.519938 1.4986)
			(layers "F.Cu" "F.Mask" "F.Paste")
			(net "M_D_CPU1_SA_DQ<1>")
		)
		(pad "10" smd rect
			(at -2.050034 -55.675022 270)
			(size 0.519938 1.4986)
			(layers "F.Cu" "F.Mask" "F.Paste")
			(net "GND")
		)
		(pad "11" smd rect
			(at -2.050034 -54.824884 270)
			(size 0.519938 1.4986)
			(layers "F.Cu" "F.Mask" "F.Paste")
			(net "M_D_CPU1_SA_DQS_DP<0>")
		)
		(pad "12" smd rect
			(at -2.050034 -53.975 270)
			(size 0.519938 1.4986)
			(layers "F.Cu" "F.Mask" "F.Paste")
			(net "M_D_CPU1_SA_DQS_DN<0>")
		)
		(pad "13" smd rect
			(at -2.050034 -53.125116 270)
			(size 0.519938 1.4986)
			(layers "F.Cu" "F.Mask" "F.Paste")
			(net "GND")
		)
		(pad "14" smd rect
			(at -2.050034 -52.274978 270)
			(size 0.519938 1.4986)
			(layers "F.Cu" "F.Mask" "F.Paste")
			(net "M_D_CPU1_SA_DQ<4>")
		)
		(pad "15" smd rect
			(at -2.050034 -51.425094 270)
			(size 0.519938 1.4986)
			(layers "F.Cu" "F.Mask" "F.Paste")
			(net "GND")
		)
		(pad "16" smd rect
			(at -2.050034 -50.574956 270)
			(size 0.519938 1.4986)
			(layers "F.Cu" "F.Mask" "F.Paste")
			(net "M_D_CPU1_SA_DQ<5>")
		)
		(pad "17" smd rect
			(at -2.050034 -49.725072 270)
			(size 0.519938 1.4986)
			(layers "F.Cu" "F.Mask" "F.Paste")
			(net "GND")
		)
		(pad "18" smd rect
			(at -2.050034 -48.874934 270)
			(size 0.519938 1.4986)
			(layers "F.Cu" "F.Mask" "F.Paste")
			(net "M_D_CPU1_SA_DQ<8>")
		)
		(pad "19" smd rect
			(at -2.050034 -48.02505 270)
			(size 0.519938 1.4986)
			(layers "F.Cu" "F.Mask" "F.Paste")
			(net "GND")
		)
		(pad "20" smd rect
			(at -2.050034 -47.174912 270)
			(size 0.519938 1.4986)
			(layers "F.Cu" "F.Mask" "F.Paste")
			(net "M_D_CPU1_SA_DQ<9>")
		)
		(pad "21" smd rect
			(at -2.050034 -46.325028 270)
			(size 0.519938 1.4986)
			(layers "F.Cu" "F.Mask" "F.Paste")
			(net "GND")
		)
		(pad "22" smd rect
			(at -2.050034 -45.47489 270)
			(size 0.519938 1.4986)
			(layers "F.Cu" "F.Mask" "F.Paste")
			(net "M_D_CPU1_SA_DQS_DP<1>")
		)
		(pad "23" smd rect
			(at -2.050034 -44.625006 270)
			(size 0.519938 1.4986)
			(layers "F.Cu" "F.Mask" "F.Paste")
			(net "M_D_CPU1_SA_DQS_DN<1>")
		)
		(pad "24" smd rect
			(at -2.050034 -43.775122 270)
			(size 0.519938 1.4986)
			(layers "F.Cu" "F.Mask" "F.Paste")
			(net "GND")
		)
		(pad "25" smd rect
			(at -2.050034 -42.924984 270)
			(size 0.519938 1.4986)
			(layers "F.Cu" "F.Mask" "F.Paste")
			(net "M_D_CPU1_SA_DQ<12>")
		)
		(pad "26" smd rect
			(at -2.050034 -42.0751 270)
			(size 0.519938 1.4986)
			(layers "F.Cu" "F.Mask" "F.Paste")
			(net "GND")
		)
		(pad "27" smd rect
			(at -2.050034 -41.224962 270)
			(size 0.519938 1.4986)
			(layers "F.Cu" "F.Mask" "F.Paste")
			(net "M_D_CPU1_SA_DQ<13>")
		)
		(pad "28" smd rect
			(at -2.050034 -40.375078 270)
			(size 0.519938 1.4986)
			(layers "F.Cu" "F.Mask" "F.Paste")
			(net "GND")
		)
		(pad "29" smd rect
			(at -2.050034 -39.52494 270)
			(size 0.519938 1.4986)
			(layers "F.Cu" "F.Mask" "F.Paste")
			(net "M_D_CPU1_SA_DQ<16>")
		)
		(pad "30" smd rect
			(at -2.050034 -38.675056 270)
			(size 0.519938 1.4986)
			(layers "F.Cu" "F.Mask" "F.Paste")
			(net "GND")
		)
		(pad "31" smd rect
			(at -2.050034 -37.824918 270)
			(size 0.519938 1.4986)
			(layers "F.Cu" "F.Mask" "F.Paste")
			(net "M_D_CPU1_SA_DQ<17>")
		)
		(pad "32" smd rect
			(at -2.050034 -36.975034 270)
			(size 0.519938 1.4986)
			(layers "F.Cu" "F.Mask" "F.Paste")
			(net "GND")
		)
		(pad "33" smd rect
			(at -2.050034 -36.124896 270)
			(size 0.519938 1.4986)
			(layers "F.Cu" "F.Mask" "F.Paste")
			(net "M_D_CPU1_SA_DQS_DP<2>")
		)
		(pad "34" smd rect
			(at -2.050034 -35.275012 270)
			(size 0.519938 1.4986)
			(layers "F.Cu" "F.Mask" "F.Paste")
			(net "M_D_CPU1_SA_DQS_DN<2>")
		)
		(pad "35" smd rect
			(at -2.050034 -34.425128 270)
			(size 0.519938 1.4986)
			(layers "F.Cu" "F.Mask" "F.Paste")
			(net "GND")
		)
		(pad "36" smd rect
			(at -2.050034 -33.57499 270)
			(size 0.519938 1.4986)
			(layers "F.Cu" "F.Mask" "F.Paste")
			(net "M_D_CPU1_SA_DQ<20>")
		)
		(pad "37" smd rect
			(at -2.050034 -32.725106 270)
			(size 0.519938 1.4986)
			(layers "F.Cu" "F.Mask" "F.Paste")
			(net "GND")
		)
		(pad "38" smd rect
			(at -2.050034 -31.874968 270)
			(size 0.519938 1.4986)
			(layers "F.Cu" "F.Mask" "F.Paste")
			(net "M_D_CPU1_SA_DQ<21>")
		)
		(pad "39" smd rect
			(at -2.050034 -31.025084 270)
			(size 0.519938 1.4986)
			(layers "F.Cu" "F.Mask" "F.Paste")
			(net "GND")
		)
		(pad "40" smd rect
			(at -2.050034 -30.174946 270)
			(size 0.519938 1.4986)
			(layers "F.Cu" "F.Mask" "F.Paste")
			(net "M_D_CPU1_SA_DQ<24>")
		)
		(pad "41" smd rect
			(at -2.050034 -29.325062 270)
			(size 0.519938 1.4986)
			(layers "F.Cu" "F.Mask" "F.Paste")
			(net "GND")
		)
		(pad "42" smd rect
			(at -2.050034 -28.474924 270)
			(size 0.519938 1.4986)
			(layers "F.Cu" "F.Mask" "F.Paste")
			(net "M_D_CPU1_SA_DQ<25>")
		)
		(pad "43" smd rect
			(at -2.050034 -27.62504 270)
			(size 0.519938 1.4986)
			(layers "F.Cu" "F.Mask" "F.Paste")
			(net "GND")
		)
		(pad "44" smd rect
			(at -2.050034 -26.774902 270)
			(size 0.519938 1.4986)
			(layers "F.Cu" "F.Mask" "F.Paste")
			(net "M_D_CPU1_SA_DQS_DP<3>")
		)
		(pad "45" smd rect
			(at -2.050034 -25.925018 270)
			(size 0.519938 1.4986)
			(layers "F.Cu" "F.Mask" "F.Paste")
			(net "M_D_CPU1_SA_DQS_DN<3>")
		)
		(pad "46" smd rect
			(at -2.050034 -25.07488 270)
			(size 0.519938 1.4986)
			(layers "F.Cu" "F.Mask" "F.Paste")
			(net "GND")
		)
		(pad "47" smd rect
			(at -2.050034 -24.224996 270)
			(size 0.519938 1.4986)
			(layers "F.Cu" "F.Mask" "F.Paste")
			(net "M_D_CPU1_SA_DQ<28>")
		)
		(pad "48" smd rect
			(at -2.050034 -23.375112 270)
			(size 0.519938 1.4986)
			(layers "F.Cu" "F.Mask" "F.Paste")
			(net "GND")
		)
		(pad "49" smd rect
			(at -2.050034 -22.524974 270)
			(size 0.519938 1.4986)
			(layers "F.Cu" "F.Mask" "F.Paste")
			(net "M_D_CPU1_SA_DQ<29>")
		)
		(pad "50" smd rect
			(at -2.050034 -21.67509 270)
			(size 0.519938 1.4986)
			(layers "F.Cu" "F.Mask" "F.Paste")
			(net "GND")
		)
		(pad "51" smd rect
			(at -2.050034 -20.824952 270)
			(size 0.519938 1.4986)
			(layers "F.Cu" "F.Mask" "F.Paste")
			(net "M_D_CPU1_SA_CB<0>")
		)
		(pad "52" smd rect
			(at -2.050034 -19.975068 270)
			(size 0.519938 1.4986)
			(layers "F.Cu" "F.Mask" "F.Paste")
			(net "GND")
		)
		(pad "53" smd rect
			(at -2.050034 -19.12493 270)
			(size 0.519938 1.4986)
			(layers "F.Cu" "F.Mask" "F.Paste")
			(net "M_D_CPU1_SA_CB<1>")
		)
		(pad "54" smd rect
			(at -2.050034 -18.275046 270)
			(size 0.519938 1.4986)
			(layers "F.Cu" "F.Mask" "F.Paste")
			(net "GND")
		)
		(pad "55" smd rect
			(at -2.050034 -17.424908 270)
			(size 0.519938 1.4986)
			(layers "F.Cu" "F.Mask" "F.Paste")
			(net "M_D_CPU1_SA_DQS_DP<4>")
		)
		(pad "56" smd rect
			(at -2.050034 -16.575024 270)
			(size 0.519938 1.4986)
			(layers "F.Cu" "F.Mask" "F.Paste")
			(net "M_D_CPU1_SA_DQS_DN<4>")
		)
		(pad "57" smd rect
			(at -2.050034 -15.724886 270)
			(size 0.519938 1.4986)
			(layers "F.Cu" "F.Mask" "F.Paste")
			(net "GND")
		)
		(pad "58" smd rect
			(at -2.050034 -14.875002 270)
			(size 0.519938 1.4986)
			(layers "F.Cu" "F.Mask" "F.Paste")
			(net "M_D_CPU1_SA_CB<4>")
		)
		(pad "59" smd rect
			(at -2.050034 -14.025118 270)
			(size 0.519938 1.4986)
			(layers "F.Cu" "F.Mask" "F.Paste")
			(net "GND")
		)
		(pad "60" smd rect
			(at -2.050034 -13.17498 270)
			(size 0.519938 1.4986)
			(layers "F.Cu" "F.Mask" "F.Paste")
			(net "M_D_CPU1_SA_CB<5>")
		)
		(pad "61" smd rect
			(at -2.050034 -12.325096 270)
			(size 0.519938 1.4986)
			(layers "F.Cu" "F.Mask" "F.Paste")
			(net "GND")
		)
		(pad "62" smd rect
			(at -2.050034 -11.474958 270)
			(size 0.519938 1.4986)
			(layers "F.Cu" "F.Mask" "F.Paste")
			(net "M_D_CPU1_ALERT_N")
		)
		(pad "63" smd rect
			(at -2.050034 -10.625074 270)
			(size 0.519938 1.4986)
			(layers "F.Cu" "F.Mask" "F.Paste")
			(net "GND")
		)
		(pad "64" smd rect
			(at -2.050034 -9.774936 270)
			(size 0.519938 1.4986)
			(layers "F.Cu" "F.Mask" "F.Paste")
			(net "M_D_CPU1_SA_CS_N<2>")
		)
		(pad "65" smd rect
			(at -2.050034 -8.925052 270)
			(size 0.519938 1.4986)
			(layers "F.Cu" "F.Mask" "F.Paste")
			(net "GND")
		)
		(pad "66" smd rect
			(at -2.050034 -8.074914 270)
			(size 0.519938 1.4986)
			(layers "F.Cu" "F.Mask" "F.Paste")
			(net "M_D_CPU1_SA_CA<0>")
		)
		(pad "67" smd rect
			(at -2.050034 -7.22503 270)
			(size 0.519938 1.4986)
			(layers "F.Cu" "F.Mask" "F.Paste")
			(net "GND")
		)
		(pad "68" smd rect
			(at -2.050034 -6.374892 270)
			(size 0.519938 1.4986)
			(layers "F.Cu" "F.Mask" "F.Paste")
			(net "M_D_CPU1_SA_CA<2>")
		)
		(pad "69" smd rect
			(at -2.050034 -5.525008 270)
			(size 0.519938 1.4986)
			(layers "F.Cu" "F.Mask" "F.Paste")
			(net "GND")
		)
		(pad "70" smd rect
			(at -2.050034 -4.675124 270)
			(size 0.519938 1.4986)
			(layers "F.Cu" "F.Mask" "F.Paste")
			(net "M_D_CPU1_SA_CA<4>")
		)
		(pad "71" smd rect
			(at -2.050034 -3.824986 270)
			(size 0.519938 1.4986)
			(layers "F.Cu" "F.Mask" "F.Paste")
			(net "GND")
		)
		(pad "72" smd rect
			(at -2.050034 -2.975102 270)
			(size 0.519938 1.4986)
			(layers "F.Cu" "F.Mask" "F.Paste")
			(net "M_D_CPU1_SA_CA<6>")
		)
		(pad "73" smd rect
			(at -2.050034 -2.124964 270)
			(size 0.519938 1.4986)
			(layers "F.Cu" "F.Mask" "F.Paste")
			(net "GND")
		)
		(pad "74" smd rect
			(at -2.050034 -1.27508 270)
			(size 0.519938 1.4986)
			(layers "F.Cu" "F.Mask" "F.Paste")
			(net "M_D_CPU1_SA_PAR")
		)
		(pad "75" smd rect
			(at -2.050034 -0.424942 270)
			(size 0.519938 1.4986)
			(layers "F.Cu" "F.Mask" "F.Paste")
			(net "GND")
		)
		(pad "76" smd rect
			(at -2.050034 5.525008 270)
			(size 0.519938 1.4986)
			(layers "F.Cu" "F.Mask" "F.Paste")
			(net "M_D_CPU1_SB_CA<0>")
		)
		(pad "77" smd rect
			(at -2.050034 6.374892 270)
			(size 0.519938 1.4986)
			(layers "F.Cu" "F.Mask" "F.Paste")
			(net "GND")
		)
		(pad "78" smd rect
			(at -2.050034 7.22503 270)
			(size 0.519938 1.4986)
			(layers "F.Cu" "F.Mask" "F.Paste")
			(net "M_D_CPU1_SB_CA<2>")
		)
		(pad "79" smd rect
			(at -2.050034 8.074914 270)
			(size 0.519938 1.4986)
			(layers "F.Cu" "F.Mask" "F.Paste")
			(net "GND")
		)
		(pad "80" smd rect
			(at -2.050034 8.925052 270)
			(size 0.519938 1.4986)
			(layers "F.Cu" "F.Mask" "F.Paste")
			(net "M_D_CPU1_SB_CA<4>")
		)
		(pad "81" smd rect
			(at -2.050034 9.774936 270)
			(size 0.519938 1.4986)
			(layers "F.Cu" "F.Mask" "F.Paste")
			(net "GND")
		)
		(pad "82" smd rect
			(at -2.050034 10.625074 270)
			(size 0.519938 1.4986)
			(layers "F.Cu" "F.Mask" "F.Paste")
			(net "M_D_CPU1_SB_CA<6>")
		)
		(pad "83" smd rect
			(at -2.050034 11.474958 270)
			(size 0.519938 1.4986)
			(layers "F.Cu" "F.Mask" "F.Paste")
			(net "GND")
		)
		(pad "84" smd rect
			(at -2.050034 12.325096 270)
			(size 0.519938 1.4986)
			(layers "F.Cu" "F.Mask" "F.Paste")
			(net "M_D_CPU1_SB_CS_N<2>")
		)
		(pad "85" smd rect
			(at -2.050034 13.17498 270)
			(size 0.519938 1.4986)
			(layers "F.Cu" "F.Mask" "F.Paste")
			(net "GND")
		)
		(pad "86" smd rect
			(at -2.050034 14.025118 270)
			(size 0.519938 1.4986)
			(layers "F.Cu" "F.Mask" "F.Paste")
			(net "M_D_CPU1_SA_RSP<1>")
		)
		(pad "87" smd rect
			(at -2.050034 14.875002 270)
			(size 0.519938 1.4986)
			(layers "F.Cu" "F.Mask" "F.Paste")
			(net "M_D_CPU1_SB_RSP<1>")
		)
		(pad "88" smd rect
			(at -2.050034 15.724886 270)
			(size 0.519938 1.4986)
			(layers "F.Cu" "F.Mask" "F.Paste")
			(net "GND")
		)
		(pad "89" smd rect
			(at -2.050034 16.575024 270)
			(size 0.519938 1.4986)
			(layers "F.Cu" "F.Mask" "F.Paste")
			(net "M_D_CPU1_SB_CB<4>")
		)
		(pad "90" smd rect
			(at -2.050034 17.424908 270)
			(size 0.519938 1.4986)
			(layers "F.Cu" "F.Mask" "F.Paste")
			(net "GND")
		)
		(pad "91" smd rect
			(at -2.050034 18.275046 270)
			(size 0.519938 1.4986)
			(layers "F.Cu" "F.Mask" "F.Paste")
			(net "M_D_CPU1_SB_CB<5>")
		)
		(pad "92" smd rect
			(at -2.050034 19.12493 270)
			(size 0.519938 1.4986)
			(layers "F.Cu" "F.Mask" "F.Paste")
			(net "GND")
		)
		(pad "93" smd rect
			(at -2.050034 19.975068 270)
			(size 0.519938 1.4986)
			(layers "F.Cu" "F.Mask" "F.Paste")
			(net "M_D_CPU1_SB_DQS_DP<9>")
		)
		(pad "94" smd rect
			(at -2.050034 20.824952 270)
			(size 0.519938 1.4986)
			(layers "F.Cu" "F.Mask" "F.Paste")
			(net "M_D_CPU1_SB_DQS_DN<9>")
		)
		(pad "95" smd rect
			(at -2.050034 21.67509 270)
			(size 0.519938 1.4986)
			(layers "F.Cu" "F.Mask" "F.Paste")
			(net "GND")
		)
		(pad "96" smd rect
			(at -2.050034 22.524974 270)
			(size 0.519938 1.4986)
			(layers "F.Cu" "F.Mask" "F.Paste")
			(net "M_D_CPU1_SB_CB<0>")
		)
		(pad "97" smd rect
			(at -2.050034 23.375112 270)
			(size 0.519938 1.4986)
			(layers "F.Cu" "F.Mask" "F.Paste")
			(net "GND")
		)
		(pad "98" smd rect
			(at -2.050034 24.224996 270)
			(size 0.519938 1.4986)
			(layers "F.Cu" "F.Mask" "F.Paste")
			(net "M_D_CPU1_SB_CB<1>")
		)
		(pad "99" smd rect
			(at -2.050034 25.07488 270)
			(size 0.519938 1.4986)
			(layers "F.Cu" "F.Mask" "F.Paste")
			(net "GND")
		)
		(pad "100" smd rect
			(at -2.050034 25.925018 270)
			(size 0.519938 1.4986)
			(layers "F.Cu" "F.Mask" "F.Paste")
			(net "M_D_CPU1_SB_DQ<0>")
		)
		(pad "101" smd rect
			(at -2.050034 26.774902 270)
			(size 0.519938 1.4986)
			(layers "F.Cu" "F.Mask" "F.Paste")
			(net "GND")
		)
		(pad "102" smd rect
			(at -2.050034 27.62504 270)
			(size 0.519938 1.4986)
			(layers "F.Cu" "F.Mask" "F.Paste")
			(net "M_D_CPU1_SB_DQ<1>")
		)
		(pad "103" smd rect
			(at -2.050034 28.474924 270)
			(size 0.519938 1.4986)
			(layers "F.Cu" "F.Mask" "F.Paste")
			(net "GND")
		)
		(pad "104" smd rect
			(at -2.050034 29.325062 270)
			(size 0.519938 1.4986)
			(layers "F.Cu" "F.Mask" "F.Paste")
			(net "M_D_CPU1_SB_DQS_DP<0>")
		)
		(pad "105" smd rect
			(at -2.050034 30.174946 270)
			(size 0.519938 1.4986)
			(layers "F.Cu" "F.Mask" "F.Paste")
			(net "M_D_CPU1_SB_DQS_DN<0>")
		)
		(pad "106" smd rect
			(at -2.050034 31.025084 270)
			(size 0.519938 1.4986)
			(layers "F.Cu" "F.Mask" "F.Paste")
			(net "GND")
		)
		(pad "107" smd rect
			(at -2.050034 31.874968 270)
			(size 0.519938 1.4986)
			(layers "F.Cu" "F.Mask" "F.Paste")
			(net "M_D_CPU1_SB_DQ<4>")
		)
		(pad "108" smd rect
			(at -2.050034 32.725106 270)
			(size 0.519938 1.4986)
			(layers "F.Cu" "F.Mask" "F.Paste")
			(net "GND")
		)
		(pad "109" smd rect
			(at -2.050034 33.57499 270)
			(size 0.519938 1.4986)
			(layers "F.Cu" "F.Mask" "F.Paste")
			(net "M_D_CPU1_SB_DQ<5>")
		)
		(pad "110" smd rect
			(at -2.050034 34.425128 270)
			(size 0.519938 1.4986)
			(layers "F.Cu" "F.Mask" "F.Paste")
			(net "GND")
		)
		(pad "111" smd rect
			(at -2.050034 35.275012 270)
			(size 0.519938 1.4986)
			(layers "F.Cu" "F.Mask" "F.Paste")
			(net "M_D_CPU1_SB_DQ<8>")
		)
		(pad "112" smd rect
			(at -2.050034 36.124896 270)
			(size 0.519938 1.4986)
			(layers "F.Cu" "F.Mask" "F.Paste")
			(net "GND")
		)
		(pad "113" smd rect
			(at -2.050034 36.975034 270)
			(size 0.519938 1.4986)
			(layers "F.Cu" "F.Mask" "F.Paste")
			(net "M_D_CPU1_SB_DQ<9>")
		)
		(pad "114" smd rect
			(at -2.050034 37.824918 270)
			(size 0.519938 1.4986)
			(layers "F.Cu" "F.Mask" "F.Paste")
			(net "GND")
		)
		(pad "115" smd rect
			(at -2.050034 38.675056 270)
			(size 0.519938 1.4986)
			(layers "F.Cu" "F.Mask" "F.Paste")
			(net "M_D_CPU1_SB_DQS_DP<1>")
		)
		(pad "116" smd rect
			(at -2.050034 39.52494 270)
			(size 0.519938 1.4986)
			(layers "F.Cu" "F.Mask" "F.Paste")
			(net "M_D_CPU1_SB_DQS_DN<1>")
		)
		(pad "117" smd rect
			(at -2.050034 40.375078 270)
			(size 0.519938 1.4986)
			(layers "F.Cu" "F.Mask" "F.Paste")
			(net "GND")
		)
		(pad "118" smd rect
			(at -2.050034 41.224962 270)
			(size 0.519938 1.4986)
			(layers "F.Cu" "F.Mask" "F.Paste")
			(net "M_D_CPU1_SB_DQ<12>")
		)
		(pad "119" smd rect
			(at -2.050034 42.0751 270)
			(size 0.519938 1.4986)
			(layers "F.Cu" "F.Mask" "F.Paste")
			(net "GND")
		)
		(pad "120" smd rect
			(at -2.050034 42.924984 270)
			(size 0.519938 1.4986)
			(layers "F.Cu" "F.Mask" "F.Paste")
			(net "M_D_CPU1_SB_DQ<13>")
		)
		(pad "121" smd rect
			(at -2.050034 43.775122 270)
			(size 0.519938 1.4986)
			(layers "F.Cu" "F.Mask" "F.Paste")
			(net "GND")
		)
		(pad "122" smd rect
			(at -2.050034 44.625006 270)
			(size 0.519938 1.4986)
			(layers "F.Cu" "F.Mask" "F.Paste")
			(net "M_D_CPU1_SB_DQ<16>")
		)
		(pad "123" smd rect
			(at -2.050034 45.47489 270)
			(size 0.519938 1.4986)
			(layers "F.Cu" "F.Mask" "F.Paste")
			(net "GND")
		)
		(pad "124" smd rect
			(at -2.050034 46.325028 270)
			(size 0.519938 1.4986)
			(layers "F.Cu" "F.Mask" "F.Paste")
			(net "M_D_CPU1_SB_DQ<17>")
		)
		(pad "125" smd rect
			(at -2.050034 47.174912 270)
			(size 0.519938 1.4986)
			(layers "F.Cu" "F.Mask" "F.Paste")
			(net "GND")
		)
		(pad "126" smd rect
			(at -2.050034 48.02505 270)
			(size 0.519938 1.4986)
			(layers "F.Cu" "F.Mask" "F.Paste")
			(net "M_D_CPU1_SB_DQS_DP<2>")
		)
		(pad "127" smd rect
			(at -2.050034 48.874934 270)
			(size 0.519938 1.4986)
			(layers "F.Cu" "F.Mask" "F.Paste")
			(net "M_D_CPU1_SB_DQS_DN<2>")
		)
		(pad "128" smd rect
			(at -2.050034 49.725072 270)
			(size 0.519938 1.4986)
			(layers "F.Cu" "F.Mask" "F.Paste")
			(net "GND")
		)
		(pad "129" smd rect
			(at -2.050034 50.574956 270)
			(size 0.519938 1.4986)
			(layers "F.Cu" "F.Mask" "F.Paste")
			(net "M_D_CPU1_SB_DQ<20>")
		)
		(pad "130" smd rect
			(at -2.050034 51.425094 270)
			(size 0.519938 1.4986)
			(layers "F.Cu" "F.Mask" "F.Paste")
			(net "GND")
		)
		(pad "131" smd rect
			(at -2.050034 52.274978 270)
			(size 0.519938 1.4986)
			(layers "F.Cu" "F.Mask" "F.Paste")
			(net "M_D_CPU1_SB_DQ<21>")
		)
		(pad "132" smd rect
			(at -2.050034 53.125116 270)
			(size 0.519938 1.4986)
			(layers "F.Cu" "F.Mask" "F.Paste")
			(net "GND")
		)
		(pad "133" smd rect
			(at -2.050034 53.975 270)
			(size 0.519938 1.4986)
			(layers "F.Cu" "F.Mask" "F.Paste")
			(net "M_D_CPU1_SB_DQ<24>")
		)
		(pad "134" smd rect
			(at -2.050034 54.824884 270)
			(size 0.519938 1.4986)
			(layers "F.Cu" "F.Mask" "F.Paste")
			(net "GND")
		)
		(pad "135" smd rect
			(at -2.050034 55.675022 270)
			(size 0.519938 1.4986)
			(layers "F.Cu" "F.Mask" "F.Paste")
			(net "M_D_CPU1_SB_DQ<25>")
		)
		(pad "136" smd rect
			(at -2.050034 56.524906 270)
			(size 0.519938 1.4986)
			(layers "F.Cu" "F.Mask" "F.Paste")
			(net "GND")
		)
		(pad "137" smd rect
			(at -2.050034 57.375044 270)
			(size 0.519938 1.4986)
			(layers "F.Cu" "F.Mask" "F.Paste")
			(net "M_D_CPU1_SB_DQS_DP<3>")
		)
		(pad "138" smd rect
			(at -2.050034 58.224928 270)
			(size 0.519938 1.4986)
			(layers "F.Cu" "F.Mask" "F.Paste")
			(net "M_D_CPU1_SB_DQS_DN<3>")
		)
		(pad "139" smd rect
			(at -2.050034 59.075066 270)
			(size 0.519938 1.4986)
			(layers "F.Cu" "F.Mask" "F.Paste")
			(net "GND")
		)
		(pad "140" smd rect
			(at -2.050034 59.92495 270)
			(size 0.519938 1.4986)
			(layers "F.Cu" "F.Mask" "F.Paste")
			(net "M_D_CPU1_SB_DQ<28>")
		)
		(pad "141" smd rect
			(at -2.050034 60.775088 270)
			(size 0.519938 1.4986)
			(layers "F.Cu" "F.Mask" "F.Paste")
			(net "GND")
		)
		(pad "142" smd rect
			(at -2.050034 61.624972 270)
			(size 0.519938 1.4986)
			(layers "F.Cu" "F.Mask" "F.Paste")
			(net "M_D_CPU1_SB_DQ<29>")
		)
		(pad "143" smd rect
			(at -2.050034 62.47511 270)
			(size 0.519938 1.4986)
			(layers "F.Cu" "F.Mask" "F.Paste")
			(net "GND")
		)
		(pad "144" smd rect
			(at -2.050034 63.324994 270)
			(size 0.519938 1.4986)
			(layers "F.Cu" "F.Mask" "F.Paste")
			(net "TP_CHD_CPU1_DIMM2_FRU_1")
		)
		(pad "145" smd rect
			(at 2.050034 -63.324994 270)
			(size 0.519938 1.4986)
			(layers "F.Cu" "F.Mask" "F.Paste")
			(net "P12V_S3_AUX_CPU1_NVDIMM")
		)
		(pad "146" smd rect
			(at 2.050034 -62.47511 270)
			(size 0.519938 1.4986)
			(layers "F.Cu" "F.Mask" "F.Paste")
			(net "P12V_S3_AUX_CPU1_NVDIMM")
		)
		(pad "147" smd rect
			(at 2.050034 -61.624972 270)
			(size 0.519938 1.4986)
			(layers "F.Cu" "F.Mask" "F.Paste")
			(net "PWRGD_CHD_CPU1_DIMM2")
		)
		(pad "148" smd rect
			(at 2.050034 -60.775088 270)
			(size 0.519938 1.4986)
			(layers "F.Cu" "F.Mask" "F.Paste")
			(net "PD_CHD_CPU1_DIMM2_SAA")
		)
		(pad "149" smd rect
			(at 2.050034 -59.92495 270)
			(size 0.519938 1.4986)
			(layers "F.Cu" "F.Mask" "F.Paste")
			(net "TP_CHD_CPU1_DIMM2_FRU_2")
		)
		(pad "150" smd rect
			(at 2.050034 -59.075066 270)
			(size 0.519938 1.4986)
			(layers "F.Cu" "F.Mask" "F.Paste")
			(net "TP_CHD_CPU1_DIMM2_FRU_3")
		)
		(pad "151" smd rect
			(at 2.050034 -58.224928 270)
			(size 0.519938 1.4986)
			(layers "F.Cu" "F.Mask" "F.Paste")
			(net "GND")
		)
		(pad "152" smd rect
			(at 2.050034 -57.375044 270)
			(size 0.519938 1.4986)
			(layers "F.Cu" "F.Mask" "F.Paste")
			(net "M_D_CPU1_SA_DQ<2>")
		)
		(pad "153" smd rect
			(at 2.050034 -56.524906 270)
			(size 0.519938 1.4986)
			(layers "F.Cu" "F.Mask" "F.Paste")
			(net "GND")
		)
		(pad "154" smd rect
			(at 2.050034 -55.675022 270)
			(size 0.519938 1.4986)
			(layers "F.Cu" "F.Mask" "F.Paste")
			(net "M_D_CPU1_SA_DQ<3>")
		)
		(pad "155" smd rect
			(at 2.050034 -54.824884 270)
			(size 0.519938 1.4986)
			(layers "F.Cu" "F.Mask" "F.Paste")
			(net "GND")
		)
		(pad "156" smd rect
			(at 2.050034 -53.975 270)
			(size 0.519938 1.4986)
			(layers "F.Cu" "F.Mask" "F.Paste")
			(net "M_D_CPU1_SA_DQS_DN<5>")
		)
		(pad "157" smd rect
			(at 2.050034 -53.125116 270)
			(size 0.519938 1.4986)
			(layers "F.Cu" "F.Mask" "F.Paste")
			(net "M_D_CPU1_SA_DQS_DP<5>")
		)
		(pad "158" smd rect
			(at 2.050034 -52.274978 270)
			(size 0.519938 1.4986)
			(layers "F.Cu" "F.Mask" "F.Paste")
			(net "GND")
		)
		(pad "159" smd rect
			(at 2.050034 -51.425094 270)
			(size 0.519938 1.4986)
			(layers "F.Cu" "F.Mask" "F.Paste")
			(net "M_D_CPU1_SA_DQ<6>")
		)
		(pad "160" smd rect
			(at 2.050034 -50.574956 270)
			(size 0.519938 1.4986)
			(layers "F.Cu" "F.Mask" "F.Paste")
			(net "GND")
		)
		(pad "161" smd rect
			(at 2.050034 -49.725072 270)
			(size 0.519938 1.4986)
			(layers "F.Cu" "F.Mask" "F.Paste")
			(net "M_D_CPU1_SA_DQ<7>")
		)
		(pad "162" smd rect
			(at 2.050034 -48.874934 270)
			(size 0.519938 1.4986)
			(layers "F.Cu" "F.Mask" "F.Paste")
			(net "GND")
		)
		(pad "163" smd rect
			(at 2.050034 -48.02505 270)
			(size 0.519938 1.4986)
			(layers "F.Cu" "F.Mask" "F.Paste")
			(net "M_D_CPU1_SA_DQ<10>")
		)
		(pad "164" smd rect
			(at 2.050034 -47.174912 270)
			(size 0.519938 1.4986)
			(layers "F.Cu" "F.Mask" "F.Paste")
			(net "GND")
		)
		(pad "165" smd rect
			(at 2.050034 -46.325028 270)
			(size 0.519938 1.4986)
			(layers "F.Cu" "F.Mask" "F.Paste")
			(net "M_D_CPU1_SA_DQ<11>")
		)
		(pad "166" smd rect
			(at 2.050034 -45.47489 270)
			(size 0.519938 1.4986)
			(layers "F.Cu" "F.Mask" "F.Paste")
			(net "GND")
		)
		(pad "167" smd rect
			(at 2.050034 -44.625006 270)
			(size 0.519938 1.4986)
			(layers "F.Cu" "F.Mask" "F.Paste")
			(net "M_D_CPU1_SA_DQS_DN<6>")
		)
		(pad "168" smd rect
			(at 2.050034 -43.775122 270)
			(size 0.519938 1.4986)
			(layers "F.Cu" "F.Mask" "F.Paste")
			(net "M_D_CPU1_SA_DQS_DP<6>")
		)
		(pad "169" smd rect
			(at 2.050034 -42.924984 270)
			(size 0.519938 1.4986)
			(layers "F.Cu" "F.Mask" "F.Paste")
			(net "GND")
		)
		(pad "170" smd rect
			(at 2.050034 -42.0751 270)
			(size 0.519938 1.4986)
			(layers "F.Cu" "F.Mask" "F.Paste")
			(net "M_D_CPU1_SA_DQ<14>")
		)
		(pad "171" smd rect
			(at 2.050034 -41.224962 270)
			(size 0.519938 1.4986)
			(layers "F.Cu" "F.Mask" "F.Paste")
			(net "GND")
		)
		(pad "172" smd rect
			(at 2.050034 -40.375078 270)
			(size 0.519938 1.4986)
			(layers "F.Cu" "F.Mask" "F.Paste")
			(net "M_D_CPU1_SA_DQ<15>")
		)
		(pad "173" smd rect
			(at 2.050034 -39.52494 270)
			(size 0.519938 1.4986)
			(layers "F.Cu" "F.Mask" "F.Paste")
			(net "GND")
		)
		(pad "174" smd rect
			(at 2.050034 -38.675056 270)
			(size 0.519938 1.4986)
			(layers "F.Cu" "F.Mask" "F.Paste")
			(net "M_D_CPU1_SA_DQ<18>")
		)
		(pad "175" smd rect
			(at 2.050034 -37.824918 270)
			(size 0.519938 1.4986)
			(layers "F.Cu" "F.Mask" "F.Paste")
			(net "GND")
		)
		(pad "176" smd rect
			(at 2.050034 -36.975034 270)
			(size 0.519938 1.4986)
			(layers "F.Cu" "F.Mask" "F.Paste")
			(net "M_D_CPU1_SA_DQ<19>")
		)
		(pad "177" smd rect
			(at 2.050034 -36.124896 270)
			(size 0.519938 1.4986)
			(layers "F.Cu" "F.Mask" "F.Paste")
			(net "GND")
		)
		(pad "178" smd rect
			(at 2.050034 -35.275012 270)
			(size 0.519938 1.4986)
			(layers "F.Cu" "F.Mask" "F.Paste")
			(net "M_D_CPU1_SA_DQS_DN<7>")
		)
		(pad "179" smd rect
			(at 2.050034 -34.425128 270)
			(size 0.519938 1.4986)
			(layers "F.Cu" "F.Mask" "F.Paste")
			(net "M_D_CPU1_SA_DQS_DP<7>")
		)
		(pad "180" smd rect
			(at 2.050034 -33.57499 270)
			(size 0.519938 1.4986)
			(layers "F.Cu" "F.Mask" "F.Paste")
			(net "GND")
		)
		(pad "181" smd rect
			(at 2.050034 -32.725106 270)
			(size 0.519938 1.4986)
			(layers "F.Cu" "F.Mask" "F.Paste")
			(net "M_D_CPU1_SA_DQ<22>")
		)
		(pad "182" smd rect
			(at 2.050034 -31.874968 270)
			(size 0.519938 1.4986)
			(layers "F.Cu" "F.Mask" "F.Paste")
			(net "GND")
		)
		(pad "183" smd rect
			(at 2.050034 -31.025084 270)
			(size 0.519938 1.4986)
			(layers "F.Cu" "F.Mask" "F.Paste")
			(net "M_D_CPU1_SA_DQ<23>")
		)
		(pad "184" smd rect
			(at 2.050034 -30.174946 270)
			(size 0.519938 1.4986)
			(layers "F.Cu" "F.Mask" "F.Paste")
			(net "GND")
		)
		(pad "185" smd rect
			(at 2.050034 -29.325062 270)
			(size 0.519938 1.4986)
			(layers "F.Cu" "F.Mask" "F.Paste")
			(net "M_D_CPU1_SA_DQ<26>")
		)
		(pad "186" smd rect
			(at 2.050034 -28.474924 270)
			(size 0.519938 1.4986)
			(layers "F.Cu" "F.Mask" "F.Paste")
			(net "GND")
		)
		(pad "187" smd rect
			(at 2.050034 -27.62504 270)
			(size 0.519938 1.4986)
			(layers "F.Cu" "F.Mask" "F.Paste")
			(net "M_D_CPU1_SA_DQ<27>")
		)
		(pad "188" smd rect
			(at 2.050034 -26.774902 270)
			(size 0.519938 1.4986)
			(layers "F.Cu" "F.Mask" "F.Paste")
			(net "GND")
		)
		(pad "189" smd rect
			(at 2.050034 -25.925018 270)
			(size 0.519938 1.4986)
			(layers "F.Cu" "F.Mask" "F.Paste")
			(net "M_D_CPU1_SA_DQS_DN<8>")
		)
		(pad "190" smd rect
			(at 2.050034 -25.07488 270)
			(size 0.519938 1.4986)
			(layers "F.Cu" "F.Mask" "F.Paste")
			(net "M_D_CPU1_SA_DQS_DP<8>")
		)
		(pad "191" smd rect
			(at 2.050034 -24.224996 270)
			(size 0.519938 1.4986)
			(layers "F.Cu" "F.Mask" "F.Paste")
			(net "GND")
		)
		(pad "192" smd rect
			(at 2.050034 -23.375112 270)
			(size 0.519938 1.4986)
			(layers "F.Cu" "F.Mask" "F.Paste")
			(net "M_D_CPU1_SA_DQ<30>")
		)
		(pad "193" smd rect
			(at 2.050034 -22.524974 270)
			(size 0.519938 1.4986)
			(layers "F.Cu" "F.Mask" "F.Paste")
			(net "GND")
		)
		(pad "194" smd rect
			(at 2.050034 -21.67509 270)
			(size 0.519938 1.4986)
			(layers "F.Cu" "F.Mask" "F.Paste")
			(net "M_D_CPU1_SA_DQ<31>")
		)
		(pad "195" smd rect
			(at 2.050034 -20.824952 270)
			(size 0.519938 1.4986)
			(layers "F.Cu" "F.Mask" "F.Paste")
			(net "GND")
		)
		(pad "196" smd rect
			(at 2.050034 -19.975068 270)
			(size 0.519938 1.4986)
			(layers "F.Cu" "F.Mask" "F.Paste")
			(net "M_D_CPU1_SA_CB<2>")
		)
		(pad "197" smd rect
			(at 2.050034 -19.12493 270)
			(size 0.519938 1.4986)
			(layers "F.Cu" "F.Mask" "F.Paste")
			(net "GND")
		)
		(pad "198" smd rect
			(at 2.050034 -18.275046 270)
			(size 0.519938 1.4986)
			(layers "F.Cu" "F.Mask" "F.Paste")
			(net "M_D_CPU1_SA_CB<3>")
		)
		(pad "199" smd rect
			(at 2.050034 -17.424908 270)
			(size 0.519938 1.4986)
			(layers "F.Cu" "F.Mask" "F.Paste")
			(net "GND")
		)
		(pad "200" smd rect
			(at 2.050034 -16.575024 270)
			(size 0.519938 1.4986)
			(layers "F.Cu" "F.Mask" "F.Paste")
			(net "M_D_CPU1_SA_DQS_DN<9>")
		)
		(pad "201" smd rect
			(at 2.050034 -15.724886 270)
			(size 0.519938 1.4986)
			(layers "F.Cu" "F.Mask" "F.Paste")
			(net "M_D_CPU1_SA_DQS_DP<9>")
		)
		(pad "202" smd rect
			(at 2.050034 -14.875002 270)
			(size 0.519938 1.4986)
			(layers "F.Cu" "F.Mask" "F.Paste")
			(net "GND")
		)
		(pad "203" smd rect
			(at 2.050034 -14.025118 270)
			(size 0.519938 1.4986)
			(layers "F.Cu" "F.Mask" "F.Paste")
			(net "M_D_CPU1_SA_CB<6>")
		)
		(pad "204" smd rect
			(at 2.050034 -13.17498 270)
			(size 0.519938 1.4986)
			(layers "F.Cu" "F.Mask" "F.Paste")
			(net "GND")
		)
		(pad "205" smd rect
			(at 2.050034 -12.325096 270)
			(size 0.519938 1.4986)
			(layers "F.Cu" "F.Mask" "F.Paste")
			(net "M_D_CPU1_SA_CB<7>")
		)
		(pad "206" smd rect
			(at 2.050034 -11.474958 270)
			(size 0.519938 1.4986)
			(layers "F.Cu" "F.Mask" "F.Paste")
			(net "GND")
		)
		(pad "207" smd rect
			(at 2.050034 -10.625074 270)
			(size 0.519938 1.4986)
			(layers "F.Cu" "F.Mask" "F.Paste")
			(net "RST_M_CD_CPU1_FPGA_N")
		)
		(pad "208" smd rect
			(at 2.050034 -9.774936 270)
			(size 0.519938 1.4986)
			(layers "F.Cu" "F.Mask" "F.Paste")
			(net "GND")
		)
		(pad "209" smd rect
			(at 2.050034 -8.925052 270)
			(size 0.519938 1.4986)
			(layers "F.Cu" "F.Mask" "F.Paste")
			(net "M_D_CPU1_SA_CS_N<3>")
		)
		(pad "210" smd rect
			(at 2.050034 -8.074914 270)
			(size 0.519938 1.4986)
			(layers "F.Cu" "F.Mask" "F.Paste")
			(net "GND")
		)
		(pad "211" smd rect
			(at 2.050034 -7.22503 270)
			(size 0.519938 1.4986)
			(layers "F.Cu" "F.Mask" "F.Paste")
			(net "M_D_CPU1_SA_CA<1>")
		)
		(pad "212" smd rect
			(at 2.050034 -6.374892 270)
			(size 0.519938 1.4986)
			(layers "F.Cu" "F.Mask" "F.Paste")
			(net "GND")
		)
		(pad "213" smd rect
			(at 2.050034 -5.525008 270)
			(size 0.519938 1.4986)
			(layers "F.Cu" "F.Mask" "F.Paste")
			(net "M_D_CPU1_SA_CA<3>")
		)
		(pad "214" smd rect
			(at 2.050034 -4.675124 270)
			(size 0.519938 1.4986)
			(layers "F.Cu" "F.Mask" "F.Paste")
			(net "GND")
		)
		(pad "215" smd rect
			(at 2.050034 -3.824986 270)
			(size 0.519938 1.4986)
			(layers "F.Cu" "F.Mask" "F.Paste")
			(net "M_D_CPU1_SA_CA<5>")
		)
		(pad "216" smd rect
			(at 2.050034 -2.975102 270)
			(size 0.519938 1.4986)
			(layers "F.Cu" "F.Mask" "F.Paste")
			(net "GND")
		)
		(pad "217" smd rect
			(at 2.050034 -2.124964 270)
			(size 0.519938 1.4986)
			(layers "F.Cu" "F.Mask" "F.Paste")
			(net "M_D_CPU1_CLK_DP<1>")
		)
		(pad "218" smd rect
			(at 2.050034 -1.27508 270)
			(size 0.519938 1.4986)
			(layers "F.Cu" "F.Mask" "F.Paste")
			(net "M_D_CPU1_CLK_DN<1>")
		)
		(pad "219" smd rect
			(at 2.050034 -0.424942 270)
			(size 0.519938 1.4986)
			(layers "F.Cu" "F.Mask" "F.Paste")
			(net "GND")
		)
		(pad "220" smd rect
			(at 2.050034 5.525008 270)
			(size 0.519938 1.4986)
			(layers "F.Cu" "F.Mask" "F.Paste")
			(net "TP_CHD_CPU1_DIMM2_FRU_4")
		)
		(pad "221" smd rect
			(at 2.050034 6.374892 270)
			(size 0.519938 1.4986)
			(layers "F.Cu" "F.Mask" "F.Paste")
			(net "M_D_CPU1_SB_CA<1>")
		)
		(pad "222" smd rect
			(at 2.050034 7.22503 270)
			(size 0.519938 1.4986)
			(layers "F.Cu" "F.Mask" "F.Paste")
			(net "GND")
		)
		(pad "223" smd rect
			(at 2.050034 8.074914 270)
			(size 0.519938 1.4986)
			(layers "F.Cu" "F.Mask" "F.Paste")
			(net "M_D_CPU1_SB_CA<3>")
		)
		(pad "224" smd rect
			(at 2.050034 8.925052 270)
			(size 0.519938 1.4986)
			(layers "F.Cu" "F.Mask" "F.Paste")
			(net "GND")
		)
		(pad "225" smd rect
			(at 2.050034 9.774936 270)
			(size 0.519938 1.4986)
			(layers "F.Cu" "F.Mask" "F.Paste")
			(net "M_D_CPU1_SB_CA<5>")
		)
		(pad "226" smd rect
			(at 2.050034 10.625074 270)
			(size 0.519938 1.4986)
			(layers "F.Cu" "F.Mask" "F.Paste")
			(net "GND")
		)
		(pad "227" smd rect
			(at 2.050034 11.474958 270)
			(size 0.519938 1.4986)
			(layers "F.Cu" "F.Mask" "F.Paste")
			(net "M_D_CPU1_SB_PAR")
		)
		(pad "228" smd rect
			(at 2.050034 12.325096 270)
			(size 0.519938 1.4986)
			(layers "F.Cu" "F.Mask" "F.Paste")
			(net "GND")
		)
		(pad "229" smd rect
			(at 2.050034 13.17498 270)
			(size 0.519938 1.4986)
			(layers "F.Cu" "F.Mask" "F.Paste")
			(net "M_D_CPU1_SB_CS_N<3>")
		)
		(pad "230" smd rect
			(at 2.050034 14.025118 270)
			(size 0.519938 1.4986)
			(layers "F.Cu" "F.Mask" "F.Paste")
			(net "GND")
		)
		(pad "231" smd rect
			(at 2.050034 14.875002 270)
			(size 0.519938 1.4986)
			(layers "F.Cu" "F.Mask" "F.Paste")
			(net "TP_CHD_CPU1_DIMM2_FRU_5")
		)
		(pad "232" smd rect
			(at 2.050034 15.724886 270)
			(size 0.519938 1.4986)
			(layers "F.Cu" "F.Mask" "F.Paste")
			(net "TP_CHD_CPU1_DIMM2_FRU_6")
		)
		(pad "233" smd rect
			(at 2.050034 16.575024 270)
			(size 0.519938 1.4986)
			(layers "F.Cu" "F.Mask" "F.Paste")
			(net "GND")
		)
		(pad "234" smd rect
			(at 2.050034 17.424908 270)
			(size 0.519938 1.4986)
			(layers "F.Cu" "F.Mask" "F.Paste")
			(net "M_D_CPU1_SB_CB<6>")
		)
		(pad "235" smd rect
			(at 2.050034 18.275046 270)
			(size 0.519938 1.4986)
			(layers "F.Cu" "F.Mask" "F.Paste")
			(net "GND")
		)
		(pad "236" smd rect
			(at 2.050034 19.12493 270)
			(size 0.519938 1.4986)
			(layers "F.Cu" "F.Mask" "F.Paste")
			(net "M_D_CPU1_SB_CB<7>")
		)
		(pad "237" smd rect
			(at 2.050034 19.975068 270)
			(size 0.519938 1.4986)
			(layers "F.Cu" "F.Mask" "F.Paste")
			(net "GND")
		)
		(pad "238" smd rect
			(at 2.050034 20.824952 270)
			(size 0.519938 1.4986)
			(layers "F.Cu" "F.Mask" "F.Paste")
			(net "M_D_CPU1_SB_DQS_DN<4>")
		)
		(pad "239" smd rect
			(at 2.050034 21.67509 270)
			(size 0.519938 1.4986)
			(layers "F.Cu" "F.Mask" "F.Paste")
			(net "M_D_CPU1_SB_DQS_DP<4>")
		)
		(pad "240" smd rect
			(at 2.050034 22.524974 270)
			(size 0.519938 1.4986)
			(layers "F.Cu" "F.Mask" "F.Paste")
			(net "GND")
		)
		(pad "241" smd rect
			(at 2.050034 23.375112 270)
			(size 0.519938 1.4986)
			(layers "F.Cu" "F.Mask" "F.Paste")
			(net "M_D_CPU1_SB_CB<2>")
		)
		(pad "242" smd rect
			(at 2.050034 24.224996 270)
			(size 0.519938 1.4986)
			(layers "F.Cu" "F.Mask" "F.Paste")
			(net "GND")
		)
		(pad "243" smd rect
			(at 2.050034 25.07488 270)
			(size 0.519938 1.4986)
			(layers "F.Cu" "F.Mask" "F.Paste")
			(net "M_D_CPU1_SB_CB<3>")
		)
		(pad "244" smd rect
			(at 2.050034 25.925018 270)
			(size 0.519938 1.4986)
			(layers "F.Cu" "F.Mask" "F.Paste")
			(net "GND")
		)
		(pad "245" smd rect
			(at 2.050034 26.774902 270)
			(size 0.519938 1.4986)
			(layers "F.Cu" "F.Mask" "F.Paste")
			(net "M_D_CPU1_SB_DQ<2>")
		)
		(pad "246" smd rect
			(at 2.050034 27.62504 270)
			(size 0.519938 1.4986)
			(layers "F.Cu" "F.Mask" "F.Paste")
			(net "GND")
		)
		(pad "247" smd rect
			(at 2.050034 28.474924 270)
			(size 0.519938 1.4986)
			(layers "F.Cu" "F.Mask" "F.Paste")
			(net "M_D_CPU1_SB_DQ<3>")
		)
		(pad "248" smd rect
			(at 2.050034 29.325062 270)
			(size 0.519938 1.4986)
			(layers "F.Cu" "F.Mask" "F.Paste")
			(net "GND")
		)
		(pad "249" smd rect
			(at 2.050034 30.174946 270)
			(size 0.519938 1.4986)
			(layers "F.Cu" "F.Mask" "F.Paste")
			(net "M_D_CPU1_SB_DQS_DN<5>")
		)
		(pad "250" smd rect
			(at 2.050034 31.025084 270)
			(size 0.519938 1.4986)
			(layers "F.Cu" "F.Mask" "F.Paste")
			(net "M_D_CPU1_SB_DQS_DP<5>")
		)
		(pad "251" smd rect
			(at 2.050034 31.874968 270)
			(size 0.519938 1.4986)
			(layers "F.Cu" "F.Mask" "F.Paste")
			(net "GND")
		)
		(pad "252" smd rect
			(at 2.050034 32.725106 270)
			(size 0.519938 1.4986)
			(layers "F.Cu" "F.Mask" "F.Paste")
			(net "M_D_CPU1_SB_DQ<6>")
		)
		(pad "253" smd rect
			(at 2.050034 33.57499 270)
			(size 0.519938 1.4986)
			(layers "F.Cu" "F.Mask" "F.Paste")
			(net "GND")
		)
		(pad "254" smd rect
			(at 2.050034 34.425128 270)
			(size 0.519938 1.4986)
			(layers "F.Cu" "F.Mask" "F.Paste")
			(net "M_D_CPU1_SB_DQ<7>")
		)
		(pad "255" smd rect
			(at 2.050034 35.275012 270)
			(size 0.519938 1.4986)
			(layers "F.Cu" "F.Mask" "F.Paste")
			(net "GND")
		)
		(pad "256" smd rect
			(at 2.050034 36.124896 270)
			(size 0.519938 1.4986)
			(layers "F.Cu" "F.Mask" "F.Paste")
			(net "M_D_CPU1_SB_DQ<10>")
		)
		(pad "257" smd rect
			(at 2.050034 36.975034 270)
			(size 0.519938 1.4986)
			(layers "F.Cu" "F.Mask" "F.Paste")
			(net "GND")
		)
		(pad "258" smd rect
			(at 2.050034 37.824918 270)
			(size 0.519938 1.4986)
			(layers "F.Cu" "F.Mask" "F.Paste")
			(net "M_D_CPU1_SB_DQ<11>")
		)
		(pad "259" smd rect
			(at 2.050034 38.675056 270)
			(size 0.519938 1.4986)
			(layers "F.Cu" "F.Mask" "F.Paste")
			(net "GND")
		)
		(pad "260" smd rect
			(at 2.050034 39.52494 270)
			(size 0.519938 1.4986)
			(layers "F.Cu" "F.Mask" "F.Paste")
			(net "M_D_CPU1_SB_DQS_DN<6>")
		)
		(pad "261" smd rect
			(at 2.050034 40.375078 270)
			(size 0.519938 1.4986)
			(layers "F.Cu" "F.Mask" "F.Paste")
			(net "M_D_CPU1_SB_DQS_DP<6>")
		)
		(pad "262" smd rect
			(at 2.050034 41.224962 270)
			(size 0.519938 1.4986)
			(layers "F.Cu" "F.Mask" "F.Paste")
			(net "GND")
		)
		(pad "263" smd rect
			(at 2.050034 42.0751 270)
			(size 0.519938 1.4986)
			(layers "F.Cu" "F.Mask" "F.Paste")
			(net "M_D_CPU1_SB_DQ<14>")
		)
		(pad "264" smd rect
			(at 2.050034 42.924984 270)
			(size 0.519938 1.4986)
			(layers "F.Cu" "F.Mask" "F.Paste")
			(net "GND")
		)
		(pad "265" smd rect
			(at 2.050034 43.775122 270)
			(size 0.519938 1.4986)
			(layers "F.Cu" "F.Mask" "F.Paste")
			(net "M_D_CPU1_SB_DQ<15>")
		)
		(pad "266" smd rect
			(at 2.050034 44.625006 270)
			(size 0.519938 1.4986)
			(layers "F.Cu" "F.Mask" "F.Paste")
			(net "GND")
		)
		(pad "267" smd rect
			(at 2.050034 45.47489 270)
			(size 0.519938 1.4986)
			(layers "F.Cu" "F.Mask" "F.Paste")
			(net "M_D_CPU1_SB_DQ<18>")
		)
		(pad "268" smd rect
			(at 2.050034 46.325028 270)
			(size 0.519938 1.4986)
			(layers "F.Cu" "F.Mask" "F.Paste")
			(net "GND")
		)
		(pad "269" smd rect
			(at 2.050034 47.174912 270)
			(size 0.519938 1.4986)
			(layers "F.Cu" "F.Mask" "F.Paste")
			(net "M_D_CPU1_SB_DQ<19>")
		)
		(pad "270" smd rect
			(at 2.050034 48.02505 270)
			(size 0.519938 1.4986)
			(layers "F.Cu" "F.Mask" "F.Paste")
			(net "GND")
		)
		(pad "271" smd rect
			(at 2.050034 48.874934 270)
			(size 0.519938 1.4986)
			(layers "F.Cu" "F.Mask" "F.Paste")
			(net "M_D_CPU1_SB_DQS_DN<7>")
		)
		(pad "272" smd rect
			(at 2.050034 49.725072 270)
			(size 0.519938 1.4986)
			(layers "F.Cu" "F.Mask" "F.Paste")
			(net "M_D_CPU1_SB_DQS_DP<7>")
		)
		(pad "273" smd rect
			(at 2.050034 50.574956 270)
			(size 0.519938 1.4986)
			(layers "F.Cu" "F.Mask" "F.Paste")
			(net "GND")
		)
		(pad "274" smd rect
			(at 2.050034 51.425094 270)
			(size 0.519938 1.4986)
			(layers "F.Cu" "F.Mask" "F.Paste")
			(net "M_D_CPU1_SB_DQ<22>")
		)
		(pad "275" smd rect
			(at 2.050034 52.274978 270)
			(size 0.519938 1.4986)
			(layers "F.Cu" "F.Mask" "F.Paste")
			(net "GND")
		)
		(pad "276" smd rect
			(at 2.050034 53.125116 270)
			(size 0.519938 1.4986)
			(layers "F.Cu" "F.Mask" "F.Paste")
			(net "M_D_CPU1_SB_DQ<23>")
		)
		(pad "277" smd rect
			(at 2.050034 53.975 270)
			(size 0.519938 1.4986)
			(layers "F.Cu" "F.Mask" "F.Paste")
			(net "GND")
		)
		(pad "278" smd rect
			(at 2.050034 54.824884 270)
			(size 0.519938 1.4986)
			(layers "F.Cu" "F.Mask" "F.Paste")
			(net "M_D_CPU1_SB_DQ<26>")
		)
		(pad "279" smd rect
			(at 2.050034 55.675022 270)
			(size 0.519938 1.4986)
			(layers "F.Cu" "F.Mask" "F.Paste")
			(net "GND")
		)
		(pad "280" smd rect
			(at 2.050034 56.524906 270)
			(size 0.519938 1.4986)
			(layers "F.Cu" "F.Mask" "F.Paste")
			(net "M_D_CPU1_SB_DQ<27>")
		)
		(pad "281" smd rect
			(at 2.050034 57.375044 270)
			(size 0.519938 1.4986)
			(layers "F.Cu" "F.Mask" "F.Paste")
			(net "GND")
		)
		(pad "282" smd rect
			(at 2.050034 58.224928 270)
			(size 0.519938 1.4986)
			(layers "F.Cu" "F.Mask" "F.Paste")
			(net "M_D_CPU1_SB_DQS_DN<8>")
		)
		(pad "283" smd rect
			(at 2.050034 59.075066 270)
			(size 0.519938 1.4986)
			(layers "F.Cu" "F.Mask" "F.Paste")
			(net "M_D_CPU1_SB_DQS_DP<8>")
		)
		(pad "284" smd rect
			(at 2.050034 59.92495 270)
			(size 0.519938 1.4986)
			(layers "F.Cu" "F.Mask" "F.Paste")
			(net "GND")
		)
		(pad "285" smd rect
			(at 2.050034 60.775088 270)
			(size 0.519938 1.4986)
			(layers "F.Cu" "F.Mask" "F.Paste")
			(net "M_D_CPU1_SB_DQ<30>")
		)
		(pad "286" smd rect
			(at 2.050034 61.624972 270)
			(size 0.519938 1.4986)
			(layers "F.Cu" "F.Mask" "F.Paste")
			(net "GND")
		)
		(pad "287" smd rect
			(at 2.050034 62.47511 270)
			(size 0.519938 1.4986)
			(layers "F.Cu" "F.Mask" "F.Paste")
			(net "M_D_CPU1_SB_DQ<31>")
		)
		(pad "288" smd rect
			(at 2.050034 63.324994 270)
			(size 0.519938 1.4986)
			(layers "F.Cu" "F.Mask" "F.Paste")
			(net "GND")
		)
		(pad "G1" thru_hole oval
			(at 0 -68.97497)
			(size 2.8194 1.5748)
			(drill oval 2.4384 1.1938)
			(layers "*.Cu" "*.Mask")
			(remove_unused_layers no)
			(net "GND")
			(clearance 0.127)
			(thermal_gap 0.127)
		)
		(pad "G2" thru_hole oval
			(at 0 3.875024)
			(size 2.8194 1.5748)
			(drill oval 2.4384 1.1938)
			(layers "*.Cu" "*.Mask")
			(remove_unused_layers no)
			(net "GND")
			(clearance 0.127)
			(thermal_gap 0.127)
		)
		(pad "G3" thru_hole oval
			(at 0 68.97497)
			(size 2.8194 1.5748)
			(drill oval 2.4384 1.1938)
			(layers "*.Cu" "*.Mask")
			(remove_unused_layers no)
			(net "GND")
			(clearance 0.127)
			(thermal_gap 0.127)
		)
	)
	(footprint ""
		(layer "F.Cu")
		(at 160.760918 -23.398226 180)
		(property "Reference" "R4150"
			(at 0 0 180)
			(layer "F.SilkS")
			(hide yes)
			(effects
				(font
					(size 1.27 1.27)
				)
			)
		)
		(property "Value" ""
			(at 0 0 180)
			(layer "F.Fab")
			(effects
				(font
					(size 1.27 1.27)
				)
			)
		)
		(duplicate_pad_numbers_are_jumpers no)
		(fp_line
			(start 0.7874 0.4064)
			(end -0.7874 0.4064)
			(stroke
				(width 0.1524)
				(type default)
			)
			(layer "F.SilkS")
		)
		(fp_line
			(start 0.7874 -0.4064)
			(end 0.7874 0.4064)
			(stroke
				(width 0.1524)
				(type default)
			)
			(layer "F.SilkS")
		)
		(fp_line
			(start -0.7874 0.4064)
			(end -0.7874 -0.4064)
			(stroke
				(width 0.1524)
				(type default)
			)
			(layer "F.SilkS")
		)
		(fp_line
			(start -0.7874 -0.4064)
			(end 0.7874 -0.4064)
			(stroke
				(width 0.1524)
				(type default)
			)
			(layer "F.SilkS")
		)
		(fp_line
			(start 0.67945 0.3048)
			(end 0.120396 0.3048)
			(stroke
				(width 0.1)
				(type default)
			)
			(layer "F.Fab")
		)
		(fp_line
			(start 0.67945 -0.3048)
			(end 0.67945 0.3048)
			(stroke
				(width 0.1)
				(type default)
			)
			(layer "F.Fab")
		)
		(fp_line
			(start 0.12065 -0.2794)
			(end 0.12065 -0.3048)
			(stroke
				(width 0.1)
				(type default)
			)
			(layer "F.Fab")
		)
		(fp_line
			(start 0.12065 -0.3048)
			(end 0.67945 -0.3048)
			(stroke
				(width 0.1)
				(type default)
			)
			(layer "F.Fab")
		)
		(fp_line
			(start 0.120396 0.3048)
			(end 0.120396 0.2794)
			(stroke
				(width 0.1)
				(type default)
			)
			(layer "F.Fab")
		)
		(fp_line
			(start 0.120396 0.2794)
			(end -0.12065 0.2794)
			(stroke
				(width 0.1)
				(type default)
			)
			(layer "F.Fab")
		)
		(fp_line
			(start -0.12065 0.3048)
			(end -0.67945 0.3048)
			(stroke
				(width 0.1)
				(type default)
			)
			(layer "F.Fab")
		)
		(fp_line
			(start -0.12065 0.2794)
			(end -0.12065 0.3048)
			(stroke
				(width 0.1)
				(type default)
			)
			(layer "F.Fab")
		)
		(fp_line
			(start -0.12065 -0.2794)
			(end 0.12065 -0.2794)
			(stroke
				(width 0.1)
				(type default)
			)
			(layer "F.Fab")
		)
		(fp_line
			(start -0.12065 -0.305054)
			(end -0.12065 -0.2794)
			(stroke
				(width 0.1)
				(type default)
			)
			(layer "F.Fab")
		)
		(fp_line
			(start -0.67945 0.3048)
			(end -0.67945 -0.305054)
			(stroke
				(width 0.1)
				(type default)
			)
			(layer "F.Fab")
		)
		(fp_line
			(start -0.67945 -0.305054)
			(end -0.12065 -0.305054)
			(stroke
				(width 0.1)
				(type default)
			)
			(layer "F.Fab")
		)
		(pad "1" smd circle
			(at -0.40005 0 180)
			(size 0 0)
			(layers "F.Cu" "F.Mask" "F.Paste")
			(net "SMB_1_PLD_3V3AUX_SDA")
		)
		(pad "2" smd circle
			(at 0.40005 0 180)
			(size 0 0)
			(layers "F.Cu" "F.Mask" "F.Paste")
			(net "SMB_1_PLD_3V3AUX_SDA_R1")
		)
	)
	(footprint ""
		(layer "F.Cu")
		(at 15.067788 -92.687648 90)
		(property "Reference" "R3659"
			(at 0 0 90)
			(layer "F.SilkS")
			(hide yes)
			(effects
				(font
					(size 1.27 1.27)
				)
			)
		)
		(property "Value" ""
			(at 0 0 90)
			(layer "F.Fab")
			(effects
				(font
					(size 1.27 1.27)
				)
			)
		)
		(duplicate_pad_numbers_are_jumpers no)
		(fp_line
			(start 0.7874 -0.4064)
			(end 0.7874 0.4064)
			(stroke
				(width 0.1524)
				(type default)
			)
			(layer "F.SilkS")
		)
		(fp_line
			(start -0.7874 -0.4064)
			(end 0.7874 -0.4064)
			(stroke
				(width 0.1524)
				(type default)
			)
			(layer "F.SilkS")
		)
		(fp_line
			(start 0.7874 0.4064)
			(end -0.7874 0.4064)
			(stroke
				(width 0.1524)
				(type default)
			)
			(layer "F.SilkS")
		)
		(fp_line
			(start -0.7874 0.4064)
			(end -0.7874 -0.4064)
			(stroke
				(width 0.1524)
				(type default)
			)
			(layer "F.SilkS")
		)
		(fp_line
			(start -0.12065 -0.305054)
			(end -0.12065 -0.2794)
			(stroke
				(width 0.1)
				(type default)
			)
			(layer "F.Fab")
		)
		(fp_line
			(start -0.67945 -0.305054)
			(end -0.12065 -0.305054)
			(stroke
				(width 0.1)
				(type default)
			)
			(layer "F.Fab")
		)
		(fp_line
			(start 0.67945 -0.3048)
			(end 0.67945 0.3048)
			(stroke
				(width 0.1)
				(type default)
			)
			(layer "F.Fab")
		)
		(fp_line
			(start 0.12065 -0.3048)
			(end 0.67945 -0.3048)
			(stroke
				(width 0.1)
				(type default)
			)
			(layer "F.Fab")
		)
		(fp_line
			(start 0.12065 -0.2794)
			(end 0.12065 -0.3048)
			(stroke
				(width 0.1)
				(type default)
			)
			(layer "F.Fab")
		)
		(fp_line
			(start -0.12065 -0.2794)
			(end 0.12065 -0.2794)
			(stroke
				(width 0.1)
				(type default)
			)
			(layer "F.Fab")
		)
		(fp_line
			(start 0.120396 0.2794)
			(end -0.12065 0.2794)
			(stroke
				(width 0.1)
				(type default)
			)
			(layer "F.Fab")
		)
		(fp_line
			(start -0.12065 0.2794)
			(end -0.12065 0.3048)
			(stroke
				(width 0.1)
				(type default)
			)
			(layer "F.Fab")
		)
		(fp_line
			(start 0.67945 0.3048)
			(end 0.120396 0.3048)
			(stroke
				(width 0.1)
				(type default)
			)
			(layer "F.Fab")
		)
		(fp_line
			(start 0.120396 0.3048)
			(end 0.120396 0.2794)
			(stroke
				(width 0.1)
				(type default)
			)
			(layer "F.Fab")
		)
		(fp_line
			(start -0.12065 0.3048)
			(end -0.67945 0.3048)
			(stroke
				(width 0.1)
				(type default)
			)
			(layer "F.Fab")
		)
		(fp_line
			(start -0.67945 0.3048)
			(end -0.67945 -0.305054)
			(stroke
				(width 0.1)
				(type default)
			)
			(layer "F.Fab")
		)
		(pad "1" smd circle
			(at -0.40005 0 90)
			(size 0 0)
			(layers "F.Cu" "F.Mask" "F.Paste")
			(net "P3V3_AUX")
		)
		(pad "2" smd circle
			(at 0.40005 0 90)
			(size 0 0)
			(layers "F.Cu" "F.Mask" "F.Paste")
			(net "USB_HUB_OVCUR4")
		)
	)
	(footprint ""
		(layer "F.Cu")
		(at 424.223942 -401.655534)
		(property "Reference" "R3470"
			(at 0 0 0)
			(layer "F.SilkS")
			(hide yes)
			(effects
				(font
					(size 1.27 1.27)
				)
			)
		)
		(property "Value" ""
			(at 0 0 0)
			(layer "F.Fab")
			(effects
				(font
					(size 1.27 1.27)
				)
			)
		)
		(duplicate_pad_numbers_are_jumpers no)
		(fp_line
			(start -0.7874 -0.4064)
			(end 0.7874 -0.4064)
			(stroke
				(width 0.1524)
				(type default)
			)
			(layer "F.SilkS")
		)
		(fp_line
			(start -0.7874 0.4064)
			(end -0.7874 -0.4064)
			(stroke
				(width 0.1524)
				(type default)
			)
			(layer "F.SilkS")
		)
		(fp_line
			(start 0.7874 -0.4064)
			(end 0.7874 0.4064)
			(stroke
				(width 0.1524)
				(type default)
			)
			(layer "F.SilkS")
		)
		(fp_line
			(start 0.7874 0.4064)
			(end -0.7874 0.4064)
			(stroke
				(width 0.1524)
				(type default)
			)
			(layer "F.SilkS")
		)
		(fp_line
			(start -0.67945 -0.305054)
			(end -0.12065 -0.305054)
			(stroke
				(width 0.1)
				(type default)
			)
			(layer "F.Fab")
		)
		(fp_line
			(start -0.67945 0.3048)
			(end -0.67945 -0.305054)
			(stroke
				(width 0.1)
				(type default)
			)
			(layer "F.Fab")
		)
		(fp_line
			(start -0.12065 -0.305054)
			(end -0.12065 -0.2794)
			(stroke
				(width 0.1)
				(type default)
			)
			(layer "F.Fab")
		)
		(fp_line
			(start -0.12065 -0.2794)
			(end 0.12065 -0.2794)
			(stroke
				(width 0.1)
				(type default)
			)
			(layer "F.Fab")
		)
		(fp_line
			(start -0.12065 0.2794)
			(end -0.12065 0.3048)
			(stroke
				(width 0.1)
				(type default)
			)
			(layer "F.Fab")
		)
		(fp_line
			(start -0.12065 0.3048)
			(end -0.67945 0.3048)
			(stroke
				(width 0.1)
				(type default)
			)
			(layer "F.Fab")
		)
		(fp_line
			(start 0.120396 0.2794)
			(end -0.12065 0.2794)
			(stroke
				(width 0.1)
				(type default)
			)
			(layer "F.Fab")
		)
		(fp_line
			(start 0.120396 0.3048)
			(end 0.120396 0.2794)
			(stroke
				(width 0.1)
				(type default)
			)
			(layer "F.Fab")
		)
		(fp_line
			(start 0.12065 -0.3048)
			(end 0.67945 -0.3048)
			(stroke
				(width 0.1)
				(type default)
			)
			(layer "F.Fab")
		)
		(fp_line
			(start 0.12065 -0.2794)
			(end 0.12065 -0.3048)
			(stroke
				(width 0.1)
				(type default)
			)
			(layer "F.Fab")
		)
		(fp_line
			(start 0.67945 -0.3048)
			(end 0.67945 0.3048)
			(stroke
				(width 0.1)
				(type default)
			)
			(layer "F.Fab")
		)
		(fp_line
			(start 0.67945 0.3048)
			(end 0.120396 0.3048)
			(stroke
				(width 0.1)
				(type default)
			)
			(layer "F.Fab")
		)
		(pad "1" smd circle
			(at -0.40005 0)
			(size 0 0)
			(layers "F.Cu" "F.Mask" "F.Paste")
			(net "P3V3_AUX")
		)
		(pad "2" smd circle
			(at 0.40005 0)
			(size 0 0)
			(layers "F.Cu" "F.Mask" "F.Paste")
			(net "GPU_WP_HW_CTRL_N")
		)
	)
	(footprint ""
		(layer "F.Cu")
		(at 69.397118 -402.371052 -90)
		(property "Reference" "C724"
			(at 0 0 270)
			(layer "F.SilkS")
			(hide yes)
			(effects
				(font
					(size 1.27 1.27)
				)
			)
		)
		(property "Value" ""
			(at 0 0 270)
			(layer "F.Fab")
			(effects
				(font
					(size 1.27 1.27)
				)
			)
		)
		(duplicate_pad_numbers_are_jumpers no)
		(fp_line
			(start -0.299974 0.150114)
			(end -0.299974 -0.150114)
			(stroke
				(width 0.1)
				(type default)
			)
			(layer "F.Fab")
		)
		(fp_line
			(start 0.299974 0.150114)
			(end -0.299974 0.150114)
			(stroke
				(width 0.1)
				(type default)
			)
			(layer "F.Fab")
		)
		(fp_line
			(start -0.299974 -0.150114)
			(end 0.299974 -0.150114)
			(stroke
				(width 0.1)
				(type default)
			)
			(layer "F.Fab")
		)
		(fp_line
			(start 0.299974 -0.150114)
			(end 0.299974 0.150114)
			(stroke
				(width 0.1)
				(type default)
			)
			(layer "F.Fab")
		)
		(pad "1" smd rect
			(at -0.2667 0 270)
			(size 0.3048 0.381)
			(layers "F.Cu" "F.Mask" "F.Paste")
			(net "P5E_CPU1_PE0_TX_C_DN<8>")
		)
		(pad "2" smd rect
			(at 0.2667 0 270)
			(size 0.3048 0.381)
			(layers "F.Cu" "F.Mask" "F.Paste")
			(net "P5E_CPU1_PE0_TX_DN<8>")
		)
	)
	(footprint ""
		(layer "F.Cu")
		(at 217.889582 -69.397118)
		(property "Reference" "PC2212"
			(at 0 0 0)
			(layer "F.SilkS")
			(hide yes)
			(effects
				(font
					(size 1.27 1.27)
				)
			)
		)
		(property "Value" ""
			(at 0 0 0)
			(layer "F.Fab")
			(effects
				(font
					(size 1.27 1.27)
				)
			)
		)
		(duplicate_pad_numbers_are_jumpers no)
		(fp_line
			(start -0.7874 -0.4064)
			(end 0.7874 -0.4064)
			(stroke
				(width 0.1524)
				(type default)
			)
			(layer "F.SilkS")
		)
		(fp_line
			(start -0.7874 0.4064)
			(end -0.7874 -0.4064)
			(stroke
				(width 0.1524)
				(type default)
			)
			(layer "F.SilkS")
		)
		(fp_line
			(start 0.7874 -0.4064)
			(end 0.7874 0.4064)
			(stroke
				(width 0.1524)
				(type default)
			)
			(layer "F.SilkS")
		)
		(fp_line
			(start 0.7874 0.4064)
			(end -0.7874 0.4064)
			(stroke
				(width 0.1524)
				(type default)
			)
			(layer "F.SilkS")
		)
		(fp_line
			(start -0.67945 -0.305054)
			(end -0.12065 -0.305054)
			(stroke
				(width 0.1)
				(type default)
			)
			(layer "F.Fab")
		)
		(fp_line
			(start -0.67945 0.3048)
			(end -0.67945 -0.305054)
			(stroke
				(width 0.1)
				(type default)
			)
			(layer "F.Fab")
		)
		(fp_line
			(start -0.12065 -0.305054)
			(end -0.12065 -0.2794)
			(stroke
				(width 0.1)
				(type default)
			)
			(layer "F.Fab")
		)
		(fp_line
			(start -0.12065 -0.2794)
			(end 0.12065 -0.2794)
			(stroke
				(width 0.1)
				(type default)
			)
			(layer "F.Fab")
		)
		(fp_line
			(start -0.12065 0.2794)
			(end -0.12065 0.3048)
			(stroke
				(width 0.1)
				(type default)
			)
			(layer "F.Fab")
		)
		(fp_line
			(start -0.12065 0.3048)
			(end -0.67945 0.3048)
			(stroke
				(width 0.1)
				(type default)
			)
			(layer "F.Fab")
		)
		(fp_line
			(start 0.120396 0.2794)
			(end -0.12065 0.2794)
			(stroke
				(width 0.1)
				(type default)
			)
			(layer "F.Fab")
		)
		(fp_line
			(start 0.120396 0.3048)
			(end 0.120396 0.2794)
			(stroke
				(width 0.1)
				(type default)
			)
			(layer "F.Fab")
		)
		(fp_line
			(start 0.12065 -0.3048)
			(end 0.67945 -0.3048)
			(stroke
				(width 0.1)
				(type default)
			)
			(layer "F.Fab")
		)
		(fp_line
			(start 0.12065 -0.2794)
			(end 0.12065 -0.3048)
			(stroke
				(width 0.1)
				(type default)
			)
			(layer "F.Fab")
		)
		(fp_line
			(start 0.67945 -0.3048)
			(end 0.67945 0.3048)
			(stroke
				(width 0.1)
				(type default)
			)
			(layer "F.Fab")
		)
		(fp_line
			(start 0.67945 0.3048)
			(end 0.120396 0.3048)
			(stroke
				(width 0.1)
				(type default)
			)
			(layer "F.Fab")
		)
		(pad "1" smd circle
			(at -0.40005 0)
			(size 0 0)
			(layers "F.Cu" "F.Mask" "F.Paste")
			(net "GND")
		)
		(pad "2" smd circle
			(at 0.40005 0)
			(size 0 0)
			(layers "F.Cu" "F.Mask" "F.Paste")
			(net "P3V3_E1S_REG_0")
		)
	)
	(footprint ""
		(layer "F.Cu")
		(at 92.7608 -33.061148)
		(property "Reference" "C2344"
			(at 0 0 0)
			(layer "F.SilkS")
			(hide yes)
			(effects
				(font
					(size 1.27 1.27)
				)
			)
		)
		(property "Value" ""
			(at 0 0 0)
			(layer "F.Fab")
			(effects
				(font
					(size 1.27 1.27)
				)
			)
		)
		(duplicate_pad_numbers_are_jumpers no)
		(fp_line
			(start -0.7874 -0.4064)
			(end 0.7874 -0.4064)
			(stroke
				(width 0.1524)
				(type default)
			)
			(layer "F.SilkS")
		)
		(fp_line
			(start -0.7874 0.4064)
			(end -0.7874 -0.4064)
			(stroke
				(width 0.1524)
				(type default)
			)
			(layer "F.SilkS")
		)
		(fp_line
			(start 0.7874 -0.4064)
			(end 0.7874 0.4064)
			(stroke
				(width 0.1524)
				(type default)
			)
			(layer "F.SilkS")
		)
		(fp_line
			(start 0.7874 0.4064)
			(end -0.7874 0.4064)
			(stroke
				(width 0.1524)
				(type default)
			)
			(layer "F.SilkS")
		)
		(fp_line
			(start -0.67945 -0.305054)
			(end -0.12065 -0.305054)
			(stroke
				(width 0.1)
				(type default)
			)
			(layer "F.Fab")
		)
		(fp_line
			(start -0.67945 0.3048)
			(end -0.67945 -0.305054)
			(stroke
				(width 0.1)
				(type default)
			)
			(layer "F.Fab")
		)
		(fp_line
			(start -0.12065 -0.305054)
			(end -0.12065 -0.2794)
			(stroke
				(width 0.1)
				(type default)
			)
			(layer "F.Fab")
		)
		(fp_line
			(start -0.12065 -0.2794)
			(end 0.12065 -0.2794)
			(stroke
				(width 0.1)
				(type default)
			)
			(layer "F.Fab")
		)
		(fp_line
			(start -0.12065 0.2794)
			(end -0.12065 0.3048)
			(stroke
				(width 0.1)
				(type default)
			)
			(layer "F.Fab")
		)
		(fp_line
			(start -0.12065 0.3048)
			(end -0.67945 0.3048)
			(stroke
				(width 0.1)
				(type default)
			)
			(layer "F.Fab")
		)
		(fp_line
			(start 0.120396 0.2794)
			(end -0.12065 0.2794)
			(stroke
				(width 0.1)
				(type default)
			)
			(layer "F.Fab")
		)
		(fp_line
			(start 0.120396 0.3048)
			(end 0.120396 0.2794)
			(stroke
				(width 0.1)
				(type default)
			)
			(layer "F.Fab")
		)
		(fp_line
			(start 0.12065 -0.3048)
			(end 0.67945 -0.3048)
			(stroke
				(width 0.1)
				(type default)
			)
			(layer "F.Fab")
		)
		(fp_line
			(start 0.12065 -0.2794)
			(end 0.12065 -0.3048)
			(stroke
				(width 0.1)
				(type default)
			)
			(layer "F.Fab")
		)
		(fp_line
			(start 0.67945 -0.3048)
			(end 0.67945 0.3048)
			(stroke
				(width 0.1)
				(type default)
			)
			(layer "F.Fab")
		)
		(fp_line
			(start 0.67945 0.3048)
			(end 0.120396 0.3048)
			(stroke
				(width 0.1)
				(type default)
			)
			(layer "F.Fab")
		)
		(pad "1" smd circle
			(at -0.40005 0)
			(size 0 0)
			(layers "F.Cu" "F.Mask" "F.Paste")
			(net "P3V3_AUX")
		)
		(pad "2" smd circle
			(at 0.40005 0)
			(size 0 0)
			(layers "F.Cu" "F.Mask" "F.Paste")
			(net "GND")
		)
	)
	(footprint ""
		(layer "F.Cu")
		(at 444.039498 -335.221072)
		(property "Reference" "U102"
			(at -0.5207 -2.466848 0)
			(unlocked yes)
			(layer "F.SilkS")
			(effects
				(font
					(size 0.7874 0.5842)
					(thickness 0.1524)
				)
				(justify left)
			)
		)
		(property "Value" ""
			(at 0 0 0)
			(layer "F.Fab")
			(effects
				(font
					(size 1.27 1.27)
				)
			)
		)
		(duplicate_pad_numbers_are_jumpers no)
		(fp_line
			(start -1.99263 -1.525016)
			(end -1.99263 1.525016)
			(stroke
				(width 0.1524)
				(type default)
			)
			(layer "F.SilkS")
		)
		(fp_line
			(start -1.99263 1.525016)
			(end 1.99263 1.525016)
			(stroke
				(width 0.1524)
				(type default)
			)
			(layer "F.SilkS")
		)
		(fp_line
			(start 1.99263 -1.525016)
			(end -1.99263 -1.525016)
			(stroke
				(width 0.1524)
				(type default)
			)
			(layer "F.SilkS")
		)
		(fp_line
			(start 1.99263 1.525016)
			(end 1.99263 -1.525016)
			(stroke
				(width 0.1524)
				(type default)
			)
			(layer "F.SilkS")
		)
		(fp_poly
			(pts
				(xy -0.843534 -2.815082) (xy -1.351534 -1.799082) (xy -1.859534 -2.815082)
			)
			(stroke
				(width 0)
				(type default)
			)
			(fill yes)
			(layer "F.SilkS")
		)
		(fp_line
			(start -0.87503 -1.525016)
			(end -0.87503 1.525016)
			(stroke
				(width 0.1)
				(type default)
			)
			(layer "F.Fab")
		)
		(fp_line
			(start -0.87503 1.525016)
			(end 0.87503 1.525016)
			(stroke
				(width 0.1)
				(type default)
			)
			(layer "F.Fab")
		)
		(fp_line
			(start 0.87503 -1.525016)
			(end -0.87503 -1.525016)
			(stroke
				(width 0.1)
				(type default)
			)
			(layer "F.Fab")
		)
		(fp_line
			(start 0.87503 1.525016)
			(end 0.87503 -1.525016)
			(stroke
				(width 0.1)
				(type default)
			)
			(layer "F.Fab")
		)
		(fp_poly
			(pts
				(xy -3.2004 -1.45796) (xy -3.2004 -0.44196) (xy -2.1844 -0.94996)
			)
			(stroke
				(width 0)
				(type default)
			)
			(fill yes)
			(layer "F.Fab")
		)
		(pad "1" smd circle
			(at -1.299972 -0.94996 270)
			(size 0 0)
			(layers "F.Cu" "F.Mask" "F.Paste")
			(net "GND")
		)
		(pad "2" smd circle
			(at -1.299972 0 270)
			(size 0 0)
			(layers "F.Cu" "F.Mask" "F.Paste")
			(net "GND")
		)
		(pad "3" smd circle
			(at -1.299972 0.94996 270)
			(size 0 0)
			(layers "F.Cu" "F.Mask" "F.Paste")
			(net "PVCCD_HV_CPU0_NVDIMM_ISENSE")
		)
		(pad "4" smd circle
			(at 1.299972 0.94996 270)
			(size 0 0)
			(layers "F.Cu" "F.Mask" "F.Paste")
			(net "P12V_AUX_CPU0_DIMM_ISEN_N")
		)
		(pad "5" smd circle
			(at 1.299972 -0.94996 270)
			(size 0 0)
			(layers "F.Cu" "F.Mask" "F.Paste")
			(net "P12V_AUX_CPU0_DIMM_ISEN_P")
		)
	)
	(footprint ""
		(layer "F.Cu")
		(at 52.423314 -161.539174 180)
		(property "Reference" "PC373"
			(at 0 0 180)
			(layer "F.SilkS")
			(hide yes)
			(effects
				(font
					(size 1.27 1.27)
				)
			)
		)
		(property "Value" ""
			(at 0 0 180)
			(layer "F.Fab")
			(effects
				(font
					(size 1.27 1.27)
				)
			)
		)
		(duplicate_pad_numbers_are_jumpers no)
		(fp_line
			(start 0.7874 0.4064)
			(end -0.7874 0.4064)
			(stroke
				(width 0.1524)
				(type default)
			)
			(layer "F.SilkS")
		)
		(fp_line
			(start 0.7874 -0.4064)
			(end 0.7874 0.4064)
			(stroke
				(width 0.1524)
				(type default)
			)
			(layer "F.SilkS")
		)
		(fp_line
			(start -0.7874 0.4064)
			(end -0.7874 -0.4064)
			(stroke
				(width 0.1524)
				(type default)
			)
			(layer "F.SilkS")
		)
		(fp_line
			(start -0.7874 -0.4064)
			(end 0.7874 -0.4064)
			(stroke
				(width 0.1524)
				(type default)
			)
			(layer "F.SilkS")
		)
		(fp_line
			(start 0.67945 0.3048)
			(end 0.120396 0.3048)
			(stroke
				(width 0.1)
				(type default)
			)
			(layer "F.Fab")
		)
		(fp_line
			(start 0.67945 -0.3048)
			(end 0.67945 0.3048)
			(stroke
				(width 0.1)
				(type default)
			)
			(layer "F.Fab")
		)
		(fp_line
			(start 0.12065 -0.2794)
			(end 0.12065 -0.3048)
			(stroke
				(width 0.1)
				(type default)
			)
			(layer "F.Fab")
		)
		(fp_line
			(start 0.12065 -0.3048)
			(end 0.67945 -0.3048)
			(stroke
				(width 0.1)
				(type default)
			)
			(layer "F.Fab")
		)
		(fp_line
			(start 0.120396 0.3048)
			(end 0.120396 0.2794)
			(stroke
				(width 0.1)
				(type default)
			)
			(layer "F.Fab")
		)
		(fp_line
			(start 0.120396 0.2794)
			(end -0.12065 0.2794)
			(stroke
				(width 0.1)
				(type default)
			)
			(layer "F.Fab")
		)
		(fp_line
			(start -0.12065 0.3048)
			(end -0.67945 0.3048)
			(stroke
				(width 0.1)
				(type default)
			)
			(layer "F.Fab")
		)
		(fp_line
			(start -0.12065 0.2794)
			(end -0.12065 0.3048)
			(stroke
				(width 0.1)
				(type default)
			)
			(layer "F.Fab")
		)
		(fp_line
			(start -0.12065 -0.2794)
			(end 0.12065 -0.2794)
			(stroke
				(width 0.1)
				(type default)
			)
			(layer "F.Fab")
		)
		(fp_line
			(start -0.12065 -0.305054)
			(end -0.12065 -0.2794)
			(stroke
				(width 0.1)
				(type default)
			)
			(layer "F.Fab")
		)
		(fp_line
			(start -0.67945 0.3048)
			(end -0.67945 -0.305054)
			(stroke
				(width 0.1)
				(type default)
			)
			(layer "F.Fab")
		)
		(fp_line
			(start -0.67945 -0.305054)
			(end -0.12065 -0.305054)
			(stroke
				(width 0.1)
				(type default)
			)
			(layer "F.Fab")
		)
		(pad "1" smd circle
			(at -0.40005 0 180)
			(size 0 0)
			(layers "F.Cu" "F.Mask" "F.Paste")
			(net "PVCCD_HV_CPU1_VDD1")
		)
		(pad "2" smd circle
			(at 0.40005 0 180)
			(size 0 0)
			(layers "F.Cu" "F.Mask" "F.Paste")
			(net "GND")
		)
	)
	(footprint ""
		(layer "F.Cu")
		(at 9.652 -51.018948)
		(property "Reference" "R3052"
			(at 0 0 0)
			(layer "F.SilkS")
			(hide yes)
			(effects
				(font
					(size 1.27 1.27)
				)
			)
		)
		(property "Value" ""
			(at 0 0 0)
			(layer "F.Fab")
			(effects
				(font
					(size 1.27 1.27)
				)
			)
		)
		(duplicate_pad_numbers_are_jumpers no)
		(fp_line
			(start -0.7874 -0.4064)
			(end 0.7874 -0.4064)
			(stroke
				(width 0.1524)
				(type default)
			)
			(layer "F.SilkS")
		)
		(fp_line
			(start -0.7874 0.4064)
			(end -0.7874 -0.4064)
			(stroke
				(width 0.1524)
				(type default)
			)
			(layer "F.SilkS")
		)
		(fp_line
			(start 0.7874 -0.4064)
			(end 0.7874 0.4064)
			(stroke
				(width 0.1524)
				(type default)
			)
			(layer "F.SilkS")
		)
		(fp_line
			(start 0.7874 0.4064)
			(end -0.7874 0.4064)
			(stroke
				(width 0.1524)
				(type default)
			)
			(layer "F.SilkS")
		)
		(fp_line
			(start -0.67945 -0.305054)
			(end -0.12065 -0.305054)
			(stroke
				(width 0.1)
				(type default)
			)
			(layer "F.Fab")
		)
		(fp_line
			(start -0.67945 0.3048)
			(end -0.67945 -0.305054)
			(stroke
				(width 0.1)
				(type default)
			)
			(layer "F.Fab")
		)
		(fp_line
			(start -0.12065 -0.305054)
			(end -0.12065 -0.2794)
			(stroke
				(width 0.1)
				(type default)
			)
			(layer "F.Fab")
		)
		(fp_line
			(start -0.12065 -0.2794)
			(end 0.12065 -0.2794)
			(stroke
				(width 0.1)
				(type default)
			)
			(layer "F.Fab")
		)
		(fp_line
			(start -0.12065 0.2794)
			(end -0.12065 0.3048)
			(stroke
				(width 0.1)
				(type default)
			)
			(layer "F.Fab")
		)
		(fp_line
			(start -0.12065 0.3048)
			(end -0.67945 0.3048)
			(stroke
				(width 0.1)
				(type default)
			)
			(layer "F.Fab")
		)
		(fp_line
			(start 0.120396 0.2794)
			(end -0.12065 0.2794)
			(stroke
				(width 0.1)
				(type default)
			)
			(layer "F.Fab")
		)
		(fp_line
			(start 0.120396 0.3048)
			(end 0.120396 0.2794)
			(stroke
				(width 0.1)
				(type default)
			)
			(layer "F.Fab")
		)
		(fp_line
			(start 0.12065 -0.3048)
			(end 0.67945 -0.3048)
			(stroke
				(width 0.1)
				(type default)
			)
			(layer "F.Fab")
		)
		(fp_line
			(start 0.12065 -0.2794)
			(end 0.12065 -0.3048)
			(stroke
				(width 0.1)
				(type default)
			)
			(layer "F.Fab")
		)
		(fp_line
			(start 0.67945 -0.3048)
			(end 0.67945 0.3048)
			(stroke
				(width 0.1)
				(type default)
			)
			(layer "F.Fab")
		)
		(fp_line
			(start 0.67945 0.3048)
			(end 0.120396 0.3048)
			(stroke
				(width 0.1)
				(type default)
			)
			(layer "F.Fab")
		)
		(pad "1" smd circle
			(at -0.40005 0)
			(size 0 0)
			(layers "F.Cu" "F.Mask" "F.Paste")
			(net "SMB_HOST_3V3AUX_SCL_R5")
		)
		(pad "2" smd circle
			(at 0.40005 0)
			(size 0 0)
			(layers "F.Cu" "F.Mask" "F.Paste")
			(net "SMB_HOST_ME_SCL")
		)
	)
	(footprint ""
		(layer "F.Cu")
		(at 155.348686 -81.89468 90)
		(property "Reference" "R3123"
			(at 0 0 90)
			(layer "F.SilkS")
			(hide yes)
			(effects
				(font
					(size 1.27 1.27)
				)
			)
		)
		(property "Value" ""
			(at 0 0 90)
			(layer "F.Fab")
			(effects
				(font
					(size 1.27 1.27)
				)
			)
		)
		(duplicate_pad_numbers_are_jumpers no)
		(fp_line
			(start 0.7874 -0.4064)
			(end 0.7874 0.4064)
			(stroke
				(width 0.1524)
				(type default)
			)
			(layer "F.SilkS")
		)
		(fp_line
			(start -0.7874 -0.4064)
			(end 0.7874 -0.4064)
			(stroke
				(width 0.1524)
				(type default)
			)
			(layer "F.SilkS")
		)
		(fp_line
			(start 0.7874 0.4064)
			(end -0.7874 0.4064)
			(stroke
				(width 0.1524)
				(type default)
			)
			(layer "F.SilkS")
		)
		(fp_line
			(start -0.7874 0.4064)
			(end -0.7874 -0.4064)
			(stroke
				(width 0.1524)
				(type default)
			)
			(layer "F.SilkS")
		)
		(fp_line
			(start -0.12065 -0.305054)
			(end -0.12065 -0.2794)
			(stroke
				(width 0.1)
				(type default)
			)
			(layer "F.Fab")
		)
		(fp_line
			(start -0.67945 -0.305054)
			(end -0.12065 -0.305054)
			(stroke
				(width 0.1)
				(type default)
			)
			(layer "F.Fab")
		)
		(fp_line
			(start 0.67945 -0.3048)
			(end 0.67945 0.3048)
			(stroke
				(width 0.1)
				(type default)
			)
			(layer "F.Fab")
		)
		(fp_line
			(start 0.12065 -0.3048)
			(end 0.67945 -0.3048)
			(stroke
				(width 0.1)
				(type default)
			)
			(layer "F.Fab")
		)
		(fp_line
			(start 0.12065 -0.2794)
			(end 0.12065 -0.3048)
			(stroke
				(width 0.1)
				(type default)
			)
			(layer "F.Fab")
		)
		(fp_line
			(start -0.12065 -0.2794)
			(end 0.12065 -0.2794)
			(stroke
				(width 0.1)
				(type default)
			)
			(layer "F.Fab")
		)
		(fp_line
			(start 0.120396 0.2794)
			(end -0.12065 0.2794)
			(stroke
				(width 0.1)
				(type default)
			)
			(layer "F.Fab")
		)
		(fp_line
			(start -0.12065 0.2794)
			(end -0.12065 0.3048)
			(stroke
				(width 0.1)
				(type default)
			)
			(layer "F.Fab")
		)
		(fp_line
			(start 0.67945 0.3048)
			(end 0.120396 0.3048)
			(stroke
				(width 0.1)
				(type default)
			)
			(layer "F.Fab")
		)
		(fp_line
			(start 0.120396 0.3048)
			(end 0.120396 0.2794)
			(stroke
				(width 0.1)
				(type default)
			)
			(layer "F.Fab")
		)
		(fp_line
			(start -0.12065 0.3048)
			(end -0.67945 0.3048)
			(stroke
				(width 0.1)
				(type default)
			)
			(layer "F.Fab")
		)
		(fp_line
			(start -0.67945 0.3048)
			(end -0.67945 -0.305054)
			(stroke
				(width 0.1)
				(type default)
			)
			(layer "F.Fab")
		)
		(pad "1" smd circle
			(at -0.40005 0 90)
			(size 0 0)
			(layers "F.Cu" "F.Mask" "F.Paste")
			(net "SMB_S3M_CPU0_PIROM_3V3AUX_SCL_R")
		)
		(pad "2" smd circle
			(at 0.40005 0 90)
			(size 0 0)
			(layers "F.Cu" "F.Mask" "F.Paste")
			(net "SMB_S3M_CPU0_PIROM_3V3AUX_SCL")
		)
	)
	(footprint ""
		(layer "F.Cu")
		(at 18.753582 -423.629836 -90)
		(property "Reference" "R3518"
			(at 0 0 270)
			(layer "F.SilkS")
			(hide yes)
			(effects
				(font
					(size 1.27 1.27)
				)
			)
		)
		(property "Value" ""
			(at 0 0 270)
			(layer "F.Fab")
			(effects
				(font
					(size 1.27 1.27)
				)
			)
		)
		(duplicate_pad_numbers_are_jumpers no)
		(fp_line
			(start -0.7874 0.4064)
			(end -0.7874 -0.4064)
			(stroke
				(width 0.1524)
				(type default)
			)
			(layer "F.SilkS")
		)
		(fp_line
			(start 0.7874 0.4064)
			(end -0.7874 0.4064)
			(stroke
				(width 0.1524)
				(type default)
			)
			(layer "F.SilkS")
		)
		(fp_line
			(start -0.7874 -0.4064)
			(end 0.7874 -0.4064)
			(stroke
				(width 0.1524)
				(type default)
			)
			(layer "F.SilkS")
		)
		(fp_line
			(start 0.7874 -0.4064)
			(end 0.7874 0.4064)
			(stroke
				(width 0.1524)
				(type default)
			)
			(layer "F.SilkS")
		)
		(fp_line
			(start -0.67945 0.3048)
			(end -0.67945 -0.305054)
			(stroke
				(width 0.1)
				(type default)
			)
			(layer "F.Fab")
		)
		(fp_line
			(start -0.12065 0.3048)
			(end -0.67945 0.3048)
			(stroke
				(width 0.1)
				(type default)
			)
			(layer "F.Fab")
		)
		(fp_line
			(start 0.120396 0.3048)
			(end 0.120396 0.2794)
			(stroke
				(width 0.1)
				(type default)
			)
			(layer "F.Fab")
		)
		(fp_line
			(start 0.67945 0.3048)
			(end 0.120396 0.3048)
			(stroke
				(width 0.1)
				(type default)
			)
			(layer "F.Fab")
		)
		(fp_line
			(start -0.12065 0.2794)
			(end -0.12065 0.3048)
			(stroke
				(width 0.1)
				(type default)
			)
			(layer "F.Fab")
		)
		(fp_line
			(start 0.120396 0.2794)
			(end -0.12065 0.2794)
			(stroke
				(width 0.1)
				(type default)
			)
			(layer "F.Fab")
		)
		(fp_line
			(start -0.12065 -0.2794)
			(end 0.12065 -0.2794)
			(stroke
				(width 0.1)
				(type default)
			)
			(layer "F.Fab")
		)
		(fp_line
			(start 0.12065 -0.2794)
			(end 0.12065 -0.3048)
			(stroke
				(width 0.1)
				(type default)
			)
			(layer "F.Fab")
		)
		(fp_line
			(start 0.12065 -0.3048)
			(end 0.67945 -0.3048)
			(stroke
				(width 0.1)
				(type default)
			)
			(layer "F.Fab")
		)
		(fp_line
			(start 0.67945 -0.3048)
			(end 0.67945 0.3048)
			(stroke
				(width 0.1)
				(type default)
			)
			(layer "F.Fab")
		)
		(fp_line
			(start -0.67945 -0.305054)
			(end -0.12065 -0.305054)
			(stroke
				(width 0.1)
				(type default)
			)
			(layer "F.Fab")
		)
		(fp_line
			(start -0.12065 -0.305054)
			(end -0.12065 -0.2794)
			(stroke
				(width 0.1)
				(type default)
			)
			(layer "F.Fab")
		)
		(pad "1" smd circle
			(at -0.40005 0 270)
			(size 0 0)
			(layers "F.Cu" "F.Mask" "F.Paste")
			(net "GPU_PEX_STRAP0")
		)
		(pad "2" smd circle
			(at 0.40005 0 270)
			(size 0 0)
			(layers "F.Cu" "F.Mask" "F.Paste")
			(net "GPU_PEX_STRAP0_R")
		)
	)
	(footprint ""
		(layer "F.Cu")
		(at 115.219734 -95.504762 -90)
		(property "Reference" "U301"
			(at -0.353568 -3.017266 0)
			(unlocked yes)
			(layer "F.SilkS")
			(effects
				(font
					(size 0.7874 0.5842)
					(thickness 0.1524)
				)
				(justify left)
			)
		)
		(property "Value" ""
			(at 0 0 270)
			(layer "F.Fab")
			(effects
				(font
					(size 1.27 1.27)
				)
			)
		)
		(duplicate_pad_numbers_are_jumpers no)
		(fp_line
			(start -2.0066 2.5527)
			(end -2.0066 -2.5527)
			(stroke
				(width 0.1524)
				(type default)
			)
			(layer "F.SilkS")
		)
		(fp_line
			(start 2.0066 2.5527)
			(end -2.0066 2.5527)
			(stroke
				(width 0.1524)
				(type default)
			)
			(layer "F.SilkS")
		)
		(fp_line
			(start 0 -1.9812)
			(end 0.5715 -2.5527)
			(stroke
				(width 0.1524)
				(type default)
			)
			(layer "F.SilkS")
		)
		(fp_line
			(start -2.0066 -2.5527)
			(end -0.5715 -2.5527)
			(stroke
				(width 0.1524)
				(type default)
			)
			(layer "F.SilkS")
		)
		(fp_line
			(start -0.5715 -2.5527)
			(end 0 -1.9812)
			(stroke
				(width 0.1524)
				(type default)
			)
			(layer "F.SilkS")
		)
		(fp_line
			(start 0.5715 -2.5527)
			(end 2.0066 -2.5527)
			(stroke
				(width 0.1524)
				(type default)
			)
			(layer "F.SilkS")
		)
		(fp_line
			(start 2.0066 -2.5527)
			(end 2.0066 2.5527)
			(stroke
				(width 0.1524)
				(type default)
			)
			(layer "F.SilkS")
		)
		(fp_poly
			(pts
				(xy -2.958084 -2.921) (xy -3.286252 -2.36728) (xy -3.582924 -2.921)
			)
			(stroke
				(width 0)
				(type default)
			)
			(fill yes)
			(layer "F.SilkS")
		)
		(fp_line
			(start -2.249932 2.549906)
			(end -2.249932 -2.549906)
			(stroke
				(width 0.1)
				(type default)
			)
			(layer "F.Fab")
		)
		(fp_line
			(start 2.249932 2.549906)
			(end -2.249932 2.549906)
			(stroke
				(width 0.1)
				(type default)
			)
			(layer "F.Fab")
		)
		(fp_line
			(start -2.249932 -2.549906)
			(end 2.249932 -2.549906)
			(stroke
				(width 0.1)
				(type default)
			)
			(layer "F.Fab")
		)
		(fp_line
			(start 2.249932 -2.549906)
			(end 2.249932 2.549906)
			(stroke
				(width 0.1)
				(type default)
			)
			(layer "F.Fab")
		)
		(fp_poly
			(pts
				(xy -4.36372 -1.608328) (xy -4.36372 -2.233168) (xy -3.81 -1.905)
			)
			(stroke
				(width 0)
				(type default)
			)
			(fill yes)
			(layer "F.Fab")
		)
		(pad "1" smd rect
			(at -2.921 -1.949958 180)
			(size 0.3556 1.4986)
			(layers "F.Cu" "F.Mask" "F.Paste")
			(net "PD_CPU0_ERRS_DIR")
		)
		(pad "2" smd rect
			(at -2.921 -1.299972 180)
			(size 0.3556 1.4986)
			(layers "F.Cu" "F.Mask" "F.Paste")
			(net "H_CPU_CATERR_LVC1_R_N")
		)
		(pad "3" smd rect
			(at -2.921 -0.649986 180)
			(size 0.3556 1.4986)
			(layers "F.Cu" "F.Mask" "F.Paste")
			(net "H_CPU_CATERR_LVC1_R_N")
		)
		(pad "4" smd rect
			(at -2.921 0 180)
			(size 0.3556 1.4986)
			(layers "F.Cu" "F.Mask" "F.Paste")
			(net "P0V62_CPU0_ERRS_VREF")
		)
		(pad "5" smd rect
			(at -2.921 0.649986 180)
			(size 0.3556 1.4986)
			(layers "F.Cu" "F.Mask" "F.Paste")
			(net "H_CPU_RMCA_LVC1_R_N")
		)
		(pad "6" smd rect
			(at -2.921 1.299972 180)
			(size 0.3556 1.4986)
			(layers "F.Cu" "F.Mask" "F.Paste")
			(net "PWRGD_CPUPWRGD_LVC1")
		)
		(pad "7" smd rect
			(at -2.921 1.949958 180)
			(size 0.3556 1.4986)
			(layers "F.Cu" "F.Mask" "F.Paste")
			(net "GND")
		)
		(pad "8" smd rect
			(at 2.921 1.949958 180)
			(size 0.3556 1.4986)
			(layers "F.Cu" "F.Mask" "F.Paste")
			(net "GND")
		)
		(pad "9" smd rect
			(at 2.921 1.299972 180)
			(size 0.3556 1.4986)
			(layers "F.Cu" "F.Mask" "F.Paste")
			(net "PWRGD_CPUPWRGD_LVC2_R")
		)
		(pad "10" smd rect
			(at 2.921 0.649986 180)
			(size 0.3556 1.4986)
			(layers "F.Cu" "F.Mask" "F.Paste")
			(net "H_CPU_RMCA_LVC2_R1_N")
		)
		(pad "11" smd rect
			(at 2.921 0 180)
			(size 0.3556 1.4986)
			(layers "F.Cu" "F.Mask" "F.Paste")
			(net "GND")
		)
		(pad "12" smd rect
			(at 2.921 -0.649986 180)
			(size 0.3556 1.4986)
			(layers "F.Cu" "F.Mask" "F.Paste")
			(net "H_CPU_CATERR_LVC2_R1_N")
		)
		(pad "13" smd rect
			(at 2.921 -1.299972 180)
			(size 0.3556 1.4986)
			(layers "F.Cu" "F.Mask" "F.Paste")
			(net "H_CPU_CATERR_LVC2_BMC_R_N")
		)
		(pad "14" smd rect
			(at 2.921 -1.949958 180)
			(size 0.3556 1.4986)
			(layers "F.Cu" "F.Mask" "F.Paste")
			(net "P3V3")
		)
	)
	(footprint ""
		(layer "F.Cu")
		(at 449.650612 -23.594314 180)
		(property "Reference" "PC2085"
			(at 0 0 180)
			(layer "F.SilkS")
			(hide yes)
			(effects
				(font
					(size 1.27 1.27)
				)
			)
		)
		(property "Value" ""
			(at 0 0 180)
			(layer "F.Fab")
			(effects
				(font
					(size 1.27 1.27)
				)
			)
		)
		(duplicate_pad_numbers_are_jumpers no)
		(fp_line
			(start 0.7874 0.4064)
			(end -0.7874 0.4064)
			(stroke
				(width 0.1524)
				(type default)
			)
			(layer "F.SilkS")
		)
		(fp_line
			(start 0.7874 -0.4064)
			(end 0.7874 0.4064)
			(stroke
				(width 0.1524)
				(type default)
			)
			(layer "F.SilkS")
		)
		(fp_line
			(start -0.7874 0.4064)
			(end -0.7874 -0.4064)
			(stroke
				(width 0.1524)
				(type default)
			)
			(layer "F.SilkS")
		)
		(fp_line
			(start -0.7874 -0.4064)
			(end 0.7874 -0.4064)
			(stroke
				(width 0.1524)
				(type default)
			)
			(layer "F.SilkS")
		)
		(fp_line
			(start 0.67945 0.3048)
			(end 0.120396 0.3048)
			(stroke
				(width 0.1)
				(type default)
			)
			(layer "F.Fab")
		)
		(fp_line
			(start 0.67945 -0.3048)
			(end 0.67945 0.3048)
			(stroke
				(width 0.1)
				(type default)
			)
			(layer "F.Fab")
		)
		(fp_line
			(start 0.12065 -0.2794)
			(end 0.12065 -0.3048)
			(stroke
				(width 0.1)
				(type default)
			)
			(layer "F.Fab")
		)
		(fp_line
			(start 0.12065 -0.3048)
			(end 0.67945 -0.3048)
			(stroke
				(width 0.1)
				(type default)
			)
			(layer "F.Fab")
		)
		(fp_line
			(start 0.120396 0.3048)
			(end 0.120396 0.2794)
			(stroke
				(width 0.1)
				(type default)
			)
			(layer "F.Fab")
		)
		(fp_line
			(start 0.120396 0.2794)
			(end -0.12065 0.2794)
			(stroke
				(width 0.1)
				(type default)
			)
			(layer "F.Fab")
		)
		(fp_line
			(start -0.12065 0.3048)
			(end -0.67945 0.3048)
			(stroke
				(width 0.1)
				(type default)
			)
			(layer "F.Fab")
		)
		(fp_line
			(start -0.12065 0.2794)
			(end -0.12065 0.3048)
			(stroke
				(width 0.1)
				(type default)
			)
			(layer "F.Fab")
		)
		(fp_line
			(start -0.12065 -0.2794)
			(end 0.12065 -0.2794)
			(stroke
				(width 0.1)
				(type default)
			)
			(layer "F.Fab")
		)
		(fp_line
			(start -0.12065 -0.305054)
			(end -0.12065 -0.2794)
			(stroke
				(width 0.1)
				(type default)
			)
			(layer "F.Fab")
		)
		(fp_line
			(start -0.67945 0.3048)
			(end -0.67945 -0.305054)
			(stroke
				(width 0.1)
				(type default)
			)
			(layer "F.Fab")
		)
		(fp_line
			(start -0.67945 -0.305054)
			(end -0.12065 -0.305054)
			(stroke
				(width 0.1)
				(type default)
			)
			(layer "F.Fab")
		)
		(pad "1" smd circle
			(at -0.40005 0 180)
			(size 0 0)
			(layers "F.Cu" "F.Mask" "F.Paste")
			(net "P12V_OCP_VCC_1")
		)
		(pad "2" smd circle
			(at 0.40005 0 180)
			(size 0 0)
			(layers "F.Cu" "F.Mask" "F.Paste")
			(net "GND")
		)
	)
	(footprint ""
		(layer "F.Cu")
		(at 60.207398 -402.371052 -90)
		(property "Reference" "C718"
			(at 0 0 270)
			(layer "F.SilkS")
			(hide yes)
			(effects
				(font
					(size 1.27 1.27)
				)
			)
		)
		(property "Value" ""
			(at 0 0 270)
			(layer "F.Fab")
			(effects
				(font
					(size 1.27 1.27)
				)
			)
		)
		(duplicate_pad_numbers_are_jumpers no)
		(fp_line
			(start -0.299974 0.150114)
			(end -0.299974 -0.150114)
			(stroke
				(width 0.1)
				(type default)
			)
			(layer "F.Fab")
		)
		(fp_line
			(start 0.299974 0.150114)
			(end -0.299974 0.150114)
			(stroke
				(width 0.1)
				(type default)
			)
			(layer "F.Fab")
		)
		(fp_line
			(start -0.299974 -0.150114)
			(end 0.299974 -0.150114)
			(stroke
				(width 0.1)
				(type default)
			)
			(layer "F.Fab")
		)
		(fp_line
			(start 0.299974 -0.150114)
			(end 0.299974 0.150114)
			(stroke
				(width 0.1)
				(type default)
			)
			(layer "F.Fab")
		)
		(pad "1" smd rect
			(at -0.2667 0 270)
			(size 0.3048 0.381)
			(layers "F.Cu" "F.Mask" "F.Paste")
			(net "P5E_CPU1_PE0_TX_C_DN<11>")
		)
		(pad "2" smd rect
			(at 0.2667 0 270)
			(size 0.3048 0.381)
			(layers "F.Cu" "F.Mask" "F.Paste")
			(net "P5E_CPU1_PE0_TX_DN<11>")
		)
	)
	(footprint ""
		(layer "F.Cu")
		(at 95.125286 -427.776386 90)
		(property "Reference" "R3502"
			(at 0 0 90)
			(layer "F.SilkS")
			(hide yes)
			(effects
				(font
					(size 1.27 1.27)
				)
			)
		)
		(property "Value" ""
			(at 0 0 90)
			(layer "F.Fab")
			(effects
				(font
					(size 1.27 1.27)
				)
			)
		)
		(duplicate_pad_numbers_are_jumpers no)
		(fp_line
			(start 0.7874 -0.4064)
			(end 0.7874 0.4064)
			(stroke
				(width 0.1524)
				(type default)
			)
			(layer "F.SilkS")
		)
		(fp_line
			(start -0.7874 -0.4064)
			(end 0.7874 -0.4064)
			(stroke
				(width 0.1524)
				(type default)
			)
			(layer "F.SilkS")
		)
		(fp_line
			(start 0.7874 0.4064)
			(end -0.7874 0.4064)
			(stroke
				(width 0.1524)
				(type default)
			)
			(layer "F.SilkS")
		)
		(fp_line
			(start -0.7874 0.4064)
			(end -0.7874 -0.4064)
			(stroke
				(width 0.1524)
				(type default)
			)
			(layer "F.SilkS")
		)
		(fp_line
			(start -0.12065 -0.305054)
			(end -0.12065 -0.2794)
			(stroke
				(width 0.1)
				(type default)
			)
			(layer "F.Fab")
		)
		(fp_line
			(start -0.67945 -0.305054)
			(end -0.12065 -0.305054)
			(stroke
				(width 0.1)
				(type default)
			)
			(layer "F.Fab")
		)
		(fp_line
			(start 0.67945 -0.3048)
			(end 0.67945 0.3048)
			(stroke
				(width 0.1)
				(type default)
			)
			(layer "F.Fab")
		)
		(fp_line
			(start 0.12065 -0.3048)
			(end 0.67945 -0.3048)
			(stroke
				(width 0.1)
				(type default)
			)
			(layer "F.Fab")
		)
		(fp_line
			(start 0.12065 -0.2794)
			(end 0.12065 -0.3048)
			(stroke
				(width 0.1)
				(type default)
			)
			(layer "F.Fab")
		)
		(fp_line
			(start -0.12065 -0.2794)
			(end 0.12065 -0.2794)
			(stroke
				(width 0.1)
				(type default)
			)
			(layer "F.Fab")
		)
		(fp_line
			(start 0.120396 0.2794)
			(end -0.12065 0.2794)
			(stroke
				(width 0.1)
				(type default)
			)
			(layer "F.Fab")
		)
		(fp_line
			(start -0.12065 0.2794)
			(end -0.12065 0.3048)
			(stroke
				(width 0.1)
				(type default)
			)
			(layer "F.Fab")
		)
		(fp_line
			(start 0.67945 0.3048)
			(end 0.120396 0.3048)
			(stroke
				(width 0.1)
				(type default)
			)
			(layer "F.Fab")
		)
		(fp_line
			(start 0.120396 0.3048)
			(end 0.120396 0.2794)
			(stroke
				(width 0.1)
				(type default)
			)
			(layer "F.Fab")
		)
		(fp_line
			(start -0.12065 0.3048)
			(end -0.67945 0.3048)
			(stroke
				(width 0.1)
				(type default)
			)
			(layer "F.Fab")
		)
		(fp_line
			(start -0.67945 0.3048)
			(end -0.67945 -0.305054)
			(stroke
				(width 0.1)
				(type default)
			)
			(layer "F.Fab")
		)
		(pad "1" smd circle
			(at -0.40005 0 90)
			(size 0 0)
			(layers "F.Cu" "F.Mask" "F.Paste")
			(net "GPU_FPGA_EROT_FATALERR_N")
		)
		(pad "2" smd circle
			(at 0.40005 0 90)
			(size 0 0)
			(layers "F.Cu" "F.Mask" "F.Paste")
			(net "GND")
		)
	)
	(footprint ""
		(layer "F.Cu")
		(at 342.059768 -408.517344 -90)
		(property "Reference" "C926"
			(at 0 0 270)
			(layer "F.SilkS")
			(hide yes)
			(effects
				(font
					(size 1.27 1.27)
				)
			)
		)
		(property "Value" ""
			(at 0 0 270)
			(layer "F.Fab")
			(effects
				(font
					(size 1.27 1.27)
				)
			)
		)
		(duplicate_pad_numbers_are_jumpers no)
		(fp_line
			(start -0.299974 0.150114)
			(end -0.299974 -0.150114)
			(stroke
				(width 0.1)
				(type default)
			)
			(layer "F.Fab")
		)
		(fp_line
			(start 0.299974 0.150114)
			(end -0.299974 0.150114)
			(stroke
				(width 0.1)
				(type default)
			)
			(layer "F.Fab")
		)
		(fp_line
			(start -0.299974 -0.150114)
			(end 0.299974 -0.150114)
			(stroke
				(width 0.1)
				(type default)
			)
			(layer "F.Fab")
		)
		(fp_line
			(start 0.299974 -0.150114)
			(end 0.299974 0.150114)
			(stroke
				(width 0.1)
				(type default)
			)
			(layer "F.Fab")
		)
		(pad "1" smd rect
			(at -0.2667 0 270)
			(size 0.3048 0.381)
			(layers "F.Cu" "F.Mask" "F.Paste")
			(net "P5E_CPU0_PE0_TX_C_DN<3>")
		)
		(pad "2" smd rect
			(at 0.2667 0 270)
			(size 0.3048 0.381)
			(layers "F.Cu" "F.Mask" "F.Paste")
			(net "P5E_CPU0_PE0_TX_DN<3>")
		)
	)
	(footprint ""
		(layer "F.Cu")
		(at 168.449498 -353.36353 -90)
		(property "Reference" "PC1242_P1_1"
			(at 0 0 270)
			(layer "F.SilkS")
			(hide yes)
			(effects
				(font
					(size 1.27 1.27)
				)
			)
		)
		(property "Value" ""
			(at 0 0 270)
			(layer "F.Fab")
			(effects
				(font
					(size 1.27 1.27)
				)
			)
		)
		(duplicate_pad_numbers_are_jumpers no)
		(fp_line
			(start -0.7874 0.4064)
			(end -0.7874 -0.4064)
			(stroke
				(width 0.1524)
				(type default)
			)
			(layer "F.SilkS")
		)
		(fp_line
			(start 0.7874 0.4064)
			(end -0.7874 0.4064)
			(stroke
				(width 0.1524)
				(type default)
			)
			(layer "F.SilkS")
		)
		(fp_line
			(start -0.7874 -0.4064)
			(end 0.7874 -0.4064)
			(stroke
				(width 0.1524)
				(type default)
			)
			(layer "F.SilkS")
		)
		(fp_line
			(start 0.7874 -0.4064)
			(end 0.7874 0.4064)
			(stroke
				(width 0.1524)
				(type default)
			)
			(layer "F.SilkS")
		)
		(fp_line
			(start -0.67945 0.3048)
			(end -0.67945 -0.305054)
			(stroke
				(width 0.1)
				(type default)
			)
			(layer "F.Fab")
		)
		(fp_line
			(start -0.12065 0.3048)
			(end -0.67945 0.3048)
			(stroke
				(width 0.1)
				(type default)
			)
			(layer "F.Fab")
		)
		(fp_line
			(start 0.120396 0.3048)
			(end 0.120396 0.2794)
			(stroke
				(width 0.1)
				(type default)
			)
			(layer "F.Fab")
		)
		(fp_line
			(start 0.67945 0.3048)
			(end 0.120396 0.3048)
			(stroke
				(width 0.1)
				(type default)
			)
			(layer "F.Fab")
		)
		(fp_line
			(start -0.12065 0.2794)
			(end -0.12065 0.3048)
			(stroke
				(width 0.1)
				(type default)
			)
			(layer "F.Fab")
		)
		(fp_line
			(start 0.120396 0.2794)
			(end -0.12065 0.2794)
			(stroke
				(width 0.1)
				(type default)
			)
			(layer "F.Fab")
		)
		(fp_line
			(start -0.12065 -0.2794)
			(end 0.12065 -0.2794)
			(stroke
				(width 0.1)
				(type default)
			)
			(layer "F.Fab")
		)
		(fp_line
			(start 0.12065 -0.2794)
			(end 0.12065 -0.3048)
			(stroke
				(width 0.1)
				(type default)
			)
			(layer "F.Fab")
		)
		(fp_line
			(start 0.12065 -0.3048)
			(end 0.67945 -0.3048)
			(stroke
				(width 0.1)
				(type default)
			)
			(layer "F.Fab")
		)
		(fp_line
			(start 0.67945 -0.3048)
			(end 0.67945 0.3048)
			(stroke
				(width 0.1)
				(type default)
			)
			(layer "F.Fab")
		)
		(fp_line
			(start -0.67945 -0.305054)
			(end -0.12065 -0.305054)
			(stroke
				(width 0.1)
				(type default)
			)
			(layer "F.Fab")
		)
		(fp_line
			(start -0.12065 -0.305054)
			(end -0.12065 -0.2794)
			(stroke
				(width 0.1)
				(type default)
			)
			(layer "F.Fab")
		)
		(pad "1" smd circle
			(at -0.40005 0 270)
			(size 0 0)
			(layers "F.Cu" "F.Mask" "F.Paste")
			(net "PVCCFA_EHV_FIVRA_CPU1_PVCC1")
		)
		(pad "2" smd circle
			(at 0.40005 0 270)
			(size 0 0)
			(layers "F.Cu" "F.Mask" "F.Paste")
			(net "GND")
		)
	)
	(footprint ""
		(layer "F.Cu")
		(at 193.60388 -107.495848)
		(property "Reference" "R1492"
			(at 0 0 0)
			(layer "F.SilkS")
			(hide yes)
			(effects
				(font
					(size 1.27 1.27)
				)
			)
		)
		(property "Value" ""
			(at 0 0 0)
			(layer "F.Fab")
			(effects
				(font
					(size 1.27 1.27)
				)
			)
		)
		(duplicate_pad_numbers_are_jumpers no)
		(fp_line
			(start -0.7874 -0.4064)
			(end 0.7874 -0.4064)
			(stroke
				(width 0.1524)
				(type default)
			)
			(layer "F.SilkS")
		)
		(fp_line
			(start -0.7874 0.4064)
			(end -0.7874 -0.4064)
			(stroke
				(width 0.1524)
				(type default)
			)
			(layer "F.SilkS")
		)
		(fp_line
			(start 0.7874 -0.4064)
			(end 0.7874 0.4064)
			(stroke
				(width 0.1524)
				(type default)
			)
			(layer "F.SilkS")
		)
		(fp_line
			(start 0.7874 0.4064)
			(end -0.7874 0.4064)
			(stroke
				(width 0.1524)
				(type default)
			)
			(layer "F.SilkS")
		)
		(fp_line
			(start -0.67945 -0.305054)
			(end -0.12065 -0.305054)
			(stroke
				(width 0.1)
				(type default)
			)
			(layer "F.Fab")
		)
		(fp_line
			(start -0.67945 0.3048)
			(end -0.67945 -0.305054)
			(stroke
				(width 0.1)
				(type default)
			)
			(layer "F.Fab")
		)
		(fp_line
			(start -0.12065 -0.305054)
			(end -0.12065 -0.2794)
			(stroke
				(width 0.1)
				(type default)
			)
			(layer "F.Fab")
		)
		(fp_line
			(start -0.12065 -0.2794)
			(end 0.12065 -0.2794)
			(stroke
				(width 0.1)
				(type default)
			)
			(layer "F.Fab")
		)
		(fp_line
			(start -0.12065 0.2794)
			(end -0.12065 0.3048)
			(stroke
				(width 0.1)
				(type default)
			)
			(layer "F.Fab")
		)
		(fp_line
			(start -0.12065 0.3048)
			(end -0.67945 0.3048)
			(stroke
				(width 0.1)
				(type default)
			)
			(layer "F.Fab")
		)
		(fp_line
			(start 0.120396 0.2794)
			(end -0.12065 0.2794)
			(stroke
				(width 0.1)
				(type default)
			)
			(layer "F.Fab")
		)
		(fp_line
			(start 0.120396 0.3048)
			(end 0.120396 0.2794)
			(stroke
				(width 0.1)
				(type default)
			)
			(layer "F.Fab")
		)
		(fp_line
			(start 0.12065 -0.3048)
			(end 0.67945 -0.3048)
			(stroke
				(width 0.1)
				(type default)
			)
			(layer "F.Fab")
		)
		(fp_line
			(start 0.12065 -0.2794)
			(end 0.12065 -0.3048)
			(stroke
				(width 0.1)
				(type default)
			)
			(layer "F.Fab")
		)
		(fp_line
			(start 0.67945 -0.3048)
			(end 0.67945 0.3048)
			(stroke
				(width 0.1)
				(type default)
			)
			(layer "F.Fab")
		)
		(fp_line
			(start 0.67945 0.3048)
			(end 0.120396 0.3048)
			(stroke
				(width 0.1)
				(type default)
			)
			(layer "F.Fab")
		)
		(pad "1" smd circle
			(at -0.40005 0)
			(size 0 0)
			(layers "F.Cu" "F.Mask" "F.Paste")
			(net "FM_DIS_PS_PWROK_DLY")
		)
		(pad "2" smd circle
			(at 0.40005 0)
			(size 0 0)
			(layers "F.Cu" "F.Mask" "F.Paste")
			(net "P3V3_AUX")
		)
	)
	(footprint ""
		(layer "F.Cu")
		(at 308.33314 -430.73701 -90)
		(property "Reference" "R4124"
			(at 0 0 270)
			(layer "F.SilkS")
			(hide yes)
			(effects
				(font
					(size 1.27 1.27)
				)
			)
		)
		(property "Value" ""
			(at 0 0 270)
			(layer "F.Fab")
			(effects
				(font
					(size 1.27 1.27)
				)
			)
		)
		(duplicate_pad_numbers_are_jumpers no)
		(fp_line
			(start -0.7874 0.4064)
			(end -0.7874 -0.4064)
			(stroke
				(width 0.1524)
				(type default)
			)
			(layer "F.SilkS")
		)
		(fp_line
			(start 0.7874 0.4064)
			(end -0.7874 0.4064)
			(stroke
				(width 0.1524)
				(type default)
			)
			(layer "F.SilkS")
		)
		(fp_line
			(start -0.7874 -0.4064)
			(end 0.7874 -0.4064)
			(stroke
				(width 0.1524)
				(type default)
			)
			(layer "F.SilkS")
		)
		(fp_line
			(start 0.7874 -0.4064)
			(end 0.7874 0.4064)
			(stroke
				(width 0.1524)
				(type default)
			)
			(layer "F.SilkS")
		)
		(fp_line
			(start -0.67945 0.3048)
			(end -0.67945 -0.305054)
			(stroke
				(width 0.1)
				(type default)
			)
			(layer "F.Fab")
		)
		(fp_line
			(start -0.12065 0.3048)
			(end -0.67945 0.3048)
			(stroke
				(width 0.1)
				(type default)
			)
			(layer "F.Fab")
		)
		(fp_line
			(start 0.120396 0.3048)
			(end 0.120396 0.2794)
			(stroke
				(width 0.1)
				(type default)
			)
			(layer "F.Fab")
		)
		(fp_line
			(start 0.67945 0.3048)
			(end 0.120396 0.3048)
			(stroke
				(width 0.1)
				(type default)
			)
			(layer "F.Fab")
		)
		(fp_line
			(start -0.12065 0.2794)
			(end -0.12065 0.3048)
			(stroke
				(width 0.1)
				(type default)
			)
			(layer "F.Fab")
		)
		(fp_line
			(start 0.120396 0.2794)
			(end -0.12065 0.2794)
			(stroke
				(width 0.1)
				(type default)
			)
			(layer "F.Fab")
		)
		(fp_line
			(start -0.12065 -0.2794)
			(end 0.12065 -0.2794)
			(stroke
				(width 0.1)
				(type default)
			)
			(layer "F.Fab")
		)
		(fp_line
			(start 0.12065 -0.2794)
			(end 0.12065 -0.3048)
			(stroke
				(width 0.1)
				(type default)
			)
			(layer "F.Fab")
		)
		(fp_line
			(start 0.12065 -0.3048)
			(end 0.67945 -0.3048)
			(stroke
				(width 0.1)
				(type default)
			)
			(layer "F.Fab")
		)
		(fp_line
			(start 0.67945 -0.3048)
			(end 0.67945 0.3048)
			(stroke
				(width 0.1)
				(type default)
			)
			(layer "F.Fab")
		)
		(fp_line
			(start -0.67945 -0.305054)
			(end -0.12065 -0.305054)
			(stroke
				(width 0.1)
				(type default)
			)
			(layer "F.Fab")
		)
		(fp_line
			(start -0.12065 -0.305054)
			(end -0.12065 -0.2794)
			(stroke
				(width 0.1)
				(type default)
			)
			(layer "F.Fab")
		)
		(pad "1" smd circle
			(at -0.40005 0 270)
			(size 0 0)
			(layers "F.Cu" "F.Mask" "F.Paste")
			(net "GPU_3V3IO_RSVD1_FFU")
		)
		(pad "2" smd circle
			(at 0.40005 0 270)
			(size 0 0)
			(layers "F.Cu" "F.Mask" "F.Paste")
			(net "GND")
		)
	)
	(footprint ""
		(layer "F.Cu")
		(at 349.523304 -333.525368 -90)
		(property "Reference" "PC294_P0_2"
			(at 0 0 270)
			(layer "F.SilkS")
			(hide yes)
			(effects
				(font
					(size 1.27 1.27)
				)
			)
		)
		(property "Value" ""
			(at 0 0 270)
			(layer "F.Fab")
			(effects
				(font
					(size 1.27 1.27)
				)
			)
		)
		(duplicate_pad_numbers_are_jumpers no)
		(fp_line
			(start -0.7874 0.4064)
			(end -0.7874 -0.4064)
			(stroke
				(width 0.1524)
				(type default)
			)
			(layer "F.SilkS")
		)
		(fp_line
			(start 0.7874 0.4064)
			(end -0.7874 0.4064)
			(stroke
				(width 0.1524)
				(type default)
			)
			(layer "F.SilkS")
		)
		(fp_line
			(start -0.7874 -0.4064)
			(end 0.7874 -0.4064)
			(stroke
				(width 0.1524)
				(type default)
			)
			(layer "F.SilkS")
		)
		(fp_line
			(start 0.7874 -0.4064)
			(end 0.7874 0.4064)
			(stroke
				(width 0.1524)
				(type default)
			)
			(layer "F.SilkS")
		)
		(fp_line
			(start -0.67945 0.3048)
			(end -0.67945 -0.305054)
			(stroke
				(width 0.1)
				(type default)
			)
			(layer "F.Fab")
		)
		(fp_line
			(start -0.12065 0.3048)
			(end -0.67945 0.3048)
			(stroke
				(width 0.1)
				(type default)
			)
			(layer "F.Fab")
		)
		(fp_line
			(start 0.120396 0.3048)
			(end 0.120396 0.2794)
			(stroke
				(width 0.1)
				(type default)
			)
			(layer "F.Fab")
		)
		(fp_line
			(start 0.67945 0.3048)
			(end 0.120396 0.3048)
			(stroke
				(width 0.1)
				(type default)
			)
			(layer "F.Fab")
		)
		(fp_line
			(start -0.12065 0.2794)
			(end -0.12065 0.3048)
			(stroke
				(width 0.1)
				(type default)
			)
			(layer "F.Fab")
		)
		(fp_line
			(start 0.120396 0.2794)
			(end -0.12065 0.2794)
			(stroke
				(width 0.1)
				(type default)
			)
			(layer "F.Fab")
		)
		(fp_line
			(start -0.12065 -0.2794)
			(end 0.12065 -0.2794)
			(stroke
				(width 0.1)
				(type default)
			)
			(layer "F.Fab")
		)
		(fp_line
			(start 0.12065 -0.2794)
			(end 0.12065 -0.3048)
			(stroke
				(width 0.1)
				(type default)
			)
			(layer "F.Fab")
		)
		(fp_line
			(start 0.12065 -0.3048)
			(end 0.67945 -0.3048)
			(stroke
				(width 0.1)
				(type default)
			)
			(layer "F.Fab")
		)
		(fp_line
			(start 0.67945 -0.3048)
			(end 0.67945 0.3048)
			(stroke
				(width 0.1)
				(type default)
			)
			(layer "F.Fab")
		)
		(fp_line
			(start -0.67945 -0.305054)
			(end -0.12065 -0.305054)
			(stroke
				(width 0.1)
				(type default)
			)
			(layer "F.Fab")
		)
		(fp_line
			(start -0.12065 -0.305054)
			(end -0.12065 -0.2794)
			(stroke
				(width 0.1)
				(type default)
			)
			(layer "F.Fab")
		)
		(pad "1" smd circle
			(at -0.40005 0 270)
			(size 0 0)
			(layers "F.Cu" "F.Mask" "F.Paste")
			(net "PVCCIN_CPU0_PVCC")
		)
		(pad "2" smd circle
			(at 0.40005 0 270)
			(size 0 0)
			(layers "F.Cu" "F.Mask" "F.Paste")
			(net "GND")
		)
	)
	(footprint ""
		(layer "F.Cu")
		(at 430.643284 -179.201572 -90)
		(property "Reference" "PR1303"
			(at 0 0 270)
			(layer "F.SilkS")
			(hide yes)
			(effects
				(font
					(size 1.27 1.27)
				)
			)
		)
		(property "Value" ""
			(at 0 0 270)
			(layer "F.Fab")
			(effects
				(font
					(size 1.27 1.27)
				)
			)
		)
		(duplicate_pad_numbers_are_jumpers no)
		(fp_line
			(start -0.7874 0.4064)
			(end -0.7874 -0.4064)
			(stroke
				(width 0.1524)
				(type default)
			)
			(layer "F.SilkS")
		)
		(fp_line
			(start 0.7874 0.4064)
			(end -0.7874 0.4064)
			(stroke
				(width 0.1524)
				(type default)
			)
			(layer "F.SilkS")
		)
		(fp_line
			(start -0.7874 -0.4064)
			(end 0.7874 -0.4064)
			(stroke
				(width 0.1524)
				(type default)
			)
			(layer "F.SilkS")
		)
		(fp_line
			(start 0.7874 -0.4064)
			(end 0.7874 0.4064)
			(stroke
				(width 0.1524)
				(type default)
			)
			(layer "F.SilkS")
		)
		(fp_line
			(start -0.67945 0.3048)
			(end -0.67945 -0.305054)
			(stroke
				(width 0.1)
				(type default)
			)
			(layer "F.Fab")
		)
		(fp_line
			(start -0.12065 0.3048)
			(end -0.67945 0.3048)
			(stroke
				(width 0.1)
				(type default)
			)
			(layer "F.Fab")
		)
		(fp_line
			(start 0.120396 0.3048)
			(end 0.120396 0.2794)
			(stroke
				(width 0.1)
				(type default)
			)
			(layer "F.Fab")
		)
		(fp_line
			(start 0.67945 0.3048)
			(end 0.120396 0.3048)
			(stroke
				(width 0.1)
				(type default)
			)
			(layer "F.Fab")
		)
		(fp_line
			(start -0.12065 0.2794)
			(end -0.12065 0.3048)
			(stroke
				(width 0.1)
				(type default)
			)
			(layer "F.Fab")
		)
		(fp_line
			(start 0.120396 0.2794)
			(end -0.12065 0.2794)
			(stroke
				(width 0.1)
				(type default)
			)
			(layer "F.Fab")
		)
		(fp_line
			(start -0.12065 -0.2794)
			(end 0.12065 -0.2794)
			(stroke
				(width 0.1)
				(type default)
			)
			(layer "F.Fab")
		)
		(fp_line
			(start 0.12065 -0.2794)
			(end 0.12065 -0.3048)
			(stroke
				(width 0.1)
				(type default)
			)
			(layer "F.Fab")
		)
		(fp_line
			(start 0.12065 -0.3048)
			(end 0.67945 -0.3048)
			(stroke
				(width 0.1)
				(type default)
			)
			(layer "F.Fab")
		)
		(fp_line
			(start 0.67945 -0.3048)
			(end 0.67945 0.3048)
			(stroke
				(width 0.1)
				(type default)
			)
			(layer "F.Fab")
		)
		(fp_line
			(start -0.67945 -0.305054)
			(end -0.12065 -0.305054)
			(stroke
				(width 0.1)
				(type default)
			)
			(layer "F.Fab")
		)
		(fp_line
			(start -0.12065 -0.305054)
			(end -0.12065 -0.2794)
			(stroke
				(width 0.1)
				(type default)
			)
			(layer "F.Fab")
		)
		(pad "1" smd circle
			(at -0.40005 0 270)
			(size 0 0)
			(layers "F.Cu" "F.Mask" "F.Paste")
			(net "PVNN_MAIN_CPU0_CS")
		)
		(pad "2" smd circle
			(at 0.40005 0 270)
			(size 0 0)
			(layers "F.Cu" "F.Mask" "F.Paste")
			(net "GND")
		)
	)
	(footprint ""
		(layer "F.Cu")
		(at 111.93018 -251.76988 90)
		(property "Reference" "U1"
			(at -74.913236 41.548812 0)
			(unlocked yes)
			(layer "F.SilkS")
			(effects
				(font
					(size 1.6002 1.1938)
					(thickness 0.1524)
				)
				(justify left)
			)
		)
		(property "Value" ""
			(at 0 0 90)
			(layer "F.Fab")
			(effects
				(font
					(size 1.27 1.27)
				)
			)
		)
		(duplicate_pad_numbers_are_jumpers no)
		(fp_line
			(start 39.499794 -32.250126)
			(end 39.499794 -31.000192)
			(stroke
				(width 0.1524)
				(type default)
			)
			(layer "F.SilkS")
		)
		(fp_line
			(start 39.499794 -32.250126)
			(end 39.499794 -30.995874)
			(stroke
				(width 0.1524)
				(type default)
			)
			(layer "F.SilkS")
		)
		(fp_line
			(start 39.299896 -32.250126)
			(end 39.499794 -32.250126)
			(stroke
				(width 0.1524)
				(type default)
			)
			(layer "F.SilkS")
		)
		(fp_line
			(start 37.69995 -32.250126)
			(end 39.299896 -32.250126)
			(stroke
				(width 0.1524)
				(type default)
			)
			(layer "F.SilkS")
		)
		(fp_line
			(start 37.499798 -32.250126)
			(end 39.499794 -32.250126)
			(stroke
				(width 0.1524)
				(type default)
			)
			(layer "F.SilkS")
		)
		(fp_line
			(start 37.499798 -32.250126)
			(end 37.69995 -32.250126)
			(stroke
				(width 0.1524)
				(type default)
			)
			(layer "F.SilkS")
		)
		(fp_line
			(start -30.80004 -32.250126)
			(end -34.99993 -32.250126)
			(stroke
				(width 0.1524)
				(type default)
			)
			(layer "F.SilkS")
		)
		(fp_line
			(start -34.99993 -32.250126)
			(end -34.99993 -31.000192)
			(stroke
				(width 0.1524)
				(type default)
			)
			(layer "F.SilkS")
		)
		(fp_line
			(start -35.000184 -32.250126)
			(end -32.999934 -32.250126)
			(stroke
				(width 0.1524)
				(type default)
			)
			(layer "F.SilkS")
		)
		(fp_line
			(start 39.499794 -32.249872)
			(end 39.499794 -30.999938)
			(stroke
				(width 0.1524)
				(type default)
			)
			(layer "F.SilkS")
		)
		(fp_line
			(start 39.299896 -32.249872)
			(end 39.499794 -32.249872)
			(stroke
				(width 0.1524)
				(type default)
			)
			(layer "F.SilkS")
		)
		(fp_line
			(start 37.69995 -32.249872)
			(end 39.299896 -32.249872)
			(stroke
				(width 0.1524)
				(type default)
			)
			(layer "F.SilkS")
		)
		(fp_line
			(start 37.499798 -32.249872)
			(end 37.69995 -32.249872)
			(stroke
				(width 0.1524)
				(type default)
			)
			(layer "F.SilkS")
		)
		(fp_line
			(start -33.000188 -32.249872)
			(end -35.000184 -32.249872)
			(stroke
				(width 0.1524)
				(type default)
			)
			(layer "F.SilkS")
		)
		(fp_line
			(start -35.000184 -32.249872)
			(end -35.000184 -30.999938)
			(stroke
				(width 0.1524)
				(type default)
			)
			(layer "F.SilkS")
		)
		(fp_line
			(start 37.499798 -31.000192)
			(end 37.499798 -32.250126)
			(stroke
				(width 0.1524)
				(type default)
			)
			(layer "F.SilkS")
		)
		(fp_line
			(start 37.499798 -31.000192)
			(end 37.499798 -32.250126)
			(stroke
				(width 0.1524)
				(type default)
			)
			(layer "F.SilkS")
		)
		(fp_line
			(start -35.000184 -31.000192)
			(end -35.000184 -32.250126)
			(stroke
				(width 0.1524)
				(type default)
			)
			(layer "F.SilkS")
		)
		(fp_line
			(start 37.499798 -30.999938)
			(end 37.499798 -32.249872)
			(stroke
				(width 0.1524)
				(type default)
			)
			(layer "F.SilkS")
		)
		(fp_line
			(start 41.000172 -30.500066)
			(end 40.000174 -30.500066)
			(stroke
				(width 0.1524)
				(type default)
			)
			(layer "F.SilkS")
		)
		(fp_line
			(start 40.999918 -30.500066)
			(end 40.999918 30.500066)
			(stroke
				(width 0.1524)
				(type default)
			)
			(layer "F.SilkS")
		)
		(fp_line
			(start 39.998396 -30.500066)
			(end 40.999918 -30.500066)
			(stroke
				(width 0.1524)
				(type default)
			)
			(layer "F.SilkS")
		)
		(fp_line
			(start 37.00018 -30.500066)
			(end 35.81019 -30.500066)
			(stroke
				(width 0.1524)
				(type default)
			)
			(layer "F.SilkS")
		)
		(fp_line
			(start 35.81019 -30.500066)
			(end 35.81019 -29.500068)
			(stroke
				(width 0.1524)
				(type default)
			)
			(layer "F.SilkS")
		)
		(fp_line
			(start 31.809944 -30.500066)
			(end 30.209998 -30.500066)
			(stroke
				(width 0.1524)
				(type default)
			)
			(layer "F.SilkS")
		)
		(fp_line
			(start 30.209998 -30.500066)
			(end 30.209998 -29.500068)
			(stroke
				(width 0.1524)
				(type default)
			)
			(layer "F.SilkS")
		)
		(fp_line
			(start -30.80004 -30.500066)
			(end -30.80004 -32.250126)
			(stroke
				(width 0.1524)
				(type default)
			)
			(layer "F.SilkS")
		)
		(fp_line
			(start -32.999934 -30.500066)
			(end 37.001704 -30.500066)
			(stroke
				(width 0.1524)
				(type default)
			)
			(layer "F.SilkS")
		)
		(fp_line
			(start -35.809936 -30.500066)
			(end -35.500056 -30.500066)
			(stroke
				(width 0.1524)
				(type default)
			)
			(layer "F.SilkS")
		)
		(fp_line
			(start -39.500048 -30.500066)
			(end -35.49523 -30.500066)
			(stroke
				(width 0.1524)
				(type default)
			)
			(layer "F.SilkS")
		)
		(fp_line
			(start -39.500048 -30.500066)
			(end -35.809936 -30.500066)
			(stroke
				(width 0.1524)
				(type default)
			)
			(layer "F.SilkS")
		)
		(fp_line
			(start 40.999918 -30.499812)
			(end 39.99992 -30.499812)
			(stroke
				(width 0.1524)
				(type default)
			)
			(layer "F.SilkS")
		)
		(fp_line
			(start 36.999926 -30.499812)
			(end 35.809936 -30.499812)
			(stroke
				(width 0.1524)
				(type default)
			)
			(layer "F.SilkS")
		)
		(fp_line
			(start 35.809936 -30.499812)
			(end 35.809936 -29.499814)
			(stroke
				(width 0.1524)
				(type default)
			)
			(layer "F.SilkS")
		)
		(fp_line
			(start 31.809944 -30.499812)
			(end 30.209998 -30.499812)
			(stroke
				(width 0.1524)
				(type default)
			)
			(layer "F.SilkS")
		)
		(fp_line
			(start 30.209998 -30.499812)
			(end 30.209998 -29.499814)
			(stroke
				(width 0.1524)
				(type default)
			)
			(layer "F.SilkS")
		)
		(fp_line
			(start -35.81019 -30.499812)
			(end -35.500056 -30.499812)
			(stroke
				(width 0.1524)
				(type default)
			)
			(layer "F.SilkS")
		)
		(fp_line
			(start -39.500048 -30.499812)
			(end -35.81019 -30.499812)
			(stroke
				(width 0.1524)
				(type default)
			)
			(layer "F.SilkS")
		)
		(fp_line
			(start 35.81019 -29.800042)
			(end 35.81019 -28.999942)
			(stroke
				(width 0.1524)
				(type default)
			)
			(layer "F.SilkS")
		)
		(fp_line
			(start 35.809936 -29.799788)
			(end 35.809936 -28.999942)
			(stroke
				(width 0.1524)
				(type default)
			)
			(layer "F.SilkS")
		)
		(fp_line
			(start 35.81019 -29.500068)
			(end 31.809944 -29.500068)
			(stroke
				(width 0.1524)
				(type default)
			)
			(layer "F.SilkS")
		)
		(fp_line
			(start 31.809944 -29.500068)
			(end 31.809944 -30.500066)
			(stroke
				(width 0.1524)
				(type default)
			)
			(layer "F.SilkS")
		)
		(fp_line
			(start 31.809944 -29.500068)
			(end 31.809944 -28.450032)
			(stroke
				(width 0.1524)
				(type default)
			)
			(layer "F.SilkS")
		)
		(fp_line
			(start 30.209998 -29.500068)
			(end 2.999994 -29.500068)
			(stroke
				(width 0.1524)
				(type default)
			)
			(layer "F.SilkS")
		)
		(fp_line
			(start 2.999994 -29.500068)
			(end 1.299972 -27.450034)
			(stroke
				(width 0.1524)
				(type default)
			)
			(layer "F.SilkS")
		)
		(fp_line
			(start -2.99974 -29.500068)
			(end -32.999934 -29.500068)
			(stroke
				(width 0.1524)
				(type default)
			)
			(layer "F.SilkS")
		)
		(fp_line
			(start -32.999934 -29.500068)
			(end -32.999934 -28.999942)
			(stroke
				(width 0.1524)
				(type default)
			)
			(layer "F.SilkS")
		)
		(fp_line
			(start 35.809936 -29.499814)
			(end 31.809944 -29.499814)
			(stroke
				(width 0.1524)
				(type default)
			)
			(layer "F.SilkS")
		)
		(fp_line
			(start 31.809944 -29.499814)
			(end 31.809944 -30.499812)
			(stroke
				(width 0.1524)
				(type default)
			)
			(layer "F.SilkS")
		)
		(fp_line
			(start 31.809944 -29.499814)
			(end 31.809944 -28.450032)
			(stroke
				(width 0.1524)
				(type default)
			)
			(layer "F.SilkS")
		)
		(fp_line
			(start 30.209998 -29.499814)
			(end 2.999994 -29.499814)
			(stroke
				(width 0.1524)
				(type default)
			)
			(layer "F.SilkS")
		)
		(fp_line
			(start 2.999994 -29.499814)
			(end 1.299972 -27.44978)
			(stroke
				(width 0.1524)
				(type default)
			)
			(layer "F.SilkS")
		)
		(fp_line
			(start -2.999994 -29.499814)
			(end -33.000188 -29.499814)
			(stroke
				(width 0.1524)
				(type default)
			)
			(layer "F.SilkS")
		)
		(fp_line
			(start -33.000188 -29.499814)
			(end -32.999934 -30.500066)
			(stroke
				(width 0.1524)
				(type default)
			)
			(layer "F.SilkS")
		)
		(fp_line
			(start -33.000188 -29.499814)
			(end -33.000188 -28.999942)
			(stroke
				(width 0.1524)
				(type default)
			)
			(layer "F.SilkS")
		)
		(fp_line
			(start 37.810186 -29.009848)
			(end 38.759892 -29.009848)
			(stroke
				(width 0.1524)
				(type default)
			)
			(layer "F.SilkS")
		)
		(fp_line
			(start 37.809932 -29.009848)
			(end 38.759892 -29.009848)
			(stroke
				(width 0.1524)
				(type default)
			)
			(layer "F.SilkS")
		)
		(fp_line
			(start -38.760146 -29.009848)
			(end -37.809932 -29.009848)
			(stroke
				(width 0.1524)
				(type default)
			)
			(layer "F.SilkS")
		)
		(fp_line
			(start -38.760146 -29.009848)
			(end -37.810186 -29.009848)
			(stroke
				(width 0.1524)
				(type default)
			)
			(layer "F.SilkS")
		)
		(fp_line
			(start -40.999918 -29.000196)
			(end -39.500048 -30.500066)
			(stroke
				(width 0.1524)
				(type default)
			)
			(layer "F.SilkS")
		)
		(fp_line
			(start 37.810186 -28.999942)
			(end 37.810186 -28.300172)
			(stroke
				(width 0.1524)
				(type default)
			)
			(layer "F.SilkS")
		)
		(fp_line
			(start 37.809932 -28.999942)
			(end 37.809932 -28.299918)
			(stroke
				(width 0.1524)
				(type default)
			)
			(layer "F.SilkS")
		)
		(fp_line
			(start -32.999934 -28.999942)
			(end -33.199832 -28.999942)
			(stroke
				(width 0.1524)
				(type default)
			)
			(layer "F.SilkS")
		)
		(fp_line
			(start -33.000188 -28.999942)
			(end -33.200086 -28.999942)
			(stroke
				(width 0.1524)
				(type default)
			)
			(layer "F.SilkS")
		)
		(fp_line
			(start -33.199832 -28.999942)
			(end -35.809936 -28.999942)
			(stroke
				(width 0.1524)
				(type default)
			)
			(layer "F.SilkS")
		)
		(fp_line
			(start -33.200086 -28.999942)
			(end -35.81019 -28.999942)
			(stroke
				(width 0.1524)
				(type default)
			)
			(layer "F.SilkS")
		)
		(fp_line
			(start -35.809936 -28.999942)
			(end -35.809936 -28.300172)
			(stroke
				(width 0.1524)
				(type default)
			)
			(layer "F.SilkS")
		)
		(fp_line
			(start -35.81019 -28.999942)
			(end -35.81019 -28.299918)
			(stroke
				(width 0.1524)
				(type default)
			)
			(layer "F.SilkS")
		)
		(fp_line
			(start -40.999918 -28.999942)
			(end -39.500048 -30.500066)
			(stroke
				(width 0.1524)
				(type default)
			)
			(layer "F.SilkS")
		)
		(fp_line
			(start -40.999918 -28.999942)
			(end -40.999918 -12.499848)
			(stroke
				(width 0.1524)
				(type default)
			)
			(layer "F.SilkS")
		)
		(fp_line
			(start -41.000172 -28.999942)
			(end -39.500048 -30.499812)
			(stroke
				(width 0.1524)
				(type default)
			)
			(layer "F.SilkS")
		)
		(fp_line
			(start -41.000172 -28.999942)
			(end -41.000172 -12.499848)
			(stroke
				(width 0.1524)
				(type default)
			)
			(layer "F.SilkS")
		)
		(fp_line
			(start 30.209998 -28.450032)
			(end 30.209998 -30.500066)
			(stroke
				(width 0.1524)
				(type default)
			)
			(layer "F.SilkS")
		)
		(fp_line
			(start 30.209998 -28.450032)
			(end 30.209998 -30.499812)
			(stroke
				(width 0.1524)
				(type default)
			)
			(layer "F.SilkS")
		)
		(fp_line
			(start 37.810186 -28.300172)
			(end 37.810186 -29.009848)
			(stroke
				(width 0.1524)
				(type default)
			)
			(layer "F.SilkS")
		)
		(fp_line
			(start 35.81019 -28.300172)
			(end 35.81019 -28.999942)
			(stroke
				(width 0.1524)
				(type default)
			)
			(layer "F.SilkS")
		)
		(fp_line
			(start 35.81019 -28.300172)
			(end 37.810186 -28.300172)
			(stroke
				(width 0.1524)
				(type default)
			)
			(layer "F.SilkS")
		)
		(fp_line
			(start -35.809936 -28.300172)
			(end -37.809932 -28.300172)
			(stroke
				(width 0.1524)
				(type default)
			)
			(layer "F.SilkS")
		)
		(fp_line
			(start -37.809932 -28.300172)
			(end -37.809932 -28.999942)
			(stroke
				(width 0.1524)
				(type default)
			)
			(layer "F.SilkS")
		)
		(fp_line
			(start 38.800024 -28.299918)
			(end -38.800024 -28.299918)
			(stroke
				(width 0.1524)
				(type default)
			)
			(layer "F.SilkS")
		)
		(fp_line
			(start 37.809932 -28.299918)
			(end 37.809932 -29.009848)
			(stroke
				(width 0.1524)
				(type default)
			)
			(layer "F.SilkS")
		)
		(fp_line
			(start 35.809936 -28.299918)
			(end 35.809936 -28.999942)
			(stroke
				(width 0.1524)
				(type default)
			)
			(layer "F.SilkS")
		)
		(fp_line
			(start 35.809936 -28.299918)
			(end 37.809932 -28.299918)
			(stroke
				(width 0.1524)
				(type default)
			)
			(layer "F.SilkS")
		)
		(fp_line
			(start -35.81019 -28.299918)
			(end -37.810186 -28.299918)
			(stroke
				(width 0.1524)
				(type default)
			)
			(layer "F.SilkS")
		)
		(fp_line
			(start -37.810186 -28.299918)
			(end -37.810186 -28.999942)
			(stroke
				(width 0.1524)
				(type default)
			)
			(layer "F.SilkS")
		)
		(fp_line
			(start -38.800024 -28.299918)
			(end -38.800024 28.299918)
			(stroke
				(width 0.1524)
				(type default)
			)
			(layer "F.SilkS")
		)
		(fp_line
			(start 39.509954 -28.26004)
			(end 39.509954 -27.31008)
			(stroke
				(width 0.1524)
				(type default)
			)
			(layer "F.SilkS")
		)
		(fp_line
			(start 39.509954 -28.259786)
			(end 39.509954 -27.309826)
			(stroke
				(width 0.1524)
				(type default)
			)
			(layer "F.SilkS")
		)
		(fp_line
			(start 1.299972 -27.450034)
			(end -1.299718 -27.450034)
			(stroke
				(width 0.1524)
				(type default)
			)
			(layer "F.SilkS")
		)
		(fp_line
			(start -1.299718 -27.450034)
			(end -2.99974 -29.500068)
			(stroke
				(width 0.1524)
				(type default)
			)
			(layer "F.SilkS")
		)
		(fp_line
			(start 1.299972 -27.44978)
			(end -1.299972 -27.44978)
			(stroke
				(width 0.1524)
				(type default)
			)
			(layer "F.SilkS")
		)
		(fp_line
			(start -1.299972 -27.44978)
			(end -2.999994 -29.499814)
			(stroke
				(width 0.1524)
				(type default)
			)
			(layer "F.SilkS")
		)
		(fp_line
			(start -38.800024 -27.31008)
			(end -38.800024 -25.310084)
			(stroke
				(width 0.1524)
				(type default)
			)
			(layer "F.SilkS")
		)
		(fp_line
			(start -39.500048 -27.31008)
			(end -38.800024 -27.31008)
			(stroke
				(width 0.1524)
				(type default)
			)
			(layer "F.SilkS")
		)
		(fp_line
			(start -39.500048 -27.31008)
			(end -39.510208 -27.31008)
			(stroke
				(width 0.1524)
				(type default)
			)
			(layer "F.SilkS")
		)
		(fp_line
			(start -39.510208 -27.31008)
			(end -39.510208 -28.26004)
			(stroke
				(width 0.1524)
				(type default)
			)
			(layer "F.SilkS")
		)
		(fp_line
			(start 39.509954 -27.309826)
			(end 39.499794 -27.309826)
			(stroke
				(width 0.1524)
				(type default)
			)
			(layer "F.SilkS")
		)
		(fp_line
			(start 38.800024 -27.309826)
			(end 39.499794 -27.309826)
			(stroke
				(width 0.1524)
				(type default)
			)
			(layer "F.SilkS")
		)
		(fp_line
			(start -38.800024 -27.309826)
			(end -38.800024 -25.30983)
			(stroke
				(width 0.1524)
				(type default)
			)
			(layer "F.SilkS")
		)
		(fp_line
			(start -39.500048 -27.309826)
			(end -38.800024 -27.309826)
			(stroke
				(width 0.1524)
				(type default)
			)
			(layer "F.SilkS")
		)
		(fp_line
			(start -39.500048 -27.309826)
			(end -39.510208 -27.309826)
			(stroke
				(width 0.1524)
				(type default)
			)
			(layer "F.SilkS")
		)
		(fp_line
			(start -39.510208 -27.309826)
			(end -39.510208 -28.259786)
			(stroke
				(width 0.1524)
				(type default)
			)
			(layer "F.SilkS")
		)
		(fp_line
			(start 40.046402 -25.310084)
			(end 41.000172 -25.310084)
			(stroke
				(width 0.1524)
				(type default)
			)
			(layer "F.SilkS")
		)
		(fp_line
			(start 38.800278 -25.310084)
			(end 40.046402 -25.310084)
			(stroke
				(width 0.1524)
				(type default)
			)
			(layer "F.SilkS")
		)
		(fp_line
			(start -40.046656 -25.310084)
			(end -38.800024 -25.310084)
			(stroke
				(width 0.1524)
				(type default)
			)
			(layer "F.SilkS")
		)
		(fp_line
			(start -40.999918 -25.310084)
			(end -40.046656 -25.310084)
			(stroke
				(width 0.1524)
				(type default)
			)
			(layer "F.SilkS")
		)
		(fp_line
			(start 40.046402 -25.30983)
			(end 40.999918 -25.30983)
			(stroke
				(width 0.1524)
				(type default)
			)
			(layer "F.SilkS")
		)
		(fp_line
			(start 38.800024 -25.30983)
			(end 38.800024 -27.309826)
			(stroke
				(width 0.1524)
				(type default)
			)
			(layer "F.SilkS")
		)
		(fp_line
			(start 38.800024 -25.30983)
			(end 40.046402 -25.30983)
			(stroke
				(width 0.1524)
				(type default)
			)
			(layer "F.SilkS")
		)
		(fp_line
			(start -40.046656 -25.30983)
			(end -38.800024 -25.30983)
			(stroke
				(width 0.1524)
				(type default)
			)
			(layer "F.SilkS")
		)
		(fp_line
			(start -41.000172 -25.30983)
			(end -40.046656 -25.30983)
			(stroke
				(width 0.1524)
				(type default)
			)
			(layer "F.SilkS")
		)
		(fp_line
			(start 41.000172 -12.499848)
			(end 41.000172 -30.500066)
			(stroke
				(width 0.1524)
				(type default)
			)
			(layer "F.SilkS")
		)
		(fp_line
			(start 40.999918 -12.499848)
			(end 40.999918 -30.499812)
			(stroke
				(width 0.1524)
				(type default)
			)
			(layer "F.SilkS")
		)
		(fp_line
			(start -40.999918 -12.499848)
			(end -39.99992 -8.000238)
			(stroke
				(width 0.1524)
				(type default)
			)
			(layer "F.SilkS")
		)
		(fp_line
			(start -41.000172 -12.499848)
			(end -40.000174 -7.999984)
			(stroke
				(width 0.1524)
				(type default)
			)
			(layer "F.SilkS")
		)
		(fp_line
			(start 10.363454 -8.419846)
			(end -15.24635 -8.419846)
			(stroke
				(width 0.1524)
				(type default)
			)
			(layer "F.SilkS")
		)
		(fp_line
			(start 10.363454 -8.419846)
			(end 10.363454 -3.797808)
			(stroke
				(width 0.1524)
				(type default)
			)
			(layer "F.SilkS")
		)
		(fp_line
			(start 40.000174 -8.000238)
			(end 41.000172 -12.499848)
			(stroke
				(width 0.1524)
				(type default)
			)
			(layer "F.SilkS")
		)
		(fp_line
			(start -39.99992 -8.000238)
			(end -39.99992 -2.62509)
			(stroke
				(width 0.1524)
				(type default)
			)
			(layer "F.SilkS")
		)
		(fp_line
			(start 39.99992 -7.999984)
			(end 40.999918 -12.499848)
			(stroke
				(width 0.1524)
				(type default)
			)
			(layer "F.SilkS")
		)
		(fp_line
			(start -40.000174 -7.999984)
			(end -40.000174 -2.624836)
			(stroke
				(width 0.1524)
				(type default)
			)
			(layer "F.SilkS")
		)
		(fp_line
			(start -15.24635 -3.797808)
			(end -15.24635 -8.419846)
			(stroke
				(width 0.1524)
				(type default)
			)
			(layer "F.SilkS")
		)
		(fp_line
			(start -15.24635 -3.797808)
			(end 10.363454 -3.797808)
			(stroke
				(width 0.1524)
				(type default)
			)
			(layer "F.SilkS")
		)
		(fp_line
			(start 40.000174 -2.62509)
			(end 40.000174 -8.000238)
			(stroke
				(width 0.1524)
				(type default)
			)
			(layer "F.SilkS")
		)
		(fp_line
			(start -39.99992 -2.62509)
			(end -37.999924 -1.550162)
			(stroke
				(width 0.1524)
				(type default)
			)
			(layer "F.SilkS")
		)
		(fp_line
			(start 39.99992 -2.624836)
			(end 39.99992 -7.999984)
			(stroke
				(width 0.1524)
				(type default)
			)
			(layer "F.SilkS")
		)
		(fp_line
			(start -40.000174 -2.624836)
			(end -38.000178 -1.549908)
			(stroke
				(width 0.1524)
				(type default)
			)
			(layer "F.SilkS")
		)
		(fp_line
			(start 38.000178 -1.550162)
			(end 40.000174 -2.62509)
			(stroke
				(width 0.1524)
				(type default)
			)
			(layer "F.SilkS")
		)
		(fp_line
			(start -37.999924 -1.550162)
			(end -37.999924 1.549908)
			(stroke
				(width 0.1524)
				(type default)
			)
			(layer "F.SilkS")
		)
		(fp_line
			(start 37.999924 -1.549908)
			(end 39.99992 -2.624836)
			(stroke
				(width 0.1524)
				(type default)
			)
			(layer "F.SilkS")
		)
		(fp_line
			(start -38.000178 -1.549908)
			(end -38.000178 1.550162)
			(stroke
				(width 0.1524)
				(type default)
			)
			(layer "F.SilkS")
		)
		(fp_line
			(start 38.000178 1.549908)
			(end 38.000178 -1.550162)
			(stroke
				(width 0.1524)
				(type default)
			)
			(layer "F.SilkS")
		)
		(fp_line
			(start -37.999924 1.549908)
			(end -39.99992 2.624836)
			(stroke
				(width 0.1524)
				(type default)
			)
			(layer "F.SilkS")
		)
		(fp_line
			(start 37.999924 1.550162)
			(end 37.999924 -1.549908)
			(stroke
				(width 0.1524)
				(type default)
			)
			(layer "F.SilkS")
		)
		(fp_line
			(start -38.000178 1.550162)
			(end -40.000174 2.62509)
			(stroke
				(width 0.1524)
				(type default)
			)
			(layer "F.SilkS")
		)
		(fp_line
			(start 40.000174 2.624836)
			(end 38.000178 1.549908)
			(stroke
				(width 0.1524)
				(type default)
			)
			(layer "F.SilkS")
		)
		(fp_line
			(start -39.99992 2.624836)
			(end -39.99992 7.99973)
			(stroke
				(width 0.1524)
				(type default)
			)
			(layer "F.SilkS")
		)
		(fp_line
			(start 39.99992 2.62509)
			(end 37.999924 1.550162)
			(stroke
				(width 0.1524)
				(type default)
			)
			(layer "F.SilkS")
		)
		(fp_line
			(start -40.000174 2.62509)
			(end -40.000174 7.999984)
			(stroke
				(width 0.1524)
				(type default)
			)
			(layer "F.SilkS")
		)
		(fp_line
			(start 10.363454 3.797554)
			(end -15.24635 3.797554)
			(stroke
				(width 0.1524)
				(type default)
			)
			(layer "F.SilkS")
		)
		(fp_line
			(start 10.363454 3.797554)
			(end 10.363454 8.419592)
			(stroke
				(width 0.1524)
				(type default)
			)
			(layer "F.SilkS")
		)
		(fp_line
			(start 40.000174 7.99973)
			(end 40.000174 2.624836)
			(stroke
				(width 0.1524)
				(type default)
			)
			(layer "F.SilkS")
		)
		(fp_line
			(start -39.99992 7.99973)
			(end -40.999918 12.499848)
			(stroke
				(width 0.1524)
				(type default)
			)
			(layer "F.SilkS")
		)
		(fp_line
			(start 39.99992 7.999984)
			(end 39.99992 2.62509)
			(stroke
				(width 0.1524)
				(type default)
			)
			(layer "F.SilkS")
		)
		(fp_line
			(start -40.000174 7.999984)
			(end -41.000172 12.500102)
			(stroke
				(width 0.1524)
				(type default)
			)
			(layer "F.SilkS")
		)
		(fp_line
			(start -15.24635 8.419592)
			(end -15.24635 3.797554)
			(stroke
				(width 0.1524)
				(type default)
			)
			(layer "F.SilkS")
		)
		(fp_line
			(start -15.24635 8.419592)
			(end 10.363454 8.419592)
			(stroke
				(width 0.1524)
				(type default)
			)
			(layer "F.SilkS")
		)
		(fp_line
			(start 41.000172 12.499848)
			(end 40.000174 7.99973)
			(stroke
				(width 0.1524)
				(type default)
			)
			(layer "F.SilkS")
		)
		(fp_line
			(start -40.999918 12.499848)
			(end -40.999918 30.499812)
			(stroke
				(width 0.1524)
				(type default)
			)
			(layer "F.SilkS")
		)
		(fp_line
			(start 40.999918 12.500102)
			(end 39.99992 7.999984)
			(stroke
				(width 0.1524)
				(type default)
			)
			(layer "F.SilkS")
		)
		(fp_line
			(start -41.000172 12.500102)
			(end -41.000172 30.500066)
			(stroke
				(width 0.1524)
				(type default)
			)
			(layer "F.SilkS")
		)
		(fp_line
			(start 41.000172 25.30983)
			(end 38.800278 25.30983)
			(stroke
				(width 0.1524)
				(type default)
			)
			(layer "F.SilkS")
		)
		(fp_line
			(start 38.800278 25.30983)
			(end 38.800278 27.309826)
			(stroke
				(width 0.1524)
				(type default)
			)
			(layer "F.SilkS")
		)
		(fp_line
			(start -39.500048 25.30983)
			(end -38.800024 25.30983)
			(stroke
				(width 0.1524)
				(type default)
			)
			(layer "F.SilkS")
		)
		(fp_line
			(start -39.500048 25.30983)
			(end -40.300148 25.30983)
			(stroke
				(width 0.1524)
				(type default)
			)
			(layer "F.SilkS")
		)
		(fp_line
			(start -40.046656 25.30983)
			(end -40.999918 25.30983)
			(stroke
				(width 0.1524)
				(type default)
			)
			(layer "F.SilkS")
		)
		(fp_line
			(start -40.999918 25.30983)
			(end -40.300148 25.30983)
			(stroke
				(width 0.1524)
				(type default)
			)
			(layer "F.SilkS")
		)
		(fp_line
			(start 40.999918 25.310084)
			(end 38.800024 25.310084)
			(stroke
				(width 0.1524)
				(type default)
			)
			(layer "F.SilkS")
		)
		(fp_line
			(start 38.800024 25.310084)
			(end 38.800024 27.31008)
			(stroke
				(width 0.1524)
				(type default)
			)
			(layer "F.SilkS")
		)
		(fp_line
			(start -39.500048 25.310084)
			(end -38.800024 25.310084)
			(stroke
				(width 0.1524)
				(type default)
			)
			(layer "F.SilkS")
		)
		(fp_line
			(start -39.500048 25.310084)
			(end -40.300148 25.310084)
			(stroke
				(width 0.1524)
				(type default)
			)
			(layer "F.SilkS")
		)
		(fp_line
			(start -40.046656 25.310084)
			(end -41.000172 25.310084)
			(stroke
				(width 0.1524)
				(type default)
			)
			(layer "F.SilkS")
		)
		(fp_line
			(start -41.000172 25.310084)
			(end -40.300148 25.310084)
			(stroke
				(width 0.1524)
				(type default)
			)
			(layer "F.SilkS")
		)
		(fp_line
			(start 38.800278 27.309826)
			(end 39.509954 27.309826)
			(stroke
				(width 0.1524)
				(type default)
			)
			(layer "F.SilkS")
		)
		(fp_line
			(start -38.800024 27.309826)
			(end -38.800024 25.30983)
			(stroke
				(width 0.1524)
				(type default)
			)
			(layer "F.SilkS")
		)
		(fp_line
			(start -39.510208 27.309826)
			(end -38.800024 27.309826)
			(stroke
				(width 0.1524)
				(type default)
			)
			(layer "F.SilkS")
		)
		(fp_line
			(start 38.800024 27.31008)
			(end 39.509954 27.31008)
			(stroke
				(width 0.1524)
				(type default)
			)
			(layer "F.SilkS")
		)
		(fp_line
			(start -38.800024 27.31008)
			(end -38.800024 25.310084)
			(stroke
				(width 0.1524)
				(type default)
			)
			(layer "F.SilkS")
		)
		(fp_line
			(start -39.510208 27.31008)
			(end -38.800024 27.31008)
			(stroke
				(width 0.1524)
				(type default)
			)
			(layer "F.SilkS")
		)
		(fp_line
			(start 1.299972 27.44978)
			(end 2.999994 29.499814)
			(stroke
				(width 0.1524)
				(type default)
			)
			(layer "F.SilkS")
		)
		(fp_line
			(start 1.299972 27.44978)
			(end 2.999994 29.500068)
			(stroke
				(width 0.1524)
				(type default)
			)
			(layer "F.SilkS")
		)
		(fp_line
			(start -1.299718 27.44978)
			(end 1.299972 27.44978)
			(stroke
				(width 0.1524)
				(type default)
			)
			(layer "F.SilkS")
		)
		(fp_line
			(start -1.299972 27.44978)
			(end 1.299972 27.44978)
			(stroke
				(width 0.1524)
				(type default)
			)
			(layer "F.SilkS")
		)
		(fp_line
			(start 39.509954 28.259786)
			(end 39.509954 27.309826)
			(stroke
				(width 0.1524)
				(type default)
			)
			(layer "F.SilkS")
		)
		(fp_line
			(start 39.509954 28.259786)
			(end 39.509954 27.31008)
			(stroke
				(width 0.1524)
				(type default)
			)
			(layer "F.SilkS")
		)
		(fp_line
			(start -39.510208 28.259786)
			(end -39.510208 27.309826)
			(stroke
				(width 0.1524)
				(type default)
			)
			(layer "F.SilkS")
		)
		(fp_line
			(start -39.510208 28.259786)
			(end -39.510208 27.31008)
			(stroke
				(width 0.1524)
				(type default)
			)
			(layer "F.SilkS")
		)
		(fp_line
			(start 38.800024 28.299918)
			(end 38.800024 -28.299918)
			(stroke
				(width 0.1524)
				(type default)
			)
			(layer "F.SilkS")
		)
		(fp_line
			(start 37.810186 28.299918)
			(end 35.81019 28.299918)
			(stroke
				(width 0.1524)
				(type default)
			)
			(layer "F.SilkS")
		)
		(fp_line
			(start 35.81019 28.299918)
			(end 35.81019 29.499814)
			(stroke
				(width 0.1524)
				(type default)
			)
			(layer "F.SilkS")
		)
		(fp_line
			(start -35.809936 28.299918)
			(end -37.809932 28.299918)
			(stroke
				(width 0.1524)
				(type default)
			)
			(layer "F.SilkS")
		)
		(fp_line
			(start -37.809932 28.299918)
			(end -37.809932 29.009848)
			(stroke
				(width 0.1524)
				(type default)
			)
			(layer "F.SilkS")
		)
		(fp_line
			(start -38.800024 28.299918)
			(end 38.800024 28.299918)
			(stroke
				(width 0.1524)
				(type default)
			)
			(layer "F.SilkS")
		)
		(fp_line
			(start 37.809932 28.300172)
			(end 35.809936 28.300172)
			(stroke
				(width 0.1524)
				(type default)
			)
			(layer "F.SilkS")
		)
		(fp_line
			(start 35.809936 28.300172)
			(end 35.809936 29.500068)
			(stroke
				(width 0.1524)
				(type default)
			)
			(layer "F.SilkS")
		)
		(fp_line
			(start -35.81019 28.300172)
			(end -37.810186 28.300172)
			(stroke
				(width 0.1524)
				(type default)
			)
			(layer "F.SilkS")
		)
		(fp_line
			(start -37.810186 28.300172)
			(end -37.810186 29.010102)
			(stroke
				(width 0.1524)
				(type default)
			)
			(layer "F.SilkS")
		)
		(fp_line
			(start 31.809944 28.449778)
			(end 31.809944 30.499812)
			(stroke
				(width 0.1524)
				(type default)
			)
			(layer "F.SilkS")
		)
		(fp_line
			(start 31.809944 28.450032)
			(end 31.809944 30.500066)
			(stroke
				(width 0.1524)
				(type default)
			)
			(layer "F.SilkS")
		)
		(fp_line
			(start -32.999934 28.999942)
			(end -32.999934 29.499814)
			(stroke
				(width 0.1524)
				(type default)
			)
			(layer "F.SilkS")
		)
		(fp_line
			(start -33.199832 28.999942)
			(end -32.999934 28.999942)
			(stroke
				(width 0.1524)
				(type default)
			)
			(layer "F.SilkS")
		)
		(fp_line
			(start -35.809936 28.999942)
			(end -35.809936 28.299918)
			(stroke
				(width 0.1524)
				(type default)
			)
			(layer "F.SilkS")
		)
		(fp_line
			(start -35.809936 28.999942)
			(end -33.199832 28.999942)
			(stroke
				(width 0.1524)
				(type default)
			)
			(layer "F.SilkS")
		)
		(fp_line
			(start -37.809932 28.999942)
			(end -37.809932 29.009848)
			(stroke
				(width 0.1524)
				(type default)
			)
			(layer "F.SilkS")
		)
		(fp_line
			(start -33.000188 29.000196)
			(end -33.000188 29.500068)
			(stroke
				(width 0.1524)
				(type default)
			)
			(layer "F.SilkS")
		)
		(fp_line
			(start -33.200086 29.000196)
			(end -33.000188 29.000196)
			(stroke
				(width 0.1524)
				(type default)
			)
			(layer "F.SilkS")
		)
		(fp_line
			(start -35.81019 29.000196)
			(end -35.81019 28.300172)
			(stroke
				(width 0.1524)
				(type default)
			)
			(layer "F.SilkS")
		)
		(fp_line
			(start -35.81019 29.000196)
			(end -33.200086 29.000196)
			(stroke
				(width 0.1524)
				(type default)
			)
			(layer "F.SilkS")
		)
		(fp_line
			(start -37.810186 29.000196)
			(end -37.810186 29.010102)
			(stroke
				(width 0.1524)
				(type default)
			)
			(layer "F.SilkS")
		)
		(fp_line
			(start 38.759892 29.009848)
			(end 37.810186 29.009848)
			(stroke
				(width 0.1524)
				(type default)
			)
			(layer "F.SilkS")
		)
		(fp_line
			(start 37.810186 29.009848)
			(end 37.810186 28.299918)
			(stroke
				(width 0.1524)
				(type default)
			)
			(layer "F.SilkS")
		)
		(fp_line
			(start -37.809932 29.009848)
			(end -38.760146 29.009848)
			(stroke
				(width 0.1524)
				(type default)
			)
			(layer "F.SilkS")
		)
		(fp_line
			(start 38.759892 29.010102)
			(end 37.809932 29.010102)
			(stroke
				(width 0.1524)
				(type default)
			)
			(layer "F.SilkS")
		)
		(fp_line
			(start 37.809932 29.010102)
			(end 37.809932 28.300172)
			(stroke
				(width 0.1524)
				(type default)
			)
			(layer "F.SilkS")
		)
		(fp_line
			(start -37.810186 29.010102)
			(end -38.760146 29.010102)
			(stroke
				(width 0.1524)
				(type default)
			)
			(layer "F.SilkS")
		)
		(fp_line
			(start 35.81019 29.499814)
			(end 35.81019 30.499812)
			(stroke
				(width 0.1524)
				(type default)
			)
			(layer "F.SilkS")
		)
		(fp_line
			(start 31.809944 29.499814)
			(end 35.81019 29.499814)
			(stroke
				(width 0.1524)
				(type default)
			)
			(layer "F.SilkS")
		)
		(fp_line
			(start 30.209998 29.499814)
			(end 30.209998 28.449778)
			(stroke
				(width 0.1524)
				(type default)
			)
			(layer "F.SilkS")
		)
		(fp_line
			(start 30.209998 29.499814)
			(end 30.209998 30.499812)
			(stroke
				(width 0.1524)
				(type default)
			)
			(layer "F.SilkS")
		)
		(fp_line
			(start 2.999994 29.499814)
			(end 30.209998 29.499814)
			(stroke
				(width 0.1524)
				(type default)
			)
			(layer "F.SilkS")
		)
		(fp_line
			(start -2.99974 29.499814)
			(end -1.299718 27.44978)
			(stroke
				(width 0.1524)
				(type default)
			)
			(layer "F.SilkS")
		)
		(fp_line
			(start -32.999934 29.499814)
			(end -2.99974 29.499814)
			(stroke
				(width 0.1524)
				(type default)
			)
			(layer "F.SilkS")
		)
		(fp_line
			(start 35.809936 29.500068)
			(end 35.809936 30.500066)
			(stroke
				(width 0.1524)
				(type default)
			)
			(layer "F.SilkS")
		)
		(fp_line
			(start 31.809944 29.500068)
			(end 35.809936 29.500068)
			(stroke
				(width 0.1524)
				(type default)
			)
			(layer "F.SilkS")
		)
		(fp_line
			(start 30.209998 29.500068)
			(end 30.209998 28.450032)
			(stroke
				(width 0.1524)
				(type default)
			)
			(layer "F.SilkS")
		)
		(fp_line
			(start 30.209998 29.500068)
			(end 30.209998 30.500066)
			(stroke
				(width 0.1524)
				(type default)
			)
			(layer "F.SilkS")
		)
		(fp_line
			(start 2.999994 29.500068)
			(end 30.209998 29.500068)
			(stroke
				(width 0.1524)
				(type default)
			)
			(layer "F.SilkS")
		)
		(fp_line
			(start -2.999994 29.500068)
			(end -1.299972 27.44978)
			(stroke
				(width 0.1524)
				(type default)
			)
			(layer "F.SilkS")
		)
		(fp_line
			(start -33.000188 29.500068)
			(end -2.999994 29.500068)
			(stroke
				(width 0.1524)
				(type default)
			)
			(layer "F.SilkS")
		)
		(fp_line
			(start 41.000172 30.499812)
			(end 41.000172 12.499848)
			(stroke
				(width 0.1524)
				(type default)
			)
			(layer "F.SilkS")
		)
		(fp_line
			(start 41.000172 30.499812)
			(end 40.000174 30.499812)
			(stroke
				(width 0.1524)
				(type default)
			)
			(layer "F.SilkS")
		)
		(fp_line
			(start 37.00018 30.499812)
			(end 35.81019 30.499812)
			(stroke
				(width 0.1524)
				(type default)
			)
			(layer "F.SilkS")
		)
		(fp_line
			(start 31.809944 30.499812)
			(end 31.809944 29.499814)
			(stroke
				(width 0.1524)
				(type default)
			)
			(layer "F.SilkS")
		)
		(fp_line
			(start 30.209998 30.499812)
			(end 31.809944 30.499812)
			(stroke
				(width 0.1524)
				(type default)
			)
			(layer "F.SilkS")
		)
		(fp_line
			(start -35.500056 30.499812)
			(end -35.809936 30.499812)
			(stroke
				(width 0.1524)
				(type default)
			)
			(layer "F.SilkS")
		)
		(fp_line
			(start -40.999918 30.499812)
			(end -35.809936 30.499812)
			(stroke
				(width 0.1524)
				(type default)
			)
			(layer "F.SilkS")
		)
		(fp_line
			(start 40.999918 30.500066)
			(end 40.999918 12.500102)
			(stroke
				(width 0.1524)
				(type default)
			)
			(layer "F.SilkS")
		)
		(fp_line
			(start 40.999918 30.500066)
			(end 39.99992 30.500066)
			(stroke
				(width 0.1524)
				(type default)
			)
			(layer "F.SilkS")
		)
		(fp_line
			(start 40.999918 30.500066)
			(end 39.997888 30.500066)
			(stroke
				(width 0.1524)
				(type default)
			)
			(layer "F.SilkS")
		)
		(fp_line
			(start 37.00145 30.500066)
			(end -32.999934 30.500066)
			(stroke
				(width 0.1524)
				(type default)
			)
			(layer "F.SilkS")
		)
		(fp_line
			(start 36.999926 30.500066)
			(end 35.809936 30.500066)
			(stroke
				(width 0.1524)
				(type default)
			)
			(layer "F.SilkS")
		)
		(fp_line
			(start 31.809944 30.500066)
			(end 31.809944 29.500068)
			(stroke
				(width 0.1524)
				(type default)
			)
			(layer "F.SilkS")
		)
		(fp_line
			(start 30.209998 30.500066)
			(end 31.809944 30.500066)
			(stroke
				(width 0.1524)
				(type default)
			)
			(layer "F.SilkS")
		)
		(fp_line
			(start -32.999934 30.500066)
			(end -33.000188 29.500068)
			(stroke
				(width 0.1524)
				(type default)
			)
			(layer "F.SilkS")
		)
		(fp_line
			(start -35.485832 30.500066)
			(end -40.999918 30.500066)
			(stroke
				(width 0.1524)
				(type default)
			)
			(layer "F.SilkS")
		)
		(fp_line
			(start -35.500056 30.500066)
			(end -35.81019 30.500066)
			(stroke
				(width 0.1524)
				(type default)
			)
			(layer "F.SilkS")
		)
		(fp_line
			(start -40.999918 30.500066)
			(end -40.999918 -29.000196)
			(stroke
				(width 0.1524)
				(type default)
			)
			(layer "F.SilkS")
		)
		(fp_line
			(start -41.000172 30.500066)
			(end -35.81019 30.500066)
			(stroke
				(width 0.1524)
				(type default)
			)
			(layer "F.SilkS")
		)
		(fp_line
			(start 39.499794 30.995112)
			(end 39.499794 32.250126)
			(stroke
				(width 0.1524)
				(type default)
			)
			(layer "F.SilkS")
		)
		(fp_line
			(start 39.499794 30.999938)
			(end 39.499794 32.249872)
			(stroke
				(width 0.1524)
				(type default)
			)
			(layer "F.SilkS")
		)
		(fp_line
			(start 39.499794 31.000192)
			(end 39.499794 32.249872)
			(stroke
				(width 0.1524)
				(type default)
			)
			(layer "F.SilkS")
		)
		(fp_line
			(start 39.499794 32.249872)
			(end 39.299896 32.249872)
			(stroke
				(width 0.1524)
				(type default)
			)
			(layer "F.SilkS")
		)
		(fp_line
			(start 39.499794 32.249872)
			(end 39.299896 32.249872)
			(stroke
				(width 0.1524)
				(type default)
			)
			(layer "F.SilkS")
		)
		(fp_line
			(start 39.299896 32.249872)
			(end 37.69995 32.249872)
			(stroke
				(width 0.1524)
				(type default)
			)
			(layer "F.SilkS")
		)
		(fp_line
			(start 39.299896 32.249872)
			(end 37.69995 32.249872)
			(stroke
				(width 0.1524)
				(type default)
			)
			(layer "F.SilkS")
		)
		(fp_line
			(start 37.69995 32.249872)
			(end 37.499798 32.249872)
			(stroke
				(width 0.1524)
				(type default)
			)
			(layer "F.SilkS")
		)
		(fp_line
			(start 37.69995 32.249872)
			(end 37.499798 32.249872)
			(stroke
				(width 0.1524)
				(type default)
			)
			(layer "F.SilkS")
		)
		(fp_line
			(start 37.499798 32.249872)
			(end 37.499798 30.999938)
			(stroke
				(width 0.1524)
				(type default)
			)
			(layer "F.SilkS")
		)
		(fp_line
			(start 37.499798 32.249872)
			(end 37.499798 31.000192)
			(stroke
				(width 0.1524)
				(type default)
			)
			(layer "F.SilkS")
		)
		(fp_line
			(start -30.80004 32.249872)
			(end -30.80004 30.500066)
			(stroke
				(width 0.1524)
				(type default)
			)
			(layer "F.SilkS")
		)
		(fp_line
			(start -30.80004 32.249872)
			(end -33.199832 32.249872)
			(stroke
				(width 0.1524)
				(type default)
			)
			(layer "F.SilkS")
		)
		(fp_line
			(start -32.999934 32.249872)
			(end -35.000184 32.249872)
			(stroke
				(width 0.1524)
				(type default)
			)
			(layer "F.SilkS")
		)
		(fp_line
			(start -33.000188 32.249872)
			(end -33.200086 32.249872)
			(stroke
				(width 0.1524)
				(type default)
			)
			(layer "F.SilkS")
		)
		(fp_line
			(start -33.199832 32.249872)
			(end -34.800032 32.249872)
			(stroke
				(width 0.1524)
				(type default)
			)
			(layer "F.SilkS")
		)
		(fp_line
			(start -33.200086 32.249872)
			(end -34.800032 32.249872)
			(stroke
				(width 0.1524)
				(type default)
			)
			(layer "F.SilkS")
		)
		(fp_line
			(start -34.800032 32.249872)
			(end -34.99993 32.249872)
			(stroke
				(width 0.1524)
				(type default)
			)
			(layer "F.SilkS")
		)
		(fp_line
			(start -34.800032 32.249872)
			(end -35.000184 32.249872)
			(stroke
				(width 0.1524)
				(type default)
			)
			(layer "F.SilkS")
		)
		(fp_line
			(start -34.99993 32.249872)
			(end -34.99993 30.999938)
			(stroke
				(width 0.1524)
				(type default)
			)
			(layer "F.SilkS")
		)
		(fp_line
			(start -35.000184 32.249872)
			(end -35.000184 30.994858)
			(stroke
				(width 0.1524)
				(type default)
			)
			(layer "F.SilkS")
		)
		(fp_line
			(start -35.000184 32.249872)
			(end -35.000184 31.000192)
			(stroke
				(width 0.1524)
				(type default)
			)
			(layer "F.SilkS")
		)
		(fp_line
			(start 39.499794 32.250126)
			(end 37.499798 32.250126)
			(stroke
				(width 0.1524)
				(type default)
			)
			(layer "F.SilkS")
		)
		(fp_line
			(start 37.499798 32.250126)
			(end 37.499798 30.995874)
			(stroke
				(width 0.1524)
				(type default)
			)
			(layer "F.SilkS")
		)
		(fp_arc
			(start 37.499798 -31.000192)
			(mid 37.354092 -30.647219)
			(end 37.001704 -30.500066)
			(stroke
				(width 0.1524)
				(type default)
			)
			(layer "F.SilkS")
		)
		(fp_arc
			(start 37.499798 -31.000192)
			(mid 37.353554 -30.64668)
			(end 37.00018 -30.500066)
			(stroke
				(width 0.1524)
				(type default)
			)
			(layer "F.SilkS")
		)
		(fp_arc
			(start -34.99993 -31.000192)
			(mid -35.146408 -30.646533)
			(end -35.500056 -30.500066)
			(stroke
				(width 0.1524)
				(type default)
			)
			(layer "F.SilkS")
		)
		(fp_arc
			(start -35.000184 -31.000192)
			(mid -35.14478 -30.64823)
			(end -35.49523 -30.500066)
			(stroke
				(width 0.1524)
				(type default)
			)
			(layer "F.SilkS")
		)
		(fp_arc
			(start 37.499798 -30.999938)
			(mid 37.353387 -30.646429)
			(end 36.999926 -30.499812)
			(stroke
				(width 0.1524)
				(type default)
			)
			(layer "F.SilkS")
		)
		(fp_arc
			(start -35.000184 -30.999938)
			(mid -35.146594 -30.646423)
			(end -35.500056 -30.499812)
			(stroke
				(width 0.1524)
				(type default)
			)
			(layer "F.SilkS")
		)
		(fp_arc
			(start 40.000174 -30.500066)
			(mid 39.646372 -30.64646)
			(end 39.499794 -31.000192)
			(stroke
				(width 0.1524)
				(type default)
			)
			(layer "F.SilkS")
		)
		(fp_arc
			(start 39.998396 -30.500066)
			(mid 39.647269 -30.645562)
			(end 39.499794 -30.995874)
			(stroke
				(width 0.1524)
				(type default)
			)
			(layer "F.SilkS")
		)
		(fp_arc
			(start 39.99992 -30.499812)
			(mid 39.646263 -30.646293)
			(end 39.499794 -30.999938)
			(stroke
				(width 0.1524)
				(type default)
			)
			(layer "F.SilkS")
		)
		(fp_arc
			(start 38.759892 -29.009848)
			(mid 39.29022 -28.790313)
			(end 39.509954 -28.26004)
			(stroke
				(width 0.1524)
				(type default)
			)
			(layer "F.SilkS")
		)
		(fp_arc
			(start 38.759892 -29.009848)
			(mid 39.290286 -28.79017)
			(end 39.509954 -28.259786)
			(stroke
				(width 0.1524)
				(type default)
			)
			(layer "F.SilkS")
		)
		(fp_arc
			(start 31.809944 -28.450032)
			(mid 31.01002 -27.649956)
			(end 30.209998 -28.450032)
			(stroke
				(width 0.1524)
				(type default)
			)
			(layer "F.SilkS")
		)
		(fp_arc
			(start 31.809944 -28.450032)
			(mid 31.01002 -27.649956)
			(end 30.209998 -28.450032)
			(stroke
				(width 0.1524)
				(type default)
			)
			(layer "F.SilkS")
		)
		(fp_arc
			(start -39.510208 -28.26004)
			(mid -39.290426 -28.790234)
			(end -38.760146 -29.009848)
			(stroke
				(width 0.1524)
				(type default)
			)
			(layer "F.SilkS")
		)
		(fp_arc
			(start -39.510208 -28.259786)
			(mid -39.290516 -28.790144)
			(end -38.760146 -29.009848)
			(stroke
				(width 0.1524)
				(type default)
			)
			(layer "F.SilkS")
		)
		(fp_arc
			(start 39.509954 28.259786)
			(mid 39.290335 28.790231)
			(end 38.759892 29.009848)
			(stroke
				(width 0.1524)
				(type default)
			)
			(layer "F.SilkS")
		)
		(fp_arc
			(start 39.509954 28.259786)
			(mid 39.290347 28.790301)
			(end 38.759892 29.010102)
			(stroke
				(width 0.1524)
				(type default)
			)
			(layer "F.SilkS")
		)
		(fp_arc
			(start 30.209998 28.449778)
			(mid 31.01002 27.649898)
			(end 31.809944 28.449778)
			(stroke
				(width 0.1524)
				(type default)
			)
			(layer "F.SilkS")
		)
		(fp_arc
			(start 30.209998 28.450032)
			(mid 31.01002 27.650098)
			(end 31.809944 28.450032)
			(stroke
				(width 0.1524)
				(type default)
			)
			(layer "F.SilkS")
		)
		(fp_arc
			(start -38.760146 29.009848)
			(mid -39.29053 28.79017)
			(end -39.510208 28.259786)
			(stroke
				(width 0.1524)
				(type default)
			)
			(layer "F.SilkS")
		)
		(fp_arc
			(start -38.760146 29.010102)
			(mid -39.290639 28.790337)
			(end -39.510208 28.259786)
			(stroke
				(width 0.1524)
				(type default)
			)
			(layer "F.SilkS")
		)
		(fp_arc
			(start 37.00018 30.499812)
			(mid 37.353577 30.646401)
			(end 37.499798 30.999938)
			(stroke
				(width 0.1524)
				(type default)
			)
			(layer "F.SilkS")
		)
		(fp_arc
			(start -35.500056 30.499812)
			(mid -35.146435 30.646305)
			(end -34.99993 30.999938)
			(stroke
				(width 0.1524)
				(type default)
			)
			(layer "F.SilkS")
		)
		(fp_arc
			(start 37.00145 30.500066)
			(mid 37.352458 30.645632)
			(end 37.499798 30.995874)
			(stroke
				(width 0.1524)
				(type default)
			)
			(layer "F.SilkS")
		)
		(fp_arc
			(start 36.999926 30.500066)
			(mid 37.353468 30.646568)
			(end 37.499798 31.000192)
			(stroke
				(width 0.1524)
				(type default)
			)
			(layer "F.SilkS")
		)
		(fp_arc
			(start -35.485832 30.500066)
			(mid -35.143179 30.649486)
			(end -35.000184 30.994858)
			(stroke
				(width 0.1524)
				(type default)
			)
			(layer "F.SilkS")
		)
		(fp_arc
			(start -35.500056 30.500066)
			(mid -35.146525 30.646575)
			(end -35.000184 31.000192)
			(stroke
				(width 0.1524)
				(type default)
			)
			(layer "F.SilkS")
		)
		(fp_arc
			(start 39.499794 30.995112)
			(mid 39.647205 30.64533)
			(end 39.997888 30.500066)
			(stroke
				(width 0.1524)
				(type default)
			)
			(layer "F.SilkS")
		)
		(fp_arc
			(start 39.499794 30.999938)
			(mid 39.646361 30.646194)
			(end 40.000174 30.499812)
			(stroke
				(width 0.1524)
				(type default)
			)
			(layer "F.SilkS")
		)
		(fp_arc
			(start 39.499794 31.000192)
			(mid 39.646287 30.646568)
			(end 39.99992 30.500066)
			(stroke
				(width 0.1524)
				(type default)
			)
			(layer "F.SilkS")
		)
		(fp_line
			(start 39.499794 -32.250126)
			(end 39.499794 -31.000192)
			(stroke
				(width 0.1)
				(type default)
			)
			(layer "F.Fab")
		)
		(fp_line
			(start 39.499794 -32.250126)
			(end 39.499794 -30.995874)
			(stroke
				(width 0.1)
				(type default)
			)
			(layer "F.Fab")
		)
		(fp_line
			(start 39.299896 -32.250126)
			(end 39.499794 -32.250126)
			(stroke
				(width 0.1)
				(type default)
			)
			(layer "F.Fab")
		)
		(fp_line
			(start 37.69995 -32.250126)
			(end 39.299896 -32.250126)
			(stroke
				(width 0.1)
				(type default)
			)
			(layer "F.Fab")
		)
		(fp_line
			(start 37.499798 -32.250126)
			(end 39.499794 -32.250126)
			(stroke
				(width 0.1)
				(type default)
			)
			(layer "F.Fab")
		)
		(fp_line
			(start 37.499798 -32.250126)
			(end 37.69995 -32.250126)
			(stroke
				(width 0.1)
				(type default)
			)
			(layer "F.Fab")
		)
		(fp_line
			(start -30.80004 -32.250126)
			(end -35.000184 -32.249872)
			(stroke
				(width 0.1)
				(type default)
			)
			(layer "F.Fab")
		)
		(fp_line
			(start -30.80004 -32.250126)
			(end -30.80004 -30.500066)
			(stroke
				(width 0.1)
				(type default)
			)
			(layer "F.Fab")
		)
		(fp_line
			(start -32.999934 -32.250126)
			(end -34.99993 -32.250126)
			(stroke
				(width 0.1)
				(type default)
			)
			(layer "F.Fab")
		)
		(fp_line
			(start -34.99993 -32.250126)
			(end -34.99993 -31.000192)
			(stroke
				(width 0.1)
				(type default)
			)
			(layer "F.Fab")
		)
		(fp_line
			(start -35.000184 -32.250126)
			(end -32.999934 -32.250126)
			(stroke
				(width 0.1)
				(type default)
			)
			(layer "F.Fab")
		)
		(fp_line
			(start 39.499794 -32.249872)
			(end 39.499794 -30.999938)
			(stroke
				(width 0.1)
				(type default)
			)
			(layer "F.Fab")
		)
		(fp_line
			(start 39.299896 -32.249872)
			(end 39.499794 -32.249872)
			(stroke
				(width 0.1)
				(type default)
			)
			(layer "F.Fab")
		)
		(fp_line
			(start 37.69995 -32.249872)
			(end 39.299896 -32.249872)
			(stroke
				(width 0.1)
				(type default)
			)
			(layer "F.Fab")
		)
		(fp_line
			(start 37.499798 -32.249872)
			(end 37.69995 -32.249872)
			(stroke
				(width 0.1)
				(type default)
			)
			(layer "F.Fab")
		)
		(fp_line
			(start -35.000184 -32.249872)
			(end -35.000184 -30.999938)
			(stroke
				(width 0.1)
				(type default)
			)
			(layer "F.Fab")
		)
		(fp_line
			(start 37.499798 -31.000192)
			(end 37.499798 -32.250126)
			(stroke
				(width 0.1)
				(type default)
			)
			(layer "F.Fab")
		)
		(fp_line
			(start 37.499798 -31.000192)
			(end 37.499798 -32.250126)
			(stroke
				(width 0.1)
				(type default)
			)
			(layer "F.Fab")
		)
		(fp_line
			(start -35.000184 -31.000192)
			(end -35.000184 -32.250126)
			(stroke
				(width 0.1)
				(type default)
			)
			(layer "F.Fab")
		)
		(fp_line
			(start 37.499798 -30.999938)
			(end 37.499798 -32.249872)
			(stroke
				(width 0.1)
				(type default)
			)
			(layer "F.Fab")
		)
		(fp_line
			(start 41.000172 -30.500066)
			(end 40.000174 -30.500066)
			(stroke
				(width 0.1)
				(type default)
			)
			(layer "F.Fab")
		)
		(fp_line
			(start 40.999918 -30.500066)
			(end 40.999918 30.500066)
			(stroke
				(width 0.1)
				(type default)
			)
			(layer "F.Fab")
		)
		(fp_line
			(start 39.998396 -30.500066)
			(end 40.999918 -30.500066)
			(stroke
				(width 0.1)
				(type default)
			)
			(layer "F.Fab")
		)
		(fp_line
			(start 37.00018 -30.500066)
			(end 35.81019 -30.500066)
			(stroke
				(width 0.1)
				(type default)
			)
			(layer "F.Fab")
		)
		(fp_line
			(start 35.81019 -30.500066)
			(end 35.81019 -29.500068)
			(stroke
				(width 0.1)
				(type default)
			)
			(layer "F.Fab")
		)
		(fp_line
			(start 31.809944 -30.500066)
			(end 30.209998 -30.500066)
			(stroke
				(width 0.1)
				(type default)
			)
			(layer "F.Fab")
		)
		(fp_line
			(start 30.209998 -30.500066)
			(end 30.209998 -29.500068)
			(stroke
				(width 0.1)
				(type default)
			)
			(layer "F.Fab")
		)
		(fp_line
			(start -32.999934 -30.500066)
			(end 37.001704 -30.500066)
			(stroke
				(width 0.1)
				(type default)
			)
			(layer "F.Fab")
		)
		(fp_line
			(start -35.809936 -30.500066)
			(end -35.500056 -30.500066)
			(stroke
				(width 0.1)
				(type default)
			)
			(layer "F.Fab")
		)
		(fp_line
			(start -39.500048 -30.500066)
			(end -35.49523 -30.500066)
			(stroke
				(width 0.1)
				(type default)
			)
			(layer "F.Fab")
		)
		(fp_line
			(start -39.500048 -30.500066)
			(end -35.809936 -30.500066)
			(stroke
				(width 0.1)
				(type default)
			)
			(layer "F.Fab")
		)
		(fp_line
			(start 40.999918 -30.499812)
			(end 39.99992 -30.499812)
			(stroke
				(width 0.1)
				(type default)
			)
			(layer "F.Fab")
		)
		(fp_line
			(start 36.999926 -30.499812)
			(end 35.809936 -30.499812)
			(stroke
				(width 0.1)
				(type default)
			)
			(layer "F.Fab")
		)
		(fp_line
			(start 35.809936 -30.499812)
			(end 35.809936 -29.499814)
			(stroke
				(width 0.1)
				(type default)
			)
			(layer "F.Fab")
		)
		(fp_line
			(start 31.809944 -30.499812)
			(end 30.209998 -30.499812)
			(stroke
				(width 0.1)
				(type default)
			)
			(layer "F.Fab")
		)
		(fp_line
			(start 30.209998 -30.499812)
			(end 30.209998 -29.499814)
			(stroke
				(width 0.1)
				(type default)
			)
			(layer "F.Fab")
		)
		(fp_line
			(start -35.81019 -30.499812)
			(end -35.500056 -30.499812)
			(stroke
				(width 0.1)
				(type default)
			)
			(layer "F.Fab")
		)
		(fp_line
			(start -39.500048 -30.499812)
			(end -35.81019 -30.499812)
			(stroke
				(width 0.1)
				(type default)
			)
			(layer "F.Fab")
		)
		(fp_line
			(start 35.81019 -29.800042)
			(end 35.81019 -28.999942)
			(stroke
				(width 0.1)
				(type default)
			)
			(layer "F.Fab")
		)
		(fp_line
			(start 35.809936 -29.799788)
			(end 35.809936 -28.999942)
			(stroke
				(width 0.1)
				(type default)
			)
			(layer "F.Fab")
		)
		(fp_line
			(start 35.81019 -29.500068)
			(end 31.809944 -29.500068)
			(stroke
				(width 0.1)
				(type default)
			)
			(layer "F.Fab")
		)
		(fp_line
			(start 31.809944 -29.500068)
			(end 31.809944 -30.500066)
			(stroke
				(width 0.1)
				(type default)
			)
			(layer "F.Fab")
		)
		(fp_line
			(start 31.809944 -29.500068)
			(end 31.809944 -28.450032)
			(stroke
				(width 0.1)
				(type default)
			)
			(layer "F.Fab")
		)
		(fp_line
			(start 30.209998 -29.500068)
			(end 2.999994 -29.500068)
			(stroke
				(width 0.1)
				(type default)
			)
			(layer "F.Fab")
		)
		(fp_line
			(start 2.999994 -29.500068)
			(end 1.299972 -27.450034)
			(stroke
				(width 0.1)
				(type default)
			)
			(layer "F.Fab")
		)
		(fp_line
			(start -2.99974 -29.500068)
			(end -32.999934 -29.500068)
			(stroke
				(width 0.1)
				(type default)
			)
			(layer "F.Fab")
		)
		(fp_line
			(start -32.999934 -29.500068)
			(end -32.999934 -30.500066)
			(stroke
				(width 0.1)
				(type default)
			)
			(layer "F.Fab")
		)
		(fp_line
			(start -32.999934 -29.500068)
			(end -32.999934 -28.999942)
			(stroke
				(width 0.1)
				(type default)
			)
			(layer "F.Fab")
		)
		(fp_line
			(start 35.809936 -29.499814)
			(end 31.809944 -29.499814)
			(stroke
				(width 0.1)
				(type default)
			)
			(layer "F.Fab")
		)
		(fp_line
			(start 31.809944 -29.499814)
			(end 31.809944 -30.499812)
			(stroke
				(width 0.1)
				(type default)
			)
			(layer "F.Fab")
		)
		(fp_line
			(start 31.809944 -29.499814)
			(end 31.809944 -28.450032)
			(stroke
				(width 0.1)
				(type default)
			)
			(layer "F.Fab")
		)
		(fp_line
			(start 30.209998 -29.499814)
			(end 2.999994 -29.499814)
			(stroke
				(width 0.1)
				(type default)
			)
			(layer "F.Fab")
		)
		(fp_line
			(start 2.999994 -29.499814)
			(end 1.299972 -27.44978)
			(stroke
				(width 0.1)
				(type default)
			)
			(layer "F.Fab")
		)
		(fp_line
			(start -2.999994 -29.499814)
			(end -33.000188 -29.499814)
			(stroke
				(width 0.1)
				(type default)
			)
			(layer "F.Fab")
		)
		(fp_line
			(start -33.000188 -29.499814)
			(end -33.000188 -28.999942)
			(stroke
				(width 0.1)
				(type default)
			)
			(layer "F.Fab")
		)
		(fp_line
			(start 37.810186 -29.009848)
			(end 38.759892 -29.009848)
			(stroke
				(width 0.1)
				(type default)
			)
			(layer "F.Fab")
		)
		(fp_line
			(start 37.809932 -29.009848)
			(end 38.759892 -29.009848)
			(stroke
				(width 0.1)
				(type default)
			)
			(layer "F.Fab")
		)
		(fp_line
			(start -38.760146 -29.009848)
			(end -37.809932 -29.009848)
			(stroke
				(width 0.1)
				(type default)
			)
			(layer "F.Fab")
		)
		(fp_line
			(start -38.760146 -29.009848)
			(end -37.810186 -29.009848)
			(stroke
				(width 0.1)
				(type default)
			)
			(layer "F.Fab")
		)
		(fp_line
			(start -40.999918 -29.000196)
			(end -39.500048 -30.500066)
			(stroke
				(width 0.1)
				(type default)
			)
			(layer "F.Fab")
		)
		(fp_line
			(start 37.810186 -28.999942)
			(end 37.810186 -28.300172)
			(stroke
				(width 0.1)
				(type default)
			)
			(layer "F.Fab")
		)
		(fp_line
			(start 37.809932 -28.999942)
			(end 37.809932 -28.299918)
			(stroke
				(width 0.1)
				(type default)
			)
			(layer "F.Fab")
		)
		(fp_line
			(start -32.999934 -28.999942)
			(end -33.199832 -28.999942)
			(stroke
				(width 0.1)
				(type default)
			)
			(layer "F.Fab")
		)
		(fp_line
			(start -33.000188 -28.999942)
			(end -33.200086 -28.999942)
			(stroke
				(width 0.1)
				(type default)
			)
			(layer "F.Fab")
		)
		(fp_line
			(start -33.199832 -28.999942)
			(end -35.809936 -28.999942)
			(stroke
				(width 0.1)
				(type default)
			)
			(layer "F.Fab")
		)
		(fp_line
			(start -33.200086 -28.999942)
			(end -35.81019 -28.999942)
			(stroke
				(width 0.1)
				(type default)
			)
			(layer "F.Fab")
		)
		(fp_line
			(start -35.809936 -28.999942)
			(end -35.809936 -28.300172)
			(stroke
				(width 0.1)
				(type default)
			)
			(layer "F.Fab")
		)
		(fp_line
			(start -35.81019 -28.999942)
			(end -35.81019 -28.299918)
			(stroke
				(width 0.1)
				(type default)
			)
			(layer "F.Fab")
		)
		(fp_line
			(start -40.999918 -28.999942)
			(end -39.500048 -30.500066)
			(stroke
				(width 0.1)
				(type default)
			)
			(layer "F.Fab")
		)
		(fp_line
			(start -40.999918 -28.999942)
			(end -40.999918 -12.499848)
			(stroke
				(width 0.1)
				(type default)
			)
			(layer "F.Fab")
		)
		(fp_line
			(start -41.000172 -28.999942)
			(end -39.500048 -30.499812)
			(stroke
				(width 0.1)
				(type default)
			)
			(layer "F.Fab")
		)
		(fp_line
			(start -41.000172 -28.999942)
			(end -41.000172 -12.499848)
			(stroke
				(width 0.1)
				(type default)
			)
			(layer "F.Fab")
		)
		(fp_line
			(start 30.209998 -28.450032)
			(end 30.209998 -30.500066)
			(stroke
				(width 0.1)
				(type default)
			)
			(layer "F.Fab")
		)
		(fp_line
			(start 30.209998 -28.450032)
			(end 30.209998 -30.499812)
			(stroke
				(width 0.1)
				(type default)
			)
			(layer "F.Fab")
		)
		(fp_line
			(start 37.810186 -28.300172)
			(end 37.810186 -29.009848)
			(stroke
				(width 0.1)
				(type default)
			)
			(layer "F.Fab")
		)
		(fp_line
			(start 35.81019 -28.300172)
			(end 35.81019 -28.999942)
			(stroke
				(width 0.1)
				(type default)
			)
			(layer "F.Fab")
		)
		(fp_line
			(start 35.81019 -28.300172)
			(end 37.810186 -28.300172)
			(stroke
				(width 0.1)
				(type default)
			)
			(layer "F.Fab")
		)
		(fp_line
			(start -35.809936 -28.300172)
			(end -37.809932 -28.300172)
			(stroke
				(width 0.1)
				(type default)
			)
			(layer "F.Fab")
		)
		(fp_line
			(start -37.809932 -28.300172)
			(end -37.809932 -28.999942)
			(stroke
				(width 0.1)
				(type default)
			)
			(layer "F.Fab")
		)
		(fp_line
			(start 38.800024 -28.299918)
			(end -38.800024 -28.299918)
			(stroke
				(width 0.1)
				(type default)
			)
			(layer "F.Fab")
		)
		(fp_line
			(start 37.809932 -28.299918)
			(end 37.809932 -29.009848)
			(stroke
				(width 0.1)
				(type default)
			)
			(layer "F.Fab")
		)
		(fp_line
			(start 35.809936 -28.299918)
			(end 35.809936 -28.999942)
			(stroke
				(width 0.1)
				(type default)
			)
			(layer "F.Fab")
		)
		(fp_line
			(start 35.809936 -28.299918)
			(end 37.809932 -28.299918)
			(stroke
				(width 0.1)
				(type default)
			)
			(layer "F.Fab")
		)
		(fp_line
			(start -35.81019 -28.299918)
			(end -37.810186 -28.299918)
			(stroke
				(width 0.1)
				(type default)
			)
			(layer "F.Fab")
		)
		(fp_line
			(start -37.810186 -28.299918)
			(end -37.810186 -28.999942)
			(stroke
				(width 0.1)
				(type default)
			)
			(layer "F.Fab")
		)
		(fp_line
			(start -38.800024 -28.299918)
			(end -38.800024 28.299918)
			(stroke
				(width 0.1)
				(type default)
			)
			(layer "F.Fab")
		)
		(fp_line
			(start 39.509954 -28.26004)
			(end 39.509954 -27.31008)
			(stroke
				(width 0.1)
				(type default)
			)
			(layer "F.Fab")
		)
		(fp_line
			(start 39.509954 -28.259786)
			(end 39.509954 -27.309826)
			(stroke
				(width 0.1)
				(type default)
			)
			(layer "F.Fab")
		)
		(fp_line
			(start 1.299972 -27.450034)
			(end -1.299718 -27.450034)
			(stroke
				(width 0.1)
				(type default)
			)
			(layer "F.Fab")
		)
		(fp_line
			(start -1.299718 -27.450034)
			(end -2.99974 -29.500068)
			(stroke
				(width 0.1)
				(type default)
			)
			(layer "F.Fab")
		)
		(fp_line
			(start 1.299972 -27.44978)
			(end -1.299972 -27.44978)
			(stroke
				(width 0.1)
				(type default)
			)
			(layer "F.Fab")
		)
		(fp_line
			(start -1.299972 -27.44978)
			(end -2.999994 -29.499814)
			(stroke
				(width 0.1)
				(type default)
			)
			(layer "F.Fab")
		)
		(fp_line
			(start -38.800024 -27.31008)
			(end -38.800024 -25.310084)
			(stroke
				(width 0.1)
				(type default)
			)
			(layer "F.Fab")
		)
		(fp_line
			(start -39.500048 -27.31008)
			(end -38.800024 -27.31008)
			(stroke
				(width 0.1)
				(type default)
			)
			(layer "F.Fab")
		)
		(fp_line
			(start -39.500048 -27.31008)
			(end -39.510208 -27.31008)
			(stroke
				(width 0.1)
				(type default)
			)
			(layer "F.Fab")
		)
		(fp_line
			(start -39.510208 -27.31008)
			(end -39.510208 -28.26004)
			(stroke
				(width 0.1)
				(type default)
			)
			(layer "F.Fab")
		)
		(fp_line
			(start 39.509954 -27.309826)
			(end 39.499794 -27.309826)
			(stroke
				(width 0.1)
				(type default)
			)
			(layer "F.Fab")
		)
		(fp_line
			(start 38.800024 -27.309826)
			(end 39.499794 -27.309826)
			(stroke
				(width 0.1)
				(type default)
			)
			(layer "F.Fab")
		)
		(fp_line
			(start -38.800024 -27.309826)
			(end -38.800024 -25.30983)
			(stroke
				(width 0.1)
				(type default)
			)
			(layer "F.Fab")
		)
		(fp_line
			(start -39.500048 -27.309826)
			(end -38.800024 -27.309826)
			(stroke
				(width 0.1)
				(type default)
			)
			(layer "F.Fab")
		)
		(fp_line
			(start -39.500048 -27.309826)
			(end -39.510208 -27.309826)
			(stroke
				(width 0.1)
				(type default)
			)
			(layer "F.Fab")
		)
		(fp_line
			(start -39.510208 -27.309826)
			(end -39.510208 -28.259786)
			(stroke
				(width 0.1)
				(type default)
			)
			(layer "F.Fab")
		)
		(fp_line
			(start 40.046402 -25.310084)
			(end 41.000172 -25.310084)
			(stroke
				(width 0.1)
				(type default)
			)
			(layer "F.Fab")
		)
		(fp_line
			(start 38.800278 -25.310084)
			(end 40.046402 -25.310084)
			(stroke
				(width 0.1)
				(type default)
			)
			(layer "F.Fab")
		)
		(fp_line
			(start -40.046656 -25.310084)
			(end -38.800024 -25.310084)
			(stroke
				(width 0.1)
				(type default)
			)
			(layer "F.Fab")
		)
		(fp_line
			(start -40.999918 -25.310084)
			(end -40.046656 -25.310084)
			(stroke
				(width 0.1)
				(type default)
			)
			(layer "F.Fab")
		)
		(fp_line
			(start 40.046402 -25.30983)
			(end 40.999918 -25.30983)
			(stroke
				(width 0.1)
				(type default)
			)
			(layer "F.Fab")
		)
		(fp_line
			(start 38.800024 -25.30983)
			(end 38.800024 -27.309826)
			(stroke
				(width 0.1)
				(type default)
			)
			(layer "F.Fab")
		)
		(fp_line
			(start 38.800024 -25.30983)
			(end 40.046402 -25.30983)
			(stroke
				(width 0.1)
				(type default)
			)
			(layer "F.Fab")
		)
		(fp_line
			(start -40.046656 -25.30983)
			(end -38.800024 -25.30983)
			(stroke
				(width 0.1)
				(type default)
			)
			(layer "F.Fab")
		)
		(fp_line
			(start -41.000172 -25.30983)
			(end -40.046656 -25.30983)
			(stroke
				(width 0.1)
				(type default)
			)
			(layer "F.Fab")
		)
		(fp_line
			(start 41.000172 -12.499848)
			(end 41.000172 -30.500066)
			(stroke
				(width 0.1)
				(type default)
			)
			(layer "F.Fab")
		)
		(fp_line
			(start 40.999918 -12.499848)
			(end 40.999918 -30.499812)
			(stroke
				(width 0.1)
				(type default)
			)
			(layer "F.Fab")
		)
		(fp_line
			(start -40.999918 -12.499848)
			(end -39.99992 -8.000238)
			(stroke
				(width 0.1)
				(type default)
			)
			(layer "F.Fab")
		)
		(fp_line
			(start -41.000172 -12.499848)
			(end -40.000174 -7.999984)
			(stroke
				(width 0.1)
				(type default)
			)
			(layer "F.Fab")
		)
		(fp_line
			(start 10.363454 -8.419846)
			(end -15.24635 -8.419846)
			(stroke
				(width 0.1)
				(type default)
			)
			(layer "F.Fab")
		)
		(fp_line
			(start 10.363454 -8.419846)
			(end 10.363454 -3.797808)
			(stroke
				(width 0.1)
				(type default)
			)
			(layer "F.Fab")
		)
		(fp_line
			(start 40.000174 -8.000238)
			(end 41.000172 -12.499848)
			(stroke
				(width 0.1)
				(type default)
			)
			(layer "F.Fab")
		)
		(fp_line
			(start -39.99992 -8.000238)
			(end -39.99992 -2.62509)
			(stroke
				(width 0.1)
				(type default)
			)
			(layer "F.Fab")
		)
		(fp_line
			(start 39.99992 -7.999984)
			(end 40.999918 -12.499848)
			(stroke
				(width 0.1)
				(type default)
			)
			(layer "F.Fab")
		)
		(fp_line
			(start -40.000174 -7.999984)
			(end -40.000174 -2.624836)
			(stroke
				(width 0.1)
				(type default)
			)
			(layer "F.Fab")
		)
		(fp_line
			(start -15.24635 -3.797808)
			(end -15.24635 -8.419846)
			(stroke
				(width 0.1)
				(type default)
			)
			(layer "F.Fab")
		)
		(fp_line
			(start -15.24635 -3.797808)
			(end 10.363454 -3.797808)
			(stroke
				(width 0.1)
				(type default)
			)
			(layer "F.Fab")
		)
		(fp_line
			(start 40.000174 -2.62509)
			(end 40.000174 -8.000238)
			(stroke
				(width 0.1)
				(type default)
			)
			(layer "F.Fab")
		)
		(fp_line
			(start -39.99992 -2.62509)
			(end -37.999924 -1.550162)
			(stroke
				(width 0.1)
				(type default)
			)
			(layer "F.Fab")
		)
		(fp_line
			(start 39.99992 -2.624836)
			(end 39.99992 -7.999984)
			(stroke
				(width 0.1)
				(type default)
			)
			(layer "F.Fab")
		)
		(fp_line
			(start -40.000174 -2.624836)
			(end -38.000178 -1.549908)
			(stroke
				(width 0.1)
				(type default)
			)
			(layer "F.Fab")
		)
		(fp_line
			(start 38.000178 -1.550162)
			(end 40.000174 -2.62509)
			(stroke
				(width 0.1)
				(type default)
			)
			(layer "F.Fab")
		)
		(fp_line
			(start -37.999924 -1.550162)
			(end -37.999924 1.549908)
			(stroke
				(width 0.1)
				(type default)
			)
			(layer "F.Fab")
		)
		(fp_line
			(start 37.999924 -1.549908)
			(end 39.99992 -2.624836)
			(stroke
				(width 0.1)
				(type default)
			)
			(layer "F.Fab")
		)
		(fp_line
			(start -38.000178 -1.549908)
			(end -38.000178 1.550162)
			(stroke
				(width 0.1)
				(type default)
			)
			(layer "F.Fab")
		)
		(fp_line
			(start 38.000178 1.549908)
			(end 38.000178 -1.550162)
			(stroke
				(width 0.1)
				(type default)
			)
			(layer "F.Fab")
		)
		(fp_line
			(start -37.999924 1.549908)
			(end -39.99992 2.624836)
			(stroke
				(width 0.1)
				(type default)
			)
			(layer "F.Fab")
		)
		(fp_line
			(start 37.999924 1.550162)
			(end 37.999924 -1.549908)
			(stroke
				(width 0.1)
				(type default)
			)
			(layer "F.Fab")
		)
		(fp_line
			(start -38.000178 1.550162)
			(end -40.000174 2.62509)
			(stroke
				(width 0.1)
				(type default)
			)
			(layer "F.Fab")
		)
		(fp_line
			(start 40.000174 2.624836)
			(end 38.000178 1.549908)
			(stroke
				(width 0.1)
				(type default)
			)
			(layer "F.Fab")
		)
		(fp_line
			(start -39.99992 2.624836)
			(end -39.99992 7.99973)
			(stroke
				(width 0.1)
				(type default)
			)
			(layer "F.Fab")
		)
		(fp_line
			(start 39.99992 2.62509)
			(end 37.999924 1.550162)
			(stroke
				(width 0.1)
				(type default)
			)
			(layer "F.Fab")
		)
		(fp_line
			(start -40.000174 2.62509)
			(end -40.000174 7.999984)
			(stroke
				(width 0.1)
				(type default)
			)
			(layer "F.Fab")
		)
		(fp_line
			(start 10.363454 3.797554)
			(end -15.24635 3.797554)
			(stroke
				(width 0.1)
				(type default)
			)
			(layer "F.Fab")
		)
		(fp_line
			(start 10.363454 3.797554)
			(end 10.363454 8.419592)
			(stroke
				(width 0.1)
				(type default)
			)
			(layer "F.Fab")
		)
		(fp_line
			(start 40.000174 7.99973)
			(end 40.000174 2.624836)
			(stroke
				(width 0.1)
				(type default)
			)
			(layer "F.Fab")
		)
		(fp_line
			(start -39.99992 7.99973)
			(end -40.999918 12.499848)
			(stroke
				(width 0.1)
				(type default)
			)
			(layer "F.Fab")
		)
		(fp_line
			(start 39.99992 7.999984)
			(end 39.99992 2.62509)
			(stroke
				(width 0.1)
				(type default)
			)
			(layer "F.Fab")
		)
		(fp_line
			(start -40.000174 7.999984)
			(end -41.000172 12.500102)
			(stroke
				(width 0.1)
				(type default)
			)
			(layer "F.Fab")
		)
		(fp_line
			(start -15.24635 8.419592)
			(end -15.24635 3.797554)
			(stroke
				(width 0.1)
				(type default)
			)
			(layer "F.Fab")
		)
		(fp_line
			(start -15.24635 8.419592)
			(end 10.363454 8.419592)
			(stroke
				(width 0.1)
				(type default)
			)
			(layer "F.Fab")
		)
		(fp_line
			(start 41.000172 12.499848)
			(end 40.000174 7.99973)
			(stroke
				(width 0.1)
				(type default)
			)
			(layer "F.Fab")
		)
		(fp_line
			(start -40.999918 12.499848)
			(end -40.999918 30.499812)
			(stroke
				(width 0.1)
				(type default)
			)
			(layer "F.Fab")
		)
		(fp_line
			(start 40.999918 12.500102)
			(end 39.99992 7.999984)
			(stroke
				(width 0.1)
				(type default)
			)
			(layer "F.Fab")
		)
		(fp_line
			(start -41.000172 12.500102)
			(end -41.000172 30.500066)
			(stroke
				(width 0.1)
				(type default)
			)
			(layer "F.Fab")
		)
		(fp_line
			(start 41.000172 25.30983)
			(end 38.800278 25.30983)
			(stroke
				(width 0.1)
				(type default)
			)
			(layer "F.Fab")
		)
		(fp_line
			(start 38.800278 25.30983)
			(end 38.800278 27.309826)
			(stroke
				(width 0.1)
				(type default)
			)
			(layer "F.Fab")
		)
		(fp_line
			(start -39.500048 25.30983)
			(end -38.800024 25.30983)
			(stroke
				(width 0.1)
				(type default)
			)
			(layer "F.Fab")
		)
		(fp_line
			(start -39.500048 25.30983)
			(end -40.300148 25.30983)
			(stroke
				(width 0.1)
				(type default)
			)
			(layer "F.Fab")
		)
		(fp_line
			(start -40.046656 25.30983)
			(end -40.999918 25.30983)
			(stroke
				(width 0.1)
				(type default)
			)
			(layer "F.Fab")
		)
		(fp_line
			(start -40.999918 25.30983)
			(end -40.300148 25.30983)
			(stroke
				(width 0.1)
				(type default)
			)
			(layer "F.Fab")
		)
		(fp_line
			(start 40.999918 25.310084)
			(end 38.800024 25.310084)
			(stroke
				(width 0.1)
				(type default)
			)
			(layer "F.Fab")
		)
		(fp_line
			(start 38.800024 25.310084)
			(end 38.800024 27.31008)
			(stroke
				(width 0.1)
				(type default)
			)
			(layer "F.Fab")
		)
		(fp_line
			(start -39.500048 25.310084)
			(end -38.800024 25.310084)
			(stroke
				(width 0.1)
				(type default)
			)
			(layer "F.Fab")
		)
		(fp_line
			(start -39.500048 25.310084)
			(end -40.300148 25.310084)
			(stroke
				(width 0.1)
				(type default)
			)
			(layer "F.Fab")
		)
		(fp_line
			(start -40.046656 25.310084)
			(end -41.000172 25.310084)
			(stroke
				(width 0.1)
				(type default)
			)
			(layer "F.Fab")
		)
		(fp_line
			(start -41.000172 25.310084)
			(end -40.300148 25.310084)
			(stroke
				(width 0.1)
				(type default)
			)
			(layer "F.Fab")
		)
		(fp_line
			(start 38.800278 27.309826)
			(end 39.509954 27.309826)
			(stroke
				(width 0.1)
				(type default)
			)
			(layer "F.Fab")
		)
		(fp_line
			(start -38.800024 27.309826)
			(end -38.800024 25.30983)
			(stroke
				(width 0.1)
				(type default)
			)
			(layer "F.Fab")
		)
		(fp_line
			(start -39.510208 27.309826)
			(end -38.800024 27.309826)
			(stroke
				(width 0.1)
				(type default)
			)
			(layer "F.Fab")
		)
		(fp_line
			(start 38.800024 27.31008)
			(end 39.509954 27.31008)
			(stroke
				(width 0.1)
				(type default)
			)
			(layer "F.Fab")
		)
		(fp_line
			(start -38.800024 27.31008)
			(end -38.800024 25.310084)
			(stroke
				(width 0.1)
				(type default)
			)
			(layer "F.Fab")
		)
		(fp_line
			(start -39.510208 27.31008)
			(end -38.800024 27.31008)
			(stroke
				(width 0.1)
				(type default)
			)
			(layer "F.Fab")
		)
		(fp_line
			(start 1.299972 27.44978)
			(end 2.999994 29.499814)
			(stroke
				(width 0.1)
				(type default)
			)
			(layer "F.Fab")
		)
		(fp_line
			(start 1.299972 27.44978)
			(end 2.999994 29.500068)
			(stroke
				(width 0.1)
				(type default)
			)
			(layer "F.Fab")
		)
		(fp_line
			(start -1.299718 27.44978)
			(end 1.299972 27.44978)
			(stroke
				(width 0.1)
				(type default)
			)
			(layer "F.Fab")
		)
		(fp_line
			(start -1.299972 27.44978)
			(end 1.299972 27.44978)
			(stroke
				(width 0.1)
				(type default)
			)
			(layer "F.Fab")
		)
		(fp_line
			(start 39.509954 28.259786)
			(end 39.509954 27.309826)
			(stroke
				(width 0.1)
				(type default)
			)
			(layer "F.Fab")
		)
		(fp_line
			(start 39.509954 28.259786)
			(end 39.509954 27.31008)
			(stroke
				(width 0.1)
				(type default)
			)
			(layer "F.Fab")
		)
		(fp_line
			(start -39.510208 28.259786)
			(end -39.510208 27.309826)
			(stroke
				(width 0.1)
				(type default)
			)
			(layer "F.Fab")
		)
		(fp_line
			(start -39.510208 28.259786)
			(end -39.510208 27.31008)
			(stroke
				(width 0.1)
				(type default)
			)
			(layer "F.Fab")
		)
		(fp_line
			(start 38.800024 28.299918)
			(end 38.800024 -28.299918)
			(stroke
				(width 0.1)
				(type default)
			)
			(layer "F.Fab")
		)
		(fp_line
			(start 37.810186 28.299918)
			(end 35.81019 28.299918)
			(stroke
				(width 0.1)
				(type default)
			)
			(layer "F.Fab")
		)
		(fp_line
			(start 35.81019 28.299918)
			(end 35.81019 29.499814)
			(stroke
				(width 0.1)
				(type default)
			)
			(layer "F.Fab")
		)
		(fp_line
			(start -35.809936 28.299918)
			(end -37.809932 28.299918)
			(stroke
				(width 0.1)
				(type default)
			)
			(layer "F.Fab")
		)
		(fp_line
			(start -37.809932 28.299918)
			(end -37.809932 29.009848)
			(stroke
				(width 0.1)
				(type default)
			)
			(layer "F.Fab")
		)
		(fp_line
			(start -38.800024 28.299918)
			(end 38.800024 28.299918)
			(stroke
				(width 0.1)
				(type default)
			)
			(layer "F.Fab")
		)
		(fp_line
			(start 37.809932 28.300172)
			(end 35.809936 28.300172)
			(stroke
				(width 0.1)
				(type default)
			)
			(layer "F.Fab")
		)
		(fp_line
			(start 35.809936 28.300172)
			(end 35.809936 29.500068)
			(stroke
				(width 0.1)
				(type default)
			)
			(layer "F.Fab")
		)
		(fp_line
			(start -35.81019 28.300172)
			(end -37.810186 28.300172)
			(stroke
				(width 0.1)
				(type default)
			)
			(layer "F.Fab")
		)
		(fp_line
			(start -37.810186 28.300172)
			(end -37.810186 29.010102)
			(stroke
				(width 0.1)
				(type default)
			)
			(layer "F.Fab")
		)
		(fp_line
			(start 31.809944 28.449778)
			(end 31.809944 30.499812)
			(stroke
				(width 0.1)
				(type default)
			)
			(layer "F.Fab")
		)
		(fp_line
			(start 31.809944 28.450032)
			(end 31.809944 30.500066)
			(stroke
				(width 0.1)
				(type default)
			)
			(layer "F.Fab")
		)
		(fp_line
			(start -32.999934 28.999942)
			(end -32.999934 29.499814)
			(stroke
				(width 0.1)
				(type default)
			)
			(layer "F.Fab")
		)
		(fp_line
			(start -33.199832 28.999942)
			(end -32.999934 28.999942)
			(stroke
				(width 0.1)
				(type default)
			)
			(layer "F.Fab")
		)
		(fp_line
			(start -35.809936 28.999942)
			(end -35.809936 28.299918)
			(stroke
				(width 0.1)
				(type default)
			)
			(layer "F.Fab")
		)
		(fp_line
			(start -35.809936 28.999942)
			(end -33.199832 28.999942)
			(stroke
				(width 0.1)
				(type default)
			)
			(layer "F.Fab")
		)
		(fp_line
			(start -37.809932 28.999942)
			(end -37.809932 29.009848)
			(stroke
				(width 0.1)
				(type default)
			)
			(layer "F.Fab")
		)
		(fp_line
			(start -33.200086 29.000196)
			(end -33.000188 29.000196)
			(stroke
				(width 0.1)
				(type default)
			)
			(layer "F.Fab")
		)
		(fp_line
			(start -35.81019 29.000196)
			(end -35.81019 28.300172)
			(stroke
				(width 0.1)
				(type default)
			)
			(layer "F.Fab")
		)
		(fp_line
			(start -35.81019 29.000196)
			(end -33.200086 29.000196)
			(stroke
				(width 0.1)
				(type default)
			)
			(layer "F.Fab")
		)
		(fp_line
			(start -37.810186 29.000196)
			(end -37.810186 29.010102)
			(stroke
				(width 0.1)
				(type default)
			)
			(layer "F.Fab")
		)
		(fp_line
			(start 38.759892 29.009848)
			(end 37.810186 29.009848)
			(stroke
				(width 0.1)
				(type default)
			)
			(layer "F.Fab")
		)
		(fp_line
			(start 37.810186 29.009848)
			(end 37.810186 28.299918)
			(stroke
				(width 0.1)
				(type default)
			)
			(layer "F.Fab")
		)
		(fp_line
			(start -37.809932 29.009848)
			(end -38.760146 29.009848)
			(stroke
				(width 0.1)
				(type default)
			)
			(layer "F.Fab")
		)
		(fp_line
			(start 38.759892 29.010102)
			(end 37.809932 29.010102)
			(stroke
				(width 0.1)
				(type default)
			)
			(layer "F.Fab")
		)
		(fp_line
			(start 37.809932 29.010102)
			(end 37.809932 28.300172)
			(stroke
				(width 0.1)
				(type default)
			)
			(layer "F.Fab")
		)
		(fp_line
			(start -37.810186 29.010102)
			(end -38.760146 29.010102)
			(stroke
				(width 0.1)
				(type default)
			)
			(layer "F.Fab")
		)
		(fp_line
			(start 35.81019 29.499814)
			(end 35.81019 30.499812)
			(stroke
				(width 0.1)
				(type default)
			)
			(layer "F.Fab")
		)
		(fp_line
			(start 31.809944 29.499814)
			(end 35.81019 29.499814)
			(stroke
				(width 0.1)
				(type default)
			)
			(layer "F.Fab")
		)
		(fp_line
			(start 30.209998 29.499814)
			(end 30.209998 28.449778)
			(stroke
				(width 0.1)
				(type default)
			)
			(layer "F.Fab")
		)
		(fp_line
			(start 30.209998 29.499814)
			(end 30.209998 30.499812)
			(stroke
				(width 0.1)
				(type default)
			)
			(layer "F.Fab")
		)
		(fp_line
			(start 2.999994 29.499814)
			(end 30.209998 29.499814)
			(stroke
				(width 0.1)
				(type default)
			)
			(layer "F.Fab")
		)
		(fp_line
			(start -2.99974 29.499814)
			(end -1.299718 27.44978)
			(stroke
				(width 0.1)
				(type default)
			)
			(layer "F.Fab")
		)
		(fp_line
			(start -32.999934 29.499814)
			(end -2.99974 29.499814)
			(stroke
				(width 0.1)
				(type default)
			)
			(layer "F.Fab")
		)
		(fp_line
			(start 35.809936 29.500068)
			(end 35.809936 30.500066)
			(stroke
				(width 0.1)
				(type default)
			)
			(layer "F.Fab")
		)
		(fp_line
			(start 31.809944 29.500068)
			(end 35.809936 29.500068)
			(stroke
				(width 0.1)
				(type default)
			)
			(layer "F.Fab")
		)
		(fp_line
			(start 30.209998 29.500068)
			(end 30.209998 28.450032)
			(stroke
				(width 0.1)
				(type default)
			)
			(layer "F.Fab")
		)
		(fp_line
			(start 30.209998 29.500068)
			(end 30.209998 30.500066)
			(stroke
				(width 0.1)
				(type default)
			)
			(layer "F.Fab")
		)
		(fp_line
			(start 2.999994 29.500068)
			(end 30.209998 29.500068)
			(stroke
				(width 0.1)
				(type default)
			)
			(layer "F.Fab")
		)
		(fp_line
			(start -2.999994 29.500068)
			(end -1.299972 27.44978)
			(stroke
				(width 0.1)
				(type default)
			)
			(layer "F.Fab")
		)
		(fp_line
			(start -33.000188 29.500068)
			(end -2.999994 29.500068)
			(stroke
				(width 0.1)
				(type default)
			)
			(layer "F.Fab")
		)
		(fp_line
			(start 41.000172 30.499812)
			(end 41.000172 12.499848)
			(stroke
				(width 0.1)
				(type default)
			)
			(layer "F.Fab")
		)
		(fp_line
			(start 41.000172 30.499812)
			(end 40.000174 30.499812)
			(stroke
				(width 0.1)
				(type default)
			)
			(layer "F.Fab")
		)
		(fp_line
			(start 37.00018 30.499812)
			(end 35.81019 30.499812)
			(stroke
				(width 0.1)
				(type default)
			)
			(layer "F.Fab")
		)
		(fp_line
			(start 31.809944 30.499812)
			(end 31.809944 29.499814)
			(stroke
				(width 0.1)
				(type default)
			)
			(layer "F.Fab")
		)
		(fp_line
			(start 30.209998 30.499812)
			(end 31.809944 30.499812)
			(stroke
				(width 0.1)
				(type default)
			)
			(layer "F.Fab")
		)
		(fp_line
			(start -35.500056 30.499812)
			(end -35.809936 30.499812)
			(stroke
				(width 0.1)
				(type default)
			)
			(layer "F.Fab")
		)
		(fp_line
			(start -40.999918 30.499812)
			(end -35.809936 30.499812)
			(stroke
				(width 0.1)
				(type default)
			)
			(layer "F.Fab")
		)
		(fp_line
			(start 40.999918 30.500066)
			(end 40.999918 12.500102)
			(stroke
				(width 0.1)
				(type default)
			)
			(layer "F.Fab")
		)
		(fp_line
			(start 40.999918 30.500066)
			(end 39.99992 30.500066)
			(stroke
				(width 0.1)
				(type default)
			)
			(layer "F.Fab")
		)
		(fp_line
			(start 40.999918 30.500066)
			(end 39.997888 30.500066)
			(stroke
				(width 0.1)
				(type default)
			)
			(layer "F.Fab")
		)
		(fp_line
			(start 37.00145 30.500066)
			(end -30.80004 30.500066)
			(stroke
				(width 0.1)
				(type default)
			)
			(layer "F.Fab")
		)
		(fp_line
			(start 36.999926 30.500066)
			(end 35.809936 30.500066)
			(stroke
				(width 0.1)
				(type default)
			)
			(layer "F.Fab")
		)
		(fp_line
			(start 31.809944 30.500066)
			(end 31.809944 29.500068)
			(stroke
				(width 0.1)
				(type default)
			)
			(layer "F.Fab")
		)
		(fp_line
			(start 30.209998 30.500066)
			(end 31.809944 30.500066)
			(stroke
				(width 0.1)
				(type default)
			)
			(layer "F.Fab")
		)
		(fp_line
			(start -30.80004 30.500066)
			(end -33.000188 30.500066)
			(stroke
				(width 0.1)
				(type default)
			)
			(layer "F.Fab")
		)
		(fp_line
			(start -30.80004 30.500066)
			(end -30.80004 32.249872)
			(stroke
				(width 0.1)
				(type default)
			)
			(layer "F.Fab")
		)
		(fp_line
			(start -33.000188 30.500066)
			(end -33.000188 29.000196)
			(stroke
				(width 0.1)
				(type default)
			)
			(layer "F.Fab")
		)
		(fp_line
			(start -35.485832 30.500066)
			(end -40.999918 30.500066)
			(stroke
				(width 0.1)
				(type default)
			)
			(layer "F.Fab")
		)
		(fp_line
			(start -35.500056 30.500066)
			(end -35.81019 30.500066)
			(stroke
				(width 0.1)
				(type default)
			)
			(layer "F.Fab")
		)
		(fp_line
			(start -40.999918 30.500066)
			(end -40.999918 -29.000196)
			(stroke
				(width 0.1)
				(type default)
			)
			(layer "F.Fab")
		)
		(fp_line
			(start -41.000172 30.500066)
			(end -35.81019 30.500066)
			(stroke
				(width 0.1)
				(type default)
			)
			(layer "F.Fab")
		)
		(fp_line
			(start 39.499794 30.995112)
			(end 39.499794 32.250126)
			(stroke
				(width 0.1)
				(type default)
			)
			(layer "F.Fab")
		)
		(fp_line
			(start 39.499794 30.999938)
			(end 39.499794 32.249872)
			(stroke
				(width 0.1)
				(type default)
			)
			(layer "F.Fab")
		)
		(fp_line
			(start 39.499794 31.000192)
			(end 39.499794 32.249872)
			(stroke
				(width 0.1)
				(type default)
			)
			(layer "F.Fab")
		)
		(fp_line
			(start 39.499794 32.249872)
			(end 39.299896 32.249872)
			(stroke
				(width 0.1)
				(type default)
			)
			(layer "F.Fab")
		)
		(fp_line
			(start 39.499794 32.249872)
			(end 39.299896 32.249872)
			(stroke
				(width 0.1)
				(type default)
			)
			(layer "F.Fab")
		)
		(fp_line
			(start 39.299896 32.249872)
			(end 37.69995 32.249872)
			(stroke
				(width 0.1)
				(type default)
			)
			(layer "F.Fab")
		)
		(fp_line
			(start 39.299896 32.249872)
			(end 37.69995 32.249872)
			(stroke
				(width 0.1)
				(type default)
			)
			(layer "F.Fab")
		)
		(fp_line
			(start 37.69995 32.249872)
			(end 37.499798 32.249872)
			(stroke
				(width 0.1)
				(type default)
			)
			(layer "F.Fab")
		)
		(fp_line
			(start 37.69995 32.249872)
			(end 37.499798 32.249872)
			(stroke
				(width 0.1)
				(type default)
			)
			(layer "F.Fab")
		)
		(fp_line
			(start 37.499798 32.249872)
			(end 37.499798 30.999938)
			(stroke
				(width 0.1)
				(type default)
			)
			(layer "F.Fab")
		)
		(fp_line
			(start 37.499798 32.249872)
			(end 37.499798 31.000192)
			(stroke
				(width 0.1)
				(type default)
			)
			(layer "F.Fab")
		)
		(fp_line
			(start -30.80004 32.249872)
			(end -35.000184 32.249872)
			(stroke
				(width 0.1)
				(type default)
			)
			(layer "F.Fab")
		)
		(fp_line
			(start -32.999934 32.249872)
			(end -33.199832 32.249872)
			(stroke
				(width 0.1)
				(type default)
			)
			(layer "F.Fab")
		)
		(fp_line
			(start -33.000188 32.249872)
			(end -33.200086 32.249872)
			(stroke
				(width 0.1)
				(type default)
			)
			(layer "F.Fab")
		)
		(fp_line
			(start -33.199832 32.249872)
			(end -34.800032 32.249872)
			(stroke
				(width 0.1)
				(type default)
			)
			(layer "F.Fab")
		)
		(fp_line
			(start -33.200086 32.249872)
			(end -34.800032 32.249872)
			(stroke
				(width 0.1)
				(type default)
			)
			(layer "F.Fab")
		)
		(fp_line
			(start -34.800032 32.249872)
			(end -34.99993 32.249872)
			(stroke
				(width 0.1)
				(type default)
			)
			(layer "F.Fab")
		)
		(fp_line
			(start -34.800032 32.249872)
			(end -35.000184 32.249872)
			(stroke
				(width 0.1)
				(type default)
			)
			(layer "F.Fab")
		)
		(fp_line
			(start -34.99993 32.249872)
			(end -34.99993 30.999938)
			(stroke
				(width 0.1)
				(type default)
			)
			(layer "F.Fab")
		)
		(fp_line
			(start -35.000184 32.249872)
			(end -35.000184 30.994858)
			(stroke
				(width 0.1)
				(type default)
			)
			(layer "F.Fab")
		)
		(fp_line
			(start -35.000184 32.249872)
			(end -35.000184 31.000192)
			(stroke
				(width 0.1)
				(type default)
			)
			(layer "F.Fab")
		)
		(fp_line
			(start 39.499794 32.250126)
			(end 37.499798 32.250126)
			(stroke
				(width 0.1)
				(type default)
			)
			(layer "F.Fab")
		)
		(fp_line
			(start 37.499798 32.250126)
			(end 37.499798 30.995874)
			(stroke
				(width 0.1)
				(type default)
			)
			(layer "F.Fab")
		)
		(fp_arc
			(start 37.499798 -31.000192)
			(mid 37.354092 -30.647219)
			(end 37.001704 -30.500066)
			(stroke
				(width 0.1)
				(type default)
			)
			(layer "F.Fab")
		)
		(fp_arc
			(start 37.499798 -31.000192)
			(mid 37.353554 -30.64668)
			(end 37.00018 -30.500066)
			(stroke
				(width 0.1)
				(type default)
			)
			(layer "F.Fab")
		)
		(fp_arc
			(start -34.99993 -31.000192)
			(mid -35.146408 -30.646533)
			(end -35.500056 -30.500066)
			(stroke
				(width 0.1)
				(type default)
			)
			(layer "F.Fab")
		)
		(fp_arc
			(start -35.000184 -31.000192)
			(mid -35.14478 -30.64823)
			(end -35.49523 -30.500066)
			(stroke
				(width 0.1)
				(type default)
			)
			(layer "F.Fab")
		)
		(fp_arc
			(start 37.499798 -30.999938)
			(mid 37.353387 -30.646429)
			(end 36.999926 -30.499812)
			(stroke
				(width 0.1)
				(type default)
			)
			(layer "F.Fab")
		)
		(fp_arc
			(start -35.000184 -30.999938)
			(mid -35.146594 -30.646423)
			(end -35.500056 -30.499812)
			(stroke
				(width 0.1)
				(type default)
			)
			(layer "F.Fab")
		)
		(fp_arc
			(start 40.000174 -30.500066)
			(mid 39.646372 -30.64646)
			(end 39.499794 -31.000192)
			(stroke
				(width 0.1)
				(type default)
			)
			(layer "F.Fab")
		)
		(fp_arc
			(start 39.998396 -30.500066)
			(mid 39.647269 -30.645562)
			(end 39.499794 -30.995874)
			(stroke
				(width 0.1)
				(type default)
			)
			(layer "F.Fab")
		)
		(fp_arc
			(start 39.99992 -30.499812)
			(mid 39.646263 -30.646293)
			(end 39.499794 -30.999938)
			(stroke
				(width 0.1)
				(type default)
			)
			(layer "F.Fab")
		)
		(fp_arc
			(start 38.759892 -29.009848)
			(mid 39.29022 -28.790313)
			(end 39.509954 -28.26004)
			(stroke
				(width 0.1)
				(type default)
			)
			(layer "F.Fab")
		)
		(fp_arc
			(start 38.759892 -29.009848)
			(mid 39.290286 -28.79017)
			(end 39.509954 -28.259786)
			(stroke
				(width 0.1)
				(type default)
			)
			(layer "F.Fab")
		)
		(fp_arc
			(start 31.809944 -28.450032)
			(mid 31.01002 -27.649956)
			(end 30.209998 -28.450032)
			(stroke
				(width 0.1)
				(type default)
			)
			(layer "F.Fab")
		)
		(fp_arc
			(start 31.809944 -28.450032)
			(mid 31.01002 -27.649956)
			(end 30.209998 -28.450032)
			(stroke
				(width 0.1)
				(type default)
			)
			(layer "F.Fab")
		)
		(fp_arc
			(start -39.510208 -28.26004)
			(mid -39.290426 -28.790234)
			(end -38.760146 -29.009848)
			(stroke
				(width 0.1)
				(type default)
			)
			(layer "F.Fab")
		)
		(fp_arc
			(start -39.510208 -28.259786)
			(mid -39.290516 -28.790144)
			(end -38.760146 -29.009848)
			(stroke
				(width 0.1)
				(type default)
			)
			(layer "F.Fab")
		)
		(fp_arc
			(start 39.509954 28.259786)
			(mid 39.290335 28.790231)
			(end 38.759892 29.009848)
			(stroke
				(width 0.1)
				(type default)
			)
			(layer "F.Fab")
		)
		(fp_arc
			(start 39.509954 28.259786)
			(mid 39.290347 28.790301)
			(end 38.759892 29.010102)
			(stroke
				(width 0.1)
				(type default)
			)
			(layer "F.Fab")
		)
		(fp_arc
			(start 30.209998 28.449778)
			(mid 31.01002 27.649898)
			(end 31.809944 28.449778)
			(stroke
				(width 0.1)
				(type default)
			)
			(layer "F.Fab")
		)
		(fp_arc
			(start 30.209998 28.450032)
			(mid 31.01002 27.650098)
			(end 31.809944 28.450032)
			(stroke
				(width 0.1)
				(type default)
			)
			(layer "F.Fab")
		)
		(fp_arc
			(start -38.760146 29.009848)
			(mid -39.29053 28.79017)
			(end -39.510208 28.259786)
			(stroke
				(width 0.1)
				(type default)
			)
			(layer "F.Fab")
		)
		(fp_arc
			(start -38.760146 29.010102)
			(mid -39.290639 28.790337)
			(end -39.510208 28.259786)
			(stroke
				(width 0.1)
				(type default)
			)
			(layer "F.Fab")
		)
		(fp_arc
			(start 37.00018 30.499812)
			(mid 37.353577 30.646401)
			(end 37.499798 30.999938)
			(stroke
				(width 0.1)
				(type default)
			)
			(layer "F.Fab")
		)
		(fp_arc
			(start -35.500056 30.499812)
			(mid -35.146435 30.646305)
			(end -34.99993 30.999938)
			(stroke
				(width 0.1)
				(type default)
			)
			(layer "F.Fab")
		)
		(fp_arc
			(start 37.00145 30.500066)
			(mid 37.352458 30.645632)
			(end 37.499798 30.995874)
			(stroke
				(width 0.1)
				(type default)
			)
			(layer "F.Fab")
		)
		(fp_arc
			(start 36.999926 30.500066)
			(mid 37.353468 30.646568)
			(end 37.499798 31.000192)
			(stroke
				(width 0.1)
				(type default)
			)
			(layer "F.Fab")
		)
		(fp_arc
			(start -35.485832 30.500066)
			(mid -35.143179 30.649486)
			(end -35.000184 30.994858)
			(stroke
				(width 0.1)
				(type default)
			)
			(layer "F.Fab")
		)
		(fp_arc
			(start -35.500056 30.500066)
			(mid -35.146525 30.646575)
			(end -35.000184 31.000192)
			(stroke
				(width 0.1)
				(type default)
			)
			(layer "F.Fab")
		)
		(fp_arc
			(start 39.499794 30.995112)
			(mid 39.647205 30.64533)
			(end 39.997888 30.500066)
			(stroke
				(width 0.1)
				(type default)
			)
			(layer "F.Fab")
		)
		(fp_arc
			(start 39.499794 30.999938)
			(mid 39.646361 30.646194)
			(end 40.000174 30.499812)
			(stroke
				(width 0.1)
				(type default)
			)
			(layer "F.Fab")
		)
		(fp_arc
			(start 39.499794 31.000192)
			(mid 39.646287 30.646568)
			(end 39.99992 30.500066)
			(stroke
				(width 0.1)
				(type default)
			)
			(layer "F.Fab")
		)
		(pad "A9" smd oval
			(at -30.914086 -27.074114 135)
			(size 0.381 0.4826)
			(drill
				(offset 0 -0.0508)
			)
			(layers "F.Cu" "F.Mask" "F.Paste")
			(net "M_A_CPU1_SB_DQS_DN<3>")
		)
		(pad "A11" smd oval
			(at -29.2862 -27.074114 90)
			(size 0.381 0.4826)
			(drill
				(offset 0 -0.0508)
			)
			(layers "F.Cu" "F.Mask" "F.Paste")
			(net "GND")
		)
		(pad "A13" smd oval
			(at -27.658314 -27.074114 90)
			(size 0.381 0.4826)
			(drill
				(offset 0 -0.0508)
			)
			(layers "F.Cu" "F.Mask" "F.Paste")
			(net "GND")
		)
		(pad "A15" smd oval
			(at -26.030682 -27.074114 90)
			(size 0.381 0.4826)
			(drill
				(offset 0 -0.0508)
			)
			(layers "F.Cu" "F.Mask" "F.Paste")
			(net "M_B_CPU1_SB_DQS_DN<3>")
		)
		(pad "A17" smd oval
			(at -24.402796 -27.074114 90)
			(size 0.381 0.4826)
			(drill
				(offset 0 -0.0508)
			)
			(layers "F.Cu" "F.Mask" "F.Paste")
			(net "GND")
		)
		(pad "A19" smd oval
			(at -22.77491 -27.074114 90)
			(size 0.381 0.4826)
			(drill
				(offset 0 -0.0508)
			)
			(layers "F.Cu" "F.Mask" "F.Paste")
			(net "GND")
		)
		(pad "A21" smd oval
			(at -21.147278 -27.074114 90)
			(size 0.381 0.4826)
			(drill
				(offset 0 -0.0508)
			)
			(layers "F.Cu" "F.Mask" "F.Paste")
			(net "M_A_CPU1_SB_DQS_DN<2>")
		)
		(pad "A23" smd oval
			(at -19.519392 -27.074114 90)
			(size 0.381 0.4826)
			(drill
				(offset 0 -0.0508)
			)
			(layers "F.Cu" "F.Mask" "F.Paste")
			(net "GND")
		)
		(pad "A25" smd oval
			(at -17.89176 -27.074114 90)
			(size 0.381 0.4826)
			(drill
				(offset 0 -0.0508)
			)
			(layers "F.Cu" "F.Mask" "F.Paste")
			(net "GND")
		)
		(pad "A27" smd oval
			(at -16.263874 -27.074114 90)
			(size 0.381 0.4826)
			(drill
				(offset 0 -0.0508)
			)
			(layers "F.Cu" "F.Mask" "F.Paste")
			(net "M_A_CPU1_SB_DQS_DN<1>")
		)
		(pad "A29" smd oval
			(at -14.635988 -27.074114 90)
			(size 0.381 0.4826)
			(drill
				(offset 0 -0.0508)
			)
			(layers "F.Cu" "F.Mask" "F.Paste")
			(net "GND")
		)
		(pad "A31" smd oval
			(at -13.008356 -27.074114 90)
			(size 0.381 0.4826)
			(drill
				(offset 0 -0.0508)
			)
			(layers "F.Cu" "F.Mask" "F.Paste")
			(net "GND")
		)
		(pad "A33" smd oval
			(at -11.380724 -27.074114 90)
			(size 0.381 0.4826)
			(drill
				(offset 0 -0.0508)
			)
			(layers "F.Cu" "F.Mask" "F.Paste")
			(net "M_A_CPU1_SB_DQS_DN<9>")
		)
		(pad "A35" smd oval
			(at -9.752838 -27.074114 90)
			(size 0.381 0.4826)
			(drill
				(offset 0 -0.0508)
			)
			(layers "F.Cu" "F.Mask" "F.Paste")
			(net "GND")
		)
		(pad "A37" smd oval
			(at -8.124952 -27.074114 90)
			(size 0.381 0.4826)
			(drill
				(offset 0 -0.0508)
			)
			(layers "F.Cu" "F.Mask" "F.Paste")
			(net "GND")
		)
		(pad "A39" smd oval
			(at -6.49732 -27.074114 90)
			(size 0.381 0.4826)
			(drill
				(offset 0 -0.0508)
			)
			(layers "F.Cu" "F.Mask" "F.Paste")
			(net "M_A_CPU1_SB_CA<6>")
		)
		(pad "A41" smd oval
			(at -4.869434 -27.074114 90)
			(size 0.381 0.4826)
			(drill
				(offset 0 -0.0508)
			)
			(layers "F.Cu" "F.Mask" "F.Paste")
			(net "GND")
		)
		(pad "A43" smd oval
			(at -3.241802 -27.074114 90)
			(size 0.381 0.4826)
			(drill
				(offset 0 -0.0508)
			)
			(layers "F.Cu" "F.Mask" "F.Paste")
			(net "PWRGD_DRAMPWRGD_CPU1_AB_LVC1_R")
		)
		(pad "A50" smd oval
			(at 4.055618 -26.964132 90)
			(size 0.381 0.4826)
			(drill
				(offset 0 -0.0508)
			)
			(layers "F.Cu" "F.Mask" "F.Paste")
			(net "GND")
		)
		(pad "A52" smd oval
			(at 5.68325 -26.964132 90)
			(size 0.381 0.4826)
			(drill
				(offset 0 -0.0508)
			)
			(layers "F.Cu" "F.Mask" "F.Paste")
			(net "M_A_CPU1_SA_CA<0>")
		)
		(pad "A54" smd oval
			(at 7.311136 -26.964132 90)
			(size 0.381 0.4826)
			(drill
				(offset 0 -0.0508)
			)
			(layers "F.Cu" "F.Mask" "F.Paste")
			(net "GND")
		)
		(pad "A56" smd oval
			(at 8.939022 -26.964132 90)
			(size 0.381 0.4826)
			(drill
				(offset 0 -0.0508)
			)
			(layers "F.Cu" "F.Mask" "F.Paste")
			(net "GND")
		)
		(pad "A58" smd oval
			(at 10.566654 -26.964132 90)
			(size 0.381 0.4826)
			(drill
				(offset 0 -0.0508)
			)
			(layers "F.Cu" "F.Mask" "F.Paste")
			(net "M_A_CPU1_SA_DQS_DN<4>")
		)
		(pad "A60" smd oval
			(at 12.19454 -26.964132 90)
			(size 0.381 0.4826)
			(drill
				(offset 0 -0.0508)
			)
			(layers "F.Cu" "F.Mask" "F.Paste")
			(net "GND")
		)
		(pad "A62" smd oval
			(at 13.822426 -26.964132 90)
			(size 0.381 0.4826)
			(drill
				(offset 0 -0.0508)
			)
			(layers "F.Cu" "F.Mask" "F.Paste")
			(net "GND")
		)
		(pad "A64" smd oval
			(at 15.450058 -26.964132 90)
			(size 0.381 0.4826)
			(drill
				(offset 0 -0.0508)
			)
			(layers "F.Cu" "F.Mask" "F.Paste")
			(net "M_A_CPU1_SA_DQS_DN<3>")
		)
		(pad "AA1" smd oval
			(at -37.425122 -17.676114 180)
			(size 0.381 0.4826)
			(drill
				(offset 0 -0.0508)
			)
			(layers "F.Cu" "F.Mask" "F.Paste")
			(net "UPI_CPU1_CPU0_P0P1_DN<6>")
		)
		(pad "AA3" smd circle
			(at -35.797236 -17.676114 270)
			(size 0.4318 0.4318)
			(layers "F.Cu" "F.Mask" "F.Paste")
			(net "PVCCFA_EHV_CPU1")
		)
		(pad "AA5" smd circle
			(at -34.169604 -17.676114 270)
			(size 0.4318 0.4318)
			(layers "F.Cu" "F.Mask" "F.Paste")
			(net "UPI_CPU0_CPU1_P1P0_DN<5>")
		)
		(pad "AA7" smd circle
			(at -32.541718 -17.676114 270)
			(size 0.4318 0.4318)
			(layers "F.Cu" "F.Mask" "F.Paste")
			(net "PVCCFA_EHV_FIVRA_CPU1")
		)
		(pad "AA9" smd circle
			(at -30.914086 -17.676114 270)
			(size 0.4318 0.4318)
			(layers "F.Cu" "F.Mask" "F.Paste")
			(net "P5E_CPU1_PE0_RX_DN<5>")
		)
		(pad "AA11" smd circle
			(at -29.2862 -17.676114 270)
			(size 0.4318 0.4318)
			(layers "F.Cu" "F.Mask" "F.Paste")
			(net "PVCCFA_EHV_FIVRA_CPU1")
		)
		(pad "AA13" smd circle
			(at -27.658314 -17.676114 270)
			(size 0.4318 0.4318)
			(layers "F.Cu" "F.Mask" "F.Paste")
			(net "P5E_CPU1_PE0_TX_DN<4>")
		)
		(pad "AA15" smd circle
			(at -26.030682 -17.676114 270)
			(size 0.4318 0.4318)
			(layers "F.Cu" "F.Mask" "F.Paste")
			(net "PVCCFA_EHV_FIVRA_CPU1")
		)
		(pad "AA17" smd circle
			(at -24.402796 -17.676114 270)
			(size 0.4318 0.4318)
			(layers "F.Cu" "F.Mask" "F.Paste")
			(net "M_C_CPU1_SB_DQ<28>")
		)
		(pad "AA19" smd circle
			(at -22.77491 -17.676114 270)
			(size 0.4318 0.4318)
			(layers "F.Cu" "F.Mask" "F.Paste")
			(net "GND")
		)
		(pad "AA21" smd circle
			(at -21.147278 -17.676114 270)
			(size 0.4318 0.4318)
			(layers "F.Cu" "F.Mask" "F.Paste")
			(net "M_C_CPU1_SB_DQS_DP<7>")
		)
		(pad "AA23" smd circle
			(at -19.519392 -17.676114 270)
			(size 0.4318 0.4318)
			(layers "F.Cu" "F.Mask" "F.Paste")
			(net "GND")
		)
		(pad "AA25" smd circle
			(at -17.89176 -17.676114 270)
			(size 0.4318 0.4318)
			(layers "F.Cu" "F.Mask" "F.Paste")
			(net "GND")
		)
		(pad "AA27" smd circle
			(at -16.263874 -17.676114 270)
			(size 0.4318 0.4318)
			(layers "F.Cu" "F.Mask" "F.Paste")
			(net "M_B_CPU1_SB_DQS_DP<5>")
		)
		(pad "AA29" smd circle
			(at -14.635988 -17.676114 270)
			(size 0.4318 0.4318)
			(layers "F.Cu" "F.Mask" "F.Paste")
			(net "GND")
		)
		(pad "AA31" smd circle
			(at -13.008356 -17.676114 270)
			(size 0.4318 0.4318)
			(layers "F.Cu" "F.Mask" "F.Paste")
			(net "GND")
		)
		(pad "AA33" smd circle
			(at -11.380724 -17.676114 270)
			(size 0.4318 0.4318)
			(layers "F.Cu" "F.Mask" "F.Paste")
			(net "M_C_CPU1_SB_DQS_DP<4>")
		)
		(pad "AA35" smd circle
			(at -9.752838 -17.676114 270)
			(size 0.4318 0.4318)
			(layers "F.Cu" "F.Mask" "F.Paste")
			(net "GND")
		)
		(pad "AA37" smd circle
			(at -8.124952 -17.676114 270)
			(size 0.4318 0.4318)
			(layers "F.Cu" "F.Mask" "F.Paste")
			(net "GND")
		)
		(pad "AA39" smd circle
			(at -6.49732 -17.676114 270)
			(size 0.4318 0.4318)
			(layers "F.Cu" "F.Mask" "F.Paste")
			(net "M_C_CPU1_SB_PAR")
		)
		(pad "AA41" smd circle
			(at -4.869434 -17.676114 270)
			(size 0.4318 0.4318)
			(layers "F.Cu" "F.Mask" "F.Paste")
			(net "GND")
		)
		(pad "AA43" smd circle
			(at -3.241802 -17.676114 270)
			(size 0.4318 0.4318)
			(layers "F.Cu" "F.Mask" "F.Paste")
			(net "GND")
		)
		(pad "AA45" smd circle
			(at -1.613916 -17.676114 270)
			(size 0.4318 0.4318)
			(layers "F.Cu" "F.Mask" "F.Paste")
			(net "M_B_CPU1_CLK_DP<1>")
		)
		(pad "AA48" smd circle
			(at 2.427732 -17.566132 270)
			(size 0.4318 0.4318)
			(layers "F.Cu" "F.Mask" "F.Paste")
			(net "GND")
		)
		(pad "AA50" smd circle
			(at 4.055618 -17.566132 270)
			(size 0.4318 0.4318)
			(layers "F.Cu" "F.Mask" "F.Paste")
			(net "GND")
		)
		(pad "AA52" smd circle
			(at 5.68325 -17.566132 270)
			(size 0.4318 0.4318)
			(layers "F.Cu" "F.Mask" "F.Paste")
			(net "M_C_CPU1_SA_CA<1>")
		)
		(pad "AA54" smd circle
			(at 7.311136 -17.566132 270)
			(size 0.4318 0.4318)
			(layers "F.Cu" "F.Mask" "F.Paste")
			(net "GND")
		)
		(pad "AA56" smd circle
			(at 8.939022 -17.566132 270)
			(size 0.4318 0.4318)
			(layers "F.Cu" "F.Mask" "F.Paste")
			(net "GND")
		)
		(pad "AA58" smd circle
			(at 10.566654 -17.566132 270)
			(size 0.4318 0.4318)
			(layers "F.Cu" "F.Mask" "F.Paste")
			(net "M_B_CPU1_SA_DQS_DN<8>")
		)
		(pad "AA60" smd circle
			(at 12.19454 -17.566132 270)
			(size 0.4318 0.4318)
			(layers "F.Cu" "F.Mask" "F.Paste")
			(net "GND")
		)
		(pad "AA62" smd circle
			(at 13.822426 -17.566132 270)
			(size 0.4318 0.4318)
			(layers "F.Cu" "F.Mask" "F.Paste")
			(net "GND")
		)
		(pad "AA64" smd circle
			(at 15.450058 -17.566132 270)
			(size 0.4318 0.4318)
			(layers "F.Cu" "F.Mask" "F.Paste")
			(net "M_C_CPU1_SA_DQS_DN<7>")
		)
		(pad "AA66" smd circle
			(at 17.07769 -17.566132 270)
			(size 0.4318 0.4318)
			(layers "F.Cu" "F.Mask" "F.Paste")
			(net "GND")
		)
		(pad "AA68" smd circle
			(at 18.705576 -17.566132 270)
			(size 0.4318 0.4318)
			(layers "F.Cu" "F.Mask" "F.Paste")
			(net "GND")
		)
		(pad "AA70" smd circle
			(at 20.333462 -17.566132 270)
			(size 0.4318 0.4318)
			(layers "F.Cu" "F.Mask" "F.Paste")
			(net "M_B_CPU1_SA_DQS_DN<6>")
		)
		(pad "AA72" smd circle
			(at 21.961094 -17.566132 270)
			(size 0.4318 0.4318)
			(layers "F.Cu" "F.Mask" "F.Paste")
			(net "GND")
		)
		(pad "AA74" smd circle
			(at 23.58898 -17.566132 270)
			(size 0.4318 0.4318)
			(layers "F.Cu" "F.Mask" "F.Paste")
			(net "GND")
		)
		(pad "AA76" smd circle
			(at 25.216612 -17.566132 270)
			(size 0.4318 0.4318)
			(layers "F.Cu" "F.Mask" "F.Paste")
			(net "M_C_CPU1_SA_DQS_DP<5>")
		)
		(pad "AA78" smd circle
			(at 26.844498 -17.566132 270)
			(size 0.4318 0.4318)
			(layers "F.Cu" "F.Mask" "F.Paste")
			(net "GND")
		)
		(pad "AA80" smd circle
			(at 28.472384 -17.566132 270)
			(size 0.4318 0.4318)
			(layers "F.Cu" "F.Mask" "F.Paste")
			(net "GND")
		)
		(pad "AA82" smd circle
			(at 30.100016 -17.566132 270)
			(size 0.4318 0.4318)
			(layers "F.Cu" "F.Mask" "F.Paste")
			(net "GND")
		)
		(pad "AA84" smd circle
			(at 31.727902 -17.566132 270)
			(size 0.4318 0.4318)
			(layers "F.Cu" "F.Mask" "F.Paste")
			(net "GND")
		)
		(pad "AA86" smd circle
			(at 33.355534 -17.566132 270)
			(size 0.4318 0.4318)
			(layers "F.Cu" "F.Mask" "F.Paste")
			(net "P5E_CPU1_PE4_TX_DN<5>")
		)
		(pad "AA88" smd circle
			(at 34.98342 -17.566132 270)
			(size 0.4318 0.4318)
			(layers "F.Cu" "F.Mask" "F.Paste")
			(net "GND")
		)
		(pad "AA90" smd circle
			(at 36.611306 -17.566132 270)
			(size 0.4318 0.4318)
			(layers "F.Cu" "F.Mask" "F.Paste")
			(net "P5E_CPU1_PE4_RX_DP<5>")
		)
		(pad "AB2" smd circle
			(at -36.611306 -17.206468 270)
			(size 0.4318 0.4318)
			(layers "F.Cu" "F.Mask" "F.Paste")
			(net "UPI_CPU1_CPU0_P0P1_DP<6>")
		)
		(pad "AB4" smd circle
			(at -34.98342 -17.206468 270)
			(size 0.4318 0.4318)
			(layers "F.Cu" "F.Mask" "F.Paste")
			(net "GND")
		)
		(pad "AB6" smd circle
			(at -33.355534 -17.206468 270)
			(size 0.4318 0.4318)
			(layers "F.Cu" "F.Mask" "F.Paste")
			(net "UPI_CPU0_CPU1_P1P0_DN<6>")
		)
		(pad "AB8" smd circle
			(at -31.727902 -17.206468 270)
			(size 0.4318 0.4318)
			(layers "F.Cu" "F.Mask" "F.Paste")
			(net "GND")
		)
		(pad "AB10" smd circle
			(at -30.100016 -17.206468 270)
			(size 0.4318 0.4318)
			(layers "F.Cu" "F.Mask" "F.Paste")
			(net "P5E_CPU1_PE0_RX_DN<6>")
		)
		(pad "AB12" smd circle
			(at -28.472384 -17.206468 270)
			(size 0.4318 0.4318)
			(layers "F.Cu" "F.Mask" "F.Paste")
			(net "GND")
		)
		(pad "AB14" smd circle
			(at -26.844498 -17.206468 270)
			(size 0.4318 0.4318)
			(layers "F.Cu" "F.Mask" "F.Paste")
			(net "P5E_CPU1_PE0_TX_DN<5>")
		)
		(pad "AB16" smd circle
			(at -25.216612 -17.206468 270)
			(size 0.4318 0.4318)
			(layers "F.Cu" "F.Mask" "F.Paste")
			(net "GND")
		)
		(pad "AB18" smd circle
			(at -23.58898 -17.206468 270)
			(size 0.4318 0.4318)
			(layers "F.Cu" "F.Mask" "F.Paste")
			(net "M_C_CPU1_SB_DQS_DN<3>")
		)
		(pad "AB20" smd circle
			(at -21.961094 -17.206468 270)
			(size 0.4318 0.4318)
			(layers "F.Cu" "F.Mask" "F.Paste")
			(net "GND")
		)
		(pad "AB22" smd circle
			(at -20.333462 -17.206468 270)
			(size 0.4318 0.4318)
			(layers "F.Cu" "F.Mask" "F.Paste")
			(net "GND")
		)
		(pad "AB24" smd circle
			(at -18.705576 -17.206468 270)
			(size 0.4318 0.4318)
			(layers "F.Cu" "F.Mask" "F.Paste")
			(net "M_D_CPU1_SB_DQS_DN<2>")
		)
		(pad "AB26" smd circle
			(at -17.07769 -17.206468 270)
			(size 0.4318 0.4318)
			(layers "F.Cu" "F.Mask" "F.Paste")
			(net "GND")
		)
		(pad "AB28" smd circle
			(at -15.450058 -17.206468 270)
			(size 0.4318 0.4318)
			(layers "F.Cu" "F.Mask" "F.Paste")
			(net "GND")
		)
		(pad "AB30" smd circle
			(at -13.822426 -17.206468 270)
			(size 0.4318 0.4318)
			(layers "F.Cu" "F.Mask" "F.Paste")
			(net "M_C_CPU1_SB_DQS_DN<1>")
		)
		(pad "AB32" smd circle
			(at -12.19454 -17.206468 270)
			(size 0.4318 0.4318)
			(layers "F.Cu" "F.Mask" "F.Paste")
			(net "GND")
		)
		(pad "AB34" smd circle
			(at -10.566654 -17.206468 270)
			(size 0.4318 0.4318)
			(layers "F.Cu" "F.Mask" "F.Paste")
			(net "GND")
		)
		(pad "AB36" smd circle
			(at -8.939022 -17.206468 270)
			(size 0.4318 0.4318)
			(layers "F.Cu" "F.Mask" "F.Paste")
			(net "M_C_CPU1_SB_DQS_DN<0>")
		)
		(pad "AB38" smd circle
			(at -7.311136 -17.206468 270)
			(size 0.4318 0.4318)
			(layers "F.Cu" "F.Mask" "F.Paste")
			(net "GND")
		)
		(pad "AB40" smd circle
			(at -5.68325 -17.206468 270)
			(size 0.4318 0.4318)
			(layers "F.Cu" "F.Mask" "F.Paste")
			(net "GND")
		)
		(pad "AB42" smd circle
			(at -4.055618 -17.206468 270)
			(size 0.4318 0.4318)
			(layers "F.Cu" "F.Mask" "F.Paste")
			(net "M_D_CPU1_SB_CA<6>")
		)
		(pad "AB44" smd circle
			(at -2.427732 -17.206468 270)
			(size 0.4318 0.4318)
			(layers "F.Cu" "F.Mask" "F.Paste")
			(net "GND")
		)
		(pad "AB47" smd circle
			(at 1.613916 -17.096486 270)
			(size 0.4318 0.4318)
			(layers "F.Cu" "F.Mask" "F.Paste")
			(net "GND")
		)
		(pad "AB49" smd circle
			(at 3.241802 -17.096486 270)
			(size 0.4318 0.4318)
			(layers "F.Cu" "F.Mask" "F.Paste")
			(net "M_C_CPU1_CLK_DN<0>")
		)
		(pad "AB51" smd circle
			(at 4.869434 -17.096486 270)
			(size 0.4318 0.4318)
			(layers "F.Cu" "F.Mask" "F.Paste")
			(net "GND")
		)
		(pad "AB53" smd circle
			(at 6.49732 -17.096486 270)
			(size 0.4318 0.4318)
			(layers "F.Cu" "F.Mask" "F.Paste")
			(net "GND")
		)
		(pad "AB55" smd circle
			(at 8.124952 -17.096486 270)
			(size 0.4318 0.4318)
			(layers "F.Cu" "F.Mask" "F.Paste")
			(net "M_C_CPU1_SA_DQS_DP<4>")
		)
		(pad "AB57" smd circle
			(at 9.752838 -17.096486 270)
			(size 0.4318 0.4318)
			(layers "F.Cu" "F.Mask" "F.Paste")
			(net "GND")
		)
		(pad "AB59" smd circle
			(at 11.380724 -17.096486 270)
			(size 0.4318 0.4318)
			(layers "F.Cu" "F.Mask" "F.Paste")
			(net "GND")
		)
		(pad "AB61" smd circle
			(at 13.008356 -17.096486 270)
			(size 0.4318 0.4318)
			(layers "F.Cu" "F.Mask" "F.Paste")
			(net "M_C_CPU1_SA_DQS_DN<3>")
		)
		(pad "AB63" smd circle
			(at 14.635988 -17.096486 270)
			(size 0.4318 0.4318)
			(layers "F.Cu" "F.Mask" "F.Paste")
			(net "GND")
		)
		(pad "AB65" smd circle
			(at 16.263874 -17.096486 270)
			(size 0.4318 0.4318)
			(layers "F.Cu" "F.Mask" "F.Paste")
			(net "GND")
		)
		(pad "AB67" smd circle
			(at 17.89176 -17.096486 270)
			(size 0.4318 0.4318)
			(layers "F.Cu" "F.Mask" "F.Paste")
			(net "M_C_CPU1_SA_DQS_DN<1>")
		)
		(pad "AB69" smd circle
			(at 19.519392 -17.096486 270)
			(size 0.4318 0.4318)
			(layers "F.Cu" "F.Mask" "F.Paste")
			(net "GND")
		)
		(pad "AB71" smd circle
			(at 21.147278 -17.096486 270)
			(size 0.4318 0.4318)
			(layers "F.Cu" "F.Mask" "F.Paste")
			(net "GND")
		)
		(pad "AB73" smd circle
			(at 22.77491 -17.096486 270)
			(size 0.4318 0.4318)
			(layers "F.Cu" "F.Mask" "F.Paste")
			(net "M_D_CPU1_SA_DQS_DN<0>")
		)
		(pad "AB75" smd circle
			(at 24.402796 -17.096486 270)
			(size 0.4318 0.4318)
			(layers "F.Cu" "F.Mask" "F.Paste")
			(net "GND")
		)
		(pad "AB77" smd circle
			(at 26.030682 -17.096486 270)
			(size 0.4318 0.4318)
			(layers "F.Cu" "F.Mask" "F.Paste")
			(net "GND")
		)
		(pad "AB79" smd circle
			(at 27.658314 -17.096486 270)
			(size 0.4318 0.4318)
			(layers "F.Cu" "F.Mask" "F.Paste")
			(net "GND")
		)
		(pad "AB81" smd circle
			(at 29.2862 -17.096486 270)
			(size 0.4318 0.4318)
			(layers "F.Cu" "F.Mask" "F.Paste")
			(net "GND")
		)
		(pad "AB83" smd circle
			(at 30.914086 -17.096486 270)
			(size 0.4318 0.4318)
			(layers "F.Cu" "F.Mask" "F.Paste")
			(net "GND")
		)
		(pad "AB85" smd circle
			(at 32.541718 -17.096486 270)
			(size 0.4318 0.4318)
			(layers "F.Cu" "F.Mask" "F.Paste")
			(net "P5E_CPU1_PE4_TX_DP<5>")
		)
		(pad "AB87" smd circle
			(at 34.169604 -17.096486 270)
			(size 0.4318 0.4318)
			(layers "F.Cu" "F.Mask" "F.Paste")
			(net "GND")
		)
		(pad "AB89" smd circle
			(at 35.797236 -17.096486 270)
			(size 0.4318 0.4318)
			(layers "F.Cu" "F.Mask" "F.Paste")
			(net "P5E_CPU1_PE4_RX_DN<5>")
		)
		(pad "AB91" smd oval
			(at 37.425122 -17.096486)
			(size 0.381 0.4826)
			(drill
				(offset 0 -0.0508)
			)
			(layers "F.Cu" "F.Mask" "F.Paste")
			(net "GND")
		)
		(pad "AC1" smd oval
			(at -37.425122 -16.736314 180)
			(size 0.381 0.4826)
			(drill
				(offset 0 -0.0508)
			)
			(layers "F.Cu" "F.Mask" "F.Paste")
			(net "GND")
		)
		(pad "AC3" smd circle
			(at -35.797236 -16.736314 270)
			(size 0.4318 0.4318)
			(layers "F.Cu" "F.Mask" "F.Paste")
			(net "UPI_CPU1_CPU0_P0P1_DP<7>")
		)
		(pad "AC5" smd circle
			(at -34.169604 -16.736314 270)
			(size 0.4318 0.4318)
			(layers "F.Cu" "F.Mask" "F.Paste")
			(net "GND")
		)
		(pad "AC7" smd circle
			(at -32.541718 -16.736314 270)
			(size 0.4318 0.4318)
			(layers "F.Cu" "F.Mask" "F.Paste")
			(net "UPI_CPU0_CPU1_P1P0_DP<6>")
		)
		(pad "AC9" smd circle
			(at -30.914086 -16.736314 270)
			(size 0.4318 0.4318)
			(layers "F.Cu" "F.Mask" "F.Paste")
			(net "GND")
		)
		(pad "AC11" smd circle
			(at -29.2862 -16.736314 270)
			(size 0.4318 0.4318)
			(layers "F.Cu" "F.Mask" "F.Paste")
			(net "P5E_CPU1_PE0_RX_DP<6>")
		)
		(pad "AC13" smd circle
			(at -27.658314 -16.736314 270)
			(size 0.4318 0.4318)
			(layers "F.Cu" "F.Mask" "F.Paste")
			(net "GND")
		)
		(pad "AC15" smd circle
			(at -26.030682 -16.736314 270)
			(size 0.4318 0.4318)
			(layers "F.Cu" "F.Mask" "F.Paste")
			(net "P5E_CPU1_PE0_TX_DP<5>")
		)
		(pad "AC17" smd circle
			(at -24.402796 -16.736314 270)
			(size 0.4318 0.4318)
			(layers "F.Cu" "F.Mask" "F.Paste")
			(net "M_C_CPU1_SB_DQ<30>")
		)
		(pad "AC19" smd circle
			(at -22.77491 -16.736314 270)
			(size 0.4318 0.4318)
			(layers "F.Cu" "F.Mask" "F.Paste")
			(net "M_C_CPU1_SB_DQ<25>")
		)
		(pad "AC21" smd circle
			(at -21.147278 -16.736314 270)
			(size 0.4318 0.4318)
			(layers "F.Cu" "F.Mask" "F.Paste")
			(net "GND")
		)
		(pad "AC23" smd circle
			(at -19.519392 -16.736314 270)
			(size 0.4318 0.4318)
			(layers "F.Cu" "F.Mask" "F.Paste")
			(net "M_D_CPU1_SB_DQ<20>")
		)
		(pad "AC25" smd circle
			(at -17.89176 -16.736314 270)
			(size 0.4318 0.4318)
			(layers "F.Cu" "F.Mask" "F.Paste")
			(net "M_D_CPU1_SB_DQ<17>")
		)
		(pad "AC27" smd circle
			(at -16.263874 -16.736314 270)
			(size 0.4318 0.4318)
			(layers "F.Cu" "F.Mask" "F.Paste")
			(net "GND")
		)
		(pad "AC29" smd circle
			(at -14.635988 -16.736314 270)
			(size 0.4318 0.4318)
			(layers "F.Cu" "F.Mask" "F.Paste")
			(net "M_C_CPU1_SB_DQ<12>")
		)
		(pad "AC31" smd circle
			(at -13.008356 -16.736314 270)
			(size 0.4318 0.4318)
			(layers "F.Cu" "F.Mask" "F.Paste")
			(net "M_C_CPU1_SB_DQ<9>")
		)
		(pad "AC33" smd circle
			(at -11.380724 -16.736314 270)
			(size 0.4318 0.4318)
			(layers "F.Cu" "F.Mask" "F.Paste")
			(net "GND")
		)
		(pad "AC35" smd circle
			(at -9.752838 -16.736314 270)
			(size 0.4318 0.4318)
			(layers "F.Cu" "F.Mask" "F.Paste")
			(net "M_C_CPU1_SB_DQ<4>")
		)
		(pad "AC37" smd circle
			(at -8.124952 -16.736314 270)
			(size 0.4318 0.4318)
			(layers "F.Cu" "F.Mask" "F.Paste")
			(net "M_C_CPU1_SB_DQ<1>")
		)
		(pad "AC39" smd circle
			(at -6.49732 -16.736314 270)
			(size 0.4318 0.4318)
			(layers "F.Cu" "F.Mask" "F.Paste")
			(net "GND")
		)
		(pad "AC41" smd circle
			(at -4.869434 -16.736314 270)
			(size 0.4318 0.4318)
			(layers "F.Cu" "F.Mask" "F.Paste")
			(net "M_D_CPU1_SB_CS_N<0>")
		)
		(pad "AC43" smd circle
			(at -3.241802 -16.736314 270)
			(size 0.4318 0.4318)
			(layers "F.Cu" "F.Mask" "F.Paste")
			(net "M_D_CPU1_SB_CA<4>")
		)
		(pad "AC45" smd circle
			(at -1.613916 -16.736314 270)
			(size 0.4318 0.4318)
			(layers "F.Cu" "F.Mask" "F.Paste")
			(net "GND")
		)
		(pad "AC48" smd circle
			(at 2.427732 -16.626332 270)
			(size 0.4318 0.4318)
			(layers "F.Cu" "F.Mask" "F.Paste")
			(net "M_C_CPU1_SA_RSP<0>")
		)
		(pad "AC50" smd circle
			(at 4.055618 -16.626332 270)
			(size 0.4318 0.4318)
			(layers "F.Cu" "F.Mask" "F.Paste")
			(net "M_D_CPU1_SA_RSP<1>")
		)
		(pad "AC52" smd circle
			(at 5.68325 -16.626332 270)
			(size 0.4318 0.4318)
			(layers "F.Cu" "F.Mask" "F.Paste")
			(net "GND")
		)
		(pad "AC54" smd circle
			(at 7.311136 -16.626332 270)
			(size 0.4318 0.4318)
			(layers "F.Cu" "F.Mask" "F.Paste")
			(net "M_C_CPU1_SA_CB<4>")
		)
		(pad "AC56" smd circle
			(at 8.939022 -16.626332 270)
			(size 0.4318 0.4318)
			(layers "F.Cu" "F.Mask" "F.Paste")
			(net "M_C_CPU1_SA_CB<1>")
		)
		(pad "AC58" smd circle
			(at 10.566654 -16.626332 270)
			(size 0.4318 0.4318)
			(layers "F.Cu" "F.Mask" "F.Paste")
			(net "GND")
		)
		(pad "AC60" smd circle
			(at 12.19454 -16.626332 270)
			(size 0.4318 0.4318)
			(layers "F.Cu" "F.Mask" "F.Paste")
			(net "M_C_CPU1_SA_DQ<28>")
		)
		(pad "AC62" smd circle
			(at 13.822426 -16.626332 270)
			(size 0.4318 0.4318)
			(layers "F.Cu" "F.Mask" "F.Paste")
			(net "M_C_CPU1_SA_DQ<25>")
		)
		(pad "AC64" smd circle
			(at 15.450058 -16.626332 270)
			(size 0.4318 0.4318)
			(layers "F.Cu" "F.Mask" "F.Paste")
			(net "GND")
		)
		(pad "AC66" smd circle
			(at 17.07769 -16.626332 270)
			(size 0.4318 0.4318)
			(layers "F.Cu" "F.Mask" "F.Paste")
			(net "M_C_CPU1_SA_DQ<12>")
		)
		(pad "AC68" smd circle
			(at 18.705576 -16.626332 270)
			(size 0.4318 0.4318)
			(layers "F.Cu" "F.Mask" "F.Paste")
			(net "M_C_CPU1_SA_DQ<9>")
		)
		(pad "AC70" smd circle
			(at 20.333462 -16.626332 270)
			(size 0.4318 0.4318)
			(layers "F.Cu" "F.Mask" "F.Paste")
			(net "GND")
		)
		(pad "AC72" smd circle
			(at 21.961094 -16.626332 270)
			(size 0.4318 0.4318)
			(layers "F.Cu" "F.Mask" "F.Paste")
			(net "M_D_CPU1_SA_DQ<4>")
		)
		(pad "AC74" smd circle
			(at 23.58898 -16.626332 270)
			(size 0.4318 0.4318)
			(layers "F.Cu" "F.Mask" "F.Paste")
			(net "M_D_CPU1_SA_DQ<1>")
		)
		(pad "AC76" smd circle
			(at 25.216612 -16.626332 270)
			(size 0.4318 0.4318)
			(layers "F.Cu" "F.Mask" "F.Paste")
			(net "GND")
		)
		(pad "AC78" smd circle
			(at 26.844498 -16.626332 270)
			(size 0.4318 0.4318)
			(layers "F.Cu" "F.Mask" "F.Paste")
			(net "NC_CPU1_HBM2_VIEWDIG0")
		)
		(pad "AC80" smd circle
			(at 28.472384 -16.626332 270)
			(size 0.4318 0.4318)
			(layers "F.Cu" "F.Mask" "F.Paste")
			(net "UPI_CPU0_CPU1_P2P2_DN<6>")
		)
		(pad "AC82" smd circle
			(at 30.100016 -16.626332 270)
			(size 0.4318 0.4318)
			(layers "F.Cu" "F.Mask" "F.Paste")
			(net "UPI_CPU0_CPU1_P2P2_DP<7>")
		)
		(pad "AC84" smd circle
			(at 31.727902 -16.626332 270)
			(size 0.4318 0.4318)
			(layers "F.Cu" "F.Mask" "F.Paste")
			(net "GND")
		)
		(pad "AC86" smd circle
			(at 33.355534 -16.626332 270)
			(size 0.4318 0.4318)
			(layers "F.Cu" "F.Mask" "F.Paste")
			(net "P5E_CPU1_PE4_TX_DN<6>")
		)
		(pad "AC88" smd circle
			(at 34.98342 -16.626332 270)
			(size 0.4318 0.4318)
			(layers "F.Cu" "F.Mask" "F.Paste")
			(net "GND")
		)
		(pad "AC90" smd circle
			(at 36.611306 -16.626332 270)
			(size 0.4318 0.4318)
			(layers "F.Cu" "F.Mask" "F.Paste")
			(net "P5E_CPU1_PE4_RX_DP<6>")
		)
		(pad "AD2" smd circle
			(at -36.611306 -16.266668 270)
			(size 0.4318 0.4318)
			(layers "F.Cu" "F.Mask" "F.Paste")
			(net "UPI_CPU1_CPU0_P0P1_DN<7>")
		)
		(pad "AD4" smd circle
			(at -34.98342 -16.266668 270)
			(size 0.4318 0.4318)
			(layers "F.Cu" "F.Mask" "F.Paste")
			(net "GND")
		)
		(pad "AD6" smd circle
			(at -33.355534 -16.266668 270)
			(size 0.4318 0.4318)
			(layers "F.Cu" "F.Mask" "F.Paste")
			(net "UPI_CPU0_CPU1_P1P0_DP<7>")
		)
		(pad "AD8" smd circle
			(at -31.727902 -16.266668 270)
			(size 0.4318 0.4318)
			(layers "F.Cu" "F.Mask" "F.Paste")
			(net "GND")
		)
		(pad "AD10" smd circle
			(at -30.100016 -16.266668 270)
			(size 0.4318 0.4318)
			(layers "F.Cu" "F.Mask" "F.Paste")
			(net "P5E_CPU1_PE0_RX_DP<7>")
		)
		(pad "AD12" smd circle
			(at -28.472384 -16.266668 270)
			(size 0.4318 0.4318)
			(layers "F.Cu" "F.Mask" "F.Paste")
			(net "GND")
		)
		(pad "AD14" smd circle
			(at -26.844498 -16.266668 270)
			(size 0.4318 0.4318)
			(layers "F.Cu" "F.Mask" "F.Paste")
			(net "P5E_CPU1_PE0_TX_DP<6>")
		)
		(pad "AD16" smd circle
			(at -25.216612 -16.266668 270)
			(size 0.4318 0.4318)
			(layers "F.Cu" "F.Mask" "F.Paste")
			(net "GND")
		)
		(pad "AD18" smd circle
			(at -23.58898 -16.266668 270)
			(size 0.4318 0.4318)
			(layers "F.Cu" "F.Mask" "F.Paste")
			(net "M_C_CPU1_SB_DQS_DP<3>")
		)
		(pad "AD20" smd circle
			(at -21.961094 -16.266668 270)
			(size 0.4318 0.4318)
			(layers "F.Cu" "F.Mask" "F.Paste")
			(net "M_C_CPU1_SB_DQ<24>")
		)
		(pad "AD22" smd circle
			(at -20.333462 -16.266668 270)
			(size 0.4318 0.4318)
			(layers "F.Cu" "F.Mask" "F.Paste")
			(net "M_D_CPU1_SB_DQ<21>")
		)
		(pad "AD24" smd circle
			(at -18.705576 -16.266668 270)
			(size 0.4318 0.4318)
			(layers "F.Cu" "F.Mask" "F.Paste")
			(net "M_D_CPU1_SB_DQS_DP<2>")
		)
		(pad "AD26" smd circle
			(at -17.07769 -16.266668 270)
			(size 0.4318 0.4318)
			(layers "F.Cu" "F.Mask" "F.Paste")
			(net "M_D_CPU1_SB_DQ<16>")
		)
		(pad "AD28" smd circle
			(at -15.450058 -16.266668 270)
			(size 0.4318 0.4318)
			(layers "F.Cu" "F.Mask" "F.Paste")
			(net "M_C_CPU1_SB_DQ<13>")
		)
		(pad "AD30" smd circle
			(at -13.822426 -16.266668 270)
			(size 0.4318 0.4318)
			(layers "F.Cu" "F.Mask" "F.Paste")
			(net "M_C_CPU1_SB_DQS_DP<1>")
		)
		(pad "AD32" smd circle
			(at -12.19454 -16.266668 270)
			(size 0.4318 0.4318)
			(layers "F.Cu" "F.Mask" "F.Paste")
			(net "M_C_CPU1_SB_DQ<8>")
		)
		(pad "AD34" smd circle
			(at -10.566654 -16.266668 270)
			(size 0.4318 0.4318)
			(layers "F.Cu" "F.Mask" "F.Paste")
			(net "M_C_CPU1_SB_DQ<5>")
		)
		(pad "AD36" smd circle
			(at -8.939022 -16.266668 270)
			(size 0.4318 0.4318)
			(layers "F.Cu" "F.Mask" "F.Paste")
			(net "M_C_CPU1_SB_DQS_DP<0>")
		)
		(pad "AD38" smd circle
			(at -7.311136 -16.266668 270)
			(size 0.4318 0.4318)
			(layers "F.Cu" "F.Mask" "F.Paste")
			(net "M_C_CPU1_SB_DQ<0>")
		)
		(pad "AD40" smd circle
			(at -5.68325 -16.266668 270)
			(size 0.4318 0.4318)
			(layers "F.Cu" "F.Mask" "F.Paste")
			(net "M_D_CPU1_SB_CS_N<3>")
		)
		(pad "AD42" smd circle
			(at -4.055618 -16.266668 270)
			(size 0.4318 0.4318)
			(layers "F.Cu" "F.Mask" "F.Paste")
			(net "GND")
		)
		(pad "AD44" smd circle
			(at -2.427732 -16.266668 270)
			(size 0.4318 0.4318)
			(layers "F.Cu" "F.Mask" "F.Paste")
			(net "M_D_CPU1_SB_CA<2>")
		)
		(pad "AD47" smd circle
			(at 1.613916 -16.156686 270)
			(size 0.4318 0.4318)
			(layers "F.Cu" "F.Mask" "F.Paste")
			(net "M_C_CPU1_SA_RSP<1>")
		)
		(pad "AD49" smd circle
			(at 3.241802 -16.156686 270)
			(size 0.4318 0.4318)
			(layers "F.Cu" "F.Mask" "F.Paste")
			(net "M_C_CPU1_CLK_DP<0>")
		)
		(pad "AD51" smd circle
			(at 4.869434 -16.156686 270)
			(size 0.4318 0.4318)
			(layers "F.Cu" "F.Mask" "F.Paste")
			(net "M_D_CPU1_SA_RSP<0>")
		)
		(pad "AD53" smd circle
			(at 6.49732 -16.156686 270)
			(size 0.4318 0.4318)
			(layers "F.Cu" "F.Mask" "F.Paste")
			(net "M_C_CPU1_SA_CB<5>")
		)
		(pad "AD55" smd circle
			(at 8.124952 -16.156686 270)
			(size 0.4318 0.4318)
			(layers "F.Cu" "F.Mask" "F.Paste")
			(net "M_C_CPU1_SA_DQS_DN<4>")
		)
		(pad "AD57" smd circle
			(at 9.752838 -16.156686 270)
			(size 0.4318 0.4318)
			(layers "F.Cu" "F.Mask" "F.Paste")
			(net "M_C_CPU1_SA_CB<0>")
		)
		(pad "AD59" smd circle
			(at 11.380724 -16.156686 270)
			(size 0.4318 0.4318)
			(layers "F.Cu" "F.Mask" "F.Paste")
			(net "M_C_CPU1_SA_DQ<29>")
		)
		(pad "AD61" smd circle
			(at 13.008356 -16.156686 270)
			(size 0.4318 0.4318)
			(layers "F.Cu" "F.Mask" "F.Paste")
			(net "M_C_CPU1_SA_DQS_DP<3>")
		)
		(pad "AD63" smd circle
			(at 14.635988 -16.156686 270)
			(size 0.4318 0.4318)
			(layers "F.Cu" "F.Mask" "F.Paste")
			(net "M_C_CPU1_SA_DQ<24>")
		)
		(pad "AD65" smd circle
			(at 16.263874 -16.156686 270)
			(size 0.4318 0.4318)
			(layers "F.Cu" "F.Mask" "F.Paste")
			(net "M_C_CPU1_SA_DQ<13>")
		)
		(pad "AD67" smd circle
			(at 17.89176 -16.156686 270)
			(size 0.4318 0.4318)
			(layers "F.Cu" "F.Mask" "F.Paste")
			(net "M_C_CPU1_SA_DQS_DP<1>")
		)
		(pad "AD69" smd circle
			(at 19.519392 -16.156686 270)
			(size 0.4318 0.4318)
			(layers "F.Cu" "F.Mask" "F.Paste")
			(net "M_C_CPU1_SA_DQ<8>")
		)
		(pad "AD71" smd circle
			(at 21.147278 -16.156686 270)
			(size 0.4318 0.4318)
			(layers "F.Cu" "F.Mask" "F.Paste")
			(net "M_D_CPU1_SA_DQ<5>")
		)
		(pad "AD73" smd circle
			(at 22.77491 -16.156686 270)
			(size 0.4318 0.4318)
			(layers "F.Cu" "F.Mask" "F.Paste")
			(net "M_D_CPU1_SA_DQS_DP<0>")
		)
		(pad "AD75" smd circle
			(at 24.402796 -16.156686 270)
			(size 0.4318 0.4318)
			(layers "F.Cu" "F.Mask" "F.Paste")
			(net "M_D_CPU1_SA_DQ<0>")
		)
		(pad "AD77" smd circle
			(at 26.030682 -16.156686 270)
			(size 0.4318 0.4318)
			(layers "F.Cu" "F.Mask" "F.Paste")
			(net "NC_CPU1_HBM2_VIEWDIG1")
		)
		(pad "AD79" smd circle
			(at 27.658314 -16.156686 270)
			(size 0.4318 0.4318)
			(layers "F.Cu" "F.Mask" "F.Paste")
			(net "GND")
		)
		(pad "AD81" smd circle
			(at 29.2862 -16.156686 270)
			(size 0.4318 0.4318)
			(layers "F.Cu" "F.Mask" "F.Paste")
			(net "UPI_CPU0_CPU1_P2P2_DN<7>")
		)
		(pad "AD83" smd circle
			(at 30.914086 -16.156686 270)
			(size 0.4318 0.4318)
			(layers "F.Cu" "F.Mask" "F.Paste")
			(net "GND")
		)
		(pad "AD85" smd circle
			(at 32.541718 -16.156686 270)
			(size 0.4318 0.4318)
			(layers "F.Cu" "F.Mask" "F.Paste")
			(net "PVCCFA_EHV_FIVRA_CPU1")
		)
		(pad "AD87" smd circle
			(at 34.169604 -16.156686 270)
			(size 0.4318 0.4318)
			(layers "F.Cu" "F.Mask" "F.Paste")
			(net "P5E_CPU1_PE4_TX_DP<6>")
		)
		(pad "AD89" smd circle
			(at 35.797236 -16.156686 270)
			(size 0.4318 0.4318)
			(layers "F.Cu" "F.Mask" "F.Paste")
			(net "PVCCFA_EHV_FIVRA_CPU1")
		)
		(pad "AD91" smd oval
			(at 37.425122 -16.156686)
			(size 0.381 0.4826)
			(drill
				(offset 0 -0.0508)
			)
			(layers "F.Cu" "F.Mask" "F.Paste")
			(net "P5E_CPU1_PE4_RX_DN<6>")
		)
		(pad "AE1" smd oval
			(at -37.425122 -15.796514 180)
			(size 0.381 0.4826)
			(drill
				(offset 0 -0.0508)
			)
			(layers "F.Cu" "F.Mask" "F.Paste")
			(net "UPI_CPU1_CPU0_P0P1_DP<8>")
		)
		(pad "AE3" smd circle
			(at -35.797236 -15.796514 270)
			(size 0.4318 0.4318)
			(layers "F.Cu" "F.Mask" "F.Paste")
			(net "PVCCFA_EHV_CPU1")
		)
		(pad "AE5" smd circle
			(at -34.169604 -15.796514 270)
			(size 0.4318 0.4318)
			(layers "F.Cu" "F.Mask" "F.Paste")
			(net "UPI_CPU0_CPU1_P1P0_DN<7>")
		)
		(pad "AE7" smd circle
			(at -32.541718 -15.796514 270)
			(size 0.4318 0.4318)
			(layers "F.Cu" "F.Mask" "F.Paste")
			(net "PVCCFA_EHV_FIVRA_CPU1")
		)
		(pad "AE9" smd circle
			(at -30.914086 -15.796514 270)
			(size 0.4318 0.4318)
			(layers "F.Cu" "F.Mask" "F.Paste")
			(net "P5E_CPU1_PE0_RX_DN<7>")
		)
		(pad "AE11" smd circle
			(at -29.2862 -15.796514 270)
			(size 0.4318 0.4318)
			(layers "F.Cu" "F.Mask" "F.Paste")
			(net "PVCCFA_EHV_FIVRA_CPU1")
		)
		(pad "AE13" smd circle
			(at -27.658314 -15.796514 270)
			(size 0.4318 0.4318)
			(layers "F.Cu" "F.Mask" "F.Paste")
			(net "P5E_CPU1_PE0_TX_DN<6>")
		)
		(pad "AE15" smd circle
			(at -26.030682 -15.796514 270)
			(size 0.4318 0.4318)
			(layers "F.Cu" "F.Mask" "F.Paste")
			(net "PVCCFA_EHV_FIVRA_CPU1")
		)
		(pad "AE17" smd circle
			(at -24.402796 -15.796514 270)
			(size 0.4318 0.4318)
			(layers "F.Cu" "F.Mask" "F.Paste")
			(net "GND")
		)
		(pad "AE19" smd circle
			(at -22.77491 -15.796514 270)
			(size 0.4318 0.4318)
			(layers "F.Cu" "F.Mask" "F.Paste")
			(net "GND")
		)
		(pad "AE21" smd circle
			(at -21.147278 -15.796514 270)
			(size 0.4318 0.4318)
			(layers "F.Cu" "F.Mask" "F.Paste")
			(net "GND")
		)
		(pad "AE23" smd circle
			(at -19.519392 -15.796514 270)
			(size 0.4318 0.4318)
			(layers "F.Cu" "F.Mask" "F.Paste")
			(net "GND")
		)
		(pad "AE25" smd circle
			(at -17.89176 -15.796514 270)
			(size 0.4318 0.4318)
			(layers "F.Cu" "F.Mask" "F.Paste")
			(net "GND")
		)
		(pad "AE27" smd circle
			(at -16.263874 -15.796514 270)
			(size 0.4318 0.4318)
			(layers "F.Cu" "F.Mask" "F.Paste")
			(net "GND")
		)
		(pad "AE29" smd circle
			(at -14.635988 -15.796514 270)
			(size 0.4318 0.4318)
			(layers "F.Cu" "F.Mask" "F.Paste")
			(net "GND")
		)
		(pad "AE31" smd circle
			(at -13.008356 -15.796514 270)
			(size 0.4318 0.4318)
			(layers "F.Cu" "F.Mask" "F.Paste")
			(net "GND")
		)
		(pad "AE33" smd circle
			(at -11.380724 -15.796514 270)
			(size 0.4318 0.4318)
			(layers "F.Cu" "F.Mask" "F.Paste")
			(net "GND")
		)
		(pad "AE35" smd circle
			(at -9.752838 -15.796514 270)
			(size 0.4318 0.4318)
			(layers "F.Cu" "F.Mask" "F.Paste")
			(net "GND")
		)
		(pad "AE37" smd circle
			(at -8.124952 -15.796514 270)
			(size 0.4318 0.4318)
			(layers "F.Cu" "F.Mask" "F.Paste")
			(net "GND")
		)
		(pad "AE39" smd circle
			(at -6.49732 -15.796514 270)
			(size 0.4318 0.4318)
			(layers "F.Cu" "F.Mask" "F.Paste")
			(net "GND")
		)
		(pad "AE41" smd circle
			(at -4.869434 -15.796514 270)
			(size 0.4318 0.4318)
			(layers "F.Cu" "F.Mask" "F.Paste")
			(net "GND")
		)
		(pad "AE43" smd circle
			(at -3.241802 -15.796514 270)
			(size 0.4318 0.4318)
			(layers "F.Cu" "F.Mask" "F.Paste")
			(net "GND")
		)
		(pad "AE45" smd circle
			(at -1.613916 -15.796514 270)
			(size 0.4318 0.4318)
			(layers "F.Cu" "F.Mask" "F.Paste")
			(net "GND")
		)
		(pad "AE48" smd circle
			(at 2.427732 -15.686532 270)
			(size 0.4318 0.4318)
			(layers "F.Cu" "F.Mask" "F.Paste")
			(net "GND")
		)
		(pad "AE50" smd circle
			(at 4.055618 -15.686532 270)
			(size 0.4318 0.4318)
			(layers "F.Cu" "F.Mask" "F.Paste")
			(net "GND")
		)
		(pad "AE52" smd circle
			(at 5.68325 -15.686532 270)
			(size 0.4318 0.4318)
			(layers "F.Cu" "F.Mask" "F.Paste")
			(net "GND")
		)
		(pad "AE54" smd circle
			(at 7.311136 -15.686532 270)
			(size 0.4318 0.4318)
			(layers "F.Cu" "F.Mask" "F.Paste")
			(net "GND")
		)
		(pad "AE56" smd circle
			(at 8.939022 -15.686532 270)
			(size 0.4318 0.4318)
			(layers "F.Cu" "F.Mask" "F.Paste")
			(net "GND")
		)
		(pad "AE58" smd circle
			(at 10.566654 -15.686532 270)
			(size 0.4318 0.4318)
			(layers "F.Cu" "F.Mask" "F.Paste")
			(net "GND")
		)
		(pad "AE60" smd circle
			(at 12.19454 -15.686532 270)
			(size 0.4318 0.4318)
			(layers "F.Cu" "F.Mask" "F.Paste")
			(net "GND")
		)
		(pad "AE62" smd circle
			(at 13.822426 -15.686532 270)
			(size 0.4318 0.4318)
			(layers "F.Cu" "F.Mask" "F.Paste")
			(net "GND")
		)
		(pad "AE64" smd circle
			(at 15.450058 -15.686532 270)
			(size 0.4318 0.4318)
			(layers "F.Cu" "F.Mask" "F.Paste")
			(net "GND")
		)
		(pad "AE66" smd circle
			(at 17.07769 -15.686532 270)
			(size 0.4318 0.4318)
			(layers "F.Cu" "F.Mask" "F.Paste")
			(net "GND")
		)
		(pad "AE68" smd circle
			(at 18.705576 -15.686532 270)
			(size 0.4318 0.4318)
			(layers "F.Cu" "F.Mask" "F.Paste")
			(net "GND")
		)
		(pad "AE70" smd circle
			(at 20.333462 -15.686532 270)
			(size 0.4318 0.4318)
			(layers "F.Cu" "F.Mask" "F.Paste")
			(net "GND")
		)
		(pad "AE72" smd circle
			(at 21.961094 -15.686532 270)
			(size 0.4318 0.4318)
			(layers "F.Cu" "F.Mask" "F.Paste")
			(net "GND")
		)
		(pad "AE74" smd circle
			(at 23.58898 -15.686532 270)
			(size 0.4318 0.4318)
			(layers "F.Cu" "F.Mask" "F.Paste")
			(net "GND")
		)
		(pad "AE76" smd circle
			(at 25.216612 -15.686532 270)
			(size 0.4318 0.4318)
			(layers "F.Cu" "F.Mask" "F.Paste")
			(net "GND")
		)
		(pad "AE78" smd circle
			(at 26.844498 -15.686532 270)
			(size 0.4318 0.4318)
			(layers "F.Cu" "F.Mask" "F.Paste")
			(net "GND")
		)
		(pad "AE80" smd circle
			(at 28.472384 -15.686532 270)
			(size 0.4318 0.4318)
			(layers "F.Cu" "F.Mask" "F.Paste")
			(net "UPI_CPU0_CPU1_P2P2_DP<6>")
		)
		(pad "AE82" smd circle
			(at 30.100016 -15.686532 270)
			(size 0.4318 0.4318)
			(layers "F.Cu" "F.Mask" "F.Paste")
			(net "UPI_CPU0_CPU1_P2P2_DN<9>")
		)
		(pad "AE84" smd circle
			(at 31.727902 -15.686532 270)
			(size 0.4318 0.4318)
			(layers "F.Cu" "F.Mask" "F.Paste")
			(net "GND")
		)
		(pad "AE86" smd circle
			(at 33.355534 -15.686532 270)
			(size 0.4318 0.4318)
			(layers "F.Cu" "F.Mask" "F.Paste")
			(net "P5E_CPU1_PE4_TX_DN<7>")
		)
		(pad "AE88" smd circle
			(at 34.98342 -15.686532 270)
			(size 0.4318 0.4318)
			(layers "F.Cu" "F.Mask" "F.Paste")
			(net "GND")
		)
		(pad "AE90" smd circle
			(at 36.611306 -15.686532 270)
			(size 0.4318 0.4318)
			(layers "F.Cu" "F.Mask" "F.Paste")
			(net "P5E_CPU1_PE4_RX_DP<7>")
		)
		(pad "AF2" smd circle
			(at -36.611306 -15.326868 270)
			(size 0.4318 0.4318)
			(layers "F.Cu" "F.Mask" "F.Paste")
			(net "UPI_CPU1_CPU0_P0P1_DN<8>")
		)
		(pad "AF4" smd circle
			(at -34.98342 -15.326868 270)
			(size 0.4318 0.4318)
			(layers "F.Cu" "F.Mask" "F.Paste")
			(net "GND")
		)
		(pad "AF6" smd circle
			(at -33.355534 -15.326868 270)
			(size 0.4318 0.4318)
			(layers "F.Cu" "F.Mask" "F.Paste")
			(net "UPI_CPU0_CPU1_P1P0_DN<8>")
		)
		(pad "AF8" smd circle
			(at -31.727902 -15.326868 270)
			(size 0.4318 0.4318)
			(layers "F.Cu" "F.Mask" "F.Paste")
			(net "GND")
		)
		(pad "AF10" smd circle
			(at -30.100016 -15.326868 270)
			(size 0.4318 0.4318)
			(layers "F.Cu" "F.Mask" "F.Paste")
			(net "P5E_CPU1_PE0_RX_DN<8>")
		)
		(pad "AF12" smd circle
			(at -28.472384 -15.326868 270)
			(size 0.4318 0.4318)
			(layers "F.Cu" "F.Mask" "F.Paste")
			(net "GND")
		)
		(pad "AF14" smd circle
			(at -26.844498 -15.326868 270)
			(size 0.4318 0.4318)
			(layers "F.Cu" "F.Mask" "F.Paste")
			(net "P5E_CPU1_PE0_TX_DN<7>")
		)
		(pad "AF16" smd circle
			(at -25.216612 -15.326868 270)
			(size 0.4318 0.4318)
			(layers "F.Cu" "F.Mask" "F.Paste")
			(net "GND")
		)
		(pad "AF18" smd circle
			(at -23.58898 -15.326868 270)
			(size 0.4318 0.4318)
			(layers "F.Cu" "F.Mask" "F.Paste")
			(net "M_C_CPU1_SB_DQS_DN<8>")
		)
		(pad "AF20" smd circle
			(at -21.961094 -15.326868 270)
			(size 0.4318 0.4318)
			(layers "F.Cu" "F.Mask" "F.Paste")
			(net "M_C_CPU1_SB_DQ<26>")
		)
		(pad "AF22" smd circle
			(at -20.333462 -15.326868 270)
			(size 0.4318 0.4318)
			(layers "F.Cu" "F.Mask" "F.Paste")
			(net "M_D_CPU1_SB_DQ<23>")
		)
		(pad "AF24" smd circle
			(at -18.705576 -15.326868 270)
			(size 0.4318 0.4318)
			(layers "F.Cu" "F.Mask" "F.Paste")
			(net "M_D_CPU1_SB_DQS_DN<7>")
		)
		(pad "AF26" smd circle
			(at -17.07769 -15.326868 270)
			(size 0.4318 0.4318)
			(layers "F.Cu" "F.Mask" "F.Paste")
			(net "M_D_CPU1_SB_DQ<18>")
		)
		(pad "AF28" smd circle
			(at -15.450058 -15.326868 270)
			(size 0.4318 0.4318)
			(layers "F.Cu" "F.Mask" "F.Paste")
			(net "M_C_CPU1_SB_DQ<15>")
		)
		(pad "AF30" smd circle
			(at -13.822426 -15.326868 270)
			(size 0.4318 0.4318)
			(layers "F.Cu" "F.Mask" "F.Paste")
			(net "M_C_CPU1_SB_DQS_DN<6>")
		)
		(pad "AF32" smd circle
			(at -12.19454 -15.326868 270)
			(size 0.4318 0.4318)
			(layers "F.Cu" "F.Mask" "F.Paste")
			(net "M_C_CPU1_SB_DQ<10>")
		)
		(pad "AF34" smd circle
			(at -10.566654 -15.326868 270)
			(size 0.4318 0.4318)
			(layers "F.Cu" "F.Mask" "F.Paste")
			(net "M_C_CPU1_SB_DQ<7>")
		)
		(pad "AF36" smd circle
			(at -8.939022 -15.326868 270)
			(size 0.4318 0.4318)
			(layers "F.Cu" "F.Mask" "F.Paste")
			(net "M_C_CPU1_SB_DQS_DN<5>")
		)
		(pad "AF38" smd circle
			(at -7.311136 -15.326868 270)
			(size 0.4318 0.4318)
			(layers "F.Cu" "F.Mask" "F.Paste")
			(net "M_C_CPU1_SB_DQ<2>")
		)
		(pad "AF40" smd circle
			(at -5.68325 -15.326868 270)
			(size 0.4318 0.4318)
			(layers "F.Cu" "F.Mask" "F.Paste")
			(net "M_D_CPU1_SB_CS_N<2>")
		)
		(pad "AF42" smd circle
			(at -4.055618 -15.326868 270)
			(size 0.4318 0.4318)
			(layers "F.Cu" "F.Mask" "F.Paste")
			(net "GND")
		)
		(pad "AF44" smd circle
			(at -2.427732 -15.326868 270)
			(size 0.4318 0.4318)
			(layers "F.Cu" "F.Mask" "F.Paste")
			(net "M_D_CPU1_SB_CA<3>")
		)
		(pad "AF47" smd circle
			(at 1.613916 -15.216886 270)
			(size 0.4318 0.4318)
			(layers "F.Cu" "F.Mask" "F.Paste")
			(net "M_C_CPU1_SB_RSP<1>")
		)
		(pad "AF49" smd circle
			(at 3.241802 -15.216886 270)
			(size 0.4318 0.4318)
			(layers "F.Cu" "F.Mask" "F.Paste")
			(net "M_C_CPU1_CLK_DN<1>")
		)
		(pad "AF51" smd circle
			(at 4.869434 -15.216886 270)
			(size 0.4318 0.4318)
			(layers "F.Cu" "F.Mask" "F.Paste")
			(net "M_D_CPU1_SB_RSP<0>")
		)
		(pad "AF53" smd circle
			(at 6.49732 -15.216886 270)
			(size 0.4318 0.4318)
			(layers "F.Cu" "F.Mask" "F.Paste")
			(net "M_C_CPU1_SA_CB<7>")
		)
		(pad "AF55" smd circle
			(at 8.124952 -15.216886 270)
			(size 0.4318 0.4318)
			(layers "F.Cu" "F.Mask" "F.Paste")
			(net "M_C_CPU1_SA_DQS_DP<9>")
		)
		(pad "AF57" smd circle
			(at 9.752838 -15.216886 270)
			(size 0.4318 0.4318)
			(layers "F.Cu" "F.Mask" "F.Paste")
			(net "M_C_CPU1_SA_CB<2>")
		)
		(pad "AF59" smd circle
			(at 11.380724 -15.216886 270)
			(size 0.4318 0.4318)
			(layers "F.Cu" "F.Mask" "F.Paste")
			(net "M_C_CPU1_SA_DQ<31>")
		)
		(pad "AF61" smd circle
			(at 13.008356 -15.216886 270)
			(size 0.4318 0.4318)
			(layers "F.Cu" "F.Mask" "F.Paste")
			(net "M_C_CPU1_SA_DQS_DN<8>")
		)
		(pad "AF63" smd circle
			(at 14.635988 -15.216886 270)
			(size 0.4318 0.4318)
			(layers "F.Cu" "F.Mask" "F.Paste")
			(net "M_C_CPU1_SA_DQ<26>")
		)
		(pad "AF65" smd circle
			(at 16.263874 -15.216886 270)
			(size 0.4318 0.4318)
			(layers "F.Cu" "F.Mask" "F.Paste")
			(net "M_C_CPU1_SA_DQ<15>")
		)
		(pad "AF67" smd circle
			(at 17.89176 -15.216886 270)
			(size 0.4318 0.4318)
			(layers "F.Cu" "F.Mask" "F.Paste")
			(net "M_C_CPU1_SA_DQS_DP<6>")
		)
		(pad "AF69" smd circle
			(at 19.519392 -15.216886 270)
			(size 0.4318 0.4318)
			(layers "F.Cu" "F.Mask" "F.Paste")
			(net "M_C_CPU1_SA_DQ<10>")
		)
		(pad "AF71" smd circle
			(at 21.147278 -15.216886 270)
			(size 0.4318 0.4318)
			(layers "F.Cu" "F.Mask" "F.Paste")
			(net "M_D_CPU1_SA_DQ<7>")
		)
		(pad "AF73" smd circle
			(at 22.77491 -15.216886 270)
			(size 0.4318 0.4318)
			(layers "F.Cu" "F.Mask" "F.Paste")
			(net "M_D_CPU1_SA_DQS_DP<5>")
		)
		(pad "AF75" smd circle
			(at 24.402796 -15.216886 270)
			(size 0.4318 0.4318)
			(layers "F.Cu" "F.Mask" "F.Paste")
			(net "M_D_CPU1_SA_DQ<2>")
		)
		(pad "AF77" smd circle
			(at 26.030682 -15.216886 270)
			(size 0.4318 0.4318)
			(layers "F.Cu" "F.Mask" "F.Paste")
			(net "PVCCFA_EHV_FIVRA_CPU1")
		)
		(pad "AF79" smd circle
			(at 27.658314 -15.216886 270)
			(size 0.4318 0.4318)
			(layers "F.Cu" "F.Mask" "F.Paste")
			(net "UPI_CPU0_CPU1_P2P2_DN<8>")
		)
		(pad "AF81" smd circle
			(at 29.2862 -15.216886 270)
			(size 0.4318 0.4318)
			(layers "F.Cu" "F.Mask" "F.Paste")
			(net "GND")
		)
		(pad "AF83" smd circle
			(at 30.914086 -15.216886 270)
			(size 0.4318 0.4318)
			(layers "F.Cu" "F.Mask" "F.Paste")
			(net "UPI_CPU0_CPU1_P2P2_DP<9>")
		)
		(pad "AF85" smd circle
			(at 32.541718 -15.216886 270)
			(size 0.4318 0.4318)
			(layers "F.Cu" "F.Mask" "F.Paste")
			(net "P5E_CPU1_PE4_TX_DP<7>")
		)
		(pad "AF87" smd circle
			(at 34.169604 -15.216886 270)
			(size 0.4318 0.4318)
			(layers "F.Cu" "F.Mask" "F.Paste")
			(net "GND")
		)
		(pad "AF89" smd circle
			(at 35.797236 -15.216886 270)
			(size 0.4318 0.4318)
			(layers "F.Cu" "F.Mask" "F.Paste")
			(net "P5E_CPU1_PE4_RX_DN<7>")
		)
		(pad "AF91" smd oval
			(at 37.425122 -15.216886)
			(size 0.381 0.4826)
			(drill
				(offset 0 -0.0508)
			)
			(layers "F.Cu" "F.Mask" "F.Paste")
			(net "GND")
		)
		(pad "AG1" smd oval
			(at -37.425122 -14.856714 180)
			(size 0.381 0.4826)
			(drill
				(offset 0 -0.0508)
			)
			(layers "F.Cu" "F.Mask" "F.Paste")
			(net "GND")
		)
		(pad "AG3" smd circle
			(at -35.797236 -14.856714 270)
			(size 0.4318 0.4318)
			(layers "F.Cu" "F.Mask" "F.Paste")
			(net "UPI_CPU1_CPU0_P0P1_DP<9>")
		)
		(pad "AG5" smd circle
			(at -34.169604 -14.856714 270)
			(size 0.4318 0.4318)
			(layers "F.Cu" "F.Mask" "F.Paste")
			(net "GND")
		)
		(pad "AG7" smd circle
			(at -32.541718 -14.856714 270)
			(size 0.4318 0.4318)
			(layers "F.Cu" "F.Mask" "F.Paste")
			(net "UPI_CPU0_CPU1_P1P0_DP<8>")
		)
		(pad "AG9" smd circle
			(at -30.914086 -14.856714 270)
			(size 0.4318 0.4318)
			(layers "F.Cu" "F.Mask" "F.Paste")
			(net "GND")
		)
		(pad "AG11" smd circle
			(at -29.2862 -14.856714 270)
			(size 0.4318 0.4318)
			(layers "F.Cu" "F.Mask" "F.Paste")
			(net "P5E_CPU1_PE0_RX_DP<8>")
		)
		(pad "AG13" smd circle
			(at -27.658314 -14.856714 270)
			(size 0.4318 0.4318)
			(layers "F.Cu" "F.Mask" "F.Paste")
			(net "GND")
		)
		(pad "AG15" smd circle
			(at -26.030682 -14.856714 270)
			(size 0.4318 0.4318)
			(layers "F.Cu" "F.Mask" "F.Paste")
			(net "P5E_CPU1_PE0_TX_DP<7>")
		)
		(pad "AG17" smd circle
			(at -24.402796 -14.856714 270)
			(size 0.4318 0.4318)
			(layers "F.Cu" "F.Mask" "F.Paste")
			(net "M_C_CPU1_SB_DQ<29>")
		)
		(pad "AG19" smd circle
			(at -22.77491 -14.856714 270)
			(size 0.4318 0.4318)
			(layers "F.Cu" "F.Mask" "F.Paste")
			(net "M_C_CPU1_SB_DQ<27>")
		)
		(pad "AG21" smd circle
			(at -21.147278 -14.856714 270)
			(size 0.4318 0.4318)
			(layers "F.Cu" "F.Mask" "F.Paste")
			(net "GND")
		)
		(pad "AG23" smd circle
			(at -19.519392 -14.856714 270)
			(size 0.4318 0.4318)
			(layers "F.Cu" "F.Mask" "F.Paste")
			(net "M_D_CPU1_SB_DQ<22>")
		)
		(pad "AG25" smd circle
			(at -17.89176 -14.856714 270)
			(size 0.4318 0.4318)
			(layers "F.Cu" "F.Mask" "F.Paste")
			(net "M_D_CPU1_SB_DQ<19>")
		)
		(pad "AG27" smd circle
			(at -16.263874 -14.856714 270)
			(size 0.4318 0.4318)
			(layers "F.Cu" "F.Mask" "F.Paste")
			(net "GND")
		)
		(pad "AG29" smd circle
			(at -14.635988 -14.856714 270)
			(size 0.4318 0.4318)
			(layers "F.Cu" "F.Mask" "F.Paste")
			(net "M_C_CPU1_SB_DQ<14>")
		)
		(pad "AG31" smd circle
			(at -13.008356 -14.856714 270)
			(size 0.4318 0.4318)
			(layers "F.Cu" "F.Mask" "F.Paste")
			(net "M_C_CPU1_SB_DQ<11>")
		)
		(pad "AG33" smd circle
			(at -11.380724 -14.856714 270)
			(size 0.4318 0.4318)
			(layers "F.Cu" "F.Mask" "F.Paste")
			(net "GND")
		)
		(pad "AG35" smd circle
			(at -9.752838 -14.856714 270)
			(size 0.4318 0.4318)
			(layers "F.Cu" "F.Mask" "F.Paste")
			(net "M_C_CPU1_SB_DQ<6>")
		)
		(pad "AG37" smd circle
			(at -8.124952 -14.856714 270)
			(size 0.4318 0.4318)
			(layers "F.Cu" "F.Mask" "F.Paste")
			(net "M_C_CPU1_SB_DQ<3>")
		)
		(pad "AG39" smd circle
			(at -6.49732 -14.856714 270)
			(size 0.4318 0.4318)
			(layers "F.Cu" "F.Mask" "F.Paste")
			(net "GND")
		)
		(pad "AG41" smd circle
			(at -4.869434 -14.856714 270)
			(size 0.4318 0.4318)
			(layers "F.Cu" "F.Mask" "F.Paste")
			(net "M_D_CPU1_SB_CS_N<1>")
		)
		(pad "AG43" smd circle
			(at -3.241802 -14.856714 270)
			(size 0.4318 0.4318)
			(layers "F.Cu" "F.Mask" "F.Paste")
			(net "M_D_CPU1_SB_CA<5>")
		)
		(pad "AG45" smd circle
			(at -1.613916 -14.856714 270)
			(size 0.4318 0.4318)
			(layers "F.Cu" "F.Mask" "F.Paste")
			(net "GND")
		)
		(pad "AG48" smd circle
			(at 2.427732 -14.746732 270)
			(size 0.4318 0.4318)
			(layers "F.Cu" "F.Mask" "F.Paste")
			(net "M_C_CPU1_SB_RSP<0>")
		)
		(pad "AG50" smd circle
			(at 4.055618 -14.746732 270)
			(size 0.4318 0.4318)
			(layers "F.Cu" "F.Mask" "F.Paste")
			(net "M_D_CPU1_SB_RSP<1>")
		)
		(pad "AG52" smd circle
			(at 5.68325 -14.746732 270)
			(size 0.4318 0.4318)
			(layers "F.Cu" "F.Mask" "F.Paste")
			(net "GND")
		)
		(pad "AG54" smd circle
			(at 7.311136 -14.746732 270)
			(size 0.4318 0.4318)
			(layers "F.Cu" "F.Mask" "F.Paste")
			(net "M_C_CPU1_SA_CB<6>")
		)
		(pad "AG56" smd circle
			(at 8.939022 -14.746732 270)
			(size 0.4318 0.4318)
			(layers "F.Cu" "F.Mask" "F.Paste")
			(net "M_C_CPU1_SA_CB<3>")
		)
		(pad "AG58" smd circle
			(at 10.566654 -14.746732 270)
			(size 0.4318 0.4318)
			(layers "F.Cu" "F.Mask" "F.Paste")
			(net "GND")
		)
		(pad "AG60" smd circle
			(at 12.19454 -14.746732 270)
			(size 0.4318 0.4318)
			(layers "F.Cu" "F.Mask" "F.Paste")
			(net "M_C_CPU1_SA_DQ<30>")
		)
		(pad "AG62" smd circle
			(at 13.822426 -14.746732 270)
			(size 0.4318 0.4318)
			(layers "F.Cu" "F.Mask" "F.Paste")
			(net "M_C_CPU1_SA_DQ<27>")
		)
		(pad "AG64" smd circle
			(at 15.450058 -14.746732 270)
			(size 0.4318 0.4318)
			(layers "F.Cu" "F.Mask" "F.Paste")
			(net "GND")
		)
		(pad "AG66" smd circle
			(at 17.07769 -14.746732 270)
			(size 0.4318 0.4318)
			(layers "F.Cu" "F.Mask" "F.Paste")
			(net "M_C_CPU1_SA_DQ<14>")
		)
		(pad "AG68" smd circle
			(at 18.705576 -14.746732 270)
			(size 0.4318 0.4318)
			(layers "F.Cu" "F.Mask" "F.Paste")
			(net "M_C_CPU1_SA_DQ<11>")
		)
		(pad "AG70" smd circle
			(at 20.333462 -14.746732 270)
			(size 0.4318 0.4318)
			(layers "F.Cu" "F.Mask" "F.Paste")
			(net "GND")
		)
		(pad "AG72" smd circle
			(at 21.961094 -14.746732 270)
			(size 0.4318 0.4318)
			(layers "F.Cu" "F.Mask" "F.Paste")
			(net "M_D_CPU1_SA_DQ<6>")
		)
		(pad "AG74" smd circle
			(at 23.58898 -14.746732 270)
			(size 0.4318 0.4318)
			(layers "F.Cu" "F.Mask" "F.Paste")
			(net "M_D_CPU1_SA_DQ<3>")
		)
		(pad "AG76" smd circle
			(at 25.216612 -14.746732 270)
			(size 0.4318 0.4318)
			(layers "F.Cu" "F.Mask" "F.Paste")
			(net "GND")
		)
		(pad "AG78" smd circle
			(at 26.844498 -14.746732 270)
			(size 0.4318 0.4318)
			(layers "F.Cu" "F.Mask" "F.Paste")
			(net "PVCCFA_EHV_FIVRA_CPU1")
		)
		(pad "AG80" smd circle
			(at 28.472384 -14.746732 270)
			(size 0.4318 0.4318)
			(layers "F.Cu" "F.Mask" "F.Paste")
			(net "UPI_CPU0_CPU1_P2P2_DP<8>")
		)
		(pad "AG82" smd circle
			(at 30.100016 -14.746732 270)
			(size 0.4318 0.4318)
			(layers "F.Cu" "F.Mask" "F.Paste")
			(net "UPI_CPU0_CPU1_P2P2_DN<11>")
		)
		(pad "AG84" smd circle
			(at 31.727902 -14.746732 270)
			(size 0.4318 0.4318)
			(layers "F.Cu" "F.Mask" "F.Paste")
			(net "GND")
		)
		(pad "AG86" smd circle
			(at 33.355534 -14.746732 270)
			(size 0.4318 0.4318)
			(layers "F.Cu" "F.Mask" "F.Paste")
			(net "P5E_CPU1_PE4_TX_DN<8>")
		)
		(pad "AG88" smd circle
			(at 34.98342 -14.746732 270)
			(size 0.4318 0.4318)
			(layers "F.Cu" "F.Mask" "F.Paste")
			(net "GND")
		)
		(pad "AG90" smd circle
			(at 36.611306 -14.746732 270)
			(size 0.4318 0.4318)
			(layers "F.Cu" "F.Mask" "F.Paste")
			(net "P5E_CPU1_PE4_RX_DP<8>")
		)
		(pad "AH2" smd circle
			(at -36.611306 -14.387068 270)
			(size 0.4318 0.4318)
			(layers "F.Cu" "F.Mask" "F.Paste")
			(net "UPI_CPU1_CPU0_P0P1_DN<9>")
		)
		(pad "AH4" smd circle
			(at -34.98342 -14.387068 270)
			(size 0.4318 0.4318)
			(layers "F.Cu" "F.Mask" "F.Paste")
			(net "GND")
		)
		(pad "AH6" smd circle
			(at -33.355534 -14.387068 270)
			(size 0.4318 0.4318)
			(layers "F.Cu" "F.Mask" "F.Paste")
			(net "UPI_CPU0_CPU1_P1P0_DN<9>")
		)
		(pad "AH8" smd circle
			(at -31.727902 -14.387068 270)
			(size 0.4318 0.4318)
			(layers "F.Cu" "F.Mask" "F.Paste")
			(net "GND")
		)
		(pad "AH10" smd circle
			(at -30.100016 -14.387068 270)
			(size 0.4318 0.4318)
			(layers "F.Cu" "F.Mask" "F.Paste")
			(net "P5E_CPU1_PE0_RX_DP<9>")
		)
		(pad "AH12" smd circle
			(at -28.472384 -14.387068 270)
			(size 0.4318 0.4318)
			(layers "F.Cu" "F.Mask" "F.Paste")
			(net "GND")
		)
		(pad "AH14" smd circle
			(at -26.844498 -14.387068 270)
			(size 0.4318 0.4318)
			(layers "F.Cu" "F.Mask" "F.Paste")
			(net "P5E_CPU1_PE0_TX_DP<8>")
		)
		(pad "AH16" smd circle
			(at -25.216612 -14.387068 270)
			(size 0.4318 0.4318)
			(layers "F.Cu" "F.Mask" "F.Paste")
			(net "GND")
		)
		(pad "AH18" smd circle
			(at -23.58898 -14.387068 270)
			(size 0.4318 0.4318)
			(layers "F.Cu" "F.Mask" "F.Paste")
			(net "M_C_CPU1_SB_DQS_DP<8>")
		)
		(pad "AH20" smd circle
			(at -21.961094 -14.387068 270)
			(size 0.4318 0.4318)
			(layers "F.Cu" "F.Mask" "F.Paste")
			(net "GND")
		)
		(pad "AH22" smd circle
			(at -20.333462 -14.387068 270)
			(size 0.4318 0.4318)
			(layers "F.Cu" "F.Mask" "F.Paste")
			(net "GND")
		)
		(pad "AH24" smd circle
			(at -18.705576 -14.387068 270)
			(size 0.4318 0.4318)
			(layers "F.Cu" "F.Mask" "F.Paste")
			(net "M_D_CPU1_SB_DQS_DP<7>")
		)
		(pad "AH26" smd circle
			(at -17.07769 -14.387068 270)
			(size 0.4318 0.4318)
			(layers "F.Cu" "F.Mask" "F.Paste")
			(net "GND")
		)
		(pad "AH28" smd circle
			(at -15.450058 -14.387068 270)
			(size 0.4318 0.4318)
			(layers "F.Cu" "F.Mask" "F.Paste")
			(net "GND")
		)
		(pad "AH30" smd circle
			(at -13.822426 -14.387068 270)
			(size 0.4318 0.4318)
			(layers "F.Cu" "F.Mask" "F.Paste")
			(net "M_C_CPU1_SB_DQS_DP<6>")
		)
		(pad "AH32" smd circle
			(at -12.19454 -14.387068 270)
			(size 0.4318 0.4318)
			(layers "F.Cu" "F.Mask" "F.Paste")
			(net "GND")
		)
		(pad "AH34" smd circle
			(at -10.566654 -14.387068 270)
			(size 0.4318 0.4318)
			(layers "F.Cu" "F.Mask" "F.Paste")
			(net "GND")
		)
		(pad "AH36" smd circle
			(at -8.939022 -14.387068 270)
			(size 0.4318 0.4318)
			(layers "F.Cu" "F.Mask" "F.Paste")
			(net "M_C_CPU1_SB_DQS_DP<5>")
		)
		(pad "AH38" smd circle
			(at -7.311136 -14.387068 270)
			(size 0.4318 0.4318)
			(layers "F.Cu" "F.Mask" "F.Paste")
			(net "GND")
		)
		(pad "AH40" smd circle
			(at -5.68325 -14.387068 270)
			(size 0.4318 0.4318)
			(layers "F.Cu" "F.Mask" "F.Paste")
			(net "GND")
		)
		(pad "AH42" smd circle
			(at -4.055618 -14.387068 270)
			(size 0.4318 0.4318)
			(layers "F.Cu" "F.Mask" "F.Paste")
			(net "M_D_CPU1_SB_PAR")
		)
		(pad "AH44" smd circle
			(at -2.427732 -14.387068 270)
			(size 0.4318 0.4318)
			(layers "F.Cu" "F.Mask" "F.Paste")
			(net "GND")
		)
		(pad "AH47" smd circle
			(at 1.613916 -14.277086 270)
			(size 0.4318 0.4318)
			(layers "F.Cu" "F.Mask" "F.Paste")
			(net "GND")
		)
		(pad "AH49" smd circle
			(at 3.241802 -14.277086 270)
			(size 0.4318 0.4318)
			(layers "F.Cu" "F.Mask" "F.Paste")
			(net "M_C_CPU1_CLK_DP<1>")
		)
		(pad "AH51" smd circle
			(at 4.869434 -14.277086 270)
			(size 0.4318 0.4318)
			(layers "F.Cu" "F.Mask" "F.Paste")
			(net "GND")
		)
		(pad "AH53" smd circle
			(at 6.49732 -14.277086 270)
			(size 0.4318 0.4318)
			(layers "F.Cu" "F.Mask" "F.Paste")
			(net "GND")
		)
		(pad "AH55" smd circle
			(at 8.124952 -14.277086 270)
			(size 0.4318 0.4318)
			(layers "F.Cu" "F.Mask" "F.Paste")
			(net "M_C_CPU1_SA_DQS_DN<9>")
		)
		(pad "AH57" smd circle
			(at 9.752838 -14.277086 270)
			(size 0.4318 0.4318)
			(layers "F.Cu" "F.Mask" "F.Paste")
			(net "GND")
		)
		(pad "AH59" smd circle
			(at 11.380724 -14.277086 270)
			(size 0.4318 0.4318)
			(layers "F.Cu" "F.Mask" "F.Paste")
			(net "GND")
		)
		(pad "AH61" smd circle
			(at 13.008356 -14.277086 270)
			(size 0.4318 0.4318)
			(layers "F.Cu" "F.Mask" "F.Paste")
			(net "M_C_CPU1_SA_DQS_DP<8>")
		)
		(pad "AH63" smd circle
			(at 14.635988 -14.277086 270)
			(size 0.4318 0.4318)
			(layers "F.Cu" "F.Mask" "F.Paste")
			(net "GND")
		)
		(pad "AH65" smd circle
			(at 16.263874 -14.277086 270)
			(size 0.4318 0.4318)
			(layers "F.Cu" "F.Mask" "F.Paste")
			(net "GND")
		)
		(pad "AH67" smd circle
			(at 17.89176 -14.277086 270)
			(size 0.4318 0.4318)
			(layers "F.Cu" "F.Mask" "F.Paste")
			(net "M_C_CPU1_SA_DQS_DN<6>")
		)
		(pad "AH69" smd circle
			(at 19.519392 -14.277086 270)
			(size 0.4318 0.4318)
			(layers "F.Cu" "F.Mask" "F.Paste")
			(net "GND")
		)
		(pad "AH71" smd circle
			(at 21.147278 -14.277086 270)
			(size 0.4318 0.4318)
			(layers "F.Cu" "F.Mask" "F.Paste")
			(net "GND")
		)
		(pad "AH73" smd circle
			(at 22.77491 -14.277086 270)
			(size 0.4318 0.4318)
			(layers "F.Cu" "F.Mask" "F.Paste")
			(net "M_D_CPU1_SA_DQS_DN<5>")
		)
		(pad "AH75" smd circle
			(at 24.402796 -14.277086 270)
			(size 0.4318 0.4318)
			(layers "F.Cu" "F.Mask" "F.Paste")
			(net "GND")
		)
		(pad "AH77" smd circle
			(at 26.030682 -14.277086 270)
			(size 0.4318 0.4318)
			(layers "F.Cu" "F.Mask" "F.Paste")
			(net "GND")
		)
		(pad "AH79" smd circle
			(at 27.658314 -14.277086 270)
			(size 0.4318 0.4318)
			(layers "F.Cu" "F.Mask" "F.Paste")
			(net "GND")
		)
		(pad "AH81" smd circle
			(at 29.2862 -14.277086 270)
			(size 0.4318 0.4318)
			(layers "F.Cu" "F.Mask" "F.Paste")
			(net "UPI_CPU0_CPU1_P2P2_DP<10>")
		)
		(pad "AH83" smd circle
			(at 30.914086 -14.277086 270)
			(size 0.4318 0.4318)
			(layers "F.Cu" "F.Mask" "F.Paste")
			(net "GND")
		)
		(pad "AH85" smd circle
			(at 32.541718 -14.277086 270)
			(size 0.4318 0.4318)
			(layers "F.Cu" "F.Mask" "F.Paste")
			(net "PVCCFA_EHV_FIVRA_CPU1")
		)
		(pad "AH87" smd circle
			(at 34.169604 -14.277086 270)
			(size 0.4318 0.4318)
			(layers "F.Cu" "F.Mask" "F.Paste")
			(net "P5E_CPU1_PE4_TX_DP<8>")
		)
		(pad "AH89" smd circle
			(at 35.797236 -14.277086 270)
			(size 0.4318 0.4318)
			(layers "F.Cu" "F.Mask" "F.Paste")
			(net "PVCCFA_EHV_FIVRA_CPU1")
		)
		(pad "AH91" smd oval
			(at 37.425122 -14.277086)
			(size 0.381 0.4826)
			(drill
				(offset 0 -0.0508)
			)
			(layers "F.Cu" "F.Mask" "F.Paste")
			(net "P5E_CPU1_PE4_RX_DN<8>")
		)
		(pad "AJ1" smd oval
			(at -37.425122 -13.916914 180)
			(size 0.381 0.4826)
			(drill
				(offset 0 -0.0508)
			)
			(layers "F.Cu" "F.Mask" "F.Paste")
			(net "UPI_CPU1_CPU0_P0P1_DP<10>")
		)
		(pad "AJ3" smd circle
			(at -35.797236 -13.916914 270)
			(size 0.4318 0.4318)
			(layers "F.Cu" "F.Mask" "F.Paste")
			(net "PVCCFA_EHV_CPU1")
		)
		(pad "AJ5" smd circle
			(at -34.169604 -13.916914 270)
			(size 0.4318 0.4318)
			(layers "F.Cu" "F.Mask" "F.Paste")
			(net "UPI_CPU0_CPU1_P1P0_DP<9>")
		)
		(pad "AJ7" smd circle
			(at -32.541718 -13.916914 270)
			(size 0.4318 0.4318)
			(layers "F.Cu" "F.Mask" "F.Paste")
			(net "PVCCFA_EHV_FIVRA_CPU1")
		)
		(pad "AJ9" smd circle
			(at -30.914086 -13.916914 270)
			(size 0.4318 0.4318)
			(layers "F.Cu" "F.Mask" "F.Paste")
			(net "P5E_CPU1_PE0_RX_DN<9>")
		)
		(pad "AJ11" smd circle
			(at -29.2862 -13.916914 270)
			(size 0.4318 0.4318)
			(layers "F.Cu" "F.Mask" "F.Paste")
			(net "PVCCFA_EHV_FIVRA_CPU1")
		)
		(pad "AJ13" smd circle
			(at -27.658314 -13.916914 270)
			(size 0.4318 0.4318)
			(layers "F.Cu" "F.Mask" "F.Paste")
			(net "P5E_CPU1_PE0_TX_DN<8>")
		)
		(pad "AJ15" smd circle
			(at -26.030682 -13.916914 270)
			(size 0.4318 0.4318)
			(layers "F.Cu" "F.Mask" "F.Paste")
			(net "PVCCFA_EHV_FIVRA_CPU1")
		)
		(pad "AJ17" smd circle
			(at -24.402796 -13.916914 270)
			(size 0.4318 0.4318)
			(layers "F.Cu" "F.Mask" "F.Paste")
			(net "M_C_CPU1_SB_DQ<31>")
		)
		(pad "AJ19" smd circle
			(at -22.77491 -13.916914 270)
			(size 0.4318 0.4318)
			(layers "F.Cu" "F.Mask" "F.Paste")
			(net "GND")
		)
		(pad "AJ21" smd circle
			(at -21.147278 -13.916914 270)
			(size 0.4318 0.4318)
			(layers "F.Cu" "F.Mask" "F.Paste")
			(net "M_D_CPU1_SB_DQS_DN<3>")
		)
		(pad "AJ23" smd circle
			(at -19.519392 -13.916914 270)
			(size 0.4318 0.4318)
			(layers "F.Cu" "F.Mask" "F.Paste")
			(net "GND")
		)
		(pad "AJ25" smd circle
			(at -17.89176 -13.916914 270)
			(size 0.4318 0.4318)
			(layers "F.Cu" "F.Mask" "F.Paste")
			(net "GND")
		)
		(pad "AJ27" smd circle
			(at -16.263874 -13.916914 270)
			(size 0.4318 0.4318)
			(layers "F.Cu" "F.Mask" "F.Paste")
			(net "M_D_CPU1_SB_DQS_DN<1>")
		)
		(pad "AJ29" smd circle
			(at -14.635988 -13.916914 270)
			(size 0.4318 0.4318)
			(layers "F.Cu" "F.Mask" "F.Paste")
			(net "GND")
		)
		(pad "AJ31" smd circle
			(at -13.008356 -13.916914 270)
			(size 0.4318 0.4318)
			(layers "F.Cu" "F.Mask" "F.Paste")
			(net "GND")
		)
		(pad "AJ33" smd circle
			(at -11.380724 -13.916914 270)
			(size 0.4318 0.4318)
			(layers "F.Cu" "F.Mask" "F.Paste")
			(net "M_D_CPU1_SB_DQS_DN<0>")
		)
		(pad "AJ35" smd circle
			(at -9.752838 -13.916914 270)
			(size 0.4318 0.4318)
			(layers "F.Cu" "F.Mask" "F.Paste")
			(net "GND")
		)
		(pad "AJ37" smd circle
			(at -8.124952 -13.916914 270)
			(size 0.4318 0.4318)
			(layers "F.Cu" "F.Mask" "F.Paste")
			(net "GND")
		)
		(pad "AJ39" smd circle
			(at -6.49732 -13.916914 270)
			(size 0.4318 0.4318)
			(layers "F.Cu" "F.Mask" "F.Paste")
			(net "M_D_CPU1_SB_DQS_DN<9>")
		)
		(pad "AJ41" smd circle
			(at -4.869434 -13.916914 270)
			(size 0.4318 0.4318)
			(layers "F.Cu" "F.Mask" "F.Paste")
			(net "GND")
		)
		(pad "AJ43" smd circle
			(at -3.241802 -13.916914 270)
			(size 0.4318 0.4318)
			(layers "F.Cu" "F.Mask" "F.Paste")
			(net "GND")
		)
		(pad "AJ45" smd circle
			(at -1.613916 -13.916914 270)
			(size 0.4318 0.4318)
			(layers "F.Cu" "F.Mask" "F.Paste")
			(net "M_D_CPU1_CLK_DN<0>")
		)
		(pad "AJ48" smd circle
			(at 2.427732 -13.806932 270)
			(size 0.4318 0.4318)
			(layers "F.Cu" "F.Mask" "F.Paste")
			(net "GND")
		)
		(pad "AJ50" smd circle
			(at 4.055618 -13.806932 270)
			(size 0.4318 0.4318)
			(layers "F.Cu" "F.Mask" "F.Paste")
			(net "GND")
		)
		(pad "AJ52" smd circle
			(at 5.68325 -13.806932 270)
			(size 0.4318 0.4318)
			(layers "F.Cu" "F.Mask" "F.Paste")
			(net "M_D_CPU1_SA_CA<0>")
		)
		(pad "AJ54" smd circle
			(at 7.311136 -13.806932 270)
			(size 0.4318 0.4318)
			(layers "F.Cu" "F.Mask" "F.Paste")
			(net "GND")
		)
		(pad "AJ56" smd circle
			(at 8.939022 -13.806932 270)
			(size 0.4318 0.4318)
			(layers "F.Cu" "F.Mask" "F.Paste")
			(net "GND")
		)
		(pad "AJ58" smd circle
			(at 10.566654 -13.806932 270)
			(size 0.4318 0.4318)
			(layers "F.Cu" "F.Mask" "F.Paste")
			(net "M_D_CPU1_SA_DQS_DN<4>")
		)
		(pad "AJ60" smd circle
			(at 12.19454 -13.806932 270)
			(size 0.4318 0.4318)
			(layers "F.Cu" "F.Mask" "F.Paste")
			(net "GND")
		)
		(pad "AJ62" smd circle
			(at 13.822426 -13.806932 270)
			(size 0.4318 0.4318)
			(layers "F.Cu" "F.Mask" "F.Paste")
			(net "GND")
		)
		(pad "AJ64" smd circle
			(at 15.450058 -13.806932 270)
			(size 0.4318 0.4318)
			(layers "F.Cu" "F.Mask" "F.Paste")
			(net "M_D_CPU1_SA_DQS_DN<3>")
		)
		(pad "AJ66" smd circle
			(at 17.07769 -13.806932 270)
			(size 0.4318 0.4318)
			(layers "F.Cu" "F.Mask" "F.Paste")
			(net "GND")
		)
		(pad "AJ68" smd circle
			(at 18.705576 -13.806932 270)
			(size 0.4318 0.4318)
			(layers "F.Cu" "F.Mask" "F.Paste")
			(net "GND")
		)
		(pad "AJ70" smd circle
			(at 20.333462 -13.806932 270)
			(size 0.4318 0.4318)
			(layers "F.Cu" "F.Mask" "F.Paste")
			(net "M_D_CPU1_SA_DQS_DN<2>")
		)
		(pad "AJ72" smd circle
			(at 21.961094 -13.806932 270)
			(size 0.4318 0.4318)
			(layers "F.Cu" "F.Mask" "F.Paste")
			(net "GND")
		)
		(pad "AJ74" smd circle
			(at 23.58898 -13.806932 270)
			(size 0.4318 0.4318)
			(layers "F.Cu" "F.Mask" "F.Paste")
			(net "GND")
		)
		(pad "AJ76" smd circle
			(at 25.216612 -13.806932 270)
			(size 0.4318 0.4318)
			(layers "F.Cu" "F.Mask" "F.Paste")
			(net "M_D_CPU1_SA_DQS_DN<1>")
		)
		(pad "AJ78" smd circle
			(at 26.844498 -13.806932 270)
			(size 0.4318 0.4318)
			(layers "F.Cu" "F.Mask" "F.Paste")
			(net "GND")
		)
		(pad "AJ80" smd circle
			(at 28.472384 -13.806932 270)
			(size 0.4318 0.4318)
			(layers "F.Cu" "F.Mask" "F.Paste")
			(net "UPI_CPU0_CPU1_P2P2_DN<10>")
		)
		(pad "AJ82" smd circle
			(at 30.100016 -13.806932 270)
			(size 0.4318 0.4318)
			(layers "F.Cu" "F.Mask" "F.Paste")
			(net "UPI_CPU0_CPU1_P2P2_DP<11>")
		)
		(pad "AJ84" smd circle
			(at 31.727902 -13.806932 270)
			(size 0.4318 0.4318)
			(layers "F.Cu" "F.Mask" "F.Paste")
			(net "GND")
		)
		(pad "AJ86" smd circle
			(at 33.355534 -13.806932 270)
			(size 0.4318 0.4318)
			(layers "F.Cu" "F.Mask" "F.Paste")
			(net "P5E_CPU1_PE4_TX_DN<9>")
		)
		(pad "AJ88" smd circle
			(at 34.98342 -13.806932 270)
			(size 0.4318 0.4318)
			(layers "F.Cu" "F.Mask" "F.Paste")
			(net "GND")
		)
		(pad "AJ90" smd circle
			(at 36.611306 -13.806932 270)
			(size 0.4318 0.4318)
			(layers "F.Cu" "F.Mask" "F.Paste")
			(net "P5E_CPU1_PE4_RX_DP<9>")
		)
		(pad "AK2" smd circle
			(at -36.611306 -13.447268 270)
			(size 0.4318 0.4318)
			(layers "F.Cu" "F.Mask" "F.Paste")
			(net "UPI_CPU1_CPU0_P0P1_DN<10>")
		)
		(pad "AK4" smd circle
			(at -34.98342 -13.447268 270)
			(size 0.4318 0.4318)
			(layers "F.Cu" "F.Mask" "F.Paste")
			(net "GND")
		)
		(pad "AK6" smd circle
			(at -33.355534 -13.447268 270)
			(size 0.4318 0.4318)
			(layers "F.Cu" "F.Mask" "F.Paste")
			(net "UPI_CPU0_CPU1_P1P0_DN<10>")
		)
		(pad "AK8" smd circle
			(at -31.727902 -13.447268 270)
			(size 0.4318 0.4318)
			(layers "F.Cu" "F.Mask" "F.Paste")
			(net "GND")
		)
		(pad "AK10" smd circle
			(at -30.100016 -13.447268 270)
			(size 0.4318 0.4318)
			(layers "F.Cu" "F.Mask" "F.Paste")
			(net "P5E_CPU1_PE0_RX_DN<10>")
		)
		(pad "AK12" smd circle
			(at -28.472384 -13.447268 270)
			(size 0.4318 0.4318)
			(layers "F.Cu" "F.Mask" "F.Paste")
			(net "GND")
		)
		(pad "AK14" smd circle
			(at -26.844498 -13.447268 270)
			(size 0.4318 0.4318)
			(layers "F.Cu" "F.Mask" "F.Paste")
			(net "P5E_CPU1_PE0_TX_DN<9>")
		)
		(pad "AK16" smd circle
			(at -25.216612 -13.447268 270)
			(size 0.4318 0.4318)
			(layers "F.Cu" "F.Mask" "F.Paste")
			(net "GND")
		)
		(pad "AK18" smd circle
			(at -23.58898 -13.447268 270)
			(size 0.4318 0.4318)
			(layers "F.Cu" "F.Mask" "F.Paste")
			(net "GND")
		)
		(pad "AK20" smd circle
			(at -21.961094 -13.447268 270)
			(size 0.4318 0.4318)
			(layers "F.Cu" "F.Mask" "F.Paste")
			(net "M_D_CPU1_SB_DQ<28>")
		)
		(pad "AK22" smd circle
			(at -20.333462 -13.447268 270)
			(size 0.4318 0.4318)
			(layers "F.Cu" "F.Mask" "F.Paste")
			(net "M_D_CPU1_SB_DQ<25>")
		)
		(pad "AK24" smd circle
			(at -18.705576 -13.447268 270)
			(size 0.4318 0.4318)
			(layers "F.Cu" "F.Mask" "F.Paste")
			(net "GND")
		)
		(pad "AK26" smd circle
			(at -17.07769 -13.447268 270)
			(size 0.4318 0.4318)
			(layers "F.Cu" "F.Mask" "F.Paste")
			(net "M_D_CPU1_SB_DQ<12>")
		)
		(pad "AK28" smd circle
			(at -15.450058 -13.447268 270)
			(size 0.4318 0.4318)
			(layers "F.Cu" "F.Mask" "F.Paste")
			(net "M_D_CPU1_SB_DQ<9>")
		)
		(pad "AK30" smd circle
			(at -13.822426 -13.447268 270)
			(size 0.4318 0.4318)
			(layers "F.Cu" "F.Mask" "F.Paste")
			(net "GND")
		)
		(pad "AK32" smd circle
			(at -12.19454 -13.447268 270)
			(size 0.4318 0.4318)
			(layers "F.Cu" "F.Mask" "F.Paste")
			(net "M_D_CPU1_SB_DQ<4>")
		)
		(pad "AK34" smd circle
			(at -10.566654 -13.447268 270)
			(size 0.4318 0.4318)
			(layers "F.Cu" "F.Mask" "F.Paste")
			(net "M_D_CPU1_SB_DQ<1>")
		)
		(pad "AK36" smd circle
			(at -8.939022 -13.447268 270)
			(size 0.4318 0.4318)
			(layers "F.Cu" "F.Mask" "F.Paste")
			(net "GND")
		)
		(pad "AK38" smd circle
			(at -7.311136 -13.447268 270)
			(size 0.4318 0.4318)
			(layers "F.Cu" "F.Mask" "F.Paste")
			(net "M_D_CPU1_SB_CB<0>")
		)
		(pad "AK40" smd circle
			(at -5.68325 -13.447268 270)
			(size 0.4318 0.4318)
			(layers "F.Cu" "F.Mask" "F.Paste")
			(net "M_D_CPU1_SB_CB<5>")
		)
		(pad "AK42" smd circle
			(at -4.055618 -13.447268 270)
			(size 0.4318 0.4318)
			(layers "F.Cu" "F.Mask" "F.Paste")
			(net "GND")
		)
		(pad "AK44" smd circle
			(at -2.427732 -13.447268 270)
			(size 0.4318 0.4318)
			(layers "F.Cu" "F.Mask" "F.Paste")
			(net "M_D_CPU1_SB_CA<0>")
		)
		(pad "AK47" smd circle
			(at 1.613916 -13.337286 270)
			(size 0.4318 0.4318)
			(layers "F.Cu" "F.Mask" "F.Paste")
			(net "M_B_CPU1_SA_RSP<1>")
		)
		(pad "AK49" smd circle
			(at 3.241802 -13.337286 270)
			(size 0.4318 0.4318)
			(layers "F.Cu" "F.Mask" "F.Paste")
			(net "GND")
		)
		(pad "AK51" smd circle
			(at 4.869434 -13.337286 270)
			(size 0.4318 0.4318)
			(layers "F.Cu" "F.Mask" "F.Paste")
			(net "M_D_CPU1_SA_CA<2>")
		)
		(pad "AK53" smd circle
			(at 6.49732 -13.337286 270)
			(size 0.4318 0.4318)
			(layers "F.Cu" "F.Mask" "F.Paste")
			(net "M_D_CPU1_SA_CS_N<1>")
		)
		(pad "AK55" smd circle
			(at 8.124952 -13.337286 270)
			(size 0.4318 0.4318)
			(layers "F.Cu" "F.Mask" "F.Paste")
			(net "GND")
		)
		(pad "AK57" smd circle
			(at 9.752838 -13.337286 270)
			(size 0.4318 0.4318)
			(layers "F.Cu" "F.Mask" "F.Paste")
			(net "M_D_CPU1_SA_CB<4>")
		)
		(pad "AK59" smd circle
			(at 11.380724 -13.337286 270)
			(size 0.4318 0.4318)
			(layers "F.Cu" "F.Mask" "F.Paste")
			(net "M_D_CPU1_SA_CB<1>")
		)
		(pad "AK61" smd circle
			(at 13.008356 -13.337286 270)
			(size 0.4318 0.4318)
			(layers "F.Cu" "F.Mask" "F.Paste")
			(net "GND")
		)
		(pad "AK63" smd circle
			(at 14.635988 -13.337286 270)
			(size 0.4318 0.4318)
			(layers "F.Cu" "F.Mask" "F.Paste")
			(net "M_D_CPU1_SA_DQ<28>")
		)
		(pad "AK65" smd circle
			(at 16.263874 -13.337286 270)
			(size 0.4318 0.4318)
			(layers "F.Cu" "F.Mask" "F.Paste")
			(net "M_D_CPU1_SA_DQ<25>")
		)
		(pad "AK67" smd circle
			(at 17.89176 -13.337286 270)
			(size 0.4318 0.4318)
			(layers "F.Cu" "F.Mask" "F.Paste")
			(net "GND")
		)
		(pad "AK69" smd circle
			(at 19.519392 -13.337286 270)
			(size 0.4318 0.4318)
			(layers "F.Cu" "F.Mask" "F.Paste")
			(net "M_D_CPU1_SA_DQ<20>")
		)
		(pad "AK71" smd circle
			(at 21.147278 -13.337286 270)
			(size 0.4318 0.4318)
			(layers "F.Cu" "F.Mask" "F.Paste")
			(net "M_D_CPU1_SA_DQ<17>")
		)
		(pad "AK73" smd circle
			(at 22.77491 -13.337286 270)
			(size 0.4318 0.4318)
			(layers "F.Cu" "F.Mask" "F.Paste")
			(net "GND")
		)
		(pad "AK75" smd circle
			(at 24.402796 -13.337286 270)
			(size 0.4318 0.4318)
			(layers "F.Cu" "F.Mask" "F.Paste")
			(net "M_D_CPU1_SA_DQ<12>")
		)
		(pad "AK77" smd circle
			(at 26.030682 -13.337286 270)
			(size 0.4318 0.4318)
			(layers "F.Cu" "F.Mask" "F.Paste")
			(net "M_D_CPU1_SA_DQ<9>")
		)
		(pad "AK79" smd circle
			(at 27.658314 -13.337286 270)
			(size 0.4318 0.4318)
			(layers "F.Cu" "F.Mask" "F.Paste")
			(net "GND")
		)
		(pad "AK81" smd circle
			(at 29.2862 -13.337286 270)
			(size 0.4318 0.4318)
			(layers "F.Cu" "F.Mask" "F.Paste")
			(net "GND")
		)
		(pad "AK83" smd circle
			(at 30.914086 -13.337286 270)
			(size 0.4318 0.4318)
			(layers "F.Cu" "F.Mask" "F.Paste")
			(net "GND")
		)
		(pad "AK85" smd circle
			(at 32.541718 -13.337286 270)
			(size 0.4318 0.4318)
			(layers "F.Cu" "F.Mask" "F.Paste")
			(net "P5E_CPU1_PE4_TX_DP<9>")
		)
		(pad "AK87" smd circle
			(at 34.169604 -13.337286 270)
			(size 0.4318 0.4318)
			(layers "F.Cu" "F.Mask" "F.Paste")
			(net "GND")
		)
		(pad "AK89" smd circle
			(at 35.797236 -13.337286 270)
			(size 0.4318 0.4318)
			(layers "F.Cu" "F.Mask" "F.Paste")
			(net "P5E_CPU1_PE4_RX_DN<9>")
		)
		(pad "AK91" smd oval
			(at 37.425122 -13.337286)
			(size 0.381 0.4826)
			(drill
				(offset 0 -0.0508)
			)
			(layers "F.Cu" "F.Mask" "F.Paste")
			(net "GND")
		)
		(pad "AL1" smd oval
			(at -37.425122 -12.977114 180)
			(size 0.381 0.4826)
			(drill
				(offset 0 -0.0508)
			)
			(layers "F.Cu" "F.Mask" "F.Paste")
			(net "GND")
		)
		(pad "AL3" smd circle
			(at -35.797236 -12.977114 270)
			(size 0.4318 0.4318)
			(layers "F.Cu" "F.Mask" "F.Paste")
			(net "UPI_CPU1_CPU0_P0P1_DP<11>")
		)
		(pad "AL5" smd circle
			(at -34.169604 -12.977114 270)
			(size 0.4318 0.4318)
			(layers "F.Cu" "F.Mask" "F.Paste")
			(net "GND")
		)
		(pad "AL7" smd circle
			(at -32.541718 -12.977114 270)
			(size 0.4318 0.4318)
			(layers "F.Cu" "F.Mask" "F.Paste")
			(net "UPI_CPU0_CPU1_P1P0_DP<10>")
		)
		(pad "AL9" smd circle
			(at -30.914086 -12.977114 270)
			(size 0.4318 0.4318)
			(layers "F.Cu" "F.Mask" "F.Paste")
			(net "GND")
		)
		(pad "AL11" smd circle
			(at -29.2862 -12.977114 270)
			(size 0.4318 0.4318)
			(layers "F.Cu" "F.Mask" "F.Paste")
			(net "P5E_CPU1_PE0_RX_DP<10>")
		)
		(pad "AL13" smd circle
			(at -27.658314 -12.977114 270)
			(size 0.4318 0.4318)
			(layers "F.Cu" "F.Mask" "F.Paste")
			(net "GND")
		)
		(pad "AL15" smd circle
			(at -26.030682 -12.977114 270)
			(size 0.4318 0.4318)
			(layers "F.Cu" "F.Mask" "F.Paste")
			(net "P5E_CPU1_PE0_TX_DP<9>")
		)
		(pad "AL17" smd circle
			(at -24.402796 -12.977114 270)
			(size 0.4318 0.4318)
			(layers "F.Cu" "F.Mask" "F.Paste")
			(net "GND")
		)
		(pad "AL19" smd circle
			(at -22.77491 -12.977114 270)
			(size 0.4318 0.4318)
			(layers "F.Cu" "F.Mask" "F.Paste")
			(net "M_D_CPU1_SB_DQ<29>")
		)
		(pad "AL21" smd circle
			(at -21.147278 -12.977114 270)
			(size 0.4318 0.4318)
			(layers "F.Cu" "F.Mask" "F.Paste")
			(net "M_D_CPU1_SB_DQS_DP<3>")
		)
		(pad "AL23" smd circle
			(at -19.519392 -12.977114 270)
			(size 0.4318 0.4318)
			(layers "F.Cu" "F.Mask" "F.Paste")
			(net "M_D_CPU1_SB_DQ<24>")
		)
		(pad "AL25" smd circle
			(at -17.89176 -12.977114 270)
			(size 0.4318 0.4318)
			(layers "F.Cu" "F.Mask" "F.Paste")
			(net "M_D_CPU1_SB_DQ<13>")
		)
		(pad "AL27" smd circle
			(at -16.263874 -12.977114 270)
			(size 0.4318 0.4318)
			(layers "F.Cu" "F.Mask" "F.Paste")
			(net "M_D_CPU1_SB_DQS_DP<1>")
		)
		(pad "AL29" smd circle
			(at -14.635988 -12.977114 270)
			(size 0.4318 0.4318)
			(layers "F.Cu" "F.Mask" "F.Paste")
			(net "M_D_CPU1_SB_DQ<8>")
		)
		(pad "AL31" smd circle
			(at -13.008356 -12.977114 270)
			(size 0.4318 0.4318)
			(layers "F.Cu" "F.Mask" "F.Paste")
			(net "M_D_CPU1_SB_DQ<5>")
		)
		(pad "AL33" smd circle
			(at -11.380724 -12.977114 270)
			(size 0.4318 0.4318)
			(layers "F.Cu" "F.Mask" "F.Paste")
			(net "M_D_CPU1_SB_DQS_DP<0>")
		)
		(pad "AL35" smd circle
			(at -9.752838 -12.977114 270)
			(size 0.4318 0.4318)
			(layers "F.Cu" "F.Mask" "F.Paste")
			(net "M_D_CPU1_SB_DQ<0>")
		)
		(pad "AL37" smd circle
			(at -8.124952 -12.977114 270)
			(size 0.4318 0.4318)
			(layers "F.Cu" "F.Mask" "F.Paste")
			(net "M_D_CPU1_SB_CB<1>")
		)
		(pad "AL39" smd circle
			(at -6.49732 -12.977114 270)
			(size 0.4318 0.4318)
			(layers "F.Cu" "F.Mask" "F.Paste")
			(net "M_D_CPU1_SB_DQS_DP<9>")
		)
		(pad "AL41" smd circle
			(at -4.869434 -12.977114 270)
			(size 0.4318 0.4318)
			(layers "F.Cu" "F.Mask" "F.Paste")
			(net "M_D_CPU1_SB_CB<4>")
		)
		(pad "AL43" smd circle
			(at -3.241802 -12.977114 270)
			(size 0.4318 0.4318)
			(layers "F.Cu" "F.Mask" "F.Paste")
			(net "M_D_CPU1_SB_CA<1>")
		)
		(pad "AL45" smd circle
			(at -1.613916 -12.977114 270)
			(size 0.4318 0.4318)
			(layers "F.Cu" "F.Mask" "F.Paste")
			(net "M_D_CPU1_CLK_DP<0>")
		)
		(pad "AL48" smd circle
			(at 2.427732 -12.867132 270)
			(size 0.4318 0.4318)
			(layers "F.Cu" "F.Mask" "F.Paste")
			(net "M_B_CPU1_SA_RSP<0>")
		)
		(pad "AL50" smd circle
			(at 4.055618 -12.867132 270)
			(size 0.4318 0.4318)
			(layers "F.Cu" "F.Mask" "F.Paste")
			(net "M_D_CPU1_SA_CA<4>")
		)
		(pad "AL52" smd circle
			(at 5.68325 -12.867132 270)
			(size 0.4318 0.4318)
			(layers "F.Cu" "F.Mask" "F.Paste")
			(net "GND")
		)
		(pad "AL54" smd circle
			(at 7.311136 -12.867132 270)
			(size 0.4318 0.4318)
			(layers "F.Cu" "F.Mask" "F.Paste")
			(net "M_D_CPU1_SA_CS_N<0>")
		)
		(pad "AL56" smd circle
			(at 8.939022 -12.867132 270)
			(size 0.4318 0.4318)
			(layers "F.Cu" "F.Mask" "F.Paste")
			(net "M_D_CPU1_SA_CB<5>")
		)
		(pad "AL58" smd circle
			(at 10.566654 -12.867132 270)
			(size 0.4318 0.4318)
			(layers "F.Cu" "F.Mask" "F.Paste")
			(net "M_D_CPU1_SA_DQS_DP<4>")
		)
		(pad "AL60" smd circle
			(at 12.19454 -12.867132 270)
			(size 0.4318 0.4318)
			(layers "F.Cu" "F.Mask" "F.Paste")
			(net "M_D_CPU1_SA_CB<0>")
		)
		(pad "AL62" smd circle
			(at 13.822426 -12.867132 270)
			(size 0.4318 0.4318)
			(layers "F.Cu" "F.Mask" "F.Paste")
			(net "M_D_CPU1_SA_DQ<29>")
		)
		(pad "AL64" smd circle
			(at 15.450058 -12.867132 270)
			(size 0.4318 0.4318)
			(layers "F.Cu" "F.Mask" "F.Paste")
			(net "M_D_CPU1_SA_DQS_DP<3>")
		)
		(pad "AL66" smd circle
			(at 17.07769 -12.867132 270)
			(size 0.4318 0.4318)
			(layers "F.Cu" "F.Mask" "F.Paste")
			(net "M_D_CPU1_SA_DQ<24>")
		)
		(pad "AL68" smd circle
			(at 18.705576 -12.867132 270)
			(size 0.4318 0.4318)
			(layers "F.Cu" "F.Mask" "F.Paste")
			(net "M_D_CPU1_SA_DQ<21>")
		)
		(pad "AL70" smd circle
			(at 20.333462 -12.867132 270)
			(size 0.4318 0.4318)
			(layers "F.Cu" "F.Mask" "F.Paste")
			(net "M_D_CPU1_SA_DQS_DP<2>")
		)
		(pad "AL72" smd circle
			(at 21.961094 -12.867132 270)
			(size 0.4318 0.4318)
			(layers "F.Cu" "F.Mask" "F.Paste")
			(net "M_D_CPU1_SA_DQ<16>")
		)
		(pad "AL74" smd circle
			(at 23.58898 -12.867132 270)
			(size 0.4318 0.4318)
			(layers "F.Cu" "F.Mask" "F.Paste")
			(net "M_D_CPU1_SA_DQ<13>")
		)
		(pad "AL76" smd circle
			(at 25.216612 -12.867132 270)
			(size 0.4318 0.4318)
			(layers "F.Cu" "F.Mask" "F.Paste")
			(net "M_D_CPU1_SA_DQS_DP<1>")
		)
		(pad "AL78" smd circle
			(at 26.844498 -12.867132 270)
			(size 0.4318 0.4318)
			(layers "F.Cu" "F.Mask" "F.Paste")
			(net "M_D_CPU1_SA_DQ<8>")
		)
		(pad "AL80" smd circle
			(at 28.472384 -12.867132 270)
			(size 0.4318 0.4318)
			(layers "F.Cu" "F.Mask" "F.Paste")
			(net "GND")
		)
		(pad "AL82" smd circle
			(at 30.100016 -12.867132 270)
			(size 0.4318 0.4318)
			(layers "F.Cu" "F.Mask" "F.Paste")
			(net "GND")
		)
		(pad "AL84" smd circle
			(at 31.727902 -12.867132 270)
			(size 0.4318 0.4318)
			(layers "F.Cu" "F.Mask" "F.Paste")
			(net "GND")
		)
		(pad "AL86" smd circle
			(at 33.355534 -12.867132 270)
			(size 0.4318 0.4318)
			(layers "F.Cu" "F.Mask" "F.Paste")
			(net "P5E_CPU1_PE4_TX_DN<10>")
		)
		(pad "AL88" smd circle
			(at 34.98342 -12.867132 270)
			(size 0.4318 0.4318)
			(layers "F.Cu" "F.Mask" "F.Paste")
			(net "GND")
		)
		(pad "AL90" smd circle
			(at 36.611306 -12.867132 270)
			(size 0.4318 0.4318)
			(layers "F.Cu" "F.Mask" "F.Paste")
			(net "P5E_CPU1_PE4_RX_DP<10>")
		)
		(pad "AM2" smd circle
			(at -36.611306 -12.507468 270)
			(size 0.4318 0.4318)
			(layers "F.Cu" "F.Mask" "F.Paste")
			(net "UPI_CPU1_CPU0_P0P1_DN<11>")
		)
		(pad "AM4" smd circle
			(at -34.98342 -12.507468 270)
			(size 0.4318 0.4318)
			(layers "F.Cu" "F.Mask" "F.Paste")
			(net "GND")
		)
		(pad "AM6" smd circle
			(at -33.355534 -12.507468 270)
			(size 0.4318 0.4318)
			(layers "F.Cu" "F.Mask" "F.Paste")
			(net "UPI_CPU0_CPU1_P1P0_DP<11>")
		)
		(pad "AM8" smd circle
			(at -31.727902 -12.507468 270)
			(size 0.4318 0.4318)
			(layers "F.Cu" "F.Mask" "F.Paste")
			(net "GND")
		)
		(pad "AM10" smd circle
			(at -30.100016 -12.507468 270)
			(size 0.4318 0.4318)
			(layers "F.Cu" "F.Mask" "F.Paste")
			(net "P5E_CPU1_PE0_RX_DN<11>")
		)
		(pad "AM12" smd circle
			(at -28.472384 -12.507468 270)
			(size 0.4318 0.4318)
			(layers "F.Cu" "F.Mask" "F.Paste")
			(net "GND")
		)
		(pad "AM14" smd circle
			(at -26.844498 -12.507468 270)
			(size 0.4318 0.4318)
			(layers "F.Cu" "F.Mask" "F.Paste")
			(net "P5E_CPU1_PE0_TX_DP<10>")
		)
		(pad "AM16" smd circle
			(at -25.216612 -12.507468 270)
			(size 0.4318 0.4318)
			(layers "F.Cu" "F.Mask" "F.Paste")
			(net "GND")
		)
		(pad "AM18" smd circle
			(at -23.58898 -12.507468 270)
			(size 0.4318 0.4318)
			(layers "F.Cu" "F.Mask" "F.Paste")
			(net "GND")
		)
		(pad "AM20" smd circle
			(at -21.961094 -12.507468 270)
			(size 0.4318 0.4318)
			(layers "F.Cu" "F.Mask" "F.Paste")
			(net "GND")
		)
		(pad "AM22" smd circle
			(at -20.333462 -12.507468 270)
			(size 0.4318 0.4318)
			(layers "F.Cu" "F.Mask" "F.Paste")
			(net "GND")
		)
		(pad "AM24" smd circle
			(at -18.705576 -12.507468 270)
			(size 0.4318 0.4318)
			(layers "F.Cu" "F.Mask" "F.Paste")
			(net "GND")
		)
		(pad "AM26" smd circle
			(at -17.07769 -12.507468 270)
			(size 0.4318 0.4318)
			(layers "F.Cu" "F.Mask" "F.Paste")
			(net "GND")
		)
		(pad "AM28" smd circle
			(at -15.450058 -12.507468 270)
			(size 0.4318 0.4318)
			(layers "F.Cu" "F.Mask" "F.Paste")
			(net "GND")
		)
		(pad "AM30" smd circle
			(at -13.822426 -12.507468 270)
			(size 0.4318 0.4318)
			(layers "F.Cu" "F.Mask" "F.Paste")
			(net "GND")
		)
		(pad "AM32" smd circle
			(at -12.19454 -12.507468 270)
			(size 0.4318 0.4318)
			(layers "F.Cu" "F.Mask" "F.Paste")
			(net "GND")
		)
		(pad "AM34" smd circle
			(at -10.566654 -12.507468 270)
			(size 0.4318 0.4318)
			(layers "F.Cu" "F.Mask" "F.Paste")
			(net "GND")
		)
		(pad "AM36" smd circle
			(at -8.939022 -12.507468 270)
			(size 0.4318 0.4318)
			(layers "F.Cu" "F.Mask" "F.Paste")
			(net "GND")
		)
		(pad "AM38" smd circle
			(at -7.311136 -12.507468 270)
			(size 0.4318 0.4318)
			(layers "F.Cu" "F.Mask" "F.Paste")
			(net "GND")
		)
		(pad "AM40" smd circle
			(at -5.68325 -12.507468 270)
			(size 0.4318 0.4318)
			(layers "F.Cu" "F.Mask" "F.Paste")
			(net "GND")
		)
		(pad "AM42" smd circle
			(at -4.055618 -12.507468 270)
			(size 0.4318 0.4318)
			(layers "F.Cu" "F.Mask" "F.Paste")
			(net "GND")
		)
		(pad "AM44" smd circle
			(at -2.427732 -12.507468 270)
			(size 0.4318 0.4318)
			(layers "F.Cu" "F.Mask" "F.Paste")
			(net "GND")
		)
		(pad "AM47" smd circle
			(at 1.613916 -12.397486 270)
			(size 0.4318 0.4318)
			(layers "F.Cu" "F.Mask" "F.Paste")
			(net "GND")
		)
		(pad "AM49" smd circle
			(at 3.241802 -12.397486 270)
			(size 0.4318 0.4318)
			(layers "F.Cu" "F.Mask" "F.Paste")
			(net "GND")
		)
		(pad "AM51" smd circle
			(at 4.869434 -12.397486 270)
			(size 0.4318 0.4318)
			(layers "F.Cu" "F.Mask" "F.Paste")
			(net "GND")
		)
		(pad "AM53" smd circle
			(at 6.49732 -12.397486 270)
			(size 0.4318 0.4318)
			(layers "F.Cu" "F.Mask" "F.Paste")
			(net "GND")
		)
		(pad "AM55" smd circle
			(at 8.124952 -12.397486 270)
			(size 0.4318 0.4318)
			(layers "F.Cu" "F.Mask" "F.Paste")
			(net "GND")
		)
		(pad "AM57" smd circle
			(at 9.752838 -12.397486 270)
			(size 0.4318 0.4318)
			(layers "F.Cu" "F.Mask" "F.Paste")
			(net "GND")
		)
		(pad "AM59" smd circle
			(at 11.380724 -12.397486 270)
			(size 0.4318 0.4318)
			(layers "F.Cu" "F.Mask" "F.Paste")
			(net "GND")
		)
		(pad "AM61" smd circle
			(at 13.008356 -12.397486 270)
			(size 0.4318 0.4318)
			(layers "F.Cu" "F.Mask" "F.Paste")
			(net "GND")
		)
		(pad "AM63" smd circle
			(at 14.635988 -12.397486 270)
			(size 0.4318 0.4318)
			(layers "F.Cu" "F.Mask" "F.Paste")
			(net "GND")
		)
		(pad "AM65" smd circle
			(at 16.263874 -12.397486 270)
			(size 0.4318 0.4318)
			(layers "F.Cu" "F.Mask" "F.Paste")
			(net "GND")
		)
		(pad "AM67" smd circle
			(at 17.89176 -12.397486 270)
			(size 0.4318 0.4318)
			(layers "F.Cu" "F.Mask" "F.Paste")
			(net "GND")
		)
		(pad "AM69" smd circle
			(at 19.519392 -12.397486 270)
			(size 0.4318 0.4318)
			(layers "F.Cu" "F.Mask" "F.Paste")
			(net "GND")
		)
		(pad "AM71" smd circle
			(at 21.147278 -12.397486 270)
			(size 0.4318 0.4318)
			(layers "F.Cu" "F.Mask" "F.Paste")
			(net "GND")
		)
		(pad "AM73" smd circle
			(at 22.77491 -12.397486 270)
			(size 0.4318 0.4318)
			(layers "F.Cu" "F.Mask" "F.Paste")
			(net "GND")
		)
		(pad "AM75" smd circle
			(at 24.402796 -12.397486 270)
			(size 0.4318 0.4318)
			(layers "F.Cu" "F.Mask" "F.Paste")
			(net "GND")
		)
		(pad "AM77" smd circle
			(at 26.030682 -12.397486 270)
			(size 0.4318 0.4318)
			(layers "F.Cu" "F.Mask" "F.Paste")
			(net "GND")
		)
		(pad "AM79" smd circle
			(at 27.658314 -12.397486 270)
			(size 0.4318 0.4318)
			(layers "F.Cu" "F.Mask" "F.Paste")
			(net "PVCCFA_EHV_FIVRA_CPU1")
		)
		(pad "AM81" smd circle
			(at 29.2862 -12.397486 270)
			(size 0.4318 0.4318)
			(layers "F.Cu" "F.Mask" "F.Paste")
			(net "UPI_CPU1_CPU0_P2P2_DN<12>")
		)
		(pad "AM83" smd circle
			(at 30.914086 -12.397486 270)
			(size 0.4318 0.4318)
			(layers "F.Cu" "F.Mask" "F.Paste")
			(net "UPI_CPU1_CPU0_P2P2_DP<13>")
		)
		(pad "AM85" smd circle
			(at 32.541718 -12.397486 270)
			(size 0.4318 0.4318)
			(layers "F.Cu" "F.Mask" "F.Paste")
			(net "PVCCFA_EHV_FIVRA_CPU1")
		)
		(pad "AM87" smd circle
			(at 34.169604 -12.397486 270)
			(size 0.4318 0.4318)
			(layers "F.Cu" "F.Mask" "F.Paste")
			(net "P5E_CPU1_PE4_TX_DP<10>")
		)
		(pad "AM89" smd circle
			(at 35.797236 -12.397486 270)
			(size 0.4318 0.4318)
			(layers "F.Cu" "F.Mask" "F.Paste")
			(net "PVCCFA_EHV_FIVRA_CPU1")
		)
		(pad "AM91" smd oval
			(at 37.425122 -12.397486)
			(size 0.381 0.4826)
			(drill
				(offset 0 -0.0508)
			)
			(layers "F.Cu" "F.Mask" "F.Paste")
			(net "P5E_CPU1_PE4_RX_DN<10>")
		)
		(pad "AN1" smd oval
			(at -37.425122 -12.037314 180)
			(size 0.381 0.4826)
			(drill
				(offset 0 -0.0508)
			)
			(layers "F.Cu" "F.Mask" "F.Paste")
			(net "UPI_CPU1_CPU0_P0P1_DP<12>")
		)
		(pad "AN3" smd circle
			(at -35.797236 -12.037314 270)
			(size 0.4318 0.4318)
			(layers "F.Cu" "F.Mask" "F.Paste")
			(net "PVCCFA_EHV_CPU1")
		)
		(pad "AN5" smd circle
			(at -34.169604 -12.037314 270)
			(size 0.4318 0.4318)
			(layers "F.Cu" "F.Mask" "F.Paste")
			(net "UPI_CPU0_CPU1_P1P0_DN<11>")
		)
		(pad "AN7" smd circle
			(at -32.541718 -12.037314 270)
			(size 0.4318 0.4318)
			(layers "F.Cu" "F.Mask" "F.Paste")
			(net "PVCCFA_EHV_FIVRA_CPU1")
		)
		(pad "AN9" smd circle
			(at -30.914086 -12.037314 270)
			(size 0.4318 0.4318)
			(layers "F.Cu" "F.Mask" "F.Paste")
			(net "P5E_CPU1_PE0_RX_DP<11>")
		)
		(pad "AN11" smd circle
			(at -29.2862 -12.037314 270)
			(size 0.4318 0.4318)
			(layers "F.Cu" "F.Mask" "F.Paste")
			(net "PVCCFA_EHV_FIVRA_CPU1")
		)
		(pad "AN13" smd circle
			(at -27.658314 -12.037314 270)
			(size 0.4318 0.4318)
			(layers "F.Cu" "F.Mask" "F.Paste")
			(net "P5E_CPU1_PE0_TX_DN<10>")
		)
		(pad "AN15" smd circle
			(at -26.030682 -12.037314 270)
			(size 0.4318 0.4318)
			(layers "F.Cu" "F.Mask" "F.Paste")
			(net "PVCCFA_EHV_FIVRA_CPU1")
		)
		(pad "AN17" smd circle
			(at -24.402796 -12.037314 270)
			(size 0.4318 0.4318)
			(layers "F.Cu" "F.Mask" "F.Paste")
			(net "NC_CPU1_UPI0_APROBE<0>")
		)
		(pad "AN19" smd circle
			(at -22.77491 -12.037314 270)
			(size 0.4318 0.4318)
			(layers "F.Cu" "F.Mask" "F.Paste")
			(net "M_D_CPU1_SB_DQ<31>")
		)
		(pad "AN21" smd circle
			(at -21.147278 -12.037314 270)
			(size 0.4318 0.4318)
			(layers "F.Cu" "F.Mask" "F.Paste")
			(net "M_D_CPU1_SB_DQS_DN<8>")
		)
		(pad "AN23" smd circle
			(at -19.519392 -12.037314 270)
			(size 0.4318 0.4318)
			(layers "F.Cu" "F.Mask" "F.Paste")
			(net "M_D_CPU1_SB_DQ<26>")
		)
		(pad "AN25" smd circle
			(at -17.89176 -12.037314 270)
			(size 0.4318 0.4318)
			(layers "F.Cu" "F.Mask" "F.Paste")
			(net "M_D_CPU1_SB_DQ<15>")
		)
		(pad "AN27" smd circle
			(at -16.263874 -12.037314 270)
			(size 0.4318 0.4318)
			(layers "F.Cu" "F.Mask" "F.Paste")
			(net "M_D_CPU1_SB_DQS_DN<6>")
		)
		(pad "AN29" smd circle
			(at -14.635988 -12.037314 270)
			(size 0.4318 0.4318)
			(layers "F.Cu" "F.Mask" "F.Paste")
			(net "M_D_CPU1_SB_DQ<10>")
		)
		(pad "AN31" smd circle
			(at -13.008356 -12.037314 270)
			(size 0.4318 0.4318)
			(layers "F.Cu" "F.Mask" "F.Paste")
			(net "M_D_CPU1_SB_DQ<7>")
		)
		(pad "AN33" smd circle
			(at -11.380724 -12.037314 270)
			(size 0.4318 0.4318)
			(layers "F.Cu" "F.Mask" "F.Paste")
			(net "M_D_CPU1_SB_DQS_DN<5>")
		)
		(pad "AN35" smd circle
			(at -9.752838 -12.037314 270)
			(size 0.4318 0.4318)
			(layers "F.Cu" "F.Mask" "F.Paste")
			(net "M_D_CPU1_SB_DQ<2>")
		)
		(pad "AN37" smd circle
			(at -8.124952 -12.037314 270)
			(size 0.4318 0.4318)
			(layers "F.Cu" "F.Mask" "F.Paste")
			(net "M_D_CPU1_SB_CB<3>")
		)
		(pad "AN39" smd circle
			(at -6.49732 -12.037314 270)
			(size 0.4318 0.4318)
			(layers "F.Cu" "F.Mask" "F.Paste")
			(net "M_D_CPU1_SB_DQS_DP<4>")
		)
		(pad "AN41" smd circle
			(at -4.869434 -12.037314 270)
			(size 0.4318 0.4318)
			(layers "F.Cu" "F.Mask" "F.Paste")
			(net "M_D_CPU1_SB_CB<6>")
		)
		(pad "AN43" smd circle
			(at -3.241802 -12.037314 270)
			(size 0.4318 0.4318)
			(layers "F.Cu" "F.Mask" "F.Paste")
			(net "M_D_CPU1_SA_CA<6>")
		)
		(pad "AN45" smd circle
			(at -1.613916 -12.037314 270)
			(size 0.4318 0.4318)
			(layers "F.Cu" "F.Mask" "F.Paste")
			(net "M_D_CPU1_CLK_DN<1>")
		)
		(pad "AN48" smd circle
			(at 2.427732 -11.927332 270)
			(size 0.4318 0.4318)
			(layers "F.Cu" "F.Mask" "F.Paste")
			(net "M_B_CPU1_SB_RSP<0>")
		)
		(pad "AN50" smd circle
			(at 4.055618 -11.927332 270)
			(size 0.4318 0.4318)
			(layers "F.Cu" "F.Mask" "F.Paste")
			(net "M_D_CPU1_SA_CA<5>")
		)
		(pad "AN52" smd circle
			(at 5.68325 -11.927332 270)
			(size 0.4318 0.4318)
			(layers "F.Cu" "F.Mask" "F.Paste")
			(net "GND")
		)
		(pad "AN54" smd circle
			(at 7.311136 -11.927332 270)
			(size 0.4318 0.4318)
			(layers "F.Cu" "F.Mask" "F.Paste")
			(net "M_D_CPU1_SA_CS_N<2>")
		)
		(pad "AN56" smd circle
			(at 8.939022 -11.927332 270)
			(size 0.4318 0.4318)
			(layers "F.Cu" "F.Mask" "F.Paste")
			(net "M_D_CPU1_SA_CB<7>")
		)
		(pad "AN58" smd circle
			(at 10.566654 -11.927332 270)
			(size 0.4318 0.4318)
			(layers "F.Cu" "F.Mask" "F.Paste")
			(net "M_D_CPU1_SA_DQS_DN<9>")
		)
		(pad "AN60" smd circle
			(at 12.19454 -11.927332 270)
			(size 0.4318 0.4318)
			(layers "F.Cu" "F.Mask" "F.Paste")
			(net "M_D_CPU1_SA_CB<2>")
		)
		(pad "AN62" smd circle
			(at 13.822426 -11.927332 270)
			(size 0.4318 0.4318)
			(layers "F.Cu" "F.Mask" "F.Paste")
			(net "M_D_CPU1_SA_DQ<31>")
		)
		(pad "AN64" smd circle
			(at 15.450058 -11.927332 270)
			(size 0.4318 0.4318)
			(layers "F.Cu" "F.Mask" "F.Paste")
			(net "M_D_CPU1_SA_DQS_DN<8>")
		)
		(pad "AN66" smd circle
			(at 17.07769 -11.927332 270)
			(size 0.4318 0.4318)
			(layers "F.Cu" "F.Mask" "F.Paste")
			(net "M_D_CPU1_SA_DQ<26>")
		)
		(pad "AN68" smd circle
			(at 18.705576 -11.927332 270)
			(size 0.4318 0.4318)
			(layers "F.Cu" "F.Mask" "F.Paste")
			(net "M_D_CPU1_SA_DQ<23>")
		)
		(pad "AN70" smd circle
			(at 20.333462 -11.927332 270)
			(size 0.4318 0.4318)
			(layers "F.Cu" "F.Mask" "F.Paste")
			(net "M_D_CPU1_SA_DQS_DN<7>")
		)
		(pad "AN72" smd circle
			(at 21.961094 -11.927332 270)
			(size 0.4318 0.4318)
			(layers "F.Cu" "F.Mask" "F.Paste")
			(net "M_D_CPU1_SA_DQ<18>")
		)
		(pad "AN74" smd circle
			(at 23.58898 -11.927332 270)
			(size 0.4318 0.4318)
			(layers "F.Cu" "F.Mask" "F.Paste")
			(net "M_D_CPU1_SA_DQ<15>")
		)
		(pad "AN76" smd circle
			(at 25.216612 -11.927332 270)
			(size 0.4318 0.4318)
			(layers "F.Cu" "F.Mask" "F.Paste")
			(net "M_D_CPU1_SA_DQS_DN<6>")
		)
		(pad "AN78" smd circle
			(at 26.844498 -11.927332 270)
			(size 0.4318 0.4318)
			(layers "F.Cu" "F.Mask" "F.Paste")
			(net "M_D_CPU1_SA_DQ<10>")
		)
		(pad "AN80" smd circle
			(at 28.472384 -11.927332 270)
			(size 0.4318 0.4318)
			(layers "F.Cu" "F.Mask" "F.Paste")
			(net "PVCCFA_EHV_FIVRA_CPU1")
		)
		(pad "AN82" smd circle
			(at 30.100016 -11.927332 270)
			(size 0.4318 0.4318)
			(layers "F.Cu" "F.Mask" "F.Paste")
			(net "UPI_CPU1_CPU0_P2P2_DN<13>")
		)
		(pad "AN84" smd circle
			(at 31.727902 -11.927332 270)
			(size 0.4318 0.4318)
			(layers "F.Cu" "F.Mask" "F.Paste")
			(net "GND")
		)
		(pad "AN86" smd circle
			(at 33.355534 -11.927332 270)
			(size 0.4318 0.4318)
			(layers "F.Cu" "F.Mask" "F.Paste")
			(net "P5E_CPU1_PE4_TX_DP<11>")
		)
		(pad "AN88" smd circle
			(at 34.98342 -11.927332 270)
			(size 0.4318 0.4318)
			(layers "F.Cu" "F.Mask" "F.Paste")
			(net "GND")
		)
		(pad "AN90" smd circle
			(at 36.611306 -11.927332 270)
			(size 0.4318 0.4318)
			(layers "F.Cu" "F.Mask" "F.Paste")
			(net "P5E_CPU1_PE4_RX_DP<11>")
		)
		(pad "AP2" smd circle
			(at -36.611306 -11.567668 270)
			(size 0.4318 0.4318)
			(layers "F.Cu" "F.Mask" "F.Paste")
			(net "UPI_CPU1_CPU0_P0P1_DN<12>")
		)
		(pad "AP4" smd circle
			(at -34.98342 -11.567668 270)
			(size 0.4318 0.4318)
			(layers "F.Cu" "F.Mask" "F.Paste")
			(net "GND")
		)
		(pad "AP6" smd circle
			(at -33.355534 -11.567668 270)
			(size 0.4318 0.4318)
			(layers "F.Cu" "F.Mask" "F.Paste")
			(net "UPI_CPU0_CPU1_P1P0_DN<12>")
		)
		(pad "AP8" smd circle
			(at -31.727902 -11.567668 270)
			(size 0.4318 0.4318)
			(layers "F.Cu" "F.Mask" "F.Paste")
			(net "GND")
		)
		(pad "AP10" smd circle
			(at -30.100016 -11.567668 270)
			(size 0.4318 0.4318)
			(layers "F.Cu" "F.Mask" "F.Paste")
			(net "P5E_CPU1_PE0_RX_DN<12>")
		)
		(pad "AP12" smd circle
			(at -28.472384 -11.567668 270)
			(size 0.4318 0.4318)
			(layers "F.Cu" "F.Mask" "F.Paste")
			(net "GND")
		)
		(pad "AP14" smd circle
			(at -26.844498 -11.567668 270)
			(size 0.4318 0.4318)
			(layers "F.Cu" "F.Mask" "F.Paste")
			(net "P5E_CPU1_PE0_TX_DN<11>")
		)
		(pad "AP16" smd circle
			(at -25.216612 -11.567668 270)
			(size 0.4318 0.4318)
			(layers "F.Cu" "F.Mask" "F.Paste")
			(net "GND")
		)
		(pad "AP18" smd circle
			(at -23.58898 -11.567668 270)
			(size 0.4318 0.4318)
			(layers "F.Cu" "F.Mask" "F.Paste")
			(net "GND")
		)
		(pad "AP20" smd circle
			(at -21.961094 -11.567668 270)
			(size 0.4318 0.4318)
			(layers "F.Cu" "F.Mask" "F.Paste")
			(net "M_D_CPU1_SB_DQ<30>")
		)
		(pad "AP22" smd circle
			(at -20.333462 -11.567668 270)
			(size 0.4318 0.4318)
			(layers "F.Cu" "F.Mask" "F.Paste")
			(net "M_D_CPU1_SB_DQ<27>")
		)
		(pad "AP24" smd circle
			(at -18.705576 -11.567668 270)
			(size 0.4318 0.4318)
			(layers "F.Cu" "F.Mask" "F.Paste")
			(net "GND")
		)
		(pad "AP26" smd circle
			(at -17.07769 -11.567668 270)
			(size 0.4318 0.4318)
			(layers "F.Cu" "F.Mask" "F.Paste")
			(net "M_D_CPU1_SB_DQ<14>")
		)
		(pad "AP28" smd circle
			(at -15.450058 -11.567668 270)
			(size 0.4318 0.4318)
			(layers "F.Cu" "F.Mask" "F.Paste")
			(net "M_D_CPU1_SB_DQ<11>")
		)
		(pad "AP30" smd circle
			(at -13.822426 -11.567668 270)
			(size 0.4318 0.4318)
			(layers "F.Cu" "F.Mask" "F.Paste")
			(net "GND")
		)
		(pad "AP32" smd circle
			(at -12.19454 -11.567668 270)
			(size 0.4318 0.4318)
			(layers "F.Cu" "F.Mask" "F.Paste")
			(net "M_D_CPU1_SB_DQ<6>")
		)
		(pad "AP34" smd circle
			(at -10.566654 -11.567668 270)
			(size 0.4318 0.4318)
			(layers "F.Cu" "F.Mask" "F.Paste")
			(net "M_D_CPU1_SB_DQ<3>")
		)
		(pad "AP36" smd circle
			(at -8.939022 -11.567668 270)
			(size 0.4318 0.4318)
			(layers "F.Cu" "F.Mask" "F.Paste")
			(net "GND")
		)
		(pad "AP38" smd circle
			(at -7.311136 -11.567668 270)
			(size 0.4318 0.4318)
			(layers "F.Cu" "F.Mask" "F.Paste")
			(net "M_D_CPU1_SB_CB<2>")
		)
		(pad "AP40" smd circle
			(at -5.68325 -11.567668 270)
			(size 0.4318 0.4318)
			(layers "F.Cu" "F.Mask" "F.Paste")
			(net "M_D_CPU1_SB_CB<7>")
		)
		(pad "AP42" smd circle
			(at -4.055618 -11.567668 270)
			(size 0.4318 0.4318)
			(layers "F.Cu" "F.Mask" "F.Paste")
			(net "GND")
		)
		(pad "AP44" smd circle
			(at -2.427732 -11.567668 270)
			(size 0.4318 0.4318)
			(layers "F.Cu" "F.Mask" "F.Paste")
			(net "M_D_CPU1_SA_PAR")
		)
		(pad "AP47" smd circle
			(at 1.613916 -11.457686 270)
			(size 0.4318 0.4318)
			(layers "F.Cu" "F.Mask" "F.Paste")
			(net "M_B_CPU1_SB_RSP<1>")
		)
		(pad "AP49" smd circle
			(at 3.241802 -11.457686 270)
			(size 0.4318 0.4318)
			(layers "F.Cu" "F.Mask" "F.Paste")
			(net "GND")
		)
		(pad "AP51" smd circle
			(at 4.869434 -11.457686 270)
			(size 0.4318 0.4318)
			(layers "F.Cu" "F.Mask" "F.Paste")
			(net "M_D_CPU1_SA_CA<3>")
		)
		(pad "AP53" smd circle
			(at 6.49732 -11.457686 270)
			(size 0.4318 0.4318)
			(layers "F.Cu" "F.Mask" "F.Paste")
			(net "M_D_CPU1_SA_CS_N<3>")
		)
		(pad "AP55" smd circle
			(at 8.124952 -11.457686 270)
			(size 0.4318 0.4318)
			(layers "F.Cu" "F.Mask" "F.Paste")
			(net "GND")
		)
		(pad "AP57" smd circle
			(at 9.752838 -11.457686 270)
			(size 0.4318 0.4318)
			(layers "F.Cu" "F.Mask" "F.Paste")
			(net "M_D_CPU1_SA_CB<6>")
		)
		(pad "AP59" smd circle
			(at 11.380724 -11.457686 270)
			(size 0.4318 0.4318)
			(layers "F.Cu" "F.Mask" "F.Paste")
			(net "M_D_CPU1_SA_CB<3>")
		)
		(pad "AP61" smd circle
			(at 13.008356 -11.457686 270)
			(size 0.4318 0.4318)
			(layers "F.Cu" "F.Mask" "F.Paste")
			(net "GND")
		)
		(pad "AP63" smd circle
			(at 14.635988 -11.457686 270)
			(size 0.4318 0.4318)
			(layers "F.Cu" "F.Mask" "F.Paste")
			(net "M_D_CPU1_SA_DQ<30>")
		)
		(pad "AP65" smd circle
			(at 16.263874 -11.457686 270)
			(size 0.4318 0.4318)
			(layers "F.Cu" "F.Mask" "F.Paste")
			(net "M_D_CPU1_SA_DQ<27>")
		)
		(pad "AP67" smd circle
			(at 17.89176 -11.457686 270)
			(size 0.4318 0.4318)
			(layers "F.Cu" "F.Mask" "F.Paste")
			(net "GND")
		)
		(pad "AP69" smd circle
			(at 19.519392 -11.457686 270)
			(size 0.4318 0.4318)
			(layers "F.Cu" "F.Mask" "F.Paste")
			(net "M_D_CPU1_SA_DQ<22>")
		)
		(pad "AP71" smd circle
			(at 21.147278 -11.457686 270)
			(size 0.4318 0.4318)
			(layers "F.Cu" "F.Mask" "F.Paste")
			(net "M_D_CPU1_SA_DQ<19>")
		)
		(pad "AP73" smd circle
			(at 22.77491 -11.457686 270)
			(size 0.4318 0.4318)
			(layers "F.Cu" "F.Mask" "F.Paste")
			(net "GND")
		)
		(pad "AP75" smd circle
			(at 24.402796 -11.457686 270)
			(size 0.4318 0.4318)
			(layers "F.Cu" "F.Mask" "F.Paste")
			(net "M_D_CPU1_SA_DQ<14>")
		)
		(pad "AP77" smd circle
			(at 26.030682 -11.457686 270)
			(size 0.4318 0.4318)
			(layers "F.Cu" "F.Mask" "F.Paste")
			(net "M_D_CPU1_SA_DQ<11>")
		)
		(pad "AP79" smd circle
			(at 27.658314 -11.457686 270)
			(size 0.4318 0.4318)
			(layers "F.Cu" "F.Mask" "F.Paste")
			(net "GND")
		)
		(pad "AP81" smd circle
			(at 29.2862 -11.457686 270)
			(size 0.4318 0.4318)
			(layers "F.Cu" "F.Mask" "F.Paste")
			(net "UPI_CPU1_CPU0_P2P2_DP<12>")
		)
		(pad "AP83" smd circle
			(at 30.914086 -11.457686 270)
			(size 0.4318 0.4318)
			(layers "F.Cu" "F.Mask" "F.Paste")
			(net "GND")
		)
		(pad "AP85" smd circle
			(at 32.541718 -11.457686 270)
			(size 0.4318 0.4318)
			(layers "F.Cu" "F.Mask" "F.Paste")
			(net "P5E_CPU1_PE4_TX_DN<11>")
		)
		(pad "AP87" smd circle
			(at 34.169604 -11.457686 270)
			(size 0.4318 0.4318)
			(layers "F.Cu" "F.Mask" "F.Paste")
			(net "GND")
		)
		(pad "AP89" smd circle
			(at 35.797236 -11.457686 270)
			(size 0.4318 0.4318)
			(layers "F.Cu" "F.Mask" "F.Paste")
			(net "P5E_CPU1_PE4_RX_DN<11>")
		)
		(pad "AP91" smd oval
			(at 37.425122 -11.457686)
			(size 0.381 0.4826)
			(drill
				(offset 0 -0.0508)
			)
			(layers "F.Cu" "F.Mask" "F.Paste")
			(net "GND")
		)
		(pad "AR1" smd oval
			(at -37.425122 -11.097514 180)
			(size 0.381 0.4826)
			(drill
				(offset 0 -0.0508)
			)
			(layers "F.Cu" "F.Mask" "F.Paste")
			(net "GND")
		)
		(pad "AR3" smd circle
			(at -35.797236 -11.097514 270)
			(size 0.4318 0.4318)
			(layers "F.Cu" "F.Mask" "F.Paste")
			(net "UPI_CPU1_CPU0_P0P1_DP<13>")
		)
		(pad "AR5" smd circle
			(at -34.169604 -11.097514 270)
			(size 0.4318 0.4318)
			(layers "F.Cu" "F.Mask" "F.Paste")
			(net "GND")
		)
		(pad "AR7" smd circle
			(at -32.541718 -11.097514 270)
			(size 0.4318 0.4318)
			(layers "F.Cu" "F.Mask" "F.Paste")
			(net "UPI_CPU0_CPU1_P1P0_DP<12>")
		)
		(pad "AR9" smd circle
			(at -30.914086 -11.097514 270)
			(size 0.4318 0.4318)
			(layers "F.Cu" "F.Mask" "F.Paste")
			(net "GND")
		)
		(pad "AR11" smd circle
			(at -29.2862 -11.097514 270)
			(size 0.4318 0.4318)
			(layers "F.Cu" "F.Mask" "F.Paste")
			(net "P5E_CPU1_PE0_RX_DP<12>")
		)
		(pad "AR13" smd circle
			(at -27.658314 -11.097514 270)
			(size 0.4318 0.4318)
			(layers "F.Cu" "F.Mask" "F.Paste")
			(net "GND")
		)
		(pad "AR15" smd circle
			(at -26.030682 -11.097514 270)
			(size 0.4318 0.4318)
			(layers "F.Cu" "F.Mask" "F.Paste")
			(net "P5E_CPU1_PE0_TX_DP<11>")
		)
		(pad "AR17" smd circle
			(at -24.402796 -11.097514 270)
			(size 0.4318 0.4318)
			(layers "F.Cu" "F.Mask" "F.Paste")
			(net "NC_CPU1_UPI0_APROBE<1>")
		)
		(pad "AR19" smd circle
			(at -22.77491 -11.097514 270)
			(size 0.4318 0.4318)
			(layers "F.Cu" "F.Mask" "F.Paste")
			(net "GND")
		)
		(pad "AR21" smd circle
			(at -21.147278 -11.097514 270)
			(size 0.4318 0.4318)
			(layers "F.Cu" "F.Mask" "F.Paste")
			(net "M_D_CPU1_SB_DQS_DP<8>")
		)
		(pad "AR23" smd circle
			(at -19.519392 -11.097514 270)
			(size 0.4318 0.4318)
			(layers "F.Cu" "F.Mask" "F.Paste")
			(net "GND")
		)
		(pad "AR25" smd circle
			(at -17.89176 -11.097514 270)
			(size 0.4318 0.4318)
			(layers "F.Cu" "F.Mask" "F.Paste")
			(net "GND")
		)
		(pad "AR27" smd circle
			(at -16.263874 -11.097514 270)
			(size 0.4318 0.4318)
			(layers "F.Cu" "F.Mask" "F.Paste")
			(net "M_D_CPU1_SB_DQS_DP<6>")
		)
		(pad "AR29" smd circle
			(at -14.635988 -11.097514 270)
			(size 0.4318 0.4318)
			(layers "F.Cu" "F.Mask" "F.Paste")
			(net "GND")
		)
		(pad "AR31" smd circle
			(at -13.008356 -11.097514 270)
			(size 0.4318 0.4318)
			(layers "F.Cu" "F.Mask" "F.Paste")
			(net "GND")
		)
		(pad "AR33" smd circle
			(at -11.380724 -11.097514 270)
			(size 0.4318 0.4318)
			(layers "F.Cu" "F.Mask" "F.Paste")
			(net "M_D_CPU1_SB_DQS_DP<5>")
		)
		(pad "AR35" smd circle
			(at -9.752838 -11.097514 270)
			(size 0.4318 0.4318)
			(layers "F.Cu" "F.Mask" "F.Paste")
			(net "GND")
		)
		(pad "AR37" smd circle
			(at -8.124952 -11.097514 270)
			(size 0.4318 0.4318)
			(layers "F.Cu" "F.Mask" "F.Paste")
			(net "GND")
		)
		(pad "AR39" smd circle
			(at -6.49732 -11.097514 270)
			(size 0.4318 0.4318)
			(layers "F.Cu" "F.Mask" "F.Paste")
			(net "M_D_CPU1_SB_DQS_DN<4>")
		)
		(pad "AR41" smd circle
			(at -4.869434 -11.097514 270)
			(size 0.4318 0.4318)
			(layers "F.Cu" "F.Mask" "F.Paste")
			(net "GND")
		)
		(pad "AR43" smd circle
			(at -3.241802 -11.097514 270)
			(size 0.4318 0.4318)
			(layers "F.Cu" "F.Mask" "F.Paste")
			(net "GND")
		)
		(pad "AR45" smd circle
			(at -1.613916 -11.097514 270)
			(size 0.4318 0.4318)
			(layers "F.Cu" "F.Mask" "F.Paste")
			(net "M_D_CPU1_CLK_DP<1>")
		)
		(pad "AR48" smd circle
			(at 2.427732 -10.987532 270)
			(size 0.4318 0.4318)
			(layers "F.Cu" "F.Mask" "F.Paste")
			(net "GND")
		)
		(pad "AR50" smd circle
			(at 4.055618 -10.987532 270)
			(size 0.4318 0.4318)
			(layers "F.Cu" "F.Mask" "F.Paste")
			(net "GND")
		)
		(pad "AR52" smd circle
			(at 5.68325 -10.987532 270)
			(size 0.4318 0.4318)
			(layers "F.Cu" "F.Mask" "F.Paste")
			(net "M_D_CPU1_SA_CA<1>")
		)
		(pad "AR54" smd circle
			(at 7.311136 -10.987532 270)
			(size 0.4318 0.4318)
			(layers "F.Cu" "F.Mask" "F.Paste")
			(net "GND")
		)
		(pad "AR56" smd circle
			(at 8.939022 -10.987532 270)
			(size 0.4318 0.4318)
			(layers "F.Cu" "F.Mask" "F.Paste")
			(net "GND")
		)
		(pad "AR58" smd circle
			(at 10.566654 -10.987532 270)
			(size 0.4318 0.4318)
			(layers "F.Cu" "F.Mask" "F.Paste")
			(net "M_D_CPU1_SA_DQS_DP<9>")
		)
		(pad "AR60" smd circle
			(at 12.19454 -10.987532 270)
			(size 0.4318 0.4318)
			(layers "F.Cu" "F.Mask" "F.Paste")
			(net "GND")
		)
		(pad "AR62" smd circle
			(at 13.822426 -10.987532 270)
			(size 0.4318 0.4318)
			(layers "F.Cu" "F.Mask" "F.Paste")
			(net "GND")
		)
		(pad "AR64" smd circle
			(at 15.450058 -10.987532 270)
			(size 0.4318 0.4318)
			(layers "F.Cu" "F.Mask" "F.Paste")
			(net "M_D_CPU1_SA_DQS_DP<8>")
		)
		(pad "AR66" smd circle
			(at 17.07769 -10.987532 270)
			(size 0.4318 0.4318)
			(layers "F.Cu" "F.Mask" "F.Paste")
			(net "GND")
		)
		(pad "AR68" smd circle
			(at 18.705576 -10.987532 270)
			(size 0.4318 0.4318)
			(layers "F.Cu" "F.Mask" "F.Paste")
			(net "GND")
		)
		(pad "AR70" smd circle
			(at 20.333462 -10.987532 270)
			(size 0.4318 0.4318)
			(layers "F.Cu" "F.Mask" "F.Paste")
			(net "M_D_CPU1_SA_DQS_DP<7>")
		)
		(pad "AR72" smd circle
			(at 21.961094 -10.987532 270)
			(size 0.4318 0.4318)
			(layers "F.Cu" "F.Mask" "F.Paste")
			(net "GND")
		)
		(pad "AR74" smd circle
			(at 23.58898 -10.987532 270)
			(size 0.4318 0.4318)
			(layers "F.Cu" "F.Mask" "F.Paste")
			(net "GND")
		)
		(pad "AR76" smd circle
			(at 25.216612 -10.987532 270)
			(size 0.4318 0.4318)
			(layers "F.Cu" "F.Mask" "F.Paste")
			(net "M_D_CPU1_SA_DQS_DP<6>")
		)
		(pad "AR78" smd circle
			(at 26.844498 -10.987532 270)
			(size 0.4318 0.4318)
			(layers "F.Cu" "F.Mask" "F.Paste")
			(net "GND")
		)
		(pad "AR80" smd circle
			(at 28.472384 -10.987532 270)
			(size 0.4318 0.4318)
			(layers "F.Cu" "F.Mask" "F.Paste")
			(net "UPI_CPU1_CPU0_P2P2_DN<14>")
		)
		(pad "AR82" smd circle
			(at 30.100016 -10.987532 270)
			(size 0.4318 0.4318)
			(layers "F.Cu" "F.Mask" "F.Paste")
			(net "GND")
		)
		(pad "AR84" smd circle
			(at 31.727902 -10.987532 270)
			(size 0.4318 0.4318)
			(layers "F.Cu" "F.Mask" "F.Paste")
			(net "GND")
		)
		(pad "AR86" smd circle
			(at 33.355534 -10.987532 270)
			(size 0.4318 0.4318)
			(layers "F.Cu" "F.Mask" "F.Paste")
			(net "P5E_CPU1_PE4_TX_DN<12>")
		)
		(pad "AR88" smd circle
			(at 34.98342 -10.987532 270)
			(size 0.4318 0.4318)
			(layers "F.Cu" "F.Mask" "F.Paste")
			(net "GND")
		)
		(pad "AR90" smd circle
			(at 36.611306 -10.987532 270)
			(size 0.4318 0.4318)
			(layers "F.Cu" "F.Mask" "F.Paste")
			(net "P5E_CPU1_PE4_RX_DP<12>")
		)
		(pad "AT2" smd circle
			(at -36.611306 -10.627868 270)
			(size 0.4318 0.4318)
			(layers "F.Cu" "F.Mask" "F.Paste")
			(net "UPI_CPU1_CPU0_P0P1_DN<13>")
		)
		(pad "AT4" smd circle
			(at -34.98342 -10.627868 270)
			(size 0.4318 0.4318)
			(layers "F.Cu" "F.Mask" "F.Paste")
			(net "GND")
		)
		(pad "AT6" smd circle
			(at -33.355534 -10.627868 270)
			(size 0.4318 0.4318)
			(layers "F.Cu" "F.Mask" "F.Paste")
			(net "UPI_CPU0_CPU1_P1P0_DP<13>")
		)
		(pad "AT8" smd circle
			(at -31.727902 -10.627868 270)
			(size 0.4318 0.4318)
			(layers "F.Cu" "F.Mask" "F.Paste")
			(net "GND")
		)
		(pad "AT10" smd circle
			(at -30.100016 -10.627868 270)
			(size 0.4318 0.4318)
			(layers "F.Cu" "F.Mask" "F.Paste")
			(net "P5E_CPU1_PE0_RX_DP<13>")
		)
		(pad "AT12" smd circle
			(at -28.472384 -10.627868 270)
			(size 0.4318 0.4318)
			(layers "F.Cu" "F.Mask" "F.Paste")
			(net "GND")
		)
		(pad "AT14" smd circle
			(at -26.844498 -10.627868 270)
			(size 0.4318 0.4318)
			(layers "F.Cu" "F.Mask" "F.Paste")
			(net "P5E_CPU1_PE0_TX_DP<12>")
		)
		(pad "AT16" smd circle
			(at -25.216612 -10.627868 270)
			(size 0.4318 0.4318)
			(layers "F.Cu" "F.Mask" "F.Paste")
			(net "GND")
		)
		(pad "AT18" smd circle
			(at -23.58898 -10.627868 270)
			(size 0.4318 0.4318)
			(layers "F.Cu" "F.Mask" "F.Paste")
			(net "PD_CPU1_BIST_ENABLE")
		)
		(pad "AT20" smd circle
			(at -21.961094 -10.627868 270)
			(size 0.4318 0.4318)
			(layers "F.Cu" "F.Mask" "F.Paste")
			(net "GND")
		)
		(pad "AT22" smd circle
			(at -20.333462 -10.627868 270)
			(size 0.4318 0.4318)
			(layers "F.Cu" "F.Mask" "F.Paste")
			(net "GND")
		)
		(pad "AT24" smd circle
			(at -18.705576 -10.627868 270)
			(size 0.4318 0.4318)
			(layers "F.Cu" "F.Mask" "F.Paste")
			(net "CPU1_RSVD<4>")
		)
		(pad "AT26" smd circle
			(at -17.07769 -10.627868 270)
			(size 0.4318 0.4318)
			(layers "F.Cu" "F.Mask" "F.Paste")
			(net "GND")
		)
		(pad "AT28" smd circle
			(at -15.450058 -10.627868 270)
			(size 0.4318 0.4318)
			(layers "F.Cu" "F.Mask" "F.Paste")
			(net "GND")
		)
		(pad "AT30" smd circle
			(at -13.822426 -10.627868 270)
			(size 0.4318 0.4318)
			(layers "F.Cu" "F.Mask" "F.Paste")
			(net "CLK_100M_DB2000_CPU1_BCLK0_DN")
		)
		(pad "AT32" smd circle
			(at -12.19454 -10.627868 270)
			(size 0.4318 0.4318)
			(layers "F.Cu" "F.Mask" "F.Paste")
			(net "GND")
		)
		(pad "AT34" smd circle
			(at -10.566654 -10.627868 270)
			(size 0.4318 0.4318)
			(layers "F.Cu" "F.Mask" "F.Paste")
			(net "GND")
		)
		(pad "AT36" smd circle
			(at -8.939022 -10.627868 270)
			(size 0.4318 0.4318)
			(layers "F.Cu" "F.Mask" "F.Paste")
			(net "PVCCD_HV_CPU1")
		)
		(pad "AT38" smd circle
			(at -7.311136 -10.627868 270)
			(size 0.4318 0.4318)
			(layers "F.Cu" "F.Mask" "F.Paste")
			(net "GND")
		)
		(pad "AT40" smd circle
			(at -5.68325 -10.627868 270)
			(size 0.4318 0.4318)
			(layers "F.Cu" "F.Mask" "F.Paste")
			(net "GND")
		)
		(pad "AT42" smd circle
			(at -4.055618 -10.627868 270)
			(size 0.4318 0.4318)
			(layers "F.Cu" "F.Mask" "F.Paste")
			(net "M_A_CPU1_SA_RSP<0>")
		)
		(pad "AT44" smd circle
			(at -2.427732 -10.627868 270)
			(size 0.4318 0.4318)
			(layers "F.Cu" "F.Mask" "F.Paste")
			(net "GND")
		)
		(pad "AT47" smd circle
			(at 1.613916 -10.517886 270)
			(size 0.4318 0.4318)
			(layers "F.Cu" "F.Mask" "F.Paste")
			(net "M_C_CPU1_ALERT_N")
		)
		(pad "AT49" smd circle
			(at 3.241802 -10.517886 270)
			(size 0.4318 0.4318)
			(layers "F.Cu" "F.Mask" "F.Paste")
			(net "M_A_CPU1_ALERT_N")
		)
		(pad "AT51" smd circle
			(at 4.869434 -10.517886 270)
			(size 0.4318 0.4318)
			(layers "F.Cu" "F.Mask" "F.Paste")
			(net "GND")
		)
		(pad "AT53" smd circle
			(at 6.49732 -10.517886 270)
			(size 0.4318 0.4318)
			(layers "F.Cu" "F.Mask" "F.Paste")
			(net "GND")
		)
		(pad "AT55" smd circle
			(at 8.124952 -10.517886 270)
			(size 0.4318 0.4318)
			(layers "F.Cu" "F.Mask" "F.Paste")
			(net "PVCCD_HV_CPU1")
		)
		(pad "AT57" smd circle
			(at 9.752838 -10.517886 270)
			(size 0.4318 0.4318)
			(layers "F.Cu" "F.Mask" "F.Paste")
			(net "GND")
		)
		(pad "AT59" smd circle
			(at 11.380724 -10.517886 270)
			(size 0.4318 0.4318)
			(layers "F.Cu" "F.Mask" "F.Paste")
			(net "GND")
		)
		(pad "AT61" smd circle
			(at 13.008356 -10.517886 270)
			(size 0.4318 0.4318)
			(layers "F.Cu" "F.Mask" "F.Paste")
			(net "PVCCFA_EHV_CPU1")
		)
		(pad "AT63" smd circle
			(at 14.635988 -10.517886 270)
			(size 0.4318 0.4318)
			(layers "F.Cu" "F.Mask" "F.Paste")
			(net "GND")
		)
		(pad "AT65" smd circle
			(at 16.263874 -10.517886 270)
			(size 0.4318 0.4318)
			(layers "F.Cu" "F.Mask" "F.Paste")
			(net "GND")
		)
		(pad "AT67" smd circle
			(at 17.89176 -10.517886 270)
			(size 0.4318 0.4318)
			(layers "F.Cu" "F.Mask" "F.Paste")
			(net "NC_CPU1_UPI2_APROBE<1>")
		)
		(pad "AT69" smd circle
			(at 19.519392 -10.517886 270)
			(size 0.4318 0.4318)
			(layers "F.Cu" "F.Mask" "F.Paste")
			(net "GND")
		)
		(pad "AT71" smd circle
			(at 21.147278 -10.517886 270)
			(size 0.4318 0.4318)
			(layers "F.Cu" "F.Mask" "F.Paste")
			(net "GND")
		)
		(pad "AT73" smd circle
			(at 22.77491 -10.517886 270)
			(size 0.4318 0.4318)
			(layers "F.Cu" "F.Mask" "F.Paste")
			(net "PVCCFA_EHV_FIVRA_CPU1")
		)
		(pad "AT75" smd circle
			(at 24.402796 -10.517886 270)
			(size 0.4318 0.4318)
			(layers "F.Cu" "F.Mask" "F.Paste")
			(net "GND")
		)
		(pad "AT77" smd circle
			(at 26.030682 -10.517886 270)
			(size 0.4318 0.4318)
			(layers "F.Cu" "F.Mask" "F.Paste")
			(net "GND")
		)
		(pad "AT79" smd circle
			(at 27.658314 -10.517886 270)
			(size 0.4318 0.4318)
			(layers "F.Cu" "F.Mask" "F.Paste")
			(net "GND")
		)
		(pad "AT81" smd circle
			(at 29.2862 -10.517886 270)
			(size 0.4318 0.4318)
			(layers "F.Cu" "F.Mask" "F.Paste")
			(net "UPI_CPU1_CPU0_P2P2_DP<14>")
		)
		(pad "AT83" smd circle
			(at 30.914086 -10.517886 270)
			(size 0.4318 0.4318)
			(layers "F.Cu" "F.Mask" "F.Paste")
			(net "UPI_CPU1_CPU0_P2P2_DN<15>")
		)
		(pad "AT85" smd circle
			(at 32.541718 -10.517886 270)
			(size 0.4318 0.4318)
			(layers "F.Cu" "F.Mask" "F.Paste")
			(net "VSENSE_PVCCFA_EHV_FIVRA_CPU1_DN")
		)
		(pad "AT87" smd circle
			(at 34.169604 -10.517886 270)
			(size 0.4318 0.4318)
			(layers "F.Cu" "F.Mask" "F.Paste")
			(net "P5E_CPU1_PE4_TX_DP<12>")
		)
		(pad "AT89" smd circle
			(at 35.797236 -10.517886 270)
			(size 0.4318 0.4318)
			(layers "F.Cu" "F.Mask" "F.Paste")
			(net "PVCCFA_EHV_FIVRA_CPU1")
		)
		(pad "AT91" smd oval
			(at 37.425122 -10.517886)
			(size 0.381 0.4826)
			(drill
				(offset 0 -0.0508)
			)
			(layers "F.Cu" "F.Mask" "F.Paste")
			(net "P5E_CPU1_PE4_RX_DN<12>")
		)
		(pad "AU1" smd oval
			(at -37.425122 -10.157714 180)
			(size 0.381 0.4826)
			(drill
				(offset 0 -0.0508)
			)
			(layers "F.Cu" "F.Mask" "F.Paste")
			(net "UPI_CPU1_CPU0_P0P1_DN<14>")
		)
		(pad "AU3" smd circle
			(at -35.797236 -10.157714 270)
			(size 0.4318 0.4318)
			(layers "F.Cu" "F.Mask" "F.Paste")
			(net "PVCCD_HV_CPU1")
		)
		(pad "AU5" smd circle
			(at -34.169604 -10.157714 270)
			(size 0.4318 0.4318)
			(layers "F.Cu" "F.Mask" "F.Paste")
			(net "UPI_CPU0_CPU1_P1P0_DN<13>")
		)
		(pad "AU7" smd circle
			(at -32.541718 -10.157714 270)
			(size 0.4318 0.4318)
			(layers "F.Cu" "F.Mask" "F.Paste")
			(net "PVCCD_HV_CPU1")
		)
		(pad "AU9" smd circle
			(at -30.914086 -10.157714 270)
			(size 0.4318 0.4318)
			(layers "F.Cu" "F.Mask" "F.Paste")
			(net "P5E_CPU1_PE0_RX_DN<13>")
		)
		(pad "AU11" smd circle
			(at -29.2862 -10.157714 270)
			(size 0.4318 0.4318)
			(layers "F.Cu" "F.Mask" "F.Paste")
			(net "VSENSE_PVCCFA_EHV_CPU1_DP")
		)
		(pad "AU13" smd circle
			(at -27.658314 -10.157714 270)
			(size 0.4318 0.4318)
			(layers "F.Cu" "F.Mask" "F.Paste")
			(net "P5E_CPU1_PE0_TX_DN<12>")
		)
		(pad "AU15" smd circle
			(at -26.030682 -10.157714 270)
			(size 0.4318 0.4318)
			(layers "F.Cu" "F.Mask" "F.Paste")
			(net "PVCCFA_EHV_FIVRA_CPU1")
		)
		(pad "AU17" smd circle
			(at -24.402796 -10.157714 270)
			(size 0.4318 0.4318)
			(layers "F.Cu" "F.Mask" "F.Paste")
			(net "PU_CPU1_FRMAGENT")
		)
		(pad "AU19" smd circle
			(at -22.77491 -10.157714 270)
			(size 0.4318 0.4318)
			(layers "F.Cu" "F.Mask" "F.Paste")
			(net "H_CPU1_PROCHOT_LVC1_N")
		)
		(pad "AU21" smd circle
			(at -21.147278 -10.157714 270)
			(size 0.4318 0.4318)
			(layers "F.Cu" "F.Mask" "F.Paste")
			(net "H_CPU1_MEMHOT_IN_LVC1_N")
		)
		(pad "AU23" smd circle
			(at -19.519392 -10.157714 270)
			(size 0.4318 0.4318)
			(layers "F.Cu" "F.Mask" "F.Paste")
			(net "PU_CPU1_SAFE_MODE_BOOT")
		)
		(pad "AU25" smd circle
			(at -17.89176 -10.157714 270)
			(size 0.4318 0.4318)
			(layers "F.Cu" "F.Mask" "F.Paste")
			(net "CPU1_RSVD<6>")
		)
		(pad "AU27" smd circle
			(at -16.263874 -10.157714 270)
			(size 0.4318 0.4318)
			(layers "F.Cu" "F.Mask" "F.Paste")
			(net "GND")
		)
		(pad "AU29" smd circle
			(at -14.635988 -10.157714 270)
			(size 0.4318 0.4318)
			(layers "F.Cu" "F.Mask" "F.Paste")
			(net "CLK_100M_DB2000_CPU1_BCLK2_DN")
		)
		(pad "AU31" smd circle
			(at -13.008356 -10.157714 270)
			(size 0.4318 0.4318)
			(layers "F.Cu" "F.Mask" "F.Paste")
			(net "GND")
		)
		(pad "AU33" smd circle
			(at -11.380724 -10.157714 270)
			(size 0.4318 0.4318)
			(layers "F.Cu" "F.Mask" "F.Paste")
			(net "NC_CPU1_DDR23_VIEWDIG1")
		)
		(pad "AU35" smd circle
			(at -9.752838 -10.157714 270)
			(size 0.4318 0.4318)
			(layers "F.Cu" "F.Mask" "F.Paste")
			(net "PVCCD_HV_CPU1")
		)
		(pad "AU37" smd circle
			(at -8.124952 -10.157714 270)
			(size 0.4318 0.4318)
			(layers "F.Cu" "F.Mask" "F.Paste")
			(net "GND")
		)
		(pad "AU39" smd circle
			(at -6.49732 -10.157714 270)
			(size 0.4318 0.4318)
			(layers "F.Cu" "F.Mask" "F.Paste")
			(net "GND")
		)
		(pad "AU41" smd circle
			(at -4.869434 -10.157714 270)
			(size 0.4318 0.4318)
			(layers "F.Cu" "F.Mask" "F.Paste")
			(net "GND")
		)
		(pad "AU43" smd circle
			(at -3.241802 -10.157714 270)
			(size 0.4318 0.4318)
			(layers "F.Cu" "F.Mask" "F.Paste")
			(net "M_A_CPU1_SA_RSP<1>")
		)
		(pad "AU45" smd circle
			(at -1.613916 -10.157714 270)
			(size 0.4318 0.4318)
			(layers "F.Cu" "F.Mask" "F.Paste")
			(net "GND")
		)
		(pad "AU48" smd circle
			(at 2.427732 -10.047732 270)
			(size 0.4318 0.4318)
			(layers "F.Cu" "F.Mask" "F.Paste")
			(net "GND")
		)
		(pad "AU50" smd circle
			(at 4.055618 -10.047732 270)
			(size 0.4318 0.4318)
			(layers "F.Cu" "F.Mask" "F.Paste")
			(net "RST_CPU1_DRAM_AB_N")
		)
		(pad "AU52" smd circle
			(at 5.68325 -10.047732 270)
			(size 0.4318 0.4318)
			(layers "F.Cu" "F.Mask" "F.Paste")
			(net "TP_CPU1_SPARE5")
		)
		(pad "AU54" smd circle
			(at 7.311136 -10.047732 270)
			(size 0.4318 0.4318)
			(layers "F.Cu" "F.Mask" "F.Paste")
			(net "PVCCD_HV_CPU1")
		)
		(pad "AU56" smd circle
			(at 8.939022 -10.047732 270)
			(size 0.4318 0.4318)
			(layers "F.Cu" "F.Mask" "F.Paste")
			(net "NC_CPU1_DDR01_VIEWDIG1")
		)
		(pad "AU58" smd circle
			(at 10.566654 -10.047732 270)
			(size 0.4318 0.4318)
			(layers "F.Cu" "F.Mask" "F.Paste")
			(net "NC_CPU1_DDR01_VIEWDIG0")
		)
		(pad "AU60" smd circle
			(at 12.19454 -10.047732 270)
			(size 0.4318 0.4318)
			(layers "F.Cu" "F.Mask" "F.Paste")
			(net "PVCCFA_EHV_CPU1")
		)
		(pad "AU62" smd circle
			(at 13.822426 -10.047732 270)
			(size 0.4318 0.4318)
			(layers "F.Cu" "F.Mask" "F.Paste")
			(net "NC_SPI_CPU1_NCM_CLK")
		)
		(pad "AU64" smd circle
			(at 15.450058 -10.047732 270)
			(size 0.4318 0.4318)
			(layers "F.Cu" "F.Mask" "F.Paste")
			(net "NC_ESPI_IBL_CPU1_IO2")
		)
		(pad "AU66" smd circle
			(at 17.07769 -10.047732 270)
			(size 0.4318 0.4318)
			(layers "F.Cu" "F.Mask" "F.Paste")
			(net "NC_CPU1_PE4_APROBE<1>")
		)
		(pad "AU68" smd circle
			(at 18.705576 -10.047732 270)
			(size 0.4318 0.4318)
			(layers "F.Cu" "F.Mask" "F.Paste")
			(net "NC_CPU1_UPI2_APROBE<0>")
		)
		(pad "AU70" smd circle
			(at 20.333462 -10.047732 270)
			(size 0.4318 0.4318)
			(layers "F.Cu" "F.Mask" "F.Paste")
			(net "GND")
		)
		(pad "AU72" smd circle
			(at 21.961094 -10.047732 270)
			(size 0.4318 0.4318)
			(layers "F.Cu" "F.Mask" "F.Paste")
			(net "GND")
		)
		(pad "AU74" smd circle
			(at 23.58898 -10.047732 270)
			(size 0.4318 0.4318)
			(layers "F.Cu" "F.Mask" "F.Paste")
			(net "GND")
		)
		(pad "AU76" smd circle
			(at 25.216612 -10.047732 270)
			(size 0.4318 0.4318)
			(layers "F.Cu" "F.Mask" "F.Paste")
			(net "GND")
		)
		(pad "AU78" smd circle
			(at 26.844498 -10.047732 270)
			(size 0.4318 0.4318)
			(layers "F.Cu" "F.Mask" "F.Paste")
			(net "UPI_CPU1_CPU0_P2P2_DN<11>")
		)
		(pad "AU80" smd circle
			(at 28.472384 -10.047732 270)
			(size 0.4318 0.4318)
			(layers "F.Cu" "F.Mask" "F.Paste")
			(net "GND")
		)
		(pad "AU82" smd circle
			(at 30.100016 -10.047732 270)
			(size 0.4318 0.4318)
			(layers "F.Cu" "F.Mask" "F.Paste")
			(net "UPI_CPU1_CPU0_P2P2_DP<16>")
		)
		(pad "AU84" smd circle
			(at 31.727902 -10.047732 270)
			(size 0.4318 0.4318)
			(layers "F.Cu" "F.Mask" "F.Paste")
			(net "GND")
		)
		(pad "AU86" smd circle
			(at 33.355534 -10.047732 270)
			(size 0.4318 0.4318)
			(layers "F.Cu" "F.Mask" "F.Paste")
			(net "P5E_CPU1_PE4_TX_DN<13>")
		)
		(pad "AU88" smd circle
			(at 34.98342 -10.047732 270)
			(size 0.4318 0.4318)
			(layers "F.Cu" "F.Mask" "F.Paste")
			(net "GND")
		)
		(pad "AU90" smd circle
			(at 36.611306 -10.047732 270)
			(size 0.4318 0.4318)
			(layers "F.Cu" "F.Mask" "F.Paste")
			(net "P5E_CPU1_PE4_RX_DP<13>")
		)
		(pad "AV2" smd circle
			(at -36.611306 -9.688068 270)
			(size 0.4318 0.4318)
			(layers "F.Cu" "F.Mask" "F.Paste")
			(net "UPI_CPU1_CPU0_P0P1_DP<14>")
		)
		(pad "AV4" smd circle
			(at -34.98342 -9.688068 270)
			(size 0.4318 0.4318)
			(layers "F.Cu" "F.Mask" "F.Paste")
			(net "GND")
		)
		(pad "AV6" smd circle
			(at -33.355534 -9.688068 270)
			(size 0.4318 0.4318)
			(layers "F.Cu" "F.Mask" "F.Paste")
			(net "UPI_CPU0_CPU1_P1P0_DN<14>")
		)
		(pad "AV8" smd circle
			(at -31.727902 -9.688068 270)
			(size 0.4318 0.4318)
			(layers "F.Cu" "F.Mask" "F.Paste")
			(net "GND")
		)
		(pad "AV10" smd circle
			(at -30.100016 -9.688068 270)
			(size 0.4318 0.4318)
			(layers "F.Cu" "F.Mask" "F.Paste")
			(net "P5E_CPU1_PE0_RX_DN<14>")
		)
		(pad "AV12" smd circle
			(at -28.472384 -9.688068 270)
			(size 0.4318 0.4318)
			(layers "F.Cu" "F.Mask" "F.Paste")
			(net "GND")
		)
		(pad "AV14" smd circle
			(at -26.844498 -9.688068 270)
			(size 0.4318 0.4318)
			(layers "F.Cu" "F.Mask" "F.Paste")
			(net "P5E_CPU1_PE0_TX_DN<13>")
		)
		(pad "AV16" smd circle
			(at -25.216612 -9.688068 270)
			(size 0.4318 0.4318)
			(layers "F.Cu" "F.Mask" "F.Paste")
			(net "GND")
		)
		(pad "AV18" smd circle
			(at -23.58898 -9.688068 270)
			(size 0.4318 0.4318)
			(layers "F.Cu" "F.Mask" "F.Paste")
			(net "H_CPU1_NMI_LVC1_N")
		)
		(pad "AV20" smd circle
			(at -21.961094 -9.688068 270)
			(size 0.4318 0.4318)
			(layers "F.Cu" "F.Mask" "F.Paste")
			(net "PWRGD_CPU1_LVC1")
		)
		(pad "AV22" smd circle
			(at -20.333462 -9.688068 270)
			(size 0.4318 0.4318)
			(layers "F.Cu" "F.Mask" "F.Paste")
			(net "H_CPU1_PREQ_QS_GTL_R_N")
		)
		(pad "AV24" smd circle
			(at -18.705576 -9.688068 270)
			(size 0.4318 0.4318)
			(layers "F.Cu" "F.Mask" "F.Paste")
			(net "H_CPU1_MEMTRIP_LVC1_R_N")
		)
		(pad "AV26" smd circle
			(at -17.07769 -9.688068 270)
			(size 0.4318 0.4318)
			(layers "F.Cu" "F.Mask" "F.Paste")
			(net "CPU1_RSVD<15>")
		)
		(pad "AV28" smd circle
			(at -15.450058 -9.688068 270)
			(size 0.4318 0.4318)
			(layers "F.Cu" "F.Mask" "F.Paste")
			(net "CLK_100M_DB2000_CPU1_BCLK2_DP")
		)
		(pad "AV30" smd circle
			(at -13.822426 -9.688068 270)
			(size 0.4318 0.4318)
			(layers "F.Cu" "F.Mask" "F.Paste")
			(net "CLK_100M_DB2000_CPU1_BCLK0_DP")
		)
		(pad "AV32" smd circle
			(at -12.19454 -9.688068 270)
			(size 0.4318 0.4318)
			(layers "F.Cu" "F.Mask" "F.Paste")
			(net "NC_CPU1_DDR23_VIEWDIG0")
		)
		(pad "AV34" smd circle
			(at -10.566654 -9.688068 270)
			(size 0.4318 0.4318)
			(layers "F.Cu" "F.Mask" "F.Paste")
			(net "PVCCD_HV_CPU1")
		)
		(pad "AV36" smd circle
			(at -8.939022 -9.688068 270)
			(size 0.4318 0.4318)
			(layers "F.Cu" "F.Mask" "F.Paste")
			(net "PVCCD_HV_CPU1")
		)
		(pad "AV38" smd circle
			(at -7.311136 -9.688068 270)
			(size 0.4318 0.4318)
			(layers "F.Cu" "F.Mask" "F.Paste")
			(net "NC_CPU1_THERMADC")
		)
		(pad "AV40" smd circle
			(at -5.68325 -9.688068 270)
			(size 0.4318 0.4318)
			(layers "F.Cu" "F.Mask" "F.Paste")
			(net "NC_CPU1_THERMADA")
		)
		(pad "AV42" smd circle
			(at -4.055618 -9.688068 270)
			(size 0.4318 0.4318)
			(layers "F.Cu" "F.Mask" "F.Paste")
			(net "M_A_CPU1_SB_RSP<1>")
		)
		(pad "AV44" smd circle
			(at -2.427732 -9.688068 270)
			(size 0.4318 0.4318)
			(layers "F.Cu" "F.Mask" "F.Paste")
			(net "M_A_CPU1_SB_RSP<0>")
		)
		(pad "AV47" smd circle
			(at 1.613916 -9.578086 270)
			(size 0.4318 0.4318)
			(layers "F.Cu" "F.Mask" "F.Paste")
			(net "M_D_CPU1_ALERT_N")
		)
		(pad "AV49" smd circle
			(at 3.241802 -9.578086 270)
			(size 0.4318 0.4318)
			(layers "F.Cu" "F.Mask" "F.Paste")
			(net "M_B_CPU1_ALERT_N")
		)
		(pad "AV51" smd circle
			(at 4.869434 -9.578086 270)
			(size 0.4318 0.4318)
			(layers "F.Cu" "F.Mask" "F.Paste")
			(net "RST_CPU1_DRAM_CD_N")
		)
		(pad "AV53" smd circle
			(at 6.49732 -9.578086 270)
			(size 0.4318 0.4318)
			(layers "F.Cu" "F.Mask" "F.Paste")
			(net "PVCCD_HV_CPU1")
		)
		(pad "AV55" smd circle
			(at 8.124952 -9.578086 270)
			(size 0.4318 0.4318)
			(layers "F.Cu" "F.Mask" "F.Paste")
			(net "PVCCD_HV_CPU1")
		)
		(pad "AV57" smd circle
			(at 9.752838 -9.578086 270)
			(size 0.4318 0.4318)
			(layers "F.Cu" "F.Mask" "F.Paste")
			(net "FM_CPU_FBRK_DEBUG_R_N")
		)
		(pad "AV59" smd circle
			(at 11.380724 -9.578086 270)
			(size 0.4318 0.4318)
			(layers "F.Cu" "F.Mask" "F.Paste")
			(net "TP_EV_CPU1_EXT_BGREF")
		)
		(pad "AV61" smd circle
			(at 13.008356 -9.578086 270)
			(size 0.4318 0.4318)
			(layers "F.Cu" "F.Mask" "F.Paste")
			(net "PVCCFA_EHV_CPU1")
		)
		(pad "AV63" smd circle
			(at 14.635988 -9.578086 270)
			(size 0.4318 0.4318)
			(layers "F.Cu" "F.Mask" "F.Paste")
			(net "NC_SPI_S3M_CPU1_CS1_LVC1_R_N")
		)
		(pad "AV65" smd circle
			(at 16.263874 -9.578086 270)
			(size 0.4318 0.4318)
			(layers "F.Cu" "F.Mask" "F.Paste")
			(net "NC_CPU1_MDFI_DIE01_EW0")
		)
		(pad "AV67" smd circle
			(at 17.89176 -9.578086 270)
			(size 0.4318 0.4318)
			(layers "F.Cu" "F.Mask" "F.Paste")
			(net "NC_CPU1_PE4_APROBE<0>")
		)
		(pad "AV69" smd circle
			(at 19.519392 -9.578086 270)
			(size 0.4318 0.4318)
			(layers "F.Cu" "F.Mask" "F.Paste")
			(net "FM_S3M_CPU1_LVC1_GPIO_2")
		)
		(pad "AV71" smd circle
			(at 21.147278 -9.578086 270)
			(size 0.4318 0.4318)
			(layers "F.Cu" "F.Mask" "F.Paste")
			(net "FM_S3M_CPU1_LVC1_GPIO_1")
		)
		(pad "AV73" smd circle
			(at 22.77491 -9.578086 270)
			(size 0.4318 0.4318)
			(layers "F.Cu" "F.Mask" "F.Paste")
			(net "UPI_CPU0_CPU1_P2P2_DN<13>")
		)
		(pad "AV75" smd circle
			(at 24.402796 -9.578086 270)
			(size 0.4318 0.4318)
			(layers "F.Cu" "F.Mask" "F.Paste")
			(net "UPI_CPU0_CPU1_P2P2_DP<16>")
		)
		(pad "AV77" smd circle
			(at 26.030682 -9.578086 270)
			(size 0.4318 0.4318)
			(layers "F.Cu" "F.Mask" "F.Paste")
			(net "GND")
		)
		(pad "AV79" smd circle
			(at 27.658314 -9.578086 270)
			(size 0.4318 0.4318)
			(layers "F.Cu" "F.Mask" "F.Paste")
			(net "UPI_CPU1_CPU0_P2P2_DP<11>")
		)
		(pad "AV81" smd circle
			(at 29.2862 -9.578086 270)
			(size 0.4318 0.4318)
			(layers "F.Cu" "F.Mask" "F.Paste")
			(net "UPI_CPU1_CPU0_P2P2_DN<16>")
		)
		(pad "AV83" smd circle
			(at 30.914086 -9.578086 270)
			(size 0.4318 0.4318)
			(layers "F.Cu" "F.Mask" "F.Paste")
			(net "UPI_CPU1_CPU0_P2P2_DP<15>")
		)
		(pad "AV85" smd circle
			(at 32.541718 -9.578086 270)
			(size 0.4318 0.4318)
			(layers "F.Cu" "F.Mask" "F.Paste")
			(net "P5E_CPU1_PE4_TX_DP<13>")
		)
		(pad "AV87" smd circle
			(at 34.169604 -9.578086 270)
			(size 0.4318 0.4318)
			(layers "F.Cu" "F.Mask" "F.Paste")
			(net "GND")
		)
		(pad "AV89" smd circle
			(at 35.797236 -9.578086 270)
			(size 0.4318 0.4318)
			(layers "F.Cu" "F.Mask" "F.Paste")
			(net "P5E_CPU1_PE4_RX_DN<13>")
		)
		(pad "AV91" smd oval
			(at 37.425122 -9.578086)
			(size 0.381 0.4826)
			(drill
				(offset 0 -0.0508)
			)
			(layers "F.Cu" "F.Mask" "F.Paste")
			(net "GND")
		)
		(pad "AW1" smd oval
			(at -37.425122 -9.217914 180)
			(size 0.381 0.4826)
			(drill
				(offset 0 -0.0508)
			)
			(layers "F.Cu" "F.Mask" "F.Paste")
			(net "GND")
		)
		(pad "AW3" smd circle
			(at -35.797236 -9.217914 270)
			(size 0.4318 0.4318)
			(layers "F.Cu" "F.Mask" "F.Paste")
			(net "UPI_CPU1_CPU0_P0P1_DP<15>")
		)
		(pad "AW5" smd circle
			(at -34.169604 -9.217914 270)
			(size 0.4318 0.4318)
			(layers "F.Cu" "F.Mask" "F.Paste")
			(net "GND")
		)
		(pad "AW7" smd circle
			(at -32.541718 -9.217914 270)
			(size 0.4318 0.4318)
			(layers "F.Cu" "F.Mask" "F.Paste")
			(net "UPI_CPU0_CPU1_P1P0_DP<14>")
		)
		(pad "AW9" smd circle
			(at -30.914086 -9.217914 270)
			(size 0.4318 0.4318)
			(layers "F.Cu" "F.Mask" "F.Paste")
			(net "GND")
		)
		(pad "AW11" smd circle
			(at -29.2862 -9.217914 270)
			(size 0.4318 0.4318)
			(layers "F.Cu" "F.Mask" "F.Paste")
			(net "P5E_CPU1_PE0_RX_DP<14>")
		)
		(pad "AW13" smd circle
			(at -27.658314 -9.217914 270)
			(size 0.4318 0.4318)
			(layers "F.Cu" "F.Mask" "F.Paste")
			(net "GND")
		)
		(pad "AW15" smd circle
			(at -26.030682 -9.217914 270)
			(size 0.4318 0.4318)
			(layers "F.Cu" "F.Mask" "F.Paste")
			(net "P5E_CPU1_PE0_TX_DP<13>")
		)
		(pad "AW17" smd circle
			(at -24.402796 -9.217914 270)
			(size 0.4318 0.4318)
			(layers "F.Cu" "F.Mask" "F.Paste")
			(net "PD_CPU1_DMIMODE_OVERRIDE")
		)
		(pad "AW19" smd circle
			(at -22.77491 -9.217914 270)
			(size 0.4318 0.4318)
			(layers "F.Cu" "F.Mask" "F.Paste")
			(net "TP_FM_WAKE_CPU1_N")
		)
		(pad "AW21" smd circle
			(at -21.147278 -9.217914 270)
			(size 0.4318 0.4318)
			(layers "F.Cu" "F.Mask" "F.Paste")
			(net "GND")
		)
		(pad "AW23" smd circle
			(at -19.519392 -9.217914 270)
			(size 0.4318 0.4318)
			(layers "F.Cu" "F.Mask" "F.Paste")
			(net "GND")
		)
		(pad "AW25" smd circle
			(at -17.89176 -9.217914 270)
			(size 0.4318 0.4318)
			(layers "F.Cu" "F.Mask" "F.Paste")
			(net "GND")
		)
		(pad "AW60" smd circle
			(at 12.19454 -9.107932 270)
			(size 0.4318 0.4318)
			(layers "F.Cu" "F.Mask" "F.Paste")
			(net "PVCCFA_EHV_CPU1")
		)
		(pad "AW62" smd circle
			(at 13.822426 -9.107932 270)
			(size 0.4318 0.4318)
			(layers "F.Cu" "F.Mask" "F.Paste")
			(net "GND")
		)
		(pad "AW64" smd circle
			(at 15.450058 -9.107932 270)
			(size 0.4318 0.4318)
			(layers "F.Cu" "F.Mask" "F.Paste")
			(net "NC_SPI_S3M_CPU1_IO1_LVC1_R")
		)
		(pad "AW66" smd circle
			(at 17.07769 -9.107932 270)
			(size 0.4318 0.4318)
			(layers "F.Cu" "F.Mask" "F.Paste")
			(net "GND")
		)
		(pad "AW68" smd circle
			(at 18.705576 -9.107932 270)
			(size 0.4318 0.4318)
			(layers "F.Cu" "F.Mask" "F.Paste")
			(net "GND")
		)
		(pad "AW70" smd circle
			(at 20.333462 -9.107932 270)
			(size 0.4318 0.4318)
			(layers "F.Cu" "F.Mask" "F.Paste")
			(net "FM_S3M_CPU1_LVC1_GPIO_4")
		)
		(pad "AW72" smd circle
			(at 21.961094 -9.107932 270)
			(size 0.4318 0.4318)
			(layers "F.Cu" "F.Mask" "F.Paste")
			(net "GND")
		)
		(pad "AW74" smd circle
			(at 23.58898 -9.107932 270)
			(size 0.4318 0.4318)
			(layers "F.Cu" "F.Mask" "F.Paste")
			(net "UPI_CPU0_CPU1_P2P2_DN<16>")
		)
		(pad "AW76" smd circle
			(at 25.216612 -9.107932 270)
			(size 0.4318 0.4318)
			(layers "F.Cu" "F.Mask" "F.Paste")
			(net "PVCCFA_EHV_FIVRA_CPU1")
		)
		(pad "AW78" smd circle
			(at 26.844498 -9.107932 270)
			(size 0.4318 0.4318)
			(layers "F.Cu" "F.Mask" "F.Paste")
			(net "UPI_CPU1_CPU0_P2P2_DN<10>")
		)
		(pad "AW80" smd circle
			(at 28.472384 -9.107932 270)
			(size 0.4318 0.4318)
			(layers "F.Cu" "F.Mask" "F.Paste")
			(net "GND")
		)
		(pad "AW82" smd circle
			(at 30.100016 -9.107932 270)
			(size 0.4318 0.4318)
			(layers "F.Cu" "F.Mask" "F.Paste")
			(net "GND")
		)
		(pad "AW84" smd circle
			(at 31.727902 -9.107932 270)
			(size 0.4318 0.4318)
			(layers "F.Cu" "F.Mask" "F.Paste")
			(net "GND")
		)
		(pad "AW86" smd circle
			(at 33.355534 -9.107932 270)
			(size 0.4318 0.4318)
			(layers "F.Cu" "F.Mask" "F.Paste")
			(net "P5E_CPU1_PE4_TX_DN<14>")
		)
		(pad "AW88" smd circle
			(at 34.98342 -9.107932 270)
			(size 0.4318 0.4318)
			(layers "F.Cu" "F.Mask" "F.Paste")
			(net "GND")
		)
		(pad "AW90" smd circle
			(at 36.611306 -9.107932 270)
			(size 0.4318 0.4318)
			(layers "F.Cu" "F.Mask" "F.Paste")
			(net "P5E_CPU1_PE4_RX_DP<14>")
		)
		(pad "AY2" smd circle
			(at -36.611306 -8.748268 270)
			(size 0.4318 0.4318)
			(layers "F.Cu" "F.Mask" "F.Paste")
			(net "UPI_CPU1_CPU0_P0P1_DN<15>")
		)
		(pad "AY4" smd circle
			(at -34.98342 -8.748268 270)
			(size 0.4318 0.4318)
			(layers "F.Cu" "F.Mask" "F.Paste")
			(net "GND")
		)
		(pad "AY6" smd circle
			(at -33.355534 -8.748268 270)
			(size 0.4318 0.4318)
			(layers "F.Cu" "F.Mask" "F.Paste")
			(net "UPI_CPU0_CPU1_P1P0_DP<15>")
		)
		(pad "AY8" smd circle
			(at -31.727902 -8.748268 270)
			(size 0.4318 0.4318)
			(layers "F.Cu" "F.Mask" "F.Paste")
			(net "GND")
		)
		(pad "AY10" smd circle
			(at -30.100016 -8.748268 270)
			(size 0.4318 0.4318)
			(layers "F.Cu" "F.Mask" "F.Paste")
			(net "P5E_CPU1_PE0_RX_DP<15>")
		)
		(pad "AY12" smd circle
			(at -28.472384 -8.748268 270)
			(size 0.4318 0.4318)
			(layers "F.Cu" "F.Mask" "F.Paste")
			(net "GND")
		)
		(pad "AY14" smd circle
			(at -26.844498 -8.748268 270)
			(size 0.4318 0.4318)
			(layers "F.Cu" "F.Mask" "F.Paste")
			(net "P5E_CPU1_PE0_TX_DP<14>")
		)
		(pad "AY16" smd circle
			(at -25.216612 -8.748268 270)
			(size 0.4318 0.4318)
			(layers "F.Cu" "F.Mask" "F.Paste")
			(net "GND")
		)
		(pad "AY18" smd circle
			(at -23.58898 -8.748268 270)
			(size 0.4318 0.4318)
			(layers "F.Cu" "F.Mask" "F.Paste")
			(net "PVCCINFAON_CPU1")
		)
		(pad "AY20" smd circle
			(at -21.961094 -8.748268 270)
			(size 0.4318 0.4318)
			(layers "F.Cu" "F.Mask" "F.Paste")
			(net "PU_TAP_ODT_CPU1_EN")
		)
		(pad "AY22" smd circle
			(at -20.333462 -8.748268 270)
			(size 0.4318 0.4318)
			(layers "F.Cu" "F.Mask" "F.Paste")
			(net "H_CPU1_ERR1_LVC1_R_N")
		)
		(pad "AY24" smd circle
			(at -18.705576 -8.748268 270)
			(size 0.4318 0.4318)
			(layers "F.Cu" "F.Mask" "F.Paste")
			(net "NC_CPU1_SOC_SPARE0")
		)
		(pad "AY26" smd circle
			(at -17.07769 -8.748268 270)
			(size 0.4318 0.4318)
			(layers "F.Cu" "F.Mask" "F.Paste")
			(net "CPU1_RSVD<25>")
		)
		(pad "AY61" smd circle
			(at 13.008356 -8.638286 270)
			(size 0.4318 0.4318)
			(layers "F.Cu" "F.Mask" "F.Paste")
			(net "NC_SPI_CPU1_NCM_IO1")
		)
		(pad "AY63" smd circle
			(at 14.635988 -8.638286 270)
			(size 0.4318 0.4318)
			(layers "F.Cu" "F.Mask" "F.Paste")
			(net "FM_CPU1_PKGID1")
		)
		(pad "AY65" smd circle
			(at 16.263874 -8.638286 270)
			(size 0.4318 0.4318)
			(layers "F.Cu" "F.Mask" "F.Paste")
			(net "CPU1_RSVD<27>")
		)
		(pad "AY67" smd circle
			(at 17.89176 -8.638286 270)
			(size 0.4318 0.4318)
			(layers "F.Cu" "F.Mask" "F.Paste")
			(net "NC_SPI_CPU1_NCM_CS0_N")
		)
		(pad "AY69" smd circle
			(at 19.519392 -8.638286 270)
			(size 0.4318 0.4318)
			(layers "F.Cu" "F.Mask" "F.Paste")
			(net "FM_S3M_CPU1_LVC1_GPIO_3")
		)
		(pad "AY71" smd circle
			(at 21.147278 -8.638286 270)
			(size 0.4318 0.4318)
			(layers "F.Cu" "F.Mask" "F.Paste")
			(net "GND")
		)
		(pad "AY73" smd circle
			(at 22.77491 -8.638286 270)
			(size 0.4318 0.4318)
			(layers "F.Cu" "F.Mask" "F.Paste")
			(net "UPI_CPU0_CPU1_P2P2_DP<13>")
		)
		(pad "AY75" smd circle
			(at 24.402796 -8.638286 270)
			(size 0.4318 0.4318)
			(layers "F.Cu" "F.Mask" "F.Paste")
			(net "UPI_CPU0_CPU1_P2P2_DN<14>")
		)
		(pad "AY77" smd circle
			(at 26.030682 -8.638286 270)
			(size 0.4318 0.4318)
			(layers "F.Cu" "F.Mask" "F.Paste")
			(net "GND")
		)
		(pad "AY79" smd circle
			(at 27.658314 -8.638286 270)
			(size 0.4318 0.4318)
			(layers "F.Cu" "F.Mask" "F.Paste")
			(net "GND")
		)
		(pad "AY81" smd circle
			(at 29.2862 -8.638286 270)
			(size 0.4318 0.4318)
			(layers "F.Cu" "F.Mask" "F.Paste")
			(net "GND")
		)
		(pad "AY83" smd circle
			(at 30.914086 -8.638286 270)
			(size 0.4318 0.4318)
			(layers "F.Cu" "F.Mask" "F.Paste")
			(net "GND")
		)
		(pad "AY85" smd circle
			(at 32.541718 -8.638286 270)
			(size 0.4318 0.4318)
			(layers "F.Cu" "F.Mask" "F.Paste")
			(net "VSENSE_PVCCFA_EHV_FIVRA_CPU1_DP")
		)
		(pad "AY87" smd circle
			(at 34.169604 -8.638286 270)
			(size 0.4318 0.4318)
			(layers "F.Cu" "F.Mask" "F.Paste")
			(net "P5E_CPU1_PE4_TX_DP<14>")
		)
		(pad "AY89" smd circle
			(at 35.797236 -8.638286 270)
			(size 0.4318 0.4318)
			(layers "F.Cu" "F.Mask" "F.Paste")
			(net "PVCCFA_EHV_FIVRA_CPU1")
		)
		(pad "AY91" smd oval
			(at 37.425122 -8.638286)
			(size 0.381 0.4826)
			(drill
				(offset 0 -0.0508)
			)
			(layers "F.Cu" "F.Mask" "F.Paste")
			(net "P5E_CPU1_PE4_RX_DN<14>")
		)
		(pad "B6" smd oval
			(at -33.355534 -26.604468 135)
			(size 0.381 0.4826)
			(drill
				(offset 0 -0.0508)
			)
			(layers "F.Cu" "F.Mask" "F.Paste")
			(net "GND")
		)
		(pad "B8" smd oval
			(at -31.727902 -26.604468 135)
			(size 0.381 0.4826)
			(drill
				(offset 0 -0.0508)
			)
			(layers "F.Cu" "F.Mask" "F.Paste")
			(net "M_A_CPU1_SB_DQ<28>")
		)
		(pad "B10" smd oval
			(at -30.100016 -26.604468 90)
			(size 0.381 0.4826)
			(drill
				(offset 0 -0.0508)
			)
			(layers "F.Cu" "F.Mask" "F.Paste")
			(net "M_A_CPU1_SB_DQ<25>")
		)
		(pad "B12" smd circle
			(at -28.472384 -26.604468 270)
			(size 0.4318 0.4318)
			(layers "F.Cu" "F.Mask" "F.Paste")
			(net "GND")
		)
		(pad "B14" smd circle
			(at -26.844498 -26.604468 270)
			(size 0.4318 0.4318)
			(layers "F.Cu" "F.Mask" "F.Paste")
			(net "M_B_CPU1_SB_DQ<30>")
		)
		(pad "B16" smd circle
			(at -25.216612 -26.604468 270)
			(size 0.4318 0.4318)
			(layers "F.Cu" "F.Mask" "F.Paste")
			(net "M_B_CPU1_SB_DQ<25>")
		)
		(pad "B18" smd circle
			(at -23.58898 -26.604468 270)
			(size 0.4318 0.4318)
			(layers "F.Cu" "F.Mask" "F.Paste")
			(net "GND")
		)
		(pad "B20" smd circle
			(at -21.961094 -26.604468 270)
			(size 0.4318 0.4318)
			(layers "F.Cu" "F.Mask" "F.Paste")
			(net "M_A_CPU1_SB_DQ<20>")
		)
		(pad "B22" smd circle
			(at -20.333462 -26.604468 270)
			(size 0.4318 0.4318)
			(layers "F.Cu" "F.Mask" "F.Paste")
			(net "M_A_CPU1_SB_DQ<17>")
		)
		(pad "B24" smd circle
			(at -18.705576 -26.604468 270)
			(size 0.4318 0.4318)
			(layers "F.Cu" "F.Mask" "F.Paste")
			(net "GND")
		)
		(pad "B26" smd circle
			(at -17.07769 -26.604468 270)
			(size 0.4318 0.4318)
			(layers "F.Cu" "F.Mask" "F.Paste")
			(net "M_A_CPU1_SB_DQ<12>")
		)
		(pad "B28" smd circle
			(at -15.450058 -26.604468 270)
			(size 0.4318 0.4318)
			(layers "F.Cu" "F.Mask" "F.Paste")
			(net "M_A_CPU1_SB_DQ<9>")
		)
		(pad "B30" smd circle
			(at -13.822426 -26.604468 270)
			(size 0.4318 0.4318)
			(layers "F.Cu" "F.Mask" "F.Paste")
			(net "GND")
		)
		(pad "B32" smd circle
			(at -12.19454 -26.604468 270)
			(size 0.4318 0.4318)
			(layers "F.Cu" "F.Mask" "F.Paste")
			(net "M_A_CPU1_SB_CB<0>")
		)
		(pad "B34" smd circle
			(at -10.566654 -26.604468 270)
			(size 0.4318 0.4318)
			(layers "F.Cu" "F.Mask" "F.Paste")
			(net "M_A_CPU1_SB_CB<5>")
		)
		(pad "B36" smd circle
			(at -8.939022 -26.604468 270)
			(size 0.4318 0.4318)
			(layers "F.Cu" "F.Mask" "F.Paste")
			(net "GND")
		)
		(pad "B38" smd circle
			(at -7.311136 -26.604468 270)
			(size 0.4318 0.4318)
			(layers "F.Cu" "F.Mask" "F.Paste")
			(net "M_A_CPU1_SB_CS_N<0>")
		)
		(pad "B40" smd circle
			(at -5.68325 -26.604468 270)
			(size 0.4318 0.4318)
			(layers "F.Cu" "F.Mask" "F.Paste")
			(net "M_A_CPU1_SB_CA<4>")
		)
		(pad "B42" smd circle
			(at -4.055618 -26.604468 270)
			(size 0.4318 0.4318)
			(layers "F.Cu" "F.Mask" "F.Paste")
			(net "GND")
		)
		(pad "B44" smd oval
			(at -2.427732 -26.604468 45)
			(size 0.381 0.4826)
			(drill
				(offset 0 -0.0508)
			)
			(layers "F.Cu" "F.Mask" "F.Paste")
			(net "M_A_CPU1_CLK_DN<0>")
		)
		(pad "B49" smd oval
			(at 3.241802 -26.494486 135)
			(size 0.381 0.4826)
			(drill
				(offset 0 -0.0508)
			)
			(layers "F.Cu" "F.Mask" "F.Paste")
			(net "GND")
		)
		(pad "B51" smd circle
			(at 4.869434 -26.494486 270)
			(size 0.4318 0.4318)
			(layers "F.Cu" "F.Mask" "F.Paste")
			(net "M_A_CPU1_SA_CA<2>")
		)
		(pad "B53" smd circle
			(at 6.49732 -26.494486 270)
			(size 0.4318 0.4318)
			(layers "F.Cu" "F.Mask" "F.Paste")
			(net "M_A_CPU1_SA_CS_N<1>")
		)
		(pad "B55" smd circle
			(at 8.124952 -26.494486 270)
			(size 0.4318 0.4318)
			(layers "F.Cu" "F.Mask" "F.Paste")
			(net "GND")
		)
		(pad "B57" smd circle
			(at 9.752838 -26.494486 270)
			(size 0.4318 0.4318)
			(layers "F.Cu" "F.Mask" "F.Paste")
			(net "M_A_CPU1_SA_CB<4>")
		)
		(pad "B59" smd circle
			(at 11.380724 -26.494486 270)
			(size 0.4318 0.4318)
			(layers "F.Cu" "F.Mask" "F.Paste")
			(net "M_A_CPU1_SA_CB<1>")
		)
		(pad "B61" smd circle
			(at 13.008356 -26.494486 270)
			(size 0.4318 0.4318)
			(layers "F.Cu" "F.Mask" "F.Paste")
			(net "GND")
		)
		(pad "B63" smd circle
			(at 14.635988 -26.494486 270)
			(size 0.4318 0.4318)
			(layers "F.Cu" "F.Mask" "F.Paste")
			(net "M_A_CPU1_SA_DQ<28>")
		)
		(pad "B65" smd oval
			(at 16.263874 -26.494486 90)
			(size 0.381 0.4826)
			(drill
				(offset 0 -0.0508)
			)
			(layers "F.Cu" "F.Mask" "F.Paste")
			(net "M_A_CPU1_SA_DQ<25>")
		)
		(pad "B67" smd oval
			(at 17.89176 -26.494486 90)
			(size 0.381 0.4826)
			(drill
				(offset 0 -0.0508)
			)
			(layers "F.Cu" "F.Mask" "F.Paste")
			(net "GND")
		)
		(pad "B69" smd oval
			(at 19.519392 -26.494486 90)
			(size 0.381 0.4826)
			(drill
				(offset 0 -0.0508)
			)
			(layers "F.Cu" "F.Mask" "F.Paste")
			(net "M_A_CPU1_SA_DQ<20>")
		)
		(pad "B71" smd oval
			(at 21.147278 -26.494486 90)
			(size 0.381 0.4826)
			(drill
				(offset 0 -0.0508)
			)
			(layers "F.Cu" "F.Mask" "F.Paste")
			(net "M_A_CPU1_SA_DQS_DN<2>")
		)
		(pad "B73" smd oval
			(at 22.77491 -26.494486 90)
			(size 0.381 0.4826)
			(drill
				(offset 0 -0.0508)
			)
			(layers "F.Cu" "F.Mask" "F.Paste")
			(net "M_A_CPU1_SA_DQ<16>")
		)
		(pad "B75" smd oval
			(at 24.402796 -26.494486 90)
			(size 0.381 0.4826)
			(drill
				(offset 0 -0.0508)
			)
			(layers "F.Cu" "F.Mask" "F.Paste")
			(net "GND")
		)
		(pad "B77" smd oval
			(at 26.030682 -26.494486 90)
			(size 0.381 0.4826)
			(drill
				(offset 0 -0.0508)
			)
			(layers "F.Cu" "F.Mask" "F.Paste")
			(net "M_A_CPU1_SA_DQS_DN<0>")
		)
		(pad "B79" smd oval
			(at 27.658314 -26.494486 90)
			(size 0.381 0.4826)
			(drill
				(offset 0 -0.0508)
			)
			(layers "F.Cu" "F.Mask" "F.Paste")
			(net "M_A_CPU1_SA_DQ<1>")
		)
		(pad "B81" smd oval
			(at 29.2862 -26.494486 90)
			(size 0.381 0.4826)
			(drill
				(offset 0 -0.0508)
			)
			(layers "F.Cu" "F.Mask" "F.Paste")
			(net "M_A_CPU1_SA_DQ<0>")
		)
		(pad "B83" smd oval
			(at 30.914086 -26.494486 45)
			(size 0.381 0.4826)
			(drill
				(offset 0 -0.0508)
			)
			(layers "F.Cu" "F.Mask" "F.Paste")
			(net "GND")
		)
		(pad "B85" smd oval
			(at 32.541718 -26.494486 45)
			(size 0.381 0.4826)
			(drill
				(offset 0 -0.0508)
			)
			(layers "F.Cu" "F.Mask" "F.Paste")
			(net "UPI_CPU1_CPU0_P2P2_DN<0>")
		)
		(pad "B87" smd oval
			(at 34.169604 -26.494486 45)
			(size 0.381 0.4826)
			(drill
				(offset 0 -0.0508)
			)
			(layers "F.Cu" "F.Mask" "F.Paste")
			(net "GND")
		)
		(pad "BA1" smd oval
			(at -37.425122 -8.278114 180)
			(size 0.381 0.4826)
			(drill
				(offset 0 -0.0508)
			)
			(layers "F.Cu" "F.Mask" "F.Paste")
			(net "UPI_CPU1_CPU0_P0P1_DP<16>")
		)
		(pad "BA3" smd circle
			(at -35.797236 -8.278114 270)
			(size 0.4318 0.4318)
			(layers "F.Cu" "F.Mask" "F.Paste")
			(net "PVCCD_HV_CPU1")
		)
		(pad "BA5" smd circle
			(at -34.169604 -8.278114 270)
			(size 0.4318 0.4318)
			(layers "F.Cu" "F.Mask" "F.Paste")
			(net "UPI_CPU0_CPU1_P1P0_DN<15>")
		)
		(pad "BA7" smd circle
			(at -32.541718 -8.278114 270)
			(size 0.4318 0.4318)
			(layers "F.Cu" "F.Mask" "F.Paste")
			(net "PVCCD_HV_CPU1")
		)
		(pad "BA9" smd circle
			(at -30.914086 -8.278114 270)
			(size 0.4318 0.4318)
			(layers "F.Cu" "F.Mask" "F.Paste")
			(net "P5E_CPU1_PE0_RX_DN<15>")
		)
		(pad "BA11" smd circle
			(at -29.2862 -8.278114 270)
			(size 0.4318 0.4318)
			(layers "F.Cu" "F.Mask" "F.Paste")
			(net "VSENSE_PVCCFA_EHV_CPU1_DN")
		)
		(pad "BA13" smd circle
			(at -27.658314 -8.278114 270)
			(size 0.4318 0.4318)
			(layers "F.Cu" "F.Mask" "F.Paste")
			(net "P5E_CPU1_PE0_TX_DN<14>")
		)
		(pad "BA15" smd circle
			(at -26.030682 -8.278114 270)
			(size 0.4318 0.4318)
			(layers "F.Cu" "F.Mask" "F.Paste")
			(net "PVCCINFAON_CPU1")
		)
		(pad "BA17" smd circle
			(at -24.402796 -8.278114 270)
			(size 0.4318 0.4318)
			(layers "F.Cu" "F.Mask" "F.Paste")
			(net "GND")
		)
		(pad "BA19" smd circle
			(at -22.77491 -8.278114 270)
			(size 0.4318 0.4318)
			(layers "F.Cu" "F.Mask" "F.Paste")
			(net "PVNN_MAIN_CPU1")
		)
		(pad "BA21" smd circle
			(at -21.147278 -8.278114 270)
			(size 0.4318 0.4318)
			(layers "F.Cu" "F.Mask" "F.Paste")
			(net "P3V3_AUX")
		)
		(pad "BA23" smd circle
			(at -19.519392 -8.278114 270)
			(size 0.4318 0.4318)
			(layers "F.Cu" "F.Mask" "F.Paste")
			(net "PU_CPU1_UPI0_AC_COUPLING")
		)
		(pad "BA25" smd circle
			(at -17.89176 -8.278114 270)
			(size 0.4318 0.4318)
			(layers "F.Cu" "F.Mask" "F.Paste")
			(net "NC_CPU1_SOC_SPARE4")
		)
		(pad "BA60" smd circle
			(at 12.19454 -8.168132 270)
			(size 0.4318 0.4318)
			(layers "F.Cu" "F.Mask" "F.Paste")
			(net "GND")
		)
		(pad "BA62" smd circle
			(at 13.822426 -8.168132 270)
			(size 0.4318 0.4318)
			(layers "F.Cu" "F.Mask" "F.Paste")
			(net "NC_SPI_S3M_CPU1_IO0_LVC1_R")
		)
		(pad "BA64" smd circle
			(at 15.450058 -8.168132 270)
			(size 0.4318 0.4318)
			(layers "F.Cu" "F.Mask" "F.Paste")
			(net "GND")
		)
		(pad "BA66" smd circle
			(at 17.07769 -8.168132 270)
			(size 0.4318 0.4318)
			(layers "F.Cu" "F.Mask" "F.Paste")
			(net "NC_SPI_CPU1_NCM_IO0")
		)
		(pad "BA68" smd circle
			(at 18.705576 -8.168132 270)
			(size 0.4318 0.4318)
			(layers "F.Cu" "F.Mask" "F.Paste")
			(net "NC_SPI_S3M_CPU1_OE_LVC1_R_N")
		)
		(pad "BA70" smd circle
			(at 20.333462 -8.168132 270)
			(size 0.4318 0.4318)
			(layers "F.Cu" "F.Mask" "F.Paste")
			(net "FM_S3M_CPU1_LVC1_GPIO_0")
		)
		(pad "BA72" smd circle
			(at 21.961094 -8.168132 270)
			(size 0.4318 0.4318)
			(layers "F.Cu" "F.Mask" "F.Paste")
			(net "UPI_CPU0_CPU1_P2P2_DN<12>")
		)
		(pad "BA74" smd circle
			(at 23.58898 -8.168132 270)
			(size 0.4318 0.4318)
			(layers "F.Cu" "F.Mask" "F.Paste")
			(net "GND")
		)
		(pad "BA76" smd circle
			(at 25.216612 -8.168132 270)
			(size 0.4318 0.4318)
			(layers "F.Cu" "F.Mask" "F.Paste")
			(net "UPI_CPU0_CPU1_P2P2_DP<14>")
		)
		(pad "BA78" smd circle
			(at 26.844498 -8.168132 270)
			(size 0.4318 0.4318)
			(layers "F.Cu" "F.Mask" "F.Paste")
			(net "UPI_CPU1_CPU0_P2P2_DP<10>")
		)
		(pad "BA80" smd circle
			(at 28.472384 -8.168132 270)
			(size 0.4318 0.4318)
			(layers "F.Cu" "F.Mask" "F.Paste")
			(net "UPI_CPU1_CPU0_P2P2_DN<17>")
		)
		(pad "BA82" smd circle
			(at 30.100016 -8.168132 270)
			(size 0.4318 0.4318)
			(layers "F.Cu" "F.Mask" "F.Paste")
			(net "UPI_CPU1_CPU0_P2P2_DP<18>")
		)
		(pad "BA84" smd circle
			(at 31.727902 -8.168132 270)
			(size 0.4318 0.4318)
			(layers "F.Cu" "F.Mask" "F.Paste")
			(net "GND")
		)
		(pad "BA86" smd circle
			(at 33.355534 -8.168132 270)
			(size 0.4318 0.4318)
			(layers "F.Cu" "F.Mask" "F.Paste")
			(net "P5E_CPU1_PE4_TX_DN<15>")
		)
		(pad "BA88" smd circle
			(at 34.98342 -8.168132 270)
			(size 0.4318 0.4318)
			(layers "F.Cu" "F.Mask" "F.Paste")
			(net "GND")
		)
		(pad "BA90" smd circle
			(at 36.611306 -8.168132 270)
			(size 0.4318 0.4318)
			(layers "F.Cu" "F.Mask" "F.Paste")
			(net "P5E_CPU1_PE4_RX_DP<15>")
		)
		(pad "BB2" smd circle
			(at -36.611306 -7.808468 270)
			(size 0.4318 0.4318)
			(layers "F.Cu" "F.Mask" "F.Paste")
			(net "UPI_CPU1_CPU0_P0P1_DN<16>")
		)
		(pad "BB4" smd circle
			(at -34.98342 -7.808468 270)
			(size 0.4318 0.4318)
			(layers "F.Cu" "F.Mask" "F.Paste")
			(net "GND")
		)
		(pad "BB6" smd circle
			(at -33.355534 -7.808468 270)
			(size 0.4318 0.4318)
			(layers "F.Cu" "F.Mask" "F.Paste")
			(net "UPI_CPU0_CPU1_P1P0_DN<16>")
		)
		(pad "BB8" smd circle
			(at -31.727902 -7.808468 270)
			(size 0.4318 0.4318)
			(layers "F.Cu" "F.Mask" "F.Paste")
			(net "GND")
		)
		(pad "BB10" smd circle
			(at -30.100016 -7.808468 270)
			(size 0.4318 0.4318)
			(layers "F.Cu" "F.Mask" "F.Paste")
			(net "GND")
		)
		(pad "BB12" smd circle
			(at -28.472384 -7.808468 270)
			(size 0.4318 0.4318)
			(layers "F.Cu" "F.Mask" "F.Paste")
			(net "GND")
		)
		(pad "BB14" smd circle
			(at -26.844498 -7.808468 270)
			(size 0.4318 0.4318)
			(layers "F.Cu" "F.Mask" "F.Paste")
			(net "P5E_CPU1_PE0_TX_DN<15>")
		)
		(pad "BB16" smd circle
			(at -25.216612 -7.808468 270)
			(size 0.4318 0.4318)
			(layers "F.Cu" "F.Mask" "F.Paste")
			(net "GND")
		)
		(pad "BB18" smd circle
			(at -23.58898 -7.808468 270)
			(size 0.4318 0.4318)
			(layers "F.Cu" "F.Mask" "F.Paste")
			(net "TP_DMI_CPU1_PCH_RX_C_DN<0>")
		)
		(pad "BB20" smd circle
			(at -21.961094 -7.808468 270)
			(size 0.4318 0.4318)
			(layers "F.Cu" "F.Mask" "F.Paste")
			(net "GND")
		)
		(pad "BB22" smd circle
			(at -20.333462 -7.808468 270)
			(size 0.4318 0.4318)
			(layers "F.Cu" "F.Mask" "F.Paste")
			(net "GND")
		)
		(pad "BB24" smd circle
			(at -18.705576 -7.808468 270)
			(size 0.4318 0.4318)
			(layers "F.Cu" "F.Mask" "F.Paste")
			(net "GND")
		)
		(pad "BB26" smd circle
			(at -17.07769 -7.808468 270)
			(size 0.4318 0.4318)
			(layers "F.Cu" "F.Mask" "F.Paste")
			(net "GND")
		)
		(pad "BB61" smd circle
			(at 13.008356 -7.698486 270)
			(size 0.4318 0.4318)
			(layers "F.Cu" "F.Mask" "F.Paste")
			(net "NC_SPI_S3M_CPU1_CS0_LVC1_R_N")
		)
		(pad "BB63" smd circle
			(at 14.635988 -7.698486 270)
			(size 0.4318 0.4318)
			(layers "F.Cu" "F.Mask" "F.Paste")
			(net "GND")
		)
		(pad "BB65" smd circle
			(at 16.263874 -7.698486 270)
			(size 0.4318 0.4318)
			(layers "F.Cu" "F.Mask" "F.Paste")
			(net "PU_CPU1_UPI2_AC_COUPLING")
		)
		(pad "BB67" smd circle
			(at 17.89176 -7.698486 270)
			(size 0.4318 0.4318)
			(layers "F.Cu" "F.Mask" "F.Paste")
			(net "NC_SPI_CPU1_NCM_OE_N")
		)
		(pad "BB69" smd circle
			(at 19.519392 -7.698486 270)
			(size 0.4318 0.4318)
			(layers "F.Cu" "F.Mask" "F.Paste")
			(net "GND")
		)
		(pad "BB71" smd circle
			(at 21.147278 -7.698486 270)
			(size 0.4318 0.4318)
			(layers "F.Cu" "F.Mask" "F.Paste")
			(net "GND")
		)
		(pad "BB73" smd circle
			(at 22.77491 -7.698486 270)
			(size 0.4318 0.4318)
			(layers "F.Cu" "F.Mask" "F.Paste")
			(net "UPI_CPU0_CPU1_P2P2_DP<12>")
		)
		(pad "BB75" smd circle
			(at 24.402796 -7.698486 270)
			(size 0.4318 0.4318)
			(layers "F.Cu" "F.Mask" "F.Paste")
			(net "UPI_CPU0_CPU1_P2P2_DN<15>")
		)
		(pad "BB77" smd circle
			(at 26.030682 -7.698486 270)
			(size 0.4318 0.4318)
			(layers "F.Cu" "F.Mask" "F.Paste")
			(net "GND")
		)
		(pad "BB79" smd circle
			(at 27.658314 -7.698486 270)
			(size 0.4318 0.4318)
			(layers "F.Cu" "F.Mask" "F.Paste")
			(net "GND")
		)
		(pad "BB81" smd circle
			(at 29.2862 -7.698486 270)
			(size 0.4318 0.4318)
			(layers "F.Cu" "F.Mask" "F.Paste")
			(net "UPI_CPU1_CPU0_P2P2_DP<17>")
		)
		(pad "BB83" smd circle
			(at 30.914086 -7.698486 270)
			(size 0.4318 0.4318)
			(layers "F.Cu" "F.Mask" "F.Paste")
			(net "GND")
		)
		(pad "BB85" smd circle
			(at 32.541718 -7.698486 270)
			(size 0.4318 0.4318)
			(layers "F.Cu" "F.Mask" "F.Paste")
			(net "P5E_CPU1_PE4_TX_DP<15>")
		)
		(pad "BB87" smd circle
			(at 34.169604 -7.698486 270)
			(size 0.4318 0.4318)
			(layers "F.Cu" "F.Mask" "F.Paste")
			(net "GND")
		)
		(pad "BB89" smd circle
			(at 35.797236 -7.698486 270)
			(size 0.4318 0.4318)
			(layers "F.Cu" "F.Mask" "F.Paste")
			(net "P5E_CPU1_PE4_RX_DN<15>")
		)
		(pad "BB91" smd oval
			(at 37.425122 -7.698486)
			(size 0.381 0.4826)
			(drill
				(offset 0 -0.0508)
			)
			(layers "F.Cu" "F.Mask" "F.Paste")
			(net "GND")
		)
		(pad "BC1" smd oval
			(at -37.425122 -7.338314 180)
			(size 0.381 0.4826)
			(drill
				(offset 0 -0.0508)
			)
			(layers "F.Cu" "F.Mask" "F.Paste")
			(net "GND")
		)
		(pad "BC3" smd circle
			(at -35.797236 -7.338314 270)
			(size 0.4318 0.4318)
			(layers "F.Cu" "F.Mask" "F.Paste")
			(net "UPI_CPU1_CPU0_P0P1_DP<17>")
		)
		(pad "BC5" smd circle
			(at -34.169604 -7.338314 270)
			(size 0.4318 0.4318)
			(layers "F.Cu" "F.Mask" "F.Paste")
			(net "GND")
		)
		(pad "BC7" smd circle
			(at -32.541718 -7.338314 270)
			(size 0.4318 0.4318)
			(layers "F.Cu" "F.Mask" "F.Paste")
			(net "UPI_CPU0_CPU1_P1P0_DP<16>")
		)
		(pad "BC9" smd circle
			(at -30.914086 -7.338314 270)
			(size 0.4318 0.4318)
			(layers "F.Cu" "F.Mask" "F.Paste")
			(net "GND")
		)
		(pad "BC11" smd circle
			(at -29.2862 -7.338314 270)
			(size 0.4318 0.4318)
			(layers "F.Cu" "F.Mask" "F.Paste")
			(net "P5E_CPU1_PE1_RX_DN<15>")
		)
		(pad "BC13" smd circle
			(at -27.658314 -7.338314 270)
			(size 0.4318 0.4318)
			(layers "F.Cu" "F.Mask" "F.Paste")
			(net "GND")
		)
		(pad "BC15" smd circle
			(at -26.030682 -7.338314 270)
			(size 0.4318 0.4318)
			(layers "F.Cu" "F.Mask" "F.Paste")
			(net "P5E_CPU1_PE0_TX_DP<15>")
		)
		(pad "BC17" smd circle
			(at -24.402796 -7.338314 270)
			(size 0.4318 0.4318)
			(layers "F.Cu" "F.Mask" "F.Paste")
			(net "GND")
		)
		(pad "BC19" smd circle
			(at -22.77491 -7.338314 270)
			(size 0.4318 0.4318)
			(layers "F.Cu" "F.Mask" "F.Paste")
			(net "TP_DMI_CPU1_PCH_RX_C_DP<0>")
		)
		(pad "BC21" smd circle
			(at -21.147278 -7.338314 270)
			(size 0.4318 0.4318)
			(layers "F.Cu" "F.Mask" "F.Paste")
			(net "P3V3_AUX")
		)
		(pad "BC23" smd circle
			(at -19.519392 -7.338314 270)
			(size 0.4318 0.4318)
			(layers "F.Cu" "F.Mask" "F.Paste")
			(net "TP_CPU1_IFST_DONE_LVC1_R")
		)
		(pad "BC25" smd circle
			(at -17.89176 -7.338314 270)
			(size 0.4318 0.4318)
			(layers "F.Cu" "F.Mask" "F.Paste")
			(net "TP_I3C_MNG3_BMC_SW_SDA")
		)
		(pad "BC60" smd circle
			(at 12.19454 -7.228332 270)
			(size 0.4318 0.4318)
			(layers "F.Cu" "F.Mask" "F.Paste")
			(net "PVCCINFAON_CPU1")
		)
		(pad "BC62" smd circle
			(at 13.822426 -7.228332 270)
			(size 0.4318 0.4318)
			(layers "F.Cu" "F.Mask" "F.Paste")
			(net "GND")
		)
		(pad "BC64" smd circle
			(at 15.450058 -7.228332 270)
			(size 0.4318 0.4318)
			(layers "F.Cu" "F.Mask" "F.Paste")
			(net "NC_SPI_S3M_CPU1_CLK_LVC1_R")
		)
		(pad "BC66" smd circle
			(at 17.07769 -7.228332 270)
			(size 0.4318 0.4318)
			(layers "F.Cu" "F.Mask" "F.Paste")
			(net "GND")
		)
		(pad "BC68" smd circle
			(at 18.705576 -7.228332 270)
			(size 0.4318 0.4318)
			(layers "F.Cu" "F.Mask" "F.Paste")
			(net "TP_TRC_CPU1_PTI<21>")
		)
		(pad "BC70" smd circle
			(at 20.333462 -7.228332 270)
			(size 0.4318 0.4318)
			(layers "F.Cu" "F.Mask" "F.Paste")
			(net "TP_TRC_CPU1_PTI<16>")
		)
		(pad "BC72" smd circle
			(at 21.961094 -7.228332 270)
			(size 0.4318 0.4318)
			(layers "F.Cu" "F.Mask" "F.Paste")
			(net "GND")
		)
		(pad "BC74" smd circle
			(at 23.58898 -7.228332 270)
			(size 0.4318 0.4318)
			(layers "F.Cu" "F.Mask" "F.Paste")
			(net "UPI_CPU0_CPU1_P2P2_DP<23>")
		)
		(pad "BC76" smd circle
			(at 25.216612 -7.228332 270)
			(size 0.4318 0.4318)
			(layers "F.Cu" "F.Mask" "F.Paste")
			(net "GND")
		)
		(pad "BC78" smd circle
			(at 26.844498 -7.228332 270)
			(size 0.4318 0.4318)
			(layers "F.Cu" "F.Mask" "F.Paste")
			(net "GND")
		)
		(pad "BC80" smd circle
			(at 28.472384 -7.228332 270)
			(size 0.4318 0.4318)
			(layers "F.Cu" "F.Mask" "F.Paste")
			(net "UPI_CPU1_CPU0_P2P2_DP<20>")
		)
		(pad "BC82" smd circle
			(at 30.100016 -7.228332 270)
			(size 0.4318 0.4318)
			(layers "F.Cu" "F.Mask" "F.Paste")
			(net "UPI_CPU1_CPU0_P2P2_DN<18>")
		)
		(pad "BC84" smd circle
			(at 31.727902 -7.228332 270)
			(size 0.4318 0.4318)
			(layers "F.Cu" "F.Mask" "F.Paste")
			(net "GND")
		)
		(pad "BC86" smd circle
			(at 33.355534 -7.228332 270)
			(size 0.4318 0.4318)
			(layers "F.Cu" "F.Mask" "F.Paste")
			(net "GND")
		)
		(pad "BC88" smd circle
			(at 34.98342 -7.228332 270)
			(size 0.4318 0.4318)
			(layers "F.Cu" "F.Mask" "F.Paste")
			(net "GND")
		)
		(pad "BC90" smd circle
			(at 36.611306 -7.228332 270)
			(size 0.4318 0.4318)
			(layers "F.Cu" "F.Mask" "F.Paste")
			(net "VSENSE_PVCCIN_CPU1_DN")
		)
		(pad "BD2" smd circle
			(at -36.611306 -6.868668 270)
			(size 0.4318 0.4318)
			(layers "F.Cu" "F.Mask" "F.Paste")
			(net "UPI_CPU1_CPU0_P0P1_DN<17>")
		)
		(pad "BD4" smd circle
			(at -34.98342 -6.868668 270)
			(size 0.4318 0.4318)
			(layers "F.Cu" "F.Mask" "F.Paste")
			(net "GND")
		)
		(pad "BD6" smd circle
			(at -33.355534 -6.868668 270)
			(size 0.4318 0.4318)
			(layers "F.Cu" "F.Mask" "F.Paste")
			(net "UPI_CPU0_CPU1_P1P0_DP<17>")
		)
		(pad "BD8" smd circle
			(at -31.727902 -6.868668 270)
			(size 0.4318 0.4318)
			(layers "F.Cu" "F.Mask" "F.Paste")
			(net "GND")
		)
		(pad "BD10" smd circle
			(at -30.100016 -6.868668 270)
			(size 0.4318 0.4318)
			(layers "F.Cu" "F.Mask" "F.Paste")
			(net "P5E_CPU1_PE1_RX_DP<15>")
		)
		(pad "BD12" smd circle
			(at -28.472384 -6.868668 270)
			(size 0.4318 0.4318)
			(layers "F.Cu" "F.Mask" "F.Paste")
			(net "GND")
		)
		(pad "BD14" smd circle
			(at -26.844498 -6.868668 270)
			(size 0.4318 0.4318)
			(layers "F.Cu" "F.Mask" "F.Paste")
			(net "P5E_CPU1_PE1_TX_DP<15>")
		)
		(pad "BD16" smd circle
			(at -25.216612 -6.868668 270)
			(size 0.4318 0.4318)
			(layers "F.Cu" "F.Mask" "F.Paste")
			(net "GND")
		)
		(pad "BD18" smd circle
			(at -23.58898 -6.868668 270)
			(size 0.4318 0.4318)
			(layers "F.Cu" "F.Mask" "F.Paste")
			(net "TP_DMI_CPU1_PCH_RX_C_DP<1>")
		)
		(pad "BD20" smd circle
			(at -21.961094 -6.868668 270)
			(size 0.4318 0.4318)
			(layers "F.Cu" "F.Mask" "F.Paste")
			(net "GND")
		)
		(pad "BD22" smd circle
			(at -20.333462 -6.868668 270)
			(size 0.4318 0.4318)
			(layers "F.Cu" "F.Mask" "F.Paste")
			(net "H_CPU1_ERR2_LVC1_R_N")
		)
		(pad "BD24" smd circle
			(at -18.705576 -6.868668 270)
			(size 0.4318 0.4318)
			(layers "F.Cu" "F.Mask" "F.Paste")
			(net "H_PMAX_TRIGGER_IO_CPU1")
		)
		(pad "BD26" smd circle
			(at -17.07769 -6.868668 270)
			(size 0.4318 0.4318)
			(layers "F.Cu" "F.Mask" "F.Paste")
			(net "SVID_DIO0_CPU1")
		)
		(pad "BD61" smd circle
			(at 13.008356 -6.758686 270)
			(size 0.4318 0.4318)
			(layers "F.Cu" "F.Mask" "F.Paste")
			(net "NC_SPI_S3M_CPU1_IO3_LVC1_R")
		)
		(pad "BD63" smd circle
			(at 14.635988 -6.758686 270)
			(size 0.4318 0.4318)
			(layers "F.Cu" "F.Mask" "F.Paste")
			(net "NC_ESPI_IBL_CPU1_ALERT1_N")
		)
		(pad "BD65" smd circle
			(at 16.263874 -6.758686 270)
			(size 0.4318 0.4318)
			(layers "F.Cu" "F.Mask" "F.Paste")
			(net "NC_SPI_S3M_CPU1_IO2_LVC1_R")
		)
		(pad "BD67" smd circle
			(at 17.89176 -6.758686 270)
			(size 0.4318 0.4318)
			(layers "F.Cu" "F.Mask" "F.Paste")
			(net "TP_TRC_CPU1_PTI<23>")
		)
		(pad "BD69" smd circle
			(at 19.519392 -6.758686 270)
			(size 0.4318 0.4318)
			(layers "F.Cu" "F.Mask" "F.Paste")
			(net "TP_TRC_CPU1_PTI<18>")
		)
		(pad "BD71" smd circle
			(at 21.147278 -6.758686 270)
			(size 0.4318 0.4318)
			(layers "F.Cu" "F.Mask" "F.Paste")
			(net "NC_CPU1_MDFI_DIE01_NS1")
		)
		(pad "BD73" smd circle
			(at 22.77491 -6.758686 270)
			(size 0.4318 0.4318)
			(layers "F.Cu" "F.Mask" "F.Paste")
			(net "UPI_CPU0_CPU1_P2P2_DN<23>")
		)
		(pad "BD75" smd circle
			(at 24.402796 -6.758686 270)
			(size 0.4318 0.4318)
			(layers "F.Cu" "F.Mask" "F.Paste")
			(net "UPI_CPU0_CPU1_P2P2_DP<15>")
		)
		(pad "BD77" smd circle
			(at 26.030682 -6.758686 270)
			(size 0.4318 0.4318)
			(layers "F.Cu" "F.Mask" "F.Paste")
			(net "TP_CPU1_SPARE13")
		)
		(pad "BD79" smd circle
			(at 27.658314 -6.758686 270)
			(size 0.4318 0.4318)
			(layers "F.Cu" "F.Mask" "F.Paste")
			(net "UPI_CPU1_CPU0_P2P2_DN<20>")
		)
		(pad "BD81" smd circle
			(at 29.2862 -6.758686 270)
			(size 0.4318 0.4318)
			(layers "F.Cu" "F.Mask" "F.Paste")
			(net "GND")
		)
		(pad "BD83" smd circle
			(at 30.914086 -6.758686 270)
			(size 0.4318 0.4318)
			(layers "F.Cu" "F.Mask" "F.Paste")
			(net "UPI_CPU1_CPU0_P2P2_DP<19>")
		)
		(pad "BD85" smd circle
			(at 32.541718 -6.758686 270)
			(size 0.4318 0.4318)
			(layers "F.Cu" "F.Mask" "F.Paste")
			(net "GND")
		)
		(pad "BD87" smd circle
			(at 34.169604 -6.758686 270)
			(size 0.4318 0.4318)
			(layers "F.Cu" "F.Mask" "F.Paste")
			(net "VSENSE_PVCCIN_CPU1_DP")
		)
		(pad "BD89" smd circle
			(at 35.797236 -6.758686 270)
			(size 0.4318 0.4318)
			(layers "F.Cu" "F.Mask" "F.Paste")
			(net "GND")
		)
		(pad "BD91" smd oval
			(at 37.425122 -6.758686)
			(size 0.381 0.4826)
			(drill
				(offset 0 -0.0508)
			)
			(layers "F.Cu" "F.Mask" "F.Paste")
			(net "PVCCIN_CPU1")
		)
		(pad "BE1" smd oval
			(at -37.425122 -6.398514 180)
			(size 0.381 0.4826)
			(drill
				(offset 0 -0.0508)
			)
			(layers "F.Cu" "F.Mask" "F.Paste")
			(net "UPI_CPU1_CPU0_P0P1_DP<18>")
		)
		(pad "BE3" smd circle
			(at -35.797236 -6.398514 270)
			(size 0.4318 0.4318)
			(layers "F.Cu" "F.Mask" "F.Paste")
			(net "PVCCD_HV_CPU1")
		)
		(pad "BE5" smd circle
			(at -34.169604 -6.398514 270)
			(size 0.4318 0.4318)
			(layers "F.Cu" "F.Mask" "F.Paste")
			(net "UPI_CPU0_CPU1_P1P0_DN<17>")
		)
		(pad "BE7" smd circle
			(at -32.541718 -6.398514 270)
			(size 0.4318 0.4318)
			(layers "F.Cu" "F.Mask" "F.Paste")
			(net "PVCCD_HV_CPU1")
		)
		(pad "BE9" smd circle
			(at -30.914086 -6.398514 270)
			(size 0.4318 0.4318)
			(layers "F.Cu" "F.Mask" "F.Paste")
			(net "P5E_CPU1_PE1_RX_DP<14>")
		)
		(pad "BE11" smd circle
			(at -29.2862 -6.398514 270)
			(size 0.4318 0.4318)
			(layers "F.Cu" "F.Mask" "F.Paste")
			(net "PVCCD_HV_CPU1")
		)
		(pad "BE13" smd circle
			(at -27.658314 -6.398514 270)
			(size 0.4318 0.4318)
			(layers "F.Cu" "F.Mask" "F.Paste")
			(net "P5E_CPU1_PE1_TX_DN<15>")
		)
		(pad "BE15" smd circle
			(at -26.030682 -6.398514 270)
			(size 0.4318 0.4318)
			(layers "F.Cu" "F.Mask" "F.Paste")
			(net "PVCCINFAON_CPU1")
		)
		(pad "BE17" smd circle
			(at -24.402796 -6.398514 270)
			(size 0.4318 0.4318)
			(layers "F.Cu" "F.Mask" "F.Paste")
			(net "TP_DMI_CPU1_PCH_RX_C_DN<1>")
		)
		(pad "BE19" smd circle
			(at -22.77491 -6.398514 270)
			(size 0.4318 0.4318)
			(layers "F.Cu" "F.Mask" "F.Paste")
			(net "PVNN_MAIN_CPU1")
		)
		(pad "BE21" smd circle
			(at -21.147278 -6.398514 270)
			(size 0.4318 0.4318)
			(layers "F.Cu" "F.Mask" "F.Paste")
			(net "TP_CPU1_DIE_HVM_EN_LVC1")
		)
		(pad "BE23" smd circle
			(at -19.519392 -6.398514 270)
			(size 0.4318 0.4318)
			(layers "F.Cu" "F.Mask" "F.Paste")
			(net "TP_CPU1_IFST_KOT_LVC1_R")
		)
		(pad "BE25" smd circle
			(at -17.89176 -6.398514 270)
			(size 0.4318 0.4318)
			(layers "F.Cu" "F.Mask" "F.Paste")
			(net "TP_I3C_MNG3_BMC_SW_SCL")
		)
		(pad "BE60" smd circle
			(at 12.19454 -6.288532 270)
			(size 0.4318 0.4318)
			(layers "F.Cu" "F.Mask" "F.Paste")
			(net "PVCCINFAON_CPU1")
		)
		(pad "BE62" smd circle
			(at 13.822426 -6.288532 270)
			(size 0.4318 0.4318)
			(layers "F.Cu" "F.Mask" "F.Paste")
			(net "NC_ESPI_IBL_CPU1_ALERT0_N")
		)
		(pad "BE64" smd circle
			(at 15.450058 -6.288532 270)
			(size 0.4318 0.4318)
			(layers "F.Cu" "F.Mask" "F.Paste")
			(net "GND")
		)
		(pad "BE66" smd circle
			(at 17.07769 -6.288532 270)
			(size 0.4318 0.4318)
			(layers "F.Cu" "F.Mask" "F.Paste")
			(net "GND")
		)
		(pad "BE68" smd circle
			(at 18.705576 -6.288532 270)
			(size 0.4318 0.4318)
			(layers "F.Cu" "F.Mask" "F.Paste")
			(net "GND")
		)
		(pad "BE70" smd circle
			(at 20.333462 -6.288532 270)
			(size 0.4318 0.4318)
			(layers "F.Cu" "F.Mask" "F.Paste")
			(net "TP_TRC_CPU1_PTI<17>")
		)
		(pad "BE72" smd circle
			(at 21.961094 -6.288532 270)
			(size 0.4318 0.4318)
			(layers "F.Cu" "F.Mask" "F.Paste")
			(net "PVCCFA_EHV_FIVRA_CPU1")
		)
		(pad "BE74" smd circle
			(at 23.58898 -6.288532 270)
			(size 0.4318 0.4318)
			(layers "F.Cu" "F.Mask" "F.Paste")
			(net "GND")
		)
		(pad "BE76" smd circle
			(at 25.216612 -6.288532 270)
			(size 0.4318 0.4318)
			(layers "F.Cu" "F.Mask" "F.Paste")
			(net "GND")
		)
		(pad "BE78" smd circle
			(at 26.844498 -6.288532 270)
			(size 0.4318 0.4318)
			(layers "F.Cu" "F.Mask" "F.Paste")
			(net "GND")
		)
		(pad "BE80" smd circle
			(at 28.472384 -6.288532 270)
			(size 0.4318 0.4318)
			(layers "F.Cu" "F.Mask" "F.Paste")
			(net "UPI_CPU1_CPU0_P2P2_DP<22>")
		)
		(pad "BE82" smd circle
			(at 30.100016 -6.288532 270)
			(size 0.4318 0.4318)
			(layers "F.Cu" "F.Mask" "F.Paste")
			(net "UPI_CPU1_CPU0_P2P2_DN<19>")
		)
		(pad "BE84" smd circle
			(at 31.727902 -6.288532 270)
			(size 0.4318 0.4318)
			(layers "F.Cu" "F.Mask" "F.Paste")
			(net "GND")
		)
		(pad "BE86" smd circle
			(at 33.355534 -6.288532 270)
			(size 0.4318 0.4318)
			(layers "F.Cu" "F.Mask" "F.Paste")
			(net "PVCCIN_CPU1")
		)
		(pad "BE88" smd circle
			(at 34.98342 -6.288532 270)
			(size 0.4318 0.4318)
			(layers "F.Cu" "F.Mask" "F.Paste")
			(net "PVCCIN_CPU1")
		)
		(pad "BE90" smd circle
			(at 36.611306 -6.288532 270)
			(size 0.4318 0.4318)
			(layers "F.Cu" "F.Mask" "F.Paste")
			(net "PVCCIN_CPU1")
		)
		(pad "BF2" smd circle
			(at -36.611306 -5.928868 270)
			(size 0.4318 0.4318)
			(layers "F.Cu" "F.Mask" "F.Paste")
			(net "UPI_CPU1_CPU0_P0P1_DN<18>")
		)
		(pad "BF4" smd circle
			(at -34.98342 -5.928868 270)
			(size 0.4318 0.4318)
			(layers "F.Cu" "F.Mask" "F.Paste")
			(net "GND")
		)
		(pad "BF6" smd circle
			(at -33.355534 -5.928868 270)
			(size 0.4318 0.4318)
			(layers "F.Cu" "F.Mask" "F.Paste")
			(net "UPI_CPU0_CPU1_P1P0_DN<18>")
		)
		(pad "BF8" smd circle
			(at -31.727902 -5.928868 270)
			(size 0.4318 0.4318)
			(layers "F.Cu" "F.Mask" "F.Paste")
			(net "GND")
		)
		(pad "BF10" smd circle
			(at -30.100016 -5.928868 270)
			(size 0.4318 0.4318)
			(layers "F.Cu" "F.Mask" "F.Paste")
			(net "P5E_CPU1_PE1_RX_DN<14>")
		)
		(pad "BF12" smd circle
			(at -28.472384 -5.928868 270)
			(size 0.4318 0.4318)
			(layers "F.Cu" "F.Mask" "F.Paste")
			(net "GND")
		)
		(pad "BF14" smd circle
			(at -26.844498 -5.928868 270)
			(size 0.4318 0.4318)
			(layers "F.Cu" "F.Mask" "F.Paste")
			(net "P5E_CPU1_PE1_TX_DN<14>")
		)
		(pad "BF16" smd circle
			(at -25.216612 -5.928868 270)
			(size 0.4318 0.4318)
			(layers "F.Cu" "F.Mask" "F.Paste")
			(net "GND")
		)
		(pad "BF18" smd circle
			(at -23.58898 -5.928868 270)
			(size 0.4318 0.4318)
			(layers "F.Cu" "F.Mask" "F.Paste")
			(net "TP_DMI_CPU1_PCH_RX_C_DN<2>")
		)
		(pad "BF20" smd circle
			(at -21.961094 -5.928868 270)
			(size 0.4318 0.4318)
			(layers "F.Cu" "F.Mask" "F.Paste")
			(net "GND")
		)
		(pad "BF22" smd circle
			(at -20.333462 -5.928868 270)
			(size 0.4318 0.4318)
			(layers "F.Cu" "F.Mask" "F.Paste")
			(net "H_CPU1_ERR0_LVC1_R_N")
		)
		(pad "BF24" smd circle
			(at -18.705576 -5.928868 270)
			(size 0.4318 0.4318)
			(layers "F.Cu" "F.Mask" "F.Paste")
			(net "TP_CPU1_IFST_TRIG_LVC1_R")
		)
		(pad "BF26" smd circle
			(at -17.07769 -5.928868 270)
			(size 0.4318 0.4318)
			(layers "F.Cu" "F.Mask" "F.Paste")
			(net "SVID_CLK1_CPU1")
		)
		(pad "BF61" smd circle
			(at 13.008356 -5.818886 270)
			(size 0.4318 0.4318)
			(layers "F.Cu" "F.Mask" "F.Paste")
			(net "GND")
		)
		(pad "BF63" smd circle
			(at 14.635988 -5.818886 270)
			(size 0.4318 0.4318)
			(layers "F.Cu" "F.Mask" "F.Paste")
			(net "GND")
		)
		(pad "BF65" smd circle
			(at 16.263874 -5.818886 270)
			(size 0.4318 0.4318)
			(layers "F.Cu" "F.Mask" "F.Paste")
			(net "NC_ESPI_IBL_CPU1_CS0_N")
		)
		(pad "BF67" smd circle
			(at 17.89176 -5.818886 270)
			(size 0.4318 0.4318)
			(layers "F.Cu" "F.Mask" "F.Paste")
			(net "TP_TRC_CPU1_PTI2_CLK")
		)
		(pad "BF69" smd circle
			(at 19.519392 -5.818886 270)
			(size 0.4318 0.4318)
			(layers "F.Cu" "F.Mask" "F.Paste")
			(net "TP_TRC_CPU1_PTI<19>")
		)
		(pad "BF71" smd circle
			(at 21.147278 -5.818886 270)
			(size 0.4318 0.4318)
			(layers "F.Cu" "F.Mask" "F.Paste")
			(net "NC_CPU1_MDFI_DIE01_NS0")
		)
		(pad "BF73" smd circle
			(at 22.77491 -5.818886 270)
			(size 0.4318 0.4318)
			(layers "F.Cu" "F.Mask" "F.Paste")
			(net "GND")
		)
		(pad "BF75" smd circle
			(at 24.402796 -5.818886 270)
			(size 0.4318 0.4318)
			(layers "F.Cu" "F.Mask" "F.Paste")
			(net "GND")
		)
		(pad "BF77" smd circle
			(at 26.030682 -5.818886 270)
			(size 0.4318 0.4318)
			(layers "F.Cu" "F.Mask" "F.Paste")
			(net "PVCCFA_EHV_FIVRA_CPU1")
		)
		(pad "BF79" smd circle
			(at 27.658314 -5.818886 270)
			(size 0.4318 0.4318)
			(layers "F.Cu" "F.Mask" "F.Paste")
			(net "GND")
		)
		(pad "BF81" smd circle
			(at 29.2862 -5.818886 270)
			(size 0.4318 0.4318)
			(layers "F.Cu" "F.Mask" "F.Paste")
			(net "UPI_CPU1_CPU0_P2P2_DN<21>")
		)
		(pad "BF83" smd circle
			(at 30.914086 -5.818886 270)
			(size 0.4318 0.4318)
			(layers "F.Cu" "F.Mask" "F.Paste")
			(net "GND")
		)
		(pad "BF85" smd circle
			(at 32.541718 -5.818886 270)
			(size 0.4318 0.4318)
			(layers "F.Cu" "F.Mask" "F.Paste")
			(net "PVCCIN_CPU1")
		)
		(pad "BF87" smd circle
			(at 34.169604 -5.818886 270)
			(size 0.4318 0.4318)
			(layers "F.Cu" "F.Mask" "F.Paste")
			(net "PVCCIN_CPU1")
		)
		(pad "BF89" smd circle
			(at 35.797236 -5.818886 270)
			(size 0.4318 0.4318)
			(layers "F.Cu" "F.Mask" "F.Paste")
			(net "PVCCIN_CPU1")
		)
		(pad "BF91" smd oval
			(at 37.425122 -5.818886)
			(size 0.381 0.4826)
			(drill
				(offset 0 -0.0508)
			)
			(layers "F.Cu" "F.Mask" "F.Paste")
			(net "PVCCIN_CPU1")
		)
		(pad "BG1" smd oval
			(at -37.425122 -5.458714 180)
			(size 0.381 0.4826)
			(drill
				(offset 0 -0.0508)
			)
			(layers "F.Cu" "F.Mask" "F.Paste")
			(net "GND")
		)
		(pad "BG3" smd circle
			(at -35.797236 -5.458714 270)
			(size 0.4318 0.4318)
			(layers "F.Cu" "F.Mask" "F.Paste")
			(net "UPI_CPU1_CPU0_P0P1_DP<19>")
		)
		(pad "BG5" smd circle
			(at -34.169604 -5.458714 270)
			(size 0.4318 0.4318)
			(layers "F.Cu" "F.Mask" "F.Paste")
			(net "GND")
		)
		(pad "BG7" smd circle
			(at -32.541718 -5.458714 270)
			(size 0.4318 0.4318)
			(layers "F.Cu" "F.Mask" "F.Paste")
			(net "UPI_CPU0_CPU1_P1P0_DP<18>")
		)
		(pad "BG9" smd circle
			(at -30.914086 -5.458714 270)
			(size 0.4318 0.4318)
			(layers "F.Cu" "F.Mask" "F.Paste")
			(net "GND")
		)
		(pad "BG11" smd circle
			(at -29.2862 -5.458714 270)
			(size 0.4318 0.4318)
			(layers "F.Cu" "F.Mask" "F.Paste")
			(net "P5E_CPU1_PE1_RX_DN<13>")
		)
		(pad "BG13" smd circle
			(at -27.658314 -5.458714 270)
			(size 0.4318 0.4318)
			(layers "F.Cu" "F.Mask" "F.Paste")
			(net "GND")
		)
		(pad "BG15" smd circle
			(at -26.030682 -5.458714 270)
			(size 0.4318 0.4318)
			(layers "F.Cu" "F.Mask" "F.Paste")
			(net "P5E_CPU1_PE1_TX_DP<14>")
		)
		(pad "BG17" smd circle
			(at -24.402796 -5.458714 270)
			(size 0.4318 0.4318)
			(layers "F.Cu" "F.Mask" "F.Paste")
			(net "GND")
		)
		(pad "BG19" smd circle
			(at -22.77491 -5.458714 270)
			(size 0.4318 0.4318)
			(layers "F.Cu" "F.Mask" "F.Paste")
			(net "TP_DMI_CPU1_PCH_RX_C_DP<2>")
		)
		(pad "BG21" smd circle
			(at -21.147278 -5.458714 270)
			(size 0.4318 0.4318)
			(layers "F.Cu" "F.Mask" "F.Paste")
			(net "GND")
		)
		(pad "BG23" smd circle
			(at -19.519392 -5.458714 270)
			(size 0.4318 0.4318)
			(layers "F.Cu" "F.Mask" "F.Paste")
			(net "GND")
		)
		(pad "BG25" smd circle
			(at -17.89176 -5.458714 270)
			(size 0.4318 0.4318)
			(layers "F.Cu" "F.Mask" "F.Paste")
			(net "GND")
		)
		(pad "BG60" smd circle
			(at 12.19454 -5.348732 270)
			(size 0.4318 0.4318)
			(layers "F.Cu" "F.Mask" "F.Paste")
			(net "PVCCINFAON_CPU1")
		)
		(pad "BG62" smd circle
			(at 13.822426 -5.348732 270)
			(size 0.4318 0.4318)
			(layers "F.Cu" "F.Mask" "F.Paste")
			(net "NC_ESPI_IBL_CPU1_CLK")
		)
		(pad "BG64" smd circle
			(at 15.450058 -5.348732 270)
			(size 0.4318 0.4318)
			(layers "F.Cu" "F.Mask" "F.Paste")
			(net "NC_ESPI_IBL_CPU1_RESET_N")
		)
		(pad "BG66" smd circle
			(at 17.07769 -5.348732 270)
			(size 0.4318 0.4318)
			(layers "F.Cu" "F.Mask" "F.Paste")
			(net "TP_TRC_CPU1_PTI<27>")
		)
		(pad "BG68" smd circle
			(at 18.705576 -5.348732 270)
			(size 0.4318 0.4318)
			(layers "F.Cu" "F.Mask" "F.Paste")
			(net "TP_TRC_CPU1_PTI<22>")
		)
		(pad "BG70" smd circle
			(at 20.333462 -5.348732 270)
			(size 0.4318 0.4318)
			(layers "F.Cu" "F.Mask" "F.Paste")
			(net "GND")
		)
		(pad "BG72" smd circle
			(at 21.961094 -5.348732 270)
			(size 0.4318 0.4318)
			(layers "F.Cu" "F.Mask" "F.Paste")
			(net "FM_CPU1_PROC_ID0")
		)
		(pad "BG74" smd circle
			(at 23.58898 -5.348732 270)
			(size 0.4318 0.4318)
			(layers "F.Cu" "F.Mask" "F.Paste")
			(net "UPI_CPU0_CPU1_P2P2_DN<20>")
		)
		(pad "BG76" smd circle
			(at 25.216612 -5.348732 270)
			(size 0.4318 0.4318)
			(layers "F.Cu" "F.Mask" "F.Paste")
			(net "UPI_CPU0_CPU1_P2P2_DP<17>")
		)
		(pad "BG78" smd circle
			(at 26.844498 -5.348732 270)
			(size 0.4318 0.4318)
			(layers "F.Cu" "F.Mask" "F.Paste")
			(net "NC_CPU1_HBM3_VIEWDIG0")
		)
		(pad "BG80" smd circle
			(at 28.472384 -5.348732 270)
			(size 0.4318 0.4318)
			(layers "F.Cu" "F.Mask" "F.Paste")
			(net "UPI_CPU1_CPU0_P2P2_DN<22>")
		)
		(pad "BG82" smd circle
			(at 30.100016 -5.348732 270)
			(size 0.4318 0.4318)
			(layers "F.Cu" "F.Mask" "F.Paste")
			(net "UPI_CPU1_CPU0_P2P2_DP<21>")
		)
		(pad "BG84" smd circle
			(at 31.727902 -5.348732 270)
			(size 0.4318 0.4318)
			(layers "F.Cu" "F.Mask" "F.Paste")
			(net "PVCCIN_CPU1")
		)
		(pad "BG86" smd circle
			(at 33.355534 -5.348732 270)
			(size 0.4318 0.4318)
			(layers "F.Cu" "F.Mask" "F.Paste")
			(net "PVCCIN_CPU1")
		)
		(pad "BG88" smd circle
			(at 34.98342 -5.348732 270)
			(size 0.4318 0.4318)
			(layers "F.Cu" "F.Mask" "F.Paste")
			(net "PVCCIN_CPU1")
		)
		(pad "BG90" smd circle
			(at 36.611306 -5.348732 270)
			(size 0.4318 0.4318)
			(layers "F.Cu" "F.Mask" "F.Paste")
			(net "PVCCIN_CPU1")
		)
		(pad "BH2" smd circle
			(at -36.611306 -4.989068 270)
			(size 0.4318 0.4318)
			(layers "F.Cu" "F.Mask" "F.Paste")
			(net "UPI_CPU1_CPU0_P0P1_DN<19>")
		)
		(pad "BH4" smd circle
			(at -34.98342 -4.989068 270)
			(size 0.4318 0.4318)
			(layers "F.Cu" "F.Mask" "F.Paste")
			(net "GND")
		)
		(pad "BH6" smd circle
			(at -33.355534 -4.989068 270)
			(size 0.4318 0.4318)
			(layers "F.Cu" "F.Mask" "F.Paste")
			(net "UPI_CPU0_CPU1_P1P0_DP<19>")
		)
		(pad "BH8" smd circle
			(at -31.727902 -4.989068 270)
			(size 0.4318 0.4318)
			(layers "F.Cu" "F.Mask" "F.Paste")
			(net "GND")
		)
		(pad "BH10" smd circle
			(at -30.100016 -4.989068 270)
			(size 0.4318 0.4318)
			(layers "F.Cu" "F.Mask" "F.Paste")
			(net "P5E_CPU1_PE1_RX_DP<13>")
		)
		(pad "BH12" smd circle
			(at -28.472384 -4.989068 270)
			(size 0.4318 0.4318)
			(layers "F.Cu" "F.Mask" "F.Paste")
			(net "GND")
		)
		(pad "BH14" smd circle
			(at -26.844498 -4.989068 270)
			(size 0.4318 0.4318)
			(layers "F.Cu" "F.Mask" "F.Paste")
			(net "P5E_CPU1_PE1_TX_DP<13>")
		)
		(pad "BH16" smd circle
			(at -25.216612 -4.989068 270)
			(size 0.4318 0.4318)
			(layers "F.Cu" "F.Mask" "F.Paste")
			(net "GND")
		)
		(pad "BH18" smd circle
			(at -23.58898 -4.989068 270)
			(size 0.4318 0.4318)
			(layers "F.Cu" "F.Mask" "F.Paste")
			(net "TP_DMI_CPU1_PCH_RX_C_DP<3>")
		)
		(pad "BH20" smd circle
			(at -21.961094 -4.989068 270)
			(size 0.4318 0.4318)
			(layers "F.Cu" "F.Mask" "F.Paste")
			(net "GND")
		)
		(pad "BH22" smd circle
			(at -20.333462 -4.989068 270)
			(size 0.4318 0.4318)
			(layers "F.Cu" "F.Mask" "F.Paste")
			(net "H_CPU1_RMCA_LVC1_R_N")
		)
		(pad "BH24" smd circle
			(at -18.705576 -4.989068 270)
			(size 0.4318 0.4318)
			(layers "F.Cu" "F.Mask" "F.Paste")
			(net "PECI_CPU1_GTL_R")
		)
		(pad "BH26" smd circle
			(at -17.07769 -4.989068 270)
			(size 0.4318 0.4318)
			(layers "F.Cu" "F.Mask" "F.Paste")
			(net "SVID_CLK0_CPU1")
		)
		(pad "BH61" smd circle
			(at 13.008356 -4.879086 270)
			(size 0.4318 0.4318)
			(layers "F.Cu" "F.Mask" "F.Paste")
			(net "RST_CPU1_LVC1_N")
		)
		(pad "BH63" smd circle
			(at 14.635988 -4.879086 270)
			(size 0.4318 0.4318)
			(layers "F.Cu" "F.Mask" "F.Paste")
			(net "NC_ESPI_IBL_CPU1_OE_N")
		)
		(pad "BH65" smd circle
			(at 16.263874 -4.879086 270)
			(size 0.4318 0.4318)
			(layers "F.Cu" "F.Mask" "F.Paste")
			(net "NC_ESPI_IBL_CPU1_CS1_N")
		)
		(pad "BH67" smd circle
			(at 17.89176 -4.879086 270)
			(size 0.4318 0.4318)
			(layers "F.Cu" "F.Mask" "F.Paste")
			(net "GND")
		)
		(pad "BH69" smd circle
			(at 19.519392 -4.879086 270)
			(size 0.4318 0.4318)
			(layers "F.Cu" "F.Mask" "F.Paste")
			(net "TP_TRC_CPU1_PTI<20>")
		)
		(pad "BH71" smd circle
			(at 21.147278 -4.879086 270)
			(size 0.4318 0.4318)
			(layers "F.Cu" "F.Mask" "F.Paste")
			(net "FM_CPU1_PROC_ID1")
		)
		(pad "BH73" smd circle
			(at 22.77491 -4.879086 270)
			(size 0.4318 0.4318)
			(layers "F.Cu" "F.Mask" "F.Paste")
			(net "GND")
		)
		(pad "BH75" smd circle
			(at 24.402796 -4.879086 270)
			(size 0.4318 0.4318)
			(layers "F.Cu" "F.Mask" "F.Paste")
			(net "UPI_CPU0_CPU1_P2P2_DN<17>")
		)
		(pad "BH77" smd circle
			(at 26.030682 -4.879086 270)
			(size 0.4318 0.4318)
			(layers "F.Cu" "F.Mask" "F.Paste")
			(net "GND")
		)
		(pad "BH79" smd circle
			(at 27.658314 -4.879086 270)
			(size 0.4318 0.4318)
			(layers "F.Cu" "F.Mask" "F.Paste")
			(net "PVCCFA_EHV_FIVRA_CPU1")
		)
		(pad "BH81" smd circle
			(at 29.2862 -4.879086 270)
			(size 0.4318 0.4318)
			(layers "F.Cu" "F.Mask" "F.Paste")
			(net "GND")
		)
		(pad "BH83" smd circle
			(at 30.914086 -4.879086 270)
			(size 0.4318 0.4318)
			(layers "F.Cu" "F.Mask" "F.Paste")
			(net "GND")
		)
		(pad "BH85" smd circle
			(at 32.541718 -4.879086 270)
			(size 0.4318 0.4318)
			(layers "F.Cu" "F.Mask" "F.Paste")
			(net "PVCCIN_CPU1")
		)
		(pad "BH87" smd circle
			(at 34.169604 -4.879086 270)
			(size 0.4318 0.4318)
			(layers "F.Cu" "F.Mask" "F.Paste")
			(net "PVCCIN_CPU1")
		)
		(pad "BH89" smd circle
			(at 35.797236 -4.879086 270)
			(size 0.4318 0.4318)
			(layers "F.Cu" "F.Mask" "F.Paste")
			(net "PVCCIN_CPU1")
		)
		(pad "BH91" smd oval
			(at 37.425122 -4.879086)
			(size 0.381 0.4826)
			(drill
				(offset 0 -0.0508)
			)
			(layers "F.Cu" "F.Mask" "F.Paste")
			(net "PVCCIN_CPU1")
		)
		(pad "BJ1" smd oval
			(at -37.425122 -4.518914 180)
			(size 0.381 0.4826)
			(drill
				(offset 0 -0.0508)
			)
			(layers "F.Cu" "F.Mask" "F.Paste")
			(net "UPI_CPU1_CPU0_P0P1_DP<20>")
		)
		(pad "BJ3" smd circle
			(at -35.797236 -4.518914 270)
			(size 0.4318 0.4318)
			(layers "F.Cu" "F.Mask" "F.Paste")
			(net "PVCCD_HV_CPU1")
		)
		(pad "BJ5" smd circle
			(at -34.169604 -4.518914 270)
			(size 0.4318 0.4318)
			(layers "F.Cu" "F.Mask" "F.Paste")
			(net "UPI_CPU0_CPU1_P1P0_DN<19>")
		)
		(pad "BJ7" smd circle
			(at -32.541718 -4.518914 270)
			(size 0.4318 0.4318)
			(layers "F.Cu" "F.Mask" "F.Paste")
			(net "PVCCD_HV_CPU1")
		)
		(pad "BJ9" smd circle
			(at -30.914086 -4.518914 270)
			(size 0.4318 0.4318)
			(layers "F.Cu" "F.Mask" "F.Paste")
			(net "P5E_CPU1_PE1_RX_DP<12>")
		)
		(pad "BJ11" smd circle
			(at -29.2862 -4.518914 270)
			(size 0.4318 0.4318)
			(layers "F.Cu" "F.Mask" "F.Paste")
			(net "PVCCD_HV_CPU1")
		)
		(pad "BJ13" smd circle
			(at -27.658314 -4.518914 270)
			(size 0.4318 0.4318)
			(layers "F.Cu" "F.Mask" "F.Paste")
			(net "P5E_CPU1_PE1_TX_DN<13>")
		)
		(pad "BJ15" smd circle
			(at -26.030682 -4.518914 270)
			(size 0.4318 0.4318)
			(layers "F.Cu" "F.Mask" "F.Paste")
			(net "PVCCINFAON_CPU1")
		)
		(pad "BJ17" smd circle
			(at -24.402796 -4.518914 270)
			(size 0.4318 0.4318)
			(layers "F.Cu" "F.Mask" "F.Paste")
			(net "TP_DMI_CPU1_PCH_RX_C_DN<3>")
		)
		(pad "BJ19" smd circle
			(at -22.77491 -4.518914 270)
			(size 0.4318 0.4318)
			(layers "F.Cu" "F.Mask" "F.Paste")
			(net "PVNN_MAIN_CPU1")
		)
		(pad "BJ21" smd circle
			(at -21.147278 -4.518914 270)
			(size 0.4318 0.4318)
			(layers "F.Cu" "F.Mask" "F.Paste")
			(net "NC_CPU1_MDFI_DIE00_NS1")
		)
		(pad "BJ23" smd circle
			(at -19.519392 -4.518914 270)
			(size 0.4318 0.4318)
			(layers "F.Cu" "F.Mask" "F.Paste")
			(net "DBP_CPU1_HOOK8_MBP2_GTL_QS_R_N")
		)
		(pad "BJ25" smd circle
			(at -17.89176 -4.518914 270)
			(size 0.4318 0.4318)
			(layers "F.Cu" "F.Mask" "F.Paste")
			(net "SVID_ALERT1_CPU1_N")
		)
		(pad "BJ60" smd circle
			(at 12.19454 -4.408932 270)
			(size 0.4318 0.4318)
			(layers "F.Cu" "F.Mask" "F.Paste")
			(net "PVCCINFAON_CPU1")
		)
		(pad "BJ62" smd circle
			(at 13.822426 -4.408932 270)
			(size 0.4318 0.4318)
			(layers "F.Cu" "F.Mask" "F.Paste")
			(net "GND")
		)
		(pad "BJ64" smd circle
			(at 15.450058 -4.408932 270)
			(size 0.4318 0.4318)
			(layers "F.Cu" "F.Mask" "F.Paste")
			(net "NC_ESPI_IBL_CPU1_IO1")
		)
		(pad "BJ66" smd circle
			(at 17.07769 -4.408932 270)
			(size 0.4318 0.4318)
			(layers "F.Cu" "F.Mask" "F.Paste")
			(net "TP_TRC_CPU1_PTI<28>")
		)
		(pad "BJ68" smd circle
			(at 18.705576 -4.408932 270)
			(size 0.4318 0.4318)
			(layers "F.Cu" "F.Mask" "F.Paste")
			(net "GND")
		)
		(pad "BJ70" smd circle
			(at 20.333462 -4.408932 270)
			(size 0.4318 0.4318)
			(layers "F.Cu" "F.Mask" "F.Paste")
			(net "CPU1_RSVD<54>")
		)
		(pad "BJ72" smd circle
			(at 21.961094 -4.408932 270)
			(size 0.4318 0.4318)
			(layers "F.Cu" "F.Mask" "F.Paste")
			(net "PVCCFA_EHV_FIVRA_CPU1")
		)
		(pad "BJ74" smd circle
			(at 23.58898 -4.408932 270)
			(size 0.4318 0.4318)
			(layers "F.Cu" "F.Mask" "F.Paste")
			(net "UPI_CPU0_CPU1_P2P2_DP<20>")
		)
		(pad "BJ76" smd circle
			(at 25.216612 -4.408932 270)
			(size 0.4318 0.4318)
			(layers "F.Cu" "F.Mask" "F.Paste")
			(net "UPI_CPU0_CPU1_P2P2_DN<18>")
		)
		(pad "BJ78" smd circle
			(at 26.844498 -4.408932 270)
			(size 0.4318 0.4318)
			(layers "F.Cu" "F.Mask" "F.Paste")
			(net "PVCCFA_EHV_FIVRA_CPU1")
		)
		(pad "BJ80" smd circle
			(at 28.472384 -4.408932 270)
			(size 0.4318 0.4318)
			(layers "F.Cu" "F.Mask" "F.Paste")
			(net "GND")
		)
		(pad "BJ82" smd circle
			(at 30.100016 -4.408932 270)
			(size 0.4318 0.4318)
			(layers "F.Cu" "F.Mask" "F.Paste")
			(net "GND")
		)
		(pad "BJ84" smd circle
			(at 31.727902 -4.408932 270)
			(size 0.4318 0.4318)
			(layers "F.Cu" "F.Mask" "F.Paste")
			(net "GND")
		)
		(pad "BJ86" smd circle
			(at 33.355534 -4.408932 270)
			(size 0.4318 0.4318)
			(layers "F.Cu" "F.Mask" "F.Paste")
			(net "GND")
		)
		(pad "BJ88" smd circle
			(at 34.98342 -4.408932 270)
			(size 0.4318 0.4318)
			(layers "F.Cu" "F.Mask" "F.Paste")
			(net "GND")
		)
		(pad "BJ90" smd circle
			(at 36.611306 -4.408932 270)
			(size 0.4318 0.4318)
			(layers "F.Cu" "F.Mask" "F.Paste")
			(net "GND")
		)
		(pad "BK2" smd circle
			(at -36.611306 -4.049268 270)
			(size 0.4318 0.4318)
			(layers "F.Cu" "F.Mask" "F.Paste")
			(net "UPI_CPU1_CPU0_P0P1_DN<20>")
		)
		(pad "BK4" smd circle
			(at -34.98342 -4.049268 270)
			(size 0.4318 0.4318)
			(layers "F.Cu" "F.Mask" "F.Paste")
			(net "GND")
		)
		(pad "BK6" smd circle
			(at -33.355534 -4.049268 270)
			(size 0.4318 0.4318)
			(layers "F.Cu" "F.Mask" "F.Paste")
			(net "UPI_CPU0_CPU1_P1P0_DN<20>")
		)
		(pad "BK8" smd circle
			(at -31.727902 -4.049268 270)
			(size 0.4318 0.4318)
			(layers "F.Cu" "F.Mask" "F.Paste")
			(net "GND")
		)
		(pad "BK10" smd circle
			(at -30.100016 -4.049268 270)
			(size 0.4318 0.4318)
			(layers "F.Cu" "F.Mask" "F.Paste")
			(net "P5E_CPU1_PE1_RX_DN<12>")
		)
		(pad "BK12" smd circle
			(at -28.472384 -4.049268 270)
			(size 0.4318 0.4318)
			(layers "F.Cu" "F.Mask" "F.Paste")
			(net "GND")
		)
		(pad "BK14" smd circle
			(at -26.844498 -4.049268 270)
			(size 0.4318 0.4318)
			(layers "F.Cu" "F.Mask" "F.Paste")
			(net "P5E_CPU1_PE1_TX_DN<12>")
		)
		(pad "BK16" smd circle
			(at -25.216612 -4.049268 270)
			(size 0.4318 0.4318)
			(layers "F.Cu" "F.Mask" "F.Paste")
			(net "GND")
		)
		(pad "BK18" smd circle
			(at -23.58898 -4.049268 270)
			(size 0.4318 0.4318)
			(layers "F.Cu" "F.Mask" "F.Paste")
			(net "TP_DMI_CPU1_PCH_RX_C_DN<4>")
		)
		(pad "BK20" smd circle
			(at -21.961094 -4.049268 270)
			(size 0.4318 0.4318)
			(layers "F.Cu" "F.Mask" "F.Paste")
			(net "GND")
		)
		(pad "BK22" smd circle
			(at -20.333462 -4.049268 270)
			(size 0.4318 0.4318)
			(layers "F.Cu" "F.Mask" "F.Paste")
			(net "NC_CPU1_MDFI_DIE00_NS0")
		)
		(pad "BK24" smd circle
			(at -18.705576 -4.049268 270)
			(size 0.4318 0.4318)
			(layers "F.Cu" "F.Mask" "F.Paste")
			(net "DBP_CPU1_HOOK9_MBP3_GTL_QS_R_N")
		)
		(pad "BK26" smd circle
			(at -17.07769 -4.049268 270)
			(size 0.4318 0.4318)
			(layers "F.Cu" "F.Mask" "F.Paste")
			(net "SVID_ALERT0_CPU1_N")
		)
		(pad "BK61" smd circle
			(at 13.008356 -3.939286 270)
			(size 0.4318 0.4318)
			(layers "F.Cu" "F.Mask" "F.Paste")
			(net "PVCCINFAON_CPU1")
		)
		(pad "BK63" smd circle
			(at 14.635988 -3.939286 270)
			(size 0.4318 0.4318)
			(layers "F.Cu" "F.Mask" "F.Paste")
			(net "NC_ESPI_IBL_CPU1_IO0")
		)
		(pad "BK65" smd circle
			(at 16.263874 -3.939286 270)
			(size 0.4318 0.4318)
			(layers "F.Cu" "F.Mask" "F.Paste")
			(net "GND")
		)
		(pad "BK67" smd circle
			(at 17.89176 -3.939286 270)
			(size 0.4318 0.4318)
			(layers "F.Cu" "F.Mask" "F.Paste")
			(net "TP_TRC_CPU1_PTI3_CLK")
		)
		(pad "BK69" smd circle
			(at 19.519392 -3.939286 270)
			(size 0.4318 0.4318)
			(layers "F.Cu" "F.Mask" "F.Paste")
			(net "TP_TRC_CPU1_PTI<24>")
		)
		(pad "BK71" smd circle
			(at 21.147278 -3.939286 270)
			(size 0.4318 0.4318)
			(layers "F.Cu" "F.Mask" "F.Paste")
			(net "GND")
		)
		(pad "BK73" smd circle
			(at 22.77491 -3.939286 270)
			(size 0.4318 0.4318)
			(layers "F.Cu" "F.Mask" "F.Paste")
			(net "UPI_CPU0_CPU1_P2P2_DN<22>")
		)
		(pad "BK75" smd circle
			(at 24.402796 -3.939286 270)
			(size 0.4318 0.4318)
			(layers "F.Cu" "F.Mask" "F.Paste")
			(net "GND")
		)
		(pad "BK77" smd circle
			(at 26.030682 -3.939286 270)
			(size 0.4318 0.4318)
			(layers "F.Cu" "F.Mask" "F.Paste")
			(net "UPI_CPU0_CPU1_P2P2_DP<18>")
		)
		(pad "BK79" smd circle
			(at 27.658314 -3.939286 270)
			(size 0.4318 0.4318)
			(layers "F.Cu" "F.Mask" "F.Paste")
			(net "GND")
		)
		(pad "BK81" smd circle
			(at 29.2862 -3.939286 270)
			(size 0.4318 0.4318)
			(layers "F.Cu" "F.Mask" "F.Paste")
			(net "PVCCIN_CPU1")
		)
		(pad "BK83" smd circle
			(at 30.914086 -3.939286 270)
			(size 0.4318 0.4318)
			(layers "F.Cu" "F.Mask" "F.Paste")
			(net "PVCCIN_CPU1")
		)
		(pad "BK85" smd circle
			(at 32.541718 -3.939286 270)
			(size 0.4318 0.4318)
			(layers "F.Cu" "F.Mask" "F.Paste")
			(net "PVCCIN_CPU1")
		)
		(pad "BK87" smd circle
			(at 34.169604 -3.939286 270)
			(size 0.4318 0.4318)
			(layers "F.Cu" "F.Mask" "F.Paste")
			(net "PVCCIN_CPU1")
		)
		(pad "BK89" smd circle
			(at 35.797236 -3.939286 270)
			(size 0.4318 0.4318)
			(layers "F.Cu" "F.Mask" "F.Paste")
			(net "PVCCIN_CPU1")
		)
		(pad "BK91" smd oval
			(at 37.425122 -3.939286)
			(size 0.381 0.4826)
			(drill
				(offset 0 -0.0508)
			)
			(layers "F.Cu" "F.Mask" "F.Paste")
			(net "PVCCIN_CPU1")
		)
		(pad "BL1" smd oval
			(at -37.425122 -3.579114 180)
			(size 0.381 0.4826)
			(drill
				(offset 0 -0.0508)
			)
			(layers "F.Cu" "F.Mask" "F.Paste")
			(net "GND")
		)
		(pad "BL3" smd circle
			(at -35.797236 -3.579114 270)
			(size 0.4318 0.4318)
			(layers "F.Cu" "F.Mask" "F.Paste")
			(net "UPI_CPU1_CPU0_P0P1_DP<21>")
		)
		(pad "BL5" smd circle
			(at -34.169604 -3.579114 270)
			(size 0.4318 0.4318)
			(layers "F.Cu" "F.Mask" "F.Paste")
			(net "GND")
		)
		(pad "BL7" smd circle
			(at -32.541718 -3.579114 270)
			(size 0.4318 0.4318)
			(layers "F.Cu" "F.Mask" "F.Paste")
			(net "UPI_CPU0_CPU1_P1P0_DP<20>")
		)
		(pad "BL9" smd circle
			(at -30.914086 -3.579114 270)
			(size 0.4318 0.4318)
			(layers "F.Cu" "F.Mask" "F.Paste")
			(net "GND")
		)
		(pad "BL11" smd circle
			(at -29.2862 -3.579114 270)
			(size 0.4318 0.4318)
			(layers "F.Cu" "F.Mask" "F.Paste")
			(net "P5E_CPU1_PE1_RX_DN<11>")
		)
		(pad "BL13" smd circle
			(at -27.658314 -3.579114 270)
			(size 0.4318 0.4318)
			(layers "F.Cu" "F.Mask" "F.Paste")
			(net "GND")
		)
		(pad "BL15" smd circle
			(at -26.030682 -3.579114 270)
			(size 0.4318 0.4318)
			(layers "F.Cu" "F.Mask" "F.Paste")
			(net "P5E_CPU1_PE1_TX_DP<12>")
		)
		(pad "BL17" smd circle
			(at -24.402796 -3.579114 270)
			(size 0.4318 0.4318)
			(layers "F.Cu" "F.Mask" "F.Paste")
			(net "GND")
		)
		(pad "BL19" smd circle
			(at -22.77491 -3.579114 270)
			(size 0.4318 0.4318)
			(layers "F.Cu" "F.Mask" "F.Paste")
			(net "TP_DMI_CPU1_PCH_RX_C_DP<4>")
		)
		(pad "BL21" smd circle
			(at -21.147278 -3.579114 270)
			(size 0.4318 0.4318)
			(layers "F.Cu" "F.Mask" "F.Paste")
			(net "NC_CPU1_PE0_APROBE<1>")
		)
		(pad "BL23" smd circle
			(at -19.519392 -3.579114 270)
			(size 0.4318 0.4318)
			(layers "F.Cu" "F.Mask" "F.Paste")
			(net "DBP_CPU1_MBP0_GTL_R_N")
		)
		(pad "BL25" smd circle
			(at -17.89176 -3.579114 270)
			(size 0.4318 0.4318)
			(layers "F.Cu" "F.Mask" "F.Paste")
			(net "SVID_DIO1_CPU1")
		)
		(pad "BL60" smd circle
			(at 12.19454 -3.469132 270)
			(size 0.4318 0.4318)
			(layers "F.Cu" "F.Mask" "F.Paste")
			(net "NC_CPU1_HBM3_VIEWDIG1")
		)
		(pad "BL62" smd circle
			(at 13.822426 -3.469132 270)
			(size 0.4318 0.4318)
			(layers "F.Cu" "F.Mask" "F.Paste")
			(net "H_CPU1_THERMTRIP_LVC1_R_N")
		)
		(pad "BL64" smd circle
			(at 15.450058 -3.469132 270)
			(size 0.4318 0.4318)
			(layers "F.Cu" "F.Mask" "F.Paste")
			(net "FM_CPU1_PKGID0")
		)
		(pad "BL66" smd circle
			(at 17.07769 -3.469132 270)
			(size 0.4318 0.4318)
			(layers "F.Cu" "F.Mask" "F.Paste")
			(net "TP_TRC_CPU1_PTI<29>")
		)
		(pad "BL68" smd circle
			(at 18.705576 -3.469132 270)
			(size 0.4318 0.4318)
			(layers "F.Cu" "F.Mask" "F.Paste")
			(net "GND")
		)
		(pad "BL70" smd circle
			(at 20.333462 -3.469132 270)
			(size 0.4318 0.4318)
			(layers "F.Cu" "F.Mask" "F.Paste")
			(net "GND")
		)
		(pad "BL72" smd circle
			(at 21.961094 -3.469132 270)
			(size 0.4318 0.4318)
			(layers "F.Cu" "F.Mask" "F.Paste")
			(net "GND")
		)
		(pad "BL74" smd circle
			(at 23.58898 -3.469132 270)
			(size 0.4318 0.4318)
			(layers "F.Cu" "F.Mask" "F.Paste")
			(net "UPI_CPU0_CPU1_P2P2_DP<22>")
		)
		(pad "BL76" smd circle
			(at 25.216612 -3.469132 270)
			(size 0.4318 0.4318)
			(layers "F.Cu" "F.Mask" "F.Paste")
			(net "UPI_CPU0_CPU1_P2P2_DN<19>")
		)
		(pad "BL78" smd circle
			(at 26.844498 -3.469132 270)
			(size 0.4318 0.4318)
			(layers "F.Cu" "F.Mask" "F.Paste")
			(net "GND")
		)
		(pad "BL80" smd circle
			(at 28.472384 -3.469132 270)
			(size 0.4318 0.4318)
			(layers "F.Cu" "F.Mask" "F.Paste")
			(net "PVCCIN_CPU1")
		)
		(pad "BL82" smd circle
			(at 30.100016 -3.469132 270)
			(size 0.4318 0.4318)
			(layers "F.Cu" "F.Mask" "F.Paste")
			(net "PVCCIN_CPU1")
		)
		(pad "BL84" smd circle
			(at 31.727902 -3.469132 270)
			(size 0.4318 0.4318)
			(layers "F.Cu" "F.Mask" "F.Paste")
			(net "PVCCIN_CPU1")
		)
		(pad "BL86" smd circle
			(at 33.355534 -3.469132 270)
			(size 0.4318 0.4318)
			(layers "F.Cu" "F.Mask" "F.Paste")
			(net "PVCCIN_CPU1")
		)
		(pad "BL88" smd circle
			(at 34.98342 -3.469132 270)
			(size 0.4318 0.4318)
			(layers "F.Cu" "F.Mask" "F.Paste")
			(net "PVCCIN_CPU1")
		)
		(pad "BL90" smd circle
			(at 36.611306 -3.469132 270)
			(size 0.4318 0.4318)
			(layers "F.Cu" "F.Mask" "F.Paste")
			(net "PVCCIN_CPU1")
		)
		(pad "BM2" smd oval
			(at -36.611306 -3.109468 180)
			(size 0.381 0.4826)
			(drill
				(offset 0 -0.0508)
			)
			(layers "F.Cu" "F.Mask" "F.Paste")
			(net "UPI_CPU1_CPU0_P0P1_DN<21>")
		)
		(pad "BM4" smd circle
			(at -34.98342 -3.109468 270)
			(size 0.4318 0.4318)
			(layers "F.Cu" "F.Mask" "F.Paste")
			(net "GND")
		)
		(pad "BM6" smd circle
			(at -33.355534 -3.109468 270)
			(size 0.4318 0.4318)
			(layers "F.Cu" "F.Mask" "F.Paste")
			(net "UPI_CPU0_CPU1_P1P0_DP<21>")
		)
		(pad "BM8" smd circle
			(at -31.727902 -3.109468 270)
			(size 0.4318 0.4318)
			(layers "F.Cu" "F.Mask" "F.Paste")
			(net "GND")
		)
		(pad "BM10" smd circle
			(at -30.100016 -3.109468 270)
			(size 0.4318 0.4318)
			(layers "F.Cu" "F.Mask" "F.Paste")
			(net "P5E_CPU1_PE1_RX_DP<11>")
		)
		(pad "BM12" smd circle
			(at -28.472384 -3.109468 270)
			(size 0.4318 0.4318)
			(layers "F.Cu" "F.Mask" "F.Paste")
			(net "GND")
		)
		(pad "BM14" smd circle
			(at -26.844498 -3.109468 270)
			(size 0.4318 0.4318)
			(layers "F.Cu" "F.Mask" "F.Paste")
			(net "P5E_CPU1_PE1_TX_DP<11>")
		)
		(pad "BM16" smd circle
			(at -25.216612 -3.109468 270)
			(size 0.4318 0.4318)
			(layers "F.Cu" "F.Mask" "F.Paste")
			(net "GND")
		)
		(pad "BM18" smd circle
			(at -23.58898 -3.109468 270)
			(size 0.4318 0.4318)
			(layers "F.Cu" "F.Mask" "F.Paste")
			(net "TP_DMI_CPU1_PCH_RX_C_DP<5>")
		)
		(pad "BM20" smd circle
			(at -21.961094 -3.109468 270)
			(size 0.4318 0.4318)
			(layers "F.Cu" "F.Mask" "F.Paste")
			(net "GND")
		)
		(pad "BM22" smd circle
			(at -20.333462 -3.109468 270)
			(size 0.4318 0.4318)
			(layers "F.Cu" "F.Mask" "F.Paste")
			(net "GND")
		)
		(pad "BM24" smd circle
			(at -18.705576 -3.109468 270)
			(size 0.4318 0.4318)
			(layers "F.Cu" "F.Mask" "F.Paste")
			(net "GND")
		)
		(pad "BM26" smd circle
			(at -17.07769 -3.109468 270)
			(size 0.4318 0.4318)
			(layers "F.Cu" "F.Mask" "F.Paste")
			(net "GND")
		)
		(pad "BM61" smd circle
			(at 13.008356 -2.999486 270)
			(size 0.4318 0.4318)
			(layers "F.Cu" "F.Mask" "F.Paste")
			(net "GND")
		)
		(pad "BM63" smd circle
			(at 14.635988 -2.999486 270)
			(size 0.4318 0.4318)
			(layers "F.Cu" "F.Mask" "F.Paste")
			(net "NC_ESPI_IBL_CPU1_IO3")
		)
		(pad "BM65" smd circle
			(at 16.263874 -2.999486 270)
			(size 0.4318 0.4318)
			(layers "F.Cu" "F.Mask" "F.Paste")
			(net "NC_CPU1_SOC_SPARE1")
		)
		(pad "BM67" smd circle
			(at 17.89176 -2.999486 270)
			(size 0.4318 0.4318)
			(layers "F.Cu" "F.Mask" "F.Paste")
			(net "TP_TRC_CPU1_PTI<30>")
		)
		(pad "BM69" smd circle
			(at 19.519392 -2.999486 270)
			(size 0.4318 0.4318)
			(layers "F.Cu" "F.Mask" "F.Paste")
			(net "TP_TRC_CPU1_PTI<25>")
		)
		(pad "BM71" smd circle
			(at 21.147278 -2.999486 270)
			(size 0.4318 0.4318)
			(layers "F.Cu" "F.Mask" "F.Paste")
			(net "UPI_CPU1_CPU0_P2P2_DN<23>")
		)
		(pad "BM73" smd circle
			(at 22.77491 -2.999486 270)
			(size 0.4318 0.4318)
			(layers "F.Cu" "F.Mask" "F.Paste")
			(net "GND")
		)
		(pad "BM75" smd circle
			(at 24.402796 -2.999486 270)
			(size 0.4318 0.4318)
			(layers "F.Cu" "F.Mask" "F.Paste")
			(net "UPI_CPU0_CPU1_P2P2_DP<21>")
		)
		(pad "BM77" smd circle
			(at 26.030682 -2.999486 270)
			(size 0.4318 0.4318)
			(layers "F.Cu" "F.Mask" "F.Paste")
			(net "GND")
		)
		(pad "BM79" smd circle
			(at 27.658314 -2.999486 270)
			(size 0.4318 0.4318)
			(layers "F.Cu" "F.Mask" "F.Paste")
			(net "PVCCIN_CPU1")
		)
		(pad "BM81" smd circle
			(at 29.2862 -2.999486 270)
			(size 0.4318 0.4318)
			(layers "F.Cu" "F.Mask" "F.Paste")
			(net "PVCCIN_CPU1")
		)
		(pad "BM83" smd circle
			(at 30.914086 -2.999486 270)
			(size 0.4318 0.4318)
			(layers "F.Cu" "F.Mask" "F.Paste")
			(net "PVCCIN_CPU1")
		)
		(pad "BM85" smd circle
			(at 32.541718 -2.999486 270)
			(size 0.4318 0.4318)
			(layers "F.Cu" "F.Mask" "F.Paste")
			(net "PVCCIN_CPU1")
		)
		(pad "BM87" smd circle
			(at 34.169604 -2.999486 270)
			(size 0.4318 0.4318)
			(layers "F.Cu" "F.Mask" "F.Paste")
			(net "PVCCIN_CPU1")
		)
		(pad "BM89" smd circle
			(at 35.797236 -2.999486 270)
			(size 0.4318 0.4318)
			(layers "F.Cu" "F.Mask" "F.Paste")
			(net "PVCCIN_CPU1")
		)
		(pad "BM91" smd oval
			(at 37.425122 -2.999486)
			(size 0.381 0.4826)
			(drill
				(offset 0 -0.0508)
			)
			(layers "F.Cu" "F.Mask" "F.Paste")
			(net "PVCCIN_CPU1")
		)
		(pad "BN3" smd circle
			(at -35.797236 -2.639314 270)
			(size 0.4318 0.4318)
			(layers "F.Cu" "F.Mask" "F.Paste")
			(net "UPI_CPU1_CPU0_P0P1_DP<22>")
		)
		(pad "BN5" smd circle
			(at -34.169604 -2.639314 270)
			(size 0.4318 0.4318)
			(layers "F.Cu" "F.Mask" "F.Paste")
			(net "UPI_CPU0_CPU1_P1P0_DN<21>")
		)
		(pad "BN7" smd circle
			(at -32.541718 -2.639314 270)
			(size 0.4318 0.4318)
			(layers "F.Cu" "F.Mask" "F.Paste")
			(net "PVCCD_HV_CPU1")
		)
		(pad "BN9" smd circle
			(at -30.914086 -2.639314 270)
			(size 0.4318 0.4318)
			(layers "F.Cu" "F.Mask" "F.Paste")
			(net "P5E_CPU1_PE1_RX_DP<10>")
		)
		(pad "BN11" smd circle
			(at -29.2862 -2.639314 270)
			(size 0.4318 0.4318)
			(layers "F.Cu" "F.Mask" "F.Paste")
			(net "VSENSE_PVCCD_HV_CPU1_DN")
		)
		(pad "BN13" smd circle
			(at -27.658314 -2.639314 270)
			(size 0.4318 0.4318)
			(layers "F.Cu" "F.Mask" "F.Paste")
			(net "P5E_CPU1_PE1_TX_DN<11>")
		)
		(pad "BN15" smd circle
			(at -26.030682 -2.639314 270)
			(size 0.4318 0.4318)
			(layers "F.Cu" "F.Mask" "F.Paste")
			(net "PVCCINFAON_CPU1")
		)
		(pad "BN17" smd circle
			(at -24.402796 -2.639314 270)
			(size 0.4318 0.4318)
			(layers "F.Cu" "F.Mask" "F.Paste")
			(net "TP_DMI_CPU1_PCH_RX_C_DN<5>")
		)
		(pad "BN19" smd circle
			(at -22.77491 -2.639314 270)
			(size 0.4318 0.4318)
			(layers "F.Cu" "F.Mask" "F.Paste")
			(net "PVNN_MAIN_CPU1")
		)
		(pad "BN21" smd circle
			(at -21.147278 -2.639314 270)
			(size 0.4318 0.4318)
			(layers "F.Cu" "F.Mask" "F.Paste")
			(net "NC_CPU1_PE0_APROBE<0>")
		)
		(pad "BN23" smd circle
			(at -19.519392 -2.639314 270)
			(size 0.4318 0.4318)
			(layers "F.Cu" "F.Mask" "F.Paste")
			(net "H_CPU1_BMCINIT_LVC1")
		)
		(pad "BN25" smd circle
			(at -17.89176 -2.639314 270)
			(size 0.4318 0.4318)
			(layers "F.Cu" "F.Mask" "F.Paste")
			(net "DBP_CPU1_MBP1_GTL_R_N")
		)
		(pad "BN27" smd circle
			(at -16.263874 -2.639314 270)
			(size 0.4318 0.4318)
			(layers "F.Cu" "F.Mask" "F.Paste")
			(net "TP_TRC_CPU1_PTI<12>")
		)
		(pad "BN29" smd circle
			(at -14.635988 -2.639314 270)
			(size 0.4318 0.4318)
			(layers "F.Cu" "F.Mask" "F.Paste")
			(net "TP_TRC_CPU1_PTI<14>")
		)
		(pad "BN31" smd circle
			(at -13.008356 -2.639314 270)
			(size 0.4318 0.4318)
			(layers "F.Cu" "F.Mask" "F.Paste")
			(net "GND")
		)
		(pad "BN33" smd circle
			(at -11.380724 -2.639314 270)
			(size 0.4318 0.4318)
			(layers "F.Cu" "F.Mask" "F.Paste")
			(net "PVCCIN_CPU1")
		)
		(pad "BN35" smd circle
			(at -9.752838 -2.639314 270)
			(size 0.4318 0.4318)
			(layers "F.Cu" "F.Mask" "F.Paste")
			(net "PVCCIN_CPU1")
		)
		(pad "BN37" smd circle
			(at -8.124952 -2.639314 270)
			(size 0.4318 0.4318)
			(layers "F.Cu" "F.Mask" "F.Paste")
			(net "PVCCIN_CPU1")
		)
		(pad "BN39" smd circle
			(at -6.49732 -2.639314 270)
			(size 0.4318 0.4318)
			(layers "F.Cu" "F.Mask" "F.Paste")
			(net "PVCCIN_CPU1")
		)
		(pad "BN41" smd circle
			(at -4.869434 -2.639314 270)
			(size 0.4318 0.4318)
			(layers "F.Cu" "F.Mask" "F.Paste")
			(net "PVCCIN_CPU1")
		)
		(pad "BN43" smd circle
			(at -3.241802 -2.639314 270)
			(size 0.4318 0.4318)
			(layers "F.Cu" "F.Mask" "F.Paste")
			(net "PVCCIN_CPU1")
		)
		(pad "BN45" smd circle
			(at -1.613916 -2.639314 270)
			(size 0.4318 0.4318)
			(layers "F.Cu" "F.Mask" "F.Paste")
			(net "PVCCIN_CPU1")
		)
		(pad "BN48" smd circle
			(at 2.427732 -2.529586 270)
			(size 0.4318 0.4318)
			(layers "F.Cu" "F.Mask" "F.Paste")
			(net "PVCCIN_CPU1")
		)
		(pad "BN50" smd circle
			(at 4.055618 -2.529586 270)
			(size 0.4318 0.4318)
			(layers "F.Cu" "F.Mask" "F.Paste")
			(net "PVCCIN_CPU1")
		)
		(pad "BN52" smd circle
			(at 5.68325 -2.529586 270)
			(size 0.4318 0.4318)
			(layers "F.Cu" "F.Mask" "F.Paste")
			(net "PVCCIN_CPU1")
		)
		(pad "BN54" smd circle
			(at 7.311136 -2.529586 270)
			(size 0.4318 0.4318)
			(layers "F.Cu" "F.Mask" "F.Paste")
			(net "PVCCIN_CPU1")
		)
		(pad "BN56" smd circle
			(at 8.939022 -2.529586 270)
			(size 0.4318 0.4318)
			(layers "F.Cu" "F.Mask" "F.Paste")
			(net "PVCCIN_CPU1")
		)
		(pad "BN58" smd circle
			(at 10.566654 -2.529586 270)
			(size 0.4318 0.4318)
			(layers "F.Cu" "F.Mask" "F.Paste")
			(net "PVCCIN_CPU1")
		)
		(pad "BN60" smd circle
			(at 12.19454 -2.529586 270)
			(size 0.4318 0.4318)
			(layers "F.Cu" "F.Mask" "F.Paste")
			(net "PVCCIN_CPU1")
		)
		(pad "BN62" smd circle
			(at 13.822426 -2.529586 270)
			(size 0.4318 0.4318)
			(layers "F.Cu" "F.Mask" "F.Paste")
			(net "GND")
		)
		(pad "BN64" smd circle
			(at 15.450058 -2.529586 270)
			(size 0.4318 0.4318)
			(layers "F.Cu" "F.Mask" "F.Paste")
			(net "FM_CPU1_PKGID2")
		)
		(pad "BN66" smd circle
			(at 17.07769 -2.529586 270)
			(size 0.4318 0.4318)
			(layers "F.Cu" "F.Mask" "F.Paste")
			(net "TP_TRC_CPU1_PTI<31>")
		)
		(pad "BN68" smd circle
			(at 18.705576 -2.529586 270)
			(size 0.4318 0.4318)
			(layers "F.Cu" "F.Mask" "F.Paste")
			(net "TP_TRC_CPU1_PTI<26>")
		)
		(pad "BN70" smd circle
			(at 20.333462 -2.529586 270)
			(size 0.4318 0.4318)
			(layers "F.Cu" "F.Mask" "F.Paste")
			(net "GND")
		)
		(pad "BN72" smd circle
			(at 21.961094 -2.529586 270)
			(size 0.4318 0.4318)
			(layers "F.Cu" "F.Mask" "F.Paste")
			(net "UPI_CPU1_CPU0_P2P2_DP<23>")
		)
		(pad "BN74" smd circle
			(at 23.58898 -2.529586 270)
			(size 0.4318 0.4318)
			(layers "F.Cu" "F.Mask" "F.Paste")
			(net "UPI_CPU0_CPU1_P2P2_DN<21>")
		)
		(pad "BN76" smd circle
			(at 25.216612 -2.529586 270)
			(size 0.4318 0.4318)
			(layers "F.Cu" "F.Mask" "F.Paste")
			(net "UPI_CPU0_CPU1_P2P2_DP<19>")
		)
		(pad "BN78" smd circle
			(at 26.844498 -2.529586 270)
			(size 0.4318 0.4318)
			(layers "F.Cu" "F.Mask" "F.Paste")
			(net "PVCCIN_CPU1")
		)
		(pad "BN80" smd circle
			(at 28.472384 -2.529586 270)
			(size 0.4318 0.4318)
			(layers "F.Cu" "F.Mask" "F.Paste")
			(net "PVCCIN_CPU1")
		)
		(pad "BN82" smd circle
			(at 30.100016 -2.529586 270)
			(size 0.4318 0.4318)
			(layers "F.Cu" "F.Mask" "F.Paste")
			(net "PVCCIN_CPU1")
		)
		(pad "BN84" smd circle
			(at 31.727902 -2.529586 270)
			(size 0.4318 0.4318)
			(layers "F.Cu" "F.Mask" "F.Paste")
			(net "PVCCIN_CPU1")
		)
		(pad "BN86" smd circle
			(at 33.355534 -2.529586 270)
			(size 0.4318 0.4318)
			(layers "F.Cu" "F.Mask" "F.Paste")
			(net "PVCCIN_CPU1")
		)
		(pad "BN88" smd circle
			(at 34.98342 -2.529586 270)
			(size 0.4318 0.4318)
			(layers "F.Cu" "F.Mask" "F.Paste")
			(net "PVCCIN_CPU1")
		)
		(pad "BN90" smd oval
			(at 36.611306 -2.529586)
			(size 0.381 0.4826)
			(drill
				(offset 0 -0.0508)
			)
			(layers "F.Cu" "F.Mask" "F.Paste")
			(net "PVCCIN_CPU1")
		)
		(pad "BP2" smd oval
			(at -36.611306 -2.169668 180)
			(size 0.381 0.4826)
			(drill
				(offset 0 -0.0508)
			)
			(layers "F.Cu" "F.Mask" "F.Paste")
			(net "GND")
		)
		(pad "BP4" smd circle
			(at -34.98342 -2.169668 270)
			(size 0.4318 0.4318)
			(layers "F.Cu" "F.Mask" "F.Paste")
			(net "GND")
		)
		(pad "BP6" smd circle
			(at -33.355534 -2.169668 270)
			(size 0.4318 0.4318)
			(layers "F.Cu" "F.Mask" "F.Paste")
			(net "UPI_CPU0_CPU1_P1P0_DP<22>")
		)
		(pad "BP8" smd circle
			(at -31.727902 -2.169668 270)
			(size 0.4318 0.4318)
			(layers "F.Cu" "F.Mask" "F.Paste")
			(net "GND")
		)
		(pad "BP10" smd circle
			(at -30.100016 -2.169668 270)
			(size 0.4318 0.4318)
			(layers "F.Cu" "F.Mask" "F.Paste")
			(net "P5E_CPU1_PE1_RX_DN<10>")
		)
		(pad "BP12" smd circle
			(at -28.472384 -2.169668 270)
			(size 0.4318 0.4318)
			(layers "F.Cu" "F.Mask" "F.Paste")
			(net "GND")
		)
		(pad "BP14" smd circle
			(at -26.844498 -2.169668 270)
			(size 0.4318 0.4318)
			(layers "F.Cu" "F.Mask" "F.Paste")
			(net "P5E_CPU1_PE1_TX_DN<10>")
		)
		(pad "BP16" smd circle
			(at -25.216612 -2.169668 270)
			(size 0.4318 0.4318)
			(layers "F.Cu" "F.Mask" "F.Paste")
			(net "GND")
		)
		(pad "BP18" smd circle
			(at -23.58898 -2.169668 270)
			(size 0.4318 0.4318)
			(layers "F.Cu" "F.Mask" "F.Paste")
			(net "TP_DMI_CPU1_PCH_RX_C_DN<6>")
		)
		(pad "BP20" smd circle
			(at -21.961094 -2.169668 270)
			(size 0.4318 0.4318)
			(layers "F.Cu" "F.Mask" "F.Paste")
			(net "GND")
		)
		(pad "BP22" smd circle
			(at -20.333462 -2.169668 270)
			(size 0.4318 0.4318)
			(layers "F.Cu" "F.Mask" "F.Paste")
			(net "NC_CPU1_MDFI_DIE00_EW0")
		)
		(pad "BP24" smd circle
			(at -18.705576 -2.169668 270)
			(size 0.4318 0.4318)
			(layers "F.Cu" "F.Mask" "F.Paste")
			(net "H_CPU1_CATERR_LVC1_R_N")
		)
		(pad "BP26" smd circle
			(at -17.07769 -2.169668 270)
			(size 0.4318 0.4318)
			(layers "F.Cu" "F.Mask" "F.Paste")
			(net "H_CPU1_PRDY_QS_GTL_R_N")
		)
		(pad "BP28" smd circle
			(at -15.450058 -2.169668 270)
			(size 0.4318 0.4318)
			(layers "F.Cu" "F.Mask" "F.Paste")
			(net "TP_TRC_CPU1_PTI<13>")
		)
		(pad "BP30" smd circle
			(at -13.822426 -2.169668 270)
			(size 0.4318 0.4318)
			(layers "F.Cu" "F.Mask" "F.Paste")
			(net "TP_TRC_CPU1_PTI<15>")
		)
		(pad "BP32" smd circle
			(at -12.19454 -2.169668 270)
			(size 0.4318 0.4318)
			(layers "F.Cu" "F.Mask" "F.Paste")
			(net "PVCCIN_CPU1")
		)
		(pad "BP34" smd circle
			(at -10.566654 -2.169668 270)
			(size 0.4318 0.4318)
			(layers "F.Cu" "F.Mask" "F.Paste")
			(net "PVCCIN_CPU1")
		)
		(pad "BP36" smd circle
			(at -8.939022 -2.169668 270)
			(size 0.4318 0.4318)
			(layers "F.Cu" "F.Mask" "F.Paste")
			(net "PVCCIN_CPU1")
		)
		(pad "BP38" smd circle
			(at -7.311136 -2.169668 270)
			(size 0.4318 0.4318)
			(layers "F.Cu" "F.Mask" "F.Paste")
			(net "PVCCIN_CPU1")
		)
		(pad "BP40" smd circle
			(at -5.68325 -2.169668 270)
			(size 0.4318 0.4318)
			(layers "F.Cu" "F.Mask" "F.Paste")
			(net "PVCCIN_CPU1")
		)
		(pad "BP42" smd circle
			(at -4.055618 -2.169668 270)
			(size 0.4318 0.4318)
			(layers "F.Cu" "F.Mask" "F.Paste")
			(net "PVCCIN_CPU1")
		)
		(pad "BP44" smd circle
			(at -2.427732 -2.169668 270)
			(size 0.4318 0.4318)
			(layers "F.Cu" "F.Mask" "F.Paste")
			(net "PVCCIN_CPU1")
		)
		(pad "BP47" smd circle
			(at 1.613916 -2.059686 270)
			(size 0.4318 0.4318)
			(layers "F.Cu" "F.Mask" "F.Paste")
			(net "PVCCIN_CPU1")
		)
		(pad "BP49" smd circle
			(at 3.241802 -2.059686 270)
			(size 0.4318 0.4318)
			(layers "F.Cu" "F.Mask" "F.Paste")
			(net "PVCCIN_CPU1")
		)
		(pad "BP51" smd circle
			(at 4.869434 -2.059686 270)
			(size 0.4318 0.4318)
			(layers "F.Cu" "F.Mask" "F.Paste")
			(net "PVCCIN_CPU1")
		)
		(pad "BP53" smd circle
			(at 6.49732 -2.059686 270)
			(size 0.4318 0.4318)
			(layers "F.Cu" "F.Mask" "F.Paste")
			(net "PVCCIN_CPU1")
		)
		(pad "BP55" smd circle
			(at 8.124952 -2.059686 270)
			(size 0.4318 0.4318)
			(layers "F.Cu" "F.Mask" "F.Paste")
			(net "PVCCIN_CPU1")
		)
		(pad "BP57" smd circle
			(at 9.752838 -2.059686 270)
			(size 0.4318 0.4318)
			(layers "F.Cu" "F.Mask" "F.Paste")
			(net "PVCCIN_CPU1")
		)
		(pad "BP59" smd circle
			(at 11.380724 -2.059686 270)
			(size 0.4318 0.4318)
			(layers "F.Cu" "F.Mask" "F.Paste")
			(net "PVCCIN_CPU1")
		)
		(pad "BP61" smd circle
			(at 13.008356 -2.059686 270)
			(size 0.4318 0.4318)
			(layers "F.Cu" "F.Mask" "F.Paste")
			(net "PVCCIN_CPU1")
		)
		(pad "BP63" smd circle
			(at 14.635988 -2.059686 270)
			(size 0.4318 0.4318)
			(layers "F.Cu" "F.Mask" "F.Paste")
			(net "GND")
		)
		(pad "BP65" smd circle
			(at 16.263874 -2.059686 270)
			(size 0.4318 0.4318)
			(layers "F.Cu" "F.Mask" "F.Paste")
			(net "NC_CPU1_SOC_SPARE5")
		)
		(pad "BP67" smd circle
			(at 17.89176 -2.059686 270)
			(size 0.4318 0.4318)
			(layers "F.Cu" "F.Mask" "F.Paste")
			(net "CPU1_RSVD<64>")
		)
		(pad "BP69" smd circle
			(at 19.519392 -2.059686 270)
			(size 0.4318 0.4318)
			(layers "F.Cu" "F.Mask" "F.Paste")
			(net "CPU1_RSVD<65>")
		)
		(pad "BP71" smd circle
			(at 21.147278 -2.059686 270)
			(size 0.4318 0.4318)
			(layers "F.Cu" "F.Mask" "F.Paste")
			(net "GND")
		)
		(pad "BP73" smd circle
			(at 22.77491 -2.059686 270)
			(size 0.4318 0.4318)
			(layers "F.Cu" "F.Mask" "F.Paste")
			(net "GND")
		)
		(pad "BP75" smd circle
			(at 24.402796 -2.059686 270)
			(size 0.4318 0.4318)
			(layers "F.Cu" "F.Mask" "F.Paste")
			(net "GND")
		)
		(pad "BP77" smd circle
			(at 26.030682 -2.059686 270)
			(size 0.4318 0.4318)
			(layers "F.Cu" "F.Mask" "F.Paste")
			(net "GND")
		)
		(pad "BP79" smd circle
			(at 27.658314 -2.059686 270)
			(size 0.4318 0.4318)
			(layers "F.Cu" "F.Mask" "F.Paste")
			(net "PVCCIN_CPU1")
		)
		(pad "BP81" smd circle
			(at 29.2862 -2.059686 270)
			(size 0.4318 0.4318)
			(layers "F.Cu" "F.Mask" "F.Paste")
			(net "PVCCIN_CPU1")
		)
		(pad "BP83" smd circle
			(at 30.914086 -2.059686 270)
			(size 0.4318 0.4318)
			(layers "F.Cu" "F.Mask" "F.Paste")
			(net "PVCCIN_CPU1")
		)
		(pad "BP85" smd circle
			(at 32.541718 -2.059686 270)
			(size 0.4318 0.4318)
			(layers "F.Cu" "F.Mask" "F.Paste")
			(net "PVCCIN_CPU1")
		)
		(pad "BP87" smd circle
			(at 34.169604 -2.059686 270)
			(size 0.4318 0.4318)
			(layers "F.Cu" "F.Mask" "F.Paste")
			(net "PVCCIN_CPU1")
		)
		(pad "BP89" smd circle
			(at 35.797236 -2.059686 270)
			(size 0.4318 0.4318)
			(layers "F.Cu" "F.Mask" "F.Paste")
			(net "PVCCIN_CPU1")
		)
		(pad "BR3" smd circle
			(at -35.797236 -1.699514 270)
			(size 0.4318 0.4318)
			(layers "F.Cu" "F.Mask" "F.Paste")
			(net "UPI_CPU1_CPU0_P0P1_DN<22>")
		)
		(pad "BR5" smd circle
			(at -34.169604 -1.699514 270)
			(size 0.4318 0.4318)
			(layers "F.Cu" "F.Mask" "F.Paste")
			(net "GND")
		)
		(pad "BR7" smd circle
			(at -32.541718 -1.699514 270)
			(size 0.4318 0.4318)
			(layers "F.Cu" "F.Mask" "F.Paste")
			(net "UPI_CPU0_CPU1_P1P0_DN<22>")
		)
		(pad "BR9" smd circle
			(at -30.914086 -1.699514 270)
			(size 0.4318 0.4318)
			(layers "F.Cu" "F.Mask" "F.Paste")
			(net "GND")
		)
		(pad "BR11" smd circle
			(at -29.2862 -1.699514 270)
			(size 0.4318 0.4318)
			(layers "F.Cu" "F.Mask" "F.Paste")
			(net "P5E_CPU1_PE1_RX_DN<9>")
		)
		(pad "BR13" smd circle
			(at -27.658314 -1.699514 270)
			(size 0.4318 0.4318)
			(layers "F.Cu" "F.Mask" "F.Paste")
			(net "GND")
		)
		(pad "BR15" smd circle
			(at -26.030682 -1.699514 270)
			(size 0.4318 0.4318)
			(layers "F.Cu" "F.Mask" "F.Paste")
			(net "P5E_CPU1_PE1_TX_DP<10>")
		)
		(pad "BR17" smd circle
			(at -24.402796 -1.699514 270)
			(size 0.4318 0.4318)
			(layers "F.Cu" "F.Mask" "F.Paste")
			(net "GND")
		)
		(pad "BR19" smd circle
			(at -22.77491 -1.699514 270)
			(size 0.4318 0.4318)
			(layers "F.Cu" "F.Mask" "F.Paste")
			(net "TP_DMI_CPU1_PCH_RX_C_DP<6>")
		)
		(pad "BR21" smd circle
			(at -21.147278 -1.699514 270)
			(size 0.4318 0.4318)
			(layers "F.Cu" "F.Mask" "F.Paste")
			(net "NC_CPU1_MDFI_DIE00_EW1")
		)
		(pad "BR23" smd circle
			(at -19.519392 -1.699514 270)
			(size 0.4318 0.4318)
			(layers "F.Cu" "F.Mask" "F.Paste")
			(net "TP_CPU1_BR23")
		)
		(pad "BR25" smd circle
			(at -17.89176 -1.699514 270)
			(size 0.4318 0.4318)
			(layers "F.Cu" "F.Mask" "F.Paste")
			(net "JTAG_DBP_CPU1_QS_GTL_R_TMS")
		)
		(pad "BR27" smd circle
			(at -16.263874 -1.699514 270)
			(size 0.4318 0.4318)
			(layers "F.Cu" "F.Mask" "F.Paste")
			(net "GND")
		)
		(pad "BR29" smd circle
			(at -14.635988 -1.699514 270)
			(size 0.4318 0.4318)
			(layers "F.Cu" "F.Mask" "F.Paste")
			(net "GND")
		)
		(pad "BR31" smd circle
			(at -13.008356 -1.699514 270)
			(size 0.4318 0.4318)
			(layers "F.Cu" "F.Mask" "F.Paste")
			(net "GND")
		)
		(pad "BR33" smd circle
			(at -11.380724 -1.699514 270)
			(size 0.4318 0.4318)
			(layers "F.Cu" "F.Mask" "F.Paste")
			(net "GND")
		)
		(pad "BR35" smd circle
			(at -9.752838 -1.699514 270)
			(size 0.4318 0.4318)
			(layers "F.Cu" "F.Mask" "F.Paste")
			(net "GND")
		)
		(pad "BR37" smd circle
			(at -8.124952 -1.699514 270)
			(size 0.4318 0.4318)
			(layers "F.Cu" "F.Mask" "F.Paste")
			(net "GND")
		)
		(pad "BR39" smd circle
			(at -6.49732 -1.699514 270)
			(size 0.4318 0.4318)
			(layers "F.Cu" "F.Mask" "F.Paste")
			(net "GND")
		)
		(pad "BR41" smd circle
			(at -4.869434 -1.699514 270)
			(size 0.4318 0.4318)
			(layers "F.Cu" "F.Mask" "F.Paste")
			(net "GND")
		)
		(pad "BR43" smd circle
			(at -3.241802 -1.699514 270)
			(size 0.4318 0.4318)
			(layers "F.Cu" "F.Mask" "F.Paste")
			(net "GND")
		)
		(pad "BR45" smd circle
			(at -1.613916 -1.699514 270)
			(size 0.4318 0.4318)
			(layers "F.Cu" "F.Mask" "F.Paste")
			(net "GND")
		)
		(pad "BR48" smd circle
			(at 2.427732 -1.589532 270)
			(size 0.4318 0.4318)
			(layers "F.Cu" "F.Mask" "F.Paste")
			(net "GND")
		)
		(pad "BR50" smd circle
			(at 4.055618 -1.589532 270)
			(size 0.4318 0.4318)
			(layers "F.Cu" "F.Mask" "F.Paste")
			(net "GND")
		)
		(pad "BR52" smd circle
			(at 5.68325 -1.589532 270)
			(size 0.4318 0.4318)
			(layers "F.Cu" "F.Mask" "F.Paste")
			(net "GND")
		)
		(pad "BR54" smd circle
			(at 7.311136 -1.589532 270)
			(size 0.4318 0.4318)
			(layers "F.Cu" "F.Mask" "F.Paste")
			(net "GND")
		)
		(pad "BR56" smd circle
			(at 8.939022 -1.589532 270)
			(size 0.4318 0.4318)
			(layers "F.Cu" "F.Mask" "F.Paste")
			(net "GND")
		)
		(pad "BR58" smd circle
			(at 10.566654 -1.589532 270)
			(size 0.4318 0.4318)
			(layers "F.Cu" "F.Mask" "F.Paste")
			(net "GND")
		)
		(pad "BR60" smd circle
			(at 12.19454 -1.589532 270)
			(size 0.4318 0.4318)
			(layers "F.Cu" "F.Mask" "F.Paste")
			(net "PVCCIN_CPU1")
		)
		(pad "BR62" smd circle
			(at 13.822426 -1.589532 270)
			(size 0.4318 0.4318)
			(layers "F.Cu" "F.Mask" "F.Paste")
			(net "PVCCIN_CPU1")
		)
		(pad "BR64" smd circle
			(at 15.450058 -1.589532 270)
			(size 0.4318 0.4318)
			(layers "F.Cu" "F.Mask" "F.Paste")
			(net "GND")
		)
		(pad "BR66" smd circle
			(at 17.07769 -1.589532 270)
			(size 0.4318 0.4318)
			(layers "F.Cu" "F.Mask" "F.Paste")
			(net "GND")
		)
		(pad "BR68" smd circle
			(at 18.705576 -1.589532 270)
			(size 0.4318 0.4318)
			(layers "F.Cu" "F.Mask" "F.Paste")
			(net "GND")
		)
		(pad "BR70" smd circle
			(at 20.333462 -1.589532 270)
			(size 0.4318 0.4318)
			(layers "F.Cu" "F.Mask" "F.Paste")
			(net "GND")
		)
		(pad "BR72" smd circle
			(at 21.961094 -1.589532 270)
			(size 0.4318 0.4318)
			(layers "F.Cu" "F.Mask" "F.Paste")
			(net "GND")
		)
		(pad "BR74" smd circle
			(at 23.58898 -1.589532 270)
			(size 0.4318 0.4318)
			(layers "F.Cu" "F.Mask" "F.Paste")
			(net "GND")
		)
		(pad "BR76" smd circle
			(at 25.216612 -1.589532 270)
			(size 0.4318 0.4318)
			(layers "F.Cu" "F.Mask" "F.Paste")
			(net "GND")
		)
		(pad "BR78" smd circle
			(at 26.844498 -1.589532 270)
			(size 0.4318 0.4318)
			(layers "F.Cu" "F.Mask" "F.Paste")
			(net "PVCCIN_CPU1")
		)
		(pad "BR80" smd circle
			(at 28.472384 -1.589532 270)
			(size 0.4318 0.4318)
			(layers "F.Cu" "F.Mask" "F.Paste")
			(net "GND")
		)
		(pad "BR82" smd circle
			(at 30.100016 -1.589532 270)
			(size 0.4318 0.4318)
			(layers "F.Cu" "F.Mask" "F.Paste")
			(net "GND")
		)
		(pad "BR84" smd circle
			(at 31.727902 -1.589532 270)
			(size 0.4318 0.4318)
			(layers "F.Cu" "F.Mask" "F.Paste")
			(net "GND")
		)
		(pad "BR86" smd circle
			(at 33.355534 -1.589532 270)
			(size 0.4318 0.4318)
			(layers "F.Cu" "F.Mask" "F.Paste")
			(net "GND")
		)
		(pad "BR88" smd circle
			(at 34.98342 -1.589532 270)
			(size 0.4318 0.4318)
			(layers "F.Cu" "F.Mask" "F.Paste")
			(net "GND")
		)
		(pad "BR90" smd oval
			(at 36.611306 -1.589532)
			(size 0.381 0.4826)
			(drill
				(offset 0 -0.0508)
			)
			(layers "F.Cu" "F.Mask" "F.Paste")
			(net "GND")
		)
		(pad "BT2" smd oval
			(at -36.611306 -1.229614 180)
			(size 0.381 0.4826)
			(drill
				(offset 0 -0.0508)
			)
			(layers "F.Cu" "F.Mask" "F.Paste")
			(net "UPI_CPU1_CPU0_P0P1_DN<23>")
		)
		(pad "BT4" smd circle
			(at -34.98342 -1.229614 270)
			(size 0.4318 0.4318)
			(layers "F.Cu" "F.Mask" "F.Paste")
			(net "GND")
		)
		(pad "BT6" smd circle
			(at -33.355534 -1.229614 270)
			(size 0.4318 0.4318)
			(layers "F.Cu" "F.Mask" "F.Paste")
			(net "UPI_CPU0_CPU1_P1P0_DP<23>")
		)
		(pad "BT8" smd circle
			(at -31.727902 -1.229614 270)
			(size 0.4318 0.4318)
			(layers "F.Cu" "F.Mask" "F.Paste")
			(net "GND")
		)
		(pad "BT10" smd circle
			(at -30.100016 -1.229614 270)
			(size 0.4318 0.4318)
			(layers "F.Cu" "F.Mask" "F.Paste")
			(net "P5E_CPU1_PE1_RX_DP<9>")
		)
		(pad "BT12" smd circle
			(at -28.472384 -1.229614 270)
			(size 0.4318 0.4318)
			(layers "F.Cu" "F.Mask" "F.Paste")
			(net "GND")
		)
		(pad "BT14" smd circle
			(at -26.844498 -1.229614 270)
			(size 0.4318 0.4318)
			(layers "F.Cu" "F.Mask" "F.Paste")
			(net "P5E_CPU1_PE1_TX_DP<9>")
		)
		(pad "BT16" smd circle
			(at -25.216612 -1.229614 270)
			(size 0.4318 0.4318)
			(layers "F.Cu" "F.Mask" "F.Paste")
			(net "GND")
		)
		(pad "BT18" smd circle
			(at -23.58898 -1.229614 270)
			(size 0.4318 0.4318)
			(layers "F.Cu" "F.Mask" "F.Paste")
			(net "TP_DMI_CPU1_PCH_RX_C_DP<7>")
		)
		(pad "BT20" smd circle
			(at -21.961094 -1.229614 270)
			(size 0.4318 0.4318)
			(layers "F.Cu" "F.Mask" "F.Paste")
			(net "GND")
		)
		(pad "BT22" smd circle
			(at -20.333462 -1.229614 270)
			(size 0.4318 0.4318)
			(layers "F.Cu" "F.Mask" "F.Paste")
			(net "I3C_SPD_DDRABCD_CPU1_SCL")
		)
		(pad "BT24" smd circle
			(at -18.705576 -1.229614 270)
			(size 0.4318 0.4318)
			(layers "F.Cu" "F.Mask" "F.Paste")
			(net "JTAG_DBP_CPU1_GTL_R_TCK")
		)
		(pad "BT26" smd circle
			(at -17.07769 -1.229614 270)
			(size 0.4318 0.4318)
			(layers "F.Cu" "F.Mask" "F.Paste")
			(net "PU_CPU1_TXT_AGENT")
		)
		(pad "BT28" smd circle
			(at -15.450058 -1.229614 270)
			(size 0.4318 0.4318)
			(layers "F.Cu" "F.Mask" "F.Paste")
			(net "TP_TRC_CPU1_PTI<9>")
		)
		(pad "BT30" smd circle
			(at -13.822426 -1.229614 270)
			(size 0.4318 0.4318)
			(layers "F.Cu" "F.Mask" "F.Paste")
			(net "TP_TRC_CPU1_PTI<11>")
		)
		(pad "BT32" smd circle
			(at -12.19454 -1.229614 270)
			(size 0.4318 0.4318)
			(layers "F.Cu" "F.Mask" "F.Paste")
			(net "PVCCIN_CPU1")
		)
		(pad "BT34" smd circle
			(at -10.566654 -1.229614 270)
			(size 0.4318 0.4318)
			(layers "F.Cu" "F.Mask" "F.Paste")
			(net "PVCCIN_CPU1")
		)
		(pad "BT36" smd circle
			(at -8.939022 -1.229614 270)
			(size 0.4318 0.4318)
			(layers "F.Cu" "F.Mask" "F.Paste")
			(net "PVCCIN_CPU1")
		)
		(pad "BT38" smd circle
			(at -7.311136 -1.229614 270)
			(size 0.4318 0.4318)
			(layers "F.Cu" "F.Mask" "F.Paste")
			(net "PVCCIN_CPU1")
		)
		(pad "BT40" smd circle
			(at -5.68325 -1.229614 270)
			(size 0.4318 0.4318)
			(layers "F.Cu" "F.Mask" "F.Paste")
			(net "PVCCIN_CPU1")
		)
		(pad "BT42" smd circle
			(at -4.055618 -1.229614 270)
			(size 0.4318 0.4318)
			(layers "F.Cu" "F.Mask" "F.Paste")
			(net "PVCCIN_CPU1")
		)
		(pad "BT44" smd circle
			(at -2.427732 -1.229614 270)
			(size 0.4318 0.4318)
			(layers "F.Cu" "F.Mask" "F.Paste")
			(net "PVCCIN_CPU1")
		)
		(pad "BT47" smd circle
			(at 1.613916 -1.119886 270)
			(size 0.4318 0.4318)
			(layers "F.Cu" "F.Mask" "F.Paste")
			(net "PVCCIN_CPU1")
		)
		(pad "BT49" smd circle
			(at 3.241802 -1.119886 270)
			(size 0.4318 0.4318)
			(layers "F.Cu" "F.Mask" "F.Paste")
			(net "PVCCIN_CPU1")
		)
		(pad "BT51" smd circle
			(at 4.869434 -1.119886 270)
			(size 0.4318 0.4318)
			(layers "F.Cu" "F.Mask" "F.Paste")
			(net "PVCCIN_CPU1")
		)
		(pad "BT53" smd circle
			(at 6.49732 -1.119886 270)
			(size 0.4318 0.4318)
			(layers "F.Cu" "F.Mask" "F.Paste")
			(net "PVCCIN_CPU1")
		)
		(pad "BT55" smd circle
			(at 8.124952 -1.119886 270)
			(size 0.4318 0.4318)
			(layers "F.Cu" "F.Mask" "F.Paste")
			(net "PVCCIN_CPU1")
		)
		(pad "BT57" smd circle
			(at 9.752838 -1.119886 270)
			(size 0.4318 0.4318)
			(layers "F.Cu" "F.Mask" "F.Paste")
			(net "PVCCIN_CPU1")
		)
		(pad "BT59" smd circle
			(at 11.380724 -1.119886 270)
			(size 0.4318 0.4318)
			(layers "F.Cu" "F.Mask" "F.Paste")
			(net "PVCCIN_CPU1")
		)
		(pad "BT61" smd circle
			(at 13.008356 -1.119886 270)
			(size 0.4318 0.4318)
			(layers "F.Cu" "F.Mask" "F.Paste")
			(net "PVCCIN_CPU1")
		)
		(pad "BT63" smd circle
			(at 14.635988 -1.119886 270)
			(size 0.4318 0.4318)
			(layers "F.Cu" "F.Mask" "F.Paste")
			(net "PVCCIN_CPU1")
		)
		(pad "BT65" smd circle
			(at 16.263874 -1.119886 270)
			(size 0.4318 0.4318)
			(layers "F.Cu" "F.Mask" "F.Paste")
			(net "PVCCIN_CPU1")
		)
		(pad "BT67" smd circle
			(at 17.89176 -1.119886 270)
			(size 0.4318 0.4318)
			(layers "F.Cu" "F.Mask" "F.Paste")
			(net "PVCCIN_CPU1")
		)
		(pad "BT69" smd circle
			(at 19.519392 -1.119886 270)
			(size 0.4318 0.4318)
			(layers "F.Cu" "F.Mask" "F.Paste")
			(net "PVCCIN_CPU1")
		)
		(pad "BT71" smd circle
			(at 21.147278 -1.119886 270)
			(size 0.4318 0.4318)
			(layers "F.Cu" "F.Mask" "F.Paste")
			(net "PVCCIN_CPU1")
		)
		(pad "BT73" smd circle
			(at 22.77491 -1.119886 270)
			(size 0.4318 0.4318)
			(layers "F.Cu" "F.Mask" "F.Paste")
			(net "PVCCIN_CPU1")
		)
		(pad "BT75" smd circle
			(at 24.402796 -1.119886 270)
			(size 0.4318 0.4318)
			(layers "F.Cu" "F.Mask" "F.Paste")
			(net "PVCCIN_CPU1")
		)
		(pad "BT77" smd circle
			(at 26.030682 -1.119886 270)
			(size 0.4318 0.4318)
			(layers "F.Cu" "F.Mask" "F.Paste")
			(net "PVCCIN_CPU1")
		)
		(pad "BT79" smd circle
			(at 27.658314 -1.119886 270)
			(size 0.4318 0.4318)
			(layers "F.Cu" "F.Mask" "F.Paste")
			(net "PVCCIN_CPU1")
		)
		(pad "BT81" smd circle
			(at 29.2862 -1.119886 270)
			(size 0.4318 0.4318)
			(layers "F.Cu" "F.Mask" "F.Paste")
			(net "PVCCIN_CPU1")
		)
		(pad "BT83" smd circle
			(at 30.914086 -1.119886 270)
			(size 0.4318 0.4318)
			(layers "F.Cu" "F.Mask" "F.Paste")
			(net "PVCCIN_CPU1")
		)
		(pad "BT85" smd circle
			(at 32.541718 -1.119886 270)
			(size 0.4318 0.4318)
			(layers "F.Cu" "F.Mask" "F.Paste")
			(net "PVCCIN_CPU1")
		)
		(pad "BT87" smd circle
			(at 34.169604 -1.119886 270)
			(size 0.4318 0.4318)
			(layers "F.Cu" "F.Mask" "F.Paste")
			(net "PVCCIN_CPU1")
		)
		(pad "BT89" smd circle
			(at 35.797236 -1.119886 270)
			(size 0.4318 0.4318)
			(layers "F.Cu" "F.Mask" "F.Paste")
			(net "PVCCIN_CPU1")
		)
		(pad "BU3" smd circle
			(at -35.797236 -0.759714 270)
			(size 0.4318 0.4318)
			(layers "F.Cu" "F.Mask" "F.Paste")
			(net "UPI_CPU1_CPU0_P0P1_DP<23>")
		)
		(pad "BU5" smd circle
			(at -34.169604 -0.759714 270)
			(size 0.4318 0.4318)
			(layers "F.Cu" "F.Mask" "F.Paste")
			(net "UPI_CPU0_CPU1_P1P0_DN<23>")
		)
		(pad "BU7" smd circle
			(at -32.541718 -0.759714 270)
			(size 0.4318 0.4318)
			(layers "F.Cu" "F.Mask" "F.Paste")
			(net "GND")
		)
		(pad "BU9" smd circle
			(at -30.914086 -0.759714 270)
			(size 0.4318 0.4318)
			(layers "F.Cu" "F.Mask" "F.Paste")
			(net "P5E_CPU1_PE1_RX_DP<8>")
		)
		(pad "BU11" smd circle
			(at -29.2862 -0.759714 270)
			(size 0.4318 0.4318)
			(layers "F.Cu" "F.Mask" "F.Paste")
			(net "VSENSE_PVCCD_HV_CPU1_DP")
		)
		(pad "BU13" smd circle
			(at -27.658314 -0.759714 270)
			(size 0.4318 0.4318)
			(layers "F.Cu" "F.Mask" "F.Paste")
			(net "P5E_CPU1_PE1_TX_DN<9>")
		)
		(pad "BU15" smd circle
			(at -26.030682 -0.759714 270)
			(size 0.4318 0.4318)
			(layers "F.Cu" "F.Mask" "F.Paste")
			(net "GND")
		)
		(pad "BU17" smd circle
			(at -24.402796 -0.759714 270)
			(size 0.4318 0.4318)
			(layers "F.Cu" "F.Mask" "F.Paste")
			(net "TP_DMI_CPU1_PCH_RX_C_DN<7>")
		)
		(pad "BU19" smd circle
			(at -22.77491 -0.759714 270)
			(size 0.4318 0.4318)
			(layers "F.Cu" "F.Mask" "F.Paste")
			(net "GND")
		)
		(pad "BU21" smd circle
			(at -21.147278 -0.759714 270)
			(size 0.4318 0.4318)
			(layers "F.Cu" "F.Mask" "F.Paste")
			(net "GND")
		)
		(pad "BU23" smd circle
			(at -19.519392 -0.759714 270)
			(size 0.4318 0.4318)
			(layers "F.Cu" "F.Mask" "F.Paste")
			(net "GND")
		)
		(pad "BU25" smd circle
			(at -17.89176 -0.759714 270)
			(size 0.4318 0.4318)
			(layers "F.Cu" "F.Mask" "F.Paste")
			(net "GND")
		)
		(pad "BU27" smd circle
			(at -16.263874 -0.759714 270)
			(size 0.4318 0.4318)
			(layers "F.Cu" "F.Mask" "F.Paste")
			(net "TP_TRC_CPU1_PTI<8>")
		)
		(pad "BU29" smd circle
			(at -14.635988 -0.759714 270)
			(size 0.4318 0.4318)
			(layers "F.Cu" "F.Mask" "F.Paste")
			(net "TP_TRC_CPU1_PTI<10>")
		)
		(pad "BU31" smd circle
			(at -13.008356 -0.759714 270)
			(size 0.4318 0.4318)
			(layers "F.Cu" "F.Mask" "F.Paste")
			(net "GND")
		)
		(pad "BU33" smd circle
			(at -11.380724 -0.759714 270)
			(size 0.4318 0.4318)
			(layers "F.Cu" "F.Mask" "F.Paste")
			(net "PVCCIN_CPU1")
		)
		(pad "BU35" smd circle
			(at -9.752838 -0.759714 270)
			(size 0.4318 0.4318)
			(layers "F.Cu" "F.Mask" "F.Paste")
			(net "PVCCIN_CPU1")
		)
		(pad "BU37" smd circle
			(at -8.124952 -0.759714 270)
			(size 0.4318 0.4318)
			(layers "F.Cu" "F.Mask" "F.Paste")
			(net "PVCCIN_CPU1")
		)
		(pad "BU39" smd circle
			(at -6.49732 -0.759714 270)
			(size 0.4318 0.4318)
			(layers "F.Cu" "F.Mask" "F.Paste")
			(net "PVCCIN_CPU1")
		)
		(pad "BU41" smd circle
			(at -4.869434 -0.759714 270)
			(size 0.4318 0.4318)
			(layers "F.Cu" "F.Mask" "F.Paste")
			(net "PVCCIN_CPU1")
		)
		(pad "BU43" smd circle
			(at -3.241802 -0.759714 270)
			(size 0.4318 0.4318)
			(layers "F.Cu" "F.Mask" "F.Paste")
			(net "PVCCIN_CPU1")
		)
		(pad "BU45" smd circle
			(at -1.613916 -0.759714 270)
			(size 0.4318 0.4318)
			(layers "F.Cu" "F.Mask" "F.Paste")
			(net "PVCCIN_CPU1")
		)
		(pad "BU48" smd circle
			(at 2.427732 -0.649732 270)
			(size 0.4318 0.4318)
			(layers "F.Cu" "F.Mask" "F.Paste")
			(net "PVCCIN_CPU1")
		)
		(pad "BU50" smd circle
			(at 4.055618 -0.649732 270)
			(size 0.4318 0.4318)
			(layers "F.Cu" "F.Mask" "F.Paste")
			(net "PVCCIN_CPU1")
		)
		(pad "BU52" smd circle
			(at 5.68325 -0.649732 270)
			(size 0.4318 0.4318)
			(layers "F.Cu" "F.Mask" "F.Paste")
			(net "PVCCIN_CPU1")
		)
		(pad "BU54" smd circle
			(at 7.311136 -0.649732 270)
			(size 0.4318 0.4318)
			(layers "F.Cu" "F.Mask" "F.Paste")
			(net "PVCCIN_CPU1")
		)
		(pad "BU56" smd circle
			(at 8.939022 -0.649732 270)
			(size 0.4318 0.4318)
			(layers "F.Cu" "F.Mask" "F.Paste")
			(net "PVCCIN_CPU1")
		)
		(pad "BU58" smd circle
			(at 10.566654 -0.649732 270)
			(size 0.4318 0.4318)
			(layers "F.Cu" "F.Mask" "F.Paste")
			(net "PVCCIN_CPU1")
		)
		(pad "BU60" smd circle
			(at 12.19454 -0.649732 270)
			(size 0.4318 0.4318)
			(layers "F.Cu" "F.Mask" "F.Paste")
			(net "PVCCIN_CPU1")
		)
		(pad "BU62" smd circle
			(at 13.822426 -0.649732 270)
			(size 0.4318 0.4318)
			(layers "F.Cu" "F.Mask" "F.Paste")
			(net "PVCCIN_CPU1")
		)
		(pad "BU64" smd circle
			(at 15.450058 -0.649732 270)
			(size 0.4318 0.4318)
			(layers "F.Cu" "F.Mask" "F.Paste")
			(net "PVCCIN_CPU1")
		)
		(pad "BU66" smd circle
			(at 17.07769 -0.649732 270)
			(size 0.4318 0.4318)
			(layers "F.Cu" "F.Mask" "F.Paste")
			(net "PVCCIN_CPU1")
		)
		(pad "BU68" smd circle
			(at 18.705576 -0.649732 270)
			(size 0.4318 0.4318)
			(layers "F.Cu" "F.Mask" "F.Paste")
			(net "PVCCIN_CPU1")
		)
		(pad "BU70" smd circle
			(at 20.333462 -0.649732 270)
			(size 0.4318 0.4318)
			(layers "F.Cu" "F.Mask" "F.Paste")
			(net "PVCCIN_CPU1")
		)
		(pad "BU72" smd circle
			(at 21.961094 -0.649732 270)
			(size 0.4318 0.4318)
			(layers "F.Cu" "F.Mask" "F.Paste")
			(net "PVCCIN_CPU1")
		)
		(pad "BU74" smd circle
			(at 23.58898 -0.649732 270)
			(size 0.4318 0.4318)
			(layers "F.Cu" "F.Mask" "F.Paste")
			(net "PVCCIN_CPU1")
		)
		(pad "BU76" smd circle
			(at 25.216612 -0.649732 270)
			(size 0.4318 0.4318)
			(layers "F.Cu" "F.Mask" "F.Paste")
			(net "PVCCIN_CPU1")
		)
		(pad "BU78" smd circle
			(at 26.844498 -0.649732 270)
			(size 0.4318 0.4318)
			(layers "F.Cu" "F.Mask" "F.Paste")
			(net "PVCCIN_CPU1")
		)
		(pad "BU80" smd circle
			(at 28.472384 -0.649732 270)
			(size 0.4318 0.4318)
			(layers "F.Cu" "F.Mask" "F.Paste")
			(net "PVCCIN_CPU1")
		)
		(pad "BU82" smd circle
			(at 30.100016 -0.649732 270)
			(size 0.4318 0.4318)
			(layers "F.Cu" "F.Mask" "F.Paste")
			(net "PVCCIN_CPU1")
		)
		(pad "BU84" smd circle
			(at 31.727902 -0.649732 270)
			(size 0.4318 0.4318)
			(layers "F.Cu" "F.Mask" "F.Paste")
			(net "PVCCIN_CPU1")
		)
		(pad "BU86" smd circle
			(at 33.355534 -0.649732 270)
			(size 0.4318 0.4318)
			(layers "F.Cu" "F.Mask" "F.Paste")
			(net "PVCCIN_CPU1")
		)
		(pad "BU88" smd circle
			(at 34.98342 -0.649732 270)
			(size 0.4318 0.4318)
			(layers "F.Cu" "F.Mask" "F.Paste")
			(net "PVCCIN_CPU1")
		)
		(pad "BU90" smd oval
			(at 36.611306 -0.649732)
			(size 0.381 0.4826)
			(drill
				(offset 0 -0.0508)
			)
			(layers "F.Cu" "F.Mask" "F.Paste")
			(net "PVCCIN_CPU1")
		)
		(pad "BV2" smd oval
			(at -36.611306 -0.290068 180)
			(size 0.381 0.4826)
			(drill
				(offset 0 -0.0508)
			)
			(layers "F.Cu" "F.Mask" "F.Paste")
			(net "GND")
		)
		(pad "BV4" smd circle
			(at -34.98342 -0.290068 270)
			(size 0.4318 0.4318)
			(layers "F.Cu" "F.Mask" "F.Paste")
			(net "GND")
		)
		(pad "BV6" smd circle
			(at -33.355534 -0.290068 270)
			(size 0.4318 0.4318)
			(layers "F.Cu" "F.Mask" "F.Paste")
			(net "GND")
		)
		(pad "BV8" smd circle
			(at -31.727902 -0.290068 270)
			(size 0.4318 0.4318)
			(layers "F.Cu" "F.Mask" "F.Paste")
			(net "GND")
		)
		(pad "BV10" smd circle
			(at -30.100016 -0.290068 270)
			(size 0.4318 0.4318)
			(layers "F.Cu" "F.Mask" "F.Paste")
			(net "P5E_CPU1_PE1_RX_DN<8>")
		)
		(pad "BV12" smd circle
			(at -28.472384 -0.290068 270)
			(size 0.4318 0.4318)
			(layers "F.Cu" "F.Mask" "F.Paste")
			(net "GND")
		)
		(pad "BV14" smd circle
			(at -26.844498 -0.290068 270)
			(size 0.4318 0.4318)
			(layers "F.Cu" "F.Mask" "F.Paste")
			(net "P5E_CPU1_PE1_TX_DN<8>")
		)
		(pad "BV16" smd circle
			(at -25.216612 -0.290068 270)
			(size 0.4318 0.4318)
			(layers "F.Cu" "F.Mask" "F.Paste")
			(net "GND")
		)
		(pad "BV18" smd circle
			(at -23.58898 -0.290068 270)
			(size 0.4318 0.4318)
			(layers "F.Cu" "F.Mask" "F.Paste")
			(net "GND")
		)
		(pad "BV20" smd circle
			(at -21.961094 -0.290068 270)
			(size 0.4318 0.4318)
			(layers "F.Cu" "F.Mask" "F.Paste")
			(net "GND")
		)
		(pad "BV22" smd circle
			(at -20.333462 -0.290068 270)
			(size 0.4318 0.4318)
			(layers "F.Cu" "F.Mask" "F.Paste")
			(net "NC_CPU1_UPI1_APROBE<0>")
		)
		(pad "BV24" smd circle
			(at -18.705576 -0.290068 270)
			(size 0.4318 0.4318)
			(layers "F.Cu" "F.Mask" "F.Paste")
			(net "JTAG_DBP_CPU1_GTL_R_TDI")
		)
		(pad "BV26" smd circle
			(at -17.07769 -0.290068 270)
			(size 0.4318 0.4318)
			(layers "F.Cu" "F.Mask" "F.Paste")
			(net "FM_PEHPCPU1_ALERT_N")
		)
		(pad "BV28" smd circle
			(at -15.450058 -0.290068 270)
			(size 0.4318 0.4318)
			(layers "F.Cu" "F.Mask" "F.Paste")
			(net "TP_TRC_CPU1_PTI<7>")
		)
		(pad "BV30" smd circle
			(at -13.822426 -0.290068 270)
			(size 0.4318 0.4318)
			(layers "F.Cu" "F.Mask" "F.Paste")
			(net "TP_TRC_CPU1_PTI<5>")
		)
		(pad "BV32" smd circle
			(at -12.19454 -0.290068 270)
			(size 0.4318 0.4318)
			(layers "F.Cu" "F.Mask" "F.Paste")
			(net "PVCCIN_CPU1")
		)
		(pad "BV34" smd circle
			(at -10.566654 -0.290068 270)
			(size 0.4318 0.4318)
			(layers "F.Cu" "F.Mask" "F.Paste")
			(net "PVCCIN_CPU1")
		)
		(pad "BV36" smd circle
			(at -8.939022 -0.290068 270)
			(size 0.4318 0.4318)
			(layers "F.Cu" "F.Mask" "F.Paste")
			(net "PVCCIN_CPU1")
		)
		(pad "BV38" smd circle
			(at -7.311136 -0.290068 270)
			(size 0.4318 0.4318)
			(layers "F.Cu" "F.Mask" "F.Paste")
			(net "PVCCIN_CPU1")
		)
		(pad "BV40" smd circle
			(at -5.68325 -0.290068 270)
			(size 0.4318 0.4318)
			(layers "F.Cu" "F.Mask" "F.Paste")
			(net "PVCCIN_CPU1")
		)
		(pad "BV42" smd circle
			(at -4.055618 -0.290068 270)
			(size 0.4318 0.4318)
			(layers "F.Cu" "F.Mask" "F.Paste")
			(net "PVCCIN_CPU1")
		)
		(pad "BV44" smd circle
			(at -2.427732 -0.290068 270)
			(size 0.4318 0.4318)
			(layers "F.Cu" "F.Mask" "F.Paste")
			(net "PVCCIN_CPU1")
		)
		(pad "BV47" smd circle
			(at 1.613916 -0.180086 270)
			(size 0.4318 0.4318)
			(layers "F.Cu" "F.Mask" "F.Paste")
			(net "PVCCIN_CPU1")
		)
		(pad "BV49" smd circle
			(at 3.241802 -0.180086 270)
			(size 0.4318 0.4318)
			(layers "F.Cu" "F.Mask" "F.Paste")
			(net "PVCCIN_CPU1")
		)
		(pad "BV51" smd circle
			(at 4.869434 -0.180086 270)
			(size 0.4318 0.4318)
			(layers "F.Cu" "F.Mask" "F.Paste")
			(net "PVCCIN_CPU1")
		)
		(pad "BV53" smd circle
			(at 6.49732 -0.180086 270)
			(size 0.4318 0.4318)
			(layers "F.Cu" "F.Mask" "F.Paste")
			(net "PVCCIN_CPU1")
		)
		(pad "BV55" smd circle
			(at 8.124952 -0.180086 270)
			(size 0.4318 0.4318)
			(layers "F.Cu" "F.Mask" "F.Paste")
			(net "PVCCIN_CPU1")
		)
		(pad "BV57" smd circle
			(at 9.752838 -0.180086 270)
			(size 0.4318 0.4318)
			(layers "F.Cu" "F.Mask" "F.Paste")
			(net "PVCCIN_CPU1")
		)
		(pad "BV59" smd circle
			(at 11.380724 -0.180086 270)
			(size 0.4318 0.4318)
			(layers "F.Cu" "F.Mask" "F.Paste")
			(net "PVCCIN_CPU1")
		)
		(pad "BV61" smd circle
			(at 13.008356 -0.180086 270)
			(size 0.4318 0.4318)
			(layers "F.Cu" "F.Mask" "F.Paste")
			(net "PVCCIN_CPU1")
		)
		(pad "BV63" smd circle
			(at 14.635988 -0.180086 270)
			(size 0.4318 0.4318)
			(layers "F.Cu" "F.Mask" "F.Paste")
			(net "PVCCIN_CPU1")
		)
		(pad "BV65" smd circle
			(at 16.263874 -0.180086 270)
			(size 0.4318 0.4318)
			(layers "F.Cu" "F.Mask" "F.Paste")
			(net "PVCCIN_CPU1")
		)
		(pad "BV67" smd circle
			(at 17.89176 -0.180086 270)
			(size 0.4318 0.4318)
			(layers "F.Cu" "F.Mask" "F.Paste")
			(net "PVCCIN_CPU1")
		)
		(pad "BV69" smd circle
			(at 19.519392 -0.180086 270)
			(size 0.4318 0.4318)
			(layers "F.Cu" "F.Mask" "F.Paste")
			(net "PVCCIN_CPU1")
		)
		(pad "BV71" smd circle
			(at 21.147278 -0.180086 270)
			(size 0.4318 0.4318)
			(layers "F.Cu" "F.Mask" "F.Paste")
			(net "PVCCIN_CPU1")
		)
		(pad "BV73" smd circle
			(at 22.77491 -0.180086 270)
			(size 0.4318 0.4318)
			(layers "F.Cu" "F.Mask" "F.Paste")
			(net "PVCCIN_CPU1")
		)
		(pad "BV75" smd circle
			(at 24.402796 -0.180086 270)
			(size 0.4318 0.4318)
			(layers "F.Cu" "F.Mask" "F.Paste")
			(net "PVCCIN_CPU1")
		)
		(pad "BV77" smd circle
			(at 26.030682 -0.180086 270)
			(size 0.4318 0.4318)
			(layers "F.Cu" "F.Mask" "F.Paste")
			(net "PVCCIN_CPU1")
		)
		(pad "BV79" smd circle
			(at 27.658314 -0.180086 270)
			(size 0.4318 0.4318)
			(layers "F.Cu" "F.Mask" "F.Paste")
			(net "PVCCIN_CPU1")
		)
		(pad "BV81" smd circle
			(at 29.2862 -0.180086 270)
			(size 0.4318 0.4318)
			(layers "F.Cu" "F.Mask" "F.Paste")
			(net "PVCCIN_CPU1")
		)
		(pad "BV83" smd circle
			(at 30.914086 -0.180086 270)
			(size 0.4318 0.4318)
			(layers "F.Cu" "F.Mask" "F.Paste")
			(net "PVCCIN_CPU1")
		)
		(pad "BV85" smd circle
			(at 32.541718 -0.180086 270)
			(size 0.4318 0.4318)
			(layers "F.Cu" "F.Mask" "F.Paste")
			(net "PVCCIN_CPU1")
		)
		(pad "BV87" smd circle
			(at 34.169604 -0.180086 270)
			(size 0.4318 0.4318)
			(layers "F.Cu" "F.Mask" "F.Paste")
			(net "PVCCIN_CPU1")
		)
		(pad "BV89" smd circle
			(at 35.797236 -0.180086 270)
			(size 0.4318 0.4318)
			(layers "F.Cu" "F.Mask" "F.Paste")
			(net "PVCCIN_CPU1")
		)
		(pad "BW3" smd circle
			(at -35.797236 0.180086 270)
			(size 0.4318 0.4318)
			(layers "F.Cu" "F.Mask" "F.Paste")
			(net "GND")
		)
		(pad "BW5" smd circle
			(at -34.169604 0.180086 270)
			(size 0.4318 0.4318)
			(layers "F.Cu" "F.Mask" "F.Paste")
			(net "GND")
		)
		(pad "BW7" smd circle
			(at -32.541718 0.180086 270)
			(size 0.4318 0.4318)
			(layers "F.Cu" "F.Mask" "F.Paste")
			(net "UPI_CPU1_CPU0_P1P0_DP<23>")
		)
		(pad "BW9" smd circle
			(at -30.914086 0.180086 270)
			(size 0.4318 0.4318)
			(layers "F.Cu" "F.Mask" "F.Paste")
			(net "GND")
		)
		(pad "BW11" smd circle
			(at -29.2862 0.180086 270)
			(size 0.4318 0.4318)
			(layers "F.Cu" "F.Mask" "F.Paste")
			(net "P5E_CPU1_PE1_RX_DN<7>")
		)
		(pad "BW13" smd circle
			(at -27.658314 0.180086 270)
			(size 0.4318 0.4318)
			(layers "F.Cu" "F.Mask" "F.Paste")
			(net "GND")
		)
		(pad "BW15" smd circle
			(at -26.030682 0.180086 270)
			(size 0.4318 0.4318)
			(layers "F.Cu" "F.Mask" "F.Paste")
			(net "P5E_CPU1_PE1_TX_DP<8>")
		)
		(pad "BW17" smd circle
			(at -24.402796 0.180086 270)
			(size 0.4318 0.4318)
			(layers "F.Cu" "F.Mask" "F.Paste")
			(net "GND")
		)
		(pad "BW19" smd circle
			(at -22.77491 0.180086 270)
			(size 0.4318 0.4318)
			(layers "F.Cu" "F.Mask" "F.Paste")
			(net "TP_DMI_CPU1_PCH_TX_DN<0>")
		)
		(pad "BW21" smd circle
			(at -21.147278 0.180086 270)
			(size 0.4318 0.4318)
			(layers "F.Cu" "F.Mask" "F.Paste")
			(net "NC_CPU1_DMI_APROBE<1>")
		)
		(pad "BW23" smd circle
			(at -19.519392 0.180086 270)
			(size 0.4318 0.4318)
			(layers "F.Cu" "F.Mask" "F.Paste")
			(net "NC_CPU1_PE2_APROBE<1>")
		)
		(pad "BW25" smd circle
			(at -17.89176 0.180086 270)
			(size 0.4318 0.4318)
			(layers "F.Cu" "F.Mask" "F.Paste")
			(net "JTAG_CPU1_MUX_GTL_TDO")
		)
		(pad "BW27" smd circle
			(at -16.263874 0.180086 270)
			(size 0.4318 0.4318)
			(layers "F.Cu" "F.Mask" "F.Paste")
			(net "GND")
		)
		(pad "BW29" smd circle
			(at -14.635988 0.180086 270)
			(size 0.4318 0.4318)
			(layers "F.Cu" "F.Mask" "F.Paste")
			(net "GND")
		)
		(pad "BW31" smd circle
			(at -13.008356 0.180086 270)
			(size 0.4318 0.4318)
			(layers "F.Cu" "F.Mask" "F.Paste")
			(net "GND")
		)
		(pad "BW33" smd circle
			(at -11.380724 0.180086 270)
			(size 0.4318 0.4318)
			(layers "F.Cu" "F.Mask" "F.Paste")
			(net "PVCCIN_CPU1")
		)
		(pad "BW35" smd circle
			(at -9.752838 0.180086 270)
			(size 0.4318 0.4318)
			(layers "F.Cu" "F.Mask" "F.Paste")
			(net "PVCCIN_CPU1")
		)
		(pad "BW37" smd circle
			(at -8.124952 0.180086 270)
			(size 0.4318 0.4318)
			(layers "F.Cu" "F.Mask" "F.Paste")
			(net "PVCCIN_CPU1")
		)
		(pad "BW39" smd circle
			(at -6.49732 0.180086 270)
			(size 0.4318 0.4318)
			(layers "F.Cu" "F.Mask" "F.Paste")
			(net "PVCCIN_CPU1")
		)
		(pad "BW41" smd circle
			(at -4.869434 0.180086 270)
			(size 0.4318 0.4318)
			(layers "F.Cu" "F.Mask" "F.Paste")
			(net "PVCCIN_CPU1")
		)
		(pad "BW43" smd circle
			(at -3.241802 0.180086 270)
			(size 0.4318 0.4318)
			(layers "F.Cu" "F.Mask" "F.Paste")
			(net "PVCCIN_CPU1")
		)
		(pad "BW45" smd circle
			(at -1.613916 0.180086 270)
			(size 0.4318 0.4318)
			(layers "F.Cu" "F.Mask" "F.Paste")
			(net "PVCCIN_CPU1")
		)
		(pad "BW48" smd circle
			(at 2.427732 0.290068 270)
			(size 0.4318 0.4318)
			(layers "F.Cu" "F.Mask" "F.Paste")
			(net "PVCCIN_CPU1")
		)
		(pad "BW50" smd circle
			(at 4.055618 0.290068 270)
			(size 0.4318 0.4318)
			(layers "F.Cu" "F.Mask" "F.Paste")
			(net "PVCCIN_CPU1")
		)
		(pad "BW52" smd circle
			(at 5.68325 0.290068 270)
			(size 0.4318 0.4318)
			(layers "F.Cu" "F.Mask" "F.Paste")
			(net "PVCCIN_CPU1")
		)
		(pad "BW54" smd circle
			(at 7.311136 0.290068 270)
			(size 0.4318 0.4318)
			(layers "F.Cu" "F.Mask" "F.Paste")
			(net "PVCCIN_CPU1")
		)
		(pad "BW56" smd circle
			(at 8.939022 0.290068 270)
			(size 0.4318 0.4318)
			(layers "F.Cu" "F.Mask" "F.Paste")
			(net "PVCCIN_CPU1")
		)
		(pad "BW58" smd circle
			(at 10.566654 0.290068 270)
			(size 0.4318 0.4318)
			(layers "F.Cu" "F.Mask" "F.Paste")
			(net "PVCCIN_CPU1")
		)
		(pad "BW60" smd circle
			(at 12.19454 0.290068 270)
			(size 0.4318 0.4318)
			(layers "F.Cu" "F.Mask" "F.Paste")
			(net "PVCCIN_CPU1")
		)
		(pad "BW62" smd circle
			(at 13.822426 0.290068 270)
			(size 0.4318 0.4318)
			(layers "F.Cu" "F.Mask" "F.Paste")
			(net "PVCCIN_CPU1")
		)
		(pad "BW64" smd circle
			(at 15.450058 0.290068 270)
			(size 0.4318 0.4318)
			(layers "F.Cu" "F.Mask" "F.Paste")
			(net "PVCCIN_CPU1")
		)
		(pad "BW66" smd circle
			(at 17.07769 0.290068 270)
			(size 0.4318 0.4318)
			(layers "F.Cu" "F.Mask" "F.Paste")
			(net "PVCCIN_CPU1")
		)
		(pad "BW68" smd circle
			(at 18.705576 0.290068 270)
			(size 0.4318 0.4318)
			(layers "F.Cu" "F.Mask" "F.Paste")
			(net "PVCCIN_CPU1")
		)
		(pad "BW70" smd circle
			(at 20.333462 0.290068 270)
			(size 0.4318 0.4318)
			(layers "F.Cu" "F.Mask" "F.Paste")
			(net "PVCCIN_CPU1")
		)
		(pad "BW72" smd circle
			(at 21.961094 0.290068 270)
			(size 0.4318 0.4318)
			(layers "F.Cu" "F.Mask" "F.Paste")
			(net "PVCCIN_CPU1")
		)
		(pad "BW74" smd circle
			(at 23.58898 0.290068 270)
			(size 0.4318 0.4318)
			(layers "F.Cu" "F.Mask" "F.Paste")
			(net "PVCCIN_CPU1")
		)
		(pad "BW76" smd circle
			(at 25.216612 0.290068 270)
			(size 0.4318 0.4318)
			(layers "F.Cu" "F.Mask" "F.Paste")
			(net "PVCCIN_CPU1")
		)
		(pad "BW78" smd circle
			(at 26.844498 0.290068 270)
			(size 0.4318 0.4318)
			(layers "F.Cu" "F.Mask" "F.Paste")
			(net "PVCCIN_CPU1")
		)
		(pad "BW80" smd circle
			(at 28.472384 0.290068 270)
			(size 0.4318 0.4318)
			(layers "F.Cu" "F.Mask" "F.Paste")
			(net "PVCCIN_CPU1")
		)
		(pad "BW82" smd circle
			(at 30.100016 0.290068 270)
			(size 0.4318 0.4318)
			(layers "F.Cu" "F.Mask" "F.Paste")
			(net "PVCCIN_CPU1")
		)
		(pad "BW84" smd circle
			(at 31.727902 0.290068 270)
			(size 0.4318 0.4318)
			(layers "F.Cu" "F.Mask" "F.Paste")
			(net "PVCCIN_CPU1")
		)
		(pad "BW86" smd circle
			(at 33.355534 0.290068 270)
			(size 0.4318 0.4318)
			(layers "F.Cu" "F.Mask" "F.Paste")
			(net "PVCCIN_CPU1")
		)
		(pad "BW88" smd circle
			(at 34.98342 0.290068 270)
			(size 0.4318 0.4318)
			(layers "F.Cu" "F.Mask" "F.Paste")
			(net "PVCCIN_CPU1")
		)
		(pad "BW90" smd oval
			(at 36.611306 0.290068)
			(size 0.381 0.4826)
			(drill
				(offset 0 -0.0508)
			)
			(layers "F.Cu" "F.Mask" "F.Paste")
			(net "PVCCIN_CPU1")
		)
		(pad "BY2" smd oval
			(at -36.611306 0.649732 180)
			(size 0.381 0.4826)
			(drill
				(offset 0 -0.0508)
			)
			(layers "F.Cu" "F.Mask" "F.Paste")
			(net "UPI_CPU0_CPU1_P0P1_DP<23>")
		)
		(pad "BY4" smd circle
			(at -34.98342 0.649732 270)
			(size 0.4318 0.4318)
			(layers "F.Cu" "F.Mask" "F.Paste")
			(net "GND")
		)
		(pad "BY6" smd circle
			(at -33.355534 0.649732 270)
			(size 0.4318 0.4318)
			(layers "F.Cu" "F.Mask" "F.Paste")
			(net "UPI_CPU1_CPU0_P1P0_DN<23>")
		)
		(pad "BY8" smd circle
			(at -31.727902 0.649732 270)
			(size 0.4318 0.4318)
			(layers "F.Cu" "F.Mask" "F.Paste")
			(net "GND")
		)
		(pad "BY10" smd circle
			(at -30.100016 0.649732 270)
			(size 0.4318 0.4318)
			(layers "F.Cu" "F.Mask" "F.Paste")
			(net "P5E_CPU1_PE1_RX_DP<7>")
		)
		(pad "BY12" smd circle
			(at -28.472384 0.649732 270)
			(size 0.4318 0.4318)
			(layers "F.Cu" "F.Mask" "F.Paste")
			(net "GND")
		)
		(pad "BY14" smd circle
			(at -26.844498 0.649732 270)
			(size 0.4318 0.4318)
			(layers "F.Cu" "F.Mask" "F.Paste")
			(net "P5E_CPU1_PE1_TX_DP<7>")
		)
		(pad "BY16" smd circle
			(at -25.216612 0.649732 270)
			(size 0.4318 0.4318)
			(layers "F.Cu" "F.Mask" "F.Paste")
			(net "GND")
		)
		(pad "BY18" smd circle
			(at -23.58898 0.649732 270)
			(size 0.4318 0.4318)
			(layers "F.Cu" "F.Mask" "F.Paste")
			(net "TP_DMI_CPU1_PCH_TX_DP<1>")
		)
		(pad "BY20" smd circle
			(at -21.961094 0.649732 270)
			(size 0.4318 0.4318)
			(layers "F.Cu" "F.Mask" "F.Paste")
			(net "GND")
		)
		(pad "BY22" smd circle
			(at -20.333462 0.649732 270)
			(size 0.4318 0.4318)
			(layers "F.Cu" "F.Mask" "F.Paste")
			(net "I3C_SPD_DDRABCD_CPU1_SDA")
		)
		(pad "BY24" smd circle
			(at -18.705576 0.649732 270)
			(size 0.4318 0.4318)
			(layers "F.Cu" "F.Mask" "F.Paste")
			(net "PD_EXT_CLK_SEL_CPU1")
		)
		(pad "BY26" smd circle
			(at -17.07769 0.649732 270)
			(size 0.4318 0.4318)
			(layers "F.Cu" "F.Mask" "F.Paste")
			(net "SMB_PEHPCPU1_GTL_SDA")
		)
		(pad "BY28" smd circle
			(at -15.450058 0.649732 270)
			(size 0.4318 0.4318)
			(layers "F.Cu" "F.Mask" "F.Paste")
			(net "TP_TRC_CPU1_PTI1_CLK")
		)
		(pad "BY30" smd circle
			(at -13.822426 0.649732 270)
			(size 0.4318 0.4318)
			(layers "F.Cu" "F.Mask" "F.Paste")
			(net "TP_TRC_CPU1_PTI<3>")
		)
		(pad "BY32" smd circle
			(at -12.19454 0.649732 270)
			(size 0.4318 0.4318)
			(layers "F.Cu" "F.Mask" "F.Paste")
			(net "PVCCIN_CPU1")
		)
		(pad "BY34" smd circle
			(at -10.566654 0.649732 270)
			(size 0.4318 0.4318)
			(layers "F.Cu" "F.Mask" "F.Paste")
			(net "PVCCIN_CPU1")
		)
		(pad "BY36" smd circle
			(at -8.939022 0.649732 270)
			(size 0.4318 0.4318)
			(layers "F.Cu" "F.Mask" "F.Paste")
			(net "PVCCIN_CPU1")
		)
		(pad "BY38" smd circle
			(at -7.311136 0.649732 270)
			(size 0.4318 0.4318)
			(layers "F.Cu" "F.Mask" "F.Paste")
			(net "PVCCIN_CPU1")
		)
		(pad "BY40" smd circle
			(at -5.68325 0.649732 270)
			(size 0.4318 0.4318)
			(layers "F.Cu" "F.Mask" "F.Paste")
			(net "PVCCIN_CPU1")
		)
		(pad "BY42" smd circle
			(at -4.055618 0.649732 270)
			(size 0.4318 0.4318)
			(layers "F.Cu" "F.Mask" "F.Paste")
			(net "PVCCIN_CPU1")
		)
		(pad "BY44" smd circle
			(at -2.427732 0.649732 270)
			(size 0.4318 0.4318)
			(layers "F.Cu" "F.Mask" "F.Paste")
			(net "PVCCIN_CPU1")
		)
		(pad "BY47" smd circle
			(at 1.613916 0.759714 270)
			(size 0.4318 0.4318)
			(layers "F.Cu" "F.Mask" "F.Paste")
			(net "PVCCIN_CPU1")
		)
		(pad "BY49" smd circle
			(at 3.241802 0.759714 270)
			(size 0.4318 0.4318)
			(layers "F.Cu" "F.Mask" "F.Paste")
			(net "PVCCIN_CPU1")
		)
		(pad "BY51" smd circle
			(at 4.869434 0.759714 270)
			(size 0.4318 0.4318)
			(layers "F.Cu" "F.Mask" "F.Paste")
			(net "PVCCIN_CPU1")
		)
		(pad "BY53" smd circle
			(at 6.49732 0.759714 270)
			(size 0.4318 0.4318)
			(layers "F.Cu" "F.Mask" "F.Paste")
			(net "PVCCIN_CPU1")
		)
		(pad "BY55" smd circle
			(at 8.124952 0.759714 270)
			(size 0.4318 0.4318)
			(layers "F.Cu" "F.Mask" "F.Paste")
			(net "PVCCIN_CPU1")
		)
		(pad "BY57" smd circle
			(at 9.752838 0.759714 270)
			(size 0.4318 0.4318)
			(layers "F.Cu" "F.Mask" "F.Paste")
			(net "PVCCIN_CPU1")
		)
		(pad "BY59" smd circle
			(at 11.380724 0.759714 270)
			(size 0.4318 0.4318)
			(layers "F.Cu" "F.Mask" "F.Paste")
			(net "PVCCIN_CPU1")
		)
		(pad "BY61" smd circle
			(at 13.008356 0.759714 270)
			(size 0.4318 0.4318)
			(layers "F.Cu" "F.Mask" "F.Paste")
			(net "PVCCIN_CPU1")
		)
		(pad "BY63" smd circle
			(at 14.635988 0.759714 270)
			(size 0.4318 0.4318)
			(layers "F.Cu" "F.Mask" "F.Paste")
			(net "PVCCIN_CPU1")
		)
		(pad "BY65" smd circle
			(at 16.263874 0.759714 270)
			(size 0.4318 0.4318)
			(layers "F.Cu" "F.Mask" "F.Paste")
			(net "PVCCIN_CPU1")
		)
		(pad "BY67" smd circle
			(at 17.89176 0.759714 270)
			(size 0.4318 0.4318)
			(layers "F.Cu" "F.Mask" "F.Paste")
			(net "PVCCIN_CPU1")
		)
		(pad "BY69" smd circle
			(at 19.519392 0.759714 270)
			(size 0.4318 0.4318)
			(layers "F.Cu" "F.Mask" "F.Paste")
			(net "PVCCIN_CPU1")
		)
		(pad "BY71" smd circle
			(at 21.147278 0.759714 270)
			(size 0.4318 0.4318)
			(layers "F.Cu" "F.Mask" "F.Paste")
			(net "PVCCIN_CPU1")
		)
		(pad "BY73" smd circle
			(at 22.77491 0.759714 270)
			(size 0.4318 0.4318)
			(layers "F.Cu" "F.Mask" "F.Paste")
			(net "PVCCIN_CPU1")
		)
		(pad "BY75" smd circle
			(at 24.402796 0.759714 270)
			(size 0.4318 0.4318)
			(layers "F.Cu" "F.Mask" "F.Paste")
			(net "PVCCIN_CPU1")
		)
		(pad "BY77" smd circle
			(at 26.030682 0.759714 270)
			(size 0.4318 0.4318)
			(layers "F.Cu" "F.Mask" "F.Paste")
			(net "PVCCIN_CPU1")
		)
		(pad "BY79" smd circle
			(at 27.658314 0.759714 270)
			(size 0.4318 0.4318)
			(layers "F.Cu" "F.Mask" "F.Paste")
			(net "PVCCIN_CPU1")
		)
		(pad "BY81" smd circle
			(at 29.2862 0.759714 270)
			(size 0.4318 0.4318)
			(layers "F.Cu" "F.Mask" "F.Paste")
			(net "PVCCIN_CPU1")
		)
		(pad "BY83" smd circle
			(at 30.914086 0.759714 270)
			(size 0.4318 0.4318)
			(layers "F.Cu" "F.Mask" "F.Paste")
			(net "PVCCIN_CPU1")
		)
		(pad "BY85" smd circle
			(at 32.541718 0.759714 270)
			(size 0.4318 0.4318)
			(layers "F.Cu" "F.Mask" "F.Paste")
			(net "PVCCIN_CPU1")
		)
		(pad "BY87" smd circle
			(at 34.169604 0.759714 270)
			(size 0.4318 0.4318)
			(layers "F.Cu" "F.Mask" "F.Paste")
			(net "PVCCIN_CPU1")
		)
		(pad "BY89" smd circle
			(at 35.797236 0.759714 270)
			(size 0.4318 0.4318)
			(layers "F.Cu" "F.Mask" "F.Paste")
			(net "PVCCIN_CPU1")
		)
		(pad "C5" smd oval
			(at -34.169604 -26.134314 135)
			(size 0.381 0.4826)
			(drill
				(offset 0 -0.0508)
			)
			(layers "F.Cu" "F.Mask" "F.Paste")
			(net "GND")
		)
		(pad "C7" smd oval
			(at -32.541718 -26.134314 135)
			(size 0.381 0.4826)
			(drill
				(offset 0 -0.0508)
			)
			(layers "F.Cu" "F.Mask" "F.Paste")
			(net "M_A_CPU1_SB_DQ<29>")
		)
		(pad "C9" smd oval
			(at -30.914086 -26.134314 90)
			(size 0.381 0.4826)
			(drill
				(offset 0 -0.0508)
			)
			(layers "F.Cu" "F.Mask" "F.Paste")
			(net "M_A_CPU1_SB_DQS_DP<3>")
		)
		(pad "C11" smd circle
			(at -29.2862 -26.134314 270)
			(size 0.4318 0.4318)
			(layers "F.Cu" "F.Mask" "F.Paste")
			(net "M_A_CPU1_SB_DQ<24>")
		)
		(pad "C13" smd circle
			(at -27.658314 -26.134314 270)
			(size 0.4318 0.4318)
			(layers "F.Cu" "F.Mask" "F.Paste")
			(net "M_B_CPU1_SB_DQ<28>")
		)
		(pad "C15" smd circle
			(at -26.030682 -26.134314 270)
			(size 0.4318 0.4318)
			(layers "F.Cu" "F.Mask" "F.Paste")
			(net "M_B_CPU1_SB_DQS_DP<3>")
		)
		(pad "C17" smd circle
			(at -24.402796 -26.134314 270)
			(size 0.4318 0.4318)
			(layers "F.Cu" "F.Mask" "F.Paste")
			(net "M_B_CPU1_SB_DQ<24>")
		)
		(pad "C19" smd circle
			(at -22.77491 -26.134314 270)
			(size 0.4318 0.4318)
			(layers "F.Cu" "F.Mask" "F.Paste")
			(net "M_A_CPU1_SB_DQ<21>")
		)
		(pad "C21" smd circle
			(at -21.147278 -26.134314 270)
			(size 0.4318 0.4318)
			(layers "F.Cu" "F.Mask" "F.Paste")
			(net "M_A_CPU1_SB_DQS_DP<2>")
		)
		(pad "C23" smd circle
			(at -19.519392 -26.134314 270)
			(size 0.4318 0.4318)
			(layers "F.Cu" "F.Mask" "F.Paste")
			(net "M_A_CPU1_SB_DQ<16>")
		)
		(pad "C25" smd circle
			(at -17.89176 -26.134314 270)
			(size 0.4318 0.4318)
			(layers "F.Cu" "F.Mask" "F.Paste")
			(net "M_A_CPU1_SB_DQ<13>")
		)
		(pad "C27" smd circle
			(at -16.263874 -26.134314 270)
			(size 0.4318 0.4318)
			(layers "F.Cu" "F.Mask" "F.Paste")
			(net "M_A_CPU1_SB_DQS_DP<1>")
		)
		(pad "C29" smd circle
			(at -14.635988 -26.134314 270)
			(size 0.4318 0.4318)
			(layers "F.Cu" "F.Mask" "F.Paste")
			(net "M_A_CPU1_SB_DQ<8>")
		)
		(pad "C31" smd circle
			(at -13.008356 -26.134314 270)
			(size 0.4318 0.4318)
			(layers "F.Cu" "F.Mask" "F.Paste")
			(net "M_A_CPU1_SB_CB<1>")
		)
		(pad "C33" smd circle
			(at -11.380724 -26.134314 270)
			(size 0.4318 0.4318)
			(layers "F.Cu" "F.Mask" "F.Paste")
			(net "M_A_CPU1_SB_DQS_DP<9>")
		)
		(pad "C35" smd circle
			(at -9.752838 -26.134314 270)
			(size 0.4318 0.4318)
			(layers "F.Cu" "F.Mask" "F.Paste")
			(net "M_A_CPU1_SB_CB<4>")
		)
		(pad "C37" smd circle
			(at -8.124952 -26.134314 270)
			(size 0.4318 0.4318)
			(layers "F.Cu" "F.Mask" "F.Paste")
			(net "M_A_CPU1_SB_CS_N<1>")
		)
		(pad "C39" smd circle
			(at -6.49732 -26.134314 270)
			(size 0.4318 0.4318)
			(layers "F.Cu" "F.Mask" "F.Paste")
			(net "GND")
		)
		(pad "C41" smd circle
			(at -4.869434 -26.134314 270)
			(size 0.4318 0.4318)
			(layers "F.Cu" "F.Mask" "F.Paste")
			(net "M_A_CPU1_SB_CA<2>")
		)
		(pad "C43" smd circle
			(at -3.241802 -26.134314 270)
			(size 0.4318 0.4318)
			(layers "F.Cu" "F.Mask" "F.Paste")
			(net "M_A_CPU1_CLK_DP<0>")
		)
		(pad "C45" smd oval
			(at -1.613916 -26.134314 45)
			(size 0.381 0.4826)
			(drill
				(offset 0 -0.0508)
			)
			(layers "F.Cu" "F.Mask" "F.Paste")
			(net "GND")
		)
		(pad "C48" smd oval
			(at 2.427732 -26.024586 135)
			(size 0.381 0.4826)
			(drill
				(offset 0 -0.0508)
			)
			(layers "F.Cu" "F.Mask" "F.Paste")
			(net "M_A_CPU1_SA_CA<6>")
		)
		(pad "C50" smd circle
			(at 4.055618 -26.024586 270)
			(size 0.4318 0.4318)
			(layers "F.Cu" "F.Mask" "F.Paste")
			(net "M_A_CPU1_SA_CA<4>")
		)
		(pad "C52" smd circle
			(at 5.68325 -26.024586 270)
			(size 0.4318 0.4318)
			(layers "F.Cu" "F.Mask" "F.Paste")
			(net "GND")
		)
		(pad "C54" smd circle
			(at 7.311136 -26.024586 270)
			(size 0.4318 0.4318)
			(layers "F.Cu" "F.Mask" "F.Paste")
			(net "M_A_CPU1_SA_CS_N<0>")
		)
		(pad "C56" smd circle
			(at 8.939022 -26.024586 270)
			(size 0.4318 0.4318)
			(layers "F.Cu" "F.Mask" "F.Paste")
			(net "M_A_CPU1_SA_CB<5>")
		)
		(pad "C58" smd circle
			(at 10.566654 -26.024586 270)
			(size 0.4318 0.4318)
			(layers "F.Cu" "F.Mask" "F.Paste")
			(net "M_A_CPU1_SA_DQS_DP<4>")
		)
		(pad "C60" smd circle
			(at 12.19454 -26.024586 270)
			(size 0.4318 0.4318)
			(layers "F.Cu" "F.Mask" "F.Paste")
			(net "M_A_CPU1_SA_CB<0>")
		)
		(pad "C62" smd circle
			(at 13.822426 -26.024586 270)
			(size 0.4318 0.4318)
			(layers "F.Cu" "F.Mask" "F.Paste")
			(net "M_A_CPU1_SA_DQ<29>")
		)
		(pad "C64" smd circle
			(at 15.450058 -26.024586 270)
			(size 0.4318 0.4318)
			(layers "F.Cu" "F.Mask" "F.Paste")
			(net "M_A_CPU1_SA_DQS_DP<3>")
		)
		(pad "C66" smd circle
			(at 17.07769 -26.024586 270)
			(size 0.4318 0.4318)
			(layers "F.Cu" "F.Mask" "F.Paste")
			(net "M_A_CPU1_SA_DQ<24>")
		)
		(pad "C68" smd circle
			(at 18.705576 -26.024586 270)
			(size 0.4318 0.4318)
			(layers "F.Cu" "F.Mask" "F.Paste")
			(net "M_A_CPU1_SA_DQ<21>")
		)
		(pad "C70" smd circle
			(at 20.333462 -26.024586 270)
			(size 0.4318 0.4318)
			(layers "F.Cu" "F.Mask" "F.Paste")
			(net "M_A_CPU1_SA_DQS_DP<2>")
		)
		(pad "C72" smd circle
			(at 21.961094 -26.024586 270)
			(size 0.4318 0.4318)
			(layers "F.Cu" "F.Mask" "F.Paste")
			(net "GND")
		)
		(pad "C74" smd circle
			(at 23.58898 -26.024586 270)
			(size 0.4318 0.4318)
			(layers "F.Cu" "F.Mask" "F.Paste")
			(net "GND")
		)
		(pad "C76" smd circle
			(at 25.216612 -26.024586 270)
			(size 0.4318 0.4318)
			(layers "F.Cu" "F.Mask" "F.Paste")
			(net "M_A_CPU1_SA_DQ<4>")
		)
		(pad "C78" smd circle
			(at 26.844498 -26.024586 270)
			(size 0.4318 0.4318)
			(layers "F.Cu" "F.Mask" "F.Paste")
			(net "GND")
		)
		(pad "C80" smd circle
			(at 28.472384 -26.024586 270)
			(size 0.4318 0.4318)
			(layers "F.Cu" "F.Mask" "F.Paste")
			(net "GND")
		)
		(pad "C82" smd circle
			(at 30.100016 -26.024586 270)
			(size 0.4318 0.4318)
			(layers "F.Cu" "F.Mask" "F.Paste")
			(net "GND")
		)
		(pad "C84" smd oval
			(at 31.727902 -26.024586 45)
			(size 0.381 0.4826)
			(drill
				(offset 0 -0.0508)
			)
			(layers "F.Cu" "F.Mask" "F.Paste")
			(net "PVCCFA_EHV_FIVRA_CPU1")
		)
		(pad "C86" smd oval
			(at 33.355534 -26.024586 45)
			(size 0.381 0.4826)
			(drill
				(offset 0 -0.0508)
			)
			(layers "F.Cu" "F.Mask" "F.Paste")
			(net "GND")
		)
		(pad "C88" smd oval
			(at 34.98342 -26.024586 45)
			(size 0.381 0.4826)
			(drill
				(offset 0 -0.0508)
			)
			(layers "F.Cu" "F.Mask" "F.Paste")
			(net "PVCCFA_EHV_FIVRA_CPU1")
		)
		(pad "CA3" smd circle
			(at -35.797236 1.119886 270)
			(size 0.4318 0.4318)
			(layers "F.Cu" "F.Mask" "F.Paste")
			(net "GND")
		)
		(pad "CA5" smd circle
			(at -34.169604 1.119886 270)
			(size 0.4318 0.4318)
			(layers "F.Cu" "F.Mask" "F.Paste")
			(net "UPI_CPU1_CPU0_P1P0_DN<22>")
		)
		(pad "CA7" smd circle
			(at -32.541718 1.119886 270)
			(size 0.4318 0.4318)
			(layers "F.Cu" "F.Mask" "F.Paste")
			(net "PVCCD_HV_CPU1")
		)
		(pad "CA9" smd circle
			(at -30.914086 1.119886 270)
			(size 0.4318 0.4318)
			(layers "F.Cu" "F.Mask" "F.Paste")
			(net "P5E_CPU1_PE1_RX_DP<6>")
		)
		(pad "CA11" smd circle
			(at -29.2862 1.119886 270)
			(size 0.4318 0.4318)
			(layers "F.Cu" "F.Mask" "F.Paste")
			(net "VSENSE_PVCCINFAON_CPU1_DP")
		)
		(pad "CA13" smd circle
			(at -27.658314 1.119886 270)
			(size 0.4318 0.4318)
			(layers "F.Cu" "F.Mask" "F.Paste")
			(net "P5E_CPU1_PE1_TX_DN<7>")
		)
		(pad "CA15" smd circle
			(at -26.030682 1.119886 270)
			(size 0.4318 0.4318)
			(layers "F.Cu" "F.Mask" "F.Paste")
			(net "PVCCINFAON_CPU1")
		)
		(pad "CA17" smd circle
			(at -24.402796 1.119886 270)
			(size 0.4318 0.4318)
			(layers "F.Cu" "F.Mask" "F.Paste")
			(net "TP_DMI_CPU1_PCH_TX_DN<1>")
		)
		(pad "CA19" smd circle
			(at -22.77491 1.119886 270)
			(size 0.4318 0.4318)
			(layers "F.Cu" "F.Mask" "F.Paste")
			(net "TP_DMI_CPU1_PCH_TX_DP<0>")
		)
		(pad "CA21" smd circle
			(at -21.147278 1.119886 270)
			(size 0.4318 0.4318)
			(layers "F.Cu" "F.Mask" "F.Paste")
			(net "NC_CPU1_DMI_APROBE<0>")
		)
		(pad "CA23" smd circle
			(at -19.519392 1.119886 270)
			(size 0.4318 0.4318)
			(layers "F.Cu" "F.Mask" "F.Paste")
			(net "NC_CPU1_UPI1_APROBE<1>")
		)
		(pad "CA25" smd circle
			(at -17.89176 1.119886 270)
			(size 0.4318 0.4318)
			(layers "F.Cu" "F.Mask" "F.Paste")
			(net "SMB_PEHPCPU1_GTL_SCL")
		)
		(pad "CA27" smd circle
			(at -16.263874 1.119886 270)
			(size 0.4318 0.4318)
			(layers "F.Cu" "F.Mask" "F.Paste")
			(net "TP_TRC_CPU1_PTI<6>")
		)
		(pad "CA29" smd circle
			(at -14.635988 1.119886 270)
			(size 0.4318 0.4318)
			(layers "F.Cu" "F.Mask" "F.Paste")
			(net "TP_TRC_CPU1_PTI<4>")
		)
		(pad "CA31" smd circle
			(at -13.008356 1.119886 270)
			(size 0.4318 0.4318)
			(layers "F.Cu" "F.Mask" "F.Paste")
			(net "GND")
		)
		(pad "CA33" smd circle
			(at -11.380724 1.119886 270)
			(size 0.4318 0.4318)
			(layers "F.Cu" "F.Mask" "F.Paste")
			(net "PVCCIN_CPU1")
		)
		(pad "CA35" smd circle
			(at -9.752838 1.119886 270)
			(size 0.4318 0.4318)
			(layers "F.Cu" "F.Mask" "F.Paste")
			(net "PVCCIN_CPU1")
		)
		(pad "CA37" smd circle
			(at -8.124952 1.119886 270)
			(size 0.4318 0.4318)
			(layers "F.Cu" "F.Mask" "F.Paste")
			(net "PVCCIN_CPU1")
		)
		(pad "CA39" smd circle
			(at -6.49732 1.119886 270)
			(size 0.4318 0.4318)
			(layers "F.Cu" "F.Mask" "F.Paste")
			(net "PVCCIN_CPU1")
		)
		(pad "CA41" smd circle
			(at -4.869434 1.119886 270)
			(size 0.4318 0.4318)
			(layers "F.Cu" "F.Mask" "F.Paste")
			(net "PVCCIN_CPU1")
		)
		(pad "CA43" smd circle
			(at -3.241802 1.119886 270)
			(size 0.4318 0.4318)
			(layers "F.Cu" "F.Mask" "F.Paste")
			(net "PVCCIN_CPU1")
		)
		(pad "CA45" smd circle
			(at -1.613916 1.119886 270)
			(size 0.4318 0.4318)
			(layers "F.Cu" "F.Mask" "F.Paste")
			(net "PVCCIN_CPU1")
		)
		(pad "CA48" smd circle
			(at 2.427732 1.229614 270)
			(size 0.4318 0.4318)
			(layers "F.Cu" "F.Mask" "F.Paste")
			(net "PVCCIN_CPU1")
		)
		(pad "CA50" smd circle
			(at 4.055618 1.229614 270)
			(size 0.4318 0.4318)
			(layers "F.Cu" "F.Mask" "F.Paste")
			(net "PVCCIN_CPU1")
		)
		(pad "CA52" smd circle
			(at 5.68325 1.229614 270)
			(size 0.4318 0.4318)
			(layers "F.Cu" "F.Mask" "F.Paste")
			(net "PVCCIN_CPU1")
		)
		(pad "CA54" smd circle
			(at 7.311136 1.229614 270)
			(size 0.4318 0.4318)
			(layers "F.Cu" "F.Mask" "F.Paste")
			(net "PVCCIN_CPU1")
		)
		(pad "CA56" smd circle
			(at 8.939022 1.229614 270)
			(size 0.4318 0.4318)
			(layers "F.Cu" "F.Mask" "F.Paste")
			(net "PVCCIN_CPU1")
		)
		(pad "CA58" smd circle
			(at 10.566654 1.229614 270)
			(size 0.4318 0.4318)
			(layers "F.Cu" "F.Mask" "F.Paste")
			(net "PVCCIN_CPU1")
		)
		(pad "CA60" smd circle
			(at 12.19454 1.229614 270)
			(size 0.4318 0.4318)
			(layers "F.Cu" "F.Mask" "F.Paste")
			(net "PVCCIN_CPU1")
		)
		(pad "CA62" smd circle
			(at 13.822426 1.229614 270)
			(size 0.4318 0.4318)
			(layers "F.Cu" "F.Mask" "F.Paste")
			(net "PVCCIN_CPU1")
		)
		(pad "CA64" smd circle
			(at 15.450058 1.229614 270)
			(size 0.4318 0.4318)
			(layers "F.Cu" "F.Mask" "F.Paste")
			(net "PVCCIN_CPU1")
		)
		(pad "CA66" smd circle
			(at 17.07769 1.229614 270)
			(size 0.4318 0.4318)
			(layers "F.Cu" "F.Mask" "F.Paste")
			(net "PVCCIN_CPU1")
		)
		(pad "CA68" smd circle
			(at 18.705576 1.229614 270)
			(size 0.4318 0.4318)
			(layers "F.Cu" "F.Mask" "F.Paste")
			(net "PVCCIN_CPU1")
		)
		(pad "CA70" smd circle
			(at 20.333462 1.229614 270)
			(size 0.4318 0.4318)
			(layers "F.Cu" "F.Mask" "F.Paste")
			(net "PVCCIN_CPU1")
		)
		(pad "CA72" smd circle
			(at 21.961094 1.229614 270)
			(size 0.4318 0.4318)
			(layers "F.Cu" "F.Mask" "F.Paste")
			(net "PVCCIN_CPU1")
		)
		(pad "CA74" smd circle
			(at 23.58898 1.229614 270)
			(size 0.4318 0.4318)
			(layers "F.Cu" "F.Mask" "F.Paste")
			(net "PVCCIN_CPU1")
		)
		(pad "CA76" smd circle
			(at 25.216612 1.229614 270)
			(size 0.4318 0.4318)
			(layers "F.Cu" "F.Mask" "F.Paste")
			(net "PVCCIN_CPU1")
		)
		(pad "CA78" smd circle
			(at 26.844498 1.229614 270)
			(size 0.4318 0.4318)
			(layers "F.Cu" "F.Mask" "F.Paste")
			(net "PVCCIN_CPU1")
		)
		(pad "CA80" smd circle
			(at 28.472384 1.229614 270)
			(size 0.4318 0.4318)
			(layers "F.Cu" "F.Mask" "F.Paste")
			(net "PVCCIN_CPU1")
		)
		(pad "CA82" smd circle
			(at 30.100016 1.229614 270)
			(size 0.4318 0.4318)
			(layers "F.Cu" "F.Mask" "F.Paste")
			(net "PVCCIN_CPU1")
		)
		(pad "CA84" smd circle
			(at 31.727902 1.229614 270)
			(size 0.4318 0.4318)
			(layers "F.Cu" "F.Mask" "F.Paste")
			(net "PVCCIN_CPU1")
		)
		(pad "CA86" smd circle
			(at 33.355534 1.229614 270)
			(size 0.4318 0.4318)
			(layers "F.Cu" "F.Mask" "F.Paste")
			(net "PVCCIN_CPU1")
		)
		(pad "CA88" smd circle
			(at 34.98342 1.229614 270)
			(size 0.4318 0.4318)
			(layers "F.Cu" "F.Mask" "F.Paste")
			(net "PVCCIN_CPU1")
		)
		(pad "CA90" smd oval
			(at 36.611306 1.229614)
			(size 0.381 0.4826)
			(drill
				(offset 0 -0.0508)
			)
			(layers "F.Cu" "F.Mask" "F.Paste")
			(net "PVCCIN_CPU1")
		)
		(pad "CB2" smd oval
			(at -36.611306 1.589532 180)
			(size 0.381 0.4826)
			(drill
				(offset 0 -0.0508)
			)
			(layers "F.Cu" "F.Mask" "F.Paste")
			(net "UPI_CPU0_CPU1_P0P1_DN<23>")
		)
		(pad "CB4" smd circle
			(at -34.98342 1.589532 270)
			(size 0.4318 0.4318)
			(layers "F.Cu" "F.Mask" "F.Paste")
			(net "GND")
		)
		(pad "CB6" smd circle
			(at -33.355534 1.589532 270)
			(size 0.4318 0.4318)
			(layers "F.Cu" "F.Mask" "F.Paste")
			(net "UPI_CPU1_CPU0_P1P0_DP<22>")
		)
		(pad "CB8" smd circle
			(at -31.727902 1.589532 270)
			(size 0.4318 0.4318)
			(layers "F.Cu" "F.Mask" "F.Paste")
			(net "GND")
		)
		(pad "CB10" smd circle
			(at -30.100016 1.589532 270)
			(size 0.4318 0.4318)
			(layers "F.Cu" "F.Mask" "F.Paste")
			(net "P5E_CPU1_PE1_RX_DN<6>")
		)
		(pad "CB12" smd circle
			(at -28.472384 1.589532 270)
			(size 0.4318 0.4318)
			(layers "F.Cu" "F.Mask" "F.Paste")
			(net "GND")
		)
		(pad "CB14" smd circle
			(at -26.844498 1.589532 270)
			(size 0.4318 0.4318)
			(layers "F.Cu" "F.Mask" "F.Paste")
			(net "P5E_CPU1_PE1_TX_DN<6>")
		)
		(pad "CB16" smd circle
			(at -25.216612 1.589532 270)
			(size 0.4318 0.4318)
			(layers "F.Cu" "F.Mask" "F.Paste")
			(net "GND")
		)
		(pad "CB18" smd circle
			(at -23.58898 1.589532 270)
			(size 0.4318 0.4318)
			(layers "F.Cu" "F.Mask" "F.Paste")
			(net "TP_DMI_CPU1_PCH_TX_DN<2>")
		)
		(pad "CB20" smd circle
			(at -21.961094 1.589532 270)
			(size 0.4318 0.4318)
			(layers "F.Cu" "F.Mask" "F.Paste")
			(net "GND")
		)
		(pad "CB22" smd circle
			(at -20.333462 1.589532 270)
			(size 0.4318 0.4318)
			(layers "F.Cu" "F.Mask" "F.Paste")
			(net "GND")
		)
		(pad "CB24" smd circle
			(at -18.705576 1.589532 270)
			(size 0.4318 0.4318)
			(layers "F.Cu" "F.Mask" "F.Paste")
			(net "GND")
		)
		(pad "CB26" smd circle
			(at -17.07769 1.589532 270)
			(size 0.4318 0.4318)
			(layers "F.Cu" "F.Mask" "F.Paste")
			(net "GND")
		)
		(pad "CB28" smd circle
			(at -15.450058 1.589532 270)
			(size 0.4318 0.4318)
			(layers "F.Cu" "F.Mask" "F.Paste")
			(net "GND")
		)
		(pad "CB30" smd circle
			(at -13.822426 1.589532 270)
			(size 0.4318 0.4318)
			(layers "F.Cu" "F.Mask" "F.Paste")
			(net "TP_TRC_CPU1_PTI0_CLK")
		)
		(pad "CB32" smd circle
			(at -12.19454 1.589532 270)
			(size 0.4318 0.4318)
			(layers "F.Cu" "F.Mask" "F.Paste")
			(net "GND")
		)
		(pad "CB34" smd circle
			(at -10.566654 1.589532 270)
			(size 0.4318 0.4318)
			(layers "F.Cu" "F.Mask" "F.Paste")
			(net "GND")
		)
		(pad "CB36" smd circle
			(at -8.939022 1.589532 270)
			(size 0.4318 0.4318)
			(layers "F.Cu" "F.Mask" "F.Paste")
			(net "GND")
		)
		(pad "CB38" smd circle
			(at -7.311136 1.589532 270)
			(size 0.4318 0.4318)
			(layers "F.Cu" "F.Mask" "F.Paste")
			(net "GND")
		)
		(pad "CB40" smd circle
			(at -5.68325 1.589532 270)
			(size 0.4318 0.4318)
			(layers "F.Cu" "F.Mask" "F.Paste")
			(net "GND")
		)
		(pad "CB42" smd circle
			(at -4.055618 1.589532 270)
			(size 0.4318 0.4318)
			(layers "F.Cu" "F.Mask" "F.Paste")
			(net "GND")
		)
		(pad "CB44" smd circle
			(at -2.427732 1.589532 270)
			(size 0.4318 0.4318)
			(layers "F.Cu" "F.Mask" "F.Paste")
			(net "GND")
		)
		(pad "CB47" smd circle
			(at 1.613916 1.699514 270)
			(size 0.4318 0.4318)
			(layers "F.Cu" "F.Mask" "F.Paste")
			(net "GND")
		)
		(pad "CB49" smd circle
			(at 3.241802 1.699514 270)
			(size 0.4318 0.4318)
			(layers "F.Cu" "F.Mask" "F.Paste")
			(net "GND")
		)
		(pad "CB51" smd circle
			(at 4.869434 1.699514 270)
			(size 0.4318 0.4318)
			(layers "F.Cu" "F.Mask" "F.Paste")
			(net "GND")
		)
		(pad "CB53" smd circle
			(at 6.49732 1.699514 270)
			(size 0.4318 0.4318)
			(layers "F.Cu" "F.Mask" "F.Paste")
			(net "GND")
		)
		(pad "CB55" smd circle
			(at 8.124952 1.699514 270)
			(size 0.4318 0.4318)
			(layers "F.Cu" "F.Mask" "F.Paste")
			(net "GND")
		)
		(pad "CB57" smd circle
			(at 9.752838 1.699514 270)
			(size 0.4318 0.4318)
			(layers "F.Cu" "F.Mask" "F.Paste")
			(net "GND")
		)
		(pad "CB59" smd circle
			(at 11.380724 1.699514 270)
			(size 0.4318 0.4318)
			(layers "F.Cu" "F.Mask" "F.Paste")
			(net "GND")
		)
		(pad "CB61" smd circle
			(at 13.008356 1.699514 270)
			(size 0.4318 0.4318)
			(layers "F.Cu" "F.Mask" "F.Paste")
			(net "PVCCIN_CPU1")
		)
		(pad "CB63" smd circle
			(at 14.635988 1.699514 270)
			(size 0.4318 0.4318)
			(layers "F.Cu" "F.Mask" "F.Paste")
			(net "GND")
		)
		(pad "CB65" smd circle
			(at 16.263874 1.699514 270)
			(size 0.4318 0.4318)
			(layers "F.Cu" "F.Mask" "F.Paste")
			(net "GND")
		)
		(pad "CB67" smd circle
			(at 17.89176 1.699514 270)
			(size 0.4318 0.4318)
			(layers "F.Cu" "F.Mask" "F.Paste")
			(net "GND")
		)
		(pad "CB69" smd circle
			(at 19.519392 1.699514 270)
			(size 0.4318 0.4318)
			(layers "F.Cu" "F.Mask" "F.Paste")
			(net "GND")
		)
		(pad "CB71" smd circle
			(at 21.147278 1.699514 270)
			(size 0.4318 0.4318)
			(layers "F.Cu" "F.Mask" "F.Paste")
			(net "GND")
		)
		(pad "CB73" smd circle
			(at 22.77491 1.699514 270)
			(size 0.4318 0.4318)
			(layers "F.Cu" "F.Mask" "F.Paste")
			(net "GND")
		)
		(pad "CB75" smd circle
			(at 24.402796 1.699514 270)
			(size 0.4318 0.4318)
			(layers "F.Cu" "F.Mask" "F.Paste")
			(net "PVCCIN_CPU1")
		)
		(pad "CB77" smd circle
			(at 26.030682 1.699514 270)
			(size 0.4318 0.4318)
			(layers "F.Cu" "F.Mask" "F.Paste")
			(net "PVCCIN_CPU1")
		)
		(pad "CB79" smd circle
			(at 27.658314 1.699514 270)
			(size 0.4318 0.4318)
			(layers "F.Cu" "F.Mask" "F.Paste")
			(net "GND")
		)
		(pad "CB81" smd circle
			(at 29.2862 1.699514 270)
			(size 0.4318 0.4318)
			(layers "F.Cu" "F.Mask" "F.Paste")
			(net "GND")
		)
		(pad "CB83" smd circle
			(at 30.914086 1.699514 270)
			(size 0.4318 0.4318)
			(layers "F.Cu" "F.Mask" "F.Paste")
			(net "GND")
		)
		(pad "CB85" smd circle
			(at 32.541718 1.699514 270)
			(size 0.4318 0.4318)
			(layers "F.Cu" "F.Mask" "F.Paste")
			(net "GND")
		)
		(pad "CB87" smd circle
			(at 34.169604 1.699514 270)
			(size 0.4318 0.4318)
			(layers "F.Cu" "F.Mask" "F.Paste")
			(net "GND")
		)
		(pad "CB89" smd circle
			(at 35.797236 1.699514 270)
			(size 0.4318 0.4318)
			(layers "F.Cu" "F.Mask" "F.Paste")
			(net "GND")
		)
		(pad "CC3" smd circle
			(at -35.797236 2.059686 270)
			(size 0.4318 0.4318)
			(layers "F.Cu" "F.Mask" "F.Paste")
			(net "UPI_CPU0_CPU1_P0P1_DP<22>")
		)
		(pad "CC5" smd circle
			(at -34.169604 2.059686 270)
			(size 0.4318 0.4318)
			(layers "F.Cu" "F.Mask" "F.Paste")
			(net "GND")
		)
		(pad "CC7" smd circle
			(at -32.541718 2.059686 270)
			(size 0.4318 0.4318)
			(layers "F.Cu" "F.Mask" "F.Paste")
			(net "UPI_CPU1_CPU0_P1P0_DP<21>")
		)
		(pad "CC9" smd circle
			(at -30.914086 2.059686 270)
			(size 0.4318 0.4318)
			(layers "F.Cu" "F.Mask" "F.Paste")
			(net "GND")
		)
		(pad "CC11" smd circle
			(at -29.2862 2.059686 270)
			(size 0.4318 0.4318)
			(layers "F.Cu" "F.Mask" "F.Paste")
			(net "P5E_CPU1_PE1_RX_DN<5>")
		)
		(pad "CC13" smd circle
			(at -27.658314 2.059686 270)
			(size 0.4318 0.4318)
			(layers "F.Cu" "F.Mask" "F.Paste")
			(net "GND")
		)
		(pad "CC15" smd circle
			(at -26.030682 2.059686 270)
			(size 0.4318 0.4318)
			(layers "F.Cu" "F.Mask" "F.Paste")
			(net "P5E_CPU1_PE1_TX_DP<6>")
		)
		(pad "CC17" smd circle
			(at -24.402796 2.059686 270)
			(size 0.4318 0.4318)
			(layers "F.Cu" "F.Mask" "F.Paste")
			(net "GND")
		)
		(pad "CC19" smd circle
			(at -22.77491 2.059686 270)
			(size 0.4318 0.4318)
			(layers "F.Cu" "F.Mask" "F.Paste")
			(net "TP_DMI_CPU1_PCH_TX_DP<2>")
		)
		(pad "CC21" smd circle
			(at -21.147278 2.059686 270)
			(size 0.4318 0.4318)
			(layers "F.Cu" "F.Mask" "F.Paste")
			(net "NC_CPU1_PE1_APROBE<1>")
		)
		(pad "CC23" smd circle
			(at -19.519392 2.059686 270)
			(size 0.4318 0.4318)
			(layers "F.Cu" "F.Mask" "F.Paste")
			(net "NC_CPU1_PE2_APROBE<0>")
		)
		(pad "CC25" smd circle
			(at -17.89176 2.059686 270)
			(size 0.4318 0.4318)
			(layers "F.Cu" "F.Mask" "F.Paste")
			(net "TP_H_SBLINK7_CPU1_PMDOWN")
		)
		(pad "CC27" smd circle
			(at -16.263874 2.059686 270)
			(size 0.4318 0.4318)
			(layers "F.Cu" "F.Mask" "F.Paste")
			(net "TP_TRC_CPU1_PTI<2>")
		)
		(pad "CC29" smd circle
			(at -14.635988 2.059686 270)
			(size 0.4318 0.4318)
			(layers "F.Cu" "F.Mask" "F.Paste")
			(net "TP_TRC_CPU1_PTI<0>")
		)
		(pad "CC31" smd circle
			(at -13.008356 2.059686 270)
			(size 0.4318 0.4318)
			(layers "F.Cu" "F.Mask" "F.Paste")
			(net "GND")
		)
		(pad "CC33" smd circle
			(at -11.380724 2.059686 270)
			(size 0.4318 0.4318)
			(layers "F.Cu" "F.Mask" "F.Paste")
			(net "PVCCIN_CPU1")
		)
		(pad "CC35" smd circle
			(at -9.752838 2.059686 270)
			(size 0.4318 0.4318)
			(layers "F.Cu" "F.Mask" "F.Paste")
			(net "PVCCIN_CPU1")
		)
		(pad "CC37" smd circle
			(at -8.124952 2.059686 270)
			(size 0.4318 0.4318)
			(layers "F.Cu" "F.Mask" "F.Paste")
			(net "PVCCIN_CPU1")
		)
		(pad "CC39" smd circle
			(at -6.49732 2.059686 270)
			(size 0.4318 0.4318)
			(layers "F.Cu" "F.Mask" "F.Paste")
			(net "PVCCIN_CPU1")
		)
		(pad "CC41" smd circle
			(at -4.869434 2.059686 270)
			(size 0.4318 0.4318)
			(layers "F.Cu" "F.Mask" "F.Paste")
			(net "PVCCIN_CPU1")
		)
		(pad "CC43" smd circle
			(at -3.241802 2.059686 270)
			(size 0.4318 0.4318)
			(layers "F.Cu" "F.Mask" "F.Paste")
			(net "PVCCIN_CPU1")
		)
		(pad "CC45" smd circle
			(at -1.613916 2.059686 270)
			(size 0.4318 0.4318)
			(layers "F.Cu" "F.Mask" "F.Paste")
			(net "PVCCIN_CPU1")
		)
		(pad "CC48" smd circle
			(at 2.427732 2.169668 270)
			(size 0.4318 0.4318)
			(layers "F.Cu" "F.Mask" "F.Paste")
			(net "PVCCIN_CPU1")
		)
		(pad "CC50" smd circle
			(at 4.055618 2.169668 270)
			(size 0.4318 0.4318)
			(layers "F.Cu" "F.Mask" "F.Paste")
			(net "PVCCIN_CPU1")
		)
		(pad "CC52" smd circle
			(at 5.68325 2.169668 270)
			(size 0.4318 0.4318)
			(layers "F.Cu" "F.Mask" "F.Paste")
			(net "PVCCIN_CPU1")
		)
		(pad "CC54" smd circle
			(at 7.311136 2.169668 270)
			(size 0.4318 0.4318)
			(layers "F.Cu" "F.Mask" "F.Paste")
			(net "PVCCIN_CPU1")
		)
		(pad "CC56" smd circle
			(at 8.939022 2.169668 270)
			(size 0.4318 0.4318)
			(layers "F.Cu" "F.Mask" "F.Paste")
			(net "PVCCIN_CPU1")
		)
		(pad "CC58" smd circle
			(at 10.566654 2.169668 270)
			(size 0.4318 0.4318)
			(layers "F.Cu" "F.Mask" "F.Paste")
			(net "PVCCIN_CPU1")
		)
		(pad "CC60" smd circle
			(at 12.19454 2.169668 270)
			(size 0.4318 0.4318)
			(layers "F.Cu" "F.Mask" "F.Paste")
			(net "PVCCIN_CPU1")
		)
		(pad "CC62" smd circle
			(at 13.822426 2.169668 270)
			(size 0.4318 0.4318)
			(layers "F.Cu" "F.Mask" "F.Paste")
			(net "GND")
		)
		(pad "CC64" smd circle
			(at 15.450058 2.169668 270)
			(size 0.4318 0.4318)
			(layers "F.Cu" "F.Mask" "F.Paste")
			(net "NC_CPU1_LGSSPARE4")
		)
		(pad "CC66" smd circle
			(at 17.07769 2.169668 270)
			(size 0.4318 0.4318)
			(layers "F.Cu" "F.Mask" "F.Paste")
			(net "NC_CPU1_MDFI_DIE01_EW1")
		)
		(pad "CC68" smd circle
			(at 18.705576 2.169668 270)
			(size 0.4318 0.4318)
			(layers "F.Cu" "F.Mask" "F.Paste")
			(net "PVPP_HBM_CPU1")
		)
		(pad "CC70" smd circle
			(at 20.333462 2.169668 270)
			(size 0.4318 0.4318)
			(layers "F.Cu" "F.Mask" "F.Paste")
			(net "GND")
		)
		(pad "CC72" smd circle
			(at 21.961094 2.169668 270)
			(size 0.4318 0.4318)
			(layers "F.Cu" "F.Mask" "F.Paste")
			(net "GND")
		)
		(pad "CC74" smd circle
			(at 23.58898 2.169668 270)
			(size 0.4318 0.4318)
			(layers "F.Cu" "F.Mask" "F.Paste")
			(net "GND")
		)
		(pad "CC76" smd circle
			(at 25.216612 2.169668 270)
			(size 0.4318 0.4318)
			(layers "F.Cu" "F.Mask" "F.Paste")
			(net "PVCCIN_CPU1")
		)
		(pad "CC78" smd circle
			(at 26.844498 2.169668 270)
			(size 0.4318 0.4318)
			(layers "F.Cu" "F.Mask" "F.Paste")
			(net "PVCCIN_CPU1")
		)
		(pad "CC80" smd circle
			(at 28.472384 2.169668 270)
			(size 0.4318 0.4318)
			(layers "F.Cu" "F.Mask" "F.Paste")
			(net "PVCCIN_CPU1")
		)
		(pad "CC82" smd circle
			(at 30.100016 2.169668 270)
			(size 0.4318 0.4318)
			(layers "F.Cu" "F.Mask" "F.Paste")
			(net "PVCCIN_CPU1")
		)
		(pad "CC84" smd circle
			(at 31.727902 2.169668 270)
			(size 0.4318 0.4318)
			(layers "F.Cu" "F.Mask" "F.Paste")
			(net "PVCCIN_CPU1")
		)
		(pad "CC86" smd circle
			(at 33.355534 2.169668 270)
			(size 0.4318 0.4318)
			(layers "F.Cu" "F.Mask" "F.Paste")
			(net "PVCCIN_CPU1")
		)
		(pad "CC88" smd circle
			(at 34.98342 2.169668 270)
			(size 0.4318 0.4318)
			(layers "F.Cu" "F.Mask" "F.Paste")
			(net "PVCCIN_CPU1")
		)
		(pad "CC90" smd oval
			(at 36.611306 2.169668)
			(size 0.381 0.4826)
			(drill
				(offset 0 -0.0508)
			)
			(layers "F.Cu" "F.Mask" "F.Paste")
			(net "PVCCIN_CPU1")
		)
		(pad "CD2" smd oval
			(at -36.611306 2.529586 180)
			(size 0.381 0.4826)
			(drill
				(offset 0 -0.0508)
			)
			(layers "F.Cu" "F.Mask" "F.Paste")
			(net "UPI_CPU0_CPU1_P0P1_DN<22>")
		)
		(pad "CD4" smd circle
			(at -34.98342 2.529586 270)
			(size 0.4318 0.4318)
			(layers "F.Cu" "F.Mask" "F.Paste")
			(net "GND")
		)
		(pad "CD6" smd circle
			(at -33.355534 2.529586 270)
			(size 0.4318 0.4318)
			(layers "F.Cu" "F.Mask" "F.Paste")
			(net "UPI_CPU1_CPU0_P1P0_DN<21>")
		)
		(pad "CD8" smd circle
			(at -31.727902 2.529586 270)
			(size 0.4318 0.4318)
			(layers "F.Cu" "F.Mask" "F.Paste")
			(net "GND")
		)
		(pad "CD10" smd circle
			(at -30.100016 2.529586 270)
			(size 0.4318 0.4318)
			(layers "F.Cu" "F.Mask" "F.Paste")
			(net "P5E_CPU1_PE1_RX_DP<5>")
		)
		(pad "CD12" smd circle
			(at -28.472384 2.529586 270)
			(size 0.4318 0.4318)
			(layers "F.Cu" "F.Mask" "F.Paste")
			(net "GND")
		)
		(pad "CD14" smd circle
			(at -26.844498 2.529586 270)
			(size 0.4318 0.4318)
			(layers "F.Cu" "F.Mask" "F.Paste")
			(net "P5E_CPU1_PE1_TX_DP<5>")
		)
		(pad "CD16" smd circle
			(at -25.216612 2.529586 270)
			(size 0.4318 0.4318)
			(layers "F.Cu" "F.Mask" "F.Paste")
			(net "GND")
		)
		(pad "CD18" smd circle
			(at -23.58898 2.529586 270)
			(size 0.4318 0.4318)
			(layers "F.Cu" "F.Mask" "F.Paste")
			(net "TP_DMI_CPU1_PCH_TX_DP<3>")
		)
		(pad "CD20" smd circle
			(at -21.961094 2.529586 270)
			(size 0.4318 0.4318)
			(layers "F.Cu" "F.Mask" "F.Paste")
			(net "GND")
		)
		(pad "CD22" smd circle
			(at -20.333462 2.529586 270)
			(size 0.4318 0.4318)
			(layers "F.Cu" "F.Mask" "F.Paste")
			(net "NC_CPU1_MDFI_DIE10_NS1")
		)
		(pad "CD24" smd circle
			(at -18.705576 2.529586 270)
			(size 0.4318 0.4318)
			(layers "F.Cu" "F.Mask" "F.Paste")
			(net "TP_H_SBLINK4_CPU1_PMDOWN")
		)
		(pad "CD26" smd circle
			(at -17.07769 2.529586 270)
			(size 0.4318 0.4318)
			(layers "F.Cu" "F.Mask" "F.Paste")
			(net "NC_CPU1_MDFI_DIE10_EW0")
		)
		(pad "CD28" smd circle
			(at -15.450058 2.529586 270)
			(size 0.4318 0.4318)
			(layers "F.Cu" "F.Mask" "F.Paste")
			(net "TP_TRC_CPU1_PTI<1>")
		)
		(pad "CD30" smd circle
			(at -13.822426 2.529586 270)
			(size 0.4318 0.4318)
			(layers "F.Cu" "F.Mask" "F.Paste")
			(net "NC_CPU1_MDFI_DIE10_EW1")
		)
		(pad "CD32" smd circle
			(at -12.19454 2.529586 270)
			(size 0.4318 0.4318)
			(layers "F.Cu" "F.Mask" "F.Paste")
			(net "PVCCIN_CPU1")
		)
		(pad "CD34" smd circle
			(at -10.566654 2.529586 270)
			(size 0.4318 0.4318)
			(layers "F.Cu" "F.Mask" "F.Paste")
			(net "PVCCIN_CPU1")
		)
		(pad "CD36" smd circle
			(at -8.939022 2.529586 270)
			(size 0.4318 0.4318)
			(layers "F.Cu" "F.Mask" "F.Paste")
			(net "PVCCIN_CPU1")
		)
		(pad "CD38" smd circle
			(at -7.311136 2.529586 270)
			(size 0.4318 0.4318)
			(layers "F.Cu" "F.Mask" "F.Paste")
			(net "PVCCIN_CPU1")
		)
		(pad "CD40" smd circle
			(at -5.68325 2.529586 270)
			(size 0.4318 0.4318)
			(layers "F.Cu" "F.Mask" "F.Paste")
			(net "PVCCIN_CPU1")
		)
		(pad "CD42" smd circle
			(at -4.055618 2.529586 270)
			(size 0.4318 0.4318)
			(layers "F.Cu" "F.Mask" "F.Paste")
			(net "PVCCIN_CPU1")
		)
		(pad "CD44" smd circle
			(at -2.427732 2.529586 270)
			(size 0.4318 0.4318)
			(layers "F.Cu" "F.Mask" "F.Paste")
			(net "PVCCIN_CPU1")
		)
		(pad "CD47" smd circle
			(at 1.613916 2.639314 270)
			(size 0.4318 0.4318)
			(layers "F.Cu" "F.Mask" "F.Paste")
			(net "PVCCIN_CPU1")
		)
		(pad "CD49" smd circle
			(at 3.241802 2.639314 270)
			(size 0.4318 0.4318)
			(layers "F.Cu" "F.Mask" "F.Paste")
			(net "PVCCIN_CPU1")
		)
		(pad "CD51" smd circle
			(at 4.869434 2.639314 270)
			(size 0.4318 0.4318)
			(layers "F.Cu" "F.Mask" "F.Paste")
			(net "PVCCIN_CPU1")
		)
		(pad "CD53" smd circle
			(at 6.49732 2.639314 270)
			(size 0.4318 0.4318)
			(layers "F.Cu" "F.Mask" "F.Paste")
			(net "PVCCIN_CPU1")
		)
		(pad "CD55" smd circle
			(at 8.124952 2.639314 270)
			(size 0.4318 0.4318)
			(layers "F.Cu" "F.Mask" "F.Paste")
			(net "PVCCIN_CPU1")
		)
		(pad "CD57" smd circle
			(at 9.752838 2.639314 270)
			(size 0.4318 0.4318)
			(layers "F.Cu" "F.Mask" "F.Paste")
			(net "PVCCIN_CPU1")
		)
		(pad "CD59" smd circle
			(at 11.380724 2.639314 270)
			(size 0.4318 0.4318)
			(layers "F.Cu" "F.Mask" "F.Paste")
			(net "PVCCIN_CPU1")
		)
		(pad "CD61" smd circle
			(at 13.008356 2.639314 270)
			(size 0.4318 0.4318)
			(layers "F.Cu" "F.Mask" "F.Paste")
			(net "GND")
		)
		(pad "CD63" smd circle
			(at 14.635988 2.639314 270)
			(size 0.4318 0.4318)
			(layers "F.Cu" "F.Mask" "F.Paste")
			(net "SMB_S3M_CPU1_SDA")
		)
		(pad "CD65" smd circle
			(at 16.263874 2.639314 270)
			(size 0.4318 0.4318)
			(layers "F.Cu" "F.Mask" "F.Paste")
			(net "TP_SGPIO_S3M_CPU1_GSXRST_N")
		)
		(pad "CD67" smd circle
			(at 17.89176 2.639314 270)
			(size 0.4318 0.4318)
			(layers "F.Cu" "F.Mask" "F.Paste")
			(net "PVPP_HBM_CPU1")
		)
		(pad "CD69" smd circle
			(at 19.519392 2.639314 270)
			(size 0.4318 0.4318)
			(layers "F.Cu" "F.Mask" "F.Paste")
			(net "TP_CPU1_SPARE11")
		)
		(pad "CD71" smd circle
			(at 21.147278 2.639314 270)
			(size 0.4318 0.4318)
			(layers "F.Cu" "F.Mask" "F.Paste")
			(net "CPU1_RSVD<82>")
		)
		(pad "CD73" smd circle
			(at 22.77491 2.639314 270)
			(size 0.4318 0.4318)
			(layers "F.Cu" "F.Mask" "F.Paste")
			(net "Net_709")
		)
		(pad "CD75" smd circle
			(at 24.402796 2.639314 270)
			(size 0.4318 0.4318)
			(layers "F.Cu" "F.Mask" "F.Paste")
			(net "GND")
		)
		(pad "CD77" smd circle
			(at 26.030682 2.639314 270)
			(size 0.4318 0.4318)
			(layers "F.Cu" "F.Mask" "F.Paste")
			(net "GND")
		)
		(pad "CD79" smd circle
			(at 27.658314 2.639314 270)
			(size 0.4318 0.4318)
			(layers "F.Cu" "F.Mask" "F.Paste")
			(net "PVCCIN_CPU1")
		)
		(pad "CD81" smd circle
			(at 29.2862 2.639314 270)
			(size 0.4318 0.4318)
			(layers "F.Cu" "F.Mask" "F.Paste")
			(net "PVCCIN_CPU1")
		)
		(pad "CD83" smd circle
			(at 30.914086 2.639314 270)
			(size 0.4318 0.4318)
			(layers "F.Cu" "F.Mask" "F.Paste")
			(net "PVCCIN_CPU1")
		)
		(pad "CD85" smd circle
			(at 32.541718 2.639314 270)
			(size 0.4318 0.4318)
			(layers "F.Cu" "F.Mask" "F.Paste")
			(net "PVCCIN_CPU1")
		)
		(pad "CD87" smd circle
			(at 34.169604 2.639314 270)
			(size 0.4318 0.4318)
			(layers "F.Cu" "F.Mask" "F.Paste")
			(net "PVCCIN_CPU1")
		)
		(pad "CD89" smd circle
			(at 35.797236 2.639314 270)
			(size 0.4318 0.4318)
			(layers "F.Cu" "F.Mask" "F.Paste")
			(net "PVCCIN_CPU1")
		)
		(pad "CE1" smd oval
			(at -37.425122 2.999486 180)
			(size 0.381 0.4826)
			(drill
				(offset 0 -0.0508)
			)
			(layers "F.Cu" "F.Mask" "F.Paste")
			(net "UPI_CPU0_CPU1_P0P1_DP<21>")
		)
		(pad "CE3" smd circle
			(at -35.797236 2.999486 270)
			(size 0.4318 0.4318)
			(layers "F.Cu" "F.Mask" "F.Paste")
			(net "GND")
		)
		(pad "CE5" smd circle
			(at -34.169604 2.999486 270)
			(size 0.4318 0.4318)
			(layers "F.Cu" "F.Mask" "F.Paste")
			(net "UPI_CPU1_CPU0_P1P0_DN<20>")
		)
		(pad "CE7" smd circle
			(at -32.541718 2.999486 270)
			(size 0.4318 0.4318)
			(layers "F.Cu" "F.Mask" "F.Paste")
			(net "PVCCD_HV_CPU1")
		)
		(pad "CE9" smd circle
			(at -30.914086 2.999486 270)
			(size 0.4318 0.4318)
			(layers "F.Cu" "F.Mask" "F.Paste")
			(net "P5E_CPU1_PE1_RX_DP<4>")
		)
		(pad "CE11" smd circle
			(at -29.2862 2.999486 270)
			(size 0.4318 0.4318)
			(layers "F.Cu" "F.Mask" "F.Paste")
			(net "VSENSE_PVCCINFAON_CPU1_DN")
		)
		(pad "CE13" smd circle
			(at -27.658314 2.999486 270)
			(size 0.4318 0.4318)
			(layers "F.Cu" "F.Mask" "F.Paste")
			(net "P5E_CPU1_PE1_TX_DN<5>")
		)
		(pad "CE15" smd circle
			(at -26.030682 2.999486 270)
			(size 0.4318 0.4318)
			(layers "F.Cu" "F.Mask" "F.Paste")
			(net "PVCCINFAON_CPU1")
		)
		(pad "CE17" smd circle
			(at -24.402796 2.999486 270)
			(size 0.4318 0.4318)
			(layers "F.Cu" "F.Mask" "F.Paste")
			(net "TP_DMI_CPU1_PCH_TX_DN<3>")
		)
		(pad "CE19" smd circle
			(at -22.77491 2.999486 270)
			(size 0.4318 0.4318)
			(layers "F.Cu" "F.Mask" "F.Paste")
			(net "PVCCINFAON_CPU1")
		)
		(pad "CE21" smd circle
			(at -21.147278 2.999486 270)
			(size 0.4318 0.4318)
			(layers "F.Cu" "F.Mask" "F.Paste")
			(net "NC_CPU1_PE1_APROBE<0>")
		)
		(pad "CE23" smd circle
			(at -19.519392 2.999486 270)
			(size 0.4318 0.4318)
			(layers "F.Cu" "F.Mask" "F.Paste")
			(net "TP_H_SBLINK6_CPU1_PMDOWN")
		)
		(pad "CE25" smd circle
			(at -17.89176 2.999486 270)
			(size 0.4318 0.4318)
			(layers "F.Cu" "F.Mask" "F.Paste")
			(net "TP_H_SBLINK4_CPU1_PMSYNC")
		)
		(pad "CE60" smd circle
			(at 12.19454 3.109468 270)
			(size 0.4318 0.4318)
			(layers "F.Cu" "F.Mask" "F.Paste")
			(net "GND")
		)
		(pad "CE62" smd circle
			(at 13.822426 3.109468 270)
			(size 0.4318 0.4318)
			(layers "F.Cu" "F.Mask" "F.Paste")
			(net "NC_CPU1_LGSSPARE3")
		)
		(pad "CE64" smd circle
			(at 15.450058 3.109468 270)
			(size 0.4318 0.4318)
			(layers "F.Cu" "F.Mask" "F.Paste")
			(net "SMB_S3M_CPU1_SCL")
		)
		(pad "CE66" smd circle
			(at 17.07769 3.109468 270)
			(size 0.4318 0.4318)
			(layers "F.Cu" "F.Mask" "F.Paste")
			(net "GND")
		)
		(pad "CE68" smd circle
			(at 18.705576 3.109468 270)
			(size 0.4318 0.4318)
			(layers "F.Cu" "F.Mask" "F.Paste")
			(net "PVPP_HBM_CPU1")
		)
		(pad "CE70" smd circle
			(at 20.333462 3.109468 270)
			(size 0.4318 0.4318)
			(layers "F.Cu" "F.Mask" "F.Paste")
			(net "CPU1_RSVD<85>")
		)
		(pad "CE72" smd circle
			(at 21.961094 3.109468 270)
			(size 0.4318 0.4318)
			(layers "F.Cu" "F.Mask" "F.Paste")
			(net "GND")
		)
		(pad "CE74" smd circle
			(at 23.58898 3.109468 270)
			(size 0.4318 0.4318)
			(layers "F.Cu" "F.Mask" "F.Paste")
			(net "PVCCFA_EHV_FIVRA_CPU1")
		)
		(pad "CE76" smd circle
			(at 25.216612 3.109468 270)
			(size 0.4318 0.4318)
			(layers "F.Cu" "F.Mask" "F.Paste")
			(net "GND")
		)
		(pad "CE78" smd circle
			(at 26.844498 3.109468 270)
			(size 0.4318 0.4318)
			(layers "F.Cu" "F.Mask" "F.Paste")
			(net "GND")
		)
		(pad "CE80" smd circle
			(at 28.472384 3.109468 270)
			(size 0.4318 0.4318)
			(layers "F.Cu" "F.Mask" "F.Paste")
			(net "PVCCIN_CPU1")
		)
		(pad "CE82" smd circle
			(at 30.100016 3.109468 270)
			(size 0.4318 0.4318)
			(layers "F.Cu" "F.Mask" "F.Paste")
			(net "PVCCIN_CPU1")
		)
		(pad "CE84" smd circle
			(at 31.727902 3.109468 270)
			(size 0.4318 0.4318)
			(layers "F.Cu" "F.Mask" "F.Paste")
			(net "PVCCIN_CPU1")
		)
		(pad "CE86" smd circle
			(at 33.355534 3.109468 270)
			(size 0.4318 0.4318)
			(layers "F.Cu" "F.Mask" "F.Paste")
			(net "PVCCIN_CPU1")
		)
		(pad "CE88" smd circle
			(at 34.98342 3.109468 270)
			(size 0.4318 0.4318)
			(layers "F.Cu" "F.Mask" "F.Paste")
			(net "PVCCIN_CPU1")
		)
		(pad "CE90" smd oval
			(at 36.611306 3.109468)
			(size 0.381 0.4826)
			(drill
				(offset 0 -0.0508)
			)
			(layers "F.Cu" "F.Mask" "F.Paste")
			(net "PVCCIN_CPU1")
		)
		(pad "CF2" smd circle
			(at -36.611306 3.469132 270)
			(size 0.4318 0.4318)
			(layers "F.Cu" "F.Mask" "F.Paste")
			(net "UPI_CPU0_CPU1_P0P1_DN<21>")
		)
		(pad "CF4" smd circle
			(at -34.98342 3.469132 270)
			(size 0.4318 0.4318)
			(layers "F.Cu" "F.Mask" "F.Paste")
			(net "GND")
		)
		(pad "CF6" smd circle
			(at -33.355534 3.469132 270)
			(size 0.4318 0.4318)
			(layers "F.Cu" "F.Mask" "F.Paste")
			(net "UPI_CPU1_CPU0_P1P0_DP<20>")
		)
		(pad "CF8" smd circle
			(at -31.727902 3.469132 270)
			(size 0.4318 0.4318)
			(layers "F.Cu" "F.Mask" "F.Paste")
			(net "GND")
		)
		(pad "CF10" smd circle
			(at -30.100016 3.469132 270)
			(size 0.4318 0.4318)
			(layers "F.Cu" "F.Mask" "F.Paste")
			(net "P5E_CPU1_PE1_RX_DN<4>")
		)
		(pad "CF12" smd circle
			(at -28.472384 3.469132 270)
			(size 0.4318 0.4318)
			(layers "F.Cu" "F.Mask" "F.Paste")
			(net "GND")
		)
		(pad "CF14" smd circle
			(at -26.844498 3.469132 270)
			(size 0.4318 0.4318)
			(layers "F.Cu" "F.Mask" "F.Paste")
			(net "P5E_CPU1_PE1_TX_DN<4>")
		)
		(pad "CF16" smd circle
			(at -25.216612 3.469132 270)
			(size 0.4318 0.4318)
			(layers "F.Cu" "F.Mask" "F.Paste")
			(net "GND")
		)
		(pad "CF18" smd circle
			(at -23.58898 3.469132 270)
			(size 0.4318 0.4318)
			(layers "F.Cu" "F.Mask" "F.Paste")
			(net "TP_DMI_CPU1_PCH_TX_DN<4>")
		)
		(pad "CF20" smd circle
			(at -21.961094 3.469132 270)
			(size 0.4318 0.4318)
			(layers "F.Cu" "F.Mask" "F.Paste")
			(net "GND")
		)
		(pad "CF22" smd circle
			(at -20.333462 3.469132 270)
			(size 0.4318 0.4318)
			(layers "F.Cu" "F.Mask" "F.Paste")
			(net "NC_CPU1_MDFI_DIE10_NS0")
		)
		(pad "CF24" smd circle
			(at -18.705576 3.469132 270)
			(size 0.4318 0.4318)
			(layers "F.Cu" "F.Mask" "F.Paste")
			(net "TP_H_SBLINK7_CPU1_PMSYNC")
		)
		(pad "CF26" smd circle
			(at -17.07769 3.469132 270)
			(size 0.4318 0.4318)
			(layers "F.Cu" "F.Mask" "F.Paste")
			(net "H_CPU1_MEMHOT_OUT_LVC1_R_N")
		)
		(pad "CF61" smd circle
			(at 13.008356 3.579114 270)
			(size 0.4318 0.4318)
			(layers "F.Cu" "F.Mask" "F.Paste")
			(net "PUD_PCH_BOOT_MODE_CPU1")
		)
		(pad "CF63" smd circle
			(at 14.635988 3.579114 270)
			(size 0.4318 0.4318)
			(layers "F.Cu" "F.Mask" "F.Paste")
			(net "TP_SGPIO_S3M_CPU1_GSXCLK")
		)
		(pad "CF65" smd circle
			(at 16.263874 3.579114 270)
			(size 0.4318 0.4318)
			(layers "F.Cu" "F.Mask" "F.Paste")
			(net "TP_SGPIO_S3M_CPU1_GSXDOUT")
		)
		(pad "CF67" smd circle
			(at 17.89176 3.579114 270)
			(size 0.4318 0.4318)
			(layers "F.Cu" "F.Mask" "F.Paste")
			(net "PVPP_HBM_CPU1")
		)
		(pad "CF69" smd circle
			(at 19.519392 3.579114 270)
			(size 0.4318 0.4318)
			(layers "F.Cu" "F.Mask" "F.Paste")
			(net "GND")
		)
		(pad "CF71" smd circle
			(at 21.147278 3.579114 270)
			(size 0.4318 0.4318)
			(layers "F.Cu" "F.Mask" "F.Paste")
			(net "GND")
		)
		(pad "CF73" smd circle
			(at 22.77491 3.579114 270)
			(size 0.4318 0.4318)
			(layers "F.Cu" "F.Mask" "F.Paste")
			(net "Net_733")
		)
		(pad "CF75" smd circle
			(at 24.402796 3.579114 270)
			(size 0.4318 0.4318)
			(layers "F.Cu" "F.Mask" "F.Paste")
			(net "Net_736")
		)
		(pad "CF77" smd circle
			(at 26.030682 3.579114 270)
			(size 0.4318 0.4318)
			(layers "F.Cu" "F.Mask" "F.Paste")
			(net "Net_714")
		)
		(pad "CF79" smd circle
			(at 27.658314 3.579114 270)
			(size 0.4318 0.4318)
			(layers "F.Cu" "F.Mask" "F.Paste")
			(net "PVCCIN_CPU1")
		)
		(pad "CF81" smd circle
			(at 29.2862 3.579114 270)
			(size 0.4318 0.4318)
			(layers "F.Cu" "F.Mask" "F.Paste")
			(net "PVCCIN_CPU1")
		)
		(pad "CF83" smd circle
			(at 30.914086 3.579114 270)
			(size 0.4318 0.4318)
			(layers "F.Cu" "F.Mask" "F.Paste")
			(net "PVCCIN_CPU1")
		)
		(pad "CF85" smd circle
			(at 32.541718 3.579114 270)
			(size 0.4318 0.4318)
			(layers "F.Cu" "F.Mask" "F.Paste")
			(net "PVCCIN_CPU1")
		)
		(pad "CF87" smd circle
			(at 34.169604 3.579114 270)
			(size 0.4318 0.4318)
			(layers "F.Cu" "F.Mask" "F.Paste")
			(net "PVCCIN_CPU1")
		)
		(pad "CF89" smd circle
			(at 35.797236 3.579114 270)
			(size 0.4318 0.4318)
			(layers "F.Cu" "F.Mask" "F.Paste")
			(net "PVCCIN_CPU1")
		)
		(pad "CF91" smd oval
			(at 37.425122 3.579114)
			(size 0.381 0.4826)
			(drill
				(offset 0 -0.0508)
			)
			(layers "F.Cu" "F.Mask" "F.Paste")
			(net "PVCCIN_CPU1")
		)
		(pad "CG1" smd oval
			(at -37.425122 3.939286 180)
			(size 0.381 0.4826)
			(drill
				(offset 0 -0.0508)
			)
			(layers "F.Cu" "F.Mask" "F.Paste")
			(net "GND")
		)
		(pad "CG3" smd circle
			(at -35.797236 3.939286 270)
			(size 0.4318 0.4318)
			(layers "F.Cu" "F.Mask" "F.Paste")
			(net "UPI_CPU0_CPU1_P0P1_DP<20>")
		)
		(pad "CG5" smd circle
			(at -34.169604 3.939286 270)
			(size 0.4318 0.4318)
			(layers "F.Cu" "F.Mask" "F.Paste")
			(net "GND")
		)
		(pad "CG7" smd circle
			(at -32.541718 3.939286 270)
			(size 0.4318 0.4318)
			(layers "F.Cu" "F.Mask" "F.Paste")
			(net "UPI_CPU1_CPU0_P1P0_DP<19>")
		)
		(pad "CG9" smd circle
			(at -30.914086 3.939286 270)
			(size 0.4318 0.4318)
			(layers "F.Cu" "F.Mask" "F.Paste")
			(net "GND")
		)
		(pad "CG11" smd circle
			(at -29.2862 3.939286 270)
			(size 0.4318 0.4318)
			(layers "F.Cu" "F.Mask" "F.Paste")
			(net "P5E_CPU1_PE1_RX_DN<3>")
		)
		(pad "CG13" smd circle
			(at -27.658314 3.939286 270)
			(size 0.4318 0.4318)
			(layers "F.Cu" "F.Mask" "F.Paste")
			(net "GND")
		)
		(pad "CG15" smd circle
			(at -26.030682 3.939286 270)
			(size 0.4318 0.4318)
			(layers "F.Cu" "F.Mask" "F.Paste")
			(net "P5E_CPU1_PE1_TX_DP<4>")
		)
		(pad "CG17" smd circle
			(at -24.402796 3.939286 270)
			(size 0.4318 0.4318)
			(layers "F.Cu" "F.Mask" "F.Paste")
			(net "GND")
		)
		(pad "CG19" smd circle
			(at -22.77491 3.939286 270)
			(size 0.4318 0.4318)
			(layers "F.Cu" "F.Mask" "F.Paste")
			(net "TP_DMI_CPU1_PCH_TX_DP<4>")
		)
		(pad "CG21" smd circle
			(at -21.147278 3.939286 270)
			(size 0.4318 0.4318)
			(layers "F.Cu" "F.Mask" "F.Paste")
			(net "GND")
		)
		(pad "CG23" smd circle
			(at -19.519392 3.939286 270)
			(size 0.4318 0.4318)
			(layers "F.Cu" "F.Mask" "F.Paste")
			(net "GND")
		)
		(pad "CG25" smd circle
			(at -17.89176 3.939286 270)
			(size 0.4318 0.4318)
			(layers "F.Cu" "F.Mask" "F.Paste")
			(net "GND")
		)
		(pad "CG60" smd circle
			(at 12.19454 4.049268 270)
			(size 0.4318 0.4318)
			(layers "F.Cu" "F.Mask" "F.Paste")
			(net "TP_CPU1_SPARE10")
		)
		(pad "CG62" smd circle
			(at 13.822426 4.049268 270)
			(size 0.4318 0.4318)
			(layers "F.Cu" "F.Mask" "F.Paste")
			(net "GND")
		)
		(pad "CG64" smd circle
			(at 15.450058 4.049268 270)
			(size 0.4318 0.4318)
			(layers "F.Cu" "F.Mask" "F.Paste")
			(net "GND")
		)
		(pad "CG66" smd circle
			(at 17.07769 4.049268 270)
			(size 0.4318 0.4318)
			(layers "F.Cu" "F.Mask" "F.Paste")
			(net "FM_CPU1_SKTOCC_LVT3_N")
		)
		(pad "CG68" smd circle
			(at 18.705576 4.049268 270)
			(size 0.4318 0.4318)
			(layers "F.Cu" "F.Mask" "F.Paste")
			(net "PVPP_HBM_CPU1")
		)
		(pad "CG70" smd circle
			(at 20.333462 4.049268 270)
			(size 0.4318 0.4318)
			(layers "F.Cu" "F.Mask" "F.Paste")
			(net "GND")
		)
		(pad "CG72" smd circle
			(at 21.961094 4.049268 270)
			(size 0.4318 0.4318)
			(layers "F.Cu" "F.Mask" "F.Paste")
			(net "GND")
		)
		(pad "CG74" smd circle
			(at 23.58898 4.049268 270)
			(size 0.4318 0.4318)
			(layers "F.Cu" "F.Mask" "F.Paste")
			(net "GND")
		)
		(pad "CG76" smd circle
			(at 25.216612 4.049268 270)
			(size 0.4318 0.4318)
			(layers "F.Cu" "F.Mask" "F.Paste")
			(net "Net_738")
		)
		(pad "CG78" smd circle
			(at 26.844498 4.049268 270)
			(size 0.4318 0.4318)
			(layers "F.Cu" "F.Mask" "F.Paste")
			(net "GND")
		)
		(pad "CG80" smd circle
			(at 28.472384 4.049268 270)
			(size 0.4318 0.4318)
			(layers "F.Cu" "F.Mask" "F.Paste")
			(net "PVCCIN_CPU1")
		)
		(pad "CG82" smd circle
			(at 30.100016 4.049268 270)
			(size 0.4318 0.4318)
			(layers "F.Cu" "F.Mask" "F.Paste")
			(net "PVCCIN_CPU1")
		)
		(pad "CG84" smd circle
			(at 31.727902 4.049268 270)
			(size 0.4318 0.4318)
			(layers "F.Cu" "F.Mask" "F.Paste")
			(net "PVCCIN_CPU1")
		)
		(pad "CG86" smd circle
			(at 33.355534 4.049268 270)
			(size 0.4318 0.4318)
			(layers "F.Cu" "F.Mask" "F.Paste")
			(net "PVCCIN_CPU1")
		)
		(pad "CG88" smd circle
			(at 34.98342 4.049268 270)
			(size 0.4318 0.4318)
			(layers "F.Cu" "F.Mask" "F.Paste")
			(net "PVCCIN_CPU1")
		)
		(pad "CG90" smd circle
			(at 36.611306 4.049268 270)
			(size 0.4318 0.4318)
			(layers "F.Cu" "F.Mask" "F.Paste")
			(net "PVCCIN_CPU1")
		)
		(pad "CH2" smd circle
			(at -36.611306 4.408932 270)
			(size 0.4318 0.4318)
			(layers "F.Cu" "F.Mask" "F.Paste")
			(net "UPI_CPU0_CPU1_P0P1_DN<20>")
		)
		(pad "CH4" smd circle
			(at -34.98342 4.408932 270)
			(size 0.4318 0.4318)
			(layers "F.Cu" "F.Mask" "F.Paste")
			(net "GND")
		)
		(pad "CH6" smd circle
			(at -33.355534 4.408932 270)
			(size 0.4318 0.4318)
			(layers "F.Cu" "F.Mask" "F.Paste")
			(net "UPI_CPU1_CPU0_P1P0_DN<19>")
		)
		(pad "CH8" smd circle
			(at -31.727902 4.408932 270)
			(size 0.4318 0.4318)
			(layers "F.Cu" "F.Mask" "F.Paste")
			(net "GND")
		)
		(pad "CH10" smd circle
			(at -30.100016 4.408932 270)
			(size 0.4318 0.4318)
			(layers "F.Cu" "F.Mask" "F.Paste")
			(net "P5E_CPU1_PE1_RX_DP<3>")
		)
		(pad "CH12" smd circle
			(at -28.472384 4.408932 270)
			(size 0.4318 0.4318)
			(layers "F.Cu" "F.Mask" "F.Paste")
			(net "GND")
		)
		(pad "CH14" smd circle
			(at -26.844498 4.408932 270)
			(size 0.4318 0.4318)
			(layers "F.Cu" "F.Mask" "F.Paste")
			(net "P5E_CPU1_PE1_TX_DP<3>")
		)
		(pad "CH16" smd circle
			(at -25.216612 4.408932 270)
			(size 0.4318 0.4318)
			(layers "F.Cu" "F.Mask" "F.Paste")
			(net "GND")
		)
		(pad "CH18" smd circle
			(at -23.58898 4.408932 270)
			(size 0.4318 0.4318)
			(layers "F.Cu" "F.Mask" "F.Paste")
			(net "TP_DMI_CPU1_PCH_TX_DP<5>")
		)
		(pad "CH20" smd circle
			(at -21.961094 4.408932 270)
			(size 0.4318 0.4318)
			(layers "F.Cu" "F.Mask" "F.Paste")
			(net "GND")
		)
		(pad "CH22" smd circle
			(at -20.333462 4.408932 270)
			(size 0.4318 0.4318)
			(layers "F.Cu" "F.Mask" "F.Paste")
			(net "PD_CPU1_ENH_MCECC_DIS")
		)
		(pad "CH24" smd circle
			(at -18.705576 4.408932 270)
			(size 0.4318 0.4318)
			(layers "F.Cu" "F.Mask" "F.Paste")
			(net "TP_H_SBLINK6_CPU1_PMSYNC")
		)
		(pad "CH26" smd circle
			(at -17.07769 4.408932 270)
			(size 0.4318 0.4318)
			(layers "F.Cu" "F.Mask" "F.Paste")
			(net "TP_H_SBLINK3_CPU1_PMSYNC")
		)
		(pad "CH61" smd circle
			(at 13.008356 4.518914 270)
			(size 0.4318 0.4318)
			(layers "F.Cu" "F.Mask" "F.Paste")
			(net "TP_CPU1_SPARE9")
		)
		(pad "CH63" smd circle
			(at 14.635988 4.518914 270)
			(size 0.4318 0.4318)
			(layers "F.Cu" "F.Mask" "F.Paste")
			(net "TP_SGPIO_S3M_CPU1_GSXDIN")
		)
		(pad "CH65" smd circle
			(at 16.263874 4.518914 270)
			(size 0.4318 0.4318)
			(layers "F.Cu" "F.Mask" "F.Paste")
			(net "PU_S3M_CPU1_CPLD_STATUS")
		)
		(pad "CH67" smd circle
			(at 17.89176 4.518914 270)
			(size 0.4318 0.4318)
			(layers "F.Cu" "F.Mask" "F.Paste")
			(net "GND")
		)
		(pad "CH69" smd circle
			(at 19.519392 4.518914 270)
			(size 0.4318 0.4318)
			(layers "F.Cu" "F.Mask" "F.Paste")
			(net "NC_CPU1_MDFI_DIE11_EW1")
		)
		(pad "CH71" smd circle
			(at 21.147278 4.518914 270)
			(size 0.4318 0.4318)
			(layers "F.Cu" "F.Mask" "F.Paste")
			(net "TP_PWRGD_S0_PWROK_CPU1_LVC1")
		)
		(pad "CH73" smd circle
			(at 22.77491 4.518914 270)
			(size 0.4318 0.4318)
			(layers "F.Cu" "F.Mask" "F.Paste")
			(net "GND")
		)
		(pad "CH75" smd circle
			(at 24.402796 4.518914 270)
			(size 0.4318 0.4318)
			(layers "F.Cu" "F.Mask" "F.Paste")
			(net "Net_712")
		)
		(pad "CH77" smd circle
			(at 26.030682 4.518914 270)
			(size 0.4318 0.4318)
			(layers "F.Cu" "F.Mask" "F.Paste")
			(net "Net_740")
		)
		(pad "CH79" smd circle
			(at 27.658314 4.518914 270)
			(size 0.4318 0.4318)
			(layers "F.Cu" "F.Mask" "F.Paste")
			(net "GND")
		)
		(pad "CH81" smd circle
			(at 29.2862 4.518914 270)
			(size 0.4318 0.4318)
			(layers "F.Cu" "F.Mask" "F.Paste")
			(net "PVCCIN_CPU1")
		)
		(pad "CH83" smd circle
			(at 30.914086 4.518914 270)
			(size 0.4318 0.4318)
			(layers "F.Cu" "F.Mask" "F.Paste")
			(net "GND")
		)
		(pad "CH85" smd circle
			(at 32.541718 4.518914 270)
			(size 0.4318 0.4318)
			(layers "F.Cu" "F.Mask" "F.Paste")
			(net "GND")
		)
		(pad "CH87" smd circle
			(at 34.169604 4.518914 270)
			(size 0.4318 0.4318)
			(layers "F.Cu" "F.Mask" "F.Paste")
			(net "GND")
		)
		(pad "CH89" smd circle
			(at 35.797236 4.518914 270)
			(size 0.4318 0.4318)
			(layers "F.Cu" "F.Mask" "F.Paste")
			(net "GND")
		)
		(pad "CH91" smd oval
			(at 37.425122 4.518914)
			(size 0.381 0.4826)
			(drill
				(offset 0 -0.0508)
			)
			(layers "F.Cu" "F.Mask" "F.Paste")
			(net "PVCCIN_CPU1")
		)
		(pad "CJ1" smd oval
			(at -37.425122 4.879086 180)
			(size 0.381 0.4826)
			(drill
				(offset 0 -0.0508)
			)
			(layers "F.Cu" "F.Mask" "F.Paste")
			(net "UPI_CPU0_CPU1_P0P1_DN<19>")
		)
		(pad "CJ3" smd circle
			(at -35.797236 4.879086 270)
			(size 0.4318 0.4318)
			(layers "F.Cu" "F.Mask" "F.Paste")
			(net "PVCCINFAON_CPU1")
		)
		(pad "CJ5" smd circle
			(at -34.169604 4.879086 270)
			(size 0.4318 0.4318)
			(layers "F.Cu" "F.Mask" "F.Paste")
			(net "UPI_CPU1_CPU0_P1P0_DN<18>")
		)
		(pad "CJ7" smd circle
			(at -32.541718 4.879086 270)
			(size 0.4318 0.4318)
			(layers "F.Cu" "F.Mask" "F.Paste")
			(net "PVCCINFAON_CPU1")
		)
		(pad "CJ9" smd circle
			(at -30.914086 4.879086 270)
			(size 0.4318 0.4318)
			(layers "F.Cu" "F.Mask" "F.Paste")
			(net "P5E_CPU1_PE1_RX_DP<2>")
		)
		(pad "CJ11" smd circle
			(at -29.2862 4.879086 270)
			(size 0.4318 0.4318)
			(layers "F.Cu" "F.Mask" "F.Paste")
			(net "PVCCINFAON_CPU1")
		)
		(pad "CJ13" smd circle
			(at -27.658314 4.879086 270)
			(size 0.4318 0.4318)
			(layers "F.Cu" "F.Mask" "F.Paste")
			(net "P5E_CPU1_PE1_TX_DN<3>")
		)
		(pad "CJ15" smd circle
			(at -26.030682 4.879086 270)
			(size 0.4318 0.4318)
			(layers "F.Cu" "F.Mask" "F.Paste")
			(net "PVCCINFAON_CPU1")
		)
		(pad "CJ17" smd circle
			(at -24.402796 4.879086 270)
			(size 0.4318 0.4318)
			(layers "F.Cu" "F.Mask" "F.Paste")
			(net "TP_DMI_CPU1_PCH_TX_DN<5>")
		)
		(pad "CJ19" smd circle
			(at -22.77491 4.879086 270)
			(size 0.4318 0.4318)
			(layers "F.Cu" "F.Mask" "F.Paste")
			(net "PVCCINFAON_CPU1")
		)
		(pad "CJ21" smd circle
			(at -21.147278 4.879086 270)
			(size 0.4318 0.4318)
			(layers "F.Cu" "F.Mask" "F.Paste")
			(net "TP_CPU1_IBL_GRST_WARN_CPU1_N")
		)
		(pad "CJ23" smd circle
			(at -19.519392 4.879086 270)
			(size 0.4318 0.4318)
			(layers "F.Cu" "F.Mask" "F.Paste")
			(net "TP_I2C_S3M_RTC_CPU1_SDA")
		)
		(pad "CJ25" smd circle
			(at -17.89176 4.879086 270)
			(size 0.4318 0.4318)
			(layers "F.Cu" "F.Mask" "F.Paste")
			(net "TP_I2C_S3M_RTC_CPU1_RST_N")
		)
		(pad "CJ60" smd circle
			(at 12.19454 4.989068 270)
			(size 0.4318 0.4318)
			(layers "F.Cu" "F.Mask" "F.Paste")
			(net "GND")
		)
		(pad "CJ62" smd circle
			(at 13.822426 4.989068 270)
			(size 0.4318 0.4318)
			(layers "F.Cu" "F.Mask" "F.Paste")
			(net "CPU1_RSVD<98>")
		)
		(pad "CJ64" smd circle
			(at 15.450058 4.989068 270)
			(size 0.4318 0.4318)
			(layers "F.Cu" "F.Mask" "F.Paste")
			(net "PU_S3M_CPU1_CPLD_CONFD")
		)
		(pad "CJ66" smd circle
			(at 17.07769 4.989068 270)
			(size 0.4318 0.4318)
			(layers "F.Cu" "F.Mask" "F.Paste")
			(net "TP_SGPIO_S3M_CPU1_GSXDLOAD")
		)
		(pad "CJ68" smd circle
			(at 18.705576 4.989068 270)
			(size 0.4318 0.4318)
			(layers "F.Cu" "F.Mask" "F.Paste")
			(net "NC_CPU1_MDFI_DIE11_NS0")
		)
		(pad "CJ70" smd circle
			(at 20.333462 4.989068 270)
			(size 0.4318 0.4318)
			(layers "F.Cu" "F.Mask" "F.Paste")
			(net "NC_CPU1_MDFI_DIE11_EW0")
		)
		(pad "CJ72" smd circle
			(at 21.961094 4.989068 270)
			(size 0.4318 0.4318)
			(layers "F.Cu" "F.Mask" "F.Paste")
			(net "PUD_XTAL_CPU1_MODE1")
		)
		(pad "CJ74" smd circle
			(at 23.58898 4.989068 270)
			(size 0.4318 0.4318)
			(layers "F.Cu" "F.Mask" "F.Paste")
			(net "Net_735")
		)
		(pad "CJ76" smd circle
			(at 25.216612 4.989068 270)
			(size 0.4318 0.4318)
			(layers "F.Cu" "F.Mask" "F.Paste")
			(net "GND")
		)
		(pad "CJ78" smd circle
			(at 26.844498 4.989068 270)
			(size 0.4318 0.4318)
			(layers "F.Cu" "F.Mask" "F.Paste")
			(net "Net_716")
		)
		(pad "CJ80" smd circle
			(at 28.472384 4.989068 270)
			(size 0.4318 0.4318)
			(layers "F.Cu" "F.Mask" "F.Paste")
			(net "GND")
		)
		(pad "CJ82" smd circle
			(at 30.100016 4.989068 270)
			(size 0.4318 0.4318)
			(layers "F.Cu" "F.Mask" "F.Paste")
			(net "PVCCIN_CPU1")
		)
		(pad "CJ84" smd circle
			(at 31.727902 4.989068 270)
			(size 0.4318 0.4318)
			(layers "F.Cu" "F.Mask" "F.Paste")
			(net "PVCCIN_CPU1")
		)
		(pad "CJ86" smd circle
			(at 33.355534 4.989068 270)
			(size 0.4318 0.4318)
			(layers "F.Cu" "F.Mask" "F.Paste")
			(net "PVCCIN_CPU1")
		)
		(pad "CJ88" smd circle
			(at 34.98342 4.989068 270)
			(size 0.4318 0.4318)
			(layers "F.Cu" "F.Mask" "F.Paste")
			(net "PVCCIN_CPU1")
		)
		(pad "CJ90" smd circle
			(at 36.611306 4.989068 270)
			(size 0.4318 0.4318)
			(layers "F.Cu" "F.Mask" "F.Paste")
			(net "PVCCIN_CPU1")
		)
		(pad "CK2" smd circle
			(at -36.611306 5.348732 270)
			(size 0.4318 0.4318)
			(layers "F.Cu" "F.Mask" "F.Paste")
			(net "UPI_CPU0_CPU1_P0P1_DP<19>")
		)
		(pad "CK4" smd circle
			(at -34.98342 5.348732 270)
			(size 0.4318 0.4318)
			(layers "F.Cu" "F.Mask" "F.Paste")
			(net "GND")
		)
		(pad "CK6" smd circle
			(at -33.355534 5.348732 270)
			(size 0.4318 0.4318)
			(layers "F.Cu" "F.Mask" "F.Paste")
			(net "UPI_CPU1_CPU0_P1P0_DP<18>")
		)
		(pad "CK8" smd circle
			(at -31.727902 5.348732 270)
			(size 0.4318 0.4318)
			(layers "F.Cu" "F.Mask" "F.Paste")
			(net "GND")
		)
		(pad "CK10" smd circle
			(at -30.100016 5.348732 270)
			(size 0.4318 0.4318)
			(layers "F.Cu" "F.Mask" "F.Paste")
			(net "P5E_CPU1_PE1_RX_DN<2>")
		)
		(pad "CK12" smd circle
			(at -28.472384 5.348732 270)
			(size 0.4318 0.4318)
			(layers "F.Cu" "F.Mask" "F.Paste")
			(net "GND")
		)
		(pad "CK14" smd circle
			(at -26.844498 5.348732 270)
			(size 0.4318 0.4318)
			(layers "F.Cu" "F.Mask" "F.Paste")
			(net "P5E_CPU1_PE1_TX_DN<2>")
		)
		(pad "CK16" smd circle
			(at -25.216612 5.348732 270)
			(size 0.4318 0.4318)
			(layers "F.Cu" "F.Mask" "F.Paste")
			(net "GND")
		)
		(pad "CK18" smd circle
			(at -23.58898 5.348732 270)
			(size 0.4318 0.4318)
			(layers "F.Cu" "F.Mask" "F.Paste")
			(net "TP_DMI_CPU1_PCH_TX_DN<6>")
		)
		(pad "CK20" smd circle
			(at -21.961094 5.348732 270)
			(size 0.4318 0.4318)
			(layers "F.Cu" "F.Mask" "F.Paste")
			(net "GND")
		)
		(pad "CK22" smd circle
			(at -20.333462 5.348732 270)
			(size 0.4318 0.4318)
			(layers "F.Cu" "F.Mask" "F.Paste")
			(net "TP_FM_SYS_RST_CPU1_N")
		)
		(pad "CK24" smd circle
			(at -18.705576 5.348732 270)
			(size 0.4318 0.4318)
			(layers "F.Cu" "F.Mask" "F.Paste")
			(net "TP_FM_IBL_PWRBTN_CPU1_N")
		)
		(pad "CK26" smd circle
			(at -17.07769 5.348732 270)
			(size 0.4318 0.4318)
			(layers "F.Cu" "F.Mask" "F.Paste")
			(net "GND")
		)
		(pad "CK61" smd circle
			(at 13.008356 5.458714 270)
			(size 0.4318 0.4318)
			(layers "F.Cu" "F.Mask" "F.Paste")
			(net "TP_CPU1_SPARE8")
		)
		(pad "CK63" smd circle
			(at 14.635988 5.458714 270)
			(size 0.4318 0.4318)
			(layers "F.Cu" "F.Mask" "F.Paste")
			(net "GND")
		)
		(pad "CK65" smd circle
			(at 16.263874 5.458714 270)
			(size 0.4318 0.4318)
			(layers "F.Cu" "F.Mask" "F.Paste")
			(net "FM_S3M_CPU1_CPLD_CONFIG_N")
		)
		(pad "CK67" smd circle
			(at 17.89176 5.458714 270)
			(size 0.4318 0.4318)
			(layers "F.Cu" "F.Mask" "F.Paste")
			(net "NC_CPU1_MDFI_DIE11_NS1")
		)
		(pad "CK69" smd circle
			(at 19.519392 5.458714 270)
			(size 0.4318 0.4318)
			(layers "F.Cu" "F.Mask" "F.Paste")
			(net "GND")
		)
		(pad "CK71" smd circle
			(at 21.147278 5.458714 270)
			(size 0.4318 0.4318)
			(layers "F.Cu" "F.Mask" "F.Paste")
			(net "PU_CPU1_UPI3_AC_COUPLING")
		)
		(pad "CK73" smd circle
			(at 22.77491 5.458714 270)
			(size 0.4318 0.4318)
			(layers "F.Cu" "F.Mask" "F.Paste")
			(net "PVCCFA_EHV_FIVRA_CPU1")
		)
		(pad "CK75" smd circle
			(at 24.402796 5.458714 270)
			(size 0.4318 0.4318)
			(layers "F.Cu" "F.Mask" "F.Paste")
			(net "Net_711")
		)
		(pad "CK77" smd circle
			(at 26.030682 5.458714 270)
			(size 0.4318 0.4318)
			(layers "F.Cu" "F.Mask" "F.Paste")
			(net "Net_741")
		)
		(pad "CK79" smd circle
			(at 27.658314 5.458714 270)
			(size 0.4318 0.4318)
			(layers "F.Cu" "F.Mask" "F.Paste")
			(net "PVCCFA_EHV_FIVRA_CPU1")
		)
		(pad "CK81" smd circle
			(at 29.2862 5.458714 270)
			(size 0.4318 0.4318)
			(layers "F.Cu" "F.Mask" "F.Paste")
			(net "GND")
		)
		(pad "CK83" smd circle
			(at 30.914086 5.458714 270)
			(size 0.4318 0.4318)
			(layers "F.Cu" "F.Mask" "F.Paste")
			(net "PVCCIN_CPU1")
		)
		(pad "CK85" smd circle
			(at 32.541718 5.458714 270)
			(size 0.4318 0.4318)
			(layers "F.Cu" "F.Mask" "F.Paste")
			(net "PVCCIN_CPU1")
		)
		(pad "CK87" smd circle
			(at 34.169604 5.458714 270)
			(size 0.4318 0.4318)
			(layers "F.Cu" "F.Mask" "F.Paste")
			(net "PVCCIN_CPU1")
		)
		(pad "CK89" smd circle
			(at 35.797236 5.458714 270)
			(size 0.4318 0.4318)
			(layers "F.Cu" "F.Mask" "F.Paste")
			(net "PVCCIN_CPU1")
		)
		(pad "CK91" smd oval
			(at 37.425122 5.458714)
			(size 0.381 0.4826)
			(drill
				(offset 0 -0.0508)
			)
			(layers "F.Cu" "F.Mask" "F.Paste")
			(net "PVCCIN_CPU1")
		)
		(pad "CL1" smd oval
			(at -37.425122 5.818886 180)
			(size 0.381 0.4826)
			(drill
				(offset 0 -0.0508)
			)
			(layers "F.Cu" "F.Mask" "F.Paste")
			(net "GND")
		)
		(pad "CL3" smd circle
			(at -35.797236 5.818886 270)
			(size 0.4318 0.4318)
			(layers "F.Cu" "F.Mask" "F.Paste")
			(net "UPI_CPU0_CPU1_P0P1_DN<18>")
		)
		(pad "CL5" smd circle
			(at -34.169604 5.818886 270)
			(size 0.4318 0.4318)
			(layers "F.Cu" "F.Mask" "F.Paste")
			(net "GND")
		)
		(pad "CL7" smd circle
			(at -32.541718 5.818886 270)
			(size 0.4318 0.4318)
			(layers "F.Cu" "F.Mask" "F.Paste")
			(net "UPI_CPU1_CPU0_P1P0_DP<17>")
		)
		(pad "CL9" smd circle
			(at -30.914086 5.818886 270)
			(size 0.4318 0.4318)
			(layers "F.Cu" "F.Mask" "F.Paste")
			(net "GND")
		)
		(pad "CL11" smd circle
			(at -29.2862 5.818886 270)
			(size 0.4318 0.4318)
			(layers "F.Cu" "F.Mask" "F.Paste")
			(net "P5E_CPU1_PE1_RX_DN<1>")
		)
		(pad "CL13" smd circle
			(at -27.658314 5.818886 270)
			(size 0.4318 0.4318)
			(layers "F.Cu" "F.Mask" "F.Paste")
			(net "GND")
		)
		(pad "CL15" smd circle
			(at -26.030682 5.818886 270)
			(size 0.4318 0.4318)
			(layers "F.Cu" "F.Mask" "F.Paste")
			(net "P5E_CPU1_PE1_TX_DP<2>")
		)
		(pad "CL17" smd circle
			(at -24.402796 5.818886 270)
			(size 0.4318 0.4318)
			(layers "F.Cu" "F.Mask" "F.Paste")
			(net "GND")
		)
		(pad "CL19" smd circle
			(at -22.77491 5.818886 270)
			(size 0.4318 0.4318)
			(layers "F.Cu" "F.Mask" "F.Paste")
			(net "TP_DMI_CPU1_PCH_TX_DP<6>")
		)
		(pad "CL21" smd circle
			(at -21.147278 5.818886 270)
			(size 0.4318 0.4318)
			(layers "F.Cu" "F.Mask" "F.Paste")
			(net "CPU1_RSVD<107>")
		)
		(pad "CL23" smd circle
			(at -19.519392 5.818886 270)
			(size 0.4318 0.4318)
			(layers "F.Cu" "F.Mask" "F.Paste")
			(net "TP_I2C_S3M_RTC_CPU1_SCL")
		)
		(pad "CL25" smd circle
			(at -17.89176 5.818886 270)
			(size 0.4318 0.4318)
			(layers "F.Cu" "F.Mask" "F.Paste")
			(net "TP_H_SBLINK2_CPU1_PMSYNC")
		)
		(pad "CL60" smd circle
			(at 12.19454 5.928868 270)
			(size 0.4318 0.4318)
			(layers "F.Cu" "F.Mask" "F.Paste")
			(net "TP_CPU1_SPARE7")
		)
		(pad "CL62" smd circle
			(at 13.822426 5.928868 270)
			(size 0.4318 0.4318)
			(layers "F.Cu" "F.Mask" "F.Paste")
			(net "GND")
		)
		(pad "CL64" smd circle
			(at 15.450058 5.928868 270)
			(size 0.4318 0.4318)
			(layers "F.Cu" "F.Mask" "F.Paste")
			(net "CPU1_RSVD<110>")
		)
		(pad "CL66" smd circle
			(at 17.07769 5.928868 270)
			(size 0.4318 0.4318)
			(layers "F.Cu" "F.Mask" "F.Paste")
			(net "TP_CPU1_SSC_SYNC")
		)
		(pad "CL68" smd circle
			(at 18.705576 5.928868 270)
			(size 0.4318 0.4318)
			(layers "F.Cu" "F.Mask" "F.Paste")
			(net "NC_CPU1_PE3_APROBE<0>")
		)
		(pad "CL70" smd circle
			(at 20.333462 5.928868 270)
			(size 0.4318 0.4318)
			(layers "F.Cu" "F.Mask" "F.Paste")
			(net "TP_CPU1_SPARE12")
		)
		(pad "CL72" smd circle
			(at 21.961094 5.928868 270)
			(size 0.4318 0.4318)
			(layers "F.Cu" "F.Mask" "F.Paste")
			(net "PUD_XTAL_CPU1_MODE0")
		)
		(pad "CL74" smd circle
			(at 23.58898 5.928868 270)
			(size 0.4318 0.4318)
			(layers "F.Cu" "F.Mask" "F.Paste")
			(net "GND")
		)
		(pad "CL76" smd circle
			(at 25.216612 5.928868 270)
			(size 0.4318 0.4318)
			(layers "F.Cu" "F.Mask" "F.Paste")
			(net "Net_715")
		)
		(pad "CL78" smd circle
			(at 26.844498 5.928868 270)
			(size 0.4318 0.4318)
			(layers "F.Cu" "F.Mask" "F.Paste")
			(net "GND")
		)
		(pad "CL80" smd circle
			(at 28.472384 5.928868 270)
			(size 0.4318 0.4318)
			(layers "F.Cu" "F.Mask" "F.Paste")
			(net "GND")
		)
		(pad "CL82" smd circle
			(at 30.100016 5.928868 270)
			(size 0.4318 0.4318)
			(layers "F.Cu" "F.Mask" "F.Paste")
			(net "GND")
		)
		(pad "CL84" smd circle
			(at 31.727902 5.928868 270)
			(size 0.4318 0.4318)
			(layers "F.Cu" "F.Mask" "F.Paste")
			(net "PVCCIN_CPU1")
		)
		(pad "CL86" smd circle
			(at 33.355534 5.928868 270)
			(size 0.4318 0.4318)
			(layers "F.Cu" "F.Mask" "F.Paste")
			(net "PVCCIN_CPU1")
		)
		(pad "CL88" smd circle
			(at 34.98342 5.928868 270)
			(size 0.4318 0.4318)
			(layers "F.Cu" "F.Mask" "F.Paste")
			(net "PVCCIN_CPU1")
		)
		(pad "CL90" smd circle
			(at 36.611306 5.928868 270)
			(size 0.4318 0.4318)
			(layers "F.Cu" "F.Mask" "F.Paste")
			(net "PVCCIN_CPU1")
		)
		(pad "CM2" smd circle
			(at -36.611306 6.288532 270)
			(size 0.4318 0.4318)
			(layers "F.Cu" "F.Mask" "F.Paste")
			(net "UPI_CPU0_CPU1_P0P1_DP<18>")
		)
		(pad "CM4" smd circle
			(at -34.98342 6.288532 270)
			(size 0.4318 0.4318)
			(layers "F.Cu" "F.Mask" "F.Paste")
			(net "GND")
		)
		(pad "CM6" smd circle
			(at -33.355534 6.288532 270)
			(size 0.4318 0.4318)
			(layers "F.Cu" "F.Mask" "F.Paste")
			(net "UPI_CPU1_CPU0_P1P0_DN<17>")
		)
		(pad "CM8" smd circle
			(at -31.727902 6.288532 270)
			(size 0.4318 0.4318)
			(layers "F.Cu" "F.Mask" "F.Paste")
			(net "GND")
		)
		(pad "CM10" smd circle
			(at -30.100016 6.288532 270)
			(size 0.4318 0.4318)
			(layers "F.Cu" "F.Mask" "F.Paste")
			(net "P5E_CPU1_PE1_RX_DP<1>")
		)
		(pad "CM12" smd circle
			(at -28.472384 6.288532 270)
			(size 0.4318 0.4318)
			(layers "F.Cu" "F.Mask" "F.Paste")
			(net "GND")
		)
		(pad "CM14" smd circle
			(at -26.844498 6.288532 270)
			(size 0.4318 0.4318)
			(layers "F.Cu" "F.Mask" "F.Paste")
			(net "P5E_CPU1_PE1_TX_DP<1>")
		)
		(pad "CM16" smd circle
			(at -25.216612 6.288532 270)
			(size 0.4318 0.4318)
			(layers "F.Cu" "F.Mask" "F.Paste")
			(net "GND")
		)
		(pad "CM18" smd circle
			(at -23.58898 6.288532 270)
			(size 0.4318 0.4318)
			(layers "F.Cu" "F.Mask" "F.Paste")
			(net "TP_DMI_CPU1_PCH_TX_DP<7>")
		)
		(pad "CM20" smd circle
			(at -21.961094 6.288532 270)
			(size 0.4318 0.4318)
			(layers "F.Cu" "F.Mask" "F.Paste")
			(net "GND")
		)
		(pad "CM22" smd circle
			(at -20.333462 6.288532 270)
			(size 0.4318 0.4318)
			(layers "F.Cu" "F.Mask" "F.Paste")
			(net "GND")
		)
		(pad "CM24" smd circle
			(at -18.705576 6.288532 270)
			(size 0.4318 0.4318)
			(layers "F.Cu" "F.Mask" "F.Paste")
			(net "GND")
		)
		(pad "CM26" smd circle
			(at -17.07769 6.288532 270)
			(size 0.4318 0.4318)
			(layers "F.Cu" "F.Mask" "F.Paste")
			(net "TP_H_SBLINK3_CPU1_PMDOWN")
		)
		(pad "CM61" smd circle
			(at 13.008356 6.398514 270)
			(size 0.4318 0.4318)
			(layers "F.Cu" "F.Mask" "F.Paste")
			(net "GND")
		)
		(pad "CM63" smd circle
			(at 14.635988 6.398514 270)
			(size 0.4318 0.4318)
			(layers "F.Cu" "F.Mask" "F.Paste")
			(net "CPU1_RSVD<115>")
		)
		(pad "CM65" smd circle
			(at 16.263874 6.398514 270)
			(size 0.4318 0.4318)
			(layers "F.Cu" "F.Mask" "F.Paste")
			(net "GND")
		)
		(pad "CM67" smd circle
			(at 17.89176 6.398514 270)
			(size 0.4318 0.4318)
			(layers "F.Cu" "F.Mask" "F.Paste")
			(net "GND")
		)
		(pad "CM69" smd circle
			(at 19.519392 6.398514 270)
			(size 0.4318 0.4318)
			(layers "F.Cu" "F.Mask" "F.Paste")
			(net "NC_CPU1_PE3_APROBE<1>")
		)
		(pad "CM71" smd circle
			(at 21.147278 6.398514 270)
			(size 0.4318 0.4318)
			(layers "F.Cu" "F.Mask" "F.Paste")
			(net "SMB_S3M_CPU1_PIROM_3V3AUX_SDA_1")
		)
		(pad "CM73" smd circle
			(at 22.77491 6.398514 270)
			(size 0.4318 0.4318)
			(layers "F.Cu" "F.Mask" "F.Paste")
			(net "PVCCFA_EHV_FIVRA_CPU1")
		)
		(pad "CM75" smd circle
			(at 24.402796 6.398514 270)
			(size 0.4318 0.4318)
			(layers "F.Cu" "F.Mask" "F.Paste")
			(net "Net_739")
		)
		(pad "CM77" smd circle
			(at 26.030682 6.398514 270)
			(size 0.4318 0.4318)
			(layers "F.Cu" "F.Mask" "F.Paste")
			(net "Net_717")
		)
		(pad "CM79" smd circle
			(at 27.658314 6.398514 270)
			(size 0.4318 0.4318)
			(layers "F.Cu" "F.Mask" "F.Paste")
			(net "GND")
		)
		(pad "CM81" smd circle
			(at 29.2862 6.398514 270)
			(size 0.4318 0.4318)
			(layers "F.Cu" "F.Mask" "F.Paste")
			(net "GND")
		)
		(pad "CM83" smd circle
			(at 30.914086 6.398514 270)
			(size 0.4318 0.4318)
			(layers "F.Cu" "F.Mask" "F.Paste")
			(net "GND")
		)
		(pad "CM85" smd circle
			(at 32.541718 6.398514 270)
			(size 0.4318 0.4318)
			(layers "F.Cu" "F.Mask" "F.Paste")
			(net "GND")
		)
		(pad "CM87" smd circle
			(at 34.169604 6.398514 270)
			(size 0.4318 0.4318)
			(layers "F.Cu" "F.Mask" "F.Paste")
			(net "PVCCIN_CPU1")
		)
		(pad "CM89" smd circle
			(at 35.797236 6.398514 270)
			(size 0.4318 0.4318)
			(layers "F.Cu" "F.Mask" "F.Paste")
			(net "PVCCIN_CPU1")
		)
		(pad "CM91" smd oval
			(at 37.425122 6.398514)
			(size 0.381 0.4826)
			(drill
				(offset 0 -0.0508)
			)
			(layers "F.Cu" "F.Mask" "F.Paste")
			(net "PVCCIN_CPU1")
		)
		(pad "CN1" smd oval
			(at -37.425122 6.758686 180)
			(size 0.381 0.4826)
			(drill
				(offset 0 -0.0508)
			)
			(layers "F.Cu" "F.Mask" "F.Paste")
			(net "UPI_CPU0_CPU1_P0P1_DN<17>")
		)
		(pad "CN3" smd circle
			(at -35.797236 6.758686 270)
			(size 0.4318 0.4318)
			(layers "F.Cu" "F.Mask" "F.Paste")
			(net "PVCCINFAON_CPU1")
		)
		(pad "CN5" smd circle
			(at -34.169604 6.758686 270)
			(size 0.4318 0.4318)
			(layers "F.Cu" "F.Mask" "F.Paste")
			(net "UPI_CPU1_CPU0_P1P0_DN<16>")
		)
		(pad "CN7" smd circle
			(at -32.541718 6.758686 270)
			(size 0.4318 0.4318)
			(layers "F.Cu" "F.Mask" "F.Paste")
			(net "PVCCINFAON_CPU1")
		)
		(pad "CN9" smd circle
			(at -30.914086 6.758686 270)
			(size 0.4318 0.4318)
			(layers "F.Cu" "F.Mask" "F.Paste")
			(net "P5E_CPU1_PE1_RX_DP<0>")
		)
		(pad "CN11" smd circle
			(at -29.2862 6.758686 270)
			(size 0.4318 0.4318)
			(layers "F.Cu" "F.Mask" "F.Paste")
			(net "PVCCINFAON_CPU1")
		)
		(pad "CN13" smd circle
			(at -27.658314 6.758686 270)
			(size 0.4318 0.4318)
			(layers "F.Cu" "F.Mask" "F.Paste")
			(net "P5E_CPU1_PE1_TX_DN<1>")
		)
		(pad "CN15" smd circle
			(at -26.030682 6.758686 270)
			(size 0.4318 0.4318)
			(layers "F.Cu" "F.Mask" "F.Paste")
			(net "PVCCINFAON_CPU1")
		)
		(pad "CN17" smd circle
			(at -24.402796 6.758686 270)
			(size 0.4318 0.4318)
			(layers "F.Cu" "F.Mask" "F.Paste")
			(net "TP_DMI_CPU1_PCH_TX_DN<7>")
		)
		(pad "CN19" smd circle
			(at -22.77491 6.758686 270)
			(size 0.4318 0.4318)
			(layers "F.Cu" "F.Mask" "F.Paste")
			(net "PVCCINFAON_CPU1")
		)
		(pad "CN21" smd circle
			(at -21.147278 6.758686 270)
			(size 0.4318 0.4318)
			(layers "F.Cu" "F.Mask" "F.Paste")
			(net "TP_FM_IBL_SLPS4_CPU1_R_N")
		)
		(pad "CN23" smd circle
			(at -19.519392 6.758686 270)
			(size 0.4318 0.4318)
			(layers "F.Cu" "F.Mask" "F.Paste")
			(net "NC_FM_IBL_ADR_ACK_CPU1")
		)
		(pad "CN25" smd circle
			(at -17.89176 6.758686 270)
			(size 0.4318 0.4318)
			(layers "F.Cu" "F.Mask" "F.Paste")
			(net "H_CPU0_PMDOWN_CPU1")
		)
		(pad "CN60" smd circle
			(at 12.19454 6.868668 270)
			(size 0.4318 0.4318)
			(layers "F.Cu" "F.Mask" "F.Paste")
			(net "NC_CPU1_LGSSPARE1")
		)
		(pad "CN62" smd circle
			(at 13.822426 6.868668 270)
			(size 0.4318 0.4318)
			(layers "F.Cu" "F.Mask" "F.Paste")
			(net "CPU1_RSVD<120>")
		)
		(pad "CN64" smd circle
			(at 15.450058 6.868668 270)
			(size 0.4318 0.4318)
			(layers "F.Cu" "F.Mask" "F.Paste")
			(net "PVCCINFAON_CPU1")
		)
		(pad "CN66" smd circle
			(at 17.07769 6.868668 270)
			(size 0.4318 0.4318)
			(layers "F.Cu" "F.Mask" "F.Paste")
			(net "PVCCINFAON_CPU1")
		)
		(pad "CN68" smd circle
			(at 18.705576 6.868668 270)
			(size 0.4318 0.4318)
			(layers "F.Cu" "F.Mask" "F.Paste")
			(net "GND")
		)
		(pad "CN70" smd circle
			(at 20.333462 6.868668 270)
			(size 0.4318 0.4318)
			(layers "F.Cu" "F.Mask" "F.Paste")
			(net "GND")
		)
		(pad "CN72" smd circle
			(at 21.961094 6.868668 270)
			(size 0.4318 0.4318)
			(layers "F.Cu" "F.Mask" "F.Paste")
			(net "GND")
		)
		(pad "CN74" smd circle
			(at 23.58898 6.868668 270)
			(size 0.4318 0.4318)
			(layers "F.Cu" "F.Mask" "F.Paste")
			(net "GND")
		)
		(pad "CN76" smd circle
			(at 25.216612 6.868668 270)
			(size 0.4318 0.4318)
			(layers "F.Cu" "F.Mask" "F.Paste")
			(net "GND")
		)
		(pad "CN78" smd circle
			(at 26.844498 6.868668 270)
			(size 0.4318 0.4318)
			(layers "F.Cu" "F.Mask" "F.Paste")
			(net "PVCCFA_EHV_FIVRA_CPU1")
		)
		(pad "CN80" smd circle
			(at 28.472384 6.868668 270)
			(size 0.4318 0.4318)
			(layers "F.Cu" "F.Mask" "F.Paste")
			(net "GND")
		)
		(pad "CN82" smd circle
			(at 30.100016 6.868668 270)
			(size 0.4318 0.4318)
			(layers "F.Cu" "F.Mask" "F.Paste")
			(net "GND")
		)
		(pad "CN84" smd circle
			(at 31.727902 6.868668 270)
			(size 0.4318 0.4318)
			(layers "F.Cu" "F.Mask" "F.Paste")
			(net "GND")
		)
		(pad "CN86" smd circle
			(at 33.355534 6.868668 270)
			(size 0.4318 0.4318)
			(layers "F.Cu" "F.Mask" "F.Paste")
			(net "GND")
		)
		(pad "CN88" smd circle
			(at 34.98342 6.868668 270)
			(size 0.4318 0.4318)
			(layers "F.Cu" "F.Mask" "F.Paste")
			(net "PVCCIN_CPU1")
		)
		(pad "CN90" smd circle
			(at 36.611306 6.868668 270)
			(size 0.4318 0.4318)
			(layers "F.Cu" "F.Mask" "F.Paste")
			(net "PVCCIN_CPU1")
		)
		(pad "CP2" smd circle
			(at -36.611306 7.228332 270)
			(size 0.4318 0.4318)
			(layers "F.Cu" "F.Mask" "F.Paste")
			(net "UPI_CPU0_CPU1_P0P1_DP<17>")
		)
		(pad "CP4" smd circle
			(at -34.98342 7.228332 270)
			(size 0.4318 0.4318)
			(layers "F.Cu" "F.Mask" "F.Paste")
			(net "GND")
		)
		(pad "CP6" smd circle
			(at -33.355534 7.228332 270)
			(size 0.4318 0.4318)
			(layers "F.Cu" "F.Mask" "F.Paste")
			(net "UPI_CPU1_CPU0_P1P0_DP<16>")
		)
		(pad "CP8" smd circle
			(at -31.727902 7.228332 270)
			(size 0.4318 0.4318)
			(layers "F.Cu" "F.Mask" "F.Paste")
			(net "GND")
		)
		(pad "CP10" smd circle
			(at -30.100016 7.228332 270)
			(size 0.4318 0.4318)
			(layers "F.Cu" "F.Mask" "F.Paste")
			(net "P5E_CPU1_PE1_RX_DN<0>")
		)
		(pad "CP12" smd circle
			(at -28.472384 7.228332 270)
			(size 0.4318 0.4318)
			(layers "F.Cu" "F.Mask" "F.Paste")
			(net "GND")
		)
		(pad "CP14" smd circle
			(at -26.844498 7.228332 270)
			(size 0.4318 0.4318)
			(layers "F.Cu" "F.Mask" "F.Paste")
			(net "P5E_CPU1_PE1_TX_DN<0>")
		)
		(pad "CP16" smd circle
			(at -25.216612 7.228332 270)
			(size 0.4318 0.4318)
			(layers "F.Cu" "F.Mask" "F.Paste")
			(net "GND")
		)
		(pad "CP18" smd circle
			(at -23.58898 7.228332 270)
			(size 0.4318 0.4318)
			(layers "F.Cu" "F.Mask" "F.Paste")
			(net "GND")
		)
		(pad "CP20" smd circle
			(at -21.961094 7.228332 270)
			(size 0.4318 0.4318)
			(layers "F.Cu" "F.Mask" "F.Paste")
			(net "H_CPU1_PM_FAST_WAKE_N")
		)
		(pad "CP22" smd circle
			(at -20.333462 7.228332 270)
			(size 0.4318 0.4318)
			(layers "F.Cu" "F.Mask" "F.Paste")
			(net "TP_JTAG_CPU1_PLD_TDO_R")
		)
		(pad "CP24" smd circle
			(at -18.705576 7.228332 270)
			(size 0.4318 0.4318)
			(layers "F.Cu" "F.Mask" "F.Paste")
			(net "NC_FM_IBL_ADR_COMPLETE_CPU1_R")
		)
		(pad "CP26" smd circle
			(at -17.07769 7.228332 270)
			(size 0.4318 0.4318)
			(layers "F.Cu" "F.Mask" "F.Paste")
			(net "TP_H_SBLINK2_CPU1_PMDOWN")
		)
		(pad "CP61" smd circle
			(at 13.008356 7.338314 270)
			(size 0.4318 0.4318)
			(layers "F.Cu" "F.Mask" "F.Paste")
			(net "NC_CPU1_LGSSPARE5")
		)
		(pad "CP63" smd circle
			(at 14.635988 7.338314 270)
			(size 0.4318 0.4318)
			(layers "F.Cu" "F.Mask" "F.Paste")
			(net "PVCCINFAON_CPU1")
		)
		(pad "CP65" smd circle
			(at 16.263874 7.338314 270)
			(size 0.4318 0.4318)
			(layers "F.Cu" "F.Mask" "F.Paste")
			(net "PVCCINFAON_CPU1")
		)
		(pad "CP67" smd circle
			(at 17.89176 7.338314 270)
			(size 0.4318 0.4318)
			(layers "F.Cu" "F.Mask" "F.Paste")
			(net "PVCCINFAON_CPU1")
		)
		(pad "CP69" smd circle
			(at 19.519392 7.338314 270)
			(size 0.4318 0.4318)
			(layers "F.Cu" "F.Mask" "F.Paste")
			(net "NC_CPU1_UPI3_APROBE<0>")
		)
		(pad "CP71" smd circle
			(at 21.147278 7.338314 270)
			(size 0.4318 0.4318)
			(layers "F.Cu" "F.Mask" "F.Paste")
			(net "PD_PIROM_CPU1_ADDR2")
		)
		(pad "CP73" smd circle
			(at 22.77491 7.338314 270)
			(size 0.4318 0.4318)
			(layers "F.Cu" "F.Mask" "F.Paste")
			(net "PVCCFA_EHV_FIVRA_CPU1")
		)
		(pad "CP75" smd circle
			(at 24.402796 7.338314 270)
			(size 0.4318 0.4318)
			(layers "F.Cu" "F.Mask" "F.Paste")
			(net "GND")
		)
		(pad "CP77" smd circle
			(at 26.030682 7.338314 270)
			(size 0.4318 0.4318)
			(layers "F.Cu" "F.Mask" "F.Paste")
			(net "GND")
		)
		(pad "CP79" smd circle
			(at 27.658314 7.338314 270)
			(size 0.4318 0.4318)
			(layers "F.Cu" "F.Mask" "F.Paste")
			(net "GND")
		)
		(pad "CP81" smd circle
			(at 29.2862 7.338314 270)
			(size 0.4318 0.4318)
			(layers "F.Cu" "F.Mask" "F.Paste")
			(net "GND")
		)
		(pad "CP83" smd circle
			(at 30.914086 7.338314 270)
			(size 0.4318 0.4318)
			(layers "F.Cu" "F.Mask" "F.Paste")
			(net "GND")
		)
		(pad "CP85" smd circle
			(at 32.541718 7.338314 270)
			(size 0.4318 0.4318)
			(layers "F.Cu" "F.Mask" "F.Paste")
			(net "P5E_CPU1_PE3_TX_DN<15>")
		)
		(pad "CP87" smd circle
			(at 34.169604 7.338314 270)
			(size 0.4318 0.4318)
			(layers "F.Cu" "F.Mask" "F.Paste")
			(net "GND")
		)
		(pad "CP89" smd circle
			(at 35.797236 7.338314 270)
			(size 0.4318 0.4318)
			(layers "F.Cu" "F.Mask" "F.Paste")
			(net "PVCCIN_CPU1")
		)
		(pad "CP91" smd oval
			(at 37.425122 7.338314)
			(size 0.381 0.4826)
			(drill
				(offset 0 -0.0508)
			)
			(layers "F.Cu" "F.Mask" "F.Paste")
			(net "GND")
		)
		(pad "CR1" smd oval
			(at -37.425122 7.698486 180)
			(size 0.381 0.4826)
			(drill
				(offset 0 -0.0508)
			)
			(layers "F.Cu" "F.Mask" "F.Paste")
			(net "GND")
		)
		(pad "CR3" smd circle
			(at -35.797236 7.698486 270)
			(size 0.4318 0.4318)
			(layers "F.Cu" "F.Mask" "F.Paste")
			(net "UPI_CPU0_CPU1_P0P1_DN<16>")
		)
		(pad "CR5" smd circle
			(at -34.169604 7.698486 270)
			(size 0.4318 0.4318)
			(layers "F.Cu" "F.Mask" "F.Paste")
			(net "GND")
		)
		(pad "CR7" smd circle
			(at -32.541718 7.698486 270)
			(size 0.4318 0.4318)
			(layers "F.Cu" "F.Mask" "F.Paste")
			(net "UPI_CPU1_CPU0_P1P0_DP<15>")
		)
		(pad "CR9" smd circle
			(at -30.914086 7.698486 270)
			(size 0.4318 0.4318)
			(layers "F.Cu" "F.Mask" "F.Paste")
			(net "GND")
		)
		(pad "CR11" smd circle
			(at -29.2862 7.698486 270)
			(size 0.4318 0.4318)
			(layers "F.Cu" "F.Mask" "F.Paste")
			(net "GND")
		)
		(pad "CR13" smd circle
			(at -27.658314 7.698486 270)
			(size 0.4318 0.4318)
			(layers "F.Cu" "F.Mask" "F.Paste")
			(net "GND")
		)
		(pad "CR15" smd circle
			(at -26.030682 7.698486 270)
			(size 0.4318 0.4318)
			(layers "F.Cu" "F.Mask" "F.Paste")
			(net "P5E_CPU1_PE1_TX_DP<0>")
		)
		(pad "CR17" smd circle
			(at -24.402796 7.698486 270)
			(size 0.4318 0.4318)
			(layers "F.Cu" "F.Mask" "F.Paste")
			(net "GND")
		)
		(pad "CR19" smd circle
			(at -22.77491 7.698486 270)
			(size 0.4318 0.4318)
			(layers "F.Cu" "F.Mask" "F.Paste")
			(net "TP_H_SBLINK5_CPU1_PMSYNC")
		)
		(pad "CR21" smd circle
			(at -21.147278 7.698486 270)
			(size 0.4318 0.4318)
			(layers "F.Cu" "F.Mask" "F.Paste")
			(net "TP_FM_IBL_SLPS3_CPU1_R_N")
		)
		(pad "CR23" smd circle
			(at -19.519392 7.698486 270)
			(size 0.4318 0.4318)
			(layers "F.Cu" "F.Mask" "F.Paste")
			(net "CPU1_RSVD<126>")
		)
		(pad "CR25" smd circle
			(at -17.89176 7.698486 270)
			(size 0.4318 0.4318)
			(layers "F.Cu" "F.Mask" "F.Paste")
			(net "NC_CPU1_VIEWPIN_GNR2")
		)
		(pad "CR60" smd circle
			(at 12.19454 7.808468 270)
			(size 0.4318 0.4318)
			(layers "F.Cu" "F.Mask" "F.Paste")
			(net "NC_CPU1_LGSSPARE0")
		)
		(pad "CR62" smd circle
			(at 13.822426 7.808468 270)
			(size 0.4318 0.4318)
			(layers "F.Cu" "F.Mask" "F.Paste")
			(net "GND")
		)
		(pad "CR64" smd circle
			(at 15.450058 7.808468 270)
			(size 0.4318 0.4318)
			(layers "F.Cu" "F.Mask" "F.Paste")
			(net "GND")
		)
		(pad "CR66" smd circle
			(at 17.07769 7.808468 270)
			(size 0.4318 0.4318)
			(layers "F.Cu" "F.Mask" "F.Paste")
			(net "PVCCINFAON_CPU1")
		)
		(pad "CR68" smd circle
			(at 18.705576 7.808468 270)
			(size 0.4318 0.4318)
			(layers "F.Cu" "F.Mask" "F.Paste")
			(net "NC_CPU1_UPI3_APROBE<1>")
		)
		(pad "CR70" smd circle
			(at 20.333462 7.808468 270)
			(size 0.4318 0.4318)
			(layers "F.Cu" "F.Mask" "F.Paste")
			(net "PU_PIROM_CPU1_ADDR0")
		)
		(pad "CR72" smd circle
			(at 21.961094 7.808468 270)
			(size 0.4318 0.4318)
			(layers "F.Cu" "F.Mask" "F.Paste")
			(net "PU_PIROM_CPU1_SM_WP")
		)
		(pad "CR74" smd circle
			(at 23.58898 7.808468 270)
			(size 0.4318 0.4318)
			(layers "F.Cu" "F.Mask" "F.Paste")
			(net "Net_742")
		)
		(pad "CR76" smd circle
			(at 25.216612 7.808468 270)
			(size 0.4318 0.4318)
			(layers "F.Cu" "F.Mask" "F.Paste")
			(net "Net_719")
		)
		(pad "CR78" smd circle
			(at 26.844498 7.808468 270)
			(size 0.4318 0.4318)
			(layers "F.Cu" "F.Mask" "F.Paste")
			(net "GND")
		)
		(pad "CR80" smd circle
			(at 28.472384 7.808468 270)
			(size 0.4318 0.4318)
			(layers "F.Cu" "F.Mask" "F.Paste")
			(net "GND")
		)
		(pad "CR82" smd circle
			(at 30.100016 7.808468 270)
			(size 0.4318 0.4318)
			(layers "F.Cu" "F.Mask" "F.Paste")
			(net "GND")
		)
		(pad "CR84" smd circle
			(at 31.727902 7.808468 270)
			(size 0.4318 0.4318)
			(layers "F.Cu" "F.Mask" "F.Paste")
			(net "GND")
		)
		(pad "CR86" smd circle
			(at 33.355534 7.808468 270)
			(size 0.4318 0.4318)
			(layers "F.Cu" "F.Mask" "F.Paste")
			(net "P5E_CPU1_PE3_TX_DP<15>")
		)
		(pad "CR88" smd circle
			(at 34.98342 7.808468 270)
			(size 0.4318 0.4318)
			(layers "F.Cu" "F.Mask" "F.Paste")
			(net "GND")
		)
		(pad "CR90" smd circle
			(at 36.611306 7.808468 270)
			(size 0.4318 0.4318)
			(layers "F.Cu" "F.Mask" "F.Paste")
			(net "GND")
		)
		(pad "CT2" smd circle
			(at -36.611306 8.168132 270)
			(size 0.4318 0.4318)
			(layers "F.Cu" "F.Mask" "F.Paste")
			(net "UPI_CPU0_CPU1_P0P1_DP<16>")
		)
		(pad "CT4" smd circle
			(at -34.98342 8.168132 270)
			(size 0.4318 0.4318)
			(layers "F.Cu" "F.Mask" "F.Paste")
			(net "GND")
		)
		(pad "CT6" smd circle
			(at -33.355534 8.168132 270)
			(size 0.4318 0.4318)
			(layers "F.Cu" "F.Mask" "F.Paste")
			(net "UPI_CPU1_CPU0_P1P0_DN<15>")
		)
		(pad "CT8" smd circle
			(at -31.727902 8.168132 270)
			(size 0.4318 0.4318)
			(layers "F.Cu" "F.Mask" "F.Paste")
			(net "GND")
		)
		(pad "CT10" smd circle
			(at -30.100016 8.168132 270)
			(size 0.4318 0.4318)
			(layers "F.Cu" "F.Mask" "F.Paste")
			(net "GND")
		)
		(pad "CT12" smd circle
			(at -28.472384 8.168132 270)
			(size 0.4318 0.4318)
			(layers "F.Cu" "F.Mask" "F.Paste")
			(net "GND")
		)
		(pad "CT14" smd circle
			(at -26.844498 8.168132 270)
			(size 0.4318 0.4318)
			(layers "F.Cu" "F.Mask" "F.Paste")
			(net "P5E_CPU1_PE2_TX_DP<0>")
		)
		(pad "CT16" smd circle
			(at -25.216612 8.168132 270)
			(size 0.4318 0.4318)
			(layers "F.Cu" "F.Mask" "F.Paste")
			(net "GND")
		)
		(pad "CT18" smd circle
			(at -23.58898 8.168132 270)
			(size 0.4318 0.4318)
			(layers "F.Cu" "F.Mask" "F.Paste")
			(net "I3C_SPD_DDREFGH_CPU1_SDA")
		)
		(pad "CT20" smd circle
			(at -21.961094 8.168132 270)
			(size 0.4318 0.4318)
			(layers "F.Cu" "F.Mask" "F.Paste")
			(net "PD_CPU1_TXT_PLTEN")
		)
		(pad "CT22" smd circle
			(at -20.333462 8.168132 270)
			(size 0.4318 0.4318)
			(layers "F.Cu" "F.Mask" "F.Paste")
			(net "TP_JTAG_CPU1_PLD_TDI")
		)
		(pad "CT24" smd circle
			(at -18.705576 8.168132 270)
			(size 0.4318 0.4318)
			(layers "F.Cu" "F.Mask" "F.Paste")
			(net "NC_FM_IBL_ADR_TRIGGER_CPU1_R")
		)
		(pad "CT26" smd circle
			(at -17.07769 8.168132 270)
			(size 0.4318 0.4318)
			(layers "F.Cu" "F.Mask" "F.Paste")
			(net "NC_CPU1_VIEWPIN_GNR0")
		)
		(pad "CT61" smd circle
			(at 13.008356 8.278114 270)
			(size 0.4318 0.4318)
			(layers "F.Cu" "F.Mask" "F.Paste")
			(net "PU_CPU1_SOCKET_ID2")
		)
		(pad "CT63" smd circle
			(at 14.635988 8.278114 270)
			(size 0.4318 0.4318)
			(layers "F.Cu" "F.Mask" "F.Paste")
			(net "PVCCINFAON_CPU1")
		)
		(pad "CT65" smd circle
			(at 16.263874 8.278114 270)
			(size 0.4318 0.4318)
			(layers "F.Cu" "F.Mask" "F.Paste")
			(net "PVCCINFAON_CPU1")
		)
		(pad "CT67" smd circle
			(at 17.89176 8.278114 270)
			(size 0.4318 0.4318)
			(layers "F.Cu" "F.Mask" "F.Paste")
			(net "PVCCINFAON_CPU1")
		)
		(pad "CT69" smd circle
			(at 19.519392 8.278114 270)
			(size 0.4318 0.4318)
			(layers "F.Cu" "F.Mask" "F.Paste")
			(net "GND")
		)
		(pad "CT71" smd circle
			(at 21.147278 8.278114 270)
			(size 0.4318 0.4318)
			(layers "F.Cu" "F.Mask" "F.Paste")
			(net "PD_PIROM_CPU1_ADDR1")
		)
		(pad "CT73" smd circle
			(at 22.77491 8.278114 270)
			(size 0.4318 0.4318)
			(layers "F.Cu" "F.Mask" "F.Paste")
			(net "GND")
		)
		(pad "CT75" smd circle
			(at 24.402796 8.278114 270)
			(size 0.4318 0.4318)
			(layers "F.Cu" "F.Mask" "F.Paste")
			(net "Net_743")
		)
		(pad "CT77" smd circle
			(at 26.030682 8.278114 270)
			(size 0.4318 0.4318)
			(layers "F.Cu" "F.Mask" "F.Paste")
			(net "PVCCFA_EHV_FIVRA_CPU1")
		)
		(pad "CT79" smd circle
			(at 27.658314 8.278114 270)
			(size 0.4318 0.4318)
			(layers "F.Cu" "F.Mask" "F.Paste")
			(net "GND")
		)
		(pad "CT81" smd circle
			(at 29.2862 8.278114 270)
			(size 0.4318 0.4318)
			(layers "F.Cu" "F.Mask" "F.Paste")
			(net "GND")
		)
		(pad "CT83" smd circle
			(at 30.914086 8.278114 270)
			(size 0.4318 0.4318)
			(layers "F.Cu" "F.Mask" "F.Paste")
			(net "GND")
		)
		(pad "CT85" smd circle
			(at 32.541718 8.278114 270)
			(size 0.4318 0.4318)
			(layers "F.Cu" "F.Mask" "F.Paste")
			(net "PVCCFA_EHV_FIVRA_CPU1")
		)
		(pad "CT87" smd circle
			(at 34.169604 8.278114 270)
			(size 0.4318 0.4318)
			(layers "F.Cu" "F.Mask" "F.Paste")
			(net "P5E_CPU1_PE3_TX_DN<14>")
		)
		(pad "CT89" smd circle
			(at 35.797236 8.278114 270)
			(size 0.4318 0.4318)
			(layers "F.Cu" "F.Mask" "F.Paste")
			(net "GND")
		)
		(pad "CT91" smd oval
			(at 37.425122 8.278114)
			(size 0.381 0.4826)
			(drill
				(offset 0 -0.0508)
			)
			(layers "F.Cu" "F.Mask" "F.Paste")
			(net "P5E_CPU1_PE3_RX_DP<15>")
		)
		(pad "CU1" smd oval
			(at -37.425122 8.638286 180)
			(size 0.381 0.4826)
			(drill
				(offset 0 -0.0508)
			)
			(layers "F.Cu" "F.Mask" "F.Paste")
			(net "UPI_CPU0_CPU1_P0P1_DP<15>")
		)
		(pad "CU3" smd circle
			(at -35.797236 8.638286 270)
			(size 0.4318 0.4318)
			(layers "F.Cu" "F.Mask" "F.Paste")
			(net "PVCCINFAON_CPU1")
		)
		(pad "CU5" smd circle
			(at -34.169604 8.638286 270)
			(size 0.4318 0.4318)
			(layers "F.Cu" "F.Mask" "F.Paste")
			(net "UPI_CPU1_CPU0_P1P0_DN<14>")
		)
		(pad "CU7" smd circle
			(at -32.541718 8.638286 270)
			(size 0.4318 0.4318)
			(layers "F.Cu" "F.Mask" "F.Paste")
			(net "PVCCINFAON_CPU1")
		)
		(pad "CU9" smd circle
			(at -30.914086 8.638286 270)
			(size 0.4318 0.4318)
			(layers "F.Cu" "F.Mask" "F.Paste")
			(net "P5E_CPU1_PE2_RX_DN<0>")
		)
		(pad "CU11" smd circle
			(at -29.2862 8.638286 270)
			(size 0.4318 0.4318)
			(layers "F.Cu" "F.Mask" "F.Paste")
			(net "PVCCINFAON_CPU1")
		)
		(pad "CU13" smd circle
			(at -27.658314 8.638286 270)
			(size 0.4318 0.4318)
			(layers "F.Cu" "F.Mask" "F.Paste")
			(net "P5E_CPU1_PE2_TX_DN<0>")
		)
		(pad "CU15" smd circle
			(at -26.030682 8.638286 270)
			(size 0.4318 0.4318)
			(layers "F.Cu" "F.Mask" "F.Paste")
			(net "PVCCINFAON_CPU1")
		)
		(pad "CU17" smd circle
			(at -24.402796 8.638286 270)
			(size 0.4318 0.4318)
			(layers "F.Cu" "F.Mask" "F.Paste")
			(net "I3C_SPD_DDREFGH_CPU1_SCL")
		)
		(pad "CU19" smd circle
			(at -22.77491 8.638286 270)
			(size 0.4318 0.4318)
			(layers "F.Cu" "F.Mask" "F.Paste")
			(net "GND")
		)
		(pad "CU21" smd circle
			(at -21.147278 8.638286 270)
			(size 0.4318 0.4318)
			(layers "F.Cu" "F.Mask" "F.Paste")
			(net "GND")
		)
		(pad "CU23" smd circle
			(at -19.519392 8.638286 270)
			(size 0.4318 0.4318)
			(layers "F.Cu" "F.Mask" "F.Paste")
			(net "GND")
		)
		(pad "CU25" smd circle
			(at -17.89176 8.638286 270)
			(size 0.4318 0.4318)
			(layers "F.Cu" "F.Mask" "F.Paste")
			(net "GND")
		)
		(pad "CU60" smd circle
			(at 12.19454 8.748268 270)
			(size 0.4318 0.4318)
			(layers "F.Cu" "F.Mask" "F.Paste")
			(net "GND")
		)
		(pad "CU62" smd circle
			(at 13.822426 8.748268 270)
			(size 0.4318 0.4318)
			(layers "F.Cu" "F.Mask" "F.Paste")
			(net "NC_CPU1_LGSSPARE2")
		)
		(pad "CU64" smd circle
			(at 15.450058 8.748268 270)
			(size 0.4318 0.4318)
			(layers "F.Cu" "F.Mask" "F.Paste")
			(net "PVCCINFAON_CPU1")
		)
		(pad "CU66" smd circle
			(at 17.07769 8.748268 270)
			(size 0.4318 0.4318)
			(layers "F.Cu" "F.Mask" "F.Paste")
			(net "GND")
		)
		(pad "CU68" smd circle
			(at 18.705576 8.748268 270)
			(size 0.4318 0.4318)
			(layers "F.Cu" "F.Mask" "F.Paste")
			(net "GND")
		)
		(pad "CU70" smd circle
			(at 20.333462 8.748268 270)
			(size 0.4318 0.4318)
			(layers "F.Cu" "F.Mask" "F.Paste")
			(net "SMB_S3M_CPU1_PIROM_3V3AUX_SCL_1")
		)
		(pad "CU72" smd circle
			(at 21.961094 8.748268 270)
			(size 0.4318 0.4318)
			(layers "F.Cu" "F.Mask" "F.Paste")
			(net "GND")
		)
		(pad "CU74" smd circle
			(at 23.58898 8.748268 270)
			(size 0.4318 0.4318)
			(layers "F.Cu" "F.Mask" "F.Paste")
			(net "Net_718")
		)
		(pad "CU76" smd circle
			(at 25.216612 8.748268 270)
			(size 0.4318 0.4318)
			(layers "F.Cu" "F.Mask" "F.Paste")
			(net "Net_744")
		)
		(pad "CU78" smd circle
			(at 26.844498 8.748268 270)
			(size 0.4318 0.4318)
			(layers "F.Cu" "F.Mask" "F.Paste")
			(net "GND")
		)
		(pad "CU80" smd circle
			(at 28.472384 8.748268 270)
			(size 0.4318 0.4318)
			(layers "F.Cu" "F.Mask" "F.Paste")
			(net "GND")
		)
		(pad "CU82" smd circle
			(at 30.100016 8.748268 270)
			(size 0.4318 0.4318)
			(layers "F.Cu" "F.Mask" "F.Paste")
			(net "GND")
		)
		(pad "CU84" smd circle
			(at 31.727902 8.748268 270)
			(size 0.4318 0.4318)
			(layers "F.Cu" "F.Mask" "F.Paste")
			(net "GND")
		)
		(pad "CU86" smd circle
			(at 33.355534 8.748268 270)
			(size 0.4318 0.4318)
			(layers "F.Cu" "F.Mask" "F.Paste")
			(net "P5E_CPU1_PE3_TX_DP<14>")
		)
		(pad "CU88" smd circle
			(at 34.98342 8.748268 270)
			(size 0.4318 0.4318)
			(layers "F.Cu" "F.Mask" "F.Paste")
			(net "GND")
		)
		(pad "CU90" smd circle
			(at 36.611306 8.748268 270)
			(size 0.4318 0.4318)
			(layers "F.Cu" "F.Mask" "F.Paste")
			(net "P5E_CPU1_PE3_RX_DN<15>")
		)
		(pad "CV2" smd circle
			(at -36.611306 9.107932 270)
			(size 0.4318 0.4318)
			(layers "F.Cu" "F.Mask" "F.Paste")
			(net "UPI_CPU0_CPU1_P0P1_DN<15>")
		)
		(pad "CV4" smd circle
			(at -34.98342 9.107932 270)
			(size 0.4318 0.4318)
			(layers "F.Cu" "F.Mask" "F.Paste")
			(net "GND")
		)
		(pad "CV6" smd circle
			(at -33.355534 9.107932 270)
			(size 0.4318 0.4318)
			(layers "F.Cu" "F.Mask" "F.Paste")
			(net "UPI_CPU1_CPU0_P1P0_DP<14>")
		)
		(pad "CV8" smd circle
			(at -31.727902 9.107932 270)
			(size 0.4318 0.4318)
			(layers "F.Cu" "F.Mask" "F.Paste")
			(net "GND")
		)
		(pad "CV10" smd circle
			(at -30.100016 9.107932 270)
			(size 0.4318 0.4318)
			(layers "F.Cu" "F.Mask" "F.Paste")
			(net "P5E_CPU1_PE2_RX_DP<0>")
		)
		(pad "CV12" smd circle
			(at -28.472384 9.107932 270)
			(size 0.4318 0.4318)
			(layers "F.Cu" "F.Mask" "F.Paste")
			(net "GND")
		)
		(pad "CV14" smd circle
			(at -26.844498 9.107932 270)
			(size 0.4318 0.4318)
			(layers "F.Cu" "F.Mask" "F.Paste")
			(net "P5E_CPU1_PE2_TX_DN<1>")
		)
		(pad "CV16" smd circle
			(at -25.216612 9.107932 270)
			(size 0.4318 0.4318)
			(layers "F.Cu" "F.Mask" "F.Paste")
			(net "GND")
		)
		(pad "CV18" smd circle
			(at -23.58898 9.107932 270)
			(size 0.4318 0.4318)
			(layers "F.Cu" "F.Mask" "F.Paste")
			(net "TP_H_SBLINK5_CPU1_PMDOWN")
		)
		(pad "CV20" smd circle
			(at -21.961094 9.107932 270)
			(size 0.4318 0.4318)
			(layers "F.Cu" "F.Mask" "F.Paste")
			(net "PWRGD_PLT_AUX_CPU1_LVT3")
		)
		(pad "CV22" smd circle
			(at -20.333462 9.107932 270)
			(size 0.4318 0.4318)
			(layers "F.Cu" "F.Mask" "F.Paste")
			(net "TP_JTAG_CPU1_PLD_TMS")
		)
		(pad "CV24" smd circle
			(at -18.705576 9.107932 270)
			(size 0.4318 0.4318)
			(layers "F.Cu" "F.Mask" "F.Paste")
			(net "CPU1_RSVD<135>")
		)
		(pad "CV26" smd circle
			(at -17.07769 9.107932 270)
			(size 0.4318 0.4318)
			(layers "F.Cu" "F.Mask" "F.Paste")
			(net "GND")
		)
		(pad "CV61" smd circle
			(at 13.008356 9.217914 270)
			(size 0.4318 0.4318)
			(layers "F.Cu" "F.Mask" "F.Paste")
			(net "PVCCINFAON_CPU1")
		)
		(pad "CV63" smd circle
			(at 14.635988 9.217914 270)
			(size 0.4318 0.4318)
			(layers "F.Cu" "F.Mask" "F.Paste")
			(net "PVCCINFAON_CPU1")
		)
		(pad "CV65" smd circle
			(at 16.263874 9.217914 270)
			(size 0.4318 0.4318)
			(layers "F.Cu" "F.Mask" "F.Paste")
			(net "PVCCINFAON_CPU1")
		)
		(pad "CV67" smd circle
			(at 17.89176 9.217914 270)
			(size 0.4318 0.4318)
			(layers "F.Cu" "F.Mask" "F.Paste")
			(net "PVCCINFAON_CPU1")
		)
		(pad "CV69" smd circle
			(at 19.519392 9.217914 270)
			(size 0.4318 0.4318)
			(layers "F.Cu" "F.Mask" "F.Paste")
			(net "NC_UART_IBL_CPU1_TXD")
		)
		(pad "CV71" smd circle
			(at 21.147278 9.217914 270)
			(size 0.4318 0.4318)
			(layers "F.Cu" "F.Mask" "F.Paste")
			(net "NC_UART_IBL_CPU1_CTS")
		)
		(pad "CV73" smd circle
			(at 22.77491 9.217914 270)
			(size 0.4318 0.4318)
			(layers "F.Cu" "F.Mask" "F.Paste")
			(net "Net_734")
		)
		(pad "CV75" smd circle
			(at 24.402796 9.217914 270)
			(size 0.4318 0.4318)
			(layers "F.Cu" "F.Mask" "F.Paste")
			(net "GND")
		)
		(pad "CV77" smd circle
			(at 26.030682 9.217914 270)
			(size 0.4318 0.4318)
			(layers "F.Cu" "F.Mask" "F.Paste")
			(net "Net_720")
		)
		(pad "CV79" smd circle
			(at 27.658314 9.217914 270)
			(size 0.4318 0.4318)
			(layers "F.Cu" "F.Mask" "F.Paste")
			(net "GND")
		)
		(pad "CV81" smd circle
			(at 29.2862 9.217914 270)
			(size 0.4318 0.4318)
			(layers "F.Cu" "F.Mask" "F.Paste")
			(net "GND")
		)
		(pad "CV83" smd circle
			(at 30.914086 9.217914 270)
			(size 0.4318 0.4318)
			(layers "F.Cu" "F.Mask" "F.Paste")
			(net "GND")
		)
		(pad "CV85" smd circle
			(at 32.541718 9.217914 270)
			(size 0.4318 0.4318)
			(layers "F.Cu" "F.Mask" "F.Paste")
			(net "P5E_CPU1_PE3_TX_DN<13>")
		)
		(pad "CV87" smd circle
			(at 34.169604 9.217914 270)
			(size 0.4318 0.4318)
			(layers "F.Cu" "F.Mask" "F.Paste")
			(net "GND")
		)
		(pad "CV89" smd circle
			(at 35.797236 9.217914 270)
			(size 0.4318 0.4318)
			(layers "F.Cu" "F.Mask" "F.Paste")
			(net "P5E_CPU1_PE3_RX_DN<14>")
		)
		(pad "CV91" smd oval
			(at 37.425122 9.217914)
			(size 0.381 0.4826)
			(drill
				(offset 0 -0.0508)
			)
			(layers "F.Cu" "F.Mask" "F.Paste")
			(net "GND")
		)
		(pad "CW1" smd oval
			(at -37.425122 9.578086 180)
			(size 0.381 0.4826)
			(drill
				(offset 0 -0.0508)
			)
			(layers "F.Cu" "F.Mask" "F.Paste")
			(net "GND")
		)
		(pad "CW3" smd circle
			(at -35.797236 9.578086 270)
			(size 0.4318 0.4318)
			(layers "F.Cu" "F.Mask" "F.Paste")
			(net "UPI_CPU0_CPU1_P0P1_DP<14>")
		)
		(pad "CW5" smd circle
			(at -34.169604 9.578086 270)
			(size 0.4318 0.4318)
			(layers "F.Cu" "F.Mask" "F.Paste")
			(net "GND")
		)
		(pad "CW7" smd circle
			(at -32.541718 9.578086 270)
			(size 0.4318 0.4318)
			(layers "F.Cu" "F.Mask" "F.Paste")
			(net "UPI_CPU1_CPU0_P1P0_DP<13>")
		)
		(pad "CW9" smd circle
			(at -30.914086 9.578086 270)
			(size 0.4318 0.4318)
			(layers "F.Cu" "F.Mask" "F.Paste")
			(net "GND")
		)
		(pad "CW11" smd circle
			(at -29.2862 9.578086 270)
			(size 0.4318 0.4318)
			(layers "F.Cu" "F.Mask" "F.Paste")
			(net "P5E_CPU1_PE2_RX_DP<1>")
		)
		(pad "CW13" smd circle
			(at -27.658314 9.578086 270)
			(size 0.4318 0.4318)
			(layers "F.Cu" "F.Mask" "F.Paste")
			(net "GND")
		)
		(pad "CW15" smd circle
			(at -26.030682 9.578086 270)
			(size 0.4318 0.4318)
			(layers "F.Cu" "F.Mask" "F.Paste")
			(net "P5E_CPU1_PE2_TX_DP<1>")
		)
		(pad "CW17" smd circle
			(at -24.402796 9.578086 270)
			(size 0.4318 0.4318)
			(layers "F.Cu" "F.Mask" "F.Paste")
			(net "GND")
		)
		(pad "CW19" smd circle
			(at -22.77491 9.578086 270)
			(size 0.4318 0.4318)
			(layers "F.Cu" "F.Mask" "F.Paste")
			(net "PU_CPU1_UPI1_AC_COUPLING")
		)
		(pad "CW21" smd circle
			(at -21.147278 9.578086 270)
			(size 0.4318 0.4318)
			(layers "F.Cu" "F.Mask" "F.Paste")
			(net "TP_FM_IBL_SLPS5_CPU1_R_N")
		)
		(pad "CW23" smd circle
			(at -19.519392 9.578086 270)
			(size 0.4318 0.4318)
			(layers "F.Cu" "F.Mask" "F.Paste")
			(net "CPU1_RSVD<139>")
		)
		(pad "CW25" smd circle
			(at -17.89176 9.578086 270)
			(size 0.4318 0.4318)
			(layers "F.Cu" "F.Mask" "F.Paste")
			(net "CPU1_RSVD<140>")
		)
		(pad "CW27" smd circle
			(at -16.263874 9.578086 270)
			(size 0.4318 0.4318)
			(layers "F.Cu" "F.Mask" "F.Paste")
			(net "CLK_100M_DB2000_CPU1_BCLK3_DN")
		)
		(pad "CW29" smd circle
			(at -14.635988 9.578086 270)
			(size 0.4318 0.4318)
			(layers "F.Cu" "F.Mask" "F.Paste")
			(net "CLK_100M_DB2000_CPU1_BCLK1_DP")
		)
		(pad "CW31" smd circle
			(at -13.008356 9.578086 270)
			(size 0.4318 0.4318)
			(layers "F.Cu" "F.Mask" "F.Paste")
			(net "CLK_25M_NSSC_CPU1_DN")
		)
		(pad "CW33" smd circle
			(at -11.380724 9.578086 270)
			(size 0.4318 0.4318)
			(layers "F.Cu" "F.Mask" "F.Paste")
			(net "GND")
		)
		(pad "CW35" smd circle
			(at -9.752838 9.578086 270)
			(size 0.4318 0.4318)
			(layers "F.Cu" "F.Mask" "F.Paste")
			(net "PVCCD_HV_CPU1")
		)
		(pad "CW37" smd circle
			(at -8.124952 9.578086 270)
			(size 0.4318 0.4318)
			(layers "F.Cu" "F.Mask" "F.Paste")
			(net "PVCCD_HV_CPU1")
		)
		(pad "CW39" smd circle
			(at -6.49732 9.578086 270)
			(size 0.4318 0.4318)
			(layers "F.Cu" "F.Mask" "F.Paste")
			(net "H_CPU0_PMSYNC_CPU1")
		)
		(pad "CW41" smd circle
			(at -4.869434 9.578086 270)
			(size 0.4318 0.4318)
			(layers "F.Cu" "F.Mask" "F.Paste")
			(net "NC_CPU1_HBM1_VIEWDIG1")
		)
		(pad "CW43" smd circle
			(at -3.241802 9.578086 270)
			(size 0.4318 0.4318)
			(layers "F.Cu" "F.Mask" "F.Paste")
			(net "TP_CPU1_SPARE6")
		)
		(pad "CW45" smd circle
			(at -1.613916 9.578086 270)
			(size 0.4318 0.4318)
			(layers "F.Cu" "F.Mask" "F.Paste")
			(net "PWRGD_DRAMPWRGD_CPU1_GH_LVC1_R")
		)
		(pad "CW48" smd circle
			(at 2.427732 9.688068 270)
			(size 0.4318 0.4318)
			(layers "F.Cu" "F.Mask" "F.Paste")
			(net "M_F_CPU1_ALERT_N")
		)
		(pad "CW50" smd circle
			(at 4.055618 9.688068 270)
			(size 0.4318 0.4318)
			(layers "F.Cu" "F.Mask" "F.Paste")
			(net "M_G_CPU1_ALERT_N")
		)
		(pad "CW52" smd circle
			(at 5.68325 9.688068 270)
			(size 0.4318 0.4318)
			(layers "F.Cu" "F.Mask" "F.Paste")
			(net "PVCCD_HV_CPU1")
		)
		(pad "CW54" smd circle
			(at 7.311136 9.688068 270)
			(size 0.4318 0.4318)
			(layers "F.Cu" "F.Mask" "F.Paste")
			(net "PVCCD_HV_CPU1")
		)
		(pad "CW56" smd circle
			(at 8.939022 9.688068 270)
			(size 0.4318 0.4318)
			(layers "F.Cu" "F.Mask" "F.Paste")
			(net "PVCCD_HV_CPU1")
		)
		(pad "CW58" smd circle
			(at 10.566654 9.688068 270)
			(size 0.4318 0.4318)
			(layers "F.Cu" "F.Mask" "F.Paste")
			(net "NC_CPU1_VIEWPIN_GNR1")
		)
		(pad "CW60" smd circle
			(at 12.19454 9.688068 270)
			(size 0.4318 0.4318)
			(layers "F.Cu" "F.Mask" "F.Paste")
			(net "PU_CPU1_SOCKET_ID0")
		)
		(pad "CW62" smd circle
			(at 13.822426 9.688068 270)
			(size 0.4318 0.4318)
			(layers "F.Cu" "F.Mask" "F.Paste")
			(net "PVCCINFAON_CPU1")
		)
		(pad "CW64" smd circle
			(at 15.450058 9.688068 270)
			(size 0.4318 0.4318)
			(layers "F.Cu" "F.Mask" "F.Paste")
			(net "PVCCINFAON_CPU1")
		)
		(pad "CW66" smd circle
			(at 17.07769 9.688068 270)
			(size 0.4318 0.4318)
			(layers "F.Cu" "F.Mask" "F.Paste")
			(net "PVCCINFAON_CPU1")
		)
		(pad "CW68" smd circle
			(at 18.705576 9.688068 270)
			(size 0.4318 0.4318)
			(layers "F.Cu" "F.Mask" "F.Paste")
			(net "CPU1_RSVD<144>")
		)
		(pad "CW70" smd circle
			(at 20.333462 9.688068 270)
			(size 0.4318 0.4318)
			(layers "F.Cu" "F.Mask" "F.Paste")
			(net "GND")
		)
		(pad "CW72" smd circle
			(at 21.961094 9.688068 270)
			(size 0.4318 0.4318)
			(layers "F.Cu" "F.Mask" "F.Paste")
			(net "GND")
		)
		(pad "CW74" smd circle
			(at 23.58898 9.688068 270)
			(size 0.4318 0.4318)
			(layers "F.Cu" "F.Mask" "F.Paste")
			(net "Net_710")
		)
		(pad "CW76" smd circle
			(at 25.216612 9.688068 270)
			(size 0.4318 0.4318)
			(layers "F.Cu" "F.Mask" "F.Paste")
			(net "Net_745")
		)
		(pad "CW78" smd circle
			(at 26.844498 9.688068 270)
			(size 0.4318 0.4318)
			(layers "F.Cu" "F.Mask" "F.Paste")
			(net "GND")
		)
		(pad "CW80" smd circle
			(at 28.472384 9.688068 270)
			(size 0.4318 0.4318)
			(layers "F.Cu" "F.Mask" "F.Paste")
			(net "GND")
		)
		(pad "CW82" smd circle
			(at 30.100016 9.688068 270)
			(size 0.4318 0.4318)
			(layers "F.Cu" "F.Mask" "F.Paste")
			(net "GND")
		)
		(pad "CW84" smd circle
			(at 31.727902 9.688068 270)
			(size 0.4318 0.4318)
			(layers "F.Cu" "F.Mask" "F.Paste")
			(net "GND")
		)
		(pad "CW86" smd circle
			(at 33.355534 9.688068 270)
			(size 0.4318 0.4318)
			(layers "F.Cu" "F.Mask" "F.Paste")
			(net "P5E_CPU1_PE3_TX_DP<13>")
		)
		(pad "CW88" smd circle
			(at 34.98342 9.688068 270)
			(size 0.4318 0.4318)
			(layers "F.Cu" "F.Mask" "F.Paste")
			(net "GND")
		)
		(pad "CW90" smd circle
			(at 36.611306 9.688068 270)
			(size 0.4318 0.4318)
			(layers "F.Cu" "F.Mask" "F.Paste")
			(net "P5E_CPU1_PE3_RX_DP<14>")
		)
		(pad "CY2" smd circle
			(at -36.611306 10.047732 270)
			(size 0.4318 0.4318)
			(layers "F.Cu" "F.Mask" "F.Paste")
			(net "UPI_CPU0_CPU1_P0P1_DN<14>")
		)
		(pad "CY4" smd circle
			(at -34.98342 10.047732 270)
			(size 0.4318 0.4318)
			(layers "F.Cu" "F.Mask" "F.Paste")
			(net "GND")
		)
		(pad "CY6" smd circle
			(at -33.355534 10.047732 270)
			(size 0.4318 0.4318)
			(layers "F.Cu" "F.Mask" "F.Paste")
			(net "UPI_CPU1_CPU0_P1P0_DN<13>")
		)
		(pad "CY8" smd circle
			(at -31.727902 10.047732 270)
			(size 0.4318 0.4318)
			(layers "F.Cu" "F.Mask" "F.Paste")
			(net "GND")
		)
		(pad "CY10" smd circle
			(at -30.100016 10.047732 270)
			(size 0.4318 0.4318)
			(layers "F.Cu" "F.Mask" "F.Paste")
			(net "P5E_CPU1_PE2_RX_DN<1>")
		)
		(pad "CY12" smd circle
			(at -28.472384 10.047732 270)
			(size 0.4318 0.4318)
			(layers "F.Cu" "F.Mask" "F.Paste")
			(net "GND")
		)
		(pad "CY14" smd circle
			(at -26.844498 10.047732 270)
			(size 0.4318 0.4318)
			(layers "F.Cu" "F.Mask" "F.Paste")
			(net "P5E_CPU1_PE2_TX_DP<2>")
		)
		(pad "CY16" smd circle
			(at -25.216612 10.047732 270)
			(size 0.4318 0.4318)
			(layers "F.Cu" "F.Mask" "F.Paste")
			(net "GND")
		)
		(pad "CY18" smd circle
			(at -23.58898 10.047732 270)
			(size 0.4318 0.4318)
			(layers "F.Cu" "F.Mask" "F.Paste")
			(net "GND")
		)
		(pad "CY20" smd circle
			(at -21.961094 10.047732 270)
			(size 0.4318 0.4318)
			(layers "F.Cu" "F.Mask" "F.Paste")
			(net "FM_S3M_CPU1_CPLD_CRC_ERROR")
		)
		(pad "CY22" smd circle
			(at -20.333462 10.047732 270)
			(size 0.4318 0.4318)
			(layers "F.Cu" "F.Mask" "F.Paste")
			(net "PD_JTAG_CPU1_PLD_TCK")
		)
		(pad "CY24" smd circle
			(at -18.705576 10.047732 270)
			(size 0.4318 0.4318)
			(layers "F.Cu" "F.Mask" "F.Paste")
			(net "NC_CPU1_DDR45_VIEWDIG0")
		)
		(pad "CY26" smd circle
			(at -17.07769 10.047732 270)
			(size 0.4318 0.4318)
			(layers "F.Cu" "F.Mask" "F.Paste")
			(net "GND")
		)
		(pad "CY28" smd circle
			(at -15.450058 10.047732 270)
			(size 0.4318 0.4318)
			(layers "F.Cu" "F.Mask" "F.Paste")
			(net "CLK_100M_DB2000_CPU1_BCLK1_DN")
		)
		(pad "CY30" smd circle
			(at -13.822426 10.047732 270)
			(size 0.4318 0.4318)
			(layers "F.Cu" "F.Mask" "F.Paste")
			(net "GND")
		)
		(pad "CY32" smd circle
			(at -12.19454 10.047732 270)
			(size 0.4318 0.4318)
			(layers "F.Cu" "F.Mask" "F.Paste")
			(net "CLK_25M_NSSC_CPU1_DP")
		)
		(pad "CY34" smd circle
			(at -10.566654 10.047732 270)
			(size 0.4318 0.4318)
			(layers "F.Cu" "F.Mask" "F.Paste")
			(net "PVCCD_HV_CPU1")
		)
		(pad "CY36" smd circle
			(at -8.939022 10.047732 270)
			(size 0.4318 0.4318)
			(layers "F.Cu" "F.Mask" "F.Paste")
			(net "PVCCD_HV_CPU1")
		)
		(pad "CY38" smd circle
			(at -7.311136 10.047732 270)
			(size 0.4318 0.4318)
			(layers "F.Cu" "F.Mask" "F.Paste")
			(net "NC_CPU1_DDR45_VIEWDIG1")
		)
		(pad "CY40" smd circle
			(at -5.68325 10.047732 270)
			(size 0.4318 0.4318)
			(layers "F.Cu" "F.Mask" "F.Paste")
			(net "TP_H_CPU1_PMDOWN_PCH_R")
		)
		(pad "CY42" smd circle
			(at -4.055618 10.047732 270)
			(size 0.4318 0.4318)
			(layers "F.Cu" "F.Mask" "F.Paste")
			(net "RST_CPU1_DRAM_EF_N")
		)
		(pad "CY44" smd circle
			(at -2.427732 10.047732 270)
			(size 0.4318 0.4318)
			(layers "F.Cu" "F.Mask" "F.Paste")
			(net "PWRGD_DRAMPWRGD_CPU1_EF_LVC1_R")
		)
		(pad "CY47" smd circle
			(at 1.613916 10.157714 270)
			(size 0.4318 0.4318)
			(layers "F.Cu" "F.Mask" "F.Paste")
			(net "M_E_CPU1_ALERT_N")
		)
		(pad "CY49" smd circle
			(at 3.241802 10.157714 270)
			(size 0.4318 0.4318)
			(layers "F.Cu" "F.Mask" "F.Paste")
			(net "NC_CPU1_DDR67_VIEWDIG1")
		)
		(pad "CY51" smd circle
			(at 4.869434 10.157714 270)
			(size 0.4318 0.4318)
			(layers "F.Cu" "F.Mask" "F.Paste")
			(net "M_H_CPU1_ALERT_N")
		)
		(pad "CY53" smd circle
			(at 6.49732 10.157714 270)
			(size 0.4318 0.4318)
			(layers "F.Cu" "F.Mask" "F.Paste")
			(net "PVCCD_HV_CPU1")
		)
		(pad "CY55" smd circle
			(at 8.124952 10.157714 270)
			(size 0.4318 0.4318)
			(layers "F.Cu" "F.Mask" "F.Paste")
			(net "RST_CPU1_DRAM_GH_N")
		)
		(pad "CY57" smd circle
			(at 9.752838 10.157714 270)
			(size 0.4318 0.4318)
			(layers "F.Cu" "F.Mask" "F.Paste")
			(net "NC_CPU1_VIEWPIN_GNR3")
		)
		(pad "CY59" smd circle
			(at 11.380724 10.157714 270)
			(size 0.4318 0.4318)
			(layers "F.Cu" "F.Mask" "F.Paste")
			(net "PU_CPU1_LEGACY_SKT")
		)
		(pad "CY61" smd circle
			(at 13.008356 10.157714 270)
			(size 0.4318 0.4318)
			(layers "F.Cu" "F.Mask" "F.Paste")
			(net "PU_CPU1_SOCKET_ID1")
		)
		(pad "CY63" smd circle
			(at 14.635988 10.157714 270)
			(size 0.4318 0.4318)
			(layers "F.Cu" "F.Mask" "F.Paste")
			(net "GND")
		)
		(pad "CY65" smd circle
			(at 16.263874 10.157714 270)
			(size 0.4318 0.4318)
			(layers "F.Cu" "F.Mask" "F.Paste")
			(net "PVCCINFAON_CPU1")
		)
		(pad "CY67" smd circle
			(at 17.89176 10.157714 270)
			(size 0.4318 0.4318)
			(layers "F.Cu" "F.Mask" "F.Paste")
			(net "PVCCINFAON_CPU1")
		)
		(pad "CY69" smd circle
			(at 19.519392 10.157714 270)
			(size 0.4318 0.4318)
			(layers "F.Cu" "F.Mask" "F.Paste")
			(net "NC_UART_IBL_CPU1_RXD")
		)
		(pad "CY71" smd circle
			(at 21.147278 10.157714 270)
			(size 0.4318 0.4318)
			(layers "F.Cu" "F.Mask" "F.Paste")
			(net "NC_UART_IBL_CPU1_RTS")
		)
		(pad "CY73" smd circle
			(at 22.77491 10.157714 270)
			(size 0.4318 0.4318)
			(layers "F.Cu" "F.Mask" "F.Paste")
			(net "GND")
		)
		(pad "CY75" smd circle
			(at 24.402796 10.157714 270)
			(size 0.4318 0.4318)
			(layers "F.Cu" "F.Mask" "F.Paste")
			(net "PVCCFA_EHV_FIVRA_CPU1")
		)
		(pad "CY77" smd circle
			(at 26.030682 10.157714 270)
			(size 0.4318 0.4318)
			(layers "F.Cu" "F.Mask" "F.Paste")
			(net "GND")
		)
		(pad "CY79" smd circle
			(at 27.658314 10.157714 270)
			(size 0.4318 0.4318)
			(layers "F.Cu" "F.Mask" "F.Paste")
			(net "PVCCFA_EHV_FIVRA_CPU1")
		)
		(pad "CY81" smd circle
			(at 29.2862 10.157714 270)
			(size 0.4318 0.4318)
			(layers "F.Cu" "F.Mask" "F.Paste")
			(net "GND")
		)
		(pad "CY83" smd circle
			(at 30.914086 10.157714 270)
			(size 0.4318 0.4318)
			(layers "F.Cu" "F.Mask" "F.Paste")
			(net "GND")
		)
		(pad "CY85" smd circle
			(at 32.541718 10.157714 270)
			(size 0.4318 0.4318)
			(layers "F.Cu" "F.Mask" "F.Paste")
			(net "PVCCFA_EHV_FIVRA_CPU1")
		)
		(pad "CY87" smd circle
			(at 34.169604 10.157714 270)
			(size 0.4318 0.4318)
			(layers "F.Cu" "F.Mask" "F.Paste")
			(net "P5E_CPU1_PE3_TX_DN<12>")
		)
		(pad "CY89" smd circle
			(at 35.797236 10.157714 270)
			(size 0.4318 0.4318)
			(layers "F.Cu" "F.Mask" "F.Paste")
			(net "PVCCFA_EHV_FIVRA_CPU1")
		)
		(pad "CY91" smd oval
			(at 37.425122 10.157714)
			(size 0.381 0.4826)
			(drill
				(offset 0 -0.0508)
			)
			(layers "F.Cu" "F.Mask" "F.Paste")
			(net "P5E_CPU1_PE3_RX_DP<13>")
		)
		(pad "D4" smd oval
			(at -34.98342 -25.664414 135)
			(size 0.381 0.4826)
			(drill
				(offset 0 -0.0508)
			)
			(layers "F.Cu" "F.Mask" "F.Paste")
			(net "CPU1_RSVD<153>")
		)
		(pad "D6" smd oval
			(at -33.355534 -25.664414 135)
			(size 0.381 0.4826)
			(drill
				(offset 0 -0.0508)
			)
			(layers "F.Cu" "F.Mask" "F.Paste")
			(net "GND")
		)
		(pad "D8" smd oval
			(at -31.727902 -25.664414 135)
			(size 0.381 0.4826)
			(drill
				(offset 0 -0.0508)
			)
			(layers "F.Cu" "F.Mask" "F.Paste")
			(net "GND")
		)
		(pad "D10" smd circle
			(at -30.100016 -25.664414 270)
			(size 0.4318 0.4318)
			(layers "F.Cu" "F.Mask" "F.Paste")
			(net "GND")
		)
		(pad "D12" smd circle
			(at -28.472384 -25.664414 270)
			(size 0.4318 0.4318)
			(layers "F.Cu" "F.Mask" "F.Paste")
			(net "GND")
		)
		(pad "D14" smd circle
			(at -26.844498 -25.664414 270)
			(size 0.4318 0.4318)
			(layers "F.Cu" "F.Mask" "F.Paste")
			(net "GND")
		)
		(pad "D16" smd circle
			(at -25.216612 -25.664414 270)
			(size 0.4318 0.4318)
			(layers "F.Cu" "F.Mask" "F.Paste")
			(net "GND")
		)
		(pad "D18" smd circle
			(at -23.58898 -25.664414 270)
			(size 0.4318 0.4318)
			(layers "F.Cu" "F.Mask" "F.Paste")
			(net "GND")
		)
		(pad "D20" smd circle
			(at -21.961094 -25.664414 270)
			(size 0.4318 0.4318)
			(layers "F.Cu" "F.Mask" "F.Paste")
			(net "GND")
		)
		(pad "D22" smd circle
			(at -20.333462 -25.664414 270)
			(size 0.4318 0.4318)
			(layers "F.Cu" "F.Mask" "F.Paste")
			(net "GND")
		)
		(pad "D24" smd circle
			(at -18.705576 -25.664414 270)
			(size 0.4318 0.4318)
			(layers "F.Cu" "F.Mask" "F.Paste")
			(net "GND")
		)
		(pad "D26" smd circle
			(at -17.07769 -25.664414 270)
			(size 0.4318 0.4318)
			(layers "F.Cu" "F.Mask" "F.Paste")
			(net "GND")
		)
		(pad "D28" smd circle
			(at -15.450058 -25.664414 270)
			(size 0.4318 0.4318)
			(layers "F.Cu" "F.Mask" "F.Paste")
			(net "GND")
		)
		(pad "D30" smd circle
			(at -13.822426 -25.664414 270)
			(size 0.4318 0.4318)
			(layers "F.Cu" "F.Mask" "F.Paste")
			(net "GND")
		)
		(pad "D32" smd circle
			(at -12.19454 -25.664414 270)
			(size 0.4318 0.4318)
			(layers "F.Cu" "F.Mask" "F.Paste")
			(net "GND")
		)
		(pad "D34" smd circle
			(at -10.566654 -25.664414 270)
			(size 0.4318 0.4318)
			(layers "F.Cu" "F.Mask" "F.Paste")
			(net "GND")
		)
		(pad "D36" smd circle
			(at -8.939022 -25.664414 270)
			(size 0.4318 0.4318)
			(layers "F.Cu" "F.Mask" "F.Paste")
			(net "GND")
		)
		(pad "D38" smd circle
			(at -7.311136 -25.664414 270)
			(size 0.4318 0.4318)
			(layers "F.Cu" "F.Mask" "F.Paste")
			(net "GND")
		)
		(pad "D40" smd circle
			(at -5.68325 -25.664414 270)
			(size 0.4318 0.4318)
			(layers "F.Cu" "F.Mask" "F.Paste")
			(net "GND")
		)
		(pad "D42" smd circle
			(at -4.055618 -25.664414 270)
			(size 0.4318 0.4318)
			(layers "F.Cu" "F.Mask" "F.Paste")
			(net "GND")
		)
		(pad "D44" smd circle
			(at -2.427732 -25.664414 270)
			(size 0.4318 0.4318)
			(layers "F.Cu" "F.Mask" "F.Paste")
			(net "GND")
		)
		(pad "D47" smd oval
			(at 1.613916 -25.554686 135)
			(size 0.381 0.4826)
			(drill
				(offset 0 -0.0508)
			)
			(layers "F.Cu" "F.Mask" "F.Paste")
			(net "GND")
		)
		(pad "D49" smd circle
			(at 3.241802 -25.554686 270)
			(size 0.4318 0.4318)
			(layers "F.Cu" "F.Mask" "F.Paste")
			(net "GND")
		)
		(pad "D51" smd circle
			(at 4.869434 -25.554686 270)
			(size 0.4318 0.4318)
			(layers "F.Cu" "F.Mask" "F.Paste")
			(net "GND")
		)
		(pad "D53" smd circle
			(at 6.49732 -25.554686 270)
			(size 0.4318 0.4318)
			(layers "F.Cu" "F.Mask" "F.Paste")
			(net "GND")
		)
		(pad "D55" smd circle
			(at 8.124952 -25.554686 270)
			(size 0.4318 0.4318)
			(layers "F.Cu" "F.Mask" "F.Paste")
			(net "GND")
		)
		(pad "D57" smd circle
			(at 9.752838 -25.554686 270)
			(size 0.4318 0.4318)
			(layers "F.Cu" "F.Mask" "F.Paste")
			(net "GND")
		)
		(pad "D59" smd circle
			(at 11.380724 -25.554686 270)
			(size 0.4318 0.4318)
			(layers "F.Cu" "F.Mask" "F.Paste")
			(net "GND")
		)
		(pad "D61" smd circle
			(at 13.008356 -25.554686 270)
			(size 0.4318 0.4318)
			(layers "F.Cu" "F.Mask" "F.Paste")
			(net "GND")
		)
		(pad "D63" smd circle
			(at 14.635988 -25.554686 270)
			(size 0.4318 0.4318)
			(layers "F.Cu" "F.Mask" "F.Paste")
			(net "GND")
		)
		(pad "D65" smd circle
			(at 16.263874 -25.554686 270)
			(size 0.4318 0.4318)
			(layers "F.Cu" "F.Mask" "F.Paste")
			(net "GND")
		)
		(pad "D67" smd circle
			(at 17.89176 -25.554686 270)
			(size 0.4318 0.4318)
			(layers "F.Cu" "F.Mask" "F.Paste")
			(net "GND")
		)
		(pad "D69" smd circle
			(at 19.519392 -25.554686 270)
			(size 0.4318 0.4318)
			(layers "F.Cu" "F.Mask" "F.Paste")
			(net "GND")
		)
		(pad "D71" smd circle
			(at 21.147278 -25.554686 270)
			(size 0.4318 0.4318)
			(layers "F.Cu" "F.Mask" "F.Paste")
			(net "GND")
		)
		(pad "D73" smd circle
			(at 22.77491 -25.554686 270)
			(size 0.4318 0.4318)
			(layers "F.Cu" "F.Mask" "F.Paste")
			(net "M_A_CPU1_SA_DQ<18>")
		)
		(pad "D75" smd circle
			(at 24.402796 -25.554686 270)
			(size 0.4318 0.4318)
			(layers "F.Cu" "F.Mask" "F.Paste")
			(net "M_A_CPU1_SA_DQ<5>")
		)
		(pad "D77" smd circle
			(at 26.030682 -25.554686 270)
			(size 0.4318 0.4318)
			(layers "F.Cu" "F.Mask" "F.Paste")
			(net "M_A_CPU1_SA_DQS_DP<0>")
		)
		(pad "D79" smd circle
			(at 27.658314 -25.554686 270)
			(size 0.4318 0.4318)
			(layers "F.Cu" "F.Mask" "F.Paste")
			(net "GND")
		)
		(pad "D81" smd circle
			(at 29.2862 -25.554686 270)
			(size 0.4318 0.4318)
			(layers "F.Cu" "F.Mask" "F.Paste")
			(net "GND")
		)
		(pad "D83" smd circle
			(at 30.914086 -25.554686 270)
			(size 0.4318 0.4318)
			(layers "F.Cu" "F.Mask" "F.Paste")
			(net "GND")
		)
		(pad "D85" smd oval
			(at 32.541718 -25.554686 45)
			(size 0.381 0.4826)
			(drill
				(offset 0 -0.0508)
			)
			(layers "F.Cu" "F.Mask" "F.Paste")
			(net "UPI_CPU1_CPU0_P2P2_DP<0>")
		)
		(pad "D87" smd oval
			(at 34.169604 -25.554686 45)
			(size 0.381 0.4826)
			(drill
				(offset 0 -0.0508)
			)
			(layers "F.Cu" "F.Mask" "F.Paste")
			(net "UPI_CPU1_CPU0_P2P2_DN<2>")
		)
		(pad "DA1" smd oval
			(at -37.425122 10.517886 180)
			(size 0.381 0.4826)
			(drill
				(offset 0 -0.0508)
			)
			(layers "F.Cu" "F.Mask" "F.Paste")
			(net "UPI_CPU0_CPU1_P0P1_DP<13>")
		)
		(pad "DA3" smd circle
			(at -35.797236 10.517886 270)
			(size 0.4318 0.4318)
			(layers "F.Cu" "F.Mask" "F.Paste")
			(net "PVCCINFAON_CPU1")
		)
		(pad "DA5" smd circle
			(at -34.169604 10.517886 270)
			(size 0.4318 0.4318)
			(layers "F.Cu" "F.Mask" "F.Paste")
			(net "UPI_CPU1_CPU0_P1P0_DN<12>")
		)
		(pad "DA7" smd circle
			(at -32.541718 10.517886 270)
			(size 0.4318 0.4318)
			(layers "F.Cu" "F.Mask" "F.Paste")
			(net "PVCCINFAON_CPU1")
		)
		(pad "DA9" smd circle
			(at -30.914086 10.517886 270)
			(size 0.4318 0.4318)
			(layers "F.Cu" "F.Mask" "F.Paste")
			(net "P5E_CPU1_PE2_RX_DN<2>")
		)
		(pad "DA11" smd circle
			(at -29.2862 10.517886 270)
			(size 0.4318 0.4318)
			(layers "F.Cu" "F.Mask" "F.Paste")
			(net "PVCCINFAON_CPU1")
		)
		(pad "DA13" smd circle
			(at -27.658314 10.517886 270)
			(size 0.4318 0.4318)
			(layers "F.Cu" "F.Mask" "F.Paste")
			(net "P5E_CPU1_PE2_TX_DN<2>")
		)
		(pad "DA15" smd circle
			(at -26.030682 10.517886 270)
			(size 0.4318 0.4318)
			(layers "F.Cu" "F.Mask" "F.Paste")
			(net "PVCCINFAON_CPU1")
		)
		(pad "DA17" smd circle
			(at -24.402796 10.517886 270)
			(size 0.4318 0.4318)
			(layers "F.Cu" "F.Mask" "F.Paste")
			(net "M_H_CPU1_SB_DQ<29>")
		)
		(pad "DA19" smd circle
			(at -22.77491 10.517886 270)
			(size 0.4318 0.4318)
			(layers "F.Cu" "F.Mask" "F.Paste")
			(net "GND")
		)
		(pad "DA21" smd circle
			(at -21.147278 10.517886 270)
			(size 0.4318 0.4318)
			(layers "F.Cu" "F.Mask" "F.Paste")
			(net "PVCCINFAON_CPU1")
		)
		(pad "DA23" smd circle
			(at -19.519392 10.517886 270)
			(size 0.4318 0.4318)
			(layers "F.Cu" "F.Mask" "F.Paste")
			(net "GND")
		)
		(pad "DA25" smd circle
			(at -17.89176 10.517886 270)
			(size 0.4318 0.4318)
			(layers "F.Cu" "F.Mask" "F.Paste")
			(net "GND")
		)
		(pad "DA27" smd circle
			(at -16.263874 10.517886 270)
			(size 0.4318 0.4318)
			(layers "F.Cu" "F.Mask" "F.Paste")
			(net "CLK_100M_DB2000_CPU1_BCLK3_DP")
		)
		(pad "DA29" smd circle
			(at -14.635988 10.517886 270)
			(size 0.4318 0.4318)
			(layers "F.Cu" "F.Mask" "F.Paste")
			(net "GND")
		)
		(pad "DA31" smd circle
			(at -13.008356 10.517886 270)
			(size 0.4318 0.4318)
			(layers "F.Cu" "F.Mask" "F.Paste")
			(net "GND")
		)
		(pad "DA33" smd circle
			(at -11.380724 10.517886 270)
			(size 0.4318 0.4318)
			(layers "F.Cu" "F.Mask" "F.Paste")
			(net "GND")
		)
		(pad "DA35" smd circle
			(at -9.752838 10.517886 270)
			(size 0.4318 0.4318)
			(layers "F.Cu" "F.Mask" "F.Paste")
			(net "GND")
		)
		(pad "DA37" smd circle
			(at -8.124952 10.517886 270)
			(size 0.4318 0.4318)
			(layers "F.Cu" "F.Mask" "F.Paste")
			(net "GND")
		)
		(pad "DA39" smd circle
			(at -6.49732 10.517886 270)
			(size 0.4318 0.4318)
			(layers "F.Cu" "F.Mask" "F.Paste")
			(net "TP_H_CPU1_PMSYNC_PCH_INTRP_R")
		)
		(pad "DA41" smd circle
			(at -4.869434 10.517886 270)
			(size 0.4318 0.4318)
			(layers "F.Cu" "F.Mask" "F.Paste")
			(net "GND")
		)
		(pad "DA43" smd circle
			(at -3.241802 10.517886 270)
			(size 0.4318 0.4318)
			(layers "F.Cu" "F.Mask" "F.Paste")
			(net "GND")
		)
		(pad "DA45" smd circle
			(at -1.613916 10.517886 270)
			(size 0.4318 0.4318)
			(layers "F.Cu" "F.Mask" "F.Paste")
			(net "NC_CPU1_DDR67_VIEWDIG0")
		)
		(pad "DA48" smd circle
			(at 2.427732 10.627868 270)
			(size 0.4318 0.4318)
			(layers "F.Cu" "F.Mask" "F.Paste")
			(net "GND")
		)
		(pad "DA50" smd circle
			(at 4.055618 10.627868 270)
			(size 0.4318 0.4318)
			(layers "F.Cu" "F.Mask" "F.Paste")
			(net "GND")
		)
		(pad "DA52" smd circle
			(at 5.68325 10.627868 270)
			(size 0.4318 0.4318)
			(layers "F.Cu" "F.Mask" "F.Paste")
			(net "PD_CPU1_PROCDIS_COD_GTL_N")
		)
		(pad "DA54" smd circle
			(at 7.311136 10.627868 270)
			(size 0.4318 0.4318)
			(layers "F.Cu" "F.Mask" "F.Paste")
			(net "GND")
		)
		(pad "DA56" smd circle
			(at 8.939022 10.627868 270)
			(size 0.4318 0.4318)
			(layers "F.Cu" "F.Mask" "F.Paste")
			(net "GND")
		)
		(pad "DA58" smd circle
			(at 10.566654 10.627868 270)
			(size 0.4318 0.4318)
			(layers "F.Cu" "F.Mask" "F.Paste")
			(net "GND")
		)
		(pad "DA60" smd circle
			(at 12.19454 10.627868 270)
			(size 0.4318 0.4318)
			(layers "F.Cu" "F.Mask" "F.Paste")
			(net "GND")
		)
		(pad "DA62" smd circle
			(at 13.822426 10.627868 270)
			(size 0.4318 0.4318)
			(layers "F.Cu" "F.Mask" "F.Paste")
			(net "GND")
		)
		(pad "DA64" smd circle
			(at 15.450058 10.627868 270)
			(size 0.4318 0.4318)
			(layers "F.Cu" "F.Mask" "F.Paste")
			(net "PVCCINFAON_CPU1")
		)
		(pad "DA66" smd circle
			(at 17.07769 10.627868 270)
			(size 0.4318 0.4318)
			(layers "F.Cu" "F.Mask" "F.Paste")
			(net "GND")
		)
		(pad "DA68" smd circle
			(at 18.705576 10.627868 270)
			(size 0.4318 0.4318)
			(layers "F.Cu" "F.Mask" "F.Paste")
			(net "GND")
		)
		(pad "DA70" smd circle
			(at 20.333462 10.627868 270)
			(size 0.4318 0.4318)
			(layers "F.Cu" "F.Mask" "F.Paste")
			(net "TP_CPU1_SPARE4")
		)
		(pad "DA72" smd circle
			(at 21.961094 10.627868 270)
			(size 0.4318 0.4318)
			(layers "F.Cu" "F.Mask" "F.Paste")
			(net "GND")
		)
		(pad "DA74" smd circle
			(at 23.58898 10.627868 270)
			(size 0.4318 0.4318)
			(layers "F.Cu" "F.Mask" "F.Paste")
			(net "GND")
		)
		(pad "DA76" smd circle
			(at 25.216612 10.627868 270)
			(size 0.4318 0.4318)
			(layers "F.Cu" "F.Mask" "F.Paste")
			(net "Net_721")
		)
		(pad "DA78" smd circle
			(at 26.844498 10.627868 270)
			(size 0.4318 0.4318)
			(layers "F.Cu" "F.Mask" "F.Paste")
			(net "GND")
		)
		(pad "DA80" smd circle
			(at 28.472384 10.627868 270)
			(size 0.4318 0.4318)
			(layers "F.Cu" "F.Mask" "F.Paste")
			(net "GND")
		)
		(pad "DA82" smd circle
			(at 30.100016 10.627868 270)
			(size 0.4318 0.4318)
			(layers "F.Cu" "F.Mask" "F.Paste")
			(net "GND")
		)
		(pad "DA84" smd circle
			(at 31.727902 10.627868 270)
			(size 0.4318 0.4318)
			(layers "F.Cu" "F.Mask" "F.Paste")
			(net "GND")
		)
		(pad "DA86" smd circle
			(at 33.355534 10.627868 270)
			(size 0.4318 0.4318)
			(layers "F.Cu" "F.Mask" "F.Paste")
			(net "P5E_CPU1_PE3_TX_DP<12>")
		)
		(pad "DA88" smd circle
			(at 34.98342 10.627868 270)
			(size 0.4318 0.4318)
			(layers "F.Cu" "F.Mask" "F.Paste")
			(net "GND")
		)
		(pad "DA90" smd circle
			(at 36.611306 10.627868 270)
			(size 0.4318 0.4318)
			(layers "F.Cu" "F.Mask" "F.Paste")
			(net "P5E_CPU1_PE3_RX_DN<13>")
		)
		(pad "DB2" smd circle
			(at -36.611306 10.987532 270)
			(size 0.4318 0.4318)
			(layers "F.Cu" "F.Mask" "F.Paste")
			(net "UPI_CPU0_CPU1_P0P1_DN<13>")
		)
		(pad "DB4" smd circle
			(at -34.98342 10.987532 270)
			(size 0.4318 0.4318)
			(layers "F.Cu" "F.Mask" "F.Paste")
			(net "GND")
		)
		(pad "DB6" smd circle
			(at -33.355534 10.987532 270)
			(size 0.4318 0.4318)
			(layers "F.Cu" "F.Mask" "F.Paste")
			(net "UPI_CPU1_CPU0_P1P0_DP<12>")
		)
		(pad "DB8" smd circle
			(at -31.727902 10.987532 270)
			(size 0.4318 0.4318)
			(layers "F.Cu" "F.Mask" "F.Paste")
			(net "GND")
		)
		(pad "DB10" smd circle
			(at -30.100016 10.987532 270)
			(size 0.4318 0.4318)
			(layers "F.Cu" "F.Mask" "F.Paste")
			(net "P5E_CPU1_PE2_RX_DP<2>")
		)
		(pad "DB12" smd circle
			(at -28.472384 10.987532 270)
			(size 0.4318 0.4318)
			(layers "F.Cu" "F.Mask" "F.Paste")
			(net "GND")
		)
		(pad "DB14" smd circle
			(at -26.844498 10.987532 270)
			(size 0.4318 0.4318)
			(layers "F.Cu" "F.Mask" "F.Paste")
			(net "P5E_CPU1_PE2_TX_DN<3>")
		)
		(pad "DB16" smd circle
			(at -25.216612 10.987532 270)
			(size 0.4318 0.4318)
			(layers "F.Cu" "F.Mask" "F.Paste")
			(net "GND")
		)
		(pad "DB18" smd circle
			(at -23.58898 10.987532 270)
			(size 0.4318 0.4318)
			(layers "F.Cu" "F.Mask" "F.Paste")
			(net "M_H_CPU1_SB_DQS_DN<3>")
		)
		(pad "DB20" smd circle
			(at -21.961094 10.987532 270)
			(size 0.4318 0.4318)
			(layers "F.Cu" "F.Mask" "F.Paste")
			(net "GND")
		)
		(pad "DB22" smd circle
			(at -20.333462 10.987532 270)
			(size 0.4318 0.4318)
			(layers "F.Cu" "F.Mask" "F.Paste")
			(net "GND")
		)
		(pad "DB24" smd circle
			(at -18.705576 10.987532 270)
			(size 0.4318 0.4318)
			(layers "F.Cu" "F.Mask" "F.Paste")
			(net "M_H_CPU1_SB_DQS_DP<1>")
		)
		(pad "DB26" smd circle
			(at -17.07769 10.987532 270)
			(size 0.4318 0.4318)
			(layers "F.Cu" "F.Mask" "F.Paste")
			(net "GND")
		)
		(pad "DB28" smd circle
			(at -15.450058 10.987532 270)
			(size 0.4318 0.4318)
			(layers "F.Cu" "F.Mask" "F.Paste")
			(net "GND")
		)
		(pad "DB30" smd circle
			(at -13.822426 10.987532 270)
			(size 0.4318 0.4318)
			(layers "F.Cu" "F.Mask" "F.Paste")
			(net "M_H_CPU1_SB_DQS_DP<0>")
		)
		(pad "DB32" smd circle
			(at -12.19454 10.987532 270)
			(size 0.4318 0.4318)
			(layers "F.Cu" "F.Mask" "F.Paste")
			(net "GND")
		)
		(pad "DB34" smd circle
			(at -10.566654 10.987532 270)
			(size 0.4318 0.4318)
			(layers "F.Cu" "F.Mask" "F.Paste")
			(net "GND")
		)
		(pad "DB36" smd circle
			(at -8.939022 10.987532 270)
			(size 0.4318 0.4318)
			(layers "F.Cu" "F.Mask" "F.Paste")
			(net "M_H_CPU1_SB_DQS_DP<9>")
		)
		(pad "DB38" smd circle
			(at -7.311136 10.987532 270)
			(size 0.4318 0.4318)
			(layers "F.Cu" "F.Mask" "F.Paste")
			(net "GND")
		)
		(pad "DB40" smd circle
			(at -5.68325 10.987532 270)
			(size 0.4318 0.4318)
			(layers "F.Cu" "F.Mask" "F.Paste")
			(net "GND")
		)
		(pad "DB42" smd circle
			(at -4.055618 10.987532 270)
			(size 0.4318 0.4318)
			(layers "F.Cu" "F.Mask" "F.Paste")
			(net "M_H_CPU1_CLK_DP<1>")
		)
		(pad "DB44" smd circle
			(at -2.427732 10.987532 270)
			(size 0.4318 0.4318)
			(layers "F.Cu" "F.Mask" "F.Paste")
			(net "GND")
		)
		(pad "DB47" smd circle
			(at 1.613916 11.097514 270)
			(size 0.4318 0.4318)
			(layers "F.Cu" "F.Mask" "F.Paste")
			(net "GND")
		)
		(pad "DB49" smd circle
			(at 3.241802 11.097514 270)
			(size 0.4318 0.4318)
			(layers "F.Cu" "F.Mask" "F.Paste")
			(net "M_H_CPU1_SA_CA<0>")
		)
		(pad "DB51" smd circle
			(at 4.869434 11.097514 270)
			(size 0.4318 0.4318)
			(layers "F.Cu" "F.Mask" "F.Paste")
			(net "GND")
		)
		(pad "DB53" smd circle
			(at 6.49732 11.097514 270)
			(size 0.4318 0.4318)
			(layers "F.Cu" "F.Mask" "F.Paste")
			(net "GND")
		)
		(pad "DB55" smd circle
			(at 8.124952 11.097514 270)
			(size 0.4318 0.4318)
			(layers "F.Cu" "F.Mask" "F.Paste")
			(net "M_H_CPU1_SA_DQS_DP<4>")
		)
		(pad "DB57" smd circle
			(at 9.752838 11.097514 270)
			(size 0.4318 0.4318)
			(layers "F.Cu" "F.Mask" "F.Paste")
			(net "GND")
		)
		(pad "DB59" smd circle
			(at 11.380724 11.097514 270)
			(size 0.4318 0.4318)
			(layers "F.Cu" "F.Mask" "F.Paste")
			(net "GND")
		)
		(pad "DB61" smd circle
			(at 13.008356 11.097514 270)
			(size 0.4318 0.4318)
			(layers "F.Cu" "F.Mask" "F.Paste")
			(net "M_H_CPU1_SA_DQS_DP<3>")
		)
		(pad "DB63" smd circle
			(at 14.635988 11.097514 270)
			(size 0.4318 0.4318)
			(layers "F.Cu" "F.Mask" "F.Paste")
			(net "GND")
		)
		(pad "DB65" smd circle
			(at 16.263874 11.097514 270)
			(size 0.4318 0.4318)
			(layers "F.Cu" "F.Mask" "F.Paste")
			(net "GND")
		)
		(pad "DB67" smd circle
			(at 17.89176 11.097514 270)
			(size 0.4318 0.4318)
			(layers "F.Cu" "F.Mask" "F.Paste")
			(net "M_H_CPU1_SA_DQS_DP<2>")
		)
		(pad "DB69" smd circle
			(at 19.519392 11.097514 270)
			(size 0.4318 0.4318)
			(layers "F.Cu" "F.Mask" "F.Paste")
			(net "GND")
		)
		(pad "DB71" smd circle
			(at 21.147278 11.097514 270)
			(size 0.4318 0.4318)
			(layers "F.Cu" "F.Mask" "F.Paste")
			(net "GND")
		)
		(pad "DB73" smd circle
			(at 22.77491 11.097514 270)
			(size 0.4318 0.4318)
			(layers "F.Cu" "F.Mask" "F.Paste")
			(net "M_H_CPU1_SA_DQS_DN<1>")
		)
		(pad "DB75" smd circle
			(at 24.402796 11.097514 270)
			(size 0.4318 0.4318)
			(layers "F.Cu" "F.Mask" "F.Paste")
			(net "GND")
		)
		(pad "DB77" smd circle
			(at 26.030682 11.097514 270)
			(size 0.4318 0.4318)
			(layers "F.Cu" "F.Mask" "F.Paste")
			(net "GND")
		)
		(pad "DB79" smd circle
			(at 27.658314 11.097514 270)
			(size 0.4318 0.4318)
			(layers "F.Cu" "F.Mask" "F.Paste")
			(net "GND")
		)
		(pad "DB81" smd circle
			(at 29.2862 11.097514 270)
			(size 0.4318 0.4318)
			(layers "F.Cu" "F.Mask" "F.Paste")
			(net "GND")
		)
		(pad "DB83" smd circle
			(at 30.914086 11.097514 270)
			(size 0.4318 0.4318)
			(layers "F.Cu" "F.Mask" "F.Paste")
			(net "GND")
		)
		(pad "DB85" smd circle
			(at 32.541718 11.097514 270)
			(size 0.4318 0.4318)
			(layers "F.Cu" "F.Mask" "F.Paste")
			(net "P5E_CPU1_PE3_TX_DN<11>")
		)
		(pad "DB87" smd circle
			(at 34.169604 11.097514 270)
			(size 0.4318 0.4318)
			(layers "F.Cu" "F.Mask" "F.Paste")
			(net "GND")
		)
		(pad "DB89" smd circle
			(at 35.797236 11.097514 270)
			(size 0.4318 0.4318)
			(layers "F.Cu" "F.Mask" "F.Paste")
			(net "P5E_CPU1_PE3_RX_DN<12>")
		)
		(pad "DB91" smd oval
			(at 37.425122 11.097514)
			(size 0.381 0.4826)
			(drill
				(offset 0 -0.0508)
			)
			(layers "F.Cu" "F.Mask" "F.Paste")
			(net "GND")
		)
		(pad "DC1" smd oval
			(at -37.425122 11.457686 180)
			(size 0.381 0.4826)
			(drill
				(offset 0 -0.0508)
			)
			(layers "F.Cu" "F.Mask" "F.Paste")
			(net "GND")
		)
		(pad "DC3" smd circle
			(at -35.797236 11.457686 270)
			(size 0.4318 0.4318)
			(layers "F.Cu" "F.Mask" "F.Paste")
			(net "UPI_CPU0_CPU1_P0P1_DP<12>")
		)
		(pad "DC5" smd circle
			(at -34.169604 11.457686 270)
			(size 0.4318 0.4318)
			(layers "F.Cu" "F.Mask" "F.Paste")
			(net "GND")
		)
		(pad "DC7" smd circle
			(at -32.541718 11.457686 270)
			(size 0.4318 0.4318)
			(layers "F.Cu" "F.Mask" "F.Paste")
			(net "UPI_CPU1_CPU0_P1P0_DP<11>")
		)
		(pad "DC9" smd circle
			(at -30.914086 11.457686 270)
			(size 0.4318 0.4318)
			(layers "F.Cu" "F.Mask" "F.Paste")
			(net "GND")
		)
		(pad "DC11" smd circle
			(at -29.2862 11.457686 270)
			(size 0.4318 0.4318)
			(layers "F.Cu" "F.Mask" "F.Paste")
			(net "P5E_CPU1_PE2_RX_DP<3>")
		)
		(pad "DC13" smd circle
			(at -27.658314 11.457686 270)
			(size 0.4318 0.4318)
			(layers "F.Cu" "F.Mask" "F.Paste")
			(net "GND")
		)
		(pad "DC15" smd circle
			(at -26.030682 11.457686 270)
			(size 0.4318 0.4318)
			(layers "F.Cu" "F.Mask" "F.Paste")
			(net "P5E_CPU1_PE2_TX_DP<3>")
		)
		(pad "DC17" smd circle
			(at -24.402796 11.457686 270)
			(size 0.4318 0.4318)
			(layers "F.Cu" "F.Mask" "F.Paste")
			(net "M_H_CPU1_SB_DQ<31>")
		)
		(pad "DC19" smd circle
			(at -22.77491 11.457686 270)
			(size 0.4318 0.4318)
			(layers "F.Cu" "F.Mask" "F.Paste")
			(net "M_H_CPU1_SB_DQ<25>")
		)
		(pad "DC21" smd circle
			(at -21.147278 11.457686 270)
			(size 0.4318 0.4318)
			(layers "F.Cu" "F.Mask" "F.Paste")
			(net "GND")
		)
		(pad "DC23" smd circle
			(at -19.519392 11.457686 270)
			(size 0.4318 0.4318)
			(layers "F.Cu" "F.Mask" "F.Paste")
			(net "M_H_CPU1_SB_DQ<12>")
		)
		(pad "DC25" smd circle
			(at -17.89176 11.457686 270)
			(size 0.4318 0.4318)
			(layers "F.Cu" "F.Mask" "F.Paste")
			(net "M_H_CPU1_SB_DQ<9>")
		)
		(pad "DC27" smd circle
			(at -16.263874 11.457686 270)
			(size 0.4318 0.4318)
			(layers "F.Cu" "F.Mask" "F.Paste")
			(net "GND")
		)
		(pad "DC29" smd circle
			(at -14.635988 11.457686 270)
			(size 0.4318 0.4318)
			(layers "F.Cu" "F.Mask" "F.Paste")
			(net "M_H_CPU1_SB_DQ<4>")
		)
		(pad "DC31" smd circle
			(at -13.008356 11.457686 270)
			(size 0.4318 0.4318)
			(layers "F.Cu" "F.Mask" "F.Paste")
			(net "M_H_CPU1_SB_DQ<1>")
		)
		(pad "DC33" smd circle
			(at -11.380724 11.457686 270)
			(size 0.4318 0.4318)
			(layers "F.Cu" "F.Mask" "F.Paste")
			(net "GND")
		)
		(pad "DC35" smd circle
			(at -9.752838 11.457686 270)
			(size 0.4318 0.4318)
			(layers "F.Cu" "F.Mask" "F.Paste")
			(net "M_H_CPU1_SB_CB<0>")
		)
		(pad "DC37" smd circle
			(at -8.124952 11.457686 270)
			(size 0.4318 0.4318)
			(layers "F.Cu" "F.Mask" "F.Paste")
			(net "M_H_CPU1_SB_CB<7>")
		)
		(pad "DC39" smd circle
			(at -6.49732 11.457686 270)
			(size 0.4318 0.4318)
			(layers "F.Cu" "F.Mask" "F.Paste")
			(net "GND")
		)
		(pad "DC41" smd circle
			(at -4.869434 11.457686 270)
			(size 0.4318 0.4318)
			(layers "F.Cu" "F.Mask" "F.Paste")
			(net "M_H_CPU1_SA_CA<6>")
		)
		(pad "DC43" smd circle
			(at -3.241802 11.457686 270)
			(size 0.4318 0.4318)
			(layers "F.Cu" "F.Mask" "F.Paste")
			(net "M_E_CPU1_SA_RSP<1>")
		)
		(pad "DC45" smd circle
			(at -1.613916 11.457686 270)
			(size 0.4318 0.4318)
			(layers "F.Cu" "F.Mask" "F.Paste")
			(net "GND")
		)
		(pad "DC48" smd circle
			(at 2.427732 11.567668 270)
			(size 0.4318 0.4318)
			(layers "F.Cu" "F.Mask" "F.Paste")
			(net "M_H_CPU1_SA_CA<2>")
		)
		(pad "DC50" smd circle
			(at 4.055618 11.567668 270)
			(size 0.4318 0.4318)
			(layers "F.Cu" "F.Mask" "F.Paste")
			(net "M_H_CPU1_SA_CS_N<3>")
		)
		(pad "DC52" smd circle
			(at 5.68325 11.567668 270)
			(size 0.4318 0.4318)
			(layers "F.Cu" "F.Mask" "F.Paste")
			(net "GND")
		)
		(pad "DC54" smd circle
			(at 7.311136 11.567668 270)
			(size 0.4318 0.4318)
			(layers "F.Cu" "F.Mask" "F.Paste")
			(net "M_H_CPU1_SA_CB<4>")
		)
		(pad "DC56" smd circle
			(at 8.939022 11.567668 270)
			(size 0.4318 0.4318)
			(layers "F.Cu" "F.Mask" "F.Paste")
			(net "M_H_CPU1_SA_CB<1>")
		)
		(pad "DC58" smd circle
			(at 10.566654 11.567668 270)
			(size 0.4318 0.4318)
			(layers "F.Cu" "F.Mask" "F.Paste")
			(net "GND")
		)
		(pad "DC60" smd circle
			(at 12.19454 11.567668 270)
			(size 0.4318 0.4318)
			(layers "F.Cu" "F.Mask" "F.Paste")
			(net "M_H_CPU1_SA_DQ<28>")
		)
		(pad "DC62" smd circle
			(at 13.822426 11.567668 270)
			(size 0.4318 0.4318)
			(layers "F.Cu" "F.Mask" "F.Paste")
			(net "M_H_CPU1_SA_DQ<25>")
		)
		(pad "DC64" smd circle
			(at 15.450058 11.567668 270)
			(size 0.4318 0.4318)
			(layers "F.Cu" "F.Mask" "F.Paste")
			(net "GND")
		)
		(pad "DC66" smd circle
			(at 17.07769 11.567668 270)
			(size 0.4318 0.4318)
			(layers "F.Cu" "F.Mask" "F.Paste")
			(net "M_H_CPU1_SA_DQ<20>")
		)
		(pad "DC68" smd circle
			(at 18.705576 11.567668 270)
			(size 0.4318 0.4318)
			(layers "F.Cu" "F.Mask" "F.Paste")
			(net "M_H_CPU1_SA_DQ<17>")
		)
		(pad "DC70" smd circle
			(at 20.333462 11.567668 270)
			(size 0.4318 0.4318)
			(layers "F.Cu" "F.Mask" "F.Paste")
			(net "GND")
		)
		(pad "DC72" smd circle
			(at 21.961094 11.567668 270)
			(size 0.4318 0.4318)
			(layers "F.Cu" "F.Mask" "F.Paste")
			(net "M_H_CPU1_SA_DQ<12>")
		)
		(pad "DC74" smd circle
			(at 23.58898 11.567668 270)
			(size 0.4318 0.4318)
			(layers "F.Cu" "F.Mask" "F.Paste")
			(net "M_H_CPU1_SA_DQ<9>")
		)
		(pad "DC76" smd circle
			(at 25.216612 11.567668 270)
			(size 0.4318 0.4318)
			(layers "F.Cu" "F.Mask" "F.Paste")
			(net "GND")
		)
		(pad "DC78" smd circle
			(at 26.844498 11.567668 270)
			(size 0.4318 0.4318)
			(layers "F.Cu" "F.Mask" "F.Paste")
			(net "GND")
		)
		(pad "DC80" smd circle
			(at 28.472384 11.567668 270)
			(size 0.4318 0.4318)
			(layers "F.Cu" "F.Mask" "F.Paste")
			(net "GND")
		)
		(pad "DC82" smd circle
			(at 30.100016 11.567668 270)
			(size 0.4318 0.4318)
			(layers "F.Cu" "F.Mask" "F.Paste")
			(net "GND")
		)
		(pad "DC84" smd circle
			(at 31.727902 11.567668 270)
			(size 0.4318 0.4318)
			(layers "F.Cu" "F.Mask" "F.Paste")
			(net "GND")
		)
		(pad "DC86" smd circle
			(at 33.355534 11.567668 270)
			(size 0.4318 0.4318)
			(layers "F.Cu" "F.Mask" "F.Paste")
			(net "P5E_CPU1_PE3_TX_DP<11>")
		)
		(pad "DC88" smd circle
			(at 34.98342 11.567668 270)
			(size 0.4318 0.4318)
			(layers "F.Cu" "F.Mask" "F.Paste")
			(net "GND")
		)
		(pad "DC90" smd circle
			(at 36.611306 11.567668 270)
			(size 0.4318 0.4318)
			(layers "F.Cu" "F.Mask" "F.Paste")
			(net "P5E_CPU1_PE3_RX_DP<12>")
		)
		(pad "DD2" smd circle
			(at -36.611306 11.927332 270)
			(size 0.4318 0.4318)
			(layers "F.Cu" "F.Mask" "F.Paste")
			(net "UPI_CPU0_CPU1_P0P1_DN<12>")
		)
		(pad "DD4" smd circle
			(at -34.98342 11.927332 270)
			(size 0.4318 0.4318)
			(layers "F.Cu" "F.Mask" "F.Paste")
			(net "GND")
		)
		(pad "DD6" smd circle
			(at -33.355534 11.927332 270)
			(size 0.4318 0.4318)
			(layers "F.Cu" "F.Mask" "F.Paste")
			(net "UPI_CPU1_CPU0_P1P0_DN<11>")
		)
		(pad "DD8" smd circle
			(at -31.727902 11.927332 270)
			(size 0.4318 0.4318)
			(layers "F.Cu" "F.Mask" "F.Paste")
			(net "GND")
		)
		(pad "DD10" smd circle
			(at -30.100016 11.927332 270)
			(size 0.4318 0.4318)
			(layers "F.Cu" "F.Mask" "F.Paste")
			(net "P5E_CPU1_PE2_RX_DN<3>")
		)
		(pad "DD12" smd circle
			(at -28.472384 11.927332 270)
			(size 0.4318 0.4318)
			(layers "F.Cu" "F.Mask" "F.Paste")
			(net "GND")
		)
		(pad "DD14" smd circle
			(at -26.844498 11.927332 270)
			(size 0.4318 0.4318)
			(layers "F.Cu" "F.Mask" "F.Paste")
			(net "P5E_CPU1_PE2_TX_DP<4>")
		)
		(pad "DD16" smd circle
			(at -25.216612 11.927332 270)
			(size 0.4318 0.4318)
			(layers "F.Cu" "F.Mask" "F.Paste")
			(net "GND")
		)
		(pad "DD18" smd circle
			(at -23.58898 11.927332 270)
			(size 0.4318 0.4318)
			(layers "F.Cu" "F.Mask" "F.Paste")
			(net "M_H_CPU1_SB_DQS_DP<3>")
		)
		(pad "DD20" smd circle
			(at -21.961094 11.927332 270)
			(size 0.4318 0.4318)
			(layers "F.Cu" "F.Mask" "F.Paste")
			(net "M_H_CPU1_SB_DQ<24>")
		)
		(pad "DD22" smd circle
			(at -20.333462 11.927332 270)
			(size 0.4318 0.4318)
			(layers "F.Cu" "F.Mask" "F.Paste")
			(net "M_H_CPU1_SB_DQ<13>")
		)
		(pad "DD24" smd circle
			(at -18.705576 11.927332 270)
			(size 0.4318 0.4318)
			(layers "F.Cu" "F.Mask" "F.Paste")
			(net "M_H_CPU1_SB_DQS_DN<1>")
		)
		(pad "DD26" smd circle
			(at -17.07769 11.927332 270)
			(size 0.4318 0.4318)
			(layers "F.Cu" "F.Mask" "F.Paste")
			(net "M_H_CPU1_SB_DQ<8>")
		)
		(pad "DD28" smd circle
			(at -15.450058 11.927332 270)
			(size 0.4318 0.4318)
			(layers "F.Cu" "F.Mask" "F.Paste")
			(net "M_H_CPU1_SB_DQ<7>")
		)
		(pad "DD30" smd circle
			(at -13.822426 11.927332 270)
			(size 0.4318 0.4318)
			(layers "F.Cu" "F.Mask" "F.Paste")
			(net "M_H_CPU1_SB_DQS_DN<0>")
		)
		(pad "DD32" smd circle
			(at -12.19454 11.927332 270)
			(size 0.4318 0.4318)
			(layers "F.Cu" "F.Mask" "F.Paste")
			(net "M_H_CPU1_SB_DQ<0>")
		)
		(pad "DD34" smd circle
			(at -10.566654 11.927332 270)
			(size 0.4318 0.4318)
			(layers "F.Cu" "F.Mask" "F.Paste")
			(net "M_H_CPU1_SB_CB<1>")
		)
		(pad "DD36" smd circle
			(at -8.939022 11.927332 270)
			(size 0.4318 0.4318)
			(layers "F.Cu" "F.Mask" "F.Paste")
			(net "M_H_CPU1_SB_DQS_DN<9>")
		)
		(pad "DD38" smd circle
			(at -7.311136 11.927332 270)
			(size 0.4318 0.4318)
			(layers "F.Cu" "F.Mask" "F.Paste")
			(net "M_H_CPU1_SB_CB<6>")
		)
		(pad "DD40" smd circle
			(at -5.68325 11.927332 270)
			(size 0.4318 0.4318)
			(layers "F.Cu" "F.Mask" "F.Paste")
			(net "M_H_CPU1_SA_PAR")
		)
		(pad "DD42" smd circle
			(at -4.055618 11.927332 270)
			(size 0.4318 0.4318)
			(layers "F.Cu" "F.Mask" "F.Paste")
			(net "M_H_CPU1_CLK_DN<1>")
		)
		(pad "DD44" smd circle
			(at -2.427732 11.927332 270)
			(size 0.4318 0.4318)
			(layers "F.Cu" "F.Mask" "F.Paste")
			(net "M_E_CPU1_SA_RSP<0>")
		)
		(pad "DD47" smd circle
			(at 1.613916 12.037314 270)
			(size 0.4318 0.4318)
			(layers "F.Cu" "F.Mask" "F.Paste")
			(net "M_H_CPU1_SA_CA<4>")
		)
		(pad "DD49" smd circle
			(at 3.241802 12.037314 270)
			(size 0.4318 0.4318)
			(layers "F.Cu" "F.Mask" "F.Paste")
			(net "GND")
		)
		(pad "DD51" smd circle
			(at 4.869434 12.037314 270)
			(size 0.4318 0.4318)
			(layers "F.Cu" "F.Mask" "F.Paste")
			(net "M_H_CPU1_SA_CS_N<2>")
		)
		(pad "DD53" smd circle
			(at 6.49732 12.037314 270)
			(size 0.4318 0.4318)
			(layers "F.Cu" "F.Mask" "F.Paste")
			(net "M_H_CPU1_SA_CB<5>")
		)
		(pad "DD55" smd circle
			(at 8.124952 12.037314 270)
			(size 0.4318 0.4318)
			(layers "F.Cu" "F.Mask" "F.Paste")
			(net "M_H_CPU1_SA_DQS_DN<4>")
		)
		(pad "DD57" smd circle
			(at 9.752838 12.037314 270)
			(size 0.4318 0.4318)
			(layers "F.Cu" "F.Mask" "F.Paste")
			(net "M_H_CPU1_SA_CB<0>")
		)
		(pad "DD59" smd circle
			(at 11.380724 12.037314 270)
			(size 0.4318 0.4318)
			(layers "F.Cu" "F.Mask" "F.Paste")
			(net "M_H_CPU1_SA_DQ<29>")
		)
		(pad "DD61" smd circle
			(at 13.008356 12.037314 270)
			(size 0.4318 0.4318)
			(layers "F.Cu" "F.Mask" "F.Paste")
			(net "M_H_CPU1_SA_DQS_DN<3>")
		)
		(pad "DD63" smd circle
			(at 14.635988 12.037314 270)
			(size 0.4318 0.4318)
			(layers "F.Cu" "F.Mask" "F.Paste")
			(net "M_H_CPU1_SA_DQ<24>")
		)
		(pad "DD65" smd circle
			(at 16.263874 12.037314 270)
			(size 0.4318 0.4318)
			(layers "F.Cu" "F.Mask" "F.Paste")
			(net "M_H_CPU1_SA_DQ<21>")
		)
		(pad "DD67" smd circle
			(at 17.89176 12.037314 270)
			(size 0.4318 0.4318)
			(layers "F.Cu" "F.Mask" "F.Paste")
			(net "M_H_CPU1_SA_DQS_DN<2>")
		)
		(pad "DD69" smd circle
			(at 19.519392 12.037314 270)
			(size 0.4318 0.4318)
			(layers "F.Cu" "F.Mask" "F.Paste")
			(net "M_H_CPU1_SA_DQ<16>")
		)
		(pad "DD71" smd circle
			(at 21.147278 12.037314 270)
			(size 0.4318 0.4318)
			(layers "F.Cu" "F.Mask" "F.Paste")
			(net "M_H_CPU1_SA_DQ<13>")
		)
		(pad "DD73" smd circle
			(at 22.77491 12.037314 270)
			(size 0.4318 0.4318)
			(layers "F.Cu" "F.Mask" "F.Paste")
			(net "M_H_CPU1_SA_DQS_DP<1>")
		)
		(pad "DD75" smd circle
			(at 24.402796 12.037314 270)
			(size 0.4318 0.4318)
			(layers "F.Cu" "F.Mask" "F.Paste")
			(net "M_H_CPU1_SA_DQ<8>")
		)
		(pad "DD77" smd circle
			(at 26.030682 12.037314 270)
			(size 0.4318 0.4318)
			(layers "F.Cu" "F.Mask" "F.Paste")
			(net "PVCCFA_EHV_FIVRA_CPU1")
		)
		(pad "DD79" smd circle
			(at 27.658314 12.037314 270)
			(size 0.4318 0.4318)
			(layers "F.Cu" "F.Mask" "F.Paste")
			(net "GND")
		)
		(pad "DD81" smd circle
			(at 29.2862 12.037314 270)
			(size 0.4318 0.4318)
			(layers "F.Cu" "F.Mask" "F.Paste")
			(net "GND")
		)
		(pad "DD83" smd circle
			(at 30.914086 12.037314 270)
			(size 0.4318 0.4318)
			(layers "F.Cu" "F.Mask" "F.Paste")
			(net "PVCCFA_EHV_FIVRA_CPU1")
		)
		(pad "DD85" smd circle
			(at 32.541718 12.037314 270)
			(size 0.4318 0.4318)
			(layers "F.Cu" "F.Mask" "F.Paste")
			(net "PVCCFA_EHV_FIVRA_CPU1")
		)
		(pad "DD87" smd circle
			(at 34.169604 12.037314 270)
			(size 0.4318 0.4318)
			(layers "F.Cu" "F.Mask" "F.Paste")
			(net "P5E_CPU1_PE3_TX_DN<10>")
		)
		(pad "DD89" smd circle
			(at 35.797236 12.037314 270)
			(size 0.4318 0.4318)
			(layers "F.Cu" "F.Mask" "F.Paste")
			(net "PVCCFA_EHV_FIVRA_CPU1")
		)
		(pad "DD91" smd oval
			(at 37.425122 12.037314)
			(size 0.381 0.4826)
			(drill
				(offset 0 -0.0508)
			)
			(layers "F.Cu" "F.Mask" "F.Paste")
			(net "P5E_CPU1_PE3_RX_DN<11>")
		)
		(pad "DE1" smd oval
			(at -37.425122 12.397486 180)
			(size 0.381 0.4826)
			(drill
				(offset 0 -0.0508)
			)
			(layers "F.Cu" "F.Mask" "F.Paste")
			(net "UPI_CPU0_CPU1_P0P1_DN<11>")
		)
		(pad "DE3" smd circle
			(at -35.797236 12.397486 270)
			(size 0.4318 0.4318)
			(layers "F.Cu" "F.Mask" "F.Paste")
			(net "PVCCINFAON_CPU1")
		)
		(pad "DE5" smd circle
			(at -34.169604 12.397486 270)
			(size 0.4318 0.4318)
			(layers "F.Cu" "F.Mask" "F.Paste")
			(net "UPI_CPU1_CPU0_P1P0_DN<10>")
		)
		(pad "DE7" smd circle
			(at -32.541718 12.397486 270)
			(size 0.4318 0.4318)
			(layers "F.Cu" "F.Mask" "F.Paste")
			(net "PVCCINFAON_CPU1")
		)
		(pad "DE9" smd circle
			(at -30.914086 12.397486 270)
			(size 0.4318 0.4318)
			(layers "F.Cu" "F.Mask" "F.Paste")
			(net "P5E_CPU1_PE2_RX_DN<4>")
		)
		(pad "DE11" smd circle
			(at -29.2862 12.397486 270)
			(size 0.4318 0.4318)
			(layers "F.Cu" "F.Mask" "F.Paste")
			(net "PVCCINFAON_CPU1")
		)
		(pad "DE13" smd circle
			(at -27.658314 12.397486 270)
			(size 0.4318 0.4318)
			(layers "F.Cu" "F.Mask" "F.Paste")
			(net "P5E_CPU1_PE2_TX_DN<4>")
		)
		(pad "DE15" smd circle
			(at -26.030682 12.397486 270)
			(size 0.4318 0.4318)
			(layers "F.Cu" "F.Mask" "F.Paste")
			(net "PVCCINFAON_CPU1")
		)
		(pad "DE17" smd circle
			(at -24.402796 12.397486 270)
			(size 0.4318 0.4318)
			(layers "F.Cu" "F.Mask" "F.Paste")
			(net "GND")
		)
		(pad "DE19" smd circle
			(at -22.77491 12.397486 270)
			(size 0.4318 0.4318)
			(layers "F.Cu" "F.Mask" "F.Paste")
			(net "GND")
		)
		(pad "DE21" smd circle
			(at -21.147278 12.397486 270)
			(size 0.4318 0.4318)
			(layers "F.Cu" "F.Mask" "F.Paste")
			(net "GND")
		)
		(pad "DE23" smd circle
			(at -19.519392 12.397486 270)
			(size 0.4318 0.4318)
			(layers "F.Cu" "F.Mask" "F.Paste")
			(net "GND")
		)
		(pad "DE25" smd circle
			(at -17.89176 12.397486 270)
			(size 0.4318 0.4318)
			(layers "F.Cu" "F.Mask" "F.Paste")
			(net "GND")
		)
		(pad "DE27" smd circle
			(at -16.263874 12.397486 270)
			(size 0.4318 0.4318)
			(layers "F.Cu" "F.Mask" "F.Paste")
			(net "GND")
		)
		(pad "DE29" smd circle
			(at -14.635988 12.397486 270)
			(size 0.4318 0.4318)
			(layers "F.Cu" "F.Mask" "F.Paste")
			(net "GND")
		)
		(pad "DE31" smd circle
			(at -13.008356 12.397486 270)
			(size 0.4318 0.4318)
			(layers "F.Cu" "F.Mask" "F.Paste")
			(net "GND")
		)
		(pad "DE33" smd circle
			(at -11.380724 12.397486 270)
			(size 0.4318 0.4318)
			(layers "F.Cu" "F.Mask" "F.Paste")
			(net "GND")
		)
		(pad "DE35" smd circle
			(at -9.752838 12.397486 270)
			(size 0.4318 0.4318)
			(layers "F.Cu" "F.Mask" "F.Paste")
			(net "GND")
		)
		(pad "DE37" smd circle
			(at -8.124952 12.397486 270)
			(size 0.4318 0.4318)
			(layers "F.Cu" "F.Mask" "F.Paste")
			(net "GND")
		)
		(pad "DE39" smd circle
			(at -6.49732 12.397486 270)
			(size 0.4318 0.4318)
			(layers "F.Cu" "F.Mask" "F.Paste")
			(net "GND")
		)
		(pad "DE41" smd circle
			(at -4.869434 12.397486 270)
			(size 0.4318 0.4318)
			(layers "F.Cu" "F.Mask" "F.Paste")
			(net "GND")
		)
		(pad "DE43" smd circle
			(at -3.241802 12.397486 270)
			(size 0.4318 0.4318)
			(layers "F.Cu" "F.Mask" "F.Paste")
			(net "GND")
		)
		(pad "DE45" smd circle
			(at -1.613916 12.397486 270)
			(size 0.4318 0.4318)
			(layers "F.Cu" "F.Mask" "F.Paste")
			(net "GND")
		)
		(pad "DE48" smd circle
			(at 2.427732 12.507468 270)
			(size 0.4318 0.4318)
			(layers "F.Cu" "F.Mask" "F.Paste")
			(net "GND")
		)
		(pad "DE50" smd circle
			(at 4.055618 12.507468 270)
			(size 0.4318 0.4318)
			(layers "F.Cu" "F.Mask" "F.Paste")
			(net "GND")
		)
		(pad "DE52" smd circle
			(at 5.68325 12.507468 270)
			(size 0.4318 0.4318)
			(layers "F.Cu" "F.Mask" "F.Paste")
			(net "GND")
		)
		(pad "DE54" smd circle
			(at 7.311136 12.507468 270)
			(size 0.4318 0.4318)
			(layers "F.Cu" "F.Mask" "F.Paste")
			(net "GND")
		)
		(pad "DE56" smd circle
			(at 8.939022 12.507468 270)
			(size 0.4318 0.4318)
			(layers "F.Cu" "F.Mask" "F.Paste")
			(net "GND")
		)
		(pad "DE58" smd circle
			(at 10.566654 12.507468 270)
			(size 0.4318 0.4318)
			(layers "F.Cu" "F.Mask" "F.Paste")
			(net "GND")
		)
		(pad "DE60" smd circle
			(at 12.19454 12.507468 270)
			(size 0.4318 0.4318)
			(layers "F.Cu" "F.Mask" "F.Paste")
			(net "GND")
		)
		(pad "DE62" smd circle
			(at 13.822426 12.507468 270)
			(size 0.4318 0.4318)
			(layers "F.Cu" "F.Mask" "F.Paste")
			(net "GND")
		)
		(pad "DE64" smd circle
			(at 15.450058 12.507468 270)
			(size 0.4318 0.4318)
			(layers "F.Cu" "F.Mask" "F.Paste")
			(net "GND")
		)
		(pad "DE66" smd circle
			(at 17.07769 12.507468 270)
			(size 0.4318 0.4318)
			(layers "F.Cu" "F.Mask" "F.Paste")
			(net "GND")
		)
		(pad "DE68" smd circle
			(at 18.705576 12.507468 270)
			(size 0.4318 0.4318)
			(layers "F.Cu" "F.Mask" "F.Paste")
			(net "GND")
		)
		(pad "DE70" smd circle
			(at 20.333462 12.507468 270)
			(size 0.4318 0.4318)
			(layers "F.Cu" "F.Mask" "F.Paste")
			(net "GND")
		)
		(pad "DE72" smd circle
			(at 21.961094 12.507468 270)
			(size 0.4318 0.4318)
			(layers "F.Cu" "F.Mask" "F.Paste")
			(net "GND")
		)
		(pad "DE74" smd circle
			(at 23.58898 12.507468 270)
			(size 0.4318 0.4318)
			(layers "F.Cu" "F.Mask" "F.Paste")
			(net "GND")
		)
		(pad "DE76" smd circle
			(at 25.216612 12.507468 270)
			(size 0.4318 0.4318)
			(layers "F.Cu" "F.Mask" "F.Paste")
			(net "GND")
		)
		(pad "DE78" smd circle
			(at 26.844498 12.507468 270)
			(size 0.4318 0.4318)
			(layers "F.Cu" "F.Mask" "F.Paste")
			(net "GND")
		)
		(pad "DE80" smd circle
			(at 28.472384 12.507468 270)
			(size 0.4318 0.4318)
			(layers "F.Cu" "F.Mask" "F.Paste")
			(net "GND")
		)
		(pad "DE82" smd circle
			(at 30.100016 12.507468 270)
			(size 0.4318 0.4318)
			(layers "F.Cu" "F.Mask" "F.Paste")
			(net "GND")
		)
		(pad "DE84" smd circle
			(at 31.727902 12.507468 270)
			(size 0.4318 0.4318)
			(layers "F.Cu" "F.Mask" "F.Paste")
			(net "GND")
		)
		(pad "DE86" smd circle
			(at 33.355534 12.507468 270)
			(size 0.4318 0.4318)
			(layers "F.Cu" "F.Mask" "F.Paste")
			(net "P5E_CPU1_PE3_TX_DP<10>")
		)
		(pad "DE88" smd circle
			(at 34.98342 12.507468 270)
			(size 0.4318 0.4318)
			(layers "F.Cu" "F.Mask" "F.Paste")
			(net "GND")
		)
		(pad "DE90" smd circle
			(at 36.611306 12.507468 270)
			(size 0.4318 0.4318)
			(layers "F.Cu" "F.Mask" "F.Paste")
			(net "P5E_CPU1_PE3_RX_DP<11>")
		)
		(pad "DF2" smd circle
			(at -36.611306 12.867132 270)
			(size 0.4318 0.4318)
			(layers "F.Cu" "F.Mask" "F.Paste")
			(net "UPI_CPU0_CPU1_P0P1_DP<11>")
		)
		(pad "DF4" smd circle
			(at -34.98342 12.867132 270)
			(size 0.4318 0.4318)
			(layers "F.Cu" "F.Mask" "F.Paste")
			(net "GND")
		)
		(pad "DF6" smd circle
			(at -33.355534 12.867132 270)
			(size 0.4318 0.4318)
			(layers "F.Cu" "F.Mask" "F.Paste")
			(net "UPI_CPU1_CPU0_P1P0_DP<10>")
		)
		(pad "DF8" smd circle
			(at -31.727902 12.867132 270)
			(size 0.4318 0.4318)
			(layers "F.Cu" "F.Mask" "F.Paste")
			(net "GND")
		)
		(pad "DF10" smd circle
			(at -30.100016 12.867132 270)
			(size 0.4318 0.4318)
			(layers "F.Cu" "F.Mask" "F.Paste")
			(net "P5E_CPU1_PE2_RX_DP<4>")
		)
		(pad "DF12" smd circle
			(at -28.472384 12.867132 270)
			(size 0.4318 0.4318)
			(layers "F.Cu" "F.Mask" "F.Paste")
			(net "GND")
		)
		(pad "DF14" smd circle
			(at -26.844498 12.867132 270)
			(size 0.4318 0.4318)
			(layers "F.Cu" "F.Mask" "F.Paste")
			(net "P5E_CPU1_PE2_TX_DN<5>")
		)
		(pad "DF16" smd circle
			(at -25.216612 12.867132 270)
			(size 0.4318 0.4318)
			(layers "F.Cu" "F.Mask" "F.Paste")
			(net "GND")
		)
		(pad "DF18" smd circle
			(at -23.58898 12.867132 270)
			(size 0.4318 0.4318)
			(layers "F.Cu" "F.Mask" "F.Paste")
			(net "M_H_CPU1_SB_DQS_DN<8>")
		)
		(pad "DF20" smd circle
			(at -21.961094 12.867132 270)
			(size 0.4318 0.4318)
			(layers "F.Cu" "F.Mask" "F.Paste")
			(net "M_H_CPU1_SB_DQ<26>")
		)
		(pad "DF22" smd circle
			(at -20.333462 12.867132 270)
			(size 0.4318 0.4318)
			(layers "F.Cu" "F.Mask" "F.Paste")
			(net "M_H_CPU1_SB_DQ<15>")
		)
		(pad "DF24" smd circle
			(at -18.705576 12.867132 270)
			(size 0.4318 0.4318)
			(layers "F.Cu" "F.Mask" "F.Paste")
			(net "M_H_CPU1_SB_DQS_DP<6>")
		)
		(pad "DF26" smd circle
			(at -17.07769 12.867132 270)
			(size 0.4318 0.4318)
			(layers "F.Cu" "F.Mask" "F.Paste")
			(net "M_H_CPU1_SB_DQ<10>")
		)
		(pad "DF28" smd circle
			(at -15.450058 12.867132 270)
			(size 0.4318 0.4318)
			(layers "F.Cu" "F.Mask" "F.Paste")
			(net "M_H_CPU1_SB_DQ<5>")
		)
		(pad "DF30" smd circle
			(at -13.822426 12.867132 270)
			(size 0.4318 0.4318)
			(layers "F.Cu" "F.Mask" "F.Paste")
			(net "M_H_CPU1_SB_DQS_DP<5>")
		)
		(pad "DF32" smd circle
			(at -12.19454 12.867132 270)
			(size 0.4318 0.4318)
			(layers "F.Cu" "F.Mask" "F.Paste")
			(net "M_H_CPU1_SB_DQ<2>")
		)
		(pad "DF34" smd circle
			(at -10.566654 12.867132 270)
			(size 0.4318 0.4318)
			(layers "F.Cu" "F.Mask" "F.Paste")
			(net "M_H_CPU1_SB_CB<3>")
		)
		(pad "DF36" smd circle
			(at -8.939022 12.867132 270)
			(size 0.4318 0.4318)
			(layers "F.Cu" "F.Mask" "F.Paste")
			(net "M_H_CPU1_SB_DQS_DP<4>")
		)
		(pad "DF38" smd circle
			(at -7.311136 12.867132 270)
			(size 0.4318 0.4318)
			(layers "F.Cu" "F.Mask" "F.Paste")
			(net "M_H_CPU1_SB_CB<4>")
		)
		(pad "DF40" smd circle
			(at -5.68325 12.867132 270)
			(size 0.4318 0.4318)
			(layers "F.Cu" "F.Mask" "F.Paste")
			(net "M_H_CPU1_SB_CA<0>")
		)
		(pad "DF42" smd circle
			(at -4.055618 12.867132 270)
			(size 0.4318 0.4318)
			(layers "F.Cu" "F.Mask" "F.Paste")
			(net "M_H_CPU1_CLK_DP<0>")
		)
		(pad "DF44" smd circle
			(at -2.427732 12.867132 270)
			(size 0.4318 0.4318)
			(layers "F.Cu" "F.Mask" "F.Paste")
			(net "M_E_CPU1_SB_RSP<0>")
		)
		(pad "DF47" smd circle
			(at 1.613916 12.977114 270)
			(size 0.4318 0.4318)
			(layers "F.Cu" "F.Mask" "F.Paste")
			(net "M_H_CPU1_SA_CA<5>")
		)
		(pad "DF49" smd circle
			(at 3.241802 12.977114 270)
			(size 0.4318 0.4318)
			(layers "F.Cu" "F.Mask" "F.Paste")
			(net "GND")
		)
		(pad "DF51" smd circle
			(at 4.869434 12.977114 270)
			(size 0.4318 0.4318)
			(layers "F.Cu" "F.Mask" "F.Paste")
			(net "M_H_CPU1_SA_CS_N<0>")
		)
		(pad "DF53" smd circle
			(at 6.49732 12.977114 270)
			(size 0.4318 0.4318)
			(layers "F.Cu" "F.Mask" "F.Paste")
			(net "M_H_CPU1_SA_CB<7>")
		)
		(pad "DF55" smd circle
			(at 8.124952 12.977114 270)
			(size 0.4318 0.4318)
			(layers "F.Cu" "F.Mask" "F.Paste")
			(net "M_H_CPU1_SA_DQS_DP<9>")
		)
		(pad "DF57" smd circle
			(at 9.752838 12.977114 270)
			(size 0.4318 0.4318)
			(layers "F.Cu" "F.Mask" "F.Paste")
			(net "M_H_CPU1_SA_CB<2>")
		)
		(pad "DF59" smd circle
			(at 11.380724 12.977114 270)
			(size 0.4318 0.4318)
			(layers "F.Cu" "F.Mask" "F.Paste")
			(net "M_H_CPU1_SA_DQ<31>")
		)
		(pad "DF61" smd circle
			(at 13.008356 12.977114 270)
			(size 0.4318 0.4318)
			(layers "F.Cu" "F.Mask" "F.Paste")
			(net "M_H_CPU1_SA_DQS_DP<8>")
		)
		(pad "DF63" smd circle
			(at 14.635988 12.977114 270)
			(size 0.4318 0.4318)
			(layers "F.Cu" "F.Mask" "F.Paste")
			(net "M_H_CPU1_SA_DQ<26>")
		)
		(pad "DF65" smd circle
			(at 16.263874 12.977114 270)
			(size 0.4318 0.4318)
			(layers "F.Cu" "F.Mask" "F.Paste")
			(net "M_H_CPU1_SA_DQ<23>")
		)
		(pad "DF67" smd circle
			(at 17.89176 12.977114 270)
			(size 0.4318 0.4318)
			(layers "F.Cu" "F.Mask" "F.Paste")
			(net "M_H_CPU1_SA_DQS_DP<7>")
		)
		(pad "DF69" smd circle
			(at 19.519392 12.977114 270)
			(size 0.4318 0.4318)
			(layers "F.Cu" "F.Mask" "F.Paste")
			(net "M_H_CPU1_SA_DQ<18>")
		)
		(pad "DF71" smd circle
			(at 21.147278 12.977114 270)
			(size 0.4318 0.4318)
			(layers "F.Cu" "F.Mask" "F.Paste")
			(net "M_H_CPU1_SA_DQ<15>")
		)
		(pad "DF73" smd circle
			(at 22.77491 12.977114 270)
			(size 0.4318 0.4318)
			(layers "F.Cu" "F.Mask" "F.Paste")
			(net "M_H_CPU1_SA_DQS_DP<6>")
		)
		(pad "DF75" smd circle
			(at 24.402796 12.977114 270)
			(size 0.4318 0.4318)
			(layers "F.Cu" "F.Mask" "F.Paste")
			(net "M_H_CPU1_SA_DQ<10>")
		)
		(pad "DF77" smd circle
			(at 26.030682 12.977114 270)
			(size 0.4318 0.4318)
			(layers "F.Cu" "F.Mask" "F.Paste")
			(net "GND")
		)
		(pad "DF79" smd circle
			(at 27.658314 12.977114 270)
			(size 0.4318 0.4318)
			(layers "F.Cu" "F.Mask" "F.Paste")
			(net "GND")
		)
		(pad "DF81" smd circle
			(at 29.2862 12.977114 270)
			(size 0.4318 0.4318)
			(layers "F.Cu" "F.Mask" "F.Paste")
			(net "GND")
		)
		(pad "DF83" smd circle
			(at 30.914086 12.977114 270)
			(size 0.4318 0.4318)
			(layers "F.Cu" "F.Mask" "F.Paste")
			(net "GND")
		)
		(pad "DF85" smd circle
			(at 32.541718 12.977114 270)
			(size 0.4318 0.4318)
			(layers "F.Cu" "F.Mask" "F.Paste")
			(net "P5E_CPU1_PE3_TX_DN<9>")
		)
		(pad "DF87" smd circle
			(at 34.169604 12.977114 270)
			(size 0.4318 0.4318)
			(layers "F.Cu" "F.Mask" "F.Paste")
			(net "GND")
		)
		(pad "DF89" smd circle
			(at 35.797236 12.977114 270)
			(size 0.4318 0.4318)
			(layers "F.Cu" "F.Mask" "F.Paste")
			(net "P5E_CPU1_PE3_RX_DP<10>")
		)
		(pad "DF91" smd oval
			(at 37.425122 12.977114)
			(size 0.381 0.4826)
			(drill
				(offset 0 -0.0508)
			)
			(layers "F.Cu" "F.Mask" "F.Paste")
			(net "GND")
		)
		(pad "DG1" smd oval
			(at -37.425122 13.337286 180)
			(size 0.381 0.4826)
			(drill
				(offset 0 -0.0508)
			)
			(layers "F.Cu" "F.Mask" "F.Paste")
			(net "GND")
		)
		(pad "DG3" smd circle
			(at -35.797236 13.337286 270)
			(size 0.4318 0.4318)
			(layers "F.Cu" "F.Mask" "F.Paste")
			(net "UPI_CPU0_CPU1_P0P1_DN<10>")
		)
		(pad "DG5" smd circle
			(at -34.169604 13.337286 270)
			(size 0.4318 0.4318)
			(layers "F.Cu" "F.Mask" "F.Paste")
			(net "GND")
		)
		(pad "DG7" smd circle
			(at -32.541718 13.337286 270)
			(size 0.4318 0.4318)
			(layers "F.Cu" "F.Mask" "F.Paste")
			(net "UPI_CPU1_CPU0_P1P0_DP<9>")
		)
		(pad "DG9" smd circle
			(at -30.914086 13.337286 270)
			(size 0.4318 0.4318)
			(layers "F.Cu" "F.Mask" "F.Paste")
			(net "GND")
		)
		(pad "DG11" smd circle
			(at -29.2862 13.337286 270)
			(size 0.4318 0.4318)
			(layers "F.Cu" "F.Mask" "F.Paste")
			(net "P5E_CPU1_PE2_RX_DP<5>")
		)
		(pad "DG13" smd circle
			(at -27.658314 13.337286 270)
			(size 0.4318 0.4318)
			(layers "F.Cu" "F.Mask" "F.Paste")
			(net "GND")
		)
		(pad "DG15" smd circle
			(at -26.030682 13.337286 270)
			(size 0.4318 0.4318)
			(layers "F.Cu" "F.Mask" "F.Paste")
			(net "P5E_CPU1_PE2_TX_DP<5>")
		)
		(pad "DG17" smd circle
			(at -24.402796 13.337286 270)
			(size 0.4318 0.4318)
			(layers "F.Cu" "F.Mask" "F.Paste")
			(net "M_H_CPU1_SB_DQ<28>")
		)
		(pad "DG19" smd circle
			(at -22.77491 13.337286 270)
			(size 0.4318 0.4318)
			(layers "F.Cu" "F.Mask" "F.Paste")
			(net "M_H_CPU1_SB_DQ<27>")
		)
		(pad "DG21" smd circle
			(at -21.147278 13.337286 270)
			(size 0.4318 0.4318)
			(layers "F.Cu" "F.Mask" "F.Paste")
			(net "GND")
		)
		(pad "DG23" smd circle
			(at -19.519392 13.337286 270)
			(size 0.4318 0.4318)
			(layers "F.Cu" "F.Mask" "F.Paste")
			(net "M_H_CPU1_SB_DQ<14>")
		)
		(pad "DG25" smd circle
			(at -17.89176 13.337286 270)
			(size 0.4318 0.4318)
			(layers "F.Cu" "F.Mask" "F.Paste")
			(net "M_H_CPU1_SB_DQ<11>")
		)
		(pad "DG27" smd circle
			(at -16.263874 13.337286 270)
			(size 0.4318 0.4318)
			(layers "F.Cu" "F.Mask" "F.Paste")
			(net "GND")
		)
		(pad "DG29" smd circle
			(at -14.635988 13.337286 270)
			(size 0.4318 0.4318)
			(layers "F.Cu" "F.Mask" "F.Paste")
			(net "M_H_CPU1_SB_DQ<6>")
		)
		(pad "DG31" smd circle
			(at -13.008356 13.337286 270)
			(size 0.4318 0.4318)
			(layers "F.Cu" "F.Mask" "F.Paste")
			(net "M_H_CPU1_SB_DQ<3>")
		)
		(pad "DG33" smd circle
			(at -11.380724 13.337286 270)
			(size 0.4318 0.4318)
			(layers "F.Cu" "F.Mask" "F.Paste")
			(net "GND")
		)
		(pad "DG35" smd circle
			(at -9.752838 13.337286 270)
			(size 0.4318 0.4318)
			(layers "F.Cu" "F.Mask" "F.Paste")
			(net "M_H_CPU1_SB_CB<2>")
		)
		(pad "DG37" smd circle
			(at -8.124952 13.337286 270)
			(size 0.4318 0.4318)
			(layers "F.Cu" "F.Mask" "F.Paste")
			(net "M_H_CPU1_SB_CB<5>")
		)
		(pad "DG39" smd circle
			(at -6.49732 13.337286 270)
			(size 0.4318 0.4318)
			(layers "F.Cu" "F.Mask" "F.Paste")
			(net "GND")
		)
		(pad "DG41" smd circle
			(at -4.869434 13.337286 270)
			(size 0.4318 0.4318)
			(layers "F.Cu" "F.Mask" "F.Paste")
			(net "M_H_CPU1_SB_CA<1>")
		)
		(pad "DG43" smd circle
			(at -3.241802 13.337286 270)
			(size 0.4318 0.4318)
			(layers "F.Cu" "F.Mask" "F.Paste")
			(net "M_E_CPU1_SB_RSP<1>")
		)
		(pad "DG45" smd circle
			(at -1.613916 13.337286 270)
			(size 0.4318 0.4318)
			(layers "F.Cu" "F.Mask" "F.Paste")
			(net "GND")
		)
		(pad "DG48" smd circle
			(at 2.427732 13.447268 270)
			(size 0.4318 0.4318)
			(layers "F.Cu" "F.Mask" "F.Paste")
			(net "M_H_CPU1_SA_CA<3>")
		)
		(pad "DG50" smd circle
			(at 4.055618 13.447268 270)
			(size 0.4318 0.4318)
			(layers "F.Cu" "F.Mask" "F.Paste")
			(net "M_H_CPU1_SA_CS_N<1>")
		)
		(pad "DG52" smd circle
			(at 5.68325 13.447268 270)
			(size 0.4318 0.4318)
			(layers "F.Cu" "F.Mask" "F.Paste")
			(net "GND")
		)
		(pad "DG54" smd circle
			(at 7.311136 13.447268 270)
			(size 0.4318 0.4318)
			(layers "F.Cu" "F.Mask" "F.Paste")
			(net "M_H_CPU1_SA_CB<6>")
		)
		(pad "DG56" smd circle
			(at 8.939022 13.447268 270)
			(size 0.4318 0.4318)
			(layers "F.Cu" "F.Mask" "F.Paste")
			(net "M_H_CPU1_SA_CB<3>")
		)
		(pad "DG58" smd circle
			(at 10.566654 13.447268 270)
			(size 0.4318 0.4318)
			(layers "F.Cu" "F.Mask" "F.Paste")
			(net "GND")
		)
		(pad "DG60" smd circle
			(at 12.19454 13.447268 270)
			(size 0.4318 0.4318)
			(layers "F.Cu" "F.Mask" "F.Paste")
			(net "M_H_CPU1_SA_DQ<30>")
		)
		(pad "DG62" smd circle
			(at 13.822426 13.447268 270)
			(size 0.4318 0.4318)
			(layers "F.Cu" "F.Mask" "F.Paste")
			(net "M_H_CPU1_SA_DQ<27>")
		)
		(pad "DG64" smd circle
			(at 15.450058 13.447268 270)
			(size 0.4318 0.4318)
			(layers "F.Cu" "F.Mask" "F.Paste")
			(net "GND")
		)
		(pad "DG66" smd circle
			(at 17.07769 13.447268 270)
			(size 0.4318 0.4318)
			(layers "F.Cu" "F.Mask" "F.Paste")
			(net "M_H_CPU1_SA_DQ<22>")
		)
		(pad "DG68" smd circle
			(at 18.705576 13.447268 270)
			(size 0.4318 0.4318)
			(layers "F.Cu" "F.Mask" "F.Paste")
			(net "M_H_CPU1_SA_DQ<19>")
		)
		(pad "DG70" smd circle
			(at 20.333462 13.447268 270)
			(size 0.4318 0.4318)
			(layers "F.Cu" "F.Mask" "F.Paste")
			(net "GND")
		)
		(pad "DG72" smd circle
			(at 21.961094 13.447268 270)
			(size 0.4318 0.4318)
			(layers "F.Cu" "F.Mask" "F.Paste")
			(net "M_H_CPU1_SA_DQ<14>")
		)
		(pad "DG74" smd circle
			(at 23.58898 13.447268 270)
			(size 0.4318 0.4318)
			(layers "F.Cu" "F.Mask" "F.Paste")
			(net "M_H_CPU1_SA_DQ<11>")
		)
		(pad "DG76" smd circle
			(at 25.216612 13.447268 270)
			(size 0.4318 0.4318)
			(layers "F.Cu" "F.Mask" "F.Paste")
			(net "GND")
		)
		(pad "DG78" smd circle
			(at 26.844498 13.447268 270)
			(size 0.4318 0.4318)
			(layers "F.Cu" "F.Mask" "F.Paste")
			(net "GND")
		)
		(pad "DG80" smd circle
			(at 28.472384 13.447268 270)
			(size 0.4318 0.4318)
			(layers "F.Cu" "F.Mask" "F.Paste")
			(net "GND")
		)
		(pad "DG82" smd circle
			(at 30.100016 13.447268 270)
			(size 0.4318 0.4318)
			(layers "F.Cu" "F.Mask" "F.Paste")
			(net "GND")
		)
		(pad "DG84" smd circle
			(at 31.727902 13.447268 270)
			(size 0.4318 0.4318)
			(layers "F.Cu" "F.Mask" "F.Paste")
			(net "GND")
		)
		(pad "DG86" smd circle
			(at 33.355534 13.447268 270)
			(size 0.4318 0.4318)
			(layers "F.Cu" "F.Mask" "F.Paste")
			(net "P5E_CPU1_PE3_TX_DP<9>")
		)
		(pad "DG88" smd circle
			(at 34.98342 13.447268 270)
			(size 0.4318 0.4318)
			(layers "F.Cu" "F.Mask" "F.Paste")
			(net "GND")
		)
		(pad "DG90" smd circle
			(at 36.611306 13.447268 270)
			(size 0.4318 0.4318)
			(layers "F.Cu" "F.Mask" "F.Paste")
			(net "P5E_CPU1_PE3_RX_DN<10>")
		)
		(pad "DH2" smd circle
			(at -36.611306 13.806932 270)
			(size 0.4318 0.4318)
			(layers "F.Cu" "F.Mask" "F.Paste")
			(net "UPI_CPU0_CPU1_P0P1_DP<10>")
		)
		(pad "DH4" smd circle
			(at -34.98342 13.806932 270)
			(size 0.4318 0.4318)
			(layers "F.Cu" "F.Mask" "F.Paste")
			(net "GND")
		)
		(pad "DH6" smd circle
			(at -33.355534 13.806932 270)
			(size 0.4318 0.4318)
			(layers "F.Cu" "F.Mask" "F.Paste")
			(net "UPI_CPU1_CPU0_P1P0_DN<9>")
		)
		(pad "DH8" smd circle
			(at -31.727902 13.806932 270)
			(size 0.4318 0.4318)
			(layers "F.Cu" "F.Mask" "F.Paste")
			(net "GND")
		)
		(pad "DH10" smd circle
			(at -30.100016 13.806932 270)
			(size 0.4318 0.4318)
			(layers "F.Cu" "F.Mask" "F.Paste")
			(net "P5E_CPU1_PE2_RX_DN<5>")
		)
		(pad "DH12" smd circle
			(at -28.472384 13.806932 270)
			(size 0.4318 0.4318)
			(layers "F.Cu" "F.Mask" "F.Paste")
			(net "GND")
		)
		(pad "DH14" smd circle
			(at -26.844498 13.806932 270)
			(size 0.4318 0.4318)
			(layers "F.Cu" "F.Mask" "F.Paste")
			(net "P5E_CPU1_PE2_TX_DP<6>")
		)
		(pad "DH16" smd circle
			(at -25.216612 13.806932 270)
			(size 0.4318 0.4318)
			(layers "F.Cu" "F.Mask" "F.Paste")
			(net "GND")
		)
		(pad "DH18" smd circle
			(at -23.58898 13.806932 270)
			(size 0.4318 0.4318)
			(layers "F.Cu" "F.Mask" "F.Paste")
			(net "M_H_CPU1_SB_DQS_DP<8>")
		)
		(pad "DH20" smd circle
			(at -21.961094 13.806932 270)
			(size 0.4318 0.4318)
			(layers "F.Cu" "F.Mask" "F.Paste")
			(net "GND")
		)
		(pad "DH22" smd circle
			(at -20.333462 13.806932 270)
			(size 0.4318 0.4318)
			(layers "F.Cu" "F.Mask" "F.Paste")
			(net "GND")
		)
		(pad "DH24" smd circle
			(at -18.705576 13.806932 270)
			(size 0.4318 0.4318)
			(layers "F.Cu" "F.Mask" "F.Paste")
			(net "M_H_CPU1_SB_DQS_DN<6>")
		)
		(pad "DH26" smd circle
			(at -17.07769 13.806932 270)
			(size 0.4318 0.4318)
			(layers "F.Cu" "F.Mask" "F.Paste")
			(net "GND")
		)
		(pad "DH28" smd circle
			(at -15.450058 13.806932 270)
			(size 0.4318 0.4318)
			(layers "F.Cu" "F.Mask" "F.Paste")
			(net "GND")
		)
		(pad "DH30" smd circle
			(at -13.822426 13.806932 270)
			(size 0.4318 0.4318)
			(layers "F.Cu" "F.Mask" "F.Paste")
			(net "M_H_CPU1_SB_DQS_DN<5>")
		)
		(pad "DH32" smd circle
			(at -12.19454 13.806932 270)
			(size 0.4318 0.4318)
			(layers "F.Cu" "F.Mask" "F.Paste")
			(net "GND")
		)
		(pad "DH34" smd circle
			(at -10.566654 13.806932 270)
			(size 0.4318 0.4318)
			(layers "F.Cu" "F.Mask" "F.Paste")
			(net "GND")
		)
		(pad "DH36" smd circle
			(at -8.939022 13.806932 270)
			(size 0.4318 0.4318)
			(layers "F.Cu" "F.Mask" "F.Paste")
			(net "M_H_CPU1_SB_DQS_DN<4>")
		)
		(pad "DH38" smd circle
			(at -7.311136 13.806932 270)
			(size 0.4318 0.4318)
			(layers "F.Cu" "F.Mask" "F.Paste")
			(net "GND")
		)
		(pad "DH40" smd circle
			(at -5.68325 13.806932 270)
			(size 0.4318 0.4318)
			(layers "F.Cu" "F.Mask" "F.Paste")
			(net "GND")
		)
		(pad "DH42" smd circle
			(at -4.055618 13.806932 270)
			(size 0.4318 0.4318)
			(layers "F.Cu" "F.Mask" "F.Paste")
			(net "M_H_CPU1_CLK_DN<0>")
		)
		(pad "DH44" smd circle
			(at -2.427732 13.806932 270)
			(size 0.4318 0.4318)
			(layers "F.Cu" "F.Mask" "F.Paste")
			(net "GND")
		)
		(pad "DH47" smd circle
			(at 1.613916 13.916914 270)
			(size 0.4318 0.4318)
			(layers "F.Cu" "F.Mask" "F.Paste")
			(net "GND")
		)
		(pad "DH49" smd circle
			(at 3.241802 13.916914 270)
			(size 0.4318 0.4318)
			(layers "F.Cu" "F.Mask" "F.Paste")
			(net "M_H_CPU1_SA_CA<1>")
		)
		(pad "DH51" smd circle
			(at 4.869434 13.916914 270)
			(size 0.4318 0.4318)
			(layers "F.Cu" "F.Mask" "F.Paste")
			(net "GND")
		)
		(pad "DH53" smd circle
			(at 6.49732 13.916914 270)
			(size 0.4318 0.4318)
			(layers "F.Cu" "F.Mask" "F.Paste")
			(net "GND")
		)
		(pad "DH55" smd circle
			(at 8.124952 13.916914 270)
			(size 0.4318 0.4318)
			(layers "F.Cu" "F.Mask" "F.Paste")
			(net "M_H_CPU1_SA_DQS_DN<9>")
		)
		(pad "DH57" smd circle
			(at 9.752838 13.916914 270)
			(size 0.4318 0.4318)
			(layers "F.Cu" "F.Mask" "F.Paste")
			(net "GND")
		)
		(pad "DH59" smd circle
			(at 11.380724 13.916914 270)
			(size 0.4318 0.4318)
			(layers "F.Cu" "F.Mask" "F.Paste")
			(net "GND")
		)
		(pad "DH61" smd circle
			(at 13.008356 13.916914 270)
			(size 0.4318 0.4318)
			(layers "F.Cu" "F.Mask" "F.Paste")
			(net "M_H_CPU1_SA_DQS_DN<8>")
		)
		(pad "DH63" smd circle
			(at 14.635988 13.916914 270)
			(size 0.4318 0.4318)
			(layers "F.Cu" "F.Mask" "F.Paste")
			(net "GND")
		)
		(pad "DH65" smd circle
			(at 16.263874 13.916914 270)
			(size 0.4318 0.4318)
			(layers "F.Cu" "F.Mask" "F.Paste")
			(net "GND")
		)
		(pad "DH67" smd circle
			(at 17.89176 13.916914 270)
			(size 0.4318 0.4318)
			(layers "F.Cu" "F.Mask" "F.Paste")
			(net "M_H_CPU1_SA_DQS_DN<7>")
		)
		(pad "DH69" smd circle
			(at 19.519392 13.916914 270)
			(size 0.4318 0.4318)
			(layers "F.Cu" "F.Mask" "F.Paste")
			(net "GND")
		)
		(pad "DH71" smd circle
			(at 21.147278 13.916914 270)
			(size 0.4318 0.4318)
			(layers "F.Cu" "F.Mask" "F.Paste")
			(net "GND")
		)
		(pad "DH73" smd circle
			(at 22.77491 13.916914 270)
			(size 0.4318 0.4318)
			(layers "F.Cu" "F.Mask" "F.Paste")
			(net "M_H_CPU1_SA_DQS_DN<6>")
		)
		(pad "DH75" smd circle
			(at 24.402796 13.916914 270)
			(size 0.4318 0.4318)
			(layers "F.Cu" "F.Mask" "F.Paste")
			(net "GND")
		)
		(pad "DH77" smd circle
			(at 26.030682 13.916914 270)
			(size 0.4318 0.4318)
			(layers "F.Cu" "F.Mask" "F.Paste")
			(net "GND")
		)
		(pad "DH79" smd circle
			(at 27.658314 13.916914 270)
			(size 0.4318 0.4318)
			(layers "F.Cu" "F.Mask" "F.Paste")
			(net "GND")
		)
		(pad "DH81" smd circle
			(at 29.2862 13.916914 270)
			(size 0.4318 0.4318)
			(layers "F.Cu" "F.Mask" "F.Paste")
			(net "GND")
		)
		(pad "DH83" smd circle
			(at 30.914086 13.916914 270)
			(size 0.4318 0.4318)
			(layers "F.Cu" "F.Mask" "F.Paste")
			(net "GND")
		)
		(pad "DH85" smd circle
			(at 32.541718 13.916914 270)
			(size 0.4318 0.4318)
			(layers "F.Cu" "F.Mask" "F.Paste")
			(net "GND")
		)
		(pad "DH87" smd circle
			(at 34.169604 13.916914 270)
			(size 0.4318 0.4318)
			(layers "F.Cu" "F.Mask" "F.Paste")
			(net "P5E_CPU1_PE3_TX_DN<8>")
		)
		(pad "DH89" smd circle
			(at 35.797236 13.916914 270)
			(size 0.4318 0.4318)
			(layers "F.Cu" "F.Mask" "F.Paste")
			(net "PVCCFA_EHV_FIVRA_CPU1")
		)
		(pad "DH91" smd oval
			(at 37.425122 13.916914)
			(size 0.381 0.4826)
			(drill
				(offset 0 -0.0508)
			)
			(layers "F.Cu" "F.Mask" "F.Paste")
			(net "P5E_CPU1_PE3_RX_DN<9>")
		)
		(pad "DJ1" smd oval
			(at -37.425122 14.277086 180)
			(size 0.381 0.4826)
			(drill
				(offset 0 -0.0508)
			)
			(layers "F.Cu" "F.Mask" "F.Paste")
			(net "UPI_CPU0_CPU1_P0P1_DN<9>")
		)
		(pad "DJ3" smd circle
			(at -35.797236 14.277086 270)
			(size 0.4318 0.4318)
			(layers "F.Cu" "F.Mask" "F.Paste")
			(net "PVCCINFAON_CPU1")
		)
		(pad "DJ5" smd circle
			(at -34.169604 14.277086 270)
			(size 0.4318 0.4318)
			(layers "F.Cu" "F.Mask" "F.Paste")
			(net "UPI_CPU1_CPU0_P1P0_DP<8>")
		)
		(pad "DJ7" smd circle
			(at -32.541718 14.277086 270)
			(size 0.4318 0.4318)
			(layers "F.Cu" "F.Mask" "F.Paste")
			(net "PVCCINFAON_CPU1")
		)
		(pad "DJ9" smd circle
			(at -30.914086 14.277086 270)
			(size 0.4318 0.4318)
			(layers "F.Cu" "F.Mask" "F.Paste")
			(net "P5E_CPU1_PE2_RX_DN<6>")
		)
		(pad "DJ11" smd circle
			(at -29.2862 14.277086 270)
			(size 0.4318 0.4318)
			(layers "F.Cu" "F.Mask" "F.Paste")
			(net "PVCCINFAON_CPU1")
		)
		(pad "DJ13" smd circle
			(at -27.658314 14.277086 270)
			(size 0.4318 0.4318)
			(layers "F.Cu" "F.Mask" "F.Paste")
			(net "P5E_CPU1_PE2_TX_DN<6>")
		)
		(pad "DJ15" smd circle
			(at -26.030682 14.277086 270)
			(size 0.4318 0.4318)
			(layers "F.Cu" "F.Mask" "F.Paste")
			(net "PVCCINFAON_CPU1")
		)
		(pad "DJ17" smd circle
			(at -24.402796 14.277086 270)
			(size 0.4318 0.4318)
			(layers "F.Cu" "F.Mask" "F.Paste")
			(net "M_H_CPU1_SB_DQ<30>")
		)
		(pad "DJ19" smd circle
			(at -22.77491 14.277086 270)
			(size 0.4318 0.4318)
			(layers "F.Cu" "F.Mask" "F.Paste")
			(net "GND")
		)
		(pad "DJ21" smd circle
			(at -21.147278 14.277086 270)
			(size 0.4318 0.4318)
			(layers "F.Cu" "F.Mask" "F.Paste")
			(net "M_H_CPU1_SB_DQS_DP<2>")
		)
		(pad "DJ23" smd circle
			(at -19.519392 14.277086 270)
			(size 0.4318 0.4318)
			(layers "F.Cu" "F.Mask" "F.Paste")
			(net "GND")
		)
		(pad "DJ25" smd circle
			(at -17.89176 14.277086 270)
			(size 0.4318 0.4318)
			(layers "F.Cu" "F.Mask" "F.Paste")
			(net "GND")
		)
		(pad "DJ27" smd circle
			(at -16.263874 14.277086 270)
			(size 0.4318 0.4318)
			(layers "F.Cu" "F.Mask" "F.Paste")
			(net "M_G_CPU1_SB_DQS_DN<1>")
		)
		(pad "DJ29" smd circle
			(at -14.635988 14.277086 270)
			(size 0.4318 0.4318)
			(layers "F.Cu" "F.Mask" "F.Paste")
			(net "GND")
		)
		(pad "DJ31" smd circle
			(at -13.008356 14.277086 270)
			(size 0.4318 0.4318)
			(layers "F.Cu" "F.Mask" "F.Paste")
			(net "GND")
		)
		(pad "DJ33" smd circle
			(at -11.380724 14.277086 270)
			(size 0.4318 0.4318)
			(layers "F.Cu" "F.Mask" "F.Paste")
			(net "M_G_CPU1_SB_DQS_DN<0>")
		)
		(pad "DJ35" smd circle
			(at -9.752838 14.277086 270)
			(size 0.4318 0.4318)
			(layers "F.Cu" "F.Mask" "F.Paste")
			(net "GND")
		)
		(pad "DJ37" smd circle
			(at -8.124952 14.277086 270)
			(size 0.4318 0.4318)
			(layers "F.Cu" "F.Mask" "F.Paste")
			(net "GND")
		)
		(pad "DJ39" smd circle
			(at -6.49732 14.277086 270)
			(size 0.4318 0.4318)
			(layers "F.Cu" "F.Mask" "F.Paste")
			(net "M_H_CPU1_SB_CA<6>")
		)
		(pad "DJ41" smd circle
			(at -4.869434 14.277086 270)
			(size 0.4318 0.4318)
			(layers "F.Cu" "F.Mask" "F.Paste")
			(net "GND")
		)
		(pad "DJ43" smd circle
			(at -3.241802 14.277086 270)
			(size 0.4318 0.4318)
			(layers "F.Cu" "F.Mask" "F.Paste")
			(net "GND")
		)
		(pad "DJ45" smd circle
			(at -1.613916 14.277086 270)
			(size 0.4318 0.4318)
			(layers "F.Cu" "F.Mask" "F.Paste")
			(net "M_G_CPU1_CLK_DP<1>")
		)
		(pad "DJ48" smd circle
			(at 2.427732 14.387068 270)
			(size 0.4318 0.4318)
			(layers "F.Cu" "F.Mask" "F.Paste")
			(net "GND")
		)
		(pad "DJ50" smd circle
			(at 4.055618 14.387068 270)
			(size 0.4318 0.4318)
			(layers "F.Cu" "F.Mask" "F.Paste")
			(net "GND")
		)
		(pad "DJ52" smd circle
			(at 5.68325 14.387068 270)
			(size 0.4318 0.4318)
			(layers "F.Cu" "F.Mask" "F.Paste")
			(net "M_G_CPU1_SA_CA<0>")
		)
		(pad "DJ54" smd circle
			(at 7.311136 14.387068 270)
			(size 0.4318 0.4318)
			(layers "F.Cu" "F.Mask" "F.Paste")
			(net "GND")
		)
		(pad "DJ56" smd circle
			(at 8.939022 14.387068 270)
			(size 0.4318 0.4318)
			(layers "F.Cu" "F.Mask" "F.Paste")
			(net "GND")
		)
		(pad "DJ58" smd circle
			(at 10.566654 14.387068 270)
			(size 0.4318 0.4318)
			(layers "F.Cu" "F.Mask" "F.Paste")
			(net "M_G_CPU1_SA_DQS_DP<4>")
		)
		(pad "DJ60" smd circle
			(at 12.19454 14.387068 270)
			(size 0.4318 0.4318)
			(layers "F.Cu" "F.Mask" "F.Paste")
			(net "GND")
		)
		(pad "DJ62" smd circle
			(at 13.822426 14.387068 270)
			(size 0.4318 0.4318)
			(layers "F.Cu" "F.Mask" "F.Paste")
			(net "GND")
		)
		(pad "DJ64" smd circle
			(at 15.450058 14.387068 270)
			(size 0.4318 0.4318)
			(layers "F.Cu" "F.Mask" "F.Paste")
			(net "M_G_CPU1_SA_DQS_DP<3>")
		)
		(pad "DJ66" smd circle
			(at 17.07769 14.387068 270)
			(size 0.4318 0.4318)
			(layers "F.Cu" "F.Mask" "F.Paste")
			(net "GND")
		)
		(pad "DJ68" smd circle
			(at 18.705576 14.387068 270)
			(size 0.4318 0.4318)
			(layers "F.Cu" "F.Mask" "F.Paste")
			(net "GND")
		)
		(pad "DJ70" smd circle
			(at 20.333462 14.387068 270)
			(size 0.4318 0.4318)
			(layers "F.Cu" "F.Mask" "F.Paste")
			(net "M_G_CPU1_SA_DQS_DN<1>")
		)
		(pad "DJ72" smd circle
			(at 21.961094 14.387068 270)
			(size 0.4318 0.4318)
			(layers "F.Cu" "F.Mask" "F.Paste")
			(net "GND")
		)
		(pad "DJ74" smd circle
			(at 23.58898 14.387068 270)
			(size 0.4318 0.4318)
			(layers "F.Cu" "F.Mask" "F.Paste")
			(net "GND")
		)
		(pad "DJ76" smd circle
			(at 25.216612 14.387068 270)
			(size 0.4318 0.4318)
			(layers "F.Cu" "F.Mask" "F.Paste")
			(net "M_H_CPU1_SA_DQS_DN<0>")
		)
		(pad "DJ78" smd circle
			(at 26.844498 14.387068 270)
			(size 0.4318 0.4318)
			(layers "F.Cu" "F.Mask" "F.Paste")
			(net "GND")
		)
		(pad "DJ80" smd circle
			(at 28.472384 14.387068 270)
			(size 0.4318 0.4318)
			(layers "F.Cu" "F.Mask" "F.Paste")
			(net "GND")
		)
		(pad "DJ82" smd circle
			(at 30.100016 14.387068 270)
			(size 0.4318 0.4318)
			(layers "F.Cu" "F.Mask" "F.Paste")
			(net "GND")
		)
		(pad "DJ84" smd circle
			(at 31.727902 14.387068 270)
			(size 0.4318 0.4318)
			(layers "F.Cu" "F.Mask" "F.Paste")
			(net "GND")
		)
		(pad "DJ86" smd circle
			(at 33.355534 14.387068 270)
			(size 0.4318 0.4318)
			(layers "F.Cu" "F.Mask" "F.Paste")
			(net "P5E_CPU1_PE3_TX_DP<8>")
		)
		(pad "DJ88" smd circle
			(at 34.98342 14.387068 270)
			(size 0.4318 0.4318)
			(layers "F.Cu" "F.Mask" "F.Paste")
			(net "GND")
		)
		(pad "DJ90" smd circle
			(at 36.611306 14.387068 270)
			(size 0.4318 0.4318)
			(layers "F.Cu" "F.Mask" "F.Paste")
			(net "P5E_CPU1_PE3_RX_DP<9>")
		)
		(pad "DK2" smd circle
			(at -36.611306 14.746732 270)
			(size 0.4318 0.4318)
			(layers "F.Cu" "F.Mask" "F.Paste")
			(net "UPI_CPU0_CPU1_P0P1_DP<9>")
		)
		(pad "DK4" smd circle
			(at -34.98342 14.746732 270)
			(size 0.4318 0.4318)
			(layers "F.Cu" "F.Mask" "F.Paste")
			(net "GND")
		)
		(pad "DK6" smd circle
			(at -33.355534 14.746732 270)
			(size 0.4318 0.4318)
			(layers "F.Cu" "F.Mask" "F.Paste")
			(net "UPI_CPU1_CPU0_P1P0_DN<8>")
		)
		(pad "DK8" smd circle
			(at -31.727902 14.746732 270)
			(size 0.4318 0.4318)
			(layers "F.Cu" "F.Mask" "F.Paste")
			(net "GND")
		)
		(pad "DK10" smd circle
			(at -30.100016 14.746732 270)
			(size 0.4318 0.4318)
			(layers "F.Cu" "F.Mask" "F.Paste")
			(net "P5E_CPU1_PE2_RX_DP<6>")
		)
		(pad "DK12" smd circle
			(at -28.472384 14.746732 270)
			(size 0.4318 0.4318)
			(layers "F.Cu" "F.Mask" "F.Paste")
			(net "GND")
		)
		(pad "DK14" smd circle
			(at -26.844498 14.746732 270)
			(size 0.4318 0.4318)
			(layers "F.Cu" "F.Mask" "F.Paste")
			(net "P5E_CPU1_PE2_TX_DN<7>")
		)
		(pad "DK16" smd circle
			(at -25.216612 14.746732 270)
			(size 0.4318 0.4318)
			(layers "F.Cu" "F.Mask" "F.Paste")
			(net "GND")
		)
		(pad "DK18" smd circle
			(at -23.58898 14.746732 270)
			(size 0.4318 0.4318)
			(layers "F.Cu" "F.Mask" "F.Paste")
			(net "GND")
		)
		(pad "DK20" smd circle
			(at -21.961094 14.746732 270)
			(size 0.4318 0.4318)
			(layers "F.Cu" "F.Mask" "F.Paste")
			(net "M_H_CPU1_SB_DQ<20>")
		)
		(pad "DK22" smd circle
			(at -20.333462 14.746732 270)
			(size 0.4318 0.4318)
			(layers "F.Cu" "F.Mask" "F.Paste")
			(net "M_H_CPU1_SB_DQ<17>")
		)
		(pad "DK24" smd circle
			(at -18.705576 14.746732 270)
			(size 0.4318 0.4318)
			(layers "F.Cu" "F.Mask" "F.Paste")
			(net "GND")
		)
		(pad "DK26" smd circle
			(at -17.07769 14.746732 270)
			(size 0.4318 0.4318)
			(layers "F.Cu" "F.Mask" "F.Paste")
			(net "M_G_CPU1_SB_DQ<12>")
		)
		(pad "DK28" smd circle
			(at -15.450058 14.746732 270)
			(size 0.4318 0.4318)
			(layers "F.Cu" "F.Mask" "F.Paste")
			(net "M_G_CPU1_SB_DQ<9>")
		)
		(pad "DK30" smd circle
			(at -13.822426 14.746732 270)
			(size 0.4318 0.4318)
			(layers "F.Cu" "F.Mask" "F.Paste")
			(net "GND")
		)
		(pad "DK32" smd circle
			(at -12.19454 14.746732 270)
			(size 0.4318 0.4318)
			(layers "F.Cu" "F.Mask" "F.Paste")
			(net "M_G_CPU1_SB_DQ<4>")
		)
		(pad "DK34" smd circle
			(at -10.566654 14.746732 270)
			(size 0.4318 0.4318)
			(layers "F.Cu" "F.Mask" "F.Paste")
			(net "M_G_CPU1_SB_DQ<1>")
		)
		(pad "DK36" smd circle
			(at -8.939022 14.746732 270)
			(size 0.4318 0.4318)
			(layers "F.Cu" "F.Mask" "F.Paste")
			(net "GND")
		)
		(pad "DK38" smd circle
			(at -7.311136 14.746732 270)
			(size 0.4318 0.4318)
			(layers "F.Cu" "F.Mask" "F.Paste")
			(net "M_H_CPU1_SB_CS_N<2>")
		)
		(pad "DK40" smd circle
			(at -5.68325 14.746732 270)
			(size 0.4318 0.4318)
			(layers "F.Cu" "F.Mask" "F.Paste")
			(net "M_H_CPU1_SB_CA<4>")
		)
		(pad "DK42" smd circle
			(at -4.055618 14.746732 270)
			(size 0.4318 0.4318)
			(layers "F.Cu" "F.Mask" "F.Paste")
			(net "GND")
		)
		(pad "DK44" smd circle
			(at -2.427732 14.746732 270)
			(size 0.4318 0.4318)
			(layers "F.Cu" "F.Mask" "F.Paste")
			(net "M_G_CPU1_SA_CA<6>")
		)
		(pad "DK47" smd circle
			(at 1.613916 14.856714 270)
			(size 0.4318 0.4318)
			(layers "F.Cu" "F.Mask" "F.Paste")
			(net "M_F_CPU1_SB_RSP<1>")
		)
		(pad "DK49" smd circle
			(at 3.241802 14.856714 270)
			(size 0.4318 0.4318)
			(layers "F.Cu" "F.Mask" "F.Paste")
			(net "GND")
		)
		(pad "DK51" smd circle
			(at 4.869434 14.856714 270)
			(size 0.4318 0.4318)
			(layers "F.Cu" "F.Mask" "F.Paste")
			(net "M_G_CPU1_SA_CA<2>")
		)
		(pad "DK53" smd circle
			(at 6.49732 14.856714 270)
			(size 0.4318 0.4318)
			(layers "F.Cu" "F.Mask" "F.Paste")
			(net "M_G_CPU1_SA_CS_N<3>")
		)
		(pad "DK55" smd circle
			(at 8.124952 14.856714 270)
			(size 0.4318 0.4318)
			(layers "F.Cu" "F.Mask" "F.Paste")
			(net "GND")
		)
		(pad "DK57" smd circle
			(at 9.752838 14.856714 270)
			(size 0.4318 0.4318)
			(layers "F.Cu" "F.Mask" "F.Paste")
			(net "M_G_CPU1_SA_CB<4>")
		)
		(pad "DK59" smd circle
			(at 11.380724 14.856714 270)
			(size 0.4318 0.4318)
			(layers "F.Cu" "F.Mask" "F.Paste")
			(net "M_G_CPU1_SA_CB<1>")
		)
		(pad "DK61" smd circle
			(at 13.008356 14.856714 270)
			(size 0.4318 0.4318)
			(layers "F.Cu" "F.Mask" "F.Paste")
			(net "GND")
		)
		(pad "DK63" smd circle
			(at 14.635988 14.856714 270)
			(size 0.4318 0.4318)
			(layers "F.Cu" "F.Mask" "F.Paste")
			(net "M_G_CPU1_SA_DQ<28>")
		)
		(pad "DK65" smd circle
			(at 16.263874 14.856714 270)
			(size 0.4318 0.4318)
			(layers "F.Cu" "F.Mask" "F.Paste")
			(net "M_G_CPU1_SA_DQ<25>")
		)
		(pad "DK67" smd circle
			(at 17.89176 14.856714 270)
			(size 0.4318 0.4318)
			(layers "F.Cu" "F.Mask" "F.Paste")
			(net "GND")
		)
		(pad "DK69" smd circle
			(at 19.519392 14.856714 270)
			(size 0.4318 0.4318)
			(layers "F.Cu" "F.Mask" "F.Paste")
			(net "M_G_CPU1_SA_DQ<12>")
		)
		(pad "DK71" smd circle
			(at 21.147278 14.856714 270)
			(size 0.4318 0.4318)
			(layers "F.Cu" "F.Mask" "F.Paste")
			(net "M_G_CPU1_SA_DQ<9>")
		)
		(pad "DK73" smd circle
			(at 22.77491 14.856714 270)
			(size 0.4318 0.4318)
			(layers "F.Cu" "F.Mask" "F.Paste")
			(net "GND")
		)
		(pad "DK75" smd circle
			(at 24.402796 14.856714 270)
			(size 0.4318 0.4318)
			(layers "F.Cu" "F.Mask" "F.Paste")
			(net "M_H_CPU1_SA_DQ<4>")
		)
		(pad "DK77" smd circle
			(at 26.030682 14.856714 270)
			(size 0.4318 0.4318)
			(layers "F.Cu" "F.Mask" "F.Paste")
			(net "GND")
		)
		(pad "DK79" smd circle
			(at 27.658314 14.856714 270)
			(size 0.4318 0.4318)
			(layers "F.Cu" "F.Mask" "F.Paste")
			(net "GND")
		)
		(pad "DK81" smd circle
			(at 29.2862 14.856714 270)
			(size 0.4318 0.4318)
			(layers "F.Cu" "F.Mask" "F.Paste")
			(net "GND")
		)
		(pad "DK83" smd circle
			(at 30.914086 14.856714 270)
			(size 0.4318 0.4318)
			(layers "F.Cu" "F.Mask" "F.Paste")
			(net "GND")
		)
		(pad "DK85" smd circle
			(at 32.541718 14.856714 270)
			(size 0.4318 0.4318)
			(layers "F.Cu" "F.Mask" "F.Paste")
			(net "P5E_CPU1_PE3_TX_DN<7>")
		)
		(pad "DK87" smd circle
			(at 34.169604 14.856714 270)
			(size 0.4318 0.4318)
			(layers "F.Cu" "F.Mask" "F.Paste")
			(net "GND")
		)
		(pad "DK89" smd circle
			(at 35.797236 14.856714 270)
			(size 0.4318 0.4318)
			(layers "F.Cu" "F.Mask" "F.Paste")
			(net "P5E_CPU1_PE3_RX_DP<8>")
		)
		(pad "DK91" smd oval
			(at 37.425122 14.856714)
			(size 0.381 0.4826)
			(drill
				(offset 0 -0.0508)
			)
			(layers "F.Cu" "F.Mask" "F.Paste")
			(net "GND")
		)
		(pad "DL1" smd oval
			(at -37.425122 15.216886 180)
			(size 0.381 0.4826)
			(drill
				(offset 0 -0.0508)
			)
			(layers "F.Cu" "F.Mask" "F.Paste")
			(net "GND")
		)
		(pad "DL3" smd circle
			(at -35.797236 15.216886 270)
			(size 0.4318 0.4318)
			(layers "F.Cu" "F.Mask" "F.Paste")
			(net "UPI_CPU0_CPU1_P0P1_DN<8>")
		)
		(pad "DL5" smd circle
			(at -34.169604 15.216886 270)
			(size 0.4318 0.4318)
			(layers "F.Cu" "F.Mask" "F.Paste")
			(net "GND")
		)
		(pad "DL7" smd circle
			(at -32.541718 15.216886 270)
			(size 0.4318 0.4318)
			(layers "F.Cu" "F.Mask" "F.Paste")
			(net "UPI_CPU1_CPU0_P1P0_DN<7>")
		)
		(pad "DL9" smd circle
			(at -30.914086 15.216886 270)
			(size 0.4318 0.4318)
			(layers "F.Cu" "F.Mask" "F.Paste")
			(net "GND")
		)
		(pad "DL11" smd circle
			(at -29.2862 15.216886 270)
			(size 0.4318 0.4318)
			(layers "F.Cu" "F.Mask" "F.Paste")
			(net "P5E_CPU1_PE2_RX_DP<7>")
		)
		(pad "DL13" smd circle
			(at -27.658314 15.216886 270)
			(size 0.4318 0.4318)
			(layers "F.Cu" "F.Mask" "F.Paste")
			(net "GND")
		)
		(pad "DL15" smd circle
			(at -26.030682 15.216886 270)
			(size 0.4318 0.4318)
			(layers "F.Cu" "F.Mask" "F.Paste")
			(net "P5E_CPU1_PE2_TX_DP<7>")
		)
		(pad "DL17" smd circle
			(at -24.402796 15.216886 270)
			(size 0.4318 0.4318)
			(layers "F.Cu" "F.Mask" "F.Paste")
			(net "GND")
		)
		(pad "DL19" smd circle
			(at -22.77491 15.216886 270)
			(size 0.4318 0.4318)
			(layers "F.Cu" "F.Mask" "F.Paste")
			(net "M_H_CPU1_SB_DQ<21>")
		)
		(pad "DL21" smd circle
			(at -21.147278 15.216886 270)
			(size 0.4318 0.4318)
			(layers "F.Cu" "F.Mask" "F.Paste")
			(net "M_H_CPU1_SB_DQS_DN<2>")
		)
		(pad "DL23" smd circle
			(at -19.519392 15.216886 270)
			(size 0.4318 0.4318)
			(layers "F.Cu" "F.Mask" "F.Paste")
			(net "M_H_CPU1_SB_DQ<16>")
		)
		(pad "DL25" smd circle
			(at -17.89176 15.216886 270)
			(size 0.4318 0.4318)
			(layers "F.Cu" "F.Mask" "F.Paste")
			(net "M_G_CPU1_SB_DQ<13>")
		)
		(pad "DL27" smd circle
			(at -16.263874 15.216886 270)
			(size 0.4318 0.4318)
			(layers "F.Cu" "F.Mask" "F.Paste")
			(net "M_G_CPU1_SB_DQS_DP<1>")
		)
		(pad "DL29" smd circle
			(at -14.635988 15.216886 270)
			(size 0.4318 0.4318)
			(layers "F.Cu" "F.Mask" "F.Paste")
			(net "M_G_CPU1_SB_DQ<10>")
		)
		(pad "DL31" smd circle
			(at -13.008356 15.216886 270)
			(size 0.4318 0.4318)
			(layers "F.Cu" "F.Mask" "F.Paste")
			(net "M_G_CPU1_SB_DQ<5>")
		)
		(pad "DL33" smd circle
			(at -11.380724 15.216886 270)
			(size 0.4318 0.4318)
			(layers "F.Cu" "F.Mask" "F.Paste")
			(net "M_G_CPU1_SB_DQS_DP<0>")
		)
		(pad "DL35" smd circle
			(at -9.752838 15.216886 270)
			(size 0.4318 0.4318)
			(layers "F.Cu" "F.Mask" "F.Paste")
			(net "M_G_CPU1_SB_DQ<0>")
		)
		(pad "DL37" smd circle
			(at -8.124952 15.216886 270)
			(size 0.4318 0.4318)
			(layers "F.Cu" "F.Mask" "F.Paste")
			(net "M_H_CPU1_SB_CS_N<0>")
		)
		(pad "DL39" smd circle
			(at -6.49732 15.216886 270)
			(size 0.4318 0.4318)
			(layers "F.Cu" "F.Mask" "F.Paste")
			(net "GND")
		)
		(pad "DL41" smd circle
			(at -4.869434 15.216886 270)
			(size 0.4318 0.4318)
			(layers "F.Cu" "F.Mask" "F.Paste")
			(net "M_H_CPU1_SB_CA<2>")
		)
		(pad "DL43" smd circle
			(at -3.241802 15.216886 270)
			(size 0.4318 0.4318)
			(layers "F.Cu" "F.Mask" "F.Paste")
			(net "M_G_CPU1_SA_PAR")
		)
		(pad "DL45" smd circle
			(at -1.613916 15.216886 270)
			(size 0.4318 0.4318)
			(layers "F.Cu" "F.Mask" "F.Paste")
			(net "M_G_CPU1_CLK_DN<1>")
		)
		(pad "DL48" smd circle
			(at 2.427732 15.326868 270)
			(size 0.4318 0.4318)
			(layers "F.Cu" "F.Mask" "F.Paste")
			(net "M_F_CPU1_SB_RSP<0>")
		)
		(pad "DL50" smd circle
			(at 4.055618 15.326868 270)
			(size 0.4318 0.4318)
			(layers "F.Cu" "F.Mask" "F.Paste")
			(net "M_G_CPU1_SA_CA<4>")
		)
		(pad "DL52" smd circle
			(at 5.68325 15.326868 270)
			(size 0.4318 0.4318)
			(layers "F.Cu" "F.Mask" "F.Paste")
			(net "GND")
		)
		(pad "DL54" smd circle
			(at 7.311136 15.326868 270)
			(size 0.4318 0.4318)
			(layers "F.Cu" "F.Mask" "F.Paste")
			(net "M_G_CPU1_SA_CS_N<2>")
		)
		(pad "DL56" smd circle
			(at 8.939022 15.326868 270)
			(size 0.4318 0.4318)
			(layers "F.Cu" "F.Mask" "F.Paste")
			(net "M_G_CPU1_SA_CB<5>")
		)
		(pad "DL58" smd circle
			(at 10.566654 15.326868 270)
			(size 0.4318 0.4318)
			(layers "F.Cu" "F.Mask" "F.Paste")
			(net "M_G_CPU1_SA_DQS_DN<4>")
		)
		(pad "DL60" smd circle
			(at 12.19454 15.326868 270)
			(size 0.4318 0.4318)
			(layers "F.Cu" "F.Mask" "F.Paste")
			(net "M_G_CPU1_SA_CB<0>")
		)
		(pad "DL62" smd circle
			(at 13.822426 15.326868 270)
			(size 0.4318 0.4318)
			(layers "F.Cu" "F.Mask" "F.Paste")
			(net "M_G_CPU1_SA_DQ<29>")
		)
		(pad "DL64" smd circle
			(at 15.450058 15.326868 270)
			(size 0.4318 0.4318)
			(layers "F.Cu" "F.Mask" "F.Paste")
			(net "M_G_CPU1_SA_DQS_DN<3>")
		)
		(pad "DL66" smd circle
			(at 17.07769 15.326868 270)
			(size 0.4318 0.4318)
			(layers "F.Cu" "F.Mask" "F.Paste")
			(net "M_G_CPU1_SA_DQ<24>")
		)
		(pad "DL68" smd circle
			(at 18.705576 15.326868 270)
			(size 0.4318 0.4318)
			(layers "F.Cu" "F.Mask" "F.Paste")
			(net "M_G_CPU1_SA_DQ<13>")
		)
		(pad "DL70" smd circle
			(at 20.333462 15.326868 270)
			(size 0.4318 0.4318)
			(layers "F.Cu" "F.Mask" "F.Paste")
			(net "M_G_CPU1_SA_DQS_DP<1>")
		)
		(pad "DL72" smd circle
			(at 21.961094 15.326868 270)
			(size 0.4318 0.4318)
			(layers "F.Cu" "F.Mask" "F.Paste")
			(net "M_G_CPU1_SA_DQ<8>")
		)
		(pad "DL74" smd circle
			(at 23.58898 15.326868 270)
			(size 0.4318 0.4318)
			(layers "F.Cu" "F.Mask" "F.Paste")
			(net "M_H_CPU1_SA_DQ<5>")
		)
		(pad "DL76" smd circle
			(at 25.216612 15.326868 270)
			(size 0.4318 0.4318)
			(layers "F.Cu" "F.Mask" "F.Paste")
			(net "M_H_CPU1_SA_DQS_DP<0>")
		)
		(pad "DL78" smd circle
			(at 26.844498 15.326868 270)
			(size 0.4318 0.4318)
			(layers "F.Cu" "F.Mask" "F.Paste")
			(net "GND")
		)
		(pad "DL80" smd circle
			(at 28.472384 15.326868 270)
			(size 0.4318 0.4318)
			(layers "F.Cu" "F.Mask" "F.Paste")
			(net "Net_746")
		)
		(pad "DL82" smd circle
			(at 30.100016 15.326868 270)
			(size 0.4318 0.4318)
			(layers "F.Cu" "F.Mask" "F.Paste")
			(net "Net_723")
		)
		(pad "DL84" smd circle
			(at 31.727902 15.326868 270)
			(size 0.4318 0.4318)
			(layers "F.Cu" "F.Mask" "F.Paste")
			(net "GND")
		)
		(pad "DL86" smd circle
			(at 33.355534 15.326868 270)
			(size 0.4318 0.4318)
			(layers "F.Cu" "F.Mask" "F.Paste")
			(net "P5E_CPU1_PE3_TX_DP<7>")
		)
		(pad "DL88" smd circle
			(at 34.98342 15.326868 270)
			(size 0.4318 0.4318)
			(layers "F.Cu" "F.Mask" "F.Paste")
			(net "GND")
		)
		(pad "DL90" smd circle
			(at 36.611306 15.326868 270)
			(size 0.4318 0.4318)
			(layers "F.Cu" "F.Mask" "F.Paste")
			(net "P5E_CPU1_PE3_RX_DN<8>")
		)
		(pad "DM2" smd circle
			(at -36.611306 15.686532 270)
			(size 0.4318 0.4318)
			(layers "F.Cu" "F.Mask" "F.Paste")
			(net "UPI_CPU0_CPU1_P0P1_DP<8>")
		)
		(pad "DM4" smd circle
			(at -34.98342 15.686532 270)
			(size 0.4318 0.4318)
			(layers "F.Cu" "F.Mask" "F.Paste")
			(net "GND")
		)
		(pad "DM6" smd circle
			(at -33.355534 15.686532 270)
			(size 0.4318 0.4318)
			(layers "F.Cu" "F.Mask" "F.Paste")
			(net "UPI_CPU1_CPU0_P1P0_DP<7>")
		)
		(pad "DM8" smd circle
			(at -31.727902 15.686532 270)
			(size 0.4318 0.4318)
			(layers "F.Cu" "F.Mask" "F.Paste")
			(net "GND")
		)
		(pad "DM10" smd circle
			(at -30.100016 15.686532 270)
			(size 0.4318 0.4318)
			(layers "F.Cu" "F.Mask" "F.Paste")
			(net "P5E_CPU1_PE2_RX_DN<7>")
		)
		(pad "DM12" smd circle
			(at -28.472384 15.686532 270)
			(size 0.4318 0.4318)
			(layers "F.Cu" "F.Mask" "F.Paste")
			(net "GND")
		)
		(pad "DM14" smd circle
			(at -26.844498 15.686532 270)
			(size 0.4318 0.4318)
			(layers "F.Cu" "F.Mask" "F.Paste")
			(net "P5E_CPU1_PE2_TX_DP<8>")
		)
		(pad "DM16" smd circle
			(at -25.216612 15.686532 270)
			(size 0.4318 0.4318)
			(layers "F.Cu" "F.Mask" "F.Paste")
			(net "GND")
		)
		(pad "DM18" smd circle
			(at -23.58898 15.686532 270)
			(size 0.4318 0.4318)
			(layers "F.Cu" "F.Mask" "F.Paste")
			(net "GND")
		)
		(pad "DM20" smd circle
			(at -21.961094 15.686532 270)
			(size 0.4318 0.4318)
			(layers "F.Cu" "F.Mask" "F.Paste")
			(net "GND")
		)
		(pad "DM22" smd circle
			(at -20.333462 15.686532 270)
			(size 0.4318 0.4318)
			(layers "F.Cu" "F.Mask" "F.Paste")
			(net "GND")
		)
		(pad "DM24" smd circle
			(at -18.705576 15.686532 270)
			(size 0.4318 0.4318)
			(layers "F.Cu" "F.Mask" "F.Paste")
			(net "GND")
		)
		(pad "DM26" smd circle
			(at -17.07769 15.686532 270)
			(size 0.4318 0.4318)
			(layers "F.Cu" "F.Mask" "F.Paste")
			(net "GND")
		)
		(pad "DM28" smd circle
			(at -15.450058 15.686532 270)
			(size 0.4318 0.4318)
			(layers "F.Cu" "F.Mask" "F.Paste")
			(net "GND")
		)
		(pad "DM30" smd circle
			(at -13.822426 15.686532 270)
			(size 0.4318 0.4318)
			(layers "F.Cu" "F.Mask" "F.Paste")
			(net "GND")
		)
		(pad "DM32" smd circle
			(at -12.19454 15.686532 270)
			(size 0.4318 0.4318)
			(layers "F.Cu" "F.Mask" "F.Paste")
			(net "GND")
		)
		(pad "DM34" smd circle
			(at -10.566654 15.686532 270)
			(size 0.4318 0.4318)
			(layers "F.Cu" "F.Mask" "F.Paste")
			(net "GND")
		)
		(pad "DM36" smd circle
			(at -8.939022 15.686532 270)
			(size 0.4318 0.4318)
			(layers "F.Cu" "F.Mask" "F.Paste")
			(net "GND")
		)
		(pad "DM38" smd circle
			(at -7.311136 15.686532 270)
			(size 0.4318 0.4318)
			(layers "F.Cu" "F.Mask" "F.Paste")
			(net "GND")
		)
		(pad "DM40" smd circle
			(at -5.68325 15.686532 270)
			(size 0.4318 0.4318)
			(layers "F.Cu" "F.Mask" "F.Paste")
			(net "GND")
		)
		(pad "DM42" smd circle
			(at -4.055618 15.686532 270)
			(size 0.4318 0.4318)
			(layers "F.Cu" "F.Mask" "F.Paste")
			(net "GND")
		)
		(pad "DM44" smd circle
			(at -2.427732 15.686532 270)
			(size 0.4318 0.4318)
			(layers "F.Cu" "F.Mask" "F.Paste")
			(net "GND")
		)
		(pad "DM47" smd circle
			(at 1.613916 15.796514 270)
			(size 0.4318 0.4318)
			(layers "F.Cu" "F.Mask" "F.Paste")
			(net "GND")
		)
		(pad "DM49" smd circle
			(at 3.241802 15.796514 270)
			(size 0.4318 0.4318)
			(layers "F.Cu" "F.Mask" "F.Paste")
			(net "GND")
		)
		(pad "DM51" smd circle
			(at 4.869434 15.796514 270)
			(size 0.4318 0.4318)
			(layers "F.Cu" "F.Mask" "F.Paste")
			(net "GND")
		)
		(pad "DM53" smd circle
			(at 6.49732 15.796514 270)
			(size 0.4318 0.4318)
			(layers "F.Cu" "F.Mask" "F.Paste")
			(net "GND")
		)
		(pad "DM55" smd circle
			(at 8.124952 15.796514 270)
			(size 0.4318 0.4318)
			(layers "F.Cu" "F.Mask" "F.Paste")
			(net "GND")
		)
		(pad "DM57" smd circle
			(at 9.752838 15.796514 270)
			(size 0.4318 0.4318)
			(layers "F.Cu" "F.Mask" "F.Paste")
			(net "GND")
		)
		(pad "DM59" smd circle
			(at 11.380724 15.796514 270)
			(size 0.4318 0.4318)
			(layers "F.Cu" "F.Mask" "F.Paste")
			(net "GND")
		)
		(pad "DM61" smd circle
			(at 13.008356 15.796514 270)
			(size 0.4318 0.4318)
			(layers "F.Cu" "F.Mask" "F.Paste")
			(net "GND")
		)
		(pad "DM63" smd circle
			(at 14.635988 15.796514 270)
			(size 0.4318 0.4318)
			(layers "F.Cu" "F.Mask" "F.Paste")
			(net "GND")
		)
		(pad "DM65" smd circle
			(at 16.263874 15.796514 270)
			(size 0.4318 0.4318)
			(layers "F.Cu" "F.Mask" "F.Paste")
			(net "GND")
		)
		(pad "DM67" smd circle
			(at 17.89176 15.796514 270)
			(size 0.4318 0.4318)
			(layers "F.Cu" "F.Mask" "F.Paste")
			(net "GND")
		)
		(pad "DM69" smd circle
			(at 19.519392 15.796514 270)
			(size 0.4318 0.4318)
			(layers "F.Cu" "F.Mask" "F.Paste")
			(net "GND")
		)
		(pad "DM71" smd circle
			(at 21.147278 15.796514 270)
			(size 0.4318 0.4318)
			(layers "F.Cu" "F.Mask" "F.Paste")
			(net "GND")
		)
		(pad "DM73" smd circle
			(at 22.77491 15.796514 270)
			(size 0.4318 0.4318)
			(layers "F.Cu" "F.Mask" "F.Paste")
			(net "GND")
		)
		(pad "DM75" smd circle
			(at 24.402796 15.796514 270)
			(size 0.4318 0.4318)
			(layers "F.Cu" "F.Mask" "F.Paste")
			(net "GND")
		)
		(pad "DM77" smd circle
			(at 26.030682 15.796514 270)
			(size 0.4318 0.4318)
			(layers "F.Cu" "F.Mask" "F.Paste")
			(net "GND")
		)
		(pad "DM79" smd circle
			(at 27.658314 15.796514 270)
			(size 0.4318 0.4318)
			(layers "F.Cu" "F.Mask" "F.Paste")
			(net "GND")
		)
		(pad "DM81" smd circle
			(at 29.2862 15.796514 270)
			(size 0.4318 0.4318)
			(layers "F.Cu" "F.Mask" "F.Paste")
			(net "Net_747")
		)
		(pad "DM83" smd circle
			(at 30.914086 15.796514 270)
			(size 0.4318 0.4318)
			(layers "F.Cu" "F.Mask" "F.Paste")
			(net "PVCCFA_EHV_FIVRA_CPU1")
		)
		(pad "DM85" smd circle
			(at 32.541718 15.796514 270)
			(size 0.4318 0.4318)
			(layers "F.Cu" "F.Mask" "F.Paste")
			(net "PVCCFA_EHV_FIVRA_CPU1")
		)
		(pad "DM87" smd circle
			(at 34.169604 15.796514 270)
			(size 0.4318 0.4318)
			(layers "F.Cu" "F.Mask" "F.Paste")
			(net "P5E_CPU1_PE3_TX_DN<6>")
		)
		(pad "DM89" smd circle
			(at 35.797236 15.796514 270)
			(size 0.4318 0.4318)
			(layers "F.Cu" "F.Mask" "F.Paste")
			(net "PVCCFA_EHV_FIVRA_CPU1")
		)
		(pad "DM91" smd oval
			(at 37.425122 15.796514)
			(size 0.381 0.4826)
			(drill
				(offset 0 -0.0508)
			)
			(layers "F.Cu" "F.Mask" "F.Paste")
			(net "P5E_CPU1_PE3_RX_DP<7>")
		)
		(pad "DN1" smd oval
			(at -37.425122 16.156686 180)
			(size 0.381 0.4826)
			(drill
				(offset 0 -0.0508)
			)
			(layers "F.Cu" "F.Mask" "F.Paste")
			(net "UPI_CPU0_CPU1_P0P1_DN<7>")
		)
		(pad "DN3" smd circle
			(at -35.797236 16.156686 270)
			(size 0.4318 0.4318)
			(layers "F.Cu" "F.Mask" "F.Paste")
			(net "PVCCFA_EHV_FIVRA_CPU1")
		)
		(pad "DN5" smd circle
			(at -34.169604 16.156686 270)
			(size 0.4318 0.4318)
			(layers "F.Cu" "F.Mask" "F.Paste")
			(net "UPI_CPU1_CPU0_P1P0_DP<6>")
		)
		(pad "DN7" smd circle
			(at -32.541718 16.156686 270)
			(size 0.4318 0.4318)
			(layers "F.Cu" "F.Mask" "F.Paste")
			(net "PVCCFA_EHV_FIVRA_CPU1")
		)
		(pad "DN9" smd circle
			(at -30.914086 16.156686 270)
			(size 0.4318 0.4318)
			(layers "F.Cu" "F.Mask" "F.Paste")
			(net "P5E_CPU1_PE2_RX_DN<8>")
		)
		(pad "DN11" smd circle
			(at -29.2862 16.156686 270)
			(size 0.4318 0.4318)
			(layers "F.Cu" "F.Mask" "F.Paste")
			(net "PVCCFA_EHV_FIVRA_CPU1")
		)
		(pad "DN13" smd circle
			(at -27.658314 16.156686 270)
			(size 0.4318 0.4318)
			(layers "F.Cu" "F.Mask" "F.Paste")
			(net "P5E_CPU1_PE2_TX_DN<8>")
		)
		(pad "DN15" smd circle
			(at -26.030682 16.156686 270)
			(size 0.4318 0.4318)
			(layers "F.Cu" "F.Mask" "F.Paste")
			(net "PVCCFA_EHV_FIVRA_CPU1")
		)
		(pad "DN17" smd circle
			(at -24.402796 16.156686 270)
			(size 0.4318 0.4318)
			(layers "F.Cu" "F.Mask" "F.Paste")
			(net "GND")
		)
		(pad "DN19" smd circle
			(at -22.77491 16.156686 270)
			(size 0.4318 0.4318)
			(layers "F.Cu" "F.Mask" "F.Paste")
			(net "M_H_CPU1_SB_DQ<23>")
		)
		(pad "DN21" smd circle
			(at -21.147278 16.156686 270)
			(size 0.4318 0.4318)
			(layers "F.Cu" "F.Mask" "F.Paste")
			(net "M_H_CPU1_SB_DQS_DP<7>")
		)
		(pad "DN23" smd circle
			(at -19.519392 16.156686 270)
			(size 0.4318 0.4318)
			(layers "F.Cu" "F.Mask" "F.Paste")
			(net "M_H_CPU1_SB_DQ<18>")
		)
		(pad "DN25" smd circle
			(at -17.89176 16.156686 270)
			(size 0.4318 0.4318)
			(layers "F.Cu" "F.Mask" "F.Paste")
			(net "M_G_CPU1_SB_DQ<15>")
		)
		(pad "DN27" smd circle
			(at -16.263874 16.156686 270)
			(size 0.4318 0.4318)
			(layers "F.Cu" "F.Mask" "F.Paste")
			(net "M_G_CPU1_SB_DQS_DN<6>")
		)
		(pad "DN29" smd circle
			(at -14.635988 16.156686 270)
			(size 0.4318 0.4318)
			(layers "F.Cu" "F.Mask" "F.Paste")
			(net "M_G_CPU1_SB_DQ<8>")
		)
		(pad "DN31" smd circle
			(at -13.008356 16.156686 270)
			(size 0.4318 0.4318)
			(layers "F.Cu" "F.Mask" "F.Paste")
			(net "M_G_CPU1_SB_DQ<7>")
		)
		(pad "DN33" smd circle
			(at -11.380724 16.156686 270)
			(size 0.4318 0.4318)
			(layers "F.Cu" "F.Mask" "F.Paste")
			(net "M_G_CPU1_SB_DQS_DP<5>")
		)
		(pad "DN35" smd circle
			(at -9.752838 16.156686 270)
			(size 0.4318 0.4318)
			(layers "F.Cu" "F.Mask" "F.Paste")
			(net "M_G_CPU1_SB_DQ<2>")
		)
		(pad "DN37" smd circle
			(at -8.124952 16.156686 270)
			(size 0.4318 0.4318)
			(layers "F.Cu" "F.Mask" "F.Paste")
			(net "M_H_CPU1_SB_CS_N<1>")
		)
		(pad "DN39" smd circle
			(at -6.49732 16.156686 270)
			(size 0.4318 0.4318)
			(layers "F.Cu" "F.Mask" "F.Paste")
			(net "GND")
		)
		(pad "DN41" smd circle
			(at -4.869434 16.156686 270)
			(size 0.4318 0.4318)
			(layers "F.Cu" "F.Mask" "F.Paste")
			(net "M_H_CPU1_SB_CA<3>")
		)
		(pad "DN43" smd circle
			(at -3.241802 16.156686 270)
			(size 0.4318 0.4318)
			(layers "F.Cu" "F.Mask" "F.Paste")
			(net "M_G_CPU1_SB_CA<0>")
		)
		(pad "DN45" smd circle
			(at -1.613916 16.156686 270)
			(size 0.4318 0.4318)
			(layers "F.Cu" "F.Mask" "F.Paste")
			(net "M_G_CPU1_CLK_DP<0>")
		)
		(pad "DN48" smd circle
			(at 2.427732 16.266668 270)
			(size 0.4318 0.4318)
			(layers "F.Cu" "F.Mask" "F.Paste")
			(net "M_F_CPU1_SA_RSP<0>")
		)
		(pad "DN50" smd circle
			(at 4.055618 16.266668 270)
			(size 0.4318 0.4318)
			(layers "F.Cu" "F.Mask" "F.Paste")
			(net "M_G_CPU1_SA_CA<5>")
		)
		(pad "DN52" smd circle
			(at 5.68325 16.266668 270)
			(size 0.4318 0.4318)
			(layers "F.Cu" "F.Mask" "F.Paste")
			(net "GND")
		)
		(pad "DN54" smd circle
			(at 7.311136 16.266668 270)
			(size 0.4318 0.4318)
			(layers "F.Cu" "F.Mask" "F.Paste")
			(net "M_G_CPU1_SA_CS_N<0>")
		)
		(pad "DN56" smd circle
			(at 8.939022 16.266668 270)
			(size 0.4318 0.4318)
			(layers "F.Cu" "F.Mask" "F.Paste")
			(net "M_G_CPU1_SA_CB<7>")
		)
		(pad "DN58" smd circle
			(at 10.566654 16.266668 270)
			(size 0.4318 0.4318)
			(layers "F.Cu" "F.Mask" "F.Paste")
			(net "M_G_CPU1_SA_DQS_DP<9>")
		)
		(pad "DN60" smd circle
			(at 12.19454 16.266668 270)
			(size 0.4318 0.4318)
			(layers "F.Cu" "F.Mask" "F.Paste")
			(net "M_G_CPU1_SA_CB<2>")
		)
		(pad "DN62" smd circle
			(at 13.822426 16.266668 270)
			(size 0.4318 0.4318)
			(layers "F.Cu" "F.Mask" "F.Paste")
			(net "M_G_CPU1_SA_DQ<31>")
		)
		(pad "DN64" smd circle
			(at 15.450058 16.266668 270)
			(size 0.4318 0.4318)
			(layers "F.Cu" "F.Mask" "F.Paste")
			(net "M_G_CPU1_SA_DQS_DP<8>")
		)
		(pad "DN66" smd circle
			(at 17.07769 16.266668 270)
			(size 0.4318 0.4318)
			(layers "F.Cu" "F.Mask" "F.Paste")
			(net "M_G_CPU1_SA_DQ<26>")
		)
		(pad "DN68" smd circle
			(at 18.705576 16.266668 270)
			(size 0.4318 0.4318)
			(layers "F.Cu" "F.Mask" "F.Paste")
			(net "M_G_CPU1_SA_DQ<15>")
		)
		(pad "DN70" smd circle
			(at 20.333462 16.266668 270)
			(size 0.4318 0.4318)
			(layers "F.Cu" "F.Mask" "F.Paste")
			(net "M_G_CPU1_SA_DQS_DP<6>")
		)
		(pad "DN72" smd circle
			(at 21.961094 16.266668 270)
			(size 0.4318 0.4318)
			(layers "F.Cu" "F.Mask" "F.Paste")
			(net "M_G_CPU1_SA_DQ<10>")
		)
		(pad "DN74" smd circle
			(at 23.58898 16.266668 270)
			(size 0.4318 0.4318)
			(layers "F.Cu" "F.Mask" "F.Paste")
			(net "M_H_CPU1_SA_DQ<7>")
		)
		(pad "DN76" smd circle
			(at 25.216612 16.266668 270)
			(size 0.4318 0.4318)
			(layers "F.Cu" "F.Mask" "F.Paste")
			(net "M_H_CPU1_SA_DQS_DP<5>")
		)
		(pad "DN78" smd circle
			(at 26.844498 16.266668 270)
			(size 0.4318 0.4318)
			(layers "F.Cu" "F.Mask" "F.Paste")
			(net "GND")
		)
		(pad "DN80" smd circle
			(at 28.472384 16.266668 270)
			(size 0.4318 0.4318)
			(layers "F.Cu" "F.Mask" "F.Paste")
			(net "Net_722")
		)
		(pad "DN82" smd circle
			(at 30.100016 16.266668 270)
			(size 0.4318 0.4318)
			(layers "F.Cu" "F.Mask" "F.Paste")
			(net "Net_726")
		)
		(pad "DN84" smd circle
			(at 31.727902 16.266668 270)
			(size 0.4318 0.4318)
			(layers "F.Cu" "F.Mask" "F.Paste")
			(net "GND")
		)
		(pad "DN86" smd circle
			(at 33.355534 16.266668 270)
			(size 0.4318 0.4318)
			(layers "F.Cu" "F.Mask" "F.Paste")
			(net "P5E_CPU1_PE3_TX_DP<6>")
		)
		(pad "DN88" smd circle
			(at 34.98342 16.266668 270)
			(size 0.4318 0.4318)
			(layers "F.Cu" "F.Mask" "F.Paste")
			(net "GND")
		)
		(pad "DN90" smd circle
			(at 36.611306 16.266668 270)
			(size 0.4318 0.4318)
			(layers "F.Cu" "F.Mask" "F.Paste")
			(net "P5E_CPU1_PE3_RX_DN<7>")
		)
		(pad "DP2" smd circle
			(at -36.611306 16.626332 270)
			(size 0.4318 0.4318)
			(layers "F.Cu" "F.Mask" "F.Paste")
			(net "UPI_CPU0_CPU1_P0P1_DP<7>")
		)
		(pad "DP4" smd circle
			(at -34.98342 16.626332 270)
			(size 0.4318 0.4318)
			(layers "F.Cu" "F.Mask" "F.Paste")
			(net "GND")
		)
		(pad "DP6" smd circle
			(at -33.355534 16.626332 270)
			(size 0.4318 0.4318)
			(layers "F.Cu" "F.Mask" "F.Paste")
			(net "UPI_CPU1_CPU0_P1P0_DN<6>")
		)
		(pad "DP8" smd circle
			(at -31.727902 16.626332 270)
			(size 0.4318 0.4318)
			(layers "F.Cu" "F.Mask" "F.Paste")
			(net "GND")
		)
		(pad "DP10" smd circle
			(at -30.100016 16.626332 270)
			(size 0.4318 0.4318)
			(layers "F.Cu" "F.Mask" "F.Paste")
			(net "P5E_CPU1_PE2_RX_DP<8>")
		)
		(pad "DP12" smd circle
			(at -28.472384 16.626332 270)
			(size 0.4318 0.4318)
			(layers "F.Cu" "F.Mask" "F.Paste")
			(net "GND")
		)
		(pad "DP14" smd circle
			(at -26.844498 16.626332 270)
			(size 0.4318 0.4318)
			(layers "F.Cu" "F.Mask" "F.Paste")
			(net "P5E_CPU1_PE2_TX_DN<9>")
		)
		(pad "DP16" smd circle
			(at -25.216612 16.626332 270)
			(size 0.4318 0.4318)
			(layers "F.Cu" "F.Mask" "F.Paste")
			(net "GND")
		)
		(pad "DP18" smd circle
			(at -23.58898 16.626332 270)
			(size 0.4318 0.4318)
			(layers "F.Cu" "F.Mask" "F.Paste")
			(net "GND")
		)
		(pad "DP20" smd circle
			(at -21.961094 16.626332 270)
			(size 0.4318 0.4318)
			(layers "F.Cu" "F.Mask" "F.Paste")
			(net "M_H_CPU1_SB_DQ<22>")
		)
		(pad "DP22" smd circle
			(at -20.333462 16.626332 270)
			(size 0.4318 0.4318)
			(layers "F.Cu" "F.Mask" "F.Paste")
			(net "M_H_CPU1_SB_DQ<19>")
		)
		(pad "DP24" smd circle
			(at -18.705576 16.626332 270)
			(size 0.4318 0.4318)
			(layers "F.Cu" "F.Mask" "F.Paste")
			(net "GND")
		)
		(pad "DP26" smd circle
			(at -17.07769 16.626332 270)
			(size 0.4318 0.4318)
			(layers "F.Cu" "F.Mask" "F.Paste")
			(net "M_G_CPU1_SB_DQ<14>")
		)
		(pad "DP28" smd circle
			(at -15.450058 16.626332 270)
			(size 0.4318 0.4318)
			(layers "F.Cu" "F.Mask" "F.Paste")
			(net "M_G_CPU1_SB_DQ<11>")
		)
		(pad "DP30" smd circle
			(at -13.822426 16.626332 270)
			(size 0.4318 0.4318)
			(layers "F.Cu" "F.Mask" "F.Paste")
			(net "GND")
		)
		(pad "DP32" smd circle
			(at -12.19454 16.626332 270)
			(size 0.4318 0.4318)
			(layers "F.Cu" "F.Mask" "F.Paste")
			(net "M_G_CPU1_SB_DQ<6>")
		)
		(pad "DP34" smd circle
			(at -10.566654 16.626332 270)
			(size 0.4318 0.4318)
			(layers "F.Cu" "F.Mask" "F.Paste")
			(net "M_G_CPU1_SB_DQ<3>")
		)
		(pad "DP36" smd circle
			(at -8.939022 16.626332 270)
			(size 0.4318 0.4318)
			(layers "F.Cu" "F.Mask" "F.Paste")
			(net "GND")
		)
		(pad "DP38" smd circle
			(at -7.311136 16.626332 270)
			(size 0.4318 0.4318)
			(layers "F.Cu" "F.Mask" "F.Paste")
			(net "M_H_CPU1_SB_CS_N<3>")
		)
		(pad "DP40" smd circle
			(at -5.68325 16.626332 270)
			(size 0.4318 0.4318)
			(layers "F.Cu" "F.Mask" "F.Paste")
			(net "M_H_CPU1_SB_CA<5>")
		)
		(pad "DP42" smd circle
			(at -4.055618 16.626332 270)
			(size 0.4318 0.4318)
			(layers "F.Cu" "F.Mask" "F.Paste")
			(net "GND")
		)
		(pad "DP44" smd circle
			(at -2.427732 16.626332 270)
			(size 0.4318 0.4318)
			(layers "F.Cu" "F.Mask" "F.Paste")
			(net "M_G_CPU1_SB_CA<1>")
		)
		(pad "DP47" smd circle
			(at 1.613916 16.736314 270)
			(size 0.4318 0.4318)
			(layers "F.Cu" "F.Mask" "F.Paste")
			(net "M_F_CPU1_SA_RSP<1>")
		)
		(pad "DP49" smd circle
			(at 3.241802 16.736314 270)
			(size 0.4318 0.4318)
			(layers "F.Cu" "F.Mask" "F.Paste")
			(net "GND")
		)
		(pad "DP51" smd circle
			(at 4.869434 16.736314 270)
			(size 0.4318 0.4318)
			(layers "F.Cu" "F.Mask" "F.Paste")
			(net "M_G_CPU1_SA_CA<3>")
		)
		(pad "DP53" smd circle
			(at 6.49732 16.736314 270)
			(size 0.4318 0.4318)
			(layers "F.Cu" "F.Mask" "F.Paste")
			(net "M_G_CPU1_SA_CS_N<1>")
		)
		(pad "DP55" smd circle
			(at 8.124952 16.736314 270)
			(size 0.4318 0.4318)
			(layers "F.Cu" "F.Mask" "F.Paste")
			(net "GND")
		)
		(pad "DP57" smd circle
			(at 9.752838 16.736314 270)
			(size 0.4318 0.4318)
			(layers "F.Cu" "F.Mask" "F.Paste")
			(net "M_G_CPU1_SA_CB<6>")
		)
		(pad "DP59" smd circle
			(at 11.380724 16.736314 270)
			(size 0.4318 0.4318)
			(layers "F.Cu" "F.Mask" "F.Paste")
			(net "M_G_CPU1_SA_CB<3>")
		)
		(pad "DP61" smd circle
			(at 13.008356 16.736314 270)
			(size 0.4318 0.4318)
			(layers "F.Cu" "F.Mask" "F.Paste")
			(net "GND")
		)
		(pad "DP63" smd circle
			(at 14.635988 16.736314 270)
			(size 0.4318 0.4318)
			(layers "F.Cu" "F.Mask" "F.Paste")
			(net "M_G_CPU1_SA_DQ<30>")
		)
		(pad "DP65" smd circle
			(at 16.263874 16.736314 270)
			(size 0.4318 0.4318)
			(layers "F.Cu" "F.Mask" "F.Paste")
			(net "M_G_CPU1_SA_DQ<27>")
		)
		(pad "DP67" smd circle
			(at 17.89176 16.736314 270)
			(size 0.4318 0.4318)
			(layers "F.Cu" "F.Mask" "F.Paste")
			(net "GND")
		)
		(pad "DP69" smd circle
			(at 19.519392 16.736314 270)
			(size 0.4318 0.4318)
			(layers "F.Cu" "F.Mask" "F.Paste")
			(net "M_G_CPU1_SA_DQ<14>")
		)
		(pad "DP71" smd circle
			(at 21.147278 16.736314 270)
			(size 0.4318 0.4318)
			(layers "F.Cu" "F.Mask" "F.Paste")
			(net "M_G_CPU1_SA_DQ<11>")
		)
		(pad "DP73" smd circle
			(at 22.77491 16.736314 270)
			(size 0.4318 0.4318)
			(layers "F.Cu" "F.Mask" "F.Paste")
			(net "GND")
		)
		(pad "DP75" smd circle
			(at 24.402796 16.736314 270)
			(size 0.4318 0.4318)
			(layers "F.Cu" "F.Mask" "F.Paste")
			(net "M_H_CPU1_SA_DQ<6>")
		)
		(pad "DP77" smd circle
			(at 26.030682 16.736314 270)
			(size 0.4318 0.4318)
			(layers "F.Cu" "F.Mask" "F.Paste")
			(net "M_H_CPU1_SA_DQ<3>")
		)
		(pad "DP79" smd circle
			(at 27.658314 16.736314 270)
			(size 0.4318 0.4318)
			(layers "F.Cu" "F.Mask" "F.Paste")
			(net "Net_727")
		)
		(pad "DP81" smd circle
			(at 29.2862 16.736314 270)
			(size 0.4318 0.4318)
			(layers "F.Cu" "F.Mask" "F.Paste")
			(net "GND")
		)
		(pad "DP83" smd circle
			(at 30.914086 16.736314 270)
			(size 0.4318 0.4318)
			(layers "F.Cu" "F.Mask" "F.Paste")
			(net "Net_702")
		)
		(pad "DP85" smd circle
			(at 32.541718 16.736314 270)
			(size 0.4318 0.4318)
			(layers "F.Cu" "F.Mask" "F.Paste")
			(net "P5E_CPU1_PE3_TX_DN<5>")
		)
		(pad "DP87" smd circle
			(at 34.169604 16.736314 270)
			(size 0.4318 0.4318)
			(layers "F.Cu" "F.Mask" "F.Paste")
			(net "GND")
		)
		(pad "DP89" smd circle
			(at 35.797236 16.736314 270)
			(size 0.4318 0.4318)
			(layers "F.Cu" "F.Mask" "F.Paste")
			(net "P5E_CPU1_PE3_RX_DN<6>")
		)
		(pad "DP91" smd oval
			(at 37.425122 16.736314)
			(size 0.381 0.4826)
			(drill
				(offset 0 -0.0508)
			)
			(layers "F.Cu" "F.Mask" "F.Paste")
			(net "GND")
		)
		(pad "DR1" smd oval
			(at -37.425122 17.096486 180)
			(size 0.381 0.4826)
			(drill
				(offset 0 -0.0508)
			)
			(layers "F.Cu" "F.Mask" "F.Paste")
			(net "GND")
		)
		(pad "DR3" smd circle
			(at -35.797236 17.096486 270)
			(size 0.4318 0.4318)
			(layers "F.Cu" "F.Mask" "F.Paste")
			(net "UPI_CPU0_CPU1_P0P1_DP<6>")
		)
		(pad "DR5" smd circle
			(at -34.169604 17.096486 270)
			(size 0.4318 0.4318)
			(layers "F.Cu" "F.Mask" "F.Paste")
			(net "GND")
		)
		(pad "DR7" smd circle
			(at -32.541718 17.096486 270)
			(size 0.4318 0.4318)
			(layers "F.Cu" "F.Mask" "F.Paste")
			(net "UPI_CPU1_CPU0_P1P0_DP<5>")
		)
		(pad "DR9" smd circle
			(at -30.914086 17.096486 270)
			(size 0.4318 0.4318)
			(layers "F.Cu" "F.Mask" "F.Paste")
			(net "GND")
		)
		(pad "DR11" smd circle
			(at -29.2862 17.096486 270)
			(size 0.4318 0.4318)
			(layers "F.Cu" "F.Mask" "F.Paste")
			(net "P5E_CPU1_PE2_RX_DP<9>")
		)
		(pad "DR13" smd circle
			(at -27.658314 17.096486 270)
			(size 0.4318 0.4318)
			(layers "F.Cu" "F.Mask" "F.Paste")
			(net "GND")
		)
		(pad "DR15" smd circle
			(at -26.030682 17.096486 270)
			(size 0.4318 0.4318)
			(layers "F.Cu" "F.Mask" "F.Paste")
			(net "P5E_CPU1_PE2_TX_DP<9>")
		)
		(pad "DR17" smd circle
			(at -24.402796 17.096486 270)
			(size 0.4318 0.4318)
			(layers "F.Cu" "F.Mask" "F.Paste")
			(net "M_F_CPU1_SB_DQ<31>")
		)
		(pad "DR19" smd circle
			(at -22.77491 17.096486 270)
			(size 0.4318 0.4318)
			(layers "F.Cu" "F.Mask" "F.Paste")
			(net "GND")
		)
		(pad "DR21" smd circle
			(at -21.147278 17.096486 270)
			(size 0.4318 0.4318)
			(layers "F.Cu" "F.Mask" "F.Paste")
			(net "M_H_CPU1_SB_DQS_DN<7>")
		)
		(pad "DR23" smd circle
			(at -19.519392 17.096486 270)
			(size 0.4318 0.4318)
			(layers "F.Cu" "F.Mask" "F.Paste")
			(net "GND")
		)
		(pad "DR25" smd circle
			(at -17.89176 17.096486 270)
			(size 0.4318 0.4318)
			(layers "F.Cu" "F.Mask" "F.Paste")
			(net "GND")
		)
		(pad "DR27" smd circle
			(at -16.263874 17.096486 270)
			(size 0.4318 0.4318)
			(layers "F.Cu" "F.Mask" "F.Paste")
			(net "M_G_CPU1_SB_DQS_DP<6>")
		)
		(pad "DR29" smd circle
			(at -14.635988 17.096486 270)
			(size 0.4318 0.4318)
			(layers "F.Cu" "F.Mask" "F.Paste")
			(net "GND")
		)
		(pad "DR31" smd circle
			(at -13.008356 17.096486 270)
			(size 0.4318 0.4318)
			(layers "F.Cu" "F.Mask" "F.Paste")
			(net "GND")
		)
		(pad "DR33" smd circle
			(at -11.380724 17.096486 270)
			(size 0.4318 0.4318)
			(layers "F.Cu" "F.Mask" "F.Paste")
			(net "M_G_CPU1_SB_DQS_DN<5>")
		)
		(pad "DR35" smd circle
			(at -9.752838 17.096486 270)
			(size 0.4318 0.4318)
			(layers "F.Cu" "F.Mask" "F.Paste")
			(net "GND")
		)
		(pad "DR37" smd circle
			(at -8.124952 17.096486 270)
			(size 0.4318 0.4318)
			(layers "F.Cu" "F.Mask" "F.Paste")
			(net "GND")
		)
		(pad "DR39" smd circle
			(at -6.49732 17.096486 270)
			(size 0.4318 0.4318)
			(layers "F.Cu" "F.Mask" "F.Paste")
			(net "M_H_CPU1_SB_PAR")
		)
		(pad "DR41" smd circle
			(at -4.869434 17.096486 270)
			(size 0.4318 0.4318)
			(layers "F.Cu" "F.Mask" "F.Paste")
			(net "GND")
		)
		(pad "DR43" smd circle
			(at -3.241802 17.096486 270)
			(size 0.4318 0.4318)
			(layers "F.Cu" "F.Mask" "F.Paste")
			(net "GND")
		)
		(pad "DR45" smd circle
			(at -1.613916 17.096486 270)
			(size 0.4318 0.4318)
			(layers "F.Cu" "F.Mask" "F.Paste")
			(net "M_G_CPU1_CLK_DN<0>")
		)
		(pad "DR48" smd circle
			(at 2.427732 17.206468 270)
			(size 0.4318 0.4318)
			(layers "F.Cu" "F.Mask" "F.Paste")
			(net "GND")
		)
		(pad "DR50" smd circle
			(at 4.055618 17.206468 270)
			(size 0.4318 0.4318)
			(layers "F.Cu" "F.Mask" "F.Paste")
			(net "GND")
		)
		(pad "DR52" smd circle
			(at 5.68325 17.206468 270)
			(size 0.4318 0.4318)
			(layers "F.Cu" "F.Mask" "F.Paste")
			(net "M_G_CPU1_SA_CA<1>")
		)
		(pad "DR54" smd circle
			(at 7.311136 17.206468 270)
			(size 0.4318 0.4318)
			(layers "F.Cu" "F.Mask" "F.Paste")
			(net "GND")
		)
		(pad "DR56" smd circle
			(at 8.939022 17.206468 270)
			(size 0.4318 0.4318)
			(layers "F.Cu" "F.Mask" "F.Paste")
			(net "GND")
		)
		(pad "DR58" smd circle
			(at 10.566654 17.206468 270)
			(size 0.4318 0.4318)
			(layers "F.Cu" "F.Mask" "F.Paste")
			(net "M_G_CPU1_SA_DQS_DN<9>")
		)
		(pad "DR60" smd circle
			(at 12.19454 17.206468 270)
			(size 0.4318 0.4318)
			(layers "F.Cu" "F.Mask" "F.Paste")
			(net "GND")
		)
		(pad "DR62" smd circle
			(at 13.822426 17.206468 270)
			(size 0.4318 0.4318)
			(layers "F.Cu" "F.Mask" "F.Paste")
			(net "GND")
		)
		(pad "DR64" smd circle
			(at 15.450058 17.206468 270)
			(size 0.4318 0.4318)
			(layers "F.Cu" "F.Mask" "F.Paste")
			(net "M_G_CPU1_SA_DQS_DN<8>")
		)
		(pad "DR66" smd circle
			(at 17.07769 17.206468 270)
			(size 0.4318 0.4318)
			(layers "F.Cu" "F.Mask" "F.Paste")
			(net "GND")
		)
		(pad "DR68" smd circle
			(at 18.705576 17.206468 270)
			(size 0.4318 0.4318)
			(layers "F.Cu" "F.Mask" "F.Paste")
			(net "GND")
		)
		(pad "DR70" smd circle
			(at 20.333462 17.206468 270)
			(size 0.4318 0.4318)
			(layers "F.Cu" "F.Mask" "F.Paste")
			(net "M_G_CPU1_SA_DQS_DN<6>")
		)
		(pad "DR72" smd circle
			(at 21.961094 17.206468 270)
			(size 0.4318 0.4318)
			(layers "F.Cu" "F.Mask" "F.Paste")
			(net "GND")
		)
		(pad "DR74" smd circle
			(at 23.58898 17.206468 270)
			(size 0.4318 0.4318)
			(layers "F.Cu" "F.Mask" "F.Paste")
			(net "GND")
		)
		(pad "DR76" smd circle
			(at 25.216612 17.206468 270)
			(size 0.4318 0.4318)
			(layers "F.Cu" "F.Mask" "F.Paste")
			(net "M_H_CPU1_SA_DQS_DN<5>")
		)
		(pad "DR78" smd circle
			(at 26.844498 17.206468 270)
			(size 0.4318 0.4318)
			(layers "F.Cu" "F.Mask" "F.Paste")
			(net "GND")
		)
		(pad "DR80" smd circle
			(at 28.472384 17.206468 270)
			(size 0.4318 0.4318)
			(layers "F.Cu" "F.Mask" "F.Paste")
			(net "Net_703")
		)
		(pad "DR82" smd circle
			(at 30.100016 17.206468 270)
			(size 0.4318 0.4318)
			(layers "F.Cu" "F.Mask" "F.Paste")
			(net "Net_728")
		)
		(pad "DR84" smd circle
			(at 31.727902 17.206468 270)
			(size 0.4318 0.4318)
			(layers "F.Cu" "F.Mask" "F.Paste")
			(net "GND")
		)
		(pad "DR86" smd circle
			(at 33.355534 17.206468 270)
			(size 0.4318 0.4318)
			(layers "F.Cu" "F.Mask" "F.Paste")
			(net "P5E_CPU1_PE3_TX_DP<5>")
		)
		(pad "DR88" smd circle
			(at 34.98342 17.206468 270)
			(size 0.4318 0.4318)
			(layers "F.Cu" "F.Mask" "F.Paste")
			(net "GND")
		)
		(pad "DR90" smd circle
			(at 36.611306 17.206468 270)
			(size 0.4318 0.4318)
			(layers "F.Cu" "F.Mask" "F.Paste")
			(net "P5E_CPU1_PE3_RX_DP<6>")
		)
		(pad "DT2" smd circle
			(at -36.611306 17.566132 270)
			(size 0.4318 0.4318)
			(layers "F.Cu" "F.Mask" "F.Paste")
			(net "UPI_CPU0_CPU1_P0P1_DN<6>")
		)
		(pad "DT4" smd circle
			(at -34.98342 17.566132 270)
			(size 0.4318 0.4318)
			(layers "F.Cu" "F.Mask" "F.Paste")
			(net "GND")
		)
		(pad "DT6" smd circle
			(at -33.355534 17.566132 270)
			(size 0.4318 0.4318)
			(layers "F.Cu" "F.Mask" "F.Paste")
			(net "UPI_CPU1_CPU0_P1P0_DN<5>")
		)
		(pad "DT8" smd circle
			(at -31.727902 17.566132 270)
			(size 0.4318 0.4318)
			(layers "F.Cu" "F.Mask" "F.Paste")
			(net "GND")
		)
		(pad "DT10" smd circle
			(at -30.100016 17.566132 270)
			(size 0.4318 0.4318)
			(layers "F.Cu" "F.Mask" "F.Paste")
			(net "P5E_CPU1_PE2_RX_DN<9>")
		)
		(pad "DT12" smd circle
			(at -28.472384 17.566132 270)
			(size 0.4318 0.4318)
			(layers "F.Cu" "F.Mask" "F.Paste")
			(net "GND")
		)
		(pad "DT14" smd circle
			(at -26.844498 17.566132 270)
			(size 0.4318 0.4318)
			(layers "F.Cu" "F.Mask" "F.Paste")
			(net "P5E_CPU1_PE2_TX_DP<10>")
		)
		(pad "DT16" smd circle
			(at -25.216612 17.566132 270)
			(size 0.4318 0.4318)
			(layers "F.Cu" "F.Mask" "F.Paste")
			(net "GND")
		)
		(pad "DT18" smd circle
			(at -23.58898 17.566132 270)
			(size 0.4318 0.4318)
			(layers "F.Cu" "F.Mask" "F.Paste")
			(net "M_F_CPU1_SB_DQS_DN<3>")
		)
		(pad "DT20" smd circle
			(at -21.961094 17.566132 270)
			(size 0.4318 0.4318)
			(layers "F.Cu" "F.Mask" "F.Paste")
			(net "GND")
		)
		(pad "DT22" smd circle
			(at -20.333462 17.566132 270)
			(size 0.4318 0.4318)
			(layers "F.Cu" "F.Mask" "F.Paste")
			(net "GND")
		)
		(pad "DT24" smd circle
			(at -18.705576 17.566132 270)
			(size 0.4318 0.4318)
			(layers "F.Cu" "F.Mask" "F.Paste")
			(net "M_G_CPU1_SB_DQS_DP<2>")
		)
		(pad "DT26" smd circle
			(at -17.07769 17.566132 270)
			(size 0.4318 0.4318)
			(layers "F.Cu" "F.Mask" "F.Paste")
			(net "GND")
		)
		(pad "DT28" smd circle
			(at -15.450058 17.566132 270)
			(size 0.4318 0.4318)
			(layers "F.Cu" "F.Mask" "F.Paste")
			(net "GND")
		)
		(pad "DT30" smd circle
			(at -13.822426 17.566132 270)
			(size 0.4318 0.4318)
			(layers "F.Cu" "F.Mask" "F.Paste")
			(net "M_F_CPU1_SB_DQS_DP<0>")
		)
		(pad "DT32" smd circle
			(at -12.19454 17.566132 270)
			(size 0.4318 0.4318)
			(layers "F.Cu" "F.Mask" "F.Paste")
			(net "GND")
		)
		(pad "DT34" smd circle
			(at -10.566654 17.566132 270)
			(size 0.4318 0.4318)
			(layers "F.Cu" "F.Mask" "F.Paste")
			(net "GND")
		)
		(pad "DT36" smd circle
			(at -8.939022 17.566132 270)
			(size 0.4318 0.4318)
			(layers "F.Cu" "F.Mask" "F.Paste")
			(net "M_G_CPU1_SB_DQS_DP<9>")
		)
		(pad "DT38" smd circle
			(at -7.311136 17.566132 270)
			(size 0.4318 0.4318)
			(layers "F.Cu" "F.Mask" "F.Paste")
			(net "GND")
		)
		(pad "DT40" smd circle
			(at -5.68325 17.566132 270)
			(size 0.4318 0.4318)
			(layers "F.Cu" "F.Mask" "F.Paste")
			(net "GND")
		)
		(pad "DT42" smd circle
			(at -4.055618 17.566132 270)
			(size 0.4318 0.4318)
			(layers "F.Cu" "F.Mask" "F.Paste")
			(net "M_G_CPU1_SB_CA<6>")
		)
		(pad "DT44" smd circle
			(at -2.427732 17.566132 270)
			(size 0.4318 0.4318)
			(layers "F.Cu" "F.Mask" "F.Paste")
			(net "GND")
		)
		(pad "DT47" smd circle
			(at 1.613916 17.676114 270)
			(size 0.4318 0.4318)
			(layers "F.Cu" "F.Mask" "F.Paste")
			(net "GND")
		)
		(pad "DT49" smd circle
			(at 3.241802 17.676114 270)
			(size 0.4318 0.4318)
			(layers "F.Cu" "F.Mask" "F.Paste")
			(net "M_F_CPU1_CLK_DP<1>")
		)
		(pad "DT51" smd circle
			(at 4.869434 17.676114 270)
			(size 0.4318 0.4318)
			(layers "F.Cu" "F.Mask" "F.Paste")
			(net "GND")
		)
		(pad "DT53" smd circle
			(at 6.49732 17.676114 270)
			(size 0.4318 0.4318)
			(layers "F.Cu" "F.Mask" "F.Paste")
			(net "GND")
		)
		(pad "DT55" smd circle
			(at 8.124952 17.676114 270)
			(size 0.4318 0.4318)
			(layers "F.Cu" "F.Mask" "F.Paste")
			(net "M_F_CPU1_SA_DQS_DP<3>")
		)
		(pad "DT57" smd circle
			(at 9.752838 17.676114 270)
			(size 0.4318 0.4318)
			(layers "F.Cu" "F.Mask" "F.Paste")
			(net "GND")
		)
		(pad "DT59" smd circle
			(at 11.380724 17.676114 270)
			(size 0.4318 0.4318)
			(layers "F.Cu" "F.Mask" "F.Paste")
			(net "GND")
		)
		(pad "DT61" smd circle
			(at 13.008356 17.676114 270)
			(size 0.4318 0.4318)
			(layers "F.Cu" "F.Mask" "F.Paste")
			(net "M_G_CPU1_SA_DQS_DN<2>")
		)
		(pad "DT63" smd circle
			(at 14.635988 17.676114 270)
			(size 0.4318 0.4318)
			(layers "F.Cu" "F.Mask" "F.Paste")
			(net "GND")
		)
		(pad "DT65" smd circle
			(at 16.263874 17.676114 270)
			(size 0.4318 0.4318)
			(layers "F.Cu" "F.Mask" "F.Paste")
			(net "GND")
		)
		(pad "DT67" smd circle
			(at 17.89176 17.676114 270)
			(size 0.4318 0.4318)
			(layers "F.Cu" "F.Mask" "F.Paste")
			(net "M_F_CPU1_SA_DQS_DN<1>")
		)
		(pad "DT69" smd circle
			(at 19.519392 17.676114 270)
			(size 0.4318 0.4318)
			(layers "F.Cu" "F.Mask" "F.Paste")
			(net "GND")
		)
		(pad "DT71" smd circle
			(at 21.147278 17.676114 270)
			(size 0.4318 0.4318)
			(layers "F.Cu" "F.Mask" "F.Paste")
			(net "GND")
		)
		(pad "DT73" smd circle
			(at 22.77491 17.676114 270)
			(size 0.4318 0.4318)
			(layers "F.Cu" "F.Mask" "F.Paste")
			(net "M_G_CPU1_SA_DQS_DP<0>")
		)
		(pad "DT75" smd circle
			(at 24.402796 17.676114 270)
			(size 0.4318 0.4318)
			(layers "F.Cu" "F.Mask" "F.Paste")
			(net "GND")
		)
		(pad "DT77" smd circle
			(at 26.030682 17.676114 270)
			(size 0.4318 0.4318)
			(layers "F.Cu" "F.Mask" "F.Paste")
			(net "M_H_CPU1_SA_DQ<1>")
		)
		(pad "DT79" smd circle
			(at 27.658314 17.676114 270)
			(size 0.4318 0.4318)
			(layers "F.Cu" "F.Mask" "F.Paste")
			(net "PVCCFA_EHV_FIVRA_CPU1")
		)
		(pad "DT81" smd circle
			(at 29.2862 17.676114 270)
			(size 0.4318 0.4318)
			(layers "F.Cu" "F.Mask" "F.Paste")
			(net "Net_705")
		)
		(pad "DT83" smd circle
			(at 30.914086 17.676114 270)
			(size 0.4318 0.4318)
			(layers "F.Cu" "F.Mask" "F.Paste")
			(net "GND")
		)
		(pad "DT85" smd circle
			(at 32.541718 17.676114 270)
			(size 0.4318 0.4318)
			(layers "F.Cu" "F.Mask" "F.Paste")
			(net "PVCCFA_EHV_FIVRA_CPU1")
		)
		(pad "DT87" smd circle
			(at 34.169604 17.676114 270)
			(size 0.4318 0.4318)
			(layers "F.Cu" "F.Mask" "F.Paste")
			(net "P5E_CPU1_PE3_TX_DN<4>")
		)
		(pad "DT89" smd circle
			(at 35.797236 17.676114 270)
			(size 0.4318 0.4318)
			(layers "F.Cu" "F.Mask" "F.Paste")
			(net "PVCCFA_EHV_FIVRA_CPU1")
		)
		(pad "DT91" smd oval
			(at 37.425122 17.676114)
			(size 0.381 0.4826)
			(drill
				(offset 0 -0.0508)
			)
			(layers "F.Cu" "F.Mask" "F.Paste")
			(net "P5E_CPU1_PE3_RX_DP<5>")
		)
		(pad "DU1" smd oval
			(at -37.425122 18.036286 180)
			(size 0.381 0.4826)
			(drill
				(offset 0 -0.0508)
			)
			(layers "F.Cu" "F.Mask" "F.Paste")
			(net "UPI_CPU0_CPU1_P0P1_DN<5>")
		)
		(pad "DU3" smd circle
			(at -35.797236 18.036286 270)
			(size 0.4318 0.4318)
			(layers "F.Cu" "F.Mask" "F.Paste")
			(net "PVCCFA_EHV_FIVRA_CPU1")
		)
		(pad "DU5" smd circle
			(at -34.169604 18.036286 270)
			(size 0.4318 0.4318)
			(layers "F.Cu" "F.Mask" "F.Paste")
			(net "UPI_CPU1_CPU0_P1P0_DP<4>")
		)
		(pad "DU7" smd circle
			(at -32.541718 18.036286 270)
			(size 0.4318 0.4318)
			(layers "F.Cu" "F.Mask" "F.Paste")
			(net "PVCCFA_EHV_FIVRA_CPU1")
		)
		(pad "DU9" smd circle
			(at -30.914086 18.036286 270)
			(size 0.4318 0.4318)
			(layers "F.Cu" "F.Mask" "F.Paste")
			(net "P5E_CPU1_PE2_RX_DN<10>")
		)
		(pad "DU11" smd circle
			(at -29.2862 18.036286 270)
			(size 0.4318 0.4318)
			(layers "F.Cu" "F.Mask" "F.Paste")
			(net "PVCCFA_EHV_FIVRA_CPU1")
		)
		(pad "DU13" smd circle
			(at -27.658314 18.036286 270)
			(size 0.4318 0.4318)
			(layers "F.Cu" "F.Mask" "F.Paste")
			(net "P5E_CPU1_PE2_TX_DN<10>")
		)
		(pad "DU15" smd circle
			(at -26.030682 18.036286 270)
			(size 0.4318 0.4318)
			(layers "F.Cu" "F.Mask" "F.Paste")
			(net "PVCCFA_EHV_FIVRA_CPU1")
		)
		(pad "DU17" smd circle
			(at -24.402796 18.036286 270)
			(size 0.4318 0.4318)
			(layers "F.Cu" "F.Mask" "F.Paste")
			(net "M_F_CPU1_SB_DQ<29>")
		)
		(pad "DU19" smd circle
			(at -22.77491 18.036286 270)
			(size 0.4318 0.4318)
			(layers "F.Cu" "F.Mask" "F.Paste")
			(net "M_F_CPU1_SB_DQ<25>")
		)
		(pad "DU21" smd circle
			(at -21.147278 18.036286 270)
			(size 0.4318 0.4318)
			(layers "F.Cu" "F.Mask" "F.Paste")
			(net "GND")
		)
		(pad "DU23" smd circle
			(at -19.519392 18.036286 270)
			(size 0.4318 0.4318)
			(layers "F.Cu" "F.Mask" "F.Paste")
			(net "M_G_CPU1_SB_DQ<20>")
		)
		(pad "DU25" smd circle
			(at -17.89176 18.036286 270)
			(size 0.4318 0.4318)
			(layers "F.Cu" "F.Mask" "F.Paste")
			(net "M_G_CPU1_SB_DQ<17>")
		)
		(pad "DU27" smd circle
			(at -16.263874 18.036286 270)
			(size 0.4318 0.4318)
			(layers "F.Cu" "F.Mask" "F.Paste")
			(net "GND")
		)
		(pad "DU29" smd circle
			(at -14.635988 18.036286 270)
			(size 0.4318 0.4318)
			(layers "F.Cu" "F.Mask" "F.Paste")
			(net "M_F_CPU1_SB_DQ<4>")
		)
		(pad "DU31" smd circle
			(at -13.008356 18.036286 270)
			(size 0.4318 0.4318)
			(layers "F.Cu" "F.Mask" "F.Paste")
			(net "M_F_CPU1_SB_DQ<1>")
		)
		(pad "DU33" smd circle
			(at -11.380724 18.036286 270)
			(size 0.4318 0.4318)
			(layers "F.Cu" "F.Mask" "F.Paste")
			(net "GND")
		)
		(pad "DU35" smd circle
			(at -9.752838 18.036286 270)
			(size 0.4318 0.4318)
			(layers "F.Cu" "F.Mask" "F.Paste")
			(net "M_G_CPU1_SB_CB<0>")
		)
		(pad "DU37" smd circle
			(at -8.124952 18.036286 270)
			(size 0.4318 0.4318)
			(layers "F.Cu" "F.Mask" "F.Paste")
			(net "M_G_CPU1_SB_CB<5>")
		)
		(pad "DU39" smd circle
			(at -6.49732 18.036286 270)
			(size 0.4318 0.4318)
			(layers "F.Cu" "F.Mask" "F.Paste")
			(net "GND")
		)
		(pad "DU41" smd circle
			(at -4.869434 18.036286 270)
			(size 0.4318 0.4318)
			(layers "F.Cu" "F.Mask" "F.Paste")
			(net "M_G_CPU1_SB_CS_N<2>")
		)
		(pad "DU43" smd circle
			(at -3.241802 18.036286 270)
			(size 0.4318 0.4318)
			(layers "F.Cu" "F.Mask" "F.Paste")
			(net "M_G_CPU1_SB_CA<4>")
		)
		(pad "DU45" smd circle
			(at -1.613916 18.036286 270)
			(size 0.4318 0.4318)
			(layers "F.Cu" "F.Mask" "F.Paste")
			(net "GND")
		)
		(pad "DU48" smd circle
			(at 2.427732 18.146268 270)
			(size 0.4318 0.4318)
			(layers "F.Cu" "F.Mask" "F.Paste")
			(net "M_G_CPU1_SB_RSP<0>")
		)
		(pad "DU50" smd circle
			(at 4.055618 18.146268 270)
			(size 0.4318 0.4318)
			(layers "F.Cu" "F.Mask" "F.Paste")
			(net "M_F_CPU1_SB_CA<1>")
		)
		(pad "DU52" smd circle
			(at 5.68325 18.146268 270)
			(size 0.4318 0.4318)
			(layers "F.Cu" "F.Mask" "F.Paste")
			(net "GND")
		)
		(pad "DU54" smd circle
			(at 7.311136 18.146268 270)
			(size 0.4318 0.4318)
			(layers "F.Cu" "F.Mask" "F.Paste")
			(net "M_F_CPU1_SA_DQ<28>")
		)
		(pad "DU56" smd circle
			(at 8.939022 18.146268 270)
			(size 0.4318 0.4318)
			(layers "F.Cu" "F.Mask" "F.Paste")
			(net "M_F_CPU1_SA_DQ<25>")
		)
		(pad "DU58" smd circle
			(at 10.566654 18.146268 270)
			(size 0.4318 0.4318)
			(layers "F.Cu" "F.Mask" "F.Paste")
			(net "GND")
		)
		(pad "DU60" smd circle
			(at 12.19454 18.146268 270)
			(size 0.4318 0.4318)
			(layers "F.Cu" "F.Mask" "F.Paste")
			(net "M_G_CPU1_SA_DQ<20>")
		)
		(pad "DU62" smd circle
			(at 13.822426 18.146268 270)
			(size 0.4318 0.4318)
			(layers "F.Cu" "F.Mask" "F.Paste")
			(net "M_G_CPU1_SA_DQ<17>")
		)
		(pad "DU64" smd circle
			(at 15.450058 18.146268 270)
			(size 0.4318 0.4318)
			(layers "F.Cu" "F.Mask" "F.Paste")
			(net "GND")
		)
		(pad "DU66" smd circle
			(at 17.07769 18.146268 270)
			(size 0.4318 0.4318)
			(layers "F.Cu" "F.Mask" "F.Paste")
			(net "M_F_CPU1_SA_DQ<12>")
		)
		(pad "DU68" smd circle
			(at 18.705576 18.146268 270)
			(size 0.4318 0.4318)
			(layers "F.Cu" "F.Mask" "F.Paste")
			(net "M_F_CPU1_SA_DQ<9>")
		)
		(pad "DU70" smd circle
			(at 20.333462 18.146268 270)
			(size 0.4318 0.4318)
			(layers "F.Cu" "F.Mask" "F.Paste")
			(net "GND")
		)
		(pad "DU72" smd circle
			(at 21.961094 18.146268 270)
			(size 0.4318 0.4318)
			(layers "F.Cu" "F.Mask" "F.Paste")
			(net "M_G_CPU1_SA_DQ<4>")
		)
		(pad "DU74" smd circle
			(at 23.58898 18.146268 270)
			(size 0.4318 0.4318)
			(layers "F.Cu" "F.Mask" "F.Paste")
			(net "M_G_CPU1_SA_DQ<1>")
		)
		(pad "DU76" smd circle
			(at 25.216612 18.146268 270)
			(size 0.4318 0.4318)
			(layers "F.Cu" "F.Mask" "F.Paste")
			(net "GND")
		)
		(pad "DU78" smd circle
			(at 26.844498 18.146268 270)
			(size 0.4318 0.4318)
			(layers "F.Cu" "F.Mask" "F.Paste")
			(net "GND")
		)
		(pad "DU80" smd circle
			(at 28.472384 18.146268 270)
			(size 0.4318 0.4318)
			(layers "F.Cu" "F.Mask" "F.Paste")
			(net "Net_729")
		)
		(pad "DU82" smd circle
			(at 30.100016 18.146268 270)
			(size 0.4318 0.4318)
			(layers "F.Cu" "F.Mask" "F.Paste")
			(net "Net_704")
		)
		(pad "DU84" smd circle
			(at 31.727902 18.146268 270)
			(size 0.4318 0.4318)
			(layers "F.Cu" "F.Mask" "F.Paste")
			(net "GND")
		)
		(pad "DU86" smd circle
			(at 33.355534 18.146268 270)
			(size 0.4318 0.4318)
			(layers "F.Cu" "F.Mask" "F.Paste")
			(net "P5E_CPU1_PE3_TX_DP<4>")
		)
		(pad "DU88" smd circle
			(at 34.98342 18.146268 270)
			(size 0.4318 0.4318)
			(layers "F.Cu" "F.Mask" "F.Paste")
			(net "GND")
		)
		(pad "DU90" smd circle
			(at 36.611306 18.146268 270)
			(size 0.4318 0.4318)
			(layers "F.Cu" "F.Mask" "F.Paste")
			(net "P5E_CPU1_PE3_RX_DN<5>")
		)
		(pad "DV2" smd circle
			(at -36.611306 18.505932 270)
			(size 0.4318 0.4318)
			(layers "F.Cu" "F.Mask" "F.Paste")
			(net "UPI_CPU0_CPU1_P0P1_DP<5>")
		)
		(pad "DV4" smd circle
			(at -34.98342 18.505932 270)
			(size 0.4318 0.4318)
			(layers "F.Cu" "F.Mask" "F.Paste")
			(net "GND")
		)
		(pad "DV6" smd circle
			(at -33.355534 18.505932 270)
			(size 0.4318 0.4318)
			(layers "F.Cu" "F.Mask" "F.Paste")
			(net "UPI_CPU1_CPU0_P1P0_DN<4>")
		)
		(pad "DV8" smd circle
			(at -31.727902 18.505932 270)
			(size 0.4318 0.4318)
			(layers "F.Cu" "F.Mask" "F.Paste")
			(net "GND")
		)
		(pad "DV10" smd circle
			(at -30.100016 18.505932 270)
			(size 0.4318 0.4318)
			(layers "F.Cu" "F.Mask" "F.Paste")
			(net "P5E_CPU1_PE2_RX_DP<10>")
		)
		(pad "DV12" smd circle
			(at -28.472384 18.505932 270)
			(size 0.4318 0.4318)
			(layers "F.Cu" "F.Mask" "F.Paste")
			(net "GND")
		)
		(pad "DV14" smd circle
			(at -26.844498 18.505932 270)
			(size 0.4318 0.4318)
			(layers "F.Cu" "F.Mask" "F.Paste")
			(net "P5E_CPU1_PE2_TX_DN<11>")
		)
		(pad "DV16" smd circle
			(at -25.216612 18.505932 270)
			(size 0.4318 0.4318)
			(layers "F.Cu" "F.Mask" "F.Paste")
			(net "GND")
		)
		(pad "DV18" smd circle
			(at -23.58898 18.505932 270)
			(size 0.4318 0.4318)
			(layers "F.Cu" "F.Mask" "F.Paste")
			(net "M_F_CPU1_SB_DQS_DP<3>")
		)
		(pad "DV20" smd circle
			(at -21.961094 18.505932 270)
			(size 0.4318 0.4318)
			(layers "F.Cu" "F.Mask" "F.Paste")
			(net "M_F_CPU1_SB_DQ<24>")
		)
		(pad "DV22" smd circle
			(at -20.333462 18.505932 270)
			(size 0.4318 0.4318)
			(layers "F.Cu" "F.Mask" "F.Paste")
			(net "M_G_CPU1_SB_DQ<21>")
		)
		(pad "DV24" smd circle
			(at -18.705576 18.505932 270)
			(size 0.4318 0.4318)
			(layers "F.Cu" "F.Mask" "F.Paste")
			(net "M_G_CPU1_SB_DQS_DN<2>")
		)
		(pad "DV26" smd circle
			(at -17.07769 18.505932 270)
			(size 0.4318 0.4318)
			(layers "F.Cu" "F.Mask" "F.Paste")
			(net "M_G_CPU1_SB_DQ<16>")
		)
		(pad "DV28" smd circle
			(at -15.450058 18.505932 270)
			(size 0.4318 0.4318)
			(layers "F.Cu" "F.Mask" "F.Paste")
			(net "M_F_CPU1_SB_DQ<5>")
		)
		(pad "DV30" smd circle
			(at -13.822426 18.505932 270)
			(size 0.4318 0.4318)
			(layers "F.Cu" "F.Mask" "F.Paste")
			(net "M_F_CPU1_SB_DQS_DN<0>")
		)
		(pad "DV32" smd circle
			(at -12.19454 18.505932 270)
			(size 0.4318 0.4318)
			(layers "F.Cu" "F.Mask" "F.Paste")
			(net "M_F_CPU1_SB_DQ<0>")
		)
		(pad "DV34" smd circle
			(at -10.566654 18.505932 270)
			(size 0.4318 0.4318)
			(layers "F.Cu" "F.Mask" "F.Paste")
			(net "M_G_CPU1_SB_CB<1>")
		)
		(pad "DV36" smd circle
			(at -8.939022 18.505932 270)
			(size 0.4318 0.4318)
			(layers "F.Cu" "F.Mask" "F.Paste")
			(net "M_G_CPU1_SB_DQS_DN<9>")
		)
		(pad "DV38" smd circle
			(at -7.311136 18.505932 270)
			(size 0.4318 0.4318)
			(layers "F.Cu" "F.Mask" "F.Paste")
			(net "M_G_CPU1_SB_CB<4>")
		)
		(pad "DV40" smd circle
			(at -5.68325 18.505932 270)
			(size 0.4318 0.4318)
			(layers "F.Cu" "F.Mask" "F.Paste")
			(net "M_G_CPU1_SB_CS_N<3>")
		)
		(pad "DV42" smd circle
			(at -4.055618 18.505932 270)
			(size 0.4318 0.4318)
			(layers "F.Cu" "F.Mask" "F.Paste")
			(net "GND")
		)
		(pad "DV44" smd circle
			(at -2.427732 18.505932 270)
			(size 0.4318 0.4318)
			(layers "F.Cu" "F.Mask" "F.Paste")
			(net "M_G_CPU1_SB_CA<2>")
		)
		(pad "DV47" smd circle
			(at 1.613916 18.615914 270)
			(size 0.4318 0.4318)
			(layers "F.Cu" "F.Mask" "F.Paste")
			(net "M_G_CPU1_SB_RSP<1>")
		)
		(pad "DV49" smd circle
			(at 3.241802 18.615914 270)
			(size 0.4318 0.4318)
			(layers "F.Cu" "F.Mask" "F.Paste")
			(net "M_F_CPU1_CLK_DN<1>")
		)
		(pad "DV51" smd circle
			(at 4.869434 18.615914 270)
			(size 0.4318 0.4318)
			(layers "F.Cu" "F.Mask" "F.Paste")
			(net "M_F_CPU1_SB_CA<0>")
		)
		(pad "DV53" smd circle
			(at 6.49732 18.615914 270)
			(size 0.4318 0.4318)
			(layers "F.Cu" "F.Mask" "F.Paste")
			(net "M_F_CPU1_SA_DQ<29>")
		)
		(pad "DV55" smd circle
			(at 8.124952 18.615914 270)
			(size 0.4318 0.4318)
			(layers "F.Cu" "F.Mask" "F.Paste")
			(net "M_F_CPU1_SA_DQS_DN<3>")
		)
		(pad "DV57" smd circle
			(at 9.752838 18.615914 270)
			(size 0.4318 0.4318)
			(layers "F.Cu" "F.Mask" "F.Paste")
			(net "M_F_CPU1_SA_DQ<24>")
		)
		(pad "DV59" smd circle
			(at 11.380724 18.615914 270)
			(size 0.4318 0.4318)
			(layers "F.Cu" "F.Mask" "F.Paste")
			(net "M_G_CPU1_SA_DQ<21>")
		)
		(pad "DV61" smd circle
			(at 13.008356 18.615914 270)
			(size 0.4318 0.4318)
			(layers "F.Cu" "F.Mask" "F.Paste")
			(net "M_G_CPU1_SA_DQS_DP<2>")
		)
		(pad "DV63" smd circle
			(at 14.635988 18.615914 270)
			(size 0.4318 0.4318)
			(layers "F.Cu" "F.Mask" "F.Paste")
			(net "M_G_CPU1_SA_DQ<16>")
		)
		(pad "DV65" smd circle
			(at 16.263874 18.615914 270)
			(size 0.4318 0.4318)
			(layers "F.Cu" "F.Mask" "F.Paste")
			(net "M_F_CPU1_SA_DQ<13>")
		)
		(pad "DV67" smd circle
			(at 17.89176 18.615914 270)
			(size 0.4318 0.4318)
			(layers "F.Cu" "F.Mask" "F.Paste")
			(net "M_F_CPU1_SA_DQS_DP<1>")
		)
		(pad "DV69" smd circle
			(at 19.519392 18.615914 270)
			(size 0.4318 0.4318)
			(layers "F.Cu" "F.Mask" "F.Paste")
			(net "M_F_CPU1_SA_DQ<8>")
		)
		(pad "DV71" smd circle
			(at 21.147278 18.615914 270)
			(size 0.4318 0.4318)
			(layers "F.Cu" "F.Mask" "F.Paste")
			(net "M_G_CPU1_SA_DQ<5>")
		)
		(pad "DV73" smd circle
			(at 22.77491 18.615914 270)
			(size 0.4318 0.4318)
			(layers "F.Cu" "F.Mask" "F.Paste")
			(net "M_G_CPU1_SA_DQS_DN<0>")
		)
		(pad "DV75" smd circle
			(at 24.402796 18.615914 270)
			(size 0.4318 0.4318)
			(layers "F.Cu" "F.Mask" "F.Paste")
			(net "M_G_CPU1_SA_DQ<0>")
		)
		(pad "DV77" smd circle
			(at 26.030682 18.615914 270)
			(size 0.4318 0.4318)
			(layers "F.Cu" "F.Mask" "F.Paste")
			(net "GND")
		)
		(pad "DV79" smd circle
			(at 27.658314 18.615914 270)
			(size 0.4318 0.4318)
			(layers "F.Cu" "F.Mask" "F.Paste")
			(net "GND")
		)
		(pad "DV81" smd circle
			(at 29.2862 18.615914 270)
			(size 0.4318 0.4318)
			(layers "F.Cu" "F.Mask" "F.Paste")
			(net "GND")
		)
		(pad "DV83" smd circle
			(at 30.914086 18.615914 270)
			(size 0.4318 0.4318)
			(layers "F.Cu" "F.Mask" "F.Paste")
			(net "GND")
		)
		(pad "DV85" smd circle
			(at 32.541718 18.615914 270)
			(size 0.4318 0.4318)
			(layers "F.Cu" "F.Mask" "F.Paste")
			(net "P5E_CPU1_PE3_TX_DN<3>")
		)
		(pad "DV87" smd circle
			(at 34.169604 18.615914 270)
			(size 0.4318 0.4318)
			(layers "F.Cu" "F.Mask" "F.Paste")
			(net "GND")
		)
		(pad "DV89" smd circle
			(at 35.797236 18.615914 270)
			(size 0.4318 0.4318)
			(layers "F.Cu" "F.Mask" "F.Paste")
			(net "P5E_CPU1_PE3_RX_DN<4>")
		)
		(pad "DV91" smd oval
			(at 37.425122 18.615914)
			(size 0.381 0.4826)
			(drill
				(offset 0 -0.0508)
			)
			(layers "F.Cu" "F.Mask" "F.Paste")
			(net "GND")
		)
		(pad "DW1" smd oval
			(at -37.425122 18.976086 180)
			(size 0.381 0.4826)
			(drill
				(offset 0 -0.0508)
			)
			(layers "F.Cu" "F.Mask" "F.Paste")
			(net "GND")
		)
		(pad "DW3" smd circle
			(at -35.797236 18.976086 270)
			(size 0.4318 0.4318)
			(layers "F.Cu" "F.Mask" "F.Paste")
			(net "UPI_CPU0_CPU1_P0P1_DP<4>")
		)
		(pad "DW5" smd circle
			(at -34.169604 18.976086 270)
			(size 0.4318 0.4318)
			(layers "F.Cu" "F.Mask" "F.Paste")
			(net "GND")
		)
		(pad "DW7" smd circle
			(at -32.541718 18.976086 270)
			(size 0.4318 0.4318)
			(layers "F.Cu" "F.Mask" "F.Paste")
			(net "UPI_CPU1_CPU0_P1P0_DP<3>")
		)
		(pad "DW9" smd circle
			(at -30.914086 18.976086 270)
			(size 0.4318 0.4318)
			(layers "F.Cu" "F.Mask" "F.Paste")
			(net "GND")
		)
		(pad "DW11" smd circle
			(at -29.2862 18.976086 270)
			(size 0.4318 0.4318)
			(layers "F.Cu" "F.Mask" "F.Paste")
			(net "P5E_CPU1_PE2_RX_DP<11>")
		)
		(pad "DW13" smd circle
			(at -27.658314 18.976086 270)
			(size 0.4318 0.4318)
			(layers "F.Cu" "F.Mask" "F.Paste")
			(net "GND")
		)
		(pad "DW15" smd circle
			(at -26.030682 18.976086 270)
			(size 0.4318 0.4318)
			(layers "F.Cu" "F.Mask" "F.Paste")
			(net "P5E_CPU1_PE2_TX_DP<11>")
		)
		(pad "DW17" smd circle
			(at -24.402796 18.976086 270)
			(size 0.4318 0.4318)
			(layers "F.Cu" "F.Mask" "F.Paste")
			(net "GND")
		)
		(pad "DW19" smd circle
			(at -22.77491 18.976086 270)
			(size 0.4318 0.4318)
			(layers "F.Cu" "F.Mask" "F.Paste")
			(net "GND")
		)
		(pad "DW21" smd circle
			(at -21.147278 18.976086 270)
			(size 0.4318 0.4318)
			(layers "F.Cu" "F.Mask" "F.Paste")
			(net "GND")
		)
		(pad "DW23" smd circle
			(at -19.519392 18.976086 270)
			(size 0.4318 0.4318)
			(layers "F.Cu" "F.Mask" "F.Paste")
			(net "GND")
		)
		(pad "DW25" smd circle
			(at -17.89176 18.976086 270)
			(size 0.4318 0.4318)
			(layers "F.Cu" "F.Mask" "F.Paste")
			(net "GND")
		)
		(pad "DW27" smd circle
			(at -16.263874 18.976086 270)
			(size 0.4318 0.4318)
			(layers "F.Cu" "F.Mask" "F.Paste")
			(net "GND")
		)
		(pad "DW29" smd circle
			(at -14.635988 18.976086 270)
			(size 0.4318 0.4318)
			(layers "F.Cu" "F.Mask" "F.Paste")
			(net "GND")
		)
		(pad "DW31" smd circle
			(at -13.008356 18.976086 270)
			(size 0.4318 0.4318)
			(layers "F.Cu" "F.Mask" "F.Paste")
			(net "GND")
		)
		(pad "DW33" smd circle
			(at -11.380724 18.976086 270)
			(size 0.4318 0.4318)
			(layers "F.Cu" "F.Mask" "F.Paste")
			(net "GND")
		)
		(pad "DW35" smd circle
			(at -9.752838 18.976086 270)
			(size 0.4318 0.4318)
			(layers "F.Cu" "F.Mask" "F.Paste")
			(net "GND")
		)
		(pad "DW37" smd circle
			(at -8.124952 18.976086 270)
			(size 0.4318 0.4318)
			(layers "F.Cu" "F.Mask" "F.Paste")
			(net "GND")
		)
		(pad "DW39" smd circle
			(at -6.49732 18.976086 270)
			(size 0.4318 0.4318)
			(layers "F.Cu" "F.Mask" "F.Paste")
			(net "GND")
		)
		(pad "DW41" smd circle
			(at -4.869434 18.976086 270)
			(size 0.4318 0.4318)
			(layers "F.Cu" "F.Mask" "F.Paste")
			(net "GND")
		)
		(pad "DW43" smd circle
			(at -3.241802 18.976086 270)
			(size 0.4318 0.4318)
			(layers "F.Cu" "F.Mask" "F.Paste")
			(net "GND")
		)
		(pad "DW45" smd circle
			(at -1.613916 18.976086 270)
			(size 0.4318 0.4318)
			(layers "F.Cu" "F.Mask" "F.Paste")
			(net "GND")
		)
		(pad "DW48" smd circle
			(at 2.427732 19.086068 270)
			(size 0.4318 0.4318)
			(layers "F.Cu" "F.Mask" "F.Paste")
			(net "GND")
		)
		(pad "DW50" smd circle
			(at 4.055618 19.086068 270)
			(size 0.4318 0.4318)
			(layers "F.Cu" "F.Mask" "F.Paste")
			(net "GND")
		)
		(pad "DW52" smd circle
			(at 5.68325 19.086068 270)
			(size 0.4318 0.4318)
			(layers "F.Cu" "F.Mask" "F.Paste")
			(net "GND")
		)
		(pad "DW54" smd circle
			(at 7.311136 19.086068 270)
			(size 0.4318 0.4318)
			(layers "F.Cu" "F.Mask" "F.Paste")
			(net "GND")
		)
		(pad "DW56" smd circle
			(at 8.939022 19.086068 270)
			(size 0.4318 0.4318)
			(layers "F.Cu" "F.Mask" "F.Paste")
			(net "GND")
		)
		(pad "DW58" smd circle
			(at 10.566654 19.086068 270)
			(size 0.4318 0.4318)
			(layers "F.Cu" "F.Mask" "F.Paste")
			(net "GND")
		)
		(pad "DW60" smd circle
			(at 12.19454 19.086068 270)
			(size 0.4318 0.4318)
			(layers "F.Cu" "F.Mask" "F.Paste")
			(net "GND")
		)
		(pad "DW62" smd circle
			(at 13.822426 19.086068 270)
			(size 0.4318 0.4318)
			(layers "F.Cu" "F.Mask" "F.Paste")
			(net "GND")
		)
		(pad "DW64" smd circle
			(at 15.450058 19.086068 270)
			(size 0.4318 0.4318)
			(layers "F.Cu" "F.Mask" "F.Paste")
			(net "GND")
		)
		(pad "DW66" smd circle
			(at 17.07769 19.086068 270)
			(size 0.4318 0.4318)
			(layers "F.Cu" "F.Mask" "F.Paste")
			(net "GND")
		)
		(pad "DW68" smd circle
			(at 18.705576 19.086068 270)
			(size 0.4318 0.4318)
			(layers "F.Cu" "F.Mask" "F.Paste")
			(net "GND")
		)
		(pad "DW70" smd circle
			(at 20.333462 19.086068 270)
			(size 0.4318 0.4318)
			(layers "F.Cu" "F.Mask" "F.Paste")
			(net "GND")
		)
		(pad "DW72" smd circle
			(at 21.961094 19.086068 270)
			(size 0.4318 0.4318)
			(layers "F.Cu" "F.Mask" "F.Paste")
			(net "GND")
		)
		(pad "DW74" smd circle
			(at 23.58898 19.086068 270)
			(size 0.4318 0.4318)
			(layers "F.Cu" "F.Mask" "F.Paste")
			(net "GND")
		)
		(pad "DW76" smd circle
			(at 25.216612 19.086068 270)
			(size 0.4318 0.4318)
			(layers "F.Cu" "F.Mask" "F.Paste")
			(net "GND")
		)
		(pad "DW78" smd circle
			(at 26.844498 19.086068 270)
			(size 0.4318 0.4318)
			(layers "F.Cu" "F.Mask" "F.Paste")
			(net "M_H_CPU1_SA_DQ<2>")
		)
		(pad "DW80" smd circle
			(at 28.472384 19.086068 270)
			(size 0.4318 0.4318)
			(layers "F.Cu" "F.Mask" "F.Paste")
			(net "GND")
		)
		(pad "DW82" smd circle
			(at 30.100016 19.086068 270)
			(size 0.4318 0.4318)
			(layers "F.Cu" "F.Mask" "F.Paste")
			(net "GND")
		)
		(pad "DW84" smd circle
			(at 31.727902 19.086068 270)
			(size 0.4318 0.4318)
			(layers "F.Cu" "F.Mask" "F.Paste")
			(net "GND")
		)
		(pad "DW86" smd circle
			(at 33.355534 19.086068 270)
			(size 0.4318 0.4318)
			(layers "F.Cu" "F.Mask" "F.Paste")
			(net "P5E_CPU1_PE3_TX_DP<3>")
		)
		(pad "DW88" smd circle
			(at 34.98342 19.086068 270)
			(size 0.4318 0.4318)
			(layers "F.Cu" "F.Mask" "F.Paste")
			(net "GND")
		)
		(pad "DW90" smd circle
			(at 36.611306 19.086068 270)
			(size 0.4318 0.4318)
			(layers "F.Cu" "F.Mask" "F.Paste")
			(net "P5E_CPU1_PE3_RX_DP<4>")
		)
		(pad "DY2" smd circle
			(at -36.611306 19.445732 270)
			(size 0.4318 0.4318)
			(layers "F.Cu" "F.Mask" "F.Paste")
			(net "UPI_CPU0_CPU1_P0P1_DN<4>")
		)
		(pad "DY4" smd circle
			(at -34.98342 19.445732 270)
			(size 0.4318 0.4318)
			(layers "F.Cu" "F.Mask" "F.Paste")
			(net "GND")
		)
		(pad "DY6" smd circle
			(at -33.355534 19.445732 270)
			(size 0.4318 0.4318)
			(layers "F.Cu" "F.Mask" "F.Paste")
			(net "UPI_CPU1_CPU0_P1P0_DN<3>")
		)
		(pad "DY8" smd circle
			(at -31.727902 19.445732 270)
			(size 0.4318 0.4318)
			(layers "F.Cu" "F.Mask" "F.Paste")
			(net "GND")
		)
		(pad "DY10" smd circle
			(at -30.100016 19.445732 270)
			(size 0.4318 0.4318)
			(layers "F.Cu" "F.Mask" "F.Paste")
			(net "P5E_CPU1_PE2_RX_DN<11>")
		)
		(pad "DY12" smd circle
			(at -28.472384 19.445732 270)
			(size 0.4318 0.4318)
			(layers "F.Cu" "F.Mask" "F.Paste")
			(net "GND")
		)
		(pad "DY14" smd circle
			(at -26.844498 19.445732 270)
			(size 0.4318 0.4318)
			(layers "F.Cu" "F.Mask" "F.Paste")
			(net "P5E_CPU1_PE2_TX_DP<12>")
		)
		(pad "DY16" smd circle
			(at -25.216612 19.445732 270)
			(size 0.4318 0.4318)
			(layers "F.Cu" "F.Mask" "F.Paste")
			(net "GND")
		)
		(pad "DY18" smd circle
			(at -23.58898 19.445732 270)
			(size 0.4318 0.4318)
			(layers "F.Cu" "F.Mask" "F.Paste")
			(net "M_F_CPU1_SB_DQS_DN<8>")
		)
		(pad "DY20" smd circle
			(at -21.961094 19.445732 270)
			(size 0.4318 0.4318)
			(layers "F.Cu" "F.Mask" "F.Paste")
			(net "M_F_CPU1_SB_DQ<26>")
		)
		(pad "DY22" smd circle
			(at -20.333462 19.445732 270)
			(size 0.4318 0.4318)
			(layers "F.Cu" "F.Mask" "F.Paste")
			(net "M_G_CPU1_SB_DQ<23>")
		)
		(pad "DY24" smd circle
			(at -18.705576 19.445732 270)
			(size 0.4318 0.4318)
			(layers "F.Cu" "F.Mask" "F.Paste")
			(net "M_G_CPU1_SB_DQS_DP<7>")
		)
		(pad "DY26" smd circle
			(at -17.07769 19.445732 270)
			(size 0.4318 0.4318)
			(layers "F.Cu" "F.Mask" "F.Paste")
			(net "M_G_CPU1_SB_DQ<18>")
		)
		(pad "DY28" smd circle
			(at -15.450058 19.445732 270)
			(size 0.4318 0.4318)
			(layers "F.Cu" "F.Mask" "F.Paste")
			(net "M_F_CPU1_SB_DQ<7>")
		)
		(pad "DY30" smd circle
			(at -13.822426 19.445732 270)
			(size 0.4318 0.4318)
			(layers "F.Cu" "F.Mask" "F.Paste")
			(net "M_F_CPU1_SB_DQS_DP<5>")
		)
		(pad "DY32" smd circle
			(at -12.19454 19.445732 270)
			(size 0.4318 0.4318)
			(layers "F.Cu" "F.Mask" "F.Paste")
			(net "M_F_CPU1_SB_DQ<2>")
		)
		(pad "DY34" smd circle
			(at -10.566654 19.445732 270)
			(size 0.4318 0.4318)
			(layers "F.Cu" "F.Mask" "F.Paste")
			(net "M_G_CPU1_SB_CB<3>")
		)
		(pad "DY36" smd circle
			(at -8.939022 19.445732 270)
			(size 0.4318 0.4318)
			(layers "F.Cu" "F.Mask" "F.Paste")
			(net "M_G_CPU1_SB_DQS_DP<4>")
		)
		(pad "DY38" smd circle
			(at -7.311136 19.445732 270)
			(size 0.4318 0.4318)
			(layers "F.Cu" "F.Mask" "F.Paste")
			(net "M_G_CPU1_SB_CB<6>")
		)
		(pad "DY40" smd circle
			(at -5.68325 19.445732 270)
			(size 0.4318 0.4318)
			(layers "F.Cu" "F.Mask" "F.Paste")
			(net "M_G_CPU1_SB_CS_N<1>")
		)
		(pad "DY42" smd circle
			(at -4.055618 19.445732 270)
			(size 0.4318 0.4318)
			(layers "F.Cu" "F.Mask" "F.Paste")
			(net "GND")
		)
		(pad "DY44" smd circle
			(at -2.427732 19.445732 270)
			(size 0.4318 0.4318)
			(layers "F.Cu" "F.Mask" "F.Paste")
			(net "M_G_CPU1_SB_CA<3>")
		)
		(pad "DY47" smd circle
			(at 1.613916 19.555714 270)
			(size 0.4318 0.4318)
			(layers "F.Cu" "F.Mask" "F.Paste")
			(net "M_G_CPU1_SA_RSP<1>")
		)
		(pad "DY49" smd circle
			(at 3.241802 19.555714 270)
			(size 0.4318 0.4318)
			(layers "F.Cu" "F.Mask" "F.Paste")
			(net "M_F_CPU1_CLK_DN<0>")
		)
		(pad "DY51" smd circle
			(at 4.869434 19.555714 270)
			(size 0.4318 0.4318)
			(layers "F.Cu" "F.Mask" "F.Paste")
			(net "M_F_CPU1_SA_CA<6>")
		)
		(pad "DY53" smd circle
			(at 6.49732 19.555714 270)
			(size 0.4318 0.4318)
			(layers "F.Cu" "F.Mask" "F.Paste")
			(net "M_F_CPU1_SA_DQ<31>")
		)
		(pad "DY55" smd circle
			(at 8.124952 19.555714 270)
			(size 0.4318 0.4318)
			(layers "F.Cu" "F.Mask" "F.Paste")
			(net "M_F_CPU1_SA_DQS_DP<8>")
		)
		(pad "DY57" smd circle
			(at 9.752838 19.555714 270)
			(size 0.4318 0.4318)
			(layers "F.Cu" "F.Mask" "F.Paste")
			(net "M_F_CPU1_SA_DQ<26>")
		)
		(pad "DY59" smd circle
			(at 11.380724 19.555714 270)
			(size 0.4318 0.4318)
			(layers "F.Cu" "F.Mask" "F.Paste")
			(net "M_G_CPU1_SA_DQ<23>")
		)
		(pad "DY61" smd circle
			(at 13.008356 19.555714 270)
			(size 0.4318 0.4318)
			(layers "F.Cu" "F.Mask" "F.Paste")
			(net "M_G_CPU1_SA_DQS_DP<7>")
		)
		(pad "DY63" smd circle
			(at 14.635988 19.555714 270)
			(size 0.4318 0.4318)
			(layers "F.Cu" "F.Mask" "F.Paste")
			(net "M_G_CPU1_SA_DQ<18>")
		)
		(pad "DY65" smd circle
			(at 16.263874 19.555714 270)
			(size 0.4318 0.4318)
			(layers "F.Cu" "F.Mask" "F.Paste")
			(net "M_F_CPU1_SA_DQ<15>")
		)
		(pad "DY67" smd circle
			(at 17.89176 19.555714 270)
			(size 0.4318 0.4318)
			(layers "F.Cu" "F.Mask" "F.Paste")
			(net "M_F_CPU1_SA_DQS_DP<6>")
		)
		(pad "DY69" smd circle
			(at 19.519392 19.555714 270)
			(size 0.4318 0.4318)
			(layers "F.Cu" "F.Mask" "F.Paste")
			(net "M_F_CPU1_SA_DQ<10>")
		)
		(pad "DY71" smd circle
			(at 21.147278 19.555714 270)
			(size 0.4318 0.4318)
			(layers "F.Cu" "F.Mask" "F.Paste")
			(net "M_G_CPU1_SA_DQ<7>")
		)
		(pad "DY73" smd circle
			(at 22.77491 19.555714 270)
			(size 0.4318 0.4318)
			(layers "F.Cu" "F.Mask" "F.Paste")
			(net "M_G_CPU1_SA_DQS_DP<5>")
		)
		(pad "DY75" smd circle
			(at 24.402796 19.555714 270)
			(size 0.4318 0.4318)
			(layers "F.Cu" "F.Mask" "F.Paste")
			(net "M_G_CPU1_SA_DQ<2>")
		)
		(pad "DY77" smd circle
			(at 26.030682 19.555714 270)
			(size 0.4318 0.4318)
			(layers "F.Cu" "F.Mask" "F.Paste")
			(net "GND")
		)
		(pad "DY79" smd circle
			(at 27.658314 19.555714 270)
			(size 0.4318 0.4318)
			(layers "F.Cu" "F.Mask" "F.Paste")
			(net "M_H_CPU1_SA_DQ<0>")
		)
		(pad "DY81" smd circle
			(at 29.2862 19.555714 270)
			(size 0.4318 0.4318)
			(layers "F.Cu" "F.Mask" "F.Paste")
			(net "GND")
		)
		(pad "DY83" smd circle
			(at 30.914086 19.555714 270)
			(size 0.4318 0.4318)
			(layers "F.Cu" "F.Mask" "F.Paste")
			(net "GND")
		)
		(pad "DY85" smd circle
			(at 32.541718 19.555714 270)
			(size 0.4318 0.4318)
			(layers "F.Cu" "F.Mask" "F.Paste")
			(net "PVCCFA_EHV_FIVRA_CPU1")
		)
		(pad "DY87" smd circle
			(at 34.169604 19.555714 270)
			(size 0.4318 0.4318)
			(layers "F.Cu" "F.Mask" "F.Paste")
			(net "P5E_CPU1_PE3_TX_DN<2>")
		)
		(pad "DY89" smd circle
			(at 35.797236 19.555714 270)
			(size 0.4318 0.4318)
			(layers "F.Cu" "F.Mask" "F.Paste")
			(net "PVCCFA_EHV_FIVRA_CPU1")
		)
		(pad "DY91" smd oval
			(at 37.425122 19.555714)
			(size 0.381 0.4826)
			(drill
				(offset 0 -0.0508)
			)
			(layers "F.Cu" "F.Mask" "F.Paste")
			(net "P5E_CPU1_PE3_RX_DN<3>")
		)
		(pad "E5" smd oval
			(at -34.169604 -25.194514 135)
			(size 0.381 0.4826)
			(drill
				(offset 0 -0.0508)
			)
			(layers "F.Cu" "F.Mask" "F.Paste")
			(net "GND")
		)
		(pad "E7" smd oval
			(at -32.541718 -25.194514 135)
			(size 0.381 0.4826)
			(drill
				(offset 0 -0.0508)
			)
			(layers "F.Cu" "F.Mask" "F.Paste")
			(net "M_A_CPU1_SB_DQ<31>")
		)
		(pad "E9" smd circle
			(at -30.914086 -25.194514 270)
			(size 0.4318 0.4318)
			(layers "F.Cu" "F.Mask" "F.Paste")
			(net "M_A_CPU1_SB_DQS_DP<8>")
		)
		(pad "E11" smd circle
			(at -29.2862 -25.194514 270)
			(size 0.4318 0.4318)
			(layers "F.Cu" "F.Mask" "F.Paste")
			(net "M_A_CPU1_SB_DQ<26>")
		)
		(pad "E13" smd circle
			(at -27.658314 -25.194514 270)
			(size 0.4318 0.4318)
			(layers "F.Cu" "F.Mask" "F.Paste")
			(net "M_B_CPU1_SB_DQ<29>")
		)
		(pad "E15" smd circle
			(at -26.030682 -25.194514 270)
			(size 0.4318 0.4318)
			(layers "F.Cu" "F.Mask" "F.Paste")
			(net "M_B_CPU1_SB_DQS_DN<8>")
		)
		(pad "E17" smd circle
			(at -24.402796 -25.194514 270)
			(size 0.4318 0.4318)
			(layers "F.Cu" "F.Mask" "F.Paste")
			(net "M_B_CPU1_SB_DQ<26>")
		)
		(pad "E19" smd circle
			(at -22.77491 -25.194514 270)
			(size 0.4318 0.4318)
			(layers "F.Cu" "F.Mask" "F.Paste")
			(net "M_A_CPU1_SB_DQ<23>")
		)
		(pad "E21" smd circle
			(at -21.147278 -25.194514 270)
			(size 0.4318 0.4318)
			(layers "F.Cu" "F.Mask" "F.Paste")
			(net "M_A_CPU1_SB_DQS_DP<7>")
		)
		(pad "E23" smd circle
			(at -19.519392 -25.194514 270)
			(size 0.4318 0.4318)
			(layers "F.Cu" "F.Mask" "F.Paste")
			(net "M_A_CPU1_SB_DQ<18>")
		)
		(pad "E25" smd circle
			(at -17.89176 -25.194514 270)
			(size 0.4318 0.4318)
			(layers "F.Cu" "F.Mask" "F.Paste")
			(net "M_A_CPU1_SB_DQ<15>")
		)
		(pad "E27" smd circle
			(at -16.263874 -25.194514 270)
			(size 0.4318 0.4318)
			(layers "F.Cu" "F.Mask" "F.Paste")
			(net "M_A_CPU1_SB_DQS_DP<6>")
		)
		(pad "E29" smd circle
			(at -14.635988 -25.194514 270)
			(size 0.4318 0.4318)
			(layers "F.Cu" "F.Mask" "F.Paste")
			(net "M_A_CPU1_SB_DQ<10>")
		)
		(pad "E31" smd circle
			(at -13.008356 -25.194514 270)
			(size 0.4318 0.4318)
			(layers "F.Cu" "F.Mask" "F.Paste")
			(net "M_A_CPU1_SB_CB<3>")
		)
		(pad "E33" smd circle
			(at -11.380724 -25.194514 270)
			(size 0.4318 0.4318)
			(layers "F.Cu" "F.Mask" "F.Paste")
			(net "M_A_CPU1_SB_DQS_DP<4>")
		)
		(pad "E35" smd circle
			(at -9.752838 -25.194514 270)
			(size 0.4318 0.4318)
			(layers "F.Cu" "F.Mask" "F.Paste")
			(net "M_A_CPU1_SB_CB<6>")
		)
		(pad "E37" smd circle
			(at -8.124952 -25.194514 270)
			(size 0.4318 0.4318)
			(layers "F.Cu" "F.Mask" "F.Paste")
			(net "M_A_CPU1_SB_CS_N<3>")
		)
		(pad "E39" smd circle
			(at -6.49732 -25.194514 270)
			(size 0.4318 0.4318)
			(layers "F.Cu" "F.Mask" "F.Paste")
			(net "GND")
		)
		(pad "E41" smd circle
			(at -4.869434 -25.194514 270)
			(size 0.4318 0.4318)
			(layers "F.Cu" "F.Mask" "F.Paste")
			(net "M_A_CPU1_SB_CA<3>")
		)
		(pad "E43" smd circle
			(at -3.241802 -25.194514 270)
			(size 0.4318 0.4318)
			(layers "F.Cu" "F.Mask" "F.Paste")
			(net "M_A_CPU1_SB_CA<0>")
		)
		(pad "E45" smd circle
			(at -1.613916 -25.194514 270)
			(size 0.4318 0.4318)
			(layers "F.Cu" "F.Mask" "F.Paste")
			(net "M_A_CPU1_CLK_DP<1>")
		)
		(pad "E48" smd circle
			(at 2.427732 -25.084532 270)
			(size 0.4318 0.4318)
			(layers "F.Cu" "F.Mask" "F.Paste")
			(net "M_A_CPU1_SA_PAR")
		)
		(pad "E50" smd circle
			(at 4.055618 -25.084532 270)
			(size 0.4318 0.4318)
			(layers "F.Cu" "F.Mask" "F.Paste")
			(net "M_A_CPU1_SA_CA<5>")
		)
		(pad "E52" smd circle
			(at 5.68325 -25.084532 270)
			(size 0.4318 0.4318)
			(layers "F.Cu" "F.Mask" "F.Paste")
			(net "GND")
		)
		(pad "E54" smd circle
			(at 7.311136 -25.084532 270)
			(size 0.4318 0.4318)
			(layers "F.Cu" "F.Mask" "F.Paste")
			(net "M_A_CPU1_SA_CS_N<2>")
		)
		(pad "E56" smd circle
			(at 8.939022 -25.084532 270)
			(size 0.4318 0.4318)
			(layers "F.Cu" "F.Mask" "F.Paste")
			(net "M_A_CPU1_SA_CB<7>")
		)
		(pad "E58" smd circle
			(at 10.566654 -25.084532 270)
			(size 0.4318 0.4318)
			(layers "F.Cu" "F.Mask" "F.Paste")
			(net "M_A_CPU1_SA_DQS_DP<9>")
		)
		(pad "E60" smd circle
			(at 12.19454 -25.084532 270)
			(size 0.4318 0.4318)
			(layers "F.Cu" "F.Mask" "F.Paste")
			(net "M_A_CPU1_SA_CB<2>")
		)
		(pad "E62" smd circle
			(at 13.822426 -25.084532 270)
			(size 0.4318 0.4318)
			(layers "F.Cu" "F.Mask" "F.Paste")
			(net "M_A_CPU1_SA_DQ<31>")
		)
		(pad "E64" smd circle
			(at 15.450058 -25.084532 270)
			(size 0.4318 0.4318)
			(layers "F.Cu" "F.Mask" "F.Paste")
			(net "M_A_CPU1_SA_DQS_DP<8>")
		)
		(pad "E66" smd circle
			(at 17.07769 -25.084532 270)
			(size 0.4318 0.4318)
			(layers "F.Cu" "F.Mask" "F.Paste")
			(net "M_A_CPU1_SA_DQ<26>")
		)
		(pad "E68" smd circle
			(at 18.705576 -25.084532 270)
			(size 0.4318 0.4318)
			(layers "F.Cu" "F.Mask" "F.Paste")
			(net "M_A_CPU1_SA_DQ<23>")
		)
		(pad "E70" smd circle
			(at 20.333462 -25.084532 270)
			(size 0.4318 0.4318)
			(layers "F.Cu" "F.Mask" "F.Paste")
			(net "M_A_CPU1_SA_DQS_DP<7>")
		)
		(pad "E72" smd circle
			(at 21.961094 -25.084532 270)
			(size 0.4318 0.4318)
			(layers "F.Cu" "F.Mask" "F.Paste")
			(net "M_A_CPU1_SA_DQ<17>")
		)
		(pad "E74" smd circle
			(at 23.58898 -25.084532 270)
			(size 0.4318 0.4318)
			(layers "F.Cu" "F.Mask" "F.Paste")
			(net "GND")
		)
		(pad "E76" smd circle
			(at 25.216612 -25.084532 270)
			(size 0.4318 0.4318)
			(layers "F.Cu" "F.Mask" "F.Paste")
			(net "GND")
		)
		(pad "E78" smd circle
			(at 26.844498 -25.084532 270)
			(size 0.4318 0.4318)
			(layers "F.Cu" "F.Mask" "F.Paste")
			(net "GND")
		)
		(pad "E80" smd circle
			(at 28.472384 -25.084532 270)
			(size 0.4318 0.4318)
			(layers "F.Cu" "F.Mask" "F.Paste")
			(net "UPI_CPU0_CPU1_P2P2_DN<0>")
		)
		(pad "E82" smd circle
			(at 30.100016 -25.084532 270)
			(size 0.4318 0.4318)
			(layers "F.Cu" "F.Mask" "F.Paste")
			(net "UPI_CPU0_CPU1_P2P2_DP<1>")
		)
		(pad "E84" smd circle
			(at 31.727902 -25.084532 270)
			(size 0.4318 0.4318)
			(layers "F.Cu" "F.Mask" "F.Paste")
			(net "UPI_CPU1_CPU0_P2P2_DN<1>")
		)
		(pad "E86" smd oval
			(at 33.355534 -25.084532 45)
			(size 0.381 0.4826)
			(drill
				(offset 0 -0.0508)
			)
			(layers "F.Cu" "F.Mask" "F.Paste")
			(net "GND")
		)
		(pad "E88" smd oval
			(at 34.98342 -25.084532 45)
			(size 0.381 0.4826)
			(drill
				(offset 0 -0.0508)
			)
			(layers "F.Cu" "F.Mask" "F.Paste")
			(net "UPI_CPU1_CPU0_P2P2_DP<2>")
		)
		(pad "EA1" smd oval
			(at -37.425122 19.915886 180)
			(size 0.381 0.4826)
			(drill
				(offset 0 -0.0508)
			)
			(layers "F.Cu" "F.Mask" "F.Paste")
			(net "UPI_CPU0_CPU1_P0P1_DN<3>")
		)
		(pad "EA3" smd circle
			(at -35.797236 19.915886 270)
			(size 0.4318 0.4318)
			(layers "F.Cu" "F.Mask" "F.Paste")
			(net "PVCCFA_EHV_FIVRA_CPU1")
		)
		(pad "EA5" smd circle
			(at -34.169604 19.915886 270)
			(size 0.4318 0.4318)
			(layers "F.Cu" "F.Mask" "F.Paste")
			(net "UPI_CPU1_CPU0_P1P0_DP<2>")
		)
		(pad "EA7" smd circle
			(at -32.541718 19.915886 270)
			(size 0.4318 0.4318)
			(layers "F.Cu" "F.Mask" "F.Paste")
			(net "PVCCFA_EHV_FIVRA_CPU1")
		)
		(pad "EA9" smd circle
			(at -30.914086 19.915886 270)
			(size 0.4318 0.4318)
			(layers "F.Cu" "F.Mask" "F.Paste")
			(net "P5E_CPU1_PE2_RX_DN<12>")
		)
		(pad "EA11" smd circle
			(at -29.2862 19.915886 270)
			(size 0.4318 0.4318)
			(layers "F.Cu" "F.Mask" "F.Paste")
			(net "PVCCFA_EHV_FIVRA_CPU1")
		)
		(pad "EA13" smd circle
			(at -27.658314 19.915886 270)
			(size 0.4318 0.4318)
			(layers "F.Cu" "F.Mask" "F.Paste")
			(net "P5E_CPU1_PE2_TX_DN<12>")
		)
		(pad "EA15" smd circle
			(at -26.030682 19.915886 270)
			(size 0.4318 0.4318)
			(layers "F.Cu" "F.Mask" "F.Paste")
			(net "PVCCFA_EHV_FIVRA_CPU1")
		)
		(pad "EA17" smd circle
			(at -24.402796 19.915886 270)
			(size 0.4318 0.4318)
			(layers "F.Cu" "F.Mask" "F.Paste")
			(net "M_F_CPU1_SB_DQ<28>")
		)
		(pad "EA19" smd circle
			(at -22.77491 19.915886 270)
			(size 0.4318 0.4318)
			(layers "F.Cu" "F.Mask" "F.Paste")
			(net "M_F_CPU1_SB_DQ<27>")
		)
		(pad "EA21" smd circle
			(at -21.147278 19.915886 270)
			(size 0.4318 0.4318)
			(layers "F.Cu" "F.Mask" "F.Paste")
			(net "GND")
		)
		(pad "EA23" smd circle
			(at -19.519392 19.915886 270)
			(size 0.4318 0.4318)
			(layers "F.Cu" "F.Mask" "F.Paste")
			(net "M_G_CPU1_SB_DQ<22>")
		)
		(pad "EA25" smd circle
			(at -17.89176 19.915886 270)
			(size 0.4318 0.4318)
			(layers "F.Cu" "F.Mask" "F.Paste")
			(net "M_G_CPU1_SB_DQ<19>")
		)
		(pad "EA27" smd circle
			(at -16.263874 19.915886 270)
			(size 0.4318 0.4318)
			(layers "F.Cu" "F.Mask" "F.Paste")
			(net "GND")
		)
		(pad "EA29" smd circle
			(at -14.635988 19.915886 270)
			(size 0.4318 0.4318)
			(layers "F.Cu" "F.Mask" "F.Paste")
			(net "M_F_CPU1_SB_DQ<6>")
		)
		(pad "EA31" smd circle
			(at -13.008356 19.915886 270)
			(size 0.4318 0.4318)
			(layers "F.Cu" "F.Mask" "F.Paste")
			(net "M_F_CPU1_SB_DQ<3>")
		)
		(pad "EA33" smd circle
			(at -11.380724 19.915886 270)
			(size 0.4318 0.4318)
			(layers "F.Cu" "F.Mask" "F.Paste")
			(net "GND")
		)
		(pad "EA35" smd circle
			(at -9.752838 19.915886 270)
			(size 0.4318 0.4318)
			(layers "F.Cu" "F.Mask" "F.Paste")
			(net "M_G_CPU1_SB_CB<2>")
		)
		(pad "EA37" smd circle
			(at -8.124952 19.915886 270)
			(size 0.4318 0.4318)
			(layers "F.Cu" "F.Mask" "F.Paste")
			(net "M_G_CPU1_SB_CB<7>")
		)
		(pad "EA39" smd circle
			(at -6.49732 19.915886 270)
			(size 0.4318 0.4318)
			(layers "F.Cu" "F.Mask" "F.Paste")
			(net "GND")
		)
		(pad "EA41" smd circle
			(at -4.869434 19.915886 270)
			(size 0.4318 0.4318)
			(layers "F.Cu" "F.Mask" "F.Paste")
			(net "M_G_CPU1_SB_CS_N<0>")
		)
		(pad "EA43" smd circle
			(at -3.241802 19.915886 270)
			(size 0.4318 0.4318)
			(layers "F.Cu" "F.Mask" "F.Paste")
			(net "M_G_CPU1_SB_CA<5>")
		)
		(pad "EA45" smd circle
			(at -1.613916 19.915886 270)
			(size 0.4318 0.4318)
			(layers "F.Cu" "F.Mask" "F.Paste")
			(net "GND")
		)
		(pad "EA48" smd circle
			(at 2.427732 20.025868 270)
			(size 0.4318 0.4318)
			(layers "F.Cu" "F.Mask" "F.Paste")
			(net "M_G_CPU1_SA_RSP<0>")
		)
		(pad "EA50" smd circle
			(at 4.055618 20.025868 270)
			(size 0.4318 0.4318)
			(layers "F.Cu" "F.Mask" "F.Paste")
			(net "M_F_CPU1_SA_PAR")
		)
		(pad "EA52" smd circle
			(at 5.68325 20.025868 270)
			(size 0.4318 0.4318)
			(layers "F.Cu" "F.Mask" "F.Paste")
			(net "GND")
		)
		(pad "EA54" smd circle
			(at 7.311136 20.025868 270)
			(size 0.4318 0.4318)
			(layers "F.Cu" "F.Mask" "F.Paste")
			(net "M_F_CPU1_SA_DQ<30>")
		)
		(pad "EA56" smd circle
			(at 8.939022 20.025868 270)
			(size 0.4318 0.4318)
			(layers "F.Cu" "F.Mask" "F.Paste")
			(net "M_F_CPU1_SA_DQ<27>")
		)
		(pad "EA58" smd circle
			(at 10.566654 20.025868 270)
			(size 0.4318 0.4318)
			(layers "F.Cu" "F.Mask" "F.Paste")
			(net "GND")
		)
		(pad "EA60" smd circle
			(at 12.19454 20.025868 270)
			(size 0.4318 0.4318)
			(layers "F.Cu" "F.Mask" "F.Paste")
			(net "M_G_CPU1_SA_DQ<22>")
		)
		(pad "EA62" smd circle
			(at 13.822426 20.025868 270)
			(size 0.4318 0.4318)
			(layers "F.Cu" "F.Mask" "F.Paste")
			(net "M_G_CPU1_SA_DQ<19>")
		)
		(pad "EA64" smd circle
			(at 15.450058 20.025868 270)
			(size 0.4318 0.4318)
			(layers "F.Cu" "F.Mask" "F.Paste")
			(net "GND")
		)
		(pad "EA66" smd circle
			(at 17.07769 20.025868 270)
			(size 0.4318 0.4318)
			(layers "F.Cu" "F.Mask" "F.Paste")
			(net "M_F_CPU1_SA_DQ<14>")
		)
		(pad "EA68" smd circle
			(at 18.705576 20.025868 270)
			(size 0.4318 0.4318)
			(layers "F.Cu" "F.Mask" "F.Paste")
			(net "M_F_CPU1_SA_DQ<11>")
		)
		(pad "EA70" smd circle
			(at 20.333462 20.025868 270)
			(size 0.4318 0.4318)
			(layers "F.Cu" "F.Mask" "F.Paste")
			(net "GND")
		)
		(pad "EA72" smd circle
			(at 21.961094 20.025868 270)
			(size 0.4318 0.4318)
			(layers "F.Cu" "F.Mask" "F.Paste")
			(net "M_G_CPU1_SA_DQ<6>")
		)
		(pad "EA74" smd circle
			(at 23.58898 20.025868 270)
			(size 0.4318 0.4318)
			(layers "F.Cu" "F.Mask" "F.Paste")
			(net "M_G_CPU1_SA_DQ<3>")
		)
		(pad "EA76" smd circle
			(at 25.216612 20.025868 270)
			(size 0.4318 0.4318)
			(layers "F.Cu" "F.Mask" "F.Paste")
			(net "GND")
		)
		(pad "EA78" smd circle
			(at 26.844498 20.025868 270)
			(size 0.4318 0.4318)
			(layers "F.Cu" "F.Mask" "F.Paste")
			(net "GND")
		)
		(pad "EA80" smd circle
			(at 28.472384 20.025868 270)
			(size 0.4318 0.4318)
			(layers "F.Cu" "F.Mask" "F.Paste")
			(net "GND")
		)
		(pad "EA82" smd circle
			(at 30.100016 20.025868 270)
			(size 0.4318 0.4318)
			(layers "F.Cu" "F.Mask" "F.Paste")
			(net "GND")
		)
		(pad "EA84" smd circle
			(at 31.727902 20.025868 270)
			(size 0.4318 0.4318)
			(layers "F.Cu" "F.Mask" "F.Paste")
			(net "GND")
		)
		(pad "EA86" smd circle
			(at 33.355534 20.025868 270)
			(size 0.4318 0.4318)
			(layers "F.Cu" "F.Mask" "F.Paste")
			(net "P5E_CPU1_PE3_TX_DP<2>")
		)
		(pad "EA88" smd circle
			(at 34.98342 20.025868 270)
			(size 0.4318 0.4318)
			(layers "F.Cu" "F.Mask" "F.Paste")
			(net "GND")
		)
		(pad "EA90" smd circle
			(at 36.611306 20.025868 270)
			(size 0.4318 0.4318)
			(layers "F.Cu" "F.Mask" "F.Paste")
			(net "P5E_CPU1_PE3_RX_DP<3>")
		)
		(pad "EB2" smd circle
			(at -36.611306 20.385532 270)
			(size 0.4318 0.4318)
			(layers "F.Cu" "F.Mask" "F.Paste")
			(net "UPI_CPU0_CPU1_P0P1_DP<3>")
		)
		(pad "EB4" smd circle
			(at -34.98342 20.385532 270)
			(size 0.4318 0.4318)
			(layers "F.Cu" "F.Mask" "F.Paste")
			(net "GND")
		)
		(pad "EB6" smd circle
			(at -33.355534 20.385532 270)
			(size 0.4318 0.4318)
			(layers "F.Cu" "F.Mask" "F.Paste")
			(net "UPI_CPU1_CPU0_P1P0_DN<2>")
		)
		(pad "EB8" smd circle
			(at -31.727902 20.385532 270)
			(size 0.4318 0.4318)
			(layers "F.Cu" "F.Mask" "F.Paste")
			(net "GND")
		)
		(pad "EB10" smd circle
			(at -30.100016 20.385532 270)
			(size 0.4318 0.4318)
			(layers "F.Cu" "F.Mask" "F.Paste")
			(net "P5E_CPU1_PE2_RX_DP<12>")
		)
		(pad "EB12" smd circle
			(at -28.472384 20.385532 270)
			(size 0.4318 0.4318)
			(layers "F.Cu" "F.Mask" "F.Paste")
			(net "GND")
		)
		(pad "EB14" smd circle
			(at -26.844498 20.385532 270)
			(size 0.4318 0.4318)
			(layers "F.Cu" "F.Mask" "F.Paste")
			(net "P5E_CPU1_PE2_TX_DN<13>")
		)
		(pad "EB16" smd circle
			(at -25.216612 20.385532 270)
			(size 0.4318 0.4318)
			(layers "F.Cu" "F.Mask" "F.Paste")
			(net "GND")
		)
		(pad "EB18" smd circle
			(at -23.58898 20.385532 270)
			(size 0.4318 0.4318)
			(layers "F.Cu" "F.Mask" "F.Paste")
			(net "M_F_CPU1_SB_DQS_DP<8>")
		)
		(pad "EB20" smd circle
			(at -21.961094 20.385532 270)
			(size 0.4318 0.4318)
			(layers "F.Cu" "F.Mask" "F.Paste")
			(net "GND")
		)
		(pad "EB22" smd circle
			(at -20.333462 20.385532 270)
			(size 0.4318 0.4318)
			(layers "F.Cu" "F.Mask" "F.Paste")
			(net "GND")
		)
		(pad "EB24" smd circle
			(at -18.705576 20.385532 270)
			(size 0.4318 0.4318)
			(layers "F.Cu" "F.Mask" "F.Paste")
			(net "M_G_CPU1_SB_DQS_DN<7>")
		)
		(pad "EB26" smd circle
			(at -17.07769 20.385532 270)
			(size 0.4318 0.4318)
			(layers "F.Cu" "F.Mask" "F.Paste")
			(net "GND")
		)
		(pad "EB28" smd circle
			(at -15.450058 20.385532 270)
			(size 0.4318 0.4318)
			(layers "F.Cu" "F.Mask" "F.Paste")
			(net "GND")
		)
		(pad "EB30" smd circle
			(at -13.822426 20.385532 270)
			(size 0.4318 0.4318)
			(layers "F.Cu" "F.Mask" "F.Paste")
			(net "M_F_CPU1_SB_DQS_DN<5>")
		)
		(pad "EB32" smd circle
			(at -12.19454 20.385532 270)
			(size 0.4318 0.4318)
			(layers "F.Cu" "F.Mask" "F.Paste")
			(net "GND")
		)
		(pad "EB34" smd circle
			(at -10.566654 20.385532 270)
			(size 0.4318 0.4318)
			(layers "F.Cu" "F.Mask" "F.Paste")
			(net "GND")
		)
		(pad "EB36" smd circle
			(at -8.939022 20.385532 270)
			(size 0.4318 0.4318)
			(layers "F.Cu" "F.Mask" "F.Paste")
			(net "M_G_CPU1_SB_DQS_DN<4>")
		)
		(pad "EB38" smd circle
			(at -7.311136 20.385532 270)
			(size 0.4318 0.4318)
			(layers "F.Cu" "F.Mask" "F.Paste")
			(net "GND")
		)
		(pad "EB40" smd circle
			(at -5.68325 20.385532 270)
			(size 0.4318 0.4318)
			(layers "F.Cu" "F.Mask" "F.Paste")
			(net "GND")
		)
		(pad "EB42" smd circle
			(at -4.055618 20.385532 270)
			(size 0.4318 0.4318)
			(layers "F.Cu" "F.Mask" "F.Paste")
			(net "M_G_CPU1_SB_PAR")
		)
		(pad "EB44" smd circle
			(at -2.427732 20.385532 270)
			(size 0.4318 0.4318)
			(layers "F.Cu" "F.Mask" "F.Paste")
			(net "GND")
		)
		(pad "EB47" smd circle
			(at 1.613916 20.495514 270)
			(size 0.4318 0.4318)
			(layers "F.Cu" "F.Mask" "F.Paste")
			(net "GND")
		)
		(pad "EB49" smd circle
			(at 3.241802 20.495514 270)
			(size 0.4318 0.4318)
			(layers "F.Cu" "F.Mask" "F.Paste")
			(net "M_F_CPU1_CLK_DP<0>")
		)
		(pad "EB51" smd circle
			(at 4.869434 20.495514 270)
			(size 0.4318 0.4318)
			(layers "F.Cu" "F.Mask" "F.Paste")
			(net "GND")
		)
		(pad "EB53" smd circle
			(at 6.49732 20.495514 270)
			(size 0.4318 0.4318)
			(layers "F.Cu" "F.Mask" "F.Paste")
			(net "GND")
		)
		(pad "EB55" smd circle
			(at 8.124952 20.495514 270)
			(size 0.4318 0.4318)
			(layers "F.Cu" "F.Mask" "F.Paste")
			(net "M_F_CPU1_SA_DQS_DN<8>")
		)
		(pad "EB57" smd circle
			(at 9.752838 20.495514 270)
			(size 0.4318 0.4318)
			(layers "F.Cu" "F.Mask" "F.Paste")
			(net "GND")
		)
		(pad "EB59" smd circle
			(at 11.380724 20.495514 270)
			(size 0.4318 0.4318)
			(layers "F.Cu" "F.Mask" "F.Paste")
			(net "GND")
		)
		(pad "EB61" smd circle
			(at 13.008356 20.495514 270)
			(size 0.4318 0.4318)
			(layers "F.Cu" "F.Mask" "F.Paste")
			(net "M_G_CPU1_SA_DQS_DN<7>")
		)
		(pad "EB63" smd circle
			(at 14.635988 20.495514 270)
			(size 0.4318 0.4318)
			(layers "F.Cu" "F.Mask" "F.Paste")
			(net "GND")
		)
		(pad "EB65" smd circle
			(at 16.263874 20.495514 270)
			(size 0.4318 0.4318)
			(layers "F.Cu" "F.Mask" "F.Paste")
			(net "GND")
		)
		(pad "EB67" smd circle
			(at 17.89176 20.495514 270)
			(size 0.4318 0.4318)
			(layers "F.Cu" "F.Mask" "F.Paste")
			(net "M_F_CPU1_SA_DQS_DN<6>")
		)
		(pad "EB69" smd circle
			(at 19.519392 20.495514 270)
			(size 0.4318 0.4318)
			(layers "F.Cu" "F.Mask" "F.Paste")
			(net "GND")
		)
		(pad "EB71" smd circle
			(at 21.147278 20.495514 270)
			(size 0.4318 0.4318)
			(layers "F.Cu" "F.Mask" "F.Paste")
			(net "GND")
		)
		(pad "EB73" smd circle
			(at 22.77491 20.495514 270)
			(size 0.4318 0.4318)
			(layers "F.Cu" "F.Mask" "F.Paste")
			(net "M_G_CPU1_SA_DQS_DN<5>")
		)
		(pad "EB75" smd circle
			(at 24.402796 20.495514 270)
			(size 0.4318 0.4318)
			(layers "F.Cu" "F.Mask" "F.Paste")
			(net "GND")
		)
		(pad "EB77" smd circle
			(at 26.030682 20.495514 270)
			(size 0.4318 0.4318)
			(layers "F.Cu" "F.Mask" "F.Paste")
			(net "M_F_CPU1_SA_DQ<0>")
		)
		(pad "EB79" smd circle
			(at 27.658314 20.495514 270)
			(size 0.4318 0.4318)
			(layers "F.Cu" "F.Mask" "F.Paste")
			(net "GND")
		)
		(pad "EB81" smd circle
			(at 29.2862 20.495514 270)
			(size 0.4318 0.4318)
			(layers "F.Cu" "F.Mask" "F.Paste")
			(net "GND")
		)
		(pad "EB83" smd circle
			(at 30.914086 20.495514 270)
			(size 0.4318 0.4318)
			(layers "F.Cu" "F.Mask" "F.Paste")
			(net "GND")
		)
		(pad "EB85" smd circle
			(at 32.541718 20.495514 270)
			(size 0.4318 0.4318)
			(layers "F.Cu" "F.Mask" "F.Paste")
			(net "P5E_CPU1_PE3_TX_DN<1>")
		)
		(pad "EB87" smd circle
			(at 34.169604 20.495514 270)
			(size 0.4318 0.4318)
			(layers "F.Cu" "F.Mask" "F.Paste")
			(net "GND")
		)
		(pad "EB89" smd circle
			(at 35.797236 20.495514 270)
			(size 0.4318 0.4318)
			(layers "F.Cu" "F.Mask" "F.Paste")
			(net "P5E_CPU1_PE3_RX_DP<2>")
		)
		(pad "EB91" smd oval
			(at 37.425122 20.495514)
			(size 0.381 0.4826)
			(drill
				(offset 0 -0.0508)
			)
			(layers "F.Cu" "F.Mask" "F.Paste")
			(net "GND")
		)
		(pad "EC1" smd oval
			(at -37.425122 20.855686 180)
			(size 0.381 0.4826)
			(drill
				(offset 0 -0.0508)
			)
			(layers "F.Cu" "F.Mask" "F.Paste")
			(net "GND")
		)
		(pad "EC3" smd circle
			(at -35.797236 20.855686 270)
			(size 0.4318 0.4318)
			(layers "F.Cu" "F.Mask" "F.Paste")
			(net "UPI_CPU0_CPU1_P0P1_DP<2>")
		)
		(pad "EC5" smd circle
			(at -34.169604 20.855686 270)
			(size 0.4318 0.4318)
			(layers "F.Cu" "F.Mask" "F.Paste")
			(net "GND")
		)
		(pad "EC7" smd circle
			(at -32.541718 20.855686 270)
			(size 0.4318 0.4318)
			(layers "F.Cu" "F.Mask" "F.Paste")
			(net "UPI_CPU1_CPU0_P1P0_DN<1>")
		)
		(pad "EC9" smd circle
			(at -30.914086 20.855686 270)
			(size 0.4318 0.4318)
			(layers "F.Cu" "F.Mask" "F.Paste")
			(net "GND")
		)
		(pad "EC11" smd circle
			(at -29.2862 20.855686 270)
			(size 0.4318 0.4318)
			(layers "F.Cu" "F.Mask" "F.Paste")
			(net "P5E_CPU1_PE2_RX_DP<13>")
		)
		(pad "EC13" smd circle
			(at -27.658314 20.855686 270)
			(size 0.4318 0.4318)
			(layers "F.Cu" "F.Mask" "F.Paste")
			(net "GND")
		)
		(pad "EC15" smd circle
			(at -26.030682 20.855686 270)
			(size 0.4318 0.4318)
			(layers "F.Cu" "F.Mask" "F.Paste")
			(net "P5E_CPU1_PE2_TX_DP<13>")
		)
		(pad "EC17" smd circle
			(at -24.402796 20.855686 270)
			(size 0.4318 0.4318)
			(layers "F.Cu" "F.Mask" "F.Paste")
			(net "M_F_CPU1_SB_DQ<30>")
		)
		(pad "EC19" smd circle
			(at -22.77491 20.855686 270)
			(size 0.4318 0.4318)
			(layers "F.Cu" "F.Mask" "F.Paste")
			(net "GND")
		)
		(pad "EC21" smd circle
			(at -21.147278 20.855686 270)
			(size 0.4318 0.4318)
			(layers "F.Cu" "F.Mask" "F.Paste")
			(net "M_F_CPU1_SB_DQS_DP<1>")
		)
		(pad "EC23" smd circle
			(at -19.519392 20.855686 270)
			(size 0.4318 0.4318)
			(layers "F.Cu" "F.Mask" "F.Paste")
			(net "GND")
		)
		(pad "EC25" smd circle
			(at -17.89176 20.855686 270)
			(size 0.4318 0.4318)
			(layers "F.Cu" "F.Mask" "F.Paste")
			(net "GND")
		)
		(pad "EC27" smd circle
			(at -16.263874 20.855686 270)
			(size 0.4318 0.4318)
			(layers "F.Cu" "F.Mask" "F.Paste")
			(net "M_E_CPU1_SB_DQS_DP<0>")
		)
		(pad "EC29" smd circle
			(at -14.635988 20.855686 270)
			(size 0.4318 0.4318)
			(layers "F.Cu" "F.Mask" "F.Paste")
			(net "GND")
		)
		(pad "EC31" smd circle
			(at -13.008356 20.855686 270)
			(size 0.4318 0.4318)
			(layers "F.Cu" "F.Mask" "F.Paste")
			(net "GND")
		)
		(pad "EC33" smd circle
			(at -11.380724 20.855686 270)
			(size 0.4318 0.4318)
			(layers "F.Cu" "F.Mask" "F.Paste")
			(net "M_F_CPU1_SB_DQS_DP<9>")
		)
		(pad "EC35" smd circle
			(at -9.752838 20.855686 270)
			(size 0.4318 0.4318)
			(layers "F.Cu" "F.Mask" "F.Paste")
			(net "GND")
		)
		(pad "EC37" smd circle
			(at -8.124952 20.855686 270)
			(size 0.4318 0.4318)
			(layers "F.Cu" "F.Mask" "F.Paste")
			(net "GND")
		)
		(pad "EC39" smd circle
			(at -6.49732 20.855686 270)
			(size 0.4318 0.4318)
			(layers "F.Cu" "F.Mask" "F.Paste")
			(net "M_F_CPU1_SB_CA<6>")
		)
		(pad "EC41" smd circle
			(at -4.869434 20.855686 270)
			(size 0.4318 0.4318)
			(layers "F.Cu" "F.Mask" "F.Paste")
			(net "GND")
		)
		(pad "EC43" smd circle
			(at -3.241802 20.855686 270)
			(size 0.4318 0.4318)
			(layers "F.Cu" "F.Mask" "F.Paste")
			(net "GND")
		)
		(pad "EC45" smd circle
			(at -1.613916 20.855686 270)
			(size 0.4318 0.4318)
			(layers "F.Cu" "F.Mask" "F.Paste")
			(net "M_E_CPU1_CLK_DP<1>")
		)
		(pad "EC48" smd circle
			(at 2.427732 20.965668 270)
			(size 0.4318 0.4318)
			(layers "F.Cu" "F.Mask" "F.Paste")
			(net "GND")
		)
		(pad "EC50" smd circle
			(at 4.055618 20.965668 270)
			(size 0.4318 0.4318)
			(layers "F.Cu" "F.Mask" "F.Paste")
			(net "GND")
		)
		(pad "EC52" smd circle
			(at 5.68325 20.965668 270)
			(size 0.4318 0.4318)
			(layers "F.Cu" "F.Mask" "F.Paste")
			(net "M_F_CPU1_SA_CA<0>")
		)
		(pad "EC54" smd circle
			(at 7.311136 20.965668 270)
			(size 0.4318 0.4318)
			(layers "F.Cu" "F.Mask" "F.Paste")
			(net "GND")
		)
		(pad "EC56" smd circle
			(at 8.939022 20.965668 270)
			(size 0.4318 0.4318)
			(layers "F.Cu" "F.Mask" "F.Paste")
			(net "GND")
		)
		(pad "EC58" smd circle
			(at 10.566654 20.965668 270)
			(size 0.4318 0.4318)
			(layers "F.Cu" "F.Mask" "F.Paste")
			(net "M_F_CPU1_SA_DQS_DP<4>")
		)
		(pad "EC60" smd circle
			(at 12.19454 20.965668 270)
			(size 0.4318 0.4318)
			(layers "F.Cu" "F.Mask" "F.Paste")
			(net "GND")
		)
		(pad "EC62" smd circle
			(at 13.822426 20.965668 270)
			(size 0.4318 0.4318)
			(layers "F.Cu" "F.Mask" "F.Paste")
			(net "GND")
		)
		(pad "EC64" smd circle
			(at 15.450058 20.965668 270)
			(size 0.4318 0.4318)
			(layers "F.Cu" "F.Mask" "F.Paste")
			(net "M_F_CPU1_SA_DQS_DN<2>")
		)
		(pad "EC66" smd circle
			(at 17.07769 20.965668 270)
			(size 0.4318 0.4318)
			(layers "F.Cu" "F.Mask" "F.Paste")
			(net "GND")
		)
		(pad "EC68" smd circle
			(at 18.705576 20.965668 270)
			(size 0.4318 0.4318)
			(layers "F.Cu" "F.Mask" "F.Paste")
			(net "GND")
		)
		(pad "EC70" smd circle
			(at 20.333462 20.965668 270)
			(size 0.4318 0.4318)
			(layers "F.Cu" "F.Mask" "F.Paste")
			(net "M_E_CPU1_SA_DQS_DN<1>")
		)
		(pad "EC72" smd circle
			(at 21.961094 20.965668 270)
			(size 0.4318 0.4318)
			(layers "F.Cu" "F.Mask" "F.Paste")
			(net "GND")
		)
		(pad "EC74" smd circle
			(at 23.58898 20.965668 270)
			(size 0.4318 0.4318)
			(layers "F.Cu" "F.Mask" "F.Paste")
			(net "GND")
		)
		(pad "EC76" smd circle
			(at 25.216612 20.965668 270)
			(size 0.4318 0.4318)
			(layers "F.Cu" "F.Mask" "F.Paste")
			(net "M_F_CPU1_SA_DQS_DP<0>")
		)
		(pad "EC78" smd circle
			(at 26.844498 20.965668 270)
			(size 0.4318 0.4318)
			(layers "F.Cu" "F.Mask" "F.Paste")
			(net "PVCCFA_EHV_FIVRA_CPU1")
		)
		(pad "EC80" smd circle
			(at 28.472384 20.965668 270)
			(size 0.4318 0.4318)
			(layers "F.Cu" "F.Mask" "F.Paste")
			(net "GND")
		)
		(pad "EC82" smd circle
			(at 30.100016 20.965668 270)
			(size 0.4318 0.4318)
			(layers "F.Cu" "F.Mask" "F.Paste")
			(net "GND")
		)
		(pad "EC84" smd circle
			(at 31.727902 20.965668 270)
			(size 0.4318 0.4318)
			(layers "F.Cu" "F.Mask" "F.Paste")
			(net "GND")
		)
		(pad "EC86" smd circle
			(at 33.355534 20.965668 270)
			(size 0.4318 0.4318)
			(layers "F.Cu" "F.Mask" "F.Paste")
			(net "P5E_CPU1_PE3_TX_DP<1>")
		)
		(pad "EC88" smd circle
			(at 34.98342 20.965668 270)
			(size 0.4318 0.4318)
			(layers "F.Cu" "F.Mask" "F.Paste")
			(net "GND")
		)
		(pad "EC90" smd circle
			(at 36.611306 20.965668 270)
			(size 0.4318 0.4318)
			(layers "F.Cu" "F.Mask" "F.Paste")
			(net "P5E_CPU1_PE3_RX_DN<2>")
		)
		(pad "ED2" smd oval
			(at -36.611306 21.325332 180)
			(size 0.381 0.4826)
			(drill
				(offset 0 -0.0508)
			)
			(layers "F.Cu" "F.Mask" "F.Paste")
			(net "UPI_CPU0_CPU1_P0P1_DN<2>")
		)
		(pad "ED4" smd circle
			(at -34.98342 21.325332 270)
			(size 0.4318 0.4318)
			(layers "F.Cu" "F.Mask" "F.Paste")
			(net "GND")
		)
		(pad "ED6" smd circle
			(at -33.355534 21.325332 270)
			(size 0.4318 0.4318)
			(layers "F.Cu" "F.Mask" "F.Paste")
			(net "UPI_CPU1_CPU0_P1P0_DP<1>")
		)
		(pad "ED8" smd circle
			(at -31.727902 21.325332 270)
			(size 0.4318 0.4318)
			(layers "F.Cu" "F.Mask" "F.Paste")
			(net "GND")
		)
		(pad "ED10" smd circle
			(at -30.100016 21.325332 270)
			(size 0.4318 0.4318)
			(layers "F.Cu" "F.Mask" "F.Paste")
			(net "P5E_CPU1_PE2_RX_DN<13>")
		)
		(pad "ED12" smd circle
			(at -28.472384 21.325332 270)
			(size 0.4318 0.4318)
			(layers "F.Cu" "F.Mask" "F.Paste")
			(net "GND")
		)
		(pad "ED14" smd circle
			(at -26.844498 21.325332 270)
			(size 0.4318 0.4318)
			(layers "F.Cu" "F.Mask" "F.Paste")
			(net "P5E_CPU1_PE2_TX_DP<14>")
		)
		(pad "ED16" smd circle
			(at -25.216612 21.325332 270)
			(size 0.4318 0.4318)
			(layers "F.Cu" "F.Mask" "F.Paste")
			(net "GND")
		)
		(pad "ED18" smd circle
			(at -23.58898 21.325332 270)
			(size 0.4318 0.4318)
			(layers "F.Cu" "F.Mask" "F.Paste")
			(net "GND")
		)
		(pad "ED20" smd circle
			(at -21.961094 21.325332 270)
			(size 0.4318 0.4318)
			(layers "F.Cu" "F.Mask" "F.Paste")
			(net "M_F_CPU1_SB_DQ<12>")
		)
		(pad "ED22" smd circle
			(at -20.333462 21.325332 270)
			(size 0.4318 0.4318)
			(layers "F.Cu" "F.Mask" "F.Paste")
			(net "M_F_CPU1_SB_DQ<9>")
		)
		(pad "ED24" smd circle
			(at -18.705576 21.325332 270)
			(size 0.4318 0.4318)
			(layers "F.Cu" "F.Mask" "F.Paste")
			(net "GND")
		)
		(pad "ED26" smd circle
			(at -17.07769 21.325332 270)
			(size 0.4318 0.4318)
			(layers "F.Cu" "F.Mask" "F.Paste")
			(net "M_E_CPU1_SB_DQ<4>")
		)
		(pad "ED28" smd circle
			(at -15.450058 21.325332 270)
			(size 0.4318 0.4318)
			(layers "F.Cu" "F.Mask" "F.Paste")
			(net "M_E_CPU1_SB_DQ<1>")
		)
		(pad "ED30" smd circle
			(at -13.822426 21.325332 270)
			(size 0.4318 0.4318)
			(layers "F.Cu" "F.Mask" "F.Paste")
			(net "GND")
		)
		(pad "ED32" smd circle
			(at -12.19454 21.325332 270)
			(size 0.4318 0.4318)
			(layers "F.Cu" "F.Mask" "F.Paste")
			(net "M_F_CPU1_SB_CB<0>")
		)
		(pad "ED34" smd circle
			(at -10.566654 21.325332 270)
			(size 0.4318 0.4318)
			(layers "F.Cu" "F.Mask" "F.Paste")
			(net "M_F_CPU1_SB_CB<5>")
		)
		(pad "ED36" smd circle
			(at -8.939022 21.325332 270)
			(size 0.4318 0.4318)
			(layers "F.Cu" "F.Mask" "F.Paste")
			(net "GND")
		)
		(pad "ED38" smd circle
			(at -7.311136 21.325332 270)
			(size 0.4318 0.4318)
			(layers "F.Cu" "F.Mask" "F.Paste")
			(net "M_F_CPU1_SB_CS_N<2>")
		)
		(pad "ED40" smd circle
			(at -5.68325 21.325332 270)
			(size 0.4318 0.4318)
			(layers "F.Cu" "F.Mask" "F.Paste")
			(net "M_F_CPU1_SB_CA<4>")
		)
		(pad "ED42" smd circle
			(at -4.055618 21.325332 270)
			(size 0.4318 0.4318)
			(layers "F.Cu" "F.Mask" "F.Paste")
			(net "GND")
		)
		(pad "ED44" smd circle
			(at -2.427732 21.325332 270)
			(size 0.4318 0.4318)
			(layers "F.Cu" "F.Mask" "F.Paste")
			(net "M_E_CPU1_SA_CA<6>")
		)
		(pad "ED47" smd circle
			(at 1.613916 21.435314 270)
			(size 0.4318 0.4318)
			(layers "F.Cu" "F.Mask" "F.Paste")
			(net "M_H_CPU1_SB_RSP<1>")
		)
		(pad "ED49" smd circle
			(at 3.241802 21.435314 270)
			(size 0.4318 0.4318)
			(layers "F.Cu" "F.Mask" "F.Paste")
			(net "GND")
		)
		(pad "ED51" smd circle
			(at 4.869434 21.435314 270)
			(size 0.4318 0.4318)
			(layers "F.Cu" "F.Mask" "F.Paste")
			(net "M_F_CPU1_SA_CA<2>")
		)
		(pad "ED53" smd circle
			(at 6.49732 21.435314 270)
			(size 0.4318 0.4318)
			(layers "F.Cu" "F.Mask" "F.Paste")
			(net "M_F_CPU1_SA_CS_N<3>")
		)
		(pad "ED55" smd circle
			(at 8.124952 21.435314 270)
			(size 0.4318 0.4318)
			(layers "F.Cu" "F.Mask" "F.Paste")
			(net "GND")
		)
		(pad "ED57" smd circle
			(at 9.752838 21.435314 270)
			(size 0.4318 0.4318)
			(layers "F.Cu" "F.Mask" "F.Paste")
			(net "M_F_CPU1_SA_CB<4>")
		)
		(pad "ED59" smd circle
			(at 11.380724 21.435314 270)
			(size 0.4318 0.4318)
			(layers "F.Cu" "F.Mask" "F.Paste")
			(net "M_F_CPU1_SA_CB<1>")
		)
		(pad "ED61" smd circle
			(at 13.008356 21.435314 270)
			(size 0.4318 0.4318)
			(layers "F.Cu" "F.Mask" "F.Paste")
			(net "GND")
		)
		(pad "ED63" smd circle
			(at 14.635988 21.435314 270)
			(size 0.4318 0.4318)
			(layers "F.Cu" "F.Mask" "F.Paste")
			(net "M_F_CPU1_SA_DQ<20>")
		)
		(pad "ED65" smd circle
			(at 16.263874 21.435314 270)
			(size 0.4318 0.4318)
			(layers "F.Cu" "F.Mask" "F.Paste")
			(net "M_F_CPU1_SA_DQ<17>")
		)
		(pad "ED67" smd circle
			(at 17.89176 21.435314 270)
			(size 0.4318 0.4318)
			(layers "F.Cu" "F.Mask" "F.Paste")
			(net "GND")
		)
		(pad "ED69" smd circle
			(at 19.519392 21.435314 270)
			(size 0.4318 0.4318)
			(layers "F.Cu" "F.Mask" "F.Paste")
			(net "M_E_CPU1_SA_DQ<12>")
		)
		(pad "ED71" smd circle
			(at 21.147278 21.435314 270)
			(size 0.4318 0.4318)
			(layers "F.Cu" "F.Mask" "F.Paste")
			(net "M_E_CPU1_SA_DQ<9>")
		)
		(pad "ED73" smd circle
			(at 22.77491 21.435314 270)
			(size 0.4318 0.4318)
			(layers "F.Cu" "F.Mask" "F.Paste")
			(net "GND")
		)
		(pad "ED75" smd circle
			(at 24.402796 21.435314 270)
			(size 0.4318 0.4318)
			(layers "F.Cu" "F.Mask" "F.Paste")
			(net "M_F_CPU1_SA_DQ<4>")
		)
		(pad "ED77" smd circle
			(at 26.030682 21.435314 270)
			(size 0.4318 0.4318)
			(layers "F.Cu" "F.Mask" "F.Paste")
			(net "M_F_CPU1_SA_DQ<2>")
		)
		(pad "ED79" smd circle
			(at 27.658314 21.435314 270)
			(size 0.4318 0.4318)
			(layers "F.Cu" "F.Mask" "F.Paste")
			(net "PVCCFA_EHV_FIVRA_CPU1")
		)
		(pad "ED81" smd circle
			(at 29.2862 21.435314 270)
			(size 0.4318 0.4318)
			(layers "F.Cu" "F.Mask" "F.Paste")
			(net "GND")
		)
		(pad "ED83" smd circle
			(at 30.914086 21.435314 270)
			(size 0.4318 0.4318)
			(layers "F.Cu" "F.Mask" "F.Paste")
			(net "GND")
		)
		(pad "ED85" smd circle
			(at 32.541718 21.435314 270)
			(size 0.4318 0.4318)
			(layers "F.Cu" "F.Mask" "F.Paste")
			(net "PVCCFA_EHV_FIVRA_CPU1")
		)
		(pad "ED87" smd circle
			(at 34.169604 21.435314 270)
			(size 0.4318 0.4318)
			(layers "F.Cu" "F.Mask" "F.Paste")
			(net "P5E_CPU1_PE3_TX_DP<0>")
		)
		(pad "ED89" smd circle
			(at 35.797236 21.435314 270)
			(size 0.4318 0.4318)
			(layers "F.Cu" "F.Mask" "F.Paste")
			(net "PVCCFA_EHV_FIVRA_CPU1")
		)
		(pad "ED91" smd oval
			(at 37.425122 21.435314)
			(size 0.381 0.4826)
			(drill
				(offset 0 -0.0508)
			)
			(layers "F.Cu" "F.Mask" "F.Paste")
			(net "P5E_CPU1_PE3_RX_DN<1>")
		)
		(pad "EE3" smd circle
			(at -35.797236 21.795486 270)
			(size 0.4318 0.4318)
			(layers "F.Cu" "F.Mask" "F.Paste")
			(net "UPI_CPU0_CPU1_P0P1_DN<1>")
		)
		(pad "EE5" smd circle
			(at -34.169604 21.795486 270)
			(size 0.4318 0.4318)
			(layers "F.Cu" "F.Mask" "F.Paste")
			(net "UPI_CPU1_CPU0_P1P0_DP<0>")
		)
		(pad "EE7" smd circle
			(at -32.541718 21.795486 270)
			(size 0.4318 0.4318)
			(layers "F.Cu" "F.Mask" "F.Paste")
			(net "PVCCFA_EHV_FIVRA_CPU1")
		)
		(pad "EE9" smd circle
			(at -30.914086 21.795486 270)
			(size 0.4318 0.4318)
			(layers "F.Cu" "F.Mask" "F.Paste")
			(net "P5E_CPU1_PE2_RX_DN<14>")
		)
		(pad "EE11" smd circle
			(at -29.2862 21.795486 270)
			(size 0.4318 0.4318)
			(layers "F.Cu" "F.Mask" "F.Paste")
			(net "PVCCFA_EHV_FIVRA_CPU1")
		)
		(pad "EE13" smd circle
			(at -27.658314 21.795486 270)
			(size 0.4318 0.4318)
			(layers "F.Cu" "F.Mask" "F.Paste")
			(net "P5E_CPU1_PE2_TX_DN<14>")
		)
		(pad "EE15" smd circle
			(at -26.030682 21.795486 270)
			(size 0.4318 0.4318)
			(layers "F.Cu" "F.Mask" "F.Paste")
			(net "PVCCFA_EHV_FIVRA_CPU1")
		)
		(pad "EE17" smd circle
			(at -24.402796 21.795486 270)
			(size 0.4318 0.4318)
			(layers "F.Cu" "F.Mask" "F.Paste")
			(net "GND")
		)
		(pad "EE19" smd circle
			(at -22.77491 21.795486 270)
			(size 0.4318 0.4318)
			(layers "F.Cu" "F.Mask" "F.Paste")
			(net "M_F_CPU1_SB_DQ<13>")
		)
		(pad "EE21" smd circle
			(at -21.147278 21.795486 270)
			(size 0.4318 0.4318)
			(layers "F.Cu" "F.Mask" "F.Paste")
			(net "M_F_CPU1_SB_DQS_DN<1>")
		)
		(pad "EE23" smd circle
			(at -19.519392 21.795486 270)
			(size 0.4318 0.4318)
			(layers "F.Cu" "F.Mask" "F.Paste")
			(net "M_F_CPU1_SB_DQ<8>")
		)
		(pad "EE25" smd circle
			(at -17.89176 21.795486 270)
			(size 0.4318 0.4318)
			(layers "F.Cu" "F.Mask" "F.Paste")
			(net "M_E_CPU1_SB_DQ<5>")
		)
		(pad "EE27" smd circle
			(at -16.263874 21.795486 270)
			(size 0.4318 0.4318)
			(layers "F.Cu" "F.Mask" "F.Paste")
			(net "M_E_CPU1_SB_DQS_DN<0>")
		)
		(pad "EE29" smd circle
			(at -14.635988 21.795486 270)
			(size 0.4318 0.4318)
			(layers "F.Cu" "F.Mask" "F.Paste")
			(net "M_E_CPU1_SB_DQ<0>")
		)
		(pad "EE31" smd circle
			(at -13.008356 21.795486 270)
			(size 0.4318 0.4318)
			(layers "F.Cu" "F.Mask" "F.Paste")
			(net "M_F_CPU1_SB_CB<1>")
		)
		(pad "EE33" smd circle
			(at -11.380724 21.795486 270)
			(size 0.4318 0.4318)
			(layers "F.Cu" "F.Mask" "F.Paste")
			(net "M_F_CPU1_SB_DQS_DN<9>")
		)
		(pad "EE35" smd circle
			(at -9.752838 21.795486 270)
			(size 0.4318 0.4318)
			(layers "F.Cu" "F.Mask" "F.Paste")
			(net "M_F_CPU1_SB_CB<4>")
		)
		(pad "EE37" smd circle
			(at -8.124952 21.795486 270)
			(size 0.4318 0.4318)
			(layers "F.Cu" "F.Mask" "F.Paste")
			(net "M_F_CPU1_SB_CS_N<3>")
		)
		(pad "EE39" smd circle
			(at -6.49732 21.795486 270)
			(size 0.4318 0.4318)
			(layers "F.Cu" "F.Mask" "F.Paste")
			(net "GND")
		)
		(pad "EE41" smd circle
			(at -4.869434 21.795486 270)
			(size 0.4318 0.4318)
			(layers "F.Cu" "F.Mask" "F.Paste")
			(net "M_F_CPU1_SB_CA<2>")
		)
		(pad "EE43" smd circle
			(at -3.241802 21.795486 270)
			(size 0.4318 0.4318)
			(layers "F.Cu" "F.Mask" "F.Paste")
			(net "M_E_CPU1_SA_PAR")
		)
		(pad "EE45" smd circle
			(at -1.613916 21.795486 270)
			(size 0.4318 0.4318)
			(layers "F.Cu" "F.Mask" "F.Paste")
			(net "M_E_CPU1_CLK_DN<1>")
		)
		(pad "EE48" smd circle
			(at 2.427732 21.905468 270)
			(size 0.4318 0.4318)
			(layers "F.Cu" "F.Mask" "F.Paste")
			(net "M_H_CPU1_SB_RSP<0>")
		)
		(pad "EE50" smd circle
			(at 4.055618 21.905468 270)
			(size 0.4318 0.4318)
			(layers "F.Cu" "F.Mask" "F.Paste")
			(net "M_F_CPU1_SA_CA<4>")
		)
		(pad "EE52" smd circle
			(at 5.68325 21.905468 270)
			(size 0.4318 0.4318)
			(layers "F.Cu" "F.Mask" "F.Paste")
			(net "GND")
		)
		(pad "EE54" smd circle
			(at 7.311136 21.905468 270)
			(size 0.4318 0.4318)
			(layers "F.Cu" "F.Mask" "F.Paste")
			(net "M_F_CPU1_SA_CS_N<2>")
		)
		(pad "EE56" smd circle
			(at 8.939022 21.905468 270)
			(size 0.4318 0.4318)
			(layers "F.Cu" "F.Mask" "F.Paste")
			(net "M_F_CPU1_SA_CB<5>")
		)
		(pad "EE58" smd circle
			(at 10.566654 21.905468 270)
			(size 0.4318 0.4318)
			(layers "F.Cu" "F.Mask" "F.Paste")
			(net "M_F_CPU1_SA_DQS_DN<4>")
		)
		(pad "EE60" smd circle
			(at 12.19454 21.905468 270)
			(size 0.4318 0.4318)
			(layers "F.Cu" "F.Mask" "F.Paste")
			(net "M_F_CPU1_SA_CB<0>")
		)
		(pad "EE62" smd circle
			(at 13.822426 21.905468 270)
			(size 0.4318 0.4318)
			(layers "F.Cu" "F.Mask" "F.Paste")
			(net "M_F_CPU1_SA_DQ<21>")
		)
		(pad "EE64" smd circle
			(at 15.450058 21.905468 270)
			(size 0.4318 0.4318)
			(layers "F.Cu" "F.Mask" "F.Paste")
			(net "M_F_CPU1_SA_DQS_DP<2>")
		)
		(pad "EE66" smd circle
			(at 17.07769 21.905468 270)
			(size 0.4318 0.4318)
			(layers "F.Cu" "F.Mask" "F.Paste")
			(net "M_F_CPU1_SA_DQ<16>")
		)
		(pad "EE68" smd circle
			(at 18.705576 21.905468 270)
			(size 0.4318 0.4318)
			(layers "F.Cu" "F.Mask" "F.Paste")
			(net "M_E_CPU1_SA_DQ<13>")
		)
		(pad "EE70" smd circle
			(at 20.333462 21.905468 270)
			(size 0.4318 0.4318)
			(layers "F.Cu" "F.Mask" "F.Paste")
			(net "M_E_CPU1_SA_DQS_DP<1>")
		)
		(pad "EE72" smd circle
			(at 21.961094 21.905468 270)
			(size 0.4318 0.4318)
			(layers "F.Cu" "F.Mask" "F.Paste")
			(net "M_E_CPU1_SA_DQ<8>")
		)
		(pad "EE74" smd circle
			(at 23.58898 21.905468 270)
			(size 0.4318 0.4318)
			(layers "F.Cu" "F.Mask" "F.Paste")
			(net "M_F_CPU1_SA_DQ<5>")
		)
		(pad "EE76" smd circle
			(at 25.216612 21.905468 270)
			(size 0.4318 0.4318)
			(layers "F.Cu" "F.Mask" "F.Paste")
			(net "M_F_CPU1_SA_DQS_DN<0>")
		)
		(pad "EE78" smd circle
			(at 26.844498 21.905468 270)
			(size 0.4318 0.4318)
			(layers "F.Cu" "F.Mask" "F.Paste")
			(net "GND")
		)
		(pad "EE80" smd circle
			(at 28.472384 21.905468 270)
			(size 0.4318 0.4318)
			(layers "F.Cu" "F.Mask" "F.Paste")
			(net "GND")
		)
		(pad "EE82" smd circle
			(at 30.100016 21.905468 270)
			(size 0.4318 0.4318)
			(layers "F.Cu" "F.Mask" "F.Paste")
			(net "GND")
		)
		(pad "EE84" smd circle
			(at 31.727902 21.905468 270)
			(size 0.4318 0.4318)
			(layers "F.Cu" "F.Mask" "F.Paste")
			(net "PVCCFA_EHV_FIVRA_CPU1")
		)
		(pad "EE86" smd circle
			(at 33.355534 21.905468 270)
			(size 0.4318 0.4318)
			(layers "F.Cu" "F.Mask" "F.Paste")
			(net "P5E_CPU1_PE3_TX_DN<0>")
		)
		(pad "EE88" smd circle
			(at 34.98342 21.905468 270)
			(size 0.4318 0.4318)
			(layers "F.Cu" "F.Mask" "F.Paste")
			(net "GND")
		)
		(pad "EE90" smd oval
			(at 36.611306 21.905468)
			(size 0.381 0.4826)
			(drill
				(offset 0 -0.0508)
			)
			(layers "F.Cu" "F.Mask" "F.Paste")
			(net "P5E_CPU1_PE3_RX_DP<1>")
		)
		(pad "EF2" smd oval
			(at -36.611306 22.265386 180)
			(size 0.381 0.4826)
			(drill
				(offset 0 -0.0508)
			)
			(layers "F.Cu" "F.Mask" "F.Paste")
			(net "GND")
		)
		(pad "EF4" smd circle
			(at -34.98342 22.265386 270)
			(size 0.4318 0.4318)
			(layers "F.Cu" "F.Mask" "F.Paste")
			(net "GND")
		)
		(pad "EF6" smd circle
			(at -33.355534 22.265386 270)
			(size 0.4318 0.4318)
			(layers "F.Cu" "F.Mask" "F.Paste")
			(net "UPI_CPU1_CPU0_P1P0_DN<0>")
		)
		(pad "EF8" smd circle
			(at -31.727902 22.265386 270)
			(size 0.4318 0.4318)
			(layers "F.Cu" "F.Mask" "F.Paste")
			(net "GND")
		)
		(pad "EF10" smd circle
			(at -30.100016 22.265386 270)
			(size 0.4318 0.4318)
			(layers "F.Cu" "F.Mask" "F.Paste")
			(net "P5E_CPU1_PE2_RX_DP<14>")
		)
		(pad "EF12" smd circle
			(at -28.472384 22.265386 270)
			(size 0.4318 0.4318)
			(layers "F.Cu" "F.Mask" "F.Paste")
			(net "GND")
		)
		(pad "EF14" smd circle
			(at -26.844498 22.265386 270)
			(size 0.4318 0.4318)
			(layers "F.Cu" "F.Mask" "F.Paste")
			(net "P5E_CPU1_PE2_TX_DN<15>")
		)
		(pad "EF16" smd circle
			(at -25.216612 22.265386 270)
			(size 0.4318 0.4318)
			(layers "F.Cu" "F.Mask" "F.Paste")
			(net "GND")
		)
		(pad "EF18" smd circle
			(at -23.58898 22.265386 270)
			(size 0.4318 0.4318)
			(layers "F.Cu" "F.Mask" "F.Paste")
			(net "GND")
		)
		(pad "EF20" smd circle
			(at -21.961094 22.265386 270)
			(size 0.4318 0.4318)
			(layers "F.Cu" "F.Mask" "F.Paste")
			(net "GND")
		)
		(pad "EF22" smd circle
			(at -20.333462 22.265386 270)
			(size 0.4318 0.4318)
			(layers "F.Cu" "F.Mask" "F.Paste")
			(net "GND")
		)
		(pad "EF24" smd circle
			(at -18.705576 22.265386 270)
			(size 0.4318 0.4318)
			(layers "F.Cu" "F.Mask" "F.Paste")
			(net "GND")
		)
		(pad "EF26" smd circle
			(at -17.07769 22.265386 270)
			(size 0.4318 0.4318)
			(layers "F.Cu" "F.Mask" "F.Paste")
			(net "GND")
		)
		(pad "EF28" smd circle
			(at -15.450058 22.265386 270)
			(size 0.4318 0.4318)
			(layers "F.Cu" "F.Mask" "F.Paste")
			(net "GND")
		)
		(pad "EF30" smd circle
			(at -13.822426 22.265386 270)
			(size 0.4318 0.4318)
			(layers "F.Cu" "F.Mask" "F.Paste")
			(net "GND")
		)
		(pad "EF32" smd circle
			(at -12.19454 22.265386 270)
			(size 0.4318 0.4318)
			(layers "F.Cu" "F.Mask" "F.Paste")
			(net "GND")
		)
		(pad "EF34" smd circle
			(at -10.566654 22.265386 270)
			(size 0.4318 0.4318)
			(layers "F.Cu" "F.Mask" "F.Paste")
			(net "GND")
		)
		(pad "EF36" smd circle
			(at -8.939022 22.265386 270)
			(size 0.4318 0.4318)
			(layers "F.Cu" "F.Mask" "F.Paste")
			(net "GND")
		)
		(pad "EF38" smd circle
			(at -7.311136 22.265386 270)
			(size 0.4318 0.4318)
			(layers "F.Cu" "F.Mask" "F.Paste")
			(net "GND")
		)
		(pad "EF40" smd circle
			(at -5.68325 22.265386 270)
			(size 0.4318 0.4318)
			(layers "F.Cu" "F.Mask" "F.Paste")
			(net "GND")
		)
		(pad "EF42" smd circle
			(at -4.055618 22.265386 270)
			(size 0.4318 0.4318)
			(layers "F.Cu" "F.Mask" "F.Paste")
			(net "GND")
		)
		(pad "EF44" smd circle
			(at -2.427732 22.265386 270)
			(size 0.4318 0.4318)
			(layers "F.Cu" "F.Mask" "F.Paste")
			(net "GND")
		)
		(pad "EF47" smd circle
			(at 1.613916 22.375114 270)
			(size 0.4318 0.4318)
			(layers "F.Cu" "F.Mask" "F.Paste")
			(net "GND")
		)
		(pad "EF49" smd circle
			(at 3.241802 22.375114 270)
			(size 0.4318 0.4318)
			(layers "F.Cu" "F.Mask" "F.Paste")
			(net "GND")
		)
		(pad "EF51" smd circle
			(at 4.869434 22.375114 270)
			(size 0.4318 0.4318)
			(layers "F.Cu" "F.Mask" "F.Paste")
			(net "GND")
		)
		(pad "EF53" smd circle
			(at 6.49732 22.375114 270)
			(size 0.4318 0.4318)
			(layers "F.Cu" "F.Mask" "F.Paste")
			(net "GND")
		)
		(pad "EF55" smd circle
			(at 8.124952 22.375114 270)
			(size 0.4318 0.4318)
			(layers "F.Cu" "F.Mask" "F.Paste")
			(net "GND")
		)
		(pad "EF57" smd circle
			(at 9.752838 22.375114 270)
			(size 0.4318 0.4318)
			(layers "F.Cu" "F.Mask" "F.Paste")
			(net "GND")
		)
		(pad "EF59" smd circle
			(at 11.380724 22.375114 270)
			(size 0.4318 0.4318)
			(layers "F.Cu" "F.Mask" "F.Paste")
			(net "GND")
		)
		(pad "EF61" smd circle
			(at 13.008356 22.375114 270)
			(size 0.4318 0.4318)
			(layers "F.Cu" "F.Mask" "F.Paste")
			(net "GND")
		)
		(pad "EF63" smd circle
			(at 14.635988 22.375114 270)
			(size 0.4318 0.4318)
			(layers "F.Cu" "F.Mask" "F.Paste")
			(net "GND")
		)
		(pad "EF65" smd circle
			(at 16.263874 22.375114 270)
			(size 0.4318 0.4318)
			(layers "F.Cu" "F.Mask" "F.Paste")
			(net "GND")
		)
		(pad "EF67" smd circle
			(at 17.89176 22.375114 270)
			(size 0.4318 0.4318)
			(layers "F.Cu" "F.Mask" "F.Paste")
			(net "GND")
		)
		(pad "EF69" smd circle
			(at 19.519392 22.375114 270)
			(size 0.4318 0.4318)
			(layers "F.Cu" "F.Mask" "F.Paste")
			(net "GND")
		)
		(pad "EF71" smd circle
			(at 21.147278 22.375114 270)
			(size 0.4318 0.4318)
			(layers "F.Cu" "F.Mask" "F.Paste")
			(net "GND")
		)
		(pad "EF73" smd circle
			(at 22.77491 22.375114 270)
			(size 0.4318 0.4318)
			(layers "F.Cu" "F.Mask" "F.Paste")
			(net "GND")
		)
		(pad "EF75" smd circle
			(at 24.402796 22.375114 270)
			(size 0.4318 0.4318)
			(layers "F.Cu" "F.Mask" "F.Paste")
			(net "GND")
		)
		(pad "EF77" smd circle
			(at 26.030682 22.375114 270)
			(size 0.4318 0.4318)
			(layers "F.Cu" "F.Mask" "F.Paste")
			(net "GND")
		)
		(pad "EF79" smd circle
			(at 27.658314 22.375114 270)
			(size 0.4318 0.4318)
			(layers "F.Cu" "F.Mask" "F.Paste")
			(net "PVCCFA_EHV_FIVRA_CPU1")
		)
		(pad "EF81" smd circle
			(at 29.2862 22.375114 270)
			(size 0.4318 0.4318)
			(layers "F.Cu" "F.Mask" "F.Paste")
			(net "GND")
		)
		(pad "EF83" smd circle
			(at 30.914086 22.375114 270)
			(size 0.4318 0.4318)
			(layers "F.Cu" "F.Mask" "F.Paste")
			(net "GND")
		)
		(pad "EF85" smd circle
			(at 32.541718 22.375114 270)
			(size 0.4318 0.4318)
			(layers "F.Cu" "F.Mask" "F.Paste")
			(net "GND")
		)
		(pad "EF87" smd circle
			(at 34.169604 22.375114 270)
			(size 0.4318 0.4318)
			(layers "F.Cu" "F.Mask" "F.Paste")
			(net "GND")
		)
		(pad "EF89" smd circle
			(at 35.797236 22.375114 270)
			(size 0.4318 0.4318)
			(layers "F.Cu" "F.Mask" "F.Paste")
			(net "GND")
		)
		(pad "EG3" smd circle
			(at -35.797236 22.735286 270)
			(size 0.4318 0.4318)
			(layers "F.Cu" "F.Mask" "F.Paste")
			(net "UPI_CPU0_CPU1_P0P1_DP<1>")
		)
		(pad "EG5" smd circle
			(at -34.169604 22.735286 270)
			(size 0.4318 0.4318)
			(layers "F.Cu" "F.Mask" "F.Paste")
			(net "GND")
		)
		(pad "EG7" smd circle
			(at -32.541718 22.735286 270)
			(size 0.4318 0.4318)
			(layers "F.Cu" "F.Mask" "F.Paste")
			(net "GND")
		)
		(pad "EG9" smd circle
			(at -30.914086 22.735286 270)
			(size 0.4318 0.4318)
			(layers "F.Cu" "F.Mask" "F.Paste")
			(net "GND")
		)
		(pad "EG11" smd circle
			(at -29.2862 22.735286 270)
			(size 0.4318 0.4318)
			(layers "F.Cu" "F.Mask" "F.Paste")
			(net "P5E_CPU1_PE2_RX_DP<15>")
		)
		(pad "EG13" smd circle
			(at -27.658314 22.735286 270)
			(size 0.4318 0.4318)
			(layers "F.Cu" "F.Mask" "F.Paste")
			(net "GND")
		)
		(pad "EG15" smd circle
			(at -26.030682 22.735286 270)
			(size 0.4318 0.4318)
			(layers "F.Cu" "F.Mask" "F.Paste")
			(net "P5E_CPU1_PE2_TX_DP<15>")
		)
		(pad "EG17" smd circle
			(at -24.402796 22.735286 270)
			(size 0.4318 0.4318)
			(layers "F.Cu" "F.Mask" "F.Paste")
			(net "NC_CPU1_HBM0_VIEWDIG1")
		)
		(pad "EG19" smd circle
			(at -22.77491 22.735286 270)
			(size 0.4318 0.4318)
			(layers "F.Cu" "F.Mask" "F.Paste")
			(net "M_F_CPU1_SB_DQ<15>")
		)
		(pad "EG21" smd circle
			(at -21.147278 22.735286 270)
			(size 0.4318 0.4318)
			(layers "F.Cu" "F.Mask" "F.Paste")
			(net "M_F_CPU1_SB_DQS_DP<6>")
		)
		(pad "EG23" smd circle
			(at -19.519392 22.735286 270)
			(size 0.4318 0.4318)
			(layers "F.Cu" "F.Mask" "F.Paste")
			(net "M_F_CPU1_SB_DQ<10>")
		)
		(pad "EG25" smd circle
			(at -17.89176 22.735286 270)
			(size 0.4318 0.4318)
			(layers "F.Cu" "F.Mask" "F.Paste")
			(net "M_E_CPU1_SB_DQ<7>")
		)
		(pad "EG27" smd circle
			(at -16.263874 22.735286 270)
			(size 0.4318 0.4318)
			(layers "F.Cu" "F.Mask" "F.Paste")
			(net "M_E_CPU1_SB_DQS_DP<5>")
		)
		(pad "EG29" smd circle
			(at -14.635988 22.735286 270)
			(size 0.4318 0.4318)
			(layers "F.Cu" "F.Mask" "F.Paste")
			(net "M_E_CPU1_SB_DQ<2>")
		)
		(pad "EG31" smd circle
			(at -13.008356 22.735286 270)
			(size 0.4318 0.4318)
			(layers "F.Cu" "F.Mask" "F.Paste")
			(net "M_F_CPU1_SB_CB<3>")
		)
		(pad "EG33" smd circle
			(at -11.380724 22.735286 270)
			(size 0.4318 0.4318)
			(layers "F.Cu" "F.Mask" "F.Paste")
			(net "M_F_CPU1_SB_DQS_DP<4>")
		)
		(pad "EG35" smd circle
			(at -9.752838 22.735286 270)
			(size 0.4318 0.4318)
			(layers "F.Cu" "F.Mask" "F.Paste")
			(net "M_F_CPU1_SB_CB<6>")
		)
		(pad "EG37" smd circle
			(at -8.124952 22.735286 270)
			(size 0.4318 0.4318)
			(layers "F.Cu" "F.Mask" "F.Paste")
			(net "M_F_CPU1_SB_CS_N<1>")
		)
		(pad "EG39" smd circle
			(at -6.49732 22.735286 270)
			(size 0.4318 0.4318)
			(layers "F.Cu" "F.Mask" "F.Paste")
			(net "GND")
		)
		(pad "EG41" smd circle
			(at -4.869434 22.735286 270)
			(size 0.4318 0.4318)
			(layers "F.Cu" "F.Mask" "F.Paste")
			(net "M_F_CPU1_SB_CA<3>")
		)
		(pad "EG43" smd circle
			(at -3.241802 22.735286 270)
			(size 0.4318 0.4318)
			(layers "F.Cu" "F.Mask" "F.Paste")
			(net "M_E_CPU1_SB_CA<0>")
		)
		(pad "EG45" smd circle
			(at -1.613916 22.735286 270)
			(size 0.4318 0.4318)
			(layers "F.Cu" "F.Mask" "F.Paste")
			(net "M_E_CPU1_CLK_DP<0>")
		)
		(pad "EG48" smd circle
			(at 2.427732 22.845268 270)
			(size 0.4318 0.4318)
			(layers "F.Cu" "F.Mask" "F.Paste")
			(net "M_H_CPU1_SA_RSP<0>")
		)
		(pad "EG50" smd circle
			(at 4.055618 22.845268 270)
			(size 0.4318 0.4318)
			(layers "F.Cu" "F.Mask" "F.Paste")
			(net "M_F_CPU1_SA_CA<5>")
		)
		(pad "EG52" smd circle
			(at 5.68325 22.845268 270)
			(size 0.4318 0.4318)
			(layers "F.Cu" "F.Mask" "F.Paste")
			(net "GND")
		)
		(pad "EG54" smd circle
			(at 7.311136 22.845268 270)
			(size 0.4318 0.4318)
			(layers "F.Cu" "F.Mask" "F.Paste")
			(net "M_F_CPU1_SA_CS_N<0>")
		)
		(pad "EG56" smd circle
			(at 8.939022 22.845268 270)
			(size 0.4318 0.4318)
			(layers "F.Cu" "F.Mask" "F.Paste")
			(net "M_F_CPU1_SA_CB<7>")
		)
		(pad "EG58" smd circle
			(at 10.566654 22.845268 270)
			(size 0.4318 0.4318)
			(layers "F.Cu" "F.Mask" "F.Paste")
			(net "M_F_CPU1_SA_DQS_DP<9>")
		)
		(pad "EG60" smd circle
			(at 12.19454 22.845268 270)
			(size 0.4318 0.4318)
			(layers "F.Cu" "F.Mask" "F.Paste")
			(net "M_F_CPU1_SA_CB<2>")
		)
		(pad "EG62" smd circle
			(at 13.822426 22.845268 270)
			(size 0.4318 0.4318)
			(layers "F.Cu" "F.Mask" "F.Paste")
			(net "M_F_CPU1_SA_DQ<23>")
		)
		(pad "EG64" smd circle
			(at 15.450058 22.845268 270)
			(size 0.4318 0.4318)
			(layers "F.Cu" "F.Mask" "F.Paste")
			(net "M_F_CPU1_SA_DQS_DP<7>")
		)
		(pad "EG66" smd circle
			(at 17.07769 22.845268 270)
			(size 0.4318 0.4318)
			(layers "F.Cu" "F.Mask" "F.Paste")
			(net "M_F_CPU1_SA_DQ<18>")
		)
		(pad "EG68" smd circle
			(at 18.705576 22.845268 270)
			(size 0.4318 0.4318)
			(layers "F.Cu" "F.Mask" "F.Paste")
			(net "M_E_CPU1_SA_DQ<15>")
		)
		(pad "EG70" smd circle
			(at 20.333462 22.845268 270)
			(size 0.4318 0.4318)
			(layers "F.Cu" "F.Mask" "F.Paste")
			(net "M_E_CPU1_SA_DQS_DP<6>")
		)
		(pad "EG72" smd circle
			(at 21.961094 22.845268 270)
			(size 0.4318 0.4318)
			(layers "F.Cu" "F.Mask" "F.Paste")
			(net "M_E_CPU1_SA_DQ<10>")
		)
		(pad "EG74" smd circle
			(at 23.58898 22.845268 270)
			(size 0.4318 0.4318)
			(layers "F.Cu" "F.Mask" "F.Paste")
			(net "M_F_CPU1_SA_DQ<7>")
		)
		(pad "EG76" smd circle
			(at 25.216612 22.845268 270)
			(size 0.4318 0.4318)
			(layers "F.Cu" "F.Mask" "F.Paste")
			(net "M_F_CPU1_SA_DQS_DP<5>")
		)
		(pad "EG78" smd circle
			(at 26.844498 22.845268 270)
			(size 0.4318 0.4318)
			(layers "F.Cu" "F.Mask" "F.Paste")
			(net "M_F_CPU1_SA_DQ<3>")
		)
		(pad "EG80" smd circle
			(at 28.472384 22.845268 270)
			(size 0.4318 0.4318)
			(layers "F.Cu" "F.Mask" "F.Paste")
			(net "PVCCFA_EHV_FIVRA_CPU1")
		)
		(pad "EG82" smd circle
			(at 30.100016 22.845268 270)
			(size 0.4318 0.4318)
			(layers "F.Cu" "F.Mask" "F.Paste")
			(net "GND")
		)
		(pad "EG84" smd circle
			(at 31.727902 22.845268 270)
			(size 0.4318 0.4318)
			(layers "F.Cu" "F.Mask" "F.Paste")
			(net "GND")
		)
		(pad "EG86" smd circle
			(at 33.355534 22.845268 270)
			(size 0.4318 0.4318)
			(layers "F.Cu" "F.Mask" "F.Paste")
			(net "GND")
		)
		(pad "EG88" smd circle
			(at 34.98342 22.845268 270)
			(size 0.4318 0.4318)
			(layers "F.Cu" "F.Mask" "F.Paste")
			(net "GND")
		)
		(pad "EG90" smd oval
			(at 36.611306 22.845268 315)
			(size 0.381 0.4826)
			(drill
				(offset 0 -0.0508)
			)
			(layers "F.Cu" "F.Mask" "F.Paste")
			(net "GND")
		)
		(pad "EH2" smd oval
			(at -36.611306 23.204932 225)
			(size 0.381 0.4826)
			(drill
				(offset 0 -0.0508)
			)
			(layers "F.Cu" "F.Mask" "F.Paste")
			(net "UPI_CPU0_CPU1_P0P1_DN<0>")
		)
		(pad "EH4" smd circle
			(at -34.98342 23.204932 270)
			(size 0.4318 0.4318)
			(layers "F.Cu" "F.Mask" "F.Paste")
			(net "GND")
		)
		(pad "EH6" smd circle
			(at -33.355534 23.204932 270)
			(size 0.4318 0.4318)
			(layers "F.Cu" "F.Mask" "F.Paste")
			(net "GND")
		)
		(pad "EH8" smd circle
			(at -31.727902 23.204932 270)
			(size 0.4318 0.4318)
			(layers "F.Cu" "F.Mask" "F.Paste")
			(net "M_G_CPU1_SB_DQ<25>")
		)
		(pad "EH10" smd circle
			(at -30.100016 23.204932 270)
			(size 0.4318 0.4318)
			(layers "F.Cu" "F.Mask" "F.Paste")
			(net "P5E_CPU1_PE2_RX_DN<15>")
		)
		(pad "EH12" smd circle
			(at -28.472384 23.204932 270)
			(size 0.4318 0.4318)
			(layers "F.Cu" "F.Mask" "F.Paste")
			(net "GND")
		)
		(pad "EH14" smd circle
			(at -26.844498 23.204932 270)
			(size 0.4318 0.4318)
			(layers "F.Cu" "F.Mask" "F.Paste")
			(net "GND")
		)
		(pad "EH16" smd circle
			(at -25.216612 23.204932 270)
			(size 0.4318 0.4318)
			(layers "F.Cu" "F.Mask" "F.Paste")
			(net "GND")
		)
		(pad "EH18" smd circle
			(at -23.58898 23.204932 270)
			(size 0.4318 0.4318)
			(layers "F.Cu" "F.Mask" "F.Paste")
			(net "GND")
		)
		(pad "EH20" smd circle
			(at -21.961094 23.204932 270)
			(size 0.4318 0.4318)
			(layers "F.Cu" "F.Mask" "F.Paste")
			(net "M_F_CPU1_SB_DQ<14>")
		)
		(pad "EH22" smd circle
			(at -20.333462 23.204932 270)
			(size 0.4318 0.4318)
			(layers "F.Cu" "F.Mask" "F.Paste")
			(net "M_F_CPU1_SB_DQ<11>")
		)
		(pad "EH24" smd circle
			(at -18.705576 23.204932 270)
			(size 0.4318 0.4318)
			(layers "F.Cu" "F.Mask" "F.Paste")
			(net "GND")
		)
		(pad "EH26" smd circle
			(at -17.07769 23.204932 270)
			(size 0.4318 0.4318)
			(layers "F.Cu" "F.Mask" "F.Paste")
			(net "M_E_CPU1_SB_DQ<6>")
		)
		(pad "EH28" smd circle
			(at -15.450058 23.204932 270)
			(size 0.4318 0.4318)
			(layers "F.Cu" "F.Mask" "F.Paste")
			(net "M_E_CPU1_SB_DQ<3>")
		)
		(pad "EH30" smd circle
			(at -13.822426 23.204932 270)
			(size 0.4318 0.4318)
			(layers "F.Cu" "F.Mask" "F.Paste")
			(net "GND")
		)
		(pad "EH32" smd circle
			(at -12.19454 23.204932 270)
			(size 0.4318 0.4318)
			(layers "F.Cu" "F.Mask" "F.Paste")
			(net "M_F_CPU1_SB_CB<2>")
		)
		(pad "EH34" smd circle
			(at -10.566654 23.204932 270)
			(size 0.4318 0.4318)
			(layers "F.Cu" "F.Mask" "F.Paste")
			(net "M_F_CPU1_SB_CB<7>")
		)
		(pad "EH36" smd circle
			(at -8.939022 23.204932 270)
			(size 0.4318 0.4318)
			(layers "F.Cu" "F.Mask" "F.Paste")
			(net "GND")
		)
		(pad "EH38" smd circle
			(at -7.311136 23.204932 270)
			(size 0.4318 0.4318)
			(layers "F.Cu" "F.Mask" "F.Paste")
			(net "M_F_CPU1_SB_CS_N<0>")
		)
		(pad "EH40" smd circle
			(at -5.68325 23.204932 270)
			(size 0.4318 0.4318)
			(layers "F.Cu" "F.Mask" "F.Paste")
			(net "M_F_CPU1_SB_CA<5>")
		)
		(pad "EH42" smd circle
			(at -4.055618 23.204932 270)
			(size 0.4318 0.4318)
			(layers "F.Cu" "F.Mask" "F.Paste")
			(net "GND")
		)
		(pad "EH44" smd circle
			(at -2.427732 23.204932 270)
			(size 0.4318 0.4318)
			(layers "F.Cu" "F.Mask" "F.Paste")
			(net "M_E_CPU1_SB_CA<1>")
		)
		(pad "EH47" smd circle
			(at 1.613916 23.314914 270)
			(size 0.4318 0.4318)
			(layers "F.Cu" "F.Mask" "F.Paste")
			(net "M_H_CPU1_SA_RSP<1>")
		)
		(pad "EH49" smd circle
			(at 3.241802 23.314914 270)
			(size 0.4318 0.4318)
			(layers "F.Cu" "F.Mask" "F.Paste")
			(net "GND")
		)
		(pad "EH51" smd circle
			(at 4.869434 23.314914 270)
			(size 0.4318 0.4318)
			(layers "F.Cu" "F.Mask" "F.Paste")
			(net "M_F_CPU1_SA_CA<3>")
		)
		(pad "EH53" smd circle
			(at 6.49732 23.314914 270)
			(size 0.4318 0.4318)
			(layers "F.Cu" "F.Mask" "F.Paste")
			(net "M_F_CPU1_SA_CS_N<1>")
		)
		(pad "EH55" smd circle
			(at 8.124952 23.314914 270)
			(size 0.4318 0.4318)
			(layers "F.Cu" "F.Mask" "F.Paste")
			(net "GND")
		)
		(pad "EH57" smd circle
			(at 9.752838 23.314914 270)
			(size 0.4318 0.4318)
			(layers "F.Cu" "F.Mask" "F.Paste")
			(net "M_F_CPU1_SA_CB<6>")
		)
		(pad "EH59" smd circle
			(at 11.380724 23.314914 270)
			(size 0.4318 0.4318)
			(layers "F.Cu" "F.Mask" "F.Paste")
			(net "M_F_CPU1_SA_CB<3>")
		)
		(pad "EH61" smd circle
			(at 13.008356 23.314914 270)
			(size 0.4318 0.4318)
			(layers "F.Cu" "F.Mask" "F.Paste")
			(net "GND")
		)
		(pad "EH63" smd circle
			(at 14.635988 23.314914 270)
			(size 0.4318 0.4318)
			(layers "F.Cu" "F.Mask" "F.Paste")
			(net "M_F_CPU1_SA_DQ<22>")
		)
		(pad "EH65" smd circle
			(at 16.263874 23.314914 270)
			(size 0.4318 0.4318)
			(layers "F.Cu" "F.Mask" "F.Paste")
			(net "M_F_CPU1_SA_DQ<19>")
		)
		(pad "EH67" smd circle
			(at 17.89176 23.314914 270)
			(size 0.4318 0.4318)
			(layers "F.Cu" "F.Mask" "F.Paste")
			(net "GND")
		)
		(pad "EH69" smd circle
			(at 19.519392 23.314914 270)
			(size 0.4318 0.4318)
			(layers "F.Cu" "F.Mask" "F.Paste")
			(net "M_E_CPU1_SA_DQ<14>")
		)
		(pad "EH71" smd circle
			(at 21.147278 23.314914 270)
			(size 0.4318 0.4318)
			(layers "F.Cu" "F.Mask" "F.Paste")
			(net "M_E_CPU1_SA_DQ<11>")
		)
		(pad "EH73" smd circle
			(at 22.77491 23.314914 270)
			(size 0.4318 0.4318)
			(layers "F.Cu" "F.Mask" "F.Paste")
			(net "GND")
		)
		(pad "EH75" smd circle
			(at 24.402796 23.314914 270)
			(size 0.4318 0.4318)
			(layers "F.Cu" "F.Mask" "F.Paste")
			(net "M_F_CPU1_SA_DQ<6>")
		)
		(pad "EH77" smd circle
			(at 26.030682 23.314914 270)
			(size 0.4318 0.4318)
			(layers "F.Cu" "F.Mask" "F.Paste")
			(net "M_F_CPU1_SA_DQ<1>")
		)
		(pad "EH79" smd circle
			(at 27.658314 23.314914 270)
			(size 0.4318 0.4318)
			(layers "F.Cu" "F.Mask" "F.Paste")
			(net "GND")
		)
		(pad "EH81" smd circle
			(at 29.2862 23.314914 270)
			(size 0.4318 0.4318)
			(layers "F.Cu" "F.Mask" "F.Paste")
			(net "GND")
		)
		(pad "EH83" smd circle
			(at 30.914086 23.314914 270)
			(size 0.4318 0.4318)
			(layers "F.Cu" "F.Mask" "F.Paste")
			(net "GND")
		)
		(pad "EH85" smd circle
			(at 32.541718 23.314914 270)
			(size 0.4318 0.4318)
			(layers "F.Cu" "F.Mask" "F.Paste")
			(net "Net_749")
		)
		(pad "EH87" smd circle
			(at 34.169604 23.314914 270)
			(size 0.4318 0.4318)
			(layers "F.Cu" "F.Mask" "F.Paste")
			(net "Net_707")
		)
		(pad "EH89" smd oval
			(at 35.797236 23.314914 315)
			(size 0.381 0.4826)
			(drill
				(offset 0 -0.0508)
			)
			(layers "F.Cu" "F.Mask" "F.Paste")
			(net "P5E_CPU1_PE3_RX_DN<0>")
		)
		(pad "EJ3" smd oval
			(at -35.797236 23.675086 225)
			(size 0.381 0.4826)
			(drill
				(offset 0 -0.0508)
			)
			(layers "F.Cu" "F.Mask" "F.Paste")
			(net "UPI_CPU0_CPU1_P0P1_DP<0>")
		)
		(pad "EJ5" smd circle
			(at -34.169604 23.675086 270)
			(size 0.4318 0.4318)
			(layers "F.Cu" "F.Mask" "F.Paste")
			(net "M_G_CPU1_SB_DQ<29>")
		)
		(pad "EJ7" smd circle
			(at -32.541718 23.675086 270)
			(size 0.4318 0.4318)
			(layers "F.Cu" "F.Mask" "F.Paste")
			(net "GND")
		)
		(pad "EJ9" smd circle
			(at -30.914086 23.675086 270)
			(size 0.4318 0.4318)
			(layers "F.Cu" "F.Mask" "F.Paste")
			(net "GND")
		)
		(pad "EJ11" smd circle
			(at -29.2862 23.675086 270)
			(size 0.4318 0.4318)
			(layers "F.Cu" "F.Mask" "F.Paste")
			(net "GND")
		)
		(pad "EJ13" smd circle
			(at -27.658314 23.675086 270)
			(size 0.4318 0.4318)
			(layers "F.Cu" "F.Mask" "F.Paste")
			(net "GND")
		)
		(pad "EJ15" smd circle
			(at -26.030682 23.675086 270)
			(size 0.4318 0.4318)
			(layers "F.Cu" "F.Mask" "F.Paste")
			(net "PVCCFA_EHV_FIVRA_CPU1")
		)
		(pad "EJ17" smd circle
			(at -24.402796 23.675086 270)
			(size 0.4318 0.4318)
			(layers "F.Cu" "F.Mask" "F.Paste")
			(net "GND")
		)
		(pad "EJ19" smd circle
			(at -22.77491 23.675086 270)
			(size 0.4318 0.4318)
			(layers "F.Cu" "F.Mask" "F.Paste")
			(net "GND")
		)
		(pad "EJ21" smd circle
			(at -21.147278 23.675086 270)
			(size 0.4318 0.4318)
			(layers "F.Cu" "F.Mask" "F.Paste")
			(net "M_F_CPU1_SB_DQS_DN<6>")
		)
		(pad "EJ23" smd circle
			(at -19.519392 23.675086 270)
			(size 0.4318 0.4318)
			(layers "F.Cu" "F.Mask" "F.Paste")
			(net "GND")
		)
		(pad "EJ25" smd circle
			(at -17.89176 23.675086 270)
			(size 0.4318 0.4318)
			(layers "F.Cu" "F.Mask" "F.Paste")
			(net "GND")
		)
		(pad "EJ27" smd circle
			(at -16.263874 23.675086 270)
			(size 0.4318 0.4318)
			(layers "F.Cu" "F.Mask" "F.Paste")
			(net "M_E_CPU1_SB_DQS_DN<5>")
		)
		(pad "EJ29" smd circle
			(at -14.635988 23.675086 270)
			(size 0.4318 0.4318)
			(layers "F.Cu" "F.Mask" "F.Paste")
			(net "GND")
		)
		(pad "EJ31" smd circle
			(at -13.008356 23.675086 270)
			(size 0.4318 0.4318)
			(layers "F.Cu" "F.Mask" "F.Paste")
			(net "GND")
		)
		(pad "EJ33" smd circle
			(at -11.380724 23.675086 270)
			(size 0.4318 0.4318)
			(layers "F.Cu" "F.Mask" "F.Paste")
			(net "M_F_CPU1_SB_DQS_DN<4>")
		)
		(pad "EJ35" smd circle
			(at -9.752838 23.675086 270)
			(size 0.4318 0.4318)
			(layers "F.Cu" "F.Mask" "F.Paste")
			(net "GND")
		)
		(pad "EJ37" smd circle
			(at -8.124952 23.675086 270)
			(size 0.4318 0.4318)
			(layers "F.Cu" "F.Mask" "F.Paste")
			(net "GND")
		)
		(pad "EJ39" smd circle
			(at -6.49732 23.675086 270)
			(size 0.4318 0.4318)
			(layers "F.Cu" "F.Mask" "F.Paste")
			(net "M_F_CPU1_SB_PAR")
		)
		(pad "EJ41" smd circle
			(at -4.869434 23.675086 270)
			(size 0.4318 0.4318)
			(layers "F.Cu" "F.Mask" "F.Paste")
			(net "GND")
		)
		(pad "EJ43" smd circle
			(at -3.241802 23.675086 270)
			(size 0.4318 0.4318)
			(layers "F.Cu" "F.Mask" "F.Paste")
			(net "GND")
		)
		(pad "EJ45" smd circle
			(at -1.613916 23.675086 270)
			(size 0.4318 0.4318)
			(layers "F.Cu" "F.Mask" "F.Paste")
			(net "M_E_CPU1_CLK_DN<0>")
		)
		(pad "EJ48" smd circle
			(at 2.427732 23.784814 270)
			(size 0.4318 0.4318)
			(layers "F.Cu" "F.Mask" "F.Paste")
			(net "GND")
		)
		(pad "EJ50" smd circle
			(at 4.055618 23.784814 270)
			(size 0.4318 0.4318)
			(layers "F.Cu" "F.Mask" "F.Paste")
			(net "GND")
		)
		(pad "EJ52" smd circle
			(at 5.68325 23.784814 270)
			(size 0.4318 0.4318)
			(layers "F.Cu" "F.Mask" "F.Paste")
			(net "M_F_CPU1_SA_CA<1>")
		)
		(pad "EJ54" smd circle
			(at 7.311136 23.784814 270)
			(size 0.4318 0.4318)
			(layers "F.Cu" "F.Mask" "F.Paste")
			(net "GND")
		)
		(pad "EJ56" smd circle
			(at 8.939022 23.784814 270)
			(size 0.4318 0.4318)
			(layers "F.Cu" "F.Mask" "F.Paste")
			(net "GND")
		)
		(pad "EJ58" smd circle
			(at 10.566654 23.784814 270)
			(size 0.4318 0.4318)
			(layers "F.Cu" "F.Mask" "F.Paste")
			(net "M_F_CPU1_SA_DQS_DN<9>")
		)
		(pad "EJ60" smd circle
			(at 12.19454 23.784814 270)
			(size 0.4318 0.4318)
			(layers "F.Cu" "F.Mask" "F.Paste")
			(net "GND")
		)
		(pad "EJ62" smd circle
			(at 13.822426 23.784814 270)
			(size 0.4318 0.4318)
			(layers "F.Cu" "F.Mask" "F.Paste")
			(net "GND")
		)
		(pad "EJ64" smd circle
			(at 15.450058 23.784814 270)
			(size 0.4318 0.4318)
			(layers "F.Cu" "F.Mask" "F.Paste")
			(net "M_F_CPU1_SA_DQS_DN<7>")
		)
		(pad "EJ66" smd circle
			(at 17.07769 23.784814 270)
			(size 0.4318 0.4318)
			(layers "F.Cu" "F.Mask" "F.Paste")
			(net "GND")
		)
		(pad "EJ68" smd circle
			(at 18.705576 23.784814 270)
			(size 0.4318 0.4318)
			(layers "F.Cu" "F.Mask" "F.Paste")
			(net "GND")
		)
		(pad "EJ70" smd circle
			(at 20.333462 23.784814 270)
			(size 0.4318 0.4318)
			(layers "F.Cu" "F.Mask" "F.Paste")
			(net "M_E_CPU1_SA_DQS_DN<6>")
		)
		(pad "EJ72" smd circle
			(at 21.961094 23.784814 270)
			(size 0.4318 0.4318)
			(layers "F.Cu" "F.Mask" "F.Paste")
			(net "GND")
		)
		(pad "EJ74" smd circle
			(at 23.58898 23.784814 270)
			(size 0.4318 0.4318)
			(layers "F.Cu" "F.Mask" "F.Paste")
			(net "GND")
		)
		(pad "EJ76" smd circle
			(at 25.216612 23.784814 270)
			(size 0.4318 0.4318)
			(layers "F.Cu" "F.Mask" "F.Paste")
			(net "M_F_CPU1_SA_DQS_DN<5>")
		)
		(pad "EJ78" smd circle
			(at 26.844498 23.784814 270)
			(size 0.4318 0.4318)
			(layers "F.Cu" "F.Mask" "F.Paste")
			(net "GND")
		)
		(pad "EJ80" smd circle
			(at 28.472384 23.784814 270)
			(size 0.4318 0.4318)
			(layers "F.Cu" "F.Mask" "F.Paste")
			(net "GND")
		)
		(pad "EJ82" smd circle
			(at 30.100016 23.784814 270)
			(size 0.4318 0.4318)
			(layers "F.Cu" "F.Mask" "F.Paste")
			(net "GND")
		)
		(pad "EJ84" smd circle
			(at 31.727902 23.784814 270)
			(size 0.4318 0.4318)
			(layers "F.Cu" "F.Mask" "F.Paste")
			(net "PVCCFA_EHV_FIVRA_CPU1")
		)
		(pad "EJ86" smd circle
			(at 33.355534 23.784814 270)
			(size 0.4318 0.4318)
			(layers "F.Cu" "F.Mask" "F.Paste")
			(net "Net_731")
		)
		(pad "EJ88" smd oval
			(at 34.98342 23.784814 315)
			(size 0.381 0.4826)
			(drill
				(offset 0 -0.0508)
			)
			(layers "F.Cu" "F.Mask" "F.Paste")
			(net "GND")
		)
		(pad "EJ90" smd oval
			(at 36.611306 23.784814 315)
			(size 0.381 0.4826)
			(drill
				(offset 0 -0.0508)
			)
			(layers "F.Cu" "F.Mask" "F.Paste")
			(net "P5E_CPU1_PE3_RX_DP<0>")
		)
		(pad "EK2" smd oval
			(at -36.611306 24.144986 225)
			(size 0.381 0.4826)
			(drill
				(offset 0 -0.0508)
			)
			(layers "F.Cu" "F.Mask" "F.Paste")
			(net "GND")
		)
		(pad "EK4" smd oval
			(at -34.98342 24.144986 225)
			(size 0.381 0.4826)
			(drill
				(offset 0 -0.0508)
			)
			(layers "F.Cu" "F.Mask" "F.Paste")
			(net "GND")
		)
		(pad "EK6" smd circle
			(at -33.355534 24.144986 270)
			(size 0.4318 0.4318)
			(layers "F.Cu" "F.Mask" "F.Paste")
			(net "M_G_CPU1_SB_DQ<28>")
		)
		(pad "EK8" smd circle
			(at -31.727902 24.144986 270)
			(size 0.4318 0.4318)
			(layers "F.Cu" "F.Mask" "F.Paste")
			(net "M_G_CPU1_SB_DQ<24>")
		)
		(pad "EK10" smd circle
			(at -30.100016 24.144986 270)
			(size 0.4318 0.4318)
			(layers "F.Cu" "F.Mask" "F.Paste")
			(net "GND")
		)
		(pad "EK12" smd circle
			(at -28.472384 24.144986 270)
			(size 0.4318 0.4318)
			(layers "F.Cu" "F.Mask" "F.Paste")
			(net "M_F_CPU1_SB_DQS_DP<2>")
		)
		(pad "EK14" smd circle
			(at -26.844498 24.144986 270)
			(size 0.4318 0.4318)
			(layers "F.Cu" "F.Mask" "F.Paste")
			(net "GND")
		)
		(pad "EK16" smd circle
			(at -25.216612 24.144986 270)
			(size 0.4318 0.4318)
			(layers "F.Cu" "F.Mask" "F.Paste")
			(net "GND")
		)
		(pad "EK18" smd circle
			(at -23.58898 24.144986 270)
			(size 0.4318 0.4318)
			(layers "F.Cu" "F.Mask" "F.Paste")
			(net "M_E_CPU1_SB_DQS_DN<3>")
		)
		(pad "EK20" smd circle
			(at -21.961094 24.144986 270)
			(size 0.4318 0.4318)
			(layers "F.Cu" "F.Mask" "F.Paste")
			(net "GND")
		)
		(pad "EK22" smd circle
			(at -20.333462 24.144986 270)
			(size 0.4318 0.4318)
			(layers "F.Cu" "F.Mask" "F.Paste")
			(net "GND")
		)
		(pad "EK24" smd circle
			(at -18.705576 24.144986 270)
			(size 0.4318 0.4318)
			(layers "F.Cu" "F.Mask" "F.Paste")
			(net "M_E_CPU1_SB_DQS_DN<2>")
		)
		(pad "EK26" smd circle
			(at -17.07769 24.144986 270)
			(size 0.4318 0.4318)
			(layers "F.Cu" "F.Mask" "F.Paste")
			(net "GND")
		)
		(pad "EK28" smd circle
			(at -15.450058 24.144986 270)
			(size 0.4318 0.4318)
			(layers "F.Cu" "F.Mask" "F.Paste")
			(net "GND")
		)
		(pad "EK30" smd circle
			(at -13.822426 24.144986 270)
			(size 0.4318 0.4318)
			(layers "F.Cu" "F.Mask" "F.Paste")
			(net "M_E_CPU1_SB_DQS_DN<1>")
		)
		(pad "EK32" smd circle
			(at -12.19454 24.144986 270)
			(size 0.4318 0.4318)
			(layers "F.Cu" "F.Mask" "F.Paste")
			(net "GND")
		)
		(pad "EK34" smd circle
			(at -10.566654 24.144986 270)
			(size 0.4318 0.4318)
			(layers "F.Cu" "F.Mask" "F.Paste")
			(net "GND")
		)
		(pad "EK36" smd circle
			(at -8.939022 24.144986 270)
			(size 0.4318 0.4318)
			(layers "F.Cu" "F.Mask" "F.Paste")
			(net "M_E_CPU1_SB_DQS_DN<9>")
		)
		(pad "EK38" smd circle
			(at -7.311136 24.144986 270)
			(size 0.4318 0.4318)
			(layers "F.Cu" "F.Mask" "F.Paste")
			(net "GND")
		)
		(pad "EK40" smd circle
			(at -5.68325 24.144986 270)
			(size 0.4318 0.4318)
			(layers "F.Cu" "F.Mask" "F.Paste")
			(net "GND")
		)
		(pad "EK42" smd circle
			(at -4.055618 24.144986 270)
			(size 0.4318 0.4318)
			(layers "F.Cu" "F.Mask" "F.Paste")
			(net "M_E_CPU1_SB_CA<6>")
		)
		(pad "EK44" smd circle
			(at -2.427732 24.144986 270)
			(size 0.4318 0.4318)
			(layers "F.Cu" "F.Mask" "F.Paste")
			(net "GND")
		)
		(pad "EK47" smd circle
			(at 1.613916 24.254714 270)
			(size 0.4318 0.4318)
			(layers "F.Cu" "F.Mask" "F.Paste")
			(net "GND")
		)
		(pad "EK49" smd circle
			(at 3.241802 24.254714 270)
			(size 0.4318 0.4318)
			(layers "F.Cu" "F.Mask" "F.Paste")
			(net "M_E_CPU1_SA_CA<2>")
		)
		(pad "EK51" smd circle
			(at 4.869434 24.254714 270)
			(size 0.4318 0.4318)
			(layers "F.Cu" "F.Mask" "F.Paste")
			(net "GND")
		)
		(pad "EK53" smd circle
			(at 6.49732 24.254714 270)
			(size 0.4318 0.4318)
			(layers "F.Cu" "F.Mask" "F.Paste")
			(net "GND")
		)
		(pad "EK55" smd circle
			(at 8.124952 24.254714 270)
			(size 0.4318 0.4318)
			(layers "F.Cu" "F.Mask" "F.Paste")
			(net "M_E_CPU1_SA_DQS_DP<4>")
		)
		(pad "EK57" smd circle
			(at 9.752838 24.254714 270)
			(size 0.4318 0.4318)
			(layers "F.Cu" "F.Mask" "F.Paste")
			(net "GND")
		)
		(pad "EK59" smd circle
			(at 11.380724 24.254714 270)
			(size 0.4318 0.4318)
			(layers "F.Cu" "F.Mask" "F.Paste")
			(net "GND")
		)
		(pad "EK61" smd circle
			(at 13.008356 24.254714 270)
			(size 0.4318 0.4318)
			(layers "F.Cu" "F.Mask" "F.Paste")
			(net "M_E_CPU1_SA_DQS_DN<3>")
		)
		(pad "EK63" smd circle
			(at 14.635988 24.254714 270)
			(size 0.4318 0.4318)
			(layers "F.Cu" "F.Mask" "F.Paste")
			(net "GND")
		)
		(pad "EK65" smd circle
			(at 16.263874 24.254714 270)
			(size 0.4318 0.4318)
			(layers "F.Cu" "F.Mask" "F.Paste")
			(net "GND")
		)
		(pad "EK67" smd circle
			(at 17.89176 24.254714 270)
			(size 0.4318 0.4318)
			(layers "F.Cu" "F.Mask" "F.Paste")
			(net "M_E_CPU1_SA_DQS_DN<2>")
		)
		(pad "EK69" smd circle
			(at 19.519392 24.254714 270)
			(size 0.4318 0.4318)
			(layers "F.Cu" "F.Mask" "F.Paste")
			(net "GND")
		)
		(pad "EK71" smd circle
			(at 21.147278 24.254714 270)
			(size 0.4318 0.4318)
			(layers "F.Cu" "F.Mask" "F.Paste")
			(net "GND")
		)
		(pad "EK73" smd circle
			(at 22.77491 24.254714 270)
			(size 0.4318 0.4318)
			(layers "F.Cu" "F.Mask" "F.Paste")
			(net "M_E_CPU1_SA_DQ<5>")
		)
		(pad "EK75" smd circle
			(at 24.402796 24.254714 270)
			(size 0.4318 0.4318)
			(layers "F.Cu" "F.Mask" "F.Paste")
			(net "GND")
		)
		(pad "EK77" smd circle
			(at 26.030682 24.254714 270)
			(size 0.4318 0.4318)
			(layers "F.Cu" "F.Mask" "F.Paste")
			(net "GND")
		)
		(pad "EK79" smd circle
			(at 27.658314 24.254714 270)
			(size 0.4318 0.4318)
			(layers "F.Cu" "F.Mask" "F.Paste")
			(net "GND")
		)
		(pad "EK81" smd circle
			(at 29.2862 24.254714 270)
			(size 0.4318 0.4318)
			(layers "F.Cu" "F.Mask" "F.Paste")
			(net "GND")
		)
		(pad "EK83" smd circle
			(at 30.914086 24.254714 270)
			(size 0.4318 0.4318)
			(layers "F.Cu" "F.Mask" "F.Paste")
			(net "GND")
		)
		(pad "EK85" smd circle
			(at 32.541718 24.254714 270)
			(size 0.4318 0.4318)
			(layers "F.Cu" "F.Mask" "F.Paste")
			(net "Net_725")
		)
		(pad "EK87" smd oval
			(at 34.169604 24.254714 315)
			(size 0.381 0.4826)
			(drill
				(offset 0 -0.0508)
			)
			(layers "F.Cu" "F.Mask" "F.Paste")
			(net "Net_730")
		)
		(pad "EK89" smd oval
			(at 35.797236 24.254714 315)
			(size 0.381 0.4826)
			(drill
				(offset 0 -0.0508)
			)
			(layers "F.Cu" "F.Mask" "F.Paste")
			(net "GND")
		)
		(pad "EL3" smd oval
			(at -35.797236 24.614886 225)
			(size 0.381 0.4826)
			(drill
				(offset 0 -0.0508)
			)
			(layers "F.Cu" "F.Mask" "F.Paste")
			(net "GND")
		)
		(pad "EL5" smd oval
			(at -34.169604 24.614886 225)
			(size 0.381 0.4826)
			(drill
				(offset 0 -0.0508)
			)
			(layers "F.Cu" "F.Mask" "F.Paste")
			(net "GND")
		)
		(pad "EL7" smd circle
			(at -32.541718 24.614886 270)
			(size 0.4318 0.4318)
			(layers "F.Cu" "F.Mask" "F.Paste")
			(net "GND")
		)
		(pad "EL9" smd circle
			(at -30.914086 24.614886 270)
			(size 0.4318 0.4318)
			(layers "F.Cu" "F.Mask" "F.Paste")
			(net "GND")
		)
		(pad "EL11" smd circle
			(at -29.2862 24.614886 270)
			(size 0.4318 0.4318)
			(layers "F.Cu" "F.Mask" "F.Paste")
			(net "M_F_CPU1_SB_DQ<20>")
		)
		(pad "EL13" smd circle
			(at -27.658314 24.614886 270)
			(size 0.4318 0.4318)
			(layers "F.Cu" "F.Mask" "F.Paste")
			(net "M_F_CPU1_SB_DQ<17>")
		)
		(pad "EL15" smd circle
			(at -26.030682 24.614886 270)
			(size 0.4318 0.4318)
			(layers "F.Cu" "F.Mask" "F.Paste")
			(net "GND")
		)
		(pad "EL17" smd circle
			(at -24.402796 24.614886 270)
			(size 0.4318 0.4318)
			(layers "F.Cu" "F.Mask" "F.Paste")
			(net "M_E_CPU1_SB_DQ<28>")
		)
		(pad "EL19" smd circle
			(at -22.77491 24.614886 270)
			(size 0.4318 0.4318)
			(layers "F.Cu" "F.Mask" "F.Paste")
			(net "M_E_CPU1_SB_DQ<25>")
		)
		(pad "EL21" smd circle
			(at -21.147278 24.614886 270)
			(size 0.4318 0.4318)
			(layers "F.Cu" "F.Mask" "F.Paste")
			(net "GND")
		)
		(pad "EL23" smd circle
			(at -19.519392 24.614886 270)
			(size 0.4318 0.4318)
			(layers "F.Cu" "F.Mask" "F.Paste")
			(net "M_E_CPU1_SB_DQ<20>")
		)
		(pad "EL25" smd circle
			(at -17.89176 24.614886 270)
			(size 0.4318 0.4318)
			(layers "F.Cu" "F.Mask" "F.Paste")
			(net "M_E_CPU1_SB_DQ<17>")
		)
		(pad "EL27" smd circle
			(at -16.263874 24.614886 270)
			(size 0.4318 0.4318)
			(layers "F.Cu" "F.Mask" "F.Paste")
			(net "GND")
		)
		(pad "EL29" smd circle
			(at -14.635988 24.614886 270)
			(size 0.4318 0.4318)
			(layers "F.Cu" "F.Mask" "F.Paste")
			(net "M_E_CPU1_SB_DQ<12>")
		)
		(pad "EL31" smd circle
			(at -13.008356 24.614886 270)
			(size 0.4318 0.4318)
			(layers "F.Cu" "F.Mask" "F.Paste")
			(net "M_E_CPU1_SB_DQ<9>")
		)
		(pad "EL33" smd circle
			(at -11.380724 24.614886 270)
			(size 0.4318 0.4318)
			(layers "F.Cu" "F.Mask" "F.Paste")
			(net "GND")
		)
		(pad "EL35" smd circle
			(at -9.752838 24.614886 270)
			(size 0.4318 0.4318)
			(layers "F.Cu" "F.Mask" "F.Paste")
			(net "M_E_CPU1_SB_CB<0>")
		)
		(pad "EL37" smd circle
			(at -8.124952 24.614886 270)
			(size 0.4318 0.4318)
			(layers "F.Cu" "F.Mask" "F.Paste")
			(net "M_E_CPU1_SB_CB<5>")
		)
		(pad "EL39" smd circle
			(at -6.49732 24.614886 270)
			(size 0.4318 0.4318)
			(layers "F.Cu" "F.Mask" "F.Paste")
			(net "GND")
		)
		(pad "EL41" smd circle
			(at -4.869434 24.614886 270)
			(size 0.4318 0.4318)
			(layers "F.Cu" "F.Mask" "F.Paste")
			(net "M_E_CPU1_SB_CS_N<3>")
		)
		(pad "EL43" smd circle
			(at -3.241802 24.614886 270)
			(size 0.4318 0.4318)
			(layers "F.Cu" "F.Mask" "F.Paste")
			(net "M_E_CPU1_SB_CA<4>")
		)
		(pad "EL45" smd circle
			(at -1.613916 24.614886 270)
			(size 0.4318 0.4318)
			(layers "F.Cu" "F.Mask" "F.Paste")
			(net "GND")
		)
		(pad "EL48" smd circle
			(at 2.427732 24.724868 270)
			(size 0.4318 0.4318)
			(layers "F.Cu" "F.Mask" "F.Paste")
			(net "M_E_CPU1_SA_CA<3>")
		)
		(pad "EL50" smd circle
			(at 4.055618 24.724868 270)
			(size 0.4318 0.4318)
			(layers "F.Cu" "F.Mask" "F.Paste")
			(net "M_E_CPU1_SA_CS_N<3>")
		)
		(pad "EL52" smd circle
			(at 5.68325 24.724868 270)
			(size 0.4318 0.4318)
			(layers "F.Cu" "F.Mask" "F.Paste")
			(net "GND")
		)
		(pad "EL54" smd circle
			(at 7.311136 24.724868 270)
			(size 0.4318 0.4318)
			(layers "F.Cu" "F.Mask" "F.Paste")
			(net "M_E_CPU1_SA_CB<4>")
		)
		(pad "EL56" smd circle
			(at 8.939022 24.724868 270)
			(size 0.4318 0.4318)
			(layers "F.Cu" "F.Mask" "F.Paste")
			(net "M_E_CPU1_SA_CB<1>")
		)
		(pad "EL58" smd circle
			(at 10.566654 24.724868 270)
			(size 0.4318 0.4318)
			(layers "F.Cu" "F.Mask" "F.Paste")
			(net "GND")
		)
		(pad "EL60" smd circle
			(at 12.19454 24.724868 270)
			(size 0.4318 0.4318)
			(layers "F.Cu" "F.Mask" "F.Paste")
			(net "M_E_CPU1_SA_DQ<28>")
		)
		(pad "EL62" smd circle
			(at 13.822426 24.724868 270)
			(size 0.4318 0.4318)
			(layers "F.Cu" "F.Mask" "F.Paste")
			(net "M_E_CPU1_SA_DQ<25>")
		)
		(pad "EL64" smd circle
			(at 15.450058 24.724868 270)
			(size 0.4318 0.4318)
			(layers "F.Cu" "F.Mask" "F.Paste")
			(net "GND")
		)
		(pad "EL66" smd circle
			(at 17.07769 24.724868 270)
			(size 0.4318 0.4318)
			(layers "F.Cu" "F.Mask" "F.Paste")
			(net "M_E_CPU1_SA_DQ<22>")
		)
		(pad "EL68" smd circle
			(at 18.705576 24.724868 270)
			(size 0.4318 0.4318)
			(layers "F.Cu" "F.Mask" "F.Paste")
			(net "M_E_CPU1_SA_DQS_DP<2>")
		)
		(pad "EL70" smd circle
			(at 20.333462 24.724868 270)
			(size 0.4318 0.4318)
			(layers "F.Cu" "F.Mask" "F.Paste")
			(net "GND")
		)
		(pad "EL72" smd circle
			(at 21.961094 24.724868 270)
			(size 0.4318 0.4318)
			(layers "F.Cu" "F.Mask" "F.Paste")
			(net "GND")
		)
		(pad "EL74" smd circle
			(at 23.58898 24.724868 270)
			(size 0.4318 0.4318)
			(layers "F.Cu" "F.Mask" "F.Paste")
			(net "M_E_CPU1_SA_DQ<4>")
		)
		(pad "EL76" smd circle
			(at 25.216612 24.724868 270)
			(size 0.4318 0.4318)
			(layers "F.Cu" "F.Mask" "F.Paste")
			(net "GND")
		)
		(pad "EL78" smd circle
			(at 26.844498 24.724868 270)
			(size 0.4318 0.4318)
			(layers "F.Cu" "F.Mask" "F.Paste")
			(net "M_E_CPU1_SA_DQ<0>")
		)
		(pad "EL80" smd circle
			(at 28.472384 24.724868 270)
			(size 0.4318 0.4318)
			(layers "F.Cu" "F.Mask" "F.Paste")
			(net "GND")
		)
		(pad "EL82" smd circle
			(at 30.100016 24.724868 270)
			(size 0.4318 0.4318)
			(layers "F.Cu" "F.Mask" "F.Paste")
			(net "GND")
		)
		(pad "EL84" smd circle
			(at 31.727902 24.724868 270)
			(size 0.4318 0.4318)
			(layers "F.Cu" "F.Mask" "F.Paste")
			(net "Net_748")
		)
		(pad "EL86" smd oval
			(at 33.355534 24.724868 315)
			(size 0.381 0.4826)
			(drill
				(offset 0 -0.0508)
			)
			(layers "F.Cu" "F.Mask" "F.Paste")
			(net "GND")
		)
		(pad "EL88" smd oval
			(at 34.98342 24.724868 315)
			(size 0.381 0.4826)
			(drill
				(offset 0 -0.0508)
			)
			(layers "F.Cu" "F.Mask" "F.Paste")
			(net "Net_706")
		)
		(pad "EM4" smd oval
			(at -34.98342 25.084532 225)
			(size 0.381 0.4826)
			(drill
				(offset 0 -0.0508)
			)
			(layers "F.Cu" "F.Mask" "F.Paste")
			(net "M_G_CPU1_SB_DQ<31>")
		)
		(pad "EM6" smd oval
			(at -33.355534 25.084532 225)
			(size 0.381 0.4826)
			(drill
				(offset 0 -0.0508)
			)
			(layers "F.Cu" "F.Mask" "F.Paste")
			(net "M_G_CPU1_SB_DQS_DN<8>")
		)
		(pad "EM8" smd circle
			(at -31.727902 25.084532 270)
			(size 0.4318 0.4318)
			(layers "F.Cu" "F.Mask" "F.Paste")
			(net "GND")
		)
		(pad "EM10" smd circle
			(at -30.100016 25.084532 270)
			(size 0.4318 0.4318)
			(layers "F.Cu" "F.Mask" "F.Paste")
			(net "M_F_CPU1_SB_DQ<21>")
		)
		(pad "EM12" smd circle
			(at -28.472384 25.084532 270)
			(size 0.4318 0.4318)
			(layers "F.Cu" "F.Mask" "F.Paste")
			(net "M_F_CPU1_SB_DQS_DN<2>")
		)
		(pad "EM14" smd circle
			(at -26.844498 25.084532 270)
			(size 0.4318 0.4318)
			(layers "F.Cu" "F.Mask" "F.Paste")
			(net "M_F_CPU1_SB_DQ<16>")
		)
		(pad "EM16" smd circle
			(at -25.216612 25.084532 270)
			(size 0.4318 0.4318)
			(layers "F.Cu" "F.Mask" "F.Paste")
			(net "M_E_CPU1_SB_DQ<29>")
		)
		(pad "EM18" smd circle
			(at -23.58898 25.084532 270)
			(size 0.4318 0.4318)
			(layers "F.Cu" "F.Mask" "F.Paste")
			(net "M_E_CPU1_SB_DQS_DP<3>")
		)
		(pad "EM20" smd circle
			(at -21.961094 25.084532 270)
			(size 0.4318 0.4318)
			(layers "F.Cu" "F.Mask" "F.Paste")
			(net "M_E_CPU1_SB_DQ<24>")
		)
		(pad "EM22" smd circle
			(at -20.333462 25.084532 270)
			(size 0.4318 0.4318)
			(layers "F.Cu" "F.Mask" "F.Paste")
			(net "M_E_CPU1_SB_DQ<21>")
		)
		(pad "EM24" smd circle
			(at -18.705576 25.084532 270)
			(size 0.4318 0.4318)
			(layers "F.Cu" "F.Mask" "F.Paste")
			(net "M_E_CPU1_SB_DQS_DP<2>")
		)
		(pad "EM26" smd circle
			(at -17.07769 25.084532 270)
			(size 0.4318 0.4318)
			(layers "F.Cu" "F.Mask" "F.Paste")
			(net "M_E_CPU1_SB_DQ<16>")
		)
		(pad "EM28" smd circle
			(at -15.450058 25.084532 270)
			(size 0.4318 0.4318)
			(layers "F.Cu" "F.Mask" "F.Paste")
			(net "M_E_CPU1_SB_DQ<13>")
		)
		(pad "EM30" smd circle
			(at -13.822426 25.084532 270)
			(size 0.4318 0.4318)
			(layers "F.Cu" "F.Mask" "F.Paste")
			(net "M_E_CPU1_SB_DQS_DP<1>")
		)
		(pad "EM32" smd circle
			(at -12.19454 25.084532 270)
			(size 0.4318 0.4318)
			(layers "F.Cu" "F.Mask" "F.Paste")
			(net "M_E_CPU1_SB_DQ<8>")
		)
		(pad "EM34" smd circle
			(at -10.566654 25.084532 270)
			(size 0.4318 0.4318)
			(layers "F.Cu" "F.Mask" "F.Paste")
			(net "M_E_CPU1_SB_CB<1>")
		)
		(pad "EM36" smd circle
			(at -8.939022 25.084532 270)
			(size 0.4318 0.4318)
			(layers "F.Cu" "F.Mask" "F.Paste")
			(net "M_E_CPU1_SB_DQS_DP<9>")
		)
		(pad "EM38" smd circle
			(at -7.311136 25.084532 270)
			(size 0.4318 0.4318)
			(layers "F.Cu" "F.Mask" "F.Paste")
			(net "M_E_CPU1_SB_CB<4>")
		)
		(pad "EM40" smd circle
			(at -5.68325 25.084532 270)
			(size 0.4318 0.4318)
			(layers "F.Cu" "F.Mask" "F.Paste")
			(net "M_E_CPU1_SB_CS_N<2>")
		)
		(pad "EM42" smd circle
			(at -4.055618 25.084532 270)
			(size 0.4318 0.4318)
			(layers "F.Cu" "F.Mask" "F.Paste")
			(net "GND")
		)
		(pad "EM44" smd circle
			(at -2.427732 25.084532 270)
			(size 0.4318 0.4318)
			(layers "F.Cu" "F.Mask" "F.Paste")
			(net "M_E_CPU1_SB_CA<2>")
		)
		(pad "EM47" smd circle
			(at 1.613916 25.194514 270)
			(size 0.4318 0.4318)
			(layers "F.Cu" "F.Mask" "F.Paste")
			(net "M_E_CPU1_SA_CA<4>")
		)
		(pad "EM49" smd circle
			(at 3.241802 25.194514 270)
			(size 0.4318 0.4318)
			(layers "F.Cu" "F.Mask" "F.Paste")
			(net "GND")
		)
		(pad "EM51" smd circle
			(at 4.869434 25.194514 270)
			(size 0.4318 0.4318)
			(layers "F.Cu" "F.Mask" "F.Paste")
			(net "M_E_CPU1_SA_CS_N<2>")
		)
		(pad "EM53" smd circle
			(at 6.49732 25.194514 270)
			(size 0.4318 0.4318)
			(layers "F.Cu" "F.Mask" "F.Paste")
			(net "M_E_CPU1_SA_CB<5>")
		)
		(pad "EM55" smd circle
			(at 8.124952 25.194514 270)
			(size 0.4318 0.4318)
			(layers "F.Cu" "F.Mask" "F.Paste")
			(net "M_E_CPU1_SA_DQS_DN<4>")
		)
		(pad "EM57" smd circle
			(at 9.752838 25.194514 270)
			(size 0.4318 0.4318)
			(layers "F.Cu" "F.Mask" "F.Paste")
			(net "M_E_CPU1_SA_CB<0>")
		)
		(pad "EM59" smd circle
			(at 11.380724 25.194514 270)
			(size 0.4318 0.4318)
			(layers "F.Cu" "F.Mask" "F.Paste")
			(net "M_E_CPU1_SA_DQ<29>")
		)
		(pad "EM61" smd circle
			(at 13.008356 25.194514 270)
			(size 0.4318 0.4318)
			(layers "F.Cu" "F.Mask" "F.Paste")
			(net "M_E_CPU1_SA_DQS_DP<3>")
		)
		(pad "EM63" smd circle
			(at 14.635988 25.194514 270)
			(size 0.4318 0.4318)
			(layers "F.Cu" "F.Mask" "F.Paste")
			(net "M_E_CPU1_SA_DQ<24>")
		)
		(pad "EM65" smd circle
			(at 16.263874 25.194514 270)
			(size 0.4318 0.4318)
			(layers "F.Cu" "F.Mask" "F.Paste")
			(net "M_E_CPU1_SA_DQ<21>")
		)
		(pad "EM67" smd circle
			(at 17.89176 25.194514 270)
			(size 0.4318 0.4318)
			(layers "F.Cu" "F.Mask" "F.Paste")
			(net "M_E_CPU1_SA_DQS_DP<7>")
		)
		(pad "EM69" smd circle
			(at 19.519392 25.194514 270)
			(size 0.4318 0.4318)
			(layers "F.Cu" "F.Mask" "F.Paste")
			(net "M_E_CPU1_SA_DQ<17>")
		)
		(pad "EM71" smd circle
			(at 21.147278 25.194514 270)
			(size 0.4318 0.4318)
			(layers "F.Cu" "F.Mask" "F.Paste")
			(net "M_E_CPU1_SA_DQ<16>")
		)
		(pad "EM73" smd circle
			(at 22.77491 25.194514 270)
			(size 0.4318 0.4318)
			(layers "F.Cu" "F.Mask" "F.Paste")
			(net "GND")
		)
		(pad "EM75" smd circle
			(at 24.402796 25.194514 270)
			(size 0.4318 0.4318)
			(layers "F.Cu" "F.Mask" "F.Paste")
			(net "M_E_CPU1_SA_DQS_DN<5>")
		)
		(pad "EM77" smd circle
			(at 26.030682 25.194514 270)
			(size 0.4318 0.4318)
			(layers "F.Cu" "F.Mask" "F.Paste")
			(net "M_E_CPU1_SA_DQ<1>")
		)
		(pad "EM79" smd circle
			(at 27.658314 25.194514 270)
			(size 0.4318 0.4318)
			(layers "F.Cu" "F.Mask" "F.Paste")
			(net "GND")
		)
		(pad "EM81" smd circle
			(at 29.2862 25.194514 270)
			(size 0.4318 0.4318)
			(layers "F.Cu" "F.Mask" "F.Paste")
			(net "GND")
		)
		(pad "EM83" smd circle
			(at 30.914086 25.194514 270)
			(size 0.4318 0.4318)
			(layers "F.Cu" "F.Mask" "F.Paste")
			(net "GND")
		)
		(pad "EM85" smd oval
			(at 32.541718 25.194514 315)
			(size 0.381 0.4826)
			(drill
				(offset 0 -0.0508)
			)
			(layers "F.Cu" "F.Mask" "F.Paste")
			(net "Net_724")
		)
		(pad "EM87" smd oval
			(at 34.169604 25.194514 315)
			(size 0.381 0.4826)
			(drill
				(offset 0 -0.0508)
			)
			(layers "F.Cu" "F.Mask" "F.Paste")
			(net "Net_732")
		)
		(pad "EN5" smd oval
			(at -34.169604 25.554686 225)
			(size 0.381 0.4826)
			(drill
				(offset 0 -0.0508)
			)
			(layers "F.Cu" "F.Mask" "F.Paste")
			(net "M_G_CPU1_SB_DQS_DP<8>")
		)
		(pad "EN7" smd oval
			(at -32.541718 25.554686 225)
			(size 0.381 0.4826)
			(drill
				(offset 0 -0.0508)
			)
			(layers "F.Cu" "F.Mask" "F.Paste")
			(net "M_G_CPU1_SB_DQS_DP<3>")
		)
		(pad "EN9" smd circle
			(at -30.914086 25.554686 270)
			(size 0.4318 0.4318)
			(layers "F.Cu" "F.Mask" "F.Paste")
			(net "GND")
		)
		(pad "EN11" smd circle
			(at -29.2862 25.554686 270)
			(size 0.4318 0.4318)
			(layers "F.Cu" "F.Mask" "F.Paste")
			(net "GND")
		)
		(pad "EN13" smd circle
			(at -27.658314 25.554686 270)
			(size 0.4318 0.4318)
			(layers "F.Cu" "F.Mask" "F.Paste")
			(net "GND")
		)
		(pad "EN15" smd circle
			(at -26.030682 25.554686 270)
			(size 0.4318 0.4318)
			(layers "F.Cu" "F.Mask" "F.Paste")
			(net "GND")
		)
		(pad "EN17" smd circle
			(at -24.402796 25.554686 270)
			(size 0.4318 0.4318)
			(layers "F.Cu" "F.Mask" "F.Paste")
			(net "GND")
		)
		(pad "EN19" smd circle
			(at -22.77491 25.554686 270)
			(size 0.4318 0.4318)
			(layers "F.Cu" "F.Mask" "F.Paste")
			(net "GND")
		)
		(pad "EN21" smd circle
			(at -21.147278 25.554686 270)
			(size 0.4318 0.4318)
			(layers "F.Cu" "F.Mask" "F.Paste")
			(net "GND")
		)
		(pad "EN23" smd circle
			(at -19.519392 25.554686 270)
			(size 0.4318 0.4318)
			(layers "F.Cu" "F.Mask" "F.Paste")
			(net "GND")
		)
		(pad "EN25" smd circle
			(at -17.89176 25.554686 270)
			(size 0.4318 0.4318)
			(layers "F.Cu" "F.Mask" "F.Paste")
			(net "GND")
		)
		(pad "EN27" smd circle
			(at -16.263874 25.554686 270)
			(size 0.4318 0.4318)
			(layers "F.Cu" "F.Mask" "F.Paste")
			(net "GND")
		)
		(pad "EN29" smd circle
			(at -14.635988 25.554686 270)
			(size 0.4318 0.4318)
			(layers "F.Cu" "F.Mask" "F.Paste")
			(net "GND")
		)
		(pad "EN31" smd circle
			(at -13.008356 25.554686 270)
			(size 0.4318 0.4318)
			(layers "F.Cu" "F.Mask" "F.Paste")
			(net "GND")
		)
		(pad "EN33" smd circle
			(at -11.380724 25.554686 270)
			(size 0.4318 0.4318)
			(layers "F.Cu" "F.Mask" "F.Paste")
			(net "GND")
		)
		(pad "EN35" smd circle
			(at -9.752838 25.554686 270)
			(size 0.4318 0.4318)
			(layers "F.Cu" "F.Mask" "F.Paste")
			(net "GND")
		)
		(pad "EN37" smd circle
			(at -8.124952 25.554686 270)
			(size 0.4318 0.4318)
			(layers "F.Cu" "F.Mask" "F.Paste")
			(net "GND")
		)
		(pad "EN39" smd circle
			(at -6.49732 25.554686 270)
			(size 0.4318 0.4318)
			(layers "F.Cu" "F.Mask" "F.Paste")
			(net "GND")
		)
		(pad "EN41" smd circle
			(at -4.869434 25.554686 270)
			(size 0.4318 0.4318)
			(layers "F.Cu" "F.Mask" "F.Paste")
			(net "GND")
		)
		(pad "EN43" smd circle
			(at -3.241802 25.554686 270)
			(size 0.4318 0.4318)
			(layers "F.Cu" "F.Mask" "F.Paste")
			(net "GND")
		)
		(pad "EN45" smd oval
			(at -1.613916 25.554686 270)
			(size 0.381 0.4826)
			(drill
				(offset 0 -0.0508)
			)
			(layers "F.Cu" "F.Mask" "F.Paste")
			(net "GND")
		)
		(pad "EN48" smd circle
			(at 2.427732 25.664414 270)
			(size 0.4318 0.4318)
			(layers "F.Cu" "F.Mask" "F.Paste")
			(net "GND")
		)
		(pad "EN50" smd circle
			(at 4.055618 25.664414 270)
			(size 0.4318 0.4318)
			(layers "F.Cu" "F.Mask" "F.Paste")
			(net "GND")
		)
		(pad "EN52" smd circle
			(at 5.68325 25.664414 270)
			(size 0.4318 0.4318)
			(layers "F.Cu" "F.Mask" "F.Paste")
			(net "GND")
		)
		(pad "EN54" smd circle
			(at 7.311136 25.664414 270)
			(size 0.4318 0.4318)
			(layers "F.Cu" "F.Mask" "F.Paste")
			(net "GND")
		)
		(pad "EN56" smd circle
			(at 8.939022 25.664414 270)
			(size 0.4318 0.4318)
			(layers "F.Cu" "F.Mask" "F.Paste")
			(net "GND")
		)
		(pad "EN58" smd circle
			(at 10.566654 25.664414 270)
			(size 0.4318 0.4318)
			(layers "F.Cu" "F.Mask" "F.Paste")
			(net "GND")
		)
		(pad "EN60" smd circle
			(at 12.19454 25.664414 270)
			(size 0.4318 0.4318)
			(layers "F.Cu" "F.Mask" "F.Paste")
			(net "GND")
		)
		(pad "EN62" smd circle
			(at 13.822426 25.664414 270)
			(size 0.4318 0.4318)
			(layers "F.Cu" "F.Mask" "F.Paste")
			(net "GND")
		)
		(pad "EN64" smd circle
			(at 15.450058 25.664414 270)
			(size 0.4318 0.4318)
			(layers "F.Cu" "F.Mask" "F.Paste")
			(net "GND")
		)
		(pad "EN66" smd circle
			(at 17.07769 25.664414 270)
			(size 0.4318 0.4318)
			(layers "F.Cu" "F.Mask" "F.Paste")
			(net "GND")
		)
		(pad "EN68" smd circle
			(at 18.705576 25.664414 270)
			(size 0.4318 0.4318)
			(layers "F.Cu" "F.Mask" "F.Paste")
			(net "M_E_CPU1_SA_DQS_DN<7>")
		)
		(pad "EN70" smd circle
			(at 20.333462 25.664414 270)
			(size 0.4318 0.4318)
			(layers "F.Cu" "F.Mask" "F.Paste")
			(net "M_E_CPU1_SA_DQ<18>")
		)
		(pad "EN72" smd circle
			(at 21.961094 25.664414 270)
			(size 0.4318 0.4318)
			(layers "F.Cu" "F.Mask" "F.Paste")
			(net "GND")
		)
		(pad "EN74" smd circle
			(at 23.58898 25.664414 270)
			(size 0.4318 0.4318)
			(layers "F.Cu" "F.Mask" "F.Paste")
			(net "M_E_CPU1_SA_DQS_DP<5>")
		)
		(pad "EN76" smd circle
			(at 25.216612 25.664414 270)
			(size 0.4318 0.4318)
			(layers "F.Cu" "F.Mask" "F.Paste")
			(net "M_E_CPU1_SA_DQS_DP<0>")
		)
		(pad "EN78" smd circle
			(at 26.844498 25.664414 270)
			(size 0.4318 0.4318)
			(layers "F.Cu" "F.Mask" "F.Paste")
			(net "GND")
		)
		(pad "EN80" smd circle
			(at 28.472384 25.664414 270)
			(size 0.4318 0.4318)
			(layers "F.Cu" "F.Mask" "F.Paste")
			(net "GND")
		)
		(pad "EN82" smd circle
			(at 30.100016 25.664414 270)
			(size 0.4318 0.4318)
			(layers "F.Cu" "F.Mask" "F.Paste")
			(net "GND")
		)
		(pad "EN84" smd oval
			(at 31.727902 25.664414 315)
			(size 0.381 0.4826)
			(drill
				(offset 0 -0.0508)
			)
			(layers "F.Cu" "F.Mask" "F.Paste")
			(net "PVCCFA_EHV_FIVRA_CPU1")
		)
		(pad "EN86" smd oval
			(at 33.355534 25.664414 315)
			(size 0.381 0.4826)
			(drill
				(offset 0 -0.0508)
			)
			(layers "F.Cu" "F.Mask" "F.Paste")
			(net "Net_713")
		)
		(pad "EN88" smd oval
			(at 34.98342 25.664414 315)
			(size 0.381 0.4826)
			(drill
				(offset 0 -0.0508)
			)
			(layers "F.Cu" "F.Mask" "F.Paste")
			(net "GND")
		)
		(pad "EP4" smd oval
			(at -34.98342 26.024586 225)
			(size 0.381 0.4826)
			(drill
				(offset 0 -0.0508)
			)
			(layers "F.Cu" "F.Mask" "F.Paste")
			(net "M_G_CPU1_SB_DQ<30>")
		)
		(pad "EP6" smd oval
			(at -33.355534 26.024586 225)
			(size 0.381 0.4826)
			(drill
				(offset 0 -0.0508)
			)
			(layers "F.Cu" "F.Mask" "F.Paste")
			(net "M_G_CPU1_SB_DQS_DN<3>")
		)
		(pad "EP8" smd oval
			(at -31.727902 26.024586 225)
			(size 0.381 0.4826)
			(drill
				(offset 0 -0.0508)
			)
			(layers "F.Cu" "F.Mask" "F.Paste")
			(net "M_G_CPU1_SB_DQ<26>")
		)
		(pad "EP10" smd circle
			(at -30.100016 26.024586 270)
			(size 0.4318 0.4318)
			(layers "F.Cu" "F.Mask" "F.Paste")
			(net "M_F_CPU1_SB_DQ<23>")
		)
		(pad "EP12" smd circle
			(at -28.472384 26.024586 270)
			(size 0.4318 0.4318)
			(layers "F.Cu" "F.Mask" "F.Paste")
			(net "M_F_CPU1_SB_DQS_DP<7>")
		)
		(pad "EP14" smd circle
			(at -26.844498 26.024586 270)
			(size 0.4318 0.4318)
			(layers "F.Cu" "F.Mask" "F.Paste")
			(net "M_F_CPU1_SB_DQ<18>")
		)
		(pad "EP16" smd circle
			(at -25.216612 26.024586 270)
			(size 0.4318 0.4318)
			(layers "F.Cu" "F.Mask" "F.Paste")
			(net "M_E_CPU1_SB_DQ<31>")
		)
		(pad "EP18" smd circle
			(at -23.58898 26.024586 270)
			(size 0.4318 0.4318)
			(layers "F.Cu" "F.Mask" "F.Paste")
			(net "M_E_CPU1_SB_DQS_DP<8>")
		)
		(pad "EP20" smd circle
			(at -21.961094 26.024586 270)
			(size 0.4318 0.4318)
			(layers "F.Cu" "F.Mask" "F.Paste")
			(net "M_E_CPU1_SB_DQ<26>")
		)
		(pad "EP22" smd circle
			(at -20.333462 26.024586 270)
			(size 0.4318 0.4318)
			(layers "F.Cu" "F.Mask" "F.Paste")
			(net "M_E_CPU1_SB_DQ<23>")
		)
		(pad "EP24" smd circle
			(at -18.705576 26.024586 270)
			(size 0.4318 0.4318)
			(layers "F.Cu" "F.Mask" "F.Paste")
			(net "M_E_CPU1_SB_DQS_DP<7>")
		)
		(pad "EP26" smd circle
			(at -17.07769 26.024586 270)
			(size 0.4318 0.4318)
			(layers "F.Cu" "F.Mask" "F.Paste")
			(net "M_E_CPU1_SB_DQ<18>")
		)
		(pad "EP28" smd circle
			(at -15.450058 26.024586 270)
			(size 0.4318 0.4318)
			(layers "F.Cu" "F.Mask" "F.Paste")
			(net "M_E_CPU1_SB_DQ<15>")
		)
		(pad "EP30" smd circle
			(at -13.822426 26.024586 270)
			(size 0.4318 0.4318)
			(layers "F.Cu" "F.Mask" "F.Paste")
			(net "M_E_CPU1_SB_DQS_DP<6>")
		)
		(pad "EP32" smd circle
			(at -12.19454 26.024586 270)
			(size 0.4318 0.4318)
			(layers "F.Cu" "F.Mask" "F.Paste")
			(net "M_E_CPU1_SB_DQ<10>")
		)
		(pad "EP34" smd circle
			(at -10.566654 26.024586 270)
			(size 0.4318 0.4318)
			(layers "F.Cu" "F.Mask" "F.Paste")
			(net "M_E_CPU1_SB_CB<3>")
		)
		(pad "EP36" smd circle
			(at -8.939022 26.024586 270)
			(size 0.4318 0.4318)
			(layers "F.Cu" "F.Mask" "F.Paste")
			(net "M_E_CPU1_SB_DQS_DP<4>")
		)
		(pad "EP38" smd circle
			(at -7.311136 26.024586 270)
			(size 0.4318 0.4318)
			(layers "F.Cu" "F.Mask" "F.Paste")
			(net "M_E_CPU1_SB_CB<6>")
		)
		(pad "EP40" smd circle
			(at -5.68325 26.024586 270)
			(size 0.4318 0.4318)
			(layers "F.Cu" "F.Mask" "F.Paste")
			(net "M_E_CPU1_SB_CS_N<0>")
		)
		(pad "EP42" smd circle
			(at -4.055618 26.024586 270)
			(size 0.4318 0.4318)
			(layers "F.Cu" "F.Mask" "F.Paste")
			(net "M_E_CPU1_SB_PAR")
		)
		(pad "EP44" smd oval
			(at -2.427732 26.024586 270)
			(size 0.381 0.4826)
			(drill
				(offset 0 -0.0508)
			)
			(layers "F.Cu" "F.Mask" "F.Paste")
			(net "M_E_CPU1_SB_CA<3>")
		)
		(pad "EP47" smd oval
			(at 1.613916 26.134314 270)
			(size 0.381 0.4826)
			(drill
				(offset 0 -0.0508)
			)
			(layers "F.Cu" "F.Mask" "F.Paste")
			(net "M_E_CPU1_SA_CA<5>")
		)
		(pad "EP49" smd circle
			(at 3.241802 26.134314 270)
			(size 0.4318 0.4318)
			(layers "F.Cu" "F.Mask" "F.Paste")
			(net "M_E_CPU1_SA_CA<0>")
		)
		(pad "EP51" smd circle
			(at 4.869434 26.134314 270)
			(size 0.4318 0.4318)
			(layers "F.Cu" "F.Mask" "F.Paste")
			(net "M_E_CPU1_SA_CS_N<0>")
		)
		(pad "EP53" smd circle
			(at 6.49732 26.134314 270)
			(size 0.4318 0.4318)
			(layers "F.Cu" "F.Mask" "F.Paste")
			(net "M_E_CPU1_SA_CB<7>")
		)
		(pad "EP55" smd circle
			(at 8.124952 26.134314 270)
			(size 0.4318 0.4318)
			(layers "F.Cu" "F.Mask" "F.Paste")
			(net "M_E_CPU1_SA_DQS_DP<9>")
		)
		(pad "EP57" smd circle
			(at 9.752838 26.134314 270)
			(size 0.4318 0.4318)
			(layers "F.Cu" "F.Mask" "F.Paste")
			(net "M_E_CPU1_SA_CB<2>")
		)
		(pad "EP59" smd circle
			(at 11.380724 26.134314 270)
			(size 0.4318 0.4318)
			(layers "F.Cu" "F.Mask" "F.Paste")
			(net "M_E_CPU1_SA_DQ<31>")
		)
		(pad "EP61" smd circle
			(at 13.008356 26.134314 270)
			(size 0.4318 0.4318)
			(layers "F.Cu" "F.Mask" "F.Paste")
			(net "M_E_CPU1_SA_DQS_DP<8>")
		)
		(pad "EP63" smd circle
			(at 14.635988 26.134314 270)
			(size 0.4318 0.4318)
			(layers "F.Cu" "F.Mask" "F.Paste")
			(net "M_E_CPU1_SA_DQ<26>")
		)
		(pad "EP65" smd circle
			(at 16.263874 26.134314 270)
			(size 0.4318 0.4318)
			(layers "F.Cu" "F.Mask" "F.Paste")
			(net "M_E_CPU1_SA_DQ<23>")
		)
		(pad "EP67" smd circle
			(at 17.89176 26.134314 270)
			(size 0.4318 0.4318)
			(layers "F.Cu" "F.Mask" "F.Paste")
			(net "GND")
		)
		(pad "EP69" smd circle
			(at 19.519392 26.134314 270)
			(size 0.4318 0.4318)
			(layers "F.Cu" "F.Mask" "F.Paste")
			(net "GND")
		)
		(pad "EP71" smd circle
			(at 21.147278 26.134314 270)
			(size 0.4318 0.4318)
			(layers "F.Cu" "F.Mask" "F.Paste")
			(net "GND")
		)
		(pad "EP73" smd circle
			(at 22.77491 26.134314 270)
			(size 0.4318 0.4318)
			(layers "F.Cu" "F.Mask" "F.Paste")
			(net "M_E_CPU1_SA_DQ<6>")
		)
		(pad "EP75" smd circle
			(at 24.402796 26.134314 270)
			(size 0.4318 0.4318)
			(layers "F.Cu" "F.Mask" "F.Paste")
			(net "M_E_CPU1_SA_DQS_DN<0>")
		)
		(pad "EP77" smd circle
			(at 26.030682 26.134314 270)
			(size 0.4318 0.4318)
			(layers "F.Cu" "F.Mask" "F.Paste")
			(net "GND")
		)
		(pad "EP79" smd circle
			(at 27.658314 26.134314 270)
			(size 0.4318 0.4318)
			(layers "F.Cu" "F.Mask" "F.Paste")
			(net "M_E_CPU1_SA_DQ<2>")
		)
		(pad "EP81" smd circle
			(at 29.2862 26.134314 270)
			(size 0.4318 0.4318)
			(layers "F.Cu" "F.Mask" "F.Paste")
			(net "GND")
		)
		(pad "EP83" smd oval
			(at 30.914086 26.134314 315)
			(size 0.381 0.4826)
			(drill
				(offset 0 -0.0508)
			)
			(layers "F.Cu" "F.Mask" "F.Paste")
			(net "GND")
		)
		(pad "EP85" smd oval
			(at 32.541718 26.134314 315)
			(size 0.381 0.4826)
			(drill
				(offset 0 -0.0508)
			)
			(layers "F.Cu" "F.Mask" "F.Paste")
			(net "Net_737")
		)
		(pad "EP87" smd oval
			(at 34.169604 26.134314 315)
			(size 0.381 0.4826)
			(drill
				(offset 0 -0.0508)
			)
			(layers "F.Cu" "F.Mask" "F.Paste")
			(net "Net_708")
		)
		(pad "ER5" smd oval
			(at -34.169604 26.494486 225)
			(size 0.381 0.4826)
			(drill
				(offset 0 -0.0508)
			)
			(layers "F.Cu" "F.Mask" "F.Paste")
			(net "GND")
		)
		(pad "ER7" smd oval
			(at -32.541718 26.494486 225)
			(size 0.381 0.4826)
			(drill
				(offset 0 -0.0508)
			)
			(layers "F.Cu" "F.Mask" "F.Paste")
			(net "GND")
		)
		(pad "ER9" smd oval
			(at -30.914086 26.494486 225)
			(size 0.381 0.4826)
			(drill
				(offset 0 -0.0508)
			)
			(layers "F.Cu" "F.Mask" "F.Paste")
			(net "GND")
		)
		(pad "ER11" smd circle
			(at -29.2862 26.494486 270)
			(size 0.4318 0.4318)
			(layers "F.Cu" "F.Mask" "F.Paste")
			(net "M_F_CPU1_SB_DQ<22>")
		)
		(pad "ER13" smd circle
			(at -27.658314 26.494486 270)
			(size 0.4318 0.4318)
			(layers "F.Cu" "F.Mask" "F.Paste")
			(net "M_F_CPU1_SB_DQ<19>")
		)
		(pad "ER15" smd circle
			(at -26.030682 26.494486 270)
			(size 0.4318 0.4318)
			(layers "F.Cu" "F.Mask" "F.Paste")
			(net "GND")
		)
		(pad "ER17" smd circle
			(at -24.402796 26.494486 270)
			(size 0.4318 0.4318)
			(layers "F.Cu" "F.Mask" "F.Paste")
			(net "M_E_CPU1_SB_DQ<30>")
		)
		(pad "ER19" smd circle
			(at -22.77491 26.494486 270)
			(size 0.4318 0.4318)
			(layers "F.Cu" "F.Mask" "F.Paste")
			(net "M_E_CPU1_SB_DQ<27>")
		)
		(pad "ER21" smd circle
			(at -21.147278 26.494486 270)
			(size 0.4318 0.4318)
			(layers "F.Cu" "F.Mask" "F.Paste")
			(net "GND")
		)
		(pad "ER23" smd circle
			(at -19.519392 26.494486 270)
			(size 0.4318 0.4318)
			(layers "F.Cu" "F.Mask" "F.Paste")
			(net "M_E_CPU1_SB_DQ<22>")
		)
		(pad "ER25" smd circle
			(at -17.89176 26.494486 270)
			(size 0.4318 0.4318)
			(layers "F.Cu" "F.Mask" "F.Paste")
			(net "M_E_CPU1_SB_DQ<19>")
		)
		(pad "ER27" smd circle
			(at -16.263874 26.494486 270)
			(size 0.4318 0.4318)
			(layers "F.Cu" "F.Mask" "F.Paste")
			(net "GND")
		)
		(pad "ER29" smd circle
			(at -14.635988 26.494486 270)
			(size 0.4318 0.4318)
			(layers "F.Cu" "F.Mask" "F.Paste")
			(net "M_E_CPU1_SB_DQ<14>")
		)
		(pad "ER31" smd circle
			(at -13.008356 26.494486 270)
			(size 0.4318 0.4318)
			(layers "F.Cu" "F.Mask" "F.Paste")
			(net "M_E_CPU1_SB_DQ<11>")
		)
		(pad "ER33" smd circle
			(at -11.380724 26.494486 270)
			(size 0.4318 0.4318)
			(layers "F.Cu" "F.Mask" "F.Paste")
			(net "GND")
		)
		(pad "ER35" smd circle
			(at -9.752838 26.494486 270)
			(size 0.4318 0.4318)
			(layers "F.Cu" "F.Mask" "F.Paste")
			(net "M_E_CPU1_SB_CB<2>")
		)
		(pad "ER37" smd circle
			(at -8.124952 26.494486 270)
			(size 0.4318 0.4318)
			(layers "F.Cu" "F.Mask" "F.Paste")
			(net "M_E_CPU1_SB_CB<7>")
		)
		(pad "ER39" smd circle
			(at -6.49732 26.494486 270)
			(size 0.4318 0.4318)
			(layers "F.Cu" "F.Mask" "F.Paste")
			(net "GND")
		)
		(pad "ER41" smd circle
			(at -4.869434 26.494486 270)
			(size 0.4318 0.4318)
			(layers "F.Cu" "F.Mask" "F.Paste")
			(net "GND")
		)
		(pad "ER43" smd oval
			(at -3.241802 26.494486 270)
			(size 0.381 0.4826)
			(drill
				(offset 0 -0.0508)
			)
			(layers "F.Cu" "F.Mask" "F.Paste")
			(net "GND")
		)
		(pad "ER48" smd oval
			(at 2.427732 26.604468 270)
			(size 0.381 0.4826)
			(drill
				(offset 0 -0.0508)
			)
			(layers "F.Cu" "F.Mask" "F.Paste")
			(net "GND")
		)
		(pad "ER50" smd circle
			(at 4.055618 26.604468 270)
			(size 0.4318 0.4318)
			(layers "F.Cu" "F.Mask" "F.Paste")
			(net "GND")
		)
		(pad "ER52" smd circle
			(at 5.68325 26.604468 270)
			(size 0.4318 0.4318)
			(layers "F.Cu" "F.Mask" "F.Paste")
			(net "GND")
		)
		(pad "ER54" smd circle
			(at 7.311136 26.604468 270)
			(size 0.4318 0.4318)
			(layers "F.Cu" "F.Mask" "F.Paste")
			(net "M_E_CPU1_SA_CB<6>")
		)
		(pad "ER56" smd circle
			(at 8.939022 26.604468 270)
			(size 0.4318 0.4318)
			(layers "F.Cu" "F.Mask" "F.Paste")
			(net "M_E_CPU1_SA_CB<3>")
		)
		(pad "ER58" smd circle
			(at 10.566654 26.604468 270)
			(size 0.4318 0.4318)
			(layers "F.Cu" "F.Mask" "F.Paste")
			(net "GND")
		)
		(pad "ER60" smd circle
			(at 12.19454 26.604468 270)
			(size 0.4318 0.4318)
			(layers "F.Cu" "F.Mask" "F.Paste")
			(net "M_E_CPU1_SA_DQ<30>")
		)
		(pad "ER62" smd oval
			(at 13.822426 26.604468 270)
			(size 0.381 0.4826)
			(drill
				(offset 0 -0.0508)
			)
			(layers "F.Cu" "F.Mask" "F.Paste")
			(net "M_E_CPU1_SA_DQ<27>")
		)
		(pad "ER64" smd oval
			(at 15.450058 26.604468 270)
			(size 0.381 0.4826)
			(drill
				(offset 0 -0.0508)
			)
			(layers "F.Cu" "F.Mask" "F.Paste")
			(net "GND")
		)
		(pad "ER66" smd oval
			(at 17.07769 26.604468 270)
			(size 0.381 0.4826)
			(drill
				(offset 0 -0.0508)
			)
			(layers "F.Cu" "F.Mask" "F.Paste")
			(net "M_E_CPU1_SA_DQ<20>")
		)
		(pad "ER68" smd oval
			(at 18.705576 26.604468 270)
			(size 0.381 0.4826)
			(drill
				(offset 0 -0.0508)
			)
			(layers "F.Cu" "F.Mask" "F.Paste")
			(net "M_E_CPU1_SA_DQ<19>")
		)
		(pad "ER70" smd oval
			(at 20.333462 26.604468 270)
			(size 0.381 0.4826)
			(drill
				(offset 0 -0.0508)
			)
			(layers "F.Cu" "F.Mask" "F.Paste")
			(net "GND")
		)
		(pad "ER72" smd oval
			(at 21.961094 26.604468 270)
			(size 0.381 0.4826)
			(drill
				(offset 0 -0.0508)
			)
			(layers "F.Cu" "F.Mask" "F.Paste")
			(net "M_E_CPU1_SA_DQ<7>")
		)
		(pad "ER74" smd oval
			(at 23.58898 26.604468 270)
			(size 0.381 0.4826)
			(drill
				(offset 0 -0.0508)
			)
			(layers "F.Cu" "F.Mask" "F.Paste")
			(net "GND")
		)
		(pad "ER76" smd oval
			(at 25.216612 26.604468 270)
			(size 0.381 0.4826)
			(drill
				(offset 0 -0.0508)
			)
			(layers "F.Cu" "F.Mask" "F.Paste")
			(net "M_E_CPU1_SA_DQ<3>")
		)
		(pad "ER78" smd oval
			(at 26.844498 26.604468 270)
			(size 0.381 0.4826)
			(drill
				(offset 0 -0.0508)
			)
			(layers "F.Cu" "F.Mask" "F.Paste")
			(net "GND")
		)
		(pad "ER80" smd oval
			(at 28.472384 26.604468 270)
			(size 0.381 0.4826)
			(drill
				(offset 0 -0.0508)
			)
			(layers "F.Cu" "F.Mask" "F.Paste")
			(net "GND")
		)
		(pad "ER82" smd oval
			(at 30.100016 26.604468 315)
			(size 0.381 0.4826)
			(drill
				(offset 0 -0.0508)
			)
			(layers "F.Cu" "F.Mask" "F.Paste")
			(net "GND")
		)
		(pad "ER84" smd oval
			(at 31.727902 26.604468 315)
			(size 0.381 0.4826)
			(drill
				(offset 0 -0.0508)
			)
			(layers "F.Cu" "F.Mask" "F.Paste")
			(net "GND")
		)
		(pad "ER86" smd oval
			(at 33.355534 26.604468 315)
			(size 0.381 0.4826)
			(drill
				(offset 0 -0.0508)
			)
			(layers "F.Cu" "F.Mask" "F.Paste")
			(net "GND")
		)
		(pad "ET8" smd oval
			(at -31.727902 26.964132 225)
			(size 0.381 0.4826)
			(drill
				(offset 0 -0.0508)
			)
			(layers "F.Cu" "F.Mask" "F.Paste")
			(net "M_G_CPU1_SB_DQ<27>")
		)
		(pad "ET10" smd oval
			(at -30.100016 26.964132 225)
			(size 0.381 0.4826)
			(drill
				(offset 0 -0.0508)
			)
			(layers "F.Cu" "F.Mask" "F.Paste")
			(net "GND")
		)
		(pad "ET12" smd oval
			(at -28.472384 26.964132 270)
			(size 0.381 0.4826)
			(drill
				(offset 0 -0.0508)
			)
			(layers "F.Cu" "F.Mask" "F.Paste")
			(net "M_F_CPU1_SB_DQS_DN<7>")
		)
		(pad "ET14" smd oval
			(at -26.844498 26.964132 270)
			(size 0.381 0.4826)
			(drill
				(offset 0 -0.0508)
			)
			(layers "F.Cu" "F.Mask" "F.Paste")
			(net "GND")
		)
		(pad "ET16" smd oval
			(at -25.216612 26.964132 270)
			(size 0.381 0.4826)
			(drill
				(offset 0 -0.0508)
			)
			(layers "F.Cu" "F.Mask" "F.Paste")
			(net "GND")
		)
		(pad "ET18" smd oval
			(at -23.58898 26.964132 270)
			(size 0.381 0.4826)
			(drill
				(offset 0 -0.0508)
			)
			(layers "F.Cu" "F.Mask" "F.Paste")
			(net "M_E_CPU1_SB_DQS_DN<8>")
		)
		(pad "ET20" smd oval
			(at -21.961094 26.964132 270)
			(size 0.381 0.4826)
			(drill
				(offset 0 -0.0508)
			)
			(layers "F.Cu" "F.Mask" "F.Paste")
			(net "GND")
		)
		(pad "ET22" smd oval
			(at -20.333462 26.964132 270)
			(size 0.381 0.4826)
			(drill
				(offset 0 -0.0508)
			)
			(layers "F.Cu" "F.Mask" "F.Paste")
			(net "GND")
		)
		(pad "ET24" smd oval
			(at -18.705576 26.964132 270)
			(size 0.381 0.4826)
			(drill
				(offset 0 -0.0508)
			)
			(layers "F.Cu" "F.Mask" "F.Paste")
			(net "M_E_CPU1_SB_DQS_DN<7>")
		)
		(pad "ET26" smd oval
			(at -17.07769 26.964132 270)
			(size 0.381 0.4826)
			(drill
				(offset 0 -0.0508)
			)
			(layers "F.Cu" "F.Mask" "F.Paste")
			(net "GND")
		)
		(pad "ET28" smd oval
			(at -15.450058 26.964132 270)
			(size 0.381 0.4826)
			(drill
				(offset 0 -0.0508)
			)
			(layers "F.Cu" "F.Mask" "F.Paste")
			(net "GND")
		)
		(pad "ET30" smd oval
			(at -13.822426 26.964132 270)
			(size 0.381 0.4826)
			(drill
				(offset 0 -0.0508)
			)
			(layers "F.Cu" "F.Mask" "F.Paste")
			(net "M_E_CPU1_SB_DQS_DN<6>")
		)
		(pad "ET32" smd oval
			(at -12.19454 26.964132 270)
			(size 0.381 0.4826)
			(drill
				(offset 0 -0.0508)
			)
			(layers "F.Cu" "F.Mask" "F.Paste")
			(net "GND")
		)
		(pad "ET34" smd oval
			(at -10.566654 26.964132 270)
			(size 0.381 0.4826)
			(drill
				(offset 0 -0.0508)
			)
			(layers "F.Cu" "F.Mask" "F.Paste")
			(net "GND")
		)
		(pad "ET36" smd oval
			(at -8.939022 26.964132 270)
			(size 0.381 0.4826)
			(drill
				(offset 0 -0.0508)
			)
			(layers "F.Cu" "F.Mask" "F.Paste")
			(net "M_E_CPU1_SB_DQS_DN<4>")
		)
		(pad "ET38" smd oval
			(at -7.311136 26.964132 270)
			(size 0.381 0.4826)
			(drill
				(offset 0 -0.0508)
			)
			(layers "F.Cu" "F.Mask" "F.Paste")
			(net "GND")
		)
		(pad "ET40" smd oval
			(at -5.68325 26.964132 270)
			(size 0.381 0.4826)
			(drill
				(offset 0 -0.0508)
			)
			(layers "F.Cu" "F.Mask" "F.Paste")
			(net "M_E_CPU1_SB_CS_N<1>")
		)
		(pad "ET42" smd oval
			(at -4.055618 26.964132 270)
			(size 0.381 0.4826)
			(drill
				(offset 0 -0.0508)
			)
			(layers "F.Cu" "F.Mask" "F.Paste")
			(net "M_E_CPU1_SB_CA<5>")
		)
		(pad "ET49" smd oval
			(at 3.241802 27.074114 270)
			(size 0.381 0.4826)
			(drill
				(offset 0 -0.0508)
			)
			(layers "F.Cu" "F.Mask" "F.Paste")
			(net "M_E_CPU1_SA_CA<1>")
		)
		(pad "ET51" smd oval
			(at 4.869434 27.074114 270)
			(size 0.381 0.4826)
			(drill
				(offset 0 -0.0508)
			)
			(layers "F.Cu" "F.Mask" "F.Paste")
			(net "M_E_CPU1_SA_CS_N<1>")
		)
		(pad "ET53" smd oval
			(at 6.49732 27.074114 270)
			(size 0.381 0.4826)
			(drill
				(offset 0 -0.0508)
			)
			(layers "F.Cu" "F.Mask" "F.Paste")
			(net "GND")
		)
		(pad "ET55" smd oval
			(at 8.124952 27.074114 270)
			(size 0.381 0.4826)
			(drill
				(offset 0 -0.0508)
			)
			(layers "F.Cu" "F.Mask" "F.Paste")
			(net "M_E_CPU1_SA_DQS_DN<9>")
		)
		(pad "ET57" smd oval
			(at 9.752838 27.074114 270)
			(size 0.381 0.4826)
			(drill
				(offset 0 -0.0508)
			)
			(layers "F.Cu" "F.Mask" "F.Paste")
			(net "GND")
		)
		(pad "ET59" smd oval
			(at 11.380724 27.074114 270)
			(size 0.381 0.4826)
			(drill
				(offset 0 -0.0508)
			)
			(layers "F.Cu" "F.Mask" "F.Paste")
			(net "GND")
		)
		(pad "ET61" smd oval
			(at 13.008356 27.074114 270)
			(size 0.381 0.4826)
			(drill
				(offset 0 -0.0508)
			)
			(layers "F.Cu" "F.Mask" "F.Paste")
			(net "M_E_CPU1_SA_DQS_DN<8>")
		)
		(pad "F4" smd oval
			(at -34.98342 -24.724868 135)
			(size 0.381 0.4826)
			(drill
				(offset 0 -0.0508)
			)
			(layers "F.Cu" "F.Mask" "F.Paste")
			(net "GND")
		)
		(pad "F6" smd oval
			(at -33.355534 -24.724868 135)
			(size 0.381 0.4826)
			(drill
				(offset 0 -0.0508)
			)
			(layers "F.Cu" "F.Mask" "F.Paste")
			(net "GND")
		)
		(pad "F8" smd circle
			(at -31.727902 -24.724868 270)
			(size 0.4318 0.4318)
			(layers "F.Cu" "F.Mask" "F.Paste")
			(net "M_A_CPU1_SB_DQ<30>")
		)
		(pad "F10" smd circle
			(at -30.100016 -24.724868 270)
			(size 0.4318 0.4318)
			(layers "F.Cu" "F.Mask" "F.Paste")
			(net "M_A_CPU1_SB_DQ<27>")
		)
		(pad "F12" smd circle
			(at -28.472384 -24.724868 270)
			(size 0.4318 0.4318)
			(layers "F.Cu" "F.Mask" "F.Paste")
			(net "GND")
		)
		(pad "F14" smd circle
			(at -26.844498 -24.724868 270)
			(size 0.4318 0.4318)
			(layers "F.Cu" "F.Mask" "F.Paste")
			(net "M_B_CPU1_SB_DQ<31>")
		)
		(pad "F16" smd circle
			(at -25.216612 -24.724868 270)
			(size 0.4318 0.4318)
			(layers "F.Cu" "F.Mask" "F.Paste")
			(net "M_B_CPU1_SB_DQ<27>")
		)
		(pad "F18" smd circle
			(at -23.58898 -24.724868 270)
			(size 0.4318 0.4318)
			(layers "F.Cu" "F.Mask" "F.Paste")
			(net "GND")
		)
		(pad "F20" smd circle
			(at -21.961094 -24.724868 270)
			(size 0.4318 0.4318)
			(layers "F.Cu" "F.Mask" "F.Paste")
			(net "M_A_CPU1_SB_DQ<22>")
		)
		(pad "F22" smd circle
			(at -20.333462 -24.724868 270)
			(size 0.4318 0.4318)
			(layers "F.Cu" "F.Mask" "F.Paste")
			(net "M_A_CPU1_SB_DQ<19>")
		)
		(pad "F24" smd circle
			(at -18.705576 -24.724868 270)
			(size 0.4318 0.4318)
			(layers "F.Cu" "F.Mask" "F.Paste")
			(net "GND")
		)
		(pad "F26" smd circle
			(at -17.07769 -24.724868 270)
			(size 0.4318 0.4318)
			(layers "F.Cu" "F.Mask" "F.Paste")
			(net "M_A_CPU1_SB_DQ<14>")
		)
		(pad "F28" smd circle
			(at -15.450058 -24.724868 270)
			(size 0.4318 0.4318)
			(layers "F.Cu" "F.Mask" "F.Paste")
			(net "M_A_CPU1_SB_DQ<11>")
		)
		(pad "F30" smd circle
			(at -13.822426 -24.724868 270)
			(size 0.4318 0.4318)
			(layers "F.Cu" "F.Mask" "F.Paste")
			(net "GND")
		)
		(pad "F32" smd circle
			(at -12.19454 -24.724868 270)
			(size 0.4318 0.4318)
			(layers "F.Cu" "F.Mask" "F.Paste")
			(net "M_A_CPU1_SB_CB<2>")
		)
		(pad "F34" smd circle
			(at -10.566654 -24.724868 270)
			(size 0.4318 0.4318)
			(layers "F.Cu" "F.Mask" "F.Paste")
			(net "M_A_CPU1_SB_CB<7>")
		)
		(pad "F36" smd circle
			(at -8.939022 -24.724868 270)
			(size 0.4318 0.4318)
			(layers "F.Cu" "F.Mask" "F.Paste")
			(net "GND")
		)
		(pad "F38" smd circle
			(at -7.311136 -24.724868 270)
			(size 0.4318 0.4318)
			(layers "F.Cu" "F.Mask" "F.Paste")
			(net "M_A_CPU1_SB_CS_N<2>")
		)
		(pad "F40" smd circle
			(at -5.68325 -24.724868 270)
			(size 0.4318 0.4318)
			(layers "F.Cu" "F.Mask" "F.Paste")
			(net "M_A_CPU1_SB_CA<5>")
		)
		(pad "F42" smd circle
			(at -4.055618 -24.724868 270)
			(size 0.4318 0.4318)
			(layers "F.Cu" "F.Mask" "F.Paste")
			(net "GND")
		)
		(pad "F44" smd circle
			(at -2.427732 -24.724868 270)
			(size 0.4318 0.4318)
			(layers "F.Cu" "F.Mask" "F.Paste")
			(net "M_A_CPU1_SB_CA<1>")
		)
		(pad "F47" smd circle
			(at 1.613916 -24.614886 270)
			(size 0.4318 0.4318)
			(layers "F.Cu" "F.Mask" "F.Paste")
			(net "PWRGD_DRAMPWRGD_CPU1_CD_LVC1_R")
		)
		(pad "F49" smd circle
			(at 3.241802 -24.614886 270)
			(size 0.4318 0.4318)
			(layers "F.Cu" "F.Mask" "F.Paste")
			(net "GND")
		)
		(pad "F51" smd circle
			(at 4.869434 -24.614886 270)
			(size 0.4318 0.4318)
			(layers "F.Cu" "F.Mask" "F.Paste")
			(net "M_A_CPU1_SA_CA<3>")
		)
		(pad "F53" smd circle
			(at 6.49732 -24.614886 270)
			(size 0.4318 0.4318)
			(layers "F.Cu" "F.Mask" "F.Paste")
			(net "M_A_CPU1_SA_CS_N<3>")
		)
		(pad "F55" smd circle
			(at 8.124952 -24.614886 270)
			(size 0.4318 0.4318)
			(layers "F.Cu" "F.Mask" "F.Paste")
			(net "GND")
		)
		(pad "F57" smd circle
			(at 9.752838 -24.614886 270)
			(size 0.4318 0.4318)
			(layers "F.Cu" "F.Mask" "F.Paste")
			(net "M_A_CPU1_SA_CB<6>")
		)
		(pad "F59" smd circle
			(at 11.380724 -24.614886 270)
			(size 0.4318 0.4318)
			(layers "F.Cu" "F.Mask" "F.Paste")
			(net "M_A_CPU1_SA_CB<3>")
		)
		(pad "F61" smd circle
			(at 13.008356 -24.614886 270)
			(size 0.4318 0.4318)
			(layers "F.Cu" "F.Mask" "F.Paste")
			(net "GND")
		)
		(pad "F63" smd circle
			(at 14.635988 -24.614886 270)
			(size 0.4318 0.4318)
			(layers "F.Cu" "F.Mask" "F.Paste")
			(net "M_A_CPU1_SA_DQ<30>")
		)
		(pad "F65" smd circle
			(at 16.263874 -24.614886 270)
			(size 0.4318 0.4318)
			(layers "F.Cu" "F.Mask" "F.Paste")
			(net "M_A_CPU1_SA_DQ<27>")
		)
		(pad "F67" smd circle
			(at 17.89176 -24.614886 270)
			(size 0.4318 0.4318)
			(layers "F.Cu" "F.Mask" "F.Paste")
			(net "GND")
		)
		(pad "F69" smd circle
			(at 19.519392 -24.614886 270)
			(size 0.4318 0.4318)
			(layers "F.Cu" "F.Mask" "F.Paste")
			(net "M_A_CPU1_SA_DQ<22>")
		)
		(pad "F71" smd circle
			(at 21.147278 -24.614886 270)
			(size 0.4318 0.4318)
			(layers "F.Cu" "F.Mask" "F.Paste")
			(net "M_A_CPU1_SA_DQ<19>")
		)
		(pad "F73" smd circle
			(at 22.77491 -24.614886 270)
			(size 0.4318 0.4318)
			(layers "F.Cu" "F.Mask" "F.Paste")
			(net "GND")
		)
		(pad "F75" smd circle
			(at 24.402796 -24.614886 270)
			(size 0.4318 0.4318)
			(layers "F.Cu" "F.Mask" "F.Paste")
			(net "M_A_CPU1_SA_DQ<7>")
		)
		(pad "F77" smd circle
			(at 26.030682 -24.614886 270)
			(size 0.4318 0.4318)
			(layers "F.Cu" "F.Mask" "F.Paste")
			(net "M_A_CPU1_SA_DQS_DP<5>")
		)
		(pad "F79" smd circle
			(at 27.658314 -24.614886 270)
			(size 0.4318 0.4318)
			(layers "F.Cu" "F.Mask" "F.Paste")
			(net "GND")
		)
		(pad "F81" smd circle
			(at 29.2862 -24.614886 270)
			(size 0.4318 0.4318)
			(layers "F.Cu" "F.Mask" "F.Paste")
			(net "UPI_CPU0_CPU1_P2P2_DN<1>")
		)
		(pad "F83" smd circle
			(at 30.914086 -24.614886 270)
			(size 0.4318 0.4318)
			(layers "F.Cu" "F.Mask" "F.Paste")
			(net "GND")
		)
		(pad "F85" smd circle
			(at 32.541718 -24.614886 270)
			(size 0.4318 0.4318)
			(layers "F.Cu" "F.Mask" "F.Paste")
			(net "UPI_CPU1_CPU0_P2P2_DP<1>")
		)
		(pad "F87" smd oval
			(at 34.169604 -24.614886 45)
			(size 0.381 0.4826)
			(drill
				(offset 0 -0.0508)
			)
			(layers "F.Cu" "F.Mask" "F.Paste")
			(net "UPI_CPU1_CPU0_P2P2_DN<3>")
		)
		(pad "F89" smd oval
			(at 35.797236 -24.614886 45)
			(size 0.381 0.4826)
			(drill
				(offset 0 -0.0508)
			)
			(layers "F.Cu" "F.Mask" "F.Paste")
			(net "GND")
		)
		(pad "G3" smd oval
			(at -35.797236 -24.254714 135)
			(size 0.381 0.4826)
			(drill
				(offset 0 -0.0508)
			)
			(layers "F.Cu" "F.Mask" "F.Paste")
			(net "GND")
		)
		(pad "G5" smd oval
			(at -34.169604 -24.254714 135)
			(size 0.381 0.4826)
			(drill
				(offset 0 -0.0508)
			)
			(layers "F.Cu" "F.Mask" "F.Paste")
			(net "CPU1_RSVD<157>")
		)
		(pad "G7" smd circle
			(at -32.541718 -24.254714 270)
			(size 0.4318 0.4318)
			(layers "F.Cu" "F.Mask" "F.Paste")
			(net "GND")
		)
		(pad "G9" smd circle
			(at -30.914086 -24.254714 270)
			(size 0.4318 0.4318)
			(layers "F.Cu" "F.Mask" "F.Paste")
			(net "M_A_CPU1_SB_DQS_DN<8>")
		)
		(pad "G11" smd circle
			(at -29.2862 -24.254714 270)
			(size 0.4318 0.4318)
			(layers "F.Cu" "F.Mask" "F.Paste")
			(net "GND")
		)
		(pad "G13" smd circle
			(at -27.658314 -24.254714 270)
			(size 0.4318 0.4318)
			(layers "F.Cu" "F.Mask" "F.Paste")
			(net "GND")
		)
		(pad "G15" smd circle
			(at -26.030682 -24.254714 270)
			(size 0.4318 0.4318)
			(layers "F.Cu" "F.Mask" "F.Paste")
			(net "M_B_CPU1_SB_DQS_DP<8>")
		)
		(pad "G17" smd circle
			(at -24.402796 -24.254714 270)
			(size 0.4318 0.4318)
			(layers "F.Cu" "F.Mask" "F.Paste")
			(net "GND")
		)
		(pad "G19" smd circle
			(at -22.77491 -24.254714 270)
			(size 0.4318 0.4318)
			(layers "F.Cu" "F.Mask" "F.Paste")
			(net "GND")
		)
		(pad "G21" smd circle
			(at -21.147278 -24.254714 270)
			(size 0.4318 0.4318)
			(layers "F.Cu" "F.Mask" "F.Paste")
			(net "M_A_CPU1_SB_DQS_DN<7>")
		)
		(pad "G23" smd circle
			(at -19.519392 -24.254714 270)
			(size 0.4318 0.4318)
			(layers "F.Cu" "F.Mask" "F.Paste")
			(net "GND")
		)
		(pad "G25" smd circle
			(at -17.89176 -24.254714 270)
			(size 0.4318 0.4318)
			(layers "F.Cu" "F.Mask" "F.Paste")
			(net "GND")
		)
		(pad "G27" smd circle
			(at -16.263874 -24.254714 270)
			(size 0.4318 0.4318)
			(layers "F.Cu" "F.Mask" "F.Paste")
			(net "M_A_CPU1_SB_DQS_DN<6>")
		)
		(pad "G29" smd circle
			(at -14.635988 -24.254714 270)
			(size 0.4318 0.4318)
			(layers "F.Cu" "F.Mask" "F.Paste")
			(net "GND")
		)
		(pad "G31" smd circle
			(at -13.008356 -24.254714 270)
			(size 0.4318 0.4318)
			(layers "F.Cu" "F.Mask" "F.Paste")
			(net "GND")
		)
		(pad "G33" smd circle
			(at -11.380724 -24.254714 270)
			(size 0.4318 0.4318)
			(layers "F.Cu" "F.Mask" "F.Paste")
			(net "M_A_CPU1_SB_DQS_DN<4>")
		)
		(pad "G35" smd circle
			(at -9.752838 -24.254714 270)
			(size 0.4318 0.4318)
			(layers "F.Cu" "F.Mask" "F.Paste")
			(net "GND")
		)
		(pad "G37" smd circle
			(at -8.124952 -24.254714 270)
			(size 0.4318 0.4318)
			(layers "F.Cu" "F.Mask" "F.Paste")
			(net "GND")
		)
		(pad "G39" smd circle
			(at -6.49732 -24.254714 270)
			(size 0.4318 0.4318)
			(layers "F.Cu" "F.Mask" "F.Paste")
			(net "M_A_CPU1_SB_PAR")
		)
		(pad "G41" smd circle
			(at -4.869434 -24.254714 270)
			(size 0.4318 0.4318)
			(layers "F.Cu" "F.Mask" "F.Paste")
			(net "GND")
		)
		(pad "G43" smd circle
			(at -3.241802 -24.254714 270)
			(size 0.4318 0.4318)
			(layers "F.Cu" "F.Mask" "F.Paste")
			(net "GND")
		)
		(pad "G45" smd circle
			(at -1.613916 -24.254714 270)
			(size 0.4318 0.4318)
			(layers "F.Cu" "F.Mask" "F.Paste")
			(net "M_A_CPU1_CLK_DN<1>")
		)
		(pad "G48" smd circle
			(at 2.427732 -24.144986 270)
			(size 0.4318 0.4318)
			(layers "F.Cu" "F.Mask" "F.Paste")
			(net "GND")
		)
		(pad "G50" smd circle
			(at 4.055618 -24.144986 270)
			(size 0.4318 0.4318)
			(layers "F.Cu" "F.Mask" "F.Paste")
			(net "GND")
		)
		(pad "G52" smd circle
			(at 5.68325 -24.144986 270)
			(size 0.4318 0.4318)
			(layers "F.Cu" "F.Mask" "F.Paste")
			(net "M_A_CPU1_SA_CA<1>")
		)
		(pad "G54" smd circle
			(at 7.311136 -24.144986 270)
			(size 0.4318 0.4318)
			(layers "F.Cu" "F.Mask" "F.Paste")
			(net "GND")
		)
		(pad "G56" smd circle
			(at 8.939022 -24.144986 270)
			(size 0.4318 0.4318)
			(layers "F.Cu" "F.Mask" "F.Paste")
			(net "GND")
		)
		(pad "G58" smd circle
			(at 10.566654 -24.144986 270)
			(size 0.4318 0.4318)
			(layers "F.Cu" "F.Mask" "F.Paste")
			(net "M_A_CPU1_SA_DQS_DN<9>")
		)
		(pad "G60" smd circle
			(at 12.19454 -24.144986 270)
			(size 0.4318 0.4318)
			(layers "F.Cu" "F.Mask" "F.Paste")
			(net "GND")
		)
		(pad "G62" smd circle
			(at 13.822426 -24.144986 270)
			(size 0.4318 0.4318)
			(layers "F.Cu" "F.Mask" "F.Paste")
			(net "GND")
		)
		(pad "G64" smd circle
			(at 15.450058 -24.144986 270)
			(size 0.4318 0.4318)
			(layers "F.Cu" "F.Mask" "F.Paste")
			(net "M_A_CPU1_SA_DQS_DN<8>")
		)
		(pad "G66" smd circle
			(at 17.07769 -24.144986 270)
			(size 0.4318 0.4318)
			(layers "F.Cu" "F.Mask" "F.Paste")
			(net "GND")
		)
		(pad "G68" smd circle
			(at 18.705576 -24.144986 270)
			(size 0.4318 0.4318)
			(layers "F.Cu" "F.Mask" "F.Paste")
			(net "GND")
		)
		(pad "G70" smd circle
			(at 20.333462 -24.144986 270)
			(size 0.4318 0.4318)
			(layers "F.Cu" "F.Mask" "F.Paste")
			(net "M_A_CPU1_SA_DQS_DN<7>")
		)
		(pad "G72" smd circle
			(at 21.961094 -24.144986 270)
			(size 0.4318 0.4318)
			(layers "F.Cu" "F.Mask" "F.Paste")
			(net "GND")
		)
		(pad "G74" smd circle
			(at 23.58898 -24.144986 270)
			(size 0.4318 0.4318)
			(layers "F.Cu" "F.Mask" "F.Paste")
			(net "GND")
		)
		(pad "G76" smd circle
			(at 25.216612 -24.144986 270)
			(size 0.4318 0.4318)
			(layers "F.Cu" "F.Mask" "F.Paste")
			(net "M_A_CPU1_SA_DQ<6>")
		)
		(pad "G78" smd circle
			(at 26.844498 -24.144986 270)
			(size 0.4318 0.4318)
			(layers "F.Cu" "F.Mask" "F.Paste")
			(net "M_A_CPU1_SA_DQ<3>")
		)
		(pad "G80" smd circle
			(at 28.472384 -24.144986 270)
			(size 0.4318 0.4318)
			(layers "F.Cu" "F.Mask" "F.Paste")
			(net "UPI_CPU0_CPU1_P2P2_DP<0>")
		)
		(pad "G82" smd circle
			(at 30.100016 -24.144986 270)
			(size 0.4318 0.4318)
			(layers "F.Cu" "F.Mask" "F.Paste")
			(net "UPI_CPU0_CPU1_P2P2_DN<2>")
		)
		(pad "G84" smd circle
			(at 31.727902 -24.144986 270)
			(size 0.4318 0.4318)
			(layers "F.Cu" "F.Mask" "F.Paste")
			(net "GND")
		)
		(pad "G86" smd circle
			(at 33.355534 -24.144986 270)
			(size 0.4318 0.4318)
			(layers "F.Cu" "F.Mask" "F.Paste")
			(net "UPI_CPU1_CPU0_P2P2_DP<4>")
		)
		(pad "G88" smd oval
			(at 34.98342 -24.144986 45)
			(size 0.381 0.4826)
			(drill
				(offset 0 -0.0508)
			)
			(layers "F.Cu" "F.Mask" "F.Paste")
			(net "GND")
		)
		(pad "G90" smd oval
			(at 36.611306 -24.144986 45)
			(size 0.381 0.4826)
			(drill
				(offset 0 -0.0508)
			)
			(layers "F.Cu" "F.Mask" "F.Paste")
			(net "GND")
		)
		(pad "H2" smd oval
			(at -36.611306 -23.784814 135)
			(size 0.381 0.4826)
			(drill
				(offset 0 -0.0508)
			)
			(layers "F.Cu" "F.Mask" "F.Paste")
			(net "GND")
		)
		(pad "H4" smd oval
			(at -34.98342 -23.784814 135)
			(size 0.381 0.4826)
			(drill
				(offset 0 -0.0508)
			)
			(layers "F.Cu" "F.Mask" "F.Paste")
			(net "GND")
		)
		(pad "H6" smd circle
			(at -33.355534 -23.784814 270)
			(size 0.4318 0.4318)
			(layers "F.Cu" "F.Mask" "F.Paste")
			(net "GND")
		)
		(pad "H8" smd circle
			(at -31.727902 -23.784814 270)
			(size 0.4318 0.4318)
			(layers "F.Cu" "F.Mask" "F.Paste")
			(net "GND")
		)
		(pad "H10" smd circle
			(at -30.100016 -23.784814 270)
			(size 0.4318 0.4318)
			(layers "F.Cu" "F.Mask" "F.Paste")
			(net "GND")
		)
		(pad "H12" smd circle
			(at -28.472384 -23.784814 270)
			(size 0.4318 0.4318)
			(layers "F.Cu" "F.Mask" "F.Paste")
			(net "TP_CPU1_A0_DEBUG_EN")
		)
		(pad "H14" smd circle
			(at -26.844498 -23.784814 270)
			(size 0.4318 0.4318)
			(layers "F.Cu" "F.Mask" "F.Paste")
			(net "GND")
		)
		(pad "H16" smd circle
			(at -25.216612 -23.784814 270)
			(size 0.4318 0.4318)
			(layers "F.Cu" "F.Mask" "F.Paste")
			(net "GND")
		)
		(pad "H18" smd circle
			(at -23.58898 -23.784814 270)
			(size 0.4318 0.4318)
			(layers "F.Cu" "F.Mask" "F.Paste")
			(net "M_B_CPU1_SB_DQS_DN<2>")
		)
		(pad "H20" smd circle
			(at -21.961094 -23.784814 270)
			(size 0.4318 0.4318)
			(layers "F.Cu" "F.Mask" "F.Paste")
			(net "GND")
		)
		(pad "H22" smd circle
			(at -20.333462 -23.784814 270)
			(size 0.4318 0.4318)
			(layers "F.Cu" "F.Mask" "F.Paste")
			(net "GND")
		)
		(pad "H24" smd circle
			(at -18.705576 -23.784814 270)
			(size 0.4318 0.4318)
			(layers "F.Cu" "F.Mask" "F.Paste")
			(net "M_B_CPU1_SB_DQS_DN<1>")
		)
		(pad "H26" smd circle
			(at -17.07769 -23.784814 270)
			(size 0.4318 0.4318)
			(layers "F.Cu" "F.Mask" "F.Paste")
			(net "GND")
		)
		(pad "H28" smd circle
			(at -15.450058 -23.784814 270)
			(size 0.4318 0.4318)
			(layers "F.Cu" "F.Mask" "F.Paste")
			(net "GND")
		)
		(pad "H30" smd circle
			(at -13.822426 -23.784814 270)
			(size 0.4318 0.4318)
			(layers "F.Cu" "F.Mask" "F.Paste")
			(net "M_A_CPU1_SB_DQS_DN<0>")
		)
		(pad "H32" smd circle
			(at -12.19454 -23.784814 270)
			(size 0.4318 0.4318)
			(layers "F.Cu" "F.Mask" "F.Paste")
			(net "GND")
		)
		(pad "H34" smd circle
			(at -10.566654 -23.784814 270)
			(size 0.4318 0.4318)
			(layers "F.Cu" "F.Mask" "F.Paste")
			(net "GND")
		)
		(pad "H36" smd circle
			(at -8.939022 -23.784814 270)
			(size 0.4318 0.4318)
			(layers "F.Cu" "F.Mask" "F.Paste")
			(net "M_B_CPU1_SB_DQS_DP<9>")
		)
		(pad "H38" smd circle
			(at -7.311136 -23.784814 270)
			(size 0.4318 0.4318)
			(layers "F.Cu" "F.Mask" "F.Paste")
			(net "GND")
		)
		(pad "H40" smd circle
			(at -5.68325 -23.784814 270)
			(size 0.4318 0.4318)
			(layers "F.Cu" "F.Mask" "F.Paste")
			(net "GND")
		)
		(pad "H42" smd circle
			(at -4.055618 -23.784814 270)
			(size 0.4318 0.4318)
			(layers "F.Cu" "F.Mask" "F.Paste")
			(net "M_B_CPU1_SB_CA<6>")
		)
		(pad "H44" smd circle
			(at -2.427732 -23.784814 270)
			(size 0.4318 0.4318)
			(layers "F.Cu" "F.Mask" "F.Paste")
			(net "GND")
		)
		(pad "H47" smd circle
			(at 1.613916 -23.675086 270)
			(size 0.4318 0.4318)
			(layers "F.Cu" "F.Mask" "F.Paste")
			(net "GND")
		)
		(pad "H49" smd circle
			(at 3.241802 -23.675086 270)
			(size 0.4318 0.4318)
			(layers "F.Cu" "F.Mask" "F.Paste")
			(net "M_B_CPU1_SA_CA<0>")
		)
		(pad "H51" smd circle
			(at 4.869434 -23.675086 270)
			(size 0.4318 0.4318)
			(layers "F.Cu" "F.Mask" "F.Paste")
			(net "GND")
		)
		(pad "H53" smd circle
			(at 6.49732 -23.675086 270)
			(size 0.4318 0.4318)
			(layers "F.Cu" "F.Mask" "F.Paste")
			(net "GND")
		)
		(pad "H55" smd circle
			(at 8.124952 -23.675086 270)
			(size 0.4318 0.4318)
			(layers "F.Cu" "F.Mask" "F.Paste")
			(net "M_B_CPU1_SA_DQS_DN<4>")
		)
		(pad "H57" smd circle
			(at 9.752838 -23.675086 270)
			(size 0.4318 0.4318)
			(layers "F.Cu" "F.Mask" "F.Paste")
			(net "GND")
		)
		(pad "H59" smd circle
			(at 11.380724 -23.675086 270)
			(size 0.4318 0.4318)
			(layers "F.Cu" "F.Mask" "F.Paste")
			(net "GND")
		)
		(pad "H61" smd circle
			(at 13.008356 -23.675086 270)
			(size 0.4318 0.4318)
			(layers "F.Cu" "F.Mask" "F.Paste")
			(net "M_B_CPU1_SA_DQS_DN<2>")
		)
		(pad "H63" smd circle
			(at 14.635988 -23.675086 270)
			(size 0.4318 0.4318)
			(layers "F.Cu" "F.Mask" "F.Paste")
			(net "GND")
		)
		(pad "H65" smd circle
			(at 16.263874 -23.675086 270)
			(size 0.4318 0.4318)
			(layers "F.Cu" "F.Mask" "F.Paste")
			(net "GND")
		)
		(pad "H67" smd circle
			(at 17.89176 -23.675086 270)
			(size 0.4318 0.4318)
			(layers "F.Cu" "F.Mask" "F.Paste")
			(net "M_A_CPU1_SA_DQS_DN<1>")
		)
		(pad "H69" smd circle
			(at 19.519392 -23.675086 270)
			(size 0.4318 0.4318)
			(layers "F.Cu" "F.Mask" "F.Paste")
			(net "GND")
		)
		(pad "H71" smd circle
			(at 21.147278 -23.675086 270)
			(size 0.4318 0.4318)
			(layers "F.Cu" "F.Mask" "F.Paste")
			(net "GND")
		)
		(pad "H73" smd circle
			(at 22.77491 -23.675086 270)
			(size 0.4318 0.4318)
			(layers "F.Cu" "F.Mask" "F.Paste")
			(net "M_B_CPU1_SA_DQS_DN<0>")
		)
		(pad "H75" smd circle
			(at 24.402796 -23.675086 270)
			(size 0.4318 0.4318)
			(layers "F.Cu" "F.Mask" "F.Paste")
			(net "GND")
		)
		(pad "H77" smd circle
			(at 26.030682 -23.675086 270)
			(size 0.4318 0.4318)
			(layers "F.Cu" "F.Mask" "F.Paste")
			(net "M_A_CPU1_SA_DQS_DN<5>")
		)
		(pad "H79" smd circle
			(at 27.658314 -23.675086 270)
			(size 0.4318 0.4318)
			(layers "F.Cu" "F.Mask" "F.Paste")
			(net "GND")
		)
		(pad "H81" smd circle
			(at 29.2862 -23.675086 270)
			(size 0.4318 0.4318)
			(layers "F.Cu" "F.Mask" "F.Paste")
			(net "GND")
		)
		(pad "H83" smd circle
			(at 30.914086 -23.675086 270)
			(size 0.4318 0.4318)
			(layers "F.Cu" "F.Mask" "F.Paste")
			(net "UPI_CPU0_CPU1_P2P2_DP<2>")
		)
		(pad "H85" smd circle
			(at 32.541718 -23.675086 270)
			(size 0.4318 0.4318)
			(layers "F.Cu" "F.Mask" "F.Paste")
			(net "UPI_CPU1_CPU0_P2P2_DN<4>")
		)
		(pad "H87" smd circle
			(at 34.169604 -23.675086 270)
			(size 0.4318 0.4318)
			(layers "F.Cu" "F.Mask" "F.Paste")
			(net "UPI_CPU1_CPU0_P2P2_DP<3>")
		)
		(pad "H89" smd oval
			(at 35.797236 -23.675086 45)
			(size 0.381 0.4826)
			(drill
				(offset 0 -0.0508)
			)
			(layers "F.Cu" "F.Mask" "F.Paste")
			(net "PVCCFA_EHV_FIVRA_CPU1")
		)
		(pad "J3" smd oval
			(at -35.797236 -23.314914 135)
			(size 0.381 0.4826)
			(drill
				(offset 0 -0.0508)
			)
			(layers "F.Cu" "F.Mask" "F.Paste")
			(net "UPI_CPU1_CPU0_P0P1_DP<0>")
		)
		(pad "J5" smd circle
			(at -34.169604 -23.314914 270)
			(size 0.4318 0.4318)
			(layers "F.Cu" "F.Mask" "F.Paste")
			(net "GND")
		)
		(pad "J7" smd circle
			(at -32.541718 -23.314914 270)
			(size 0.4318 0.4318)
			(layers "F.Cu" "F.Mask" "F.Paste")
			(net "PVCCFA_EHV_FIVRA_CPU1")
		)
		(pad "J9" smd circle
			(at -30.914086 -23.314914 270)
			(size 0.4318 0.4318)
			(layers "F.Cu" "F.Mask" "F.Paste")
			(net "GND")
		)
		(pad "J11" smd circle
			(at -29.2862 -23.314914 270)
			(size 0.4318 0.4318)
			(layers "F.Cu" "F.Mask" "F.Paste")
			(net "PVCCFA_EHV_FIVRA_CPU1")
		)
		(pad "J13" smd circle
			(at -27.658314 -23.314914 270)
			(size 0.4318 0.4318)
			(layers "F.Cu" "F.Mask" "F.Paste")
			(net "TP_CPU1_PPD")
		)
		(pad "J15" smd circle
			(at -26.030682 -23.314914 270)
			(size 0.4318 0.4318)
			(layers "F.Cu" "F.Mask" "F.Paste")
			(net "GND")
		)
		(pad "J17" smd circle
			(at -24.402796 -23.314914 270)
			(size 0.4318 0.4318)
			(layers "F.Cu" "F.Mask" "F.Paste")
			(net "M_B_CPU1_SB_DQ<20>")
		)
		(pad "J19" smd circle
			(at -22.77491 -23.314914 270)
			(size 0.4318 0.4318)
			(layers "F.Cu" "F.Mask" "F.Paste")
			(net "M_B_CPU1_SB_DQ<17>")
		)
		(pad "J21" smd circle
			(at -21.147278 -23.314914 270)
			(size 0.4318 0.4318)
			(layers "F.Cu" "F.Mask" "F.Paste")
			(net "GND")
		)
		(pad "J23" smd circle
			(at -19.519392 -23.314914 270)
			(size 0.4318 0.4318)
			(layers "F.Cu" "F.Mask" "F.Paste")
			(net "M_B_CPU1_SB_DQ<12>")
		)
		(pad "J25" smd circle
			(at -17.89176 -23.314914 270)
			(size 0.4318 0.4318)
			(layers "F.Cu" "F.Mask" "F.Paste")
			(net "M_B_CPU1_SB_DQ<9>")
		)
		(pad "J27" smd circle
			(at -16.263874 -23.314914 270)
			(size 0.4318 0.4318)
			(layers "F.Cu" "F.Mask" "F.Paste")
			(net "GND")
		)
		(pad "J29" smd circle
			(at -14.635988 -23.314914 270)
			(size 0.4318 0.4318)
			(layers "F.Cu" "F.Mask" "F.Paste")
			(net "M_A_CPU1_SB_DQ<4>")
		)
		(pad "J31" smd circle
			(at -13.008356 -23.314914 270)
			(size 0.4318 0.4318)
			(layers "F.Cu" "F.Mask" "F.Paste")
			(net "M_A_CPU1_SB_DQ<1>")
		)
		(pad "J33" smd circle
			(at -11.380724 -23.314914 270)
			(size 0.4318 0.4318)
			(layers "F.Cu" "F.Mask" "F.Paste")
			(net "GND")
		)
		(pad "J35" smd circle
			(at -9.752838 -23.314914 270)
			(size 0.4318 0.4318)
			(layers "F.Cu" "F.Mask" "F.Paste")
			(net "M_B_CPU1_SB_CB<0>")
		)
		(pad "J37" smd circle
			(at -8.124952 -23.314914 270)
			(size 0.4318 0.4318)
			(layers "F.Cu" "F.Mask" "F.Paste")
			(net "M_B_CPU1_SB_CB<5>")
		)
		(pad "J39" smd circle
			(at -6.49732 -23.314914 270)
			(size 0.4318 0.4318)
			(layers "F.Cu" "F.Mask" "F.Paste")
			(net "GND")
		)
		(pad "J41" smd circle
			(at -4.869434 -23.314914 270)
			(size 0.4318 0.4318)
			(layers "F.Cu" "F.Mask" "F.Paste")
			(net "M_B_CPU1_SB_CS_N<0>")
		)
		(pad "J43" smd circle
			(at -3.241802 -23.314914 270)
			(size 0.4318 0.4318)
			(layers "F.Cu" "F.Mask" "F.Paste")
			(net "M_B_CPU1_SB_CA<4>")
		)
		(pad "J45" smd circle
			(at -1.613916 -23.314914 270)
			(size 0.4318 0.4318)
			(layers "F.Cu" "F.Mask" "F.Paste")
			(net "GND")
		)
		(pad "J48" smd circle
			(at 2.427732 -23.204932 270)
			(size 0.4318 0.4318)
			(layers "F.Cu" "F.Mask" "F.Paste")
			(net "M_B_CPU1_SA_CA<2>")
		)
		(pad "J50" smd circle
			(at 4.055618 -23.204932 270)
			(size 0.4318 0.4318)
			(layers "F.Cu" "F.Mask" "F.Paste")
			(net "M_B_CPU1_SA_CS_N<1>")
		)
		(pad "J52" smd circle
			(at 5.68325 -23.204932 270)
			(size 0.4318 0.4318)
			(layers "F.Cu" "F.Mask" "F.Paste")
			(net "GND")
		)
		(pad "J54" smd circle
			(at 7.311136 -23.204932 270)
			(size 0.4318 0.4318)
			(layers "F.Cu" "F.Mask" "F.Paste")
			(net "M_B_CPU1_SA_CB<4>")
		)
		(pad "J56" smd circle
			(at 8.939022 -23.204932 270)
			(size 0.4318 0.4318)
			(layers "F.Cu" "F.Mask" "F.Paste")
			(net "M_B_CPU1_SA_CB<1>")
		)
		(pad "J58" smd circle
			(at 10.566654 -23.204932 270)
			(size 0.4318 0.4318)
			(layers "F.Cu" "F.Mask" "F.Paste")
			(net "GND")
		)
		(pad "J60" smd circle
			(at 12.19454 -23.204932 270)
			(size 0.4318 0.4318)
			(layers "F.Cu" "F.Mask" "F.Paste")
			(net "M_B_CPU1_SA_DQ<20>")
		)
		(pad "J62" smd circle
			(at 13.822426 -23.204932 270)
			(size 0.4318 0.4318)
			(layers "F.Cu" "F.Mask" "F.Paste")
			(net "M_B_CPU1_SA_DQ<17>")
		)
		(pad "J64" smd circle
			(at 15.450058 -23.204932 270)
			(size 0.4318 0.4318)
			(layers "F.Cu" "F.Mask" "F.Paste")
			(net "GND")
		)
		(pad "J66" smd circle
			(at 17.07769 -23.204932 270)
			(size 0.4318 0.4318)
			(layers "F.Cu" "F.Mask" "F.Paste")
			(net "M_A_CPU1_SA_DQ<12>")
		)
		(pad "J68" smd circle
			(at 18.705576 -23.204932 270)
			(size 0.4318 0.4318)
			(layers "F.Cu" "F.Mask" "F.Paste")
			(net "M_A_CPU1_SA_DQ<9>")
		)
		(pad "J70" smd circle
			(at 20.333462 -23.204932 270)
			(size 0.4318 0.4318)
			(layers "F.Cu" "F.Mask" "F.Paste")
			(net "GND")
		)
		(pad "J72" smd circle
			(at 21.961094 -23.204932 270)
			(size 0.4318 0.4318)
			(layers "F.Cu" "F.Mask" "F.Paste")
			(net "M_B_CPU1_SA_DQ<4>")
		)
		(pad "J74" smd circle
			(at 23.58898 -23.204932 270)
			(size 0.4318 0.4318)
			(layers "F.Cu" "F.Mask" "F.Paste")
			(net "M_B_CPU1_SA_DQ<1>")
		)
		(pad "J76" smd circle
			(at 25.216612 -23.204932 270)
			(size 0.4318 0.4318)
			(layers "F.Cu" "F.Mask" "F.Paste")
			(net "GND")
		)
		(pad "J78" smd circle
			(at 26.844498 -23.204932 270)
			(size 0.4318 0.4318)
			(layers "F.Cu" "F.Mask" "F.Paste")
			(net "GND")
		)
		(pad "J80" smd circle
			(at 28.472384 -23.204932 270)
			(size 0.4318 0.4318)
			(layers "F.Cu" "F.Mask" "F.Paste")
			(net "PVCCFA_EHV_FIVRA_CPU1")
		)
		(pad "J82" smd circle
			(at 30.100016 -23.204932 270)
			(size 0.4318 0.4318)
			(layers "F.Cu" "F.Mask" "F.Paste")
			(net "UPI_CPU0_CPU1_P2P2_DN<4>")
		)
		(pad "J84" smd circle
			(at 31.727902 -23.204932 270)
			(size 0.4318 0.4318)
			(layers "F.Cu" "F.Mask" "F.Paste")
			(net "GND")
		)
		(pad "J86" smd circle
			(at 33.355534 -23.204932 270)
			(size 0.4318 0.4318)
			(layers "F.Cu" "F.Mask" "F.Paste")
			(net "GND")
		)
		(pad "J88" smd circle
			(at 34.98342 -23.204932 270)
			(size 0.4318 0.4318)
			(layers "F.Cu" "F.Mask" "F.Paste")
			(net "GND")
		)
		(pad "J90" smd oval
			(at 36.611306 -23.204932 45)
			(size 0.381 0.4826)
			(drill
				(offset 0 -0.0508)
			)
			(layers "F.Cu" "F.Mask" "F.Paste")
			(net "P5E_CPU1_PE4_RX_DN<0>")
		)
		(pad "K2" smd oval
			(at -36.611306 -22.845268 135)
			(size 0.381 0.4826)
			(drill
				(offset 0 -0.0508)
			)
			(layers "F.Cu" "F.Mask" "F.Paste")
			(net "GND")
		)
		(pad "K4" smd circle
			(at -34.98342 -22.845268 270)
			(size 0.4318 0.4318)
			(layers "F.Cu" "F.Mask" "F.Paste")
			(net "UPI_CPU1_CPU0_P0P1_DN<0>")
		)
		(pad "K6" smd circle
			(at -33.355534 -22.845268 270)
			(size 0.4318 0.4318)
			(layers "F.Cu" "F.Mask" "F.Paste")
			(net "UPI_CPU0_CPU1_P1P0_DN<0>")
		)
		(pad "K8" smd circle
			(at -31.727902 -22.845268 270)
			(size 0.4318 0.4318)
			(layers "F.Cu" "F.Mask" "F.Paste")
			(net "GND")
		)
		(pad "K10" smd circle
			(at -30.100016 -22.845268 270)
			(size 0.4318 0.4318)
			(layers "F.Cu" "F.Mask" "F.Paste")
			(net "P5E_CPU1_PE0_RX_DN<0>")
		)
		(pad "K12" smd circle
			(at -28.472384 -22.845268 270)
			(size 0.4318 0.4318)
			(layers "F.Cu" "F.Mask" "F.Paste")
			(net "GND")
		)
		(pad "K14" smd circle
			(at -26.844498 -22.845268 270)
			(size 0.4318 0.4318)
			(layers "F.Cu" "F.Mask" "F.Paste")
			(net "GND")
		)
		(pad "K16" smd circle
			(at -25.216612 -22.845268 270)
			(size 0.4318 0.4318)
			(layers "F.Cu" "F.Mask" "F.Paste")
			(net "M_B_CPU1_SB_DQ<21>")
		)
		(pad "K18" smd circle
			(at -23.58898 -22.845268 270)
			(size 0.4318 0.4318)
			(layers "F.Cu" "F.Mask" "F.Paste")
			(net "M_B_CPU1_SB_DQS_DP<2>")
		)
		(pad "K20" smd circle
			(at -21.961094 -22.845268 270)
			(size 0.4318 0.4318)
			(layers "F.Cu" "F.Mask" "F.Paste")
			(net "M_B_CPU1_SB_DQ<16>")
		)
		(pad "K22" smd circle
			(at -20.333462 -22.845268 270)
			(size 0.4318 0.4318)
			(layers "F.Cu" "F.Mask" "F.Paste")
			(net "M_B_CPU1_SB_DQ<13>")
		)
		(pad "K24" smd circle
			(at -18.705576 -22.845268 270)
			(size 0.4318 0.4318)
			(layers "F.Cu" "F.Mask" "F.Paste")
			(net "M_B_CPU1_SB_DQS_DP<1>")
		)
		(pad "K26" smd circle
			(at -17.07769 -22.845268 270)
			(size 0.4318 0.4318)
			(layers "F.Cu" "F.Mask" "F.Paste")
			(net "M_B_CPU1_SB_DQ<8>")
		)
		(pad "K28" smd circle
			(at -15.450058 -22.845268 270)
			(size 0.4318 0.4318)
			(layers "F.Cu" "F.Mask" "F.Paste")
			(net "M_A_CPU1_SB_DQ<5>")
		)
		(pad "K30" smd circle
			(at -13.822426 -22.845268 270)
			(size 0.4318 0.4318)
			(layers "F.Cu" "F.Mask" "F.Paste")
			(net "M_A_CPU1_SB_DQS_DP<0>")
		)
		(pad "K32" smd circle
			(at -12.19454 -22.845268 270)
			(size 0.4318 0.4318)
			(layers "F.Cu" "F.Mask" "F.Paste")
			(net "M_A_CPU1_SB_DQ<0>")
		)
		(pad "K34" smd circle
			(at -10.566654 -22.845268 270)
			(size 0.4318 0.4318)
			(layers "F.Cu" "F.Mask" "F.Paste")
			(net "M_B_CPU1_SB_CB<1>")
		)
		(pad "K36" smd circle
			(at -8.939022 -22.845268 270)
			(size 0.4318 0.4318)
			(layers "F.Cu" "F.Mask" "F.Paste")
			(net "M_B_CPU1_SB_DQS_DN<9>")
		)
		(pad "K38" smd circle
			(at -7.311136 -22.845268 270)
			(size 0.4318 0.4318)
			(layers "F.Cu" "F.Mask" "F.Paste")
			(net "M_B_CPU1_SB_CB<4>")
		)
		(pad "K40" smd circle
			(at -5.68325 -22.845268 270)
			(size 0.4318 0.4318)
			(layers "F.Cu" "F.Mask" "F.Paste")
			(net "M_B_CPU1_SB_CS_N<1>")
		)
		(pad "K42" smd circle
			(at -4.055618 -22.845268 270)
			(size 0.4318 0.4318)
			(layers "F.Cu" "F.Mask" "F.Paste")
			(net "GND")
		)
		(pad "K44" smd circle
			(at -2.427732 -22.845268 270)
			(size 0.4318 0.4318)
			(layers "F.Cu" "F.Mask" "F.Paste")
			(net "M_B_CPU1_SB_CA<2>")
		)
		(pad "K47" smd circle
			(at 1.613916 -22.735286 270)
			(size 0.4318 0.4318)
			(layers "F.Cu" "F.Mask" "F.Paste")
			(net "M_B_CPU1_SA_CA<4>")
		)
		(pad "K49" smd circle
			(at 3.241802 -22.735286 270)
			(size 0.4318 0.4318)
			(layers "F.Cu" "F.Mask" "F.Paste")
			(net "GND")
		)
		(pad "K51" smd circle
			(at 4.869434 -22.735286 270)
			(size 0.4318 0.4318)
			(layers "F.Cu" "F.Mask" "F.Paste")
			(net "M_B_CPU1_SA_CS_N<0>")
		)
		(pad "K53" smd circle
			(at 6.49732 -22.735286 270)
			(size 0.4318 0.4318)
			(layers "F.Cu" "F.Mask" "F.Paste")
			(net "M_B_CPU1_SA_CB<5>")
		)
		(pad "K55" smd circle
			(at 8.124952 -22.735286 270)
			(size 0.4318 0.4318)
			(layers "F.Cu" "F.Mask" "F.Paste")
			(net "M_B_CPU1_SA_DQS_DP<4>")
		)
		(pad "K57" smd circle
			(at 9.752838 -22.735286 270)
			(size 0.4318 0.4318)
			(layers "F.Cu" "F.Mask" "F.Paste")
			(net "M_B_CPU1_SA_CB<0>")
		)
		(pad "K59" smd circle
			(at 11.380724 -22.735286 270)
			(size 0.4318 0.4318)
			(layers "F.Cu" "F.Mask" "F.Paste")
			(net "M_B_CPU1_SA_DQ<21>")
		)
		(pad "K61" smd circle
			(at 13.008356 -22.735286 270)
			(size 0.4318 0.4318)
			(layers "F.Cu" "F.Mask" "F.Paste")
			(net "M_B_CPU1_SA_DQS_DP<2>")
		)
		(pad "K63" smd circle
			(at 14.635988 -22.735286 270)
			(size 0.4318 0.4318)
			(layers "F.Cu" "F.Mask" "F.Paste")
			(net "M_B_CPU1_SA_DQ<16>")
		)
		(pad "K65" smd circle
			(at 16.263874 -22.735286 270)
			(size 0.4318 0.4318)
			(layers "F.Cu" "F.Mask" "F.Paste")
			(net "M_A_CPU1_SA_DQ<13>")
		)
		(pad "K67" smd circle
			(at 17.89176 -22.735286 270)
			(size 0.4318 0.4318)
			(layers "F.Cu" "F.Mask" "F.Paste")
			(net "M_A_CPU1_SA_DQS_DP<1>")
		)
		(pad "K69" smd circle
			(at 19.519392 -22.735286 270)
			(size 0.4318 0.4318)
			(layers "F.Cu" "F.Mask" "F.Paste")
			(net "M_A_CPU1_SA_DQ<8>")
		)
		(pad "K71" smd circle
			(at 21.147278 -22.735286 270)
			(size 0.4318 0.4318)
			(layers "F.Cu" "F.Mask" "F.Paste")
			(net "M_B_CPU1_SA_DQ<5>")
		)
		(pad "K73" smd circle
			(at 22.77491 -22.735286 270)
			(size 0.4318 0.4318)
			(layers "F.Cu" "F.Mask" "F.Paste")
			(net "M_B_CPU1_SA_DQS_DP<0>")
		)
		(pad "K75" smd circle
			(at 24.402796 -22.735286 270)
			(size 0.4318 0.4318)
			(layers "F.Cu" "F.Mask" "F.Paste")
			(net "M_B_CPU1_SA_DQ<0>")
		)
		(pad "K77" smd circle
			(at 26.030682 -22.735286 270)
			(size 0.4318 0.4318)
			(layers "F.Cu" "F.Mask" "F.Paste")
			(net "GND")
		)
		(pad "K79" smd circle
			(at 27.658314 -22.735286 270)
			(size 0.4318 0.4318)
			(layers "F.Cu" "F.Mask" "F.Paste")
			(net "UPI_CPU0_CPU1_P2P2_DN<3>")
		)
		(pad "K81" smd circle
			(at 29.2862 -22.735286 270)
			(size 0.4318 0.4318)
			(layers "F.Cu" "F.Mask" "F.Paste")
			(net "UPI_CPU0_CPU1_P2P2_DP<5>")
		)
		(pad "K83" smd circle
			(at 30.914086 -22.735286 270)
			(size 0.4318 0.4318)
			(layers "F.Cu" "F.Mask" "F.Paste")
			(net "GND")
		)
		(pad "K85" smd circle
			(at 32.541718 -22.735286 270)
			(size 0.4318 0.4318)
			(layers "F.Cu" "F.Mask" "F.Paste")
			(net "GND")
		)
		(pad "K87" smd circle
			(at 34.169604 -22.735286 270)
			(size 0.4318 0.4318)
			(layers "F.Cu" "F.Mask" "F.Paste")
			(net "PVCCFA_EHV_FIVRA_CPU1")
		)
		(pad "K89" smd circle
			(at 35.797236 -22.735286 270)
			(size 0.4318 0.4318)
			(layers "F.Cu" "F.Mask" "F.Paste")
			(net "P5E_CPU1_PE4_RX_DP<0>")
		)
		(pad "L3" smd circle
			(at -35.797236 -22.375114 270)
			(size 0.4318 0.4318)
			(layers "F.Cu" "F.Mask" "F.Paste")
			(net "UPI_CPU1_CPU0_P0P1_DP<1>")
		)
		(pad "L5" smd circle
			(at -34.169604 -22.375114 270)
			(size 0.4318 0.4318)
			(layers "F.Cu" "F.Mask" "F.Paste")
			(net "GND")
		)
		(pad "L7" smd circle
			(at -32.541718 -22.375114 270)
			(size 0.4318 0.4318)
			(layers "F.Cu" "F.Mask" "F.Paste")
			(net "UPI_CPU0_CPU1_P1P0_DP<0>")
		)
		(pad "L9" smd circle
			(at -30.914086 -22.375114 270)
			(size 0.4318 0.4318)
			(layers "F.Cu" "F.Mask" "F.Paste")
			(net "GND")
		)
		(pad "L11" smd circle
			(at -29.2862 -22.375114 270)
			(size 0.4318 0.4318)
			(layers "F.Cu" "F.Mask" "F.Paste")
			(net "P5E_CPU1_PE0_RX_DP<0>")
		)
		(pad "L13" smd circle
			(at -27.658314 -22.375114 270)
			(size 0.4318 0.4318)
			(layers "F.Cu" "F.Mask" "F.Paste")
			(net "GND")
		)
		(pad "L15" smd circle
			(at -26.030682 -22.375114 270)
			(size 0.4318 0.4318)
			(layers "F.Cu" "F.Mask" "F.Paste")
			(net "GND")
		)
		(pad "L17" smd circle
			(at -24.402796 -22.375114 270)
			(size 0.4318 0.4318)
			(layers "F.Cu" "F.Mask" "F.Paste")
			(net "GND")
		)
		(pad "L19" smd circle
			(at -22.77491 -22.375114 270)
			(size 0.4318 0.4318)
			(layers "F.Cu" "F.Mask" "F.Paste")
			(net "GND")
		)
		(pad "L21" smd circle
			(at -21.147278 -22.375114 270)
			(size 0.4318 0.4318)
			(layers "F.Cu" "F.Mask" "F.Paste")
			(net "GND")
		)
		(pad "L23" smd circle
			(at -19.519392 -22.375114 270)
			(size 0.4318 0.4318)
			(layers "F.Cu" "F.Mask" "F.Paste")
			(net "GND")
		)
		(pad "L25" smd circle
			(at -17.89176 -22.375114 270)
			(size 0.4318 0.4318)
			(layers "F.Cu" "F.Mask" "F.Paste")
			(net "GND")
		)
		(pad "L27" smd circle
			(at -16.263874 -22.375114 270)
			(size 0.4318 0.4318)
			(layers "F.Cu" "F.Mask" "F.Paste")
			(net "GND")
		)
		(pad "L29" smd circle
			(at -14.635988 -22.375114 270)
			(size 0.4318 0.4318)
			(layers "F.Cu" "F.Mask" "F.Paste")
			(net "GND")
		)
		(pad "L31" smd circle
			(at -13.008356 -22.375114 270)
			(size 0.4318 0.4318)
			(layers "F.Cu" "F.Mask" "F.Paste")
			(net "GND")
		)
		(pad "L33" smd circle
			(at -11.380724 -22.375114 270)
			(size 0.4318 0.4318)
			(layers "F.Cu" "F.Mask" "F.Paste")
			(net "GND")
		)
		(pad "L35" smd circle
			(at -9.752838 -22.375114 270)
			(size 0.4318 0.4318)
			(layers "F.Cu" "F.Mask" "F.Paste")
			(net "GND")
		)
		(pad "L37" smd circle
			(at -8.124952 -22.375114 270)
			(size 0.4318 0.4318)
			(layers "F.Cu" "F.Mask" "F.Paste")
			(net "GND")
		)
		(pad "L39" smd circle
			(at -6.49732 -22.375114 270)
			(size 0.4318 0.4318)
			(layers "F.Cu" "F.Mask" "F.Paste")
			(net "GND")
		)
		(pad "L41" smd circle
			(at -4.869434 -22.375114 270)
			(size 0.4318 0.4318)
			(layers "F.Cu" "F.Mask" "F.Paste")
			(net "GND")
		)
		(pad "L43" smd circle
			(at -3.241802 -22.375114 270)
			(size 0.4318 0.4318)
			(layers "F.Cu" "F.Mask" "F.Paste")
			(net "GND")
		)
		(pad "L45" smd circle
			(at -1.613916 -22.375114 270)
			(size 0.4318 0.4318)
			(layers "F.Cu" "F.Mask" "F.Paste")
			(net "GND")
		)
		(pad "L48" smd circle
			(at 2.427732 -22.265386 270)
			(size 0.4318 0.4318)
			(layers "F.Cu" "F.Mask" "F.Paste")
			(net "GND")
		)
		(pad "L50" smd circle
			(at 4.055618 -22.265386 270)
			(size 0.4318 0.4318)
			(layers "F.Cu" "F.Mask" "F.Paste")
			(net "GND")
		)
		(pad "L52" smd circle
			(at 5.68325 -22.265386 270)
			(size 0.4318 0.4318)
			(layers "F.Cu" "F.Mask" "F.Paste")
			(net "GND")
		)
		(pad "L54" smd circle
			(at 7.311136 -22.265386 270)
			(size 0.4318 0.4318)
			(layers "F.Cu" "F.Mask" "F.Paste")
			(net "GND")
		)
		(pad "L56" smd circle
			(at 8.939022 -22.265386 270)
			(size 0.4318 0.4318)
			(layers "F.Cu" "F.Mask" "F.Paste")
			(net "GND")
		)
		(pad "L58" smd circle
			(at 10.566654 -22.265386 270)
			(size 0.4318 0.4318)
			(layers "F.Cu" "F.Mask" "F.Paste")
			(net "GND")
		)
		(pad "L60" smd circle
			(at 12.19454 -22.265386 270)
			(size 0.4318 0.4318)
			(layers "F.Cu" "F.Mask" "F.Paste")
			(net "GND")
		)
		(pad "L62" smd circle
			(at 13.822426 -22.265386 270)
			(size 0.4318 0.4318)
			(layers "F.Cu" "F.Mask" "F.Paste")
			(net "GND")
		)
		(pad "L64" smd circle
			(at 15.450058 -22.265386 270)
			(size 0.4318 0.4318)
			(layers "F.Cu" "F.Mask" "F.Paste")
			(net "GND")
		)
		(pad "L66" smd circle
			(at 17.07769 -22.265386 270)
			(size 0.4318 0.4318)
			(layers "F.Cu" "F.Mask" "F.Paste")
			(net "GND")
		)
		(pad "L68" smd circle
			(at 18.705576 -22.265386 270)
			(size 0.4318 0.4318)
			(layers "F.Cu" "F.Mask" "F.Paste")
			(net "GND")
		)
		(pad "L70" smd circle
			(at 20.333462 -22.265386 270)
			(size 0.4318 0.4318)
			(layers "F.Cu" "F.Mask" "F.Paste")
			(net "GND")
		)
		(pad "L72" smd circle
			(at 21.961094 -22.265386 270)
			(size 0.4318 0.4318)
			(layers "F.Cu" "F.Mask" "F.Paste")
			(net "GND")
		)
		(pad "L74" smd circle
			(at 23.58898 -22.265386 270)
			(size 0.4318 0.4318)
			(layers "F.Cu" "F.Mask" "F.Paste")
			(net "GND")
		)
		(pad "L76" smd circle
			(at 25.216612 -22.265386 270)
			(size 0.4318 0.4318)
			(layers "F.Cu" "F.Mask" "F.Paste")
			(net "GND")
		)
		(pad "L78" smd circle
			(at 26.844498 -22.265386 270)
			(size 0.4318 0.4318)
			(layers "F.Cu" "F.Mask" "F.Paste")
			(net "GND")
		)
		(pad "L80" smd circle
			(at 28.472384 -22.265386 270)
			(size 0.4318 0.4318)
			(layers "F.Cu" "F.Mask" "F.Paste")
			(net "UPI_CPU0_CPU1_P2P2_DN<5>")
		)
		(pad "L82" smd circle
			(at 30.100016 -22.265386 270)
			(size 0.4318 0.4318)
			(layers "F.Cu" "F.Mask" "F.Paste")
			(net "UPI_CPU0_CPU1_P2P2_DP<4>")
		)
		(pad "L84" smd circle
			(at 31.727902 -22.265386 270)
			(size 0.4318 0.4318)
			(layers "F.Cu" "F.Mask" "F.Paste")
			(net "PVCCFA_EHV_FIVRA_CPU1")
		)
		(pad "L86" smd circle
			(at 33.355534 -22.265386 270)
			(size 0.4318 0.4318)
			(layers "F.Cu" "F.Mask" "F.Paste")
			(net "P5E_CPU1_PE4_TX_DN<0>")
		)
		(pad "L88" smd circle
			(at 34.98342 -22.265386 270)
			(size 0.4318 0.4318)
			(layers "F.Cu" "F.Mask" "F.Paste")
			(net "GND")
		)
		(pad "L90" smd oval
			(at 36.611306 -22.265386)
			(size 0.381 0.4826)
			(drill
				(offset 0 -0.0508)
			)
			(layers "F.Cu" "F.Mask" "F.Paste")
			(net "GND")
		)
		(pad "M2" smd oval
			(at -36.611306 -21.905468 180)
			(size 0.381 0.4826)
			(drill
				(offset 0 -0.0508)
			)
			(layers "F.Cu" "F.Mask" "F.Paste")
			(net "UPI_CPU1_CPU0_P0P1_DN<1>")
		)
		(pad "M4" smd circle
			(at -34.98342 -21.905468 270)
			(size 0.4318 0.4318)
			(layers "F.Cu" "F.Mask" "F.Paste")
			(net "GND")
		)
		(pad "M6" smd circle
			(at -33.355534 -21.905468 270)
			(size 0.4318 0.4318)
			(layers "F.Cu" "F.Mask" "F.Paste")
			(net "UPI_CPU0_CPU1_P1P0_DP<1>")
		)
		(pad "M8" smd circle
			(at -31.727902 -21.905468 270)
			(size 0.4318 0.4318)
			(layers "F.Cu" "F.Mask" "F.Paste")
			(net "GND")
		)
		(pad "M10" smd circle
			(at -30.100016 -21.905468 270)
			(size 0.4318 0.4318)
			(layers "F.Cu" "F.Mask" "F.Paste")
			(net "P5E_CPU1_PE0_RX_DN<1>")
		)
		(pad "M12" smd circle
			(at -28.472384 -21.905468 270)
			(size 0.4318 0.4318)
			(layers "F.Cu" "F.Mask" "F.Paste")
			(net "GND")
		)
		(pad "M14" smd circle
			(at -26.844498 -21.905468 270)
			(size 0.4318 0.4318)
			(layers "F.Cu" "F.Mask" "F.Paste")
			(net "P5E_CPU1_PE0_TX_DP<0>")
		)
		(pad "M16" smd circle
			(at -25.216612 -21.905468 270)
			(size 0.4318 0.4318)
			(layers "F.Cu" "F.Mask" "F.Paste")
			(net "M_B_CPU1_SB_DQ<23>")
		)
		(pad "M18" smd circle
			(at -23.58898 -21.905468 270)
			(size 0.4318 0.4318)
			(layers "F.Cu" "F.Mask" "F.Paste")
			(net "M_B_CPU1_SB_DQS_DN<7>")
		)
		(pad "M20" smd circle
			(at -21.961094 -21.905468 270)
			(size 0.4318 0.4318)
			(layers "F.Cu" "F.Mask" "F.Paste")
			(net "M_B_CPU1_SB_DQ<18>")
		)
		(pad "M22" smd circle
			(at -20.333462 -21.905468 270)
			(size 0.4318 0.4318)
			(layers "F.Cu" "F.Mask" "F.Paste")
			(net "M_B_CPU1_SB_DQ<15>")
		)
		(pad "M24" smd circle
			(at -18.705576 -21.905468 270)
			(size 0.4318 0.4318)
			(layers "F.Cu" "F.Mask" "F.Paste")
			(net "M_B_CPU1_SB_DQS_DN<6>")
		)
		(pad "M26" smd circle
			(at -17.07769 -21.905468 270)
			(size 0.4318 0.4318)
			(layers "F.Cu" "F.Mask" "F.Paste")
			(net "M_B_CPU1_SB_DQ<10>")
		)
		(pad "M28" smd circle
			(at -15.450058 -21.905468 270)
			(size 0.4318 0.4318)
			(layers "F.Cu" "F.Mask" "F.Paste")
			(net "M_A_CPU1_SB_DQ<7>")
		)
		(pad "M30" smd circle
			(at -13.822426 -21.905468 270)
			(size 0.4318 0.4318)
			(layers "F.Cu" "F.Mask" "F.Paste")
			(net "M_A_CPU1_SB_DQS_DN<5>")
		)
		(pad "M32" smd circle
			(at -12.19454 -21.905468 270)
			(size 0.4318 0.4318)
			(layers "F.Cu" "F.Mask" "F.Paste")
			(net "M_A_CPU1_SB_DQ<2>")
		)
		(pad "M34" smd circle
			(at -10.566654 -21.905468 270)
			(size 0.4318 0.4318)
			(layers "F.Cu" "F.Mask" "F.Paste")
			(net "M_B_CPU1_SB_CB<3>")
		)
		(pad "M36" smd circle
			(at -8.939022 -21.905468 270)
			(size 0.4318 0.4318)
			(layers "F.Cu" "F.Mask" "F.Paste")
			(net "M_B_CPU1_SB_DQS_DP<4>")
		)
		(pad "M38" smd circle
			(at -7.311136 -21.905468 270)
			(size 0.4318 0.4318)
			(layers "F.Cu" "F.Mask" "F.Paste")
			(net "M_B_CPU1_SB_CB<6>")
		)
		(pad "M40" smd circle
			(at -5.68325 -21.905468 270)
			(size 0.4318 0.4318)
			(layers "F.Cu" "F.Mask" "F.Paste")
			(net "M_B_CPU1_SB_CS_N<3>")
		)
		(pad "M42" smd circle
			(at -4.055618 -21.905468 270)
			(size 0.4318 0.4318)
			(layers "F.Cu" "F.Mask" "F.Paste")
			(net "GND")
		)
		(pad "M44" smd circle
			(at -2.427732 -21.905468 270)
			(size 0.4318 0.4318)
			(layers "F.Cu" "F.Mask" "F.Paste")
			(net "M_B_CPU1_SB_CA<3>")
		)
		(pad "M47" smd circle
			(at 1.613916 -21.795486 270)
			(size 0.4318 0.4318)
			(layers "F.Cu" "F.Mask" "F.Paste")
			(net "M_B_CPU1_SA_CA<5>")
		)
		(pad "M49" smd circle
			(at 3.241802 -21.795486 270)
			(size 0.4318 0.4318)
			(layers "F.Cu" "F.Mask" "F.Paste")
			(net "GND")
		)
		(pad "M51" smd circle
			(at 4.869434 -21.795486 270)
			(size 0.4318 0.4318)
			(layers "F.Cu" "F.Mask" "F.Paste")
			(net "M_B_CPU1_SA_CS_N<2>")
		)
		(pad "M53" smd circle
			(at 6.49732 -21.795486 270)
			(size 0.4318 0.4318)
			(layers "F.Cu" "F.Mask" "F.Paste")
			(net "M_B_CPU1_SA_CB<7>")
		)
		(pad "M55" smd circle
			(at 8.124952 -21.795486 270)
			(size 0.4318 0.4318)
			(layers "F.Cu" "F.Mask" "F.Paste")
			(net "M_B_CPU1_SA_DQS_DN<9>")
		)
		(pad "M57" smd circle
			(at 9.752838 -21.795486 270)
			(size 0.4318 0.4318)
			(layers "F.Cu" "F.Mask" "F.Paste")
			(net "M_B_CPU1_SA_CB<2>")
		)
		(pad "M59" smd circle
			(at 11.380724 -21.795486 270)
			(size 0.4318 0.4318)
			(layers "F.Cu" "F.Mask" "F.Paste")
			(net "M_B_CPU1_SA_DQ<23>")
		)
		(pad "M61" smd circle
			(at 13.008356 -21.795486 270)
			(size 0.4318 0.4318)
			(layers "F.Cu" "F.Mask" "F.Paste")
			(net "M_B_CPU1_SA_DQS_DN<7>")
		)
		(pad "M63" smd circle
			(at 14.635988 -21.795486 270)
			(size 0.4318 0.4318)
			(layers "F.Cu" "F.Mask" "F.Paste")
			(net "M_B_CPU1_SA_DQ<18>")
		)
		(pad "M65" smd circle
			(at 16.263874 -21.795486 270)
			(size 0.4318 0.4318)
			(layers "F.Cu" "F.Mask" "F.Paste")
			(net "M_A_CPU1_SA_DQ<15>")
		)
		(pad "M67" smd circle
			(at 17.89176 -21.795486 270)
			(size 0.4318 0.4318)
			(layers "F.Cu" "F.Mask" "F.Paste")
			(net "M_A_CPU1_SA_DQS_DP<6>")
		)
		(pad "M69" smd circle
			(at 19.519392 -21.795486 270)
			(size 0.4318 0.4318)
			(layers "F.Cu" "F.Mask" "F.Paste")
			(net "M_A_CPU1_SA_DQ<10>")
		)
		(pad "M71" smd circle
			(at 21.147278 -21.795486 270)
			(size 0.4318 0.4318)
			(layers "F.Cu" "F.Mask" "F.Paste")
			(net "M_B_CPU1_SA_DQ<7>")
		)
		(pad "M73" smd circle
			(at 22.77491 -21.795486 270)
			(size 0.4318 0.4318)
			(layers "F.Cu" "F.Mask" "F.Paste")
			(net "M_B_CPU1_SA_DQS_DN<5>")
		)
		(pad "M75" smd circle
			(at 24.402796 -21.795486 270)
			(size 0.4318 0.4318)
			(layers "F.Cu" "F.Mask" "F.Paste")
			(net "M_B_CPU1_SA_DQ<2>")
		)
		(pad "M77" smd circle
			(at 26.030682 -21.795486 270)
			(size 0.4318 0.4318)
			(layers "F.Cu" "F.Mask" "F.Paste")
			(net "M_A_CPU1_SA_DQ<2>")
		)
		(pad "M79" smd circle
			(at 27.658314 -21.795486 270)
			(size 0.4318 0.4318)
			(layers "F.Cu" "F.Mask" "F.Paste")
			(net "UPI_CPU0_CPU1_P2P2_DP<3>")
		)
		(pad "M81" smd circle
			(at 29.2862 -21.795486 270)
			(size 0.4318 0.4318)
			(layers "F.Cu" "F.Mask" "F.Paste")
			(net "GND")
		)
		(pad "M83" smd circle
			(at 30.914086 -21.795486 270)
			(size 0.4318 0.4318)
			(layers "F.Cu" "F.Mask" "F.Paste")
			(net "GND")
		)
		(pad "M85" smd circle
			(at 32.541718 -21.795486 270)
			(size 0.4318 0.4318)
			(layers "F.Cu" "F.Mask" "F.Paste")
			(net "PVCCFA_EHV_FIVRA_CPU1")
		)
		(pad "M87" smd circle
			(at 34.169604 -21.795486 270)
			(size 0.4318 0.4318)
			(layers "F.Cu" "F.Mask" "F.Paste")
			(net "P5E_CPU1_PE4_TX_DP<0>")
		)
		(pad "M89" smd circle
			(at 35.797236 -21.795486 270)
			(size 0.4318 0.4318)
			(layers "F.Cu" "F.Mask" "F.Paste")
			(net "PVCCFA_EHV_FIVRA_CPU1")
		)
		(pad "N1" smd oval
			(at -37.425122 -21.435314 180)
			(size 0.381 0.4826)
			(drill
				(offset 0 -0.0508)
			)
			(layers "F.Cu" "F.Mask" "F.Paste")
			(net "UPI_CPU1_CPU0_P0P1_DN<2>")
		)
		(pad "N3" smd circle
			(at -35.797236 -21.435314 270)
			(size 0.4318 0.4318)
			(layers "F.Cu" "F.Mask" "F.Paste")
			(net "PVCCFA_EHV_CPU1")
		)
		(pad "N5" smd circle
			(at -34.169604 -21.435314 270)
			(size 0.4318 0.4318)
			(layers "F.Cu" "F.Mask" "F.Paste")
			(net "UPI_CPU0_CPU1_P1P0_DN<1>")
		)
		(pad "N7" smd circle
			(at -32.541718 -21.435314 270)
			(size 0.4318 0.4318)
			(layers "F.Cu" "F.Mask" "F.Paste")
			(net "PVCCFA_EHV_FIVRA_CPU1")
		)
		(pad "N9" smd circle
			(at -30.914086 -21.435314 270)
			(size 0.4318 0.4318)
			(layers "F.Cu" "F.Mask" "F.Paste")
			(net "P5E_CPU1_PE0_RX_DP<1>")
		)
		(pad "N11" smd circle
			(at -29.2862 -21.435314 270)
			(size 0.4318 0.4318)
			(layers "F.Cu" "F.Mask" "F.Paste")
			(net "PVCCFA_EHV_FIVRA_CPU1")
		)
		(pad "N13" smd circle
			(at -27.658314 -21.435314 270)
			(size 0.4318 0.4318)
			(layers "F.Cu" "F.Mask" "F.Paste")
			(net "P5E_CPU1_PE0_TX_DN<0>")
		)
		(pad "N15" smd circle
			(at -26.030682 -21.435314 270)
			(size 0.4318 0.4318)
			(layers "F.Cu" "F.Mask" "F.Paste")
			(net "GND")
		)
		(pad "N17" smd circle
			(at -24.402796 -21.435314 270)
			(size 0.4318 0.4318)
			(layers "F.Cu" "F.Mask" "F.Paste")
			(net "M_B_CPU1_SB_DQ<22>")
		)
		(pad "N19" smd circle
			(at -22.77491 -21.435314 270)
			(size 0.4318 0.4318)
			(layers "F.Cu" "F.Mask" "F.Paste")
			(net "M_B_CPU1_SB_DQ<19>")
		)
		(pad "N21" smd circle
			(at -21.147278 -21.435314 270)
			(size 0.4318 0.4318)
			(layers "F.Cu" "F.Mask" "F.Paste")
			(net "GND")
		)
		(pad "N23" smd circle
			(at -19.519392 -21.435314 270)
			(size 0.4318 0.4318)
			(layers "F.Cu" "F.Mask" "F.Paste")
			(net "M_B_CPU1_SB_DQ<14>")
		)
		(pad "N25" smd circle
			(at -17.89176 -21.435314 270)
			(size 0.4318 0.4318)
			(layers "F.Cu" "F.Mask" "F.Paste")
			(net "M_B_CPU1_SB_DQ<11>")
		)
		(pad "N27" smd circle
			(at -16.263874 -21.435314 270)
			(size 0.4318 0.4318)
			(layers "F.Cu" "F.Mask" "F.Paste")
			(net "GND")
		)
		(pad "N29" smd circle
			(at -14.635988 -21.435314 270)
			(size 0.4318 0.4318)
			(layers "F.Cu" "F.Mask" "F.Paste")
			(net "M_A_CPU1_SB_DQ<6>")
		)
		(pad "N31" smd circle
			(at -13.008356 -21.435314 270)
			(size 0.4318 0.4318)
			(layers "F.Cu" "F.Mask" "F.Paste")
			(net "M_A_CPU1_SB_DQ<3>")
		)
		(pad "N33" smd circle
			(at -11.380724 -21.435314 270)
			(size 0.4318 0.4318)
			(layers "F.Cu" "F.Mask" "F.Paste")
			(net "GND")
		)
		(pad "N35" smd circle
			(at -9.752838 -21.435314 270)
			(size 0.4318 0.4318)
			(layers "F.Cu" "F.Mask" "F.Paste")
			(net "M_B_CPU1_SB_CB<2>")
		)
		(pad "N37" smd circle
			(at -8.124952 -21.435314 270)
			(size 0.4318 0.4318)
			(layers "F.Cu" "F.Mask" "F.Paste")
			(net "M_B_CPU1_SB_CB<7>")
		)
		(pad "N39" smd circle
			(at -6.49732 -21.435314 270)
			(size 0.4318 0.4318)
			(layers "F.Cu" "F.Mask" "F.Paste")
			(net "GND")
		)
		(pad "N41" smd circle
			(at -4.869434 -21.435314 270)
			(size 0.4318 0.4318)
			(layers "F.Cu" "F.Mask" "F.Paste")
			(net "M_B_CPU1_SB_CS_N<2>")
		)
		(pad "N43" smd circle
			(at -3.241802 -21.435314 270)
			(size 0.4318 0.4318)
			(layers "F.Cu" "F.Mask" "F.Paste")
			(net "M_B_CPU1_SB_CA<5>")
		)
		(pad "N45" smd circle
			(at -1.613916 -21.435314 270)
			(size 0.4318 0.4318)
			(layers "F.Cu" "F.Mask" "F.Paste")
			(net "GND")
		)
		(pad "N48" smd circle
			(at 2.427732 -21.325332 270)
			(size 0.4318 0.4318)
			(layers "F.Cu" "F.Mask" "F.Paste")
			(net "M_B_CPU1_SA_CA<3>")
		)
		(pad "N50" smd circle
			(at 4.055618 -21.325332 270)
			(size 0.4318 0.4318)
			(layers "F.Cu" "F.Mask" "F.Paste")
			(net "M_B_CPU1_SA_CS_N<3>")
		)
		(pad "N52" smd circle
			(at 5.68325 -21.325332 270)
			(size 0.4318 0.4318)
			(layers "F.Cu" "F.Mask" "F.Paste")
			(net "GND")
		)
		(pad "N54" smd circle
			(at 7.311136 -21.325332 270)
			(size 0.4318 0.4318)
			(layers "F.Cu" "F.Mask" "F.Paste")
			(net "M_B_CPU1_SA_CB<6>")
		)
		(pad "N56" smd circle
			(at 8.939022 -21.325332 270)
			(size 0.4318 0.4318)
			(layers "F.Cu" "F.Mask" "F.Paste")
			(net "M_B_CPU1_SA_CB<3>")
		)
		(pad "N58" smd circle
			(at 10.566654 -21.325332 270)
			(size 0.4318 0.4318)
			(layers "F.Cu" "F.Mask" "F.Paste")
			(net "GND")
		)
		(pad "N60" smd circle
			(at 12.19454 -21.325332 270)
			(size 0.4318 0.4318)
			(layers "F.Cu" "F.Mask" "F.Paste")
			(net "M_B_CPU1_SA_DQ<22>")
		)
		(pad "N62" smd circle
			(at 13.822426 -21.325332 270)
			(size 0.4318 0.4318)
			(layers "F.Cu" "F.Mask" "F.Paste")
			(net "M_B_CPU1_SA_DQ<19>")
		)
		(pad "N64" smd circle
			(at 15.450058 -21.325332 270)
			(size 0.4318 0.4318)
			(layers "F.Cu" "F.Mask" "F.Paste")
			(net "GND")
		)
		(pad "N66" smd circle
			(at 17.07769 -21.325332 270)
			(size 0.4318 0.4318)
			(layers "F.Cu" "F.Mask" "F.Paste")
			(net "M_A_CPU1_SA_DQ<14>")
		)
		(pad "N68" smd circle
			(at 18.705576 -21.325332 270)
			(size 0.4318 0.4318)
			(layers "F.Cu" "F.Mask" "F.Paste")
			(net "M_A_CPU1_SA_DQ<11>")
		)
		(pad "N70" smd circle
			(at 20.333462 -21.325332 270)
			(size 0.4318 0.4318)
			(layers "F.Cu" "F.Mask" "F.Paste")
			(net "GND")
		)
		(pad "N72" smd circle
			(at 21.961094 -21.325332 270)
			(size 0.4318 0.4318)
			(layers "F.Cu" "F.Mask" "F.Paste")
			(net "M_B_CPU1_SA_DQ<6>")
		)
		(pad "N74" smd circle
			(at 23.58898 -21.325332 270)
			(size 0.4318 0.4318)
			(layers "F.Cu" "F.Mask" "F.Paste")
			(net "M_B_CPU1_SA_DQ<3>")
		)
		(pad "N76" smd circle
			(at 25.216612 -21.325332 270)
			(size 0.4318 0.4318)
			(layers "F.Cu" "F.Mask" "F.Paste")
			(net "GND")
		)
		(pad "N78" smd circle
			(at 26.844498 -21.325332 270)
			(size 0.4318 0.4318)
			(layers "F.Cu" "F.Mask" "F.Paste")
			(net "GND")
		)
		(pad "N80" smd circle
			(at 28.472384 -21.325332 270)
			(size 0.4318 0.4318)
			(layers "F.Cu" "F.Mask" "F.Paste")
			(net "GND")
		)
		(pad "N82" smd circle
			(at 30.100016 -21.325332 270)
			(size 0.4318 0.4318)
			(layers "F.Cu" "F.Mask" "F.Paste")
			(net "GND")
		)
		(pad "N84" smd circle
			(at 31.727902 -21.325332 270)
			(size 0.4318 0.4318)
			(layers "F.Cu" "F.Mask" "F.Paste")
			(net "GND")
		)
		(pad "N86" smd circle
			(at 33.355534 -21.325332 270)
			(size 0.4318 0.4318)
			(layers "F.Cu" "F.Mask" "F.Paste")
			(net "P5E_CPU1_PE4_TX_DP<1>")
		)
		(pad "N88" smd circle
			(at 34.98342 -21.325332 270)
			(size 0.4318 0.4318)
			(layers "F.Cu" "F.Mask" "F.Paste")
			(net "GND")
		)
		(pad "N90" smd oval
			(at 36.611306 -21.325332)
			(size 0.381 0.4826)
			(drill
				(offset 0 -0.0508)
			)
			(layers "F.Cu" "F.Mask" "F.Paste")
			(net "P5E_CPU1_PE4_RX_DP<1>")
		)
		(pad "P2" smd circle
			(at -36.611306 -20.965668 270)
			(size 0.4318 0.4318)
			(layers "F.Cu" "F.Mask" "F.Paste")
			(net "UPI_CPU1_CPU0_P0P1_DP<2>")
		)
		(pad "P4" smd circle
			(at -34.98342 -20.965668 270)
			(size 0.4318 0.4318)
			(layers "F.Cu" "F.Mask" "F.Paste")
			(net "GND")
		)
		(pad "P6" smd circle
			(at -33.355534 -20.965668 270)
			(size 0.4318 0.4318)
			(layers "F.Cu" "F.Mask" "F.Paste")
			(net "UPI_CPU0_CPU1_P1P0_DN<2>")
		)
		(pad "P8" smd circle
			(at -31.727902 -20.965668 270)
			(size 0.4318 0.4318)
			(layers "F.Cu" "F.Mask" "F.Paste")
			(net "GND")
		)
		(pad "P10" smd circle
			(at -30.100016 -20.965668 270)
			(size 0.4318 0.4318)
			(layers "F.Cu" "F.Mask" "F.Paste")
			(net "P5E_CPU1_PE0_RX_DN<2>")
		)
		(pad "P12" smd circle
			(at -28.472384 -20.965668 270)
			(size 0.4318 0.4318)
			(layers "F.Cu" "F.Mask" "F.Paste")
			(net "GND")
		)
		(pad "P14" smd circle
			(at -26.844498 -20.965668 270)
			(size 0.4318 0.4318)
			(layers "F.Cu" "F.Mask" "F.Paste")
			(net "P5E_CPU1_PE0_TX_DN<1>")
		)
		(pad "P16" smd circle
			(at -25.216612 -20.965668 270)
			(size 0.4318 0.4318)
			(layers "F.Cu" "F.Mask" "F.Paste")
			(net "GND")
		)
		(pad "P18" smd circle
			(at -23.58898 -20.965668 270)
			(size 0.4318 0.4318)
			(layers "F.Cu" "F.Mask" "F.Paste")
			(net "M_B_CPU1_SB_DQS_DP<7>")
		)
		(pad "P20" smd circle
			(at -21.961094 -20.965668 270)
			(size 0.4318 0.4318)
			(layers "F.Cu" "F.Mask" "F.Paste")
			(net "GND")
		)
		(pad "P22" smd circle
			(at -20.333462 -20.965668 270)
			(size 0.4318 0.4318)
			(layers "F.Cu" "F.Mask" "F.Paste")
			(net "GND")
		)
		(pad "P24" smd circle
			(at -18.705576 -20.965668 270)
			(size 0.4318 0.4318)
			(layers "F.Cu" "F.Mask" "F.Paste")
			(net "M_B_CPU1_SB_DQS_DP<6>")
		)
		(pad "P26" smd circle
			(at -17.07769 -20.965668 270)
			(size 0.4318 0.4318)
			(layers "F.Cu" "F.Mask" "F.Paste")
			(net "GND")
		)
		(pad "P28" smd circle
			(at -15.450058 -20.965668 270)
			(size 0.4318 0.4318)
			(layers "F.Cu" "F.Mask" "F.Paste")
			(net "GND")
		)
		(pad "P30" smd circle
			(at -13.822426 -20.965668 270)
			(size 0.4318 0.4318)
			(layers "F.Cu" "F.Mask" "F.Paste")
			(net "M_A_CPU1_SB_DQS_DP<5>")
		)
		(pad "P32" smd circle
			(at -12.19454 -20.965668 270)
			(size 0.4318 0.4318)
			(layers "F.Cu" "F.Mask" "F.Paste")
			(net "GND")
		)
		(pad "P34" smd circle
			(at -10.566654 -20.965668 270)
			(size 0.4318 0.4318)
			(layers "F.Cu" "F.Mask" "F.Paste")
			(net "GND")
		)
		(pad "P36" smd circle
			(at -8.939022 -20.965668 270)
			(size 0.4318 0.4318)
			(layers "F.Cu" "F.Mask" "F.Paste")
			(net "M_B_CPU1_SB_DQS_DN<4>")
		)
		(pad "P38" smd circle
			(at -7.311136 -20.965668 270)
			(size 0.4318 0.4318)
			(layers "F.Cu" "F.Mask" "F.Paste")
			(net "GND")
		)
		(pad "P40" smd circle
			(at -5.68325 -20.965668 270)
			(size 0.4318 0.4318)
			(layers "F.Cu" "F.Mask" "F.Paste")
			(net "GND")
		)
		(pad "P42" smd circle
			(at -4.055618 -20.965668 270)
			(size 0.4318 0.4318)
			(layers "F.Cu" "F.Mask" "F.Paste")
			(net "M_B_CPU1_SB_PAR")
		)
		(pad "P44" smd circle
			(at -2.427732 -20.965668 270)
			(size 0.4318 0.4318)
			(layers "F.Cu" "F.Mask" "F.Paste")
			(net "GND")
		)
		(pad "P47" smd circle
			(at 1.613916 -20.855686 270)
			(size 0.4318 0.4318)
			(layers "F.Cu" "F.Mask" "F.Paste")
			(net "GND")
		)
		(pad "P49" smd circle
			(at 3.241802 -20.855686 270)
			(size 0.4318 0.4318)
			(layers "F.Cu" "F.Mask" "F.Paste")
			(net "M_B_CPU1_SA_CA<1>")
		)
		(pad "P51" smd circle
			(at 4.869434 -20.855686 270)
			(size 0.4318 0.4318)
			(layers "F.Cu" "F.Mask" "F.Paste")
			(net "GND")
		)
		(pad "P53" smd circle
			(at 6.49732 -20.855686 270)
			(size 0.4318 0.4318)
			(layers "F.Cu" "F.Mask" "F.Paste")
			(net "GND")
		)
		(pad "P55" smd circle
			(at 8.124952 -20.855686 270)
			(size 0.4318 0.4318)
			(layers "F.Cu" "F.Mask" "F.Paste")
			(net "M_B_CPU1_SA_DQS_DP<9>")
		)
		(pad "P57" smd circle
			(at 9.752838 -20.855686 270)
			(size 0.4318 0.4318)
			(layers "F.Cu" "F.Mask" "F.Paste")
			(net "GND")
		)
		(pad "P59" smd circle
			(at 11.380724 -20.855686 270)
			(size 0.4318 0.4318)
			(layers "F.Cu" "F.Mask" "F.Paste")
			(net "GND")
		)
		(pad "P61" smd circle
			(at 13.008356 -20.855686 270)
			(size 0.4318 0.4318)
			(layers "F.Cu" "F.Mask" "F.Paste")
			(net "M_B_CPU1_SA_DQS_DP<7>")
		)
		(pad "P63" smd circle
			(at 14.635988 -20.855686 270)
			(size 0.4318 0.4318)
			(layers "F.Cu" "F.Mask" "F.Paste")
			(net "GND")
		)
		(pad "P65" smd circle
			(at 16.263874 -20.855686 270)
			(size 0.4318 0.4318)
			(layers "F.Cu" "F.Mask" "F.Paste")
			(net "GND")
		)
		(pad "P67" smd circle
			(at 17.89176 -20.855686 270)
			(size 0.4318 0.4318)
			(layers "F.Cu" "F.Mask" "F.Paste")
			(net "M_A_CPU1_SA_DQS_DN<6>")
		)
		(pad "P69" smd circle
			(at 19.519392 -20.855686 270)
			(size 0.4318 0.4318)
			(layers "F.Cu" "F.Mask" "F.Paste")
			(net "GND")
		)
		(pad "P71" smd circle
			(at 21.147278 -20.855686 270)
			(size 0.4318 0.4318)
			(layers "F.Cu" "F.Mask" "F.Paste")
			(net "GND")
		)
		(pad "P73" smd circle
			(at 22.77491 -20.855686 270)
			(size 0.4318 0.4318)
			(layers "F.Cu" "F.Mask" "F.Paste")
			(net "M_B_CPU1_SA_DQS_DP<5>")
		)
		(pad "P75" smd circle
			(at 24.402796 -20.855686 270)
			(size 0.4318 0.4318)
			(layers "F.Cu" "F.Mask" "F.Paste")
			(net "GND")
		)
		(pad "P77" smd circle
			(at 26.030682 -20.855686 270)
			(size 0.4318 0.4318)
			(layers "F.Cu" "F.Mask" "F.Paste")
			(net "GND")
		)
		(pad "P79" smd circle
			(at 27.658314 -20.855686 270)
			(size 0.4318 0.4318)
			(layers "F.Cu" "F.Mask" "F.Paste")
			(net "PVCCFA_EHV_FIVRA_CPU1")
		)
		(pad "P81" smd circle
			(at 29.2862 -20.855686 270)
			(size 0.4318 0.4318)
			(layers "F.Cu" "F.Mask" "F.Paste")
			(net "UPI_CPU1_CPU0_P2P2_DN<5>")
		)
		(pad "P83" smd circle
			(at 30.914086 -20.855686 270)
			(size 0.4318 0.4318)
			(layers "F.Cu" "F.Mask" "F.Paste")
			(net "UPI_CPU1_CPU0_P2P2_DP<6>")
		)
		(pad "P85" smd circle
			(at 32.541718 -20.855686 270)
			(size 0.4318 0.4318)
			(layers "F.Cu" "F.Mask" "F.Paste")
			(net "P5E_CPU1_PE4_TX_DN<1>")
		)
		(pad "P87" smd circle
			(at 34.169604 -20.855686 270)
			(size 0.4318 0.4318)
			(layers "F.Cu" "F.Mask" "F.Paste")
			(net "GND")
		)
		(pad "P89" smd circle
			(at 35.797236 -20.855686 270)
			(size 0.4318 0.4318)
			(layers "F.Cu" "F.Mask" "F.Paste")
			(net "P5E_CPU1_PE4_RX_DN<1>")
		)
		(pad "P91" smd oval
			(at 37.425122 -20.855686)
			(size 0.381 0.4826)
			(drill
				(offset 0 -0.0508)
			)
			(layers "F.Cu" "F.Mask" "F.Paste")
			(net "GND")
		)
		(pad "R1" smd oval
			(at -37.425122 -20.495514 180)
			(size 0.381 0.4826)
			(drill
				(offset 0 -0.0508)
			)
			(layers "F.Cu" "F.Mask" "F.Paste")
			(net "GND")
		)
		(pad "R3" smd circle
			(at -35.797236 -20.495514 270)
			(size 0.4318 0.4318)
			(layers "F.Cu" "F.Mask" "F.Paste")
			(net "UPI_CPU1_CPU0_P0P1_DP<3>")
		)
		(pad "R5" smd circle
			(at -34.169604 -20.495514 270)
			(size 0.4318 0.4318)
			(layers "F.Cu" "F.Mask" "F.Paste")
			(net "GND")
		)
		(pad "R7" smd circle
			(at -32.541718 -20.495514 270)
			(size 0.4318 0.4318)
			(layers "F.Cu" "F.Mask" "F.Paste")
			(net "UPI_CPU0_CPU1_P1P0_DP<2>")
		)
		(pad "R9" smd circle
			(at -30.914086 -20.495514 270)
			(size 0.4318 0.4318)
			(layers "F.Cu" "F.Mask" "F.Paste")
			(net "GND")
		)
		(pad "R11" smd circle
			(at -29.2862 -20.495514 270)
			(size 0.4318 0.4318)
			(layers "F.Cu" "F.Mask" "F.Paste")
			(net "P5E_CPU1_PE0_RX_DP<2>")
		)
		(pad "R13" smd circle
			(at -27.658314 -20.495514 270)
			(size 0.4318 0.4318)
			(layers "F.Cu" "F.Mask" "F.Paste")
			(net "GND")
		)
		(pad "R15" smd circle
			(at -26.030682 -20.495514 270)
			(size 0.4318 0.4318)
			(layers "F.Cu" "F.Mask" "F.Paste")
			(net "P5E_CPU1_PE0_TX_DP<1>")
		)
		(pad "R17" smd circle
			(at -24.402796 -20.495514 270)
			(size 0.4318 0.4318)
			(layers "F.Cu" "F.Mask" "F.Paste")
			(net "GND")
		)
		(pad "R19" smd circle
			(at -22.77491 -20.495514 270)
			(size 0.4318 0.4318)
			(layers "F.Cu" "F.Mask" "F.Paste")
			(net "GND")
		)
		(pad "R21" smd circle
			(at -21.147278 -20.495514 270)
			(size 0.4318 0.4318)
			(layers "F.Cu" "F.Mask" "F.Paste")
			(net "M_C_CPU1_SB_DQS_DN<2>")
		)
		(pad "R23" smd circle
			(at -19.519392 -20.495514 270)
			(size 0.4318 0.4318)
			(layers "F.Cu" "F.Mask" "F.Paste")
			(net "GND")
		)
		(pad "R25" smd circle
			(at -17.89176 -20.495514 270)
			(size 0.4318 0.4318)
			(layers "F.Cu" "F.Mask" "F.Paste")
			(net "GND")
		)
		(pad "R27" smd circle
			(at -16.263874 -20.495514 270)
			(size 0.4318 0.4318)
			(layers "F.Cu" "F.Mask" "F.Paste")
			(net "M_B_CPU1_SB_DQS_DN<0>")
		)
		(pad "R29" smd circle
			(at -14.635988 -20.495514 270)
			(size 0.4318 0.4318)
			(layers "F.Cu" "F.Mask" "F.Paste")
			(net "GND")
		)
		(pad "R31" smd circle
			(at -13.008356 -20.495514 270)
			(size 0.4318 0.4318)
			(layers "F.Cu" "F.Mask" "F.Paste")
			(net "GND")
		)
		(pad "R33" smd circle
			(at -11.380724 -20.495514 270)
			(size 0.4318 0.4318)
			(layers "F.Cu" "F.Mask" "F.Paste")
			(net "M_C_CPU1_SB_DQS_DN<9>")
		)
		(pad "R35" smd circle
			(at -9.752838 -20.495514 270)
			(size 0.4318 0.4318)
			(layers "F.Cu" "F.Mask" "F.Paste")
			(net "GND")
		)
		(pad "R37" smd circle
			(at -8.124952 -20.495514 270)
			(size 0.4318 0.4318)
			(layers "F.Cu" "F.Mask" "F.Paste")
			(net "GND")
		)
		(pad "R39" smd circle
			(at -6.49732 -20.495514 270)
			(size 0.4318 0.4318)
			(layers "F.Cu" "F.Mask" "F.Paste")
			(net "M_C_CPU1_SB_CA<6>")
		)
		(pad "R41" smd circle
			(at -4.869434 -20.495514 270)
			(size 0.4318 0.4318)
			(layers "F.Cu" "F.Mask" "F.Paste")
			(net "GND")
		)
		(pad "R43" smd circle
			(at -3.241802 -20.495514 270)
			(size 0.4318 0.4318)
			(layers "F.Cu" "F.Mask" "F.Paste")
			(net "GND")
		)
		(pad "R45" smd circle
			(at -1.613916 -20.495514 270)
			(size 0.4318 0.4318)
			(layers "F.Cu" "F.Mask" "F.Paste")
			(net "M_B_CPU1_CLK_DN<0>")
		)
		(pad "R48" smd circle
			(at 2.427732 -20.385532 270)
			(size 0.4318 0.4318)
			(layers "F.Cu" "F.Mask" "F.Paste")
			(net "GND")
		)
		(pad "R50" smd circle
			(at 4.055618 -20.385532 270)
			(size 0.4318 0.4318)
			(layers "F.Cu" "F.Mask" "F.Paste")
			(net "GND")
		)
		(pad "R52" smd circle
			(at 5.68325 -20.385532 270)
			(size 0.4318 0.4318)
			(layers "F.Cu" "F.Mask" "F.Paste")
			(net "M_C_CPU1_SA_CA<0>")
		)
		(pad "R54" smd circle
			(at 7.311136 -20.385532 270)
			(size 0.4318 0.4318)
			(layers "F.Cu" "F.Mask" "F.Paste")
			(net "GND")
		)
		(pad "R56" smd circle
			(at 8.939022 -20.385532 270)
			(size 0.4318 0.4318)
			(layers "F.Cu" "F.Mask" "F.Paste")
			(net "GND")
		)
		(pad "R58" smd circle
			(at 10.566654 -20.385532 270)
			(size 0.4318 0.4318)
			(layers "F.Cu" "F.Mask" "F.Paste")
			(net "M_B_CPU1_SA_DQS_DN<3>")
		)
		(pad "R60" smd circle
			(at 12.19454 -20.385532 270)
			(size 0.4318 0.4318)
			(layers "F.Cu" "F.Mask" "F.Paste")
			(net "GND")
		)
		(pad "R62" smd circle
			(at 13.822426 -20.385532 270)
			(size 0.4318 0.4318)
			(layers "F.Cu" "F.Mask" "F.Paste")
			(net "GND")
		)
		(pad "R64" smd circle
			(at 15.450058 -20.385532 270)
			(size 0.4318 0.4318)
			(layers "F.Cu" "F.Mask" "F.Paste")
			(net "M_C_CPU1_SA_DQS_DN<2>")
		)
		(pad "R66" smd circle
			(at 17.07769 -20.385532 270)
			(size 0.4318 0.4318)
			(layers "F.Cu" "F.Mask" "F.Paste")
			(net "GND")
		)
		(pad "R68" smd circle
			(at 18.705576 -20.385532 270)
			(size 0.4318 0.4318)
			(layers "F.Cu" "F.Mask" "F.Paste")
			(net "GND")
		)
		(pad "R70" smd circle
			(at 20.333462 -20.385532 270)
			(size 0.4318 0.4318)
			(layers "F.Cu" "F.Mask" "F.Paste")
			(net "M_B_CPU1_SA_DQS_DN<1>")
		)
		(pad "R72" smd circle
			(at 21.961094 -20.385532 270)
			(size 0.4318 0.4318)
			(layers "F.Cu" "F.Mask" "F.Paste")
			(net "GND")
		)
		(pad "R74" smd circle
			(at 23.58898 -20.385532 270)
			(size 0.4318 0.4318)
			(layers "F.Cu" "F.Mask" "F.Paste")
			(net "GND")
		)
		(pad "R76" smd circle
			(at 25.216612 -20.385532 270)
			(size 0.4318 0.4318)
			(layers "F.Cu" "F.Mask" "F.Paste")
			(net "M_C_CPU1_SA_DQS_DN<0>")
		)
		(pad "R78" smd circle
			(at 26.844498 -20.385532 270)
			(size 0.4318 0.4318)
			(layers "F.Cu" "F.Mask" "F.Paste")
			(net "GND")
		)
		(pad "R80" smd circle
			(at 28.472384 -20.385532 270)
			(size 0.4318 0.4318)
			(layers "F.Cu" "F.Mask" "F.Paste")
			(net "PVCCFA_EHV_FIVRA_CPU1")
		)
		(pad "R82" smd circle
			(at 30.100016 -20.385532 270)
			(size 0.4318 0.4318)
			(layers "F.Cu" "F.Mask" "F.Paste")
			(net "UPI_CPU1_CPU0_P2P2_DN<6>")
		)
		(pad "R84" smd circle
			(at 31.727902 -20.385532 270)
			(size 0.4318 0.4318)
			(layers "F.Cu" "F.Mask" "F.Paste")
			(net "GND")
		)
		(pad "R86" smd circle
			(at 33.355534 -20.385532 270)
			(size 0.4318 0.4318)
			(layers "F.Cu" "F.Mask" "F.Paste")
			(net "P5E_CPU1_PE4_TX_DN<2>")
		)
		(pad "R88" smd circle
			(at 34.98342 -20.385532 270)
			(size 0.4318 0.4318)
			(layers "F.Cu" "F.Mask" "F.Paste")
			(net "GND")
		)
		(pad "R90" smd circle
			(at 36.611306 -20.385532 270)
			(size 0.4318 0.4318)
			(layers "F.Cu" "F.Mask" "F.Paste")
			(net "P5E_CPU1_PE4_RX_DP<2>")
		)
		(pad "T2" smd circle
			(at -36.611306 -20.025868 270)
			(size 0.4318 0.4318)
			(layers "F.Cu" "F.Mask" "F.Paste")
			(net "UPI_CPU1_CPU0_P0P1_DN<3>")
		)
		(pad "T4" smd circle
			(at -34.98342 -20.025868 270)
			(size 0.4318 0.4318)
			(layers "F.Cu" "F.Mask" "F.Paste")
			(net "GND")
		)
		(pad "T6" smd circle
			(at -33.355534 -20.025868 270)
			(size 0.4318 0.4318)
			(layers "F.Cu" "F.Mask" "F.Paste")
			(net "UPI_CPU0_CPU1_P1P0_DP<3>")
		)
		(pad "T8" smd circle
			(at -31.727902 -20.025868 270)
			(size 0.4318 0.4318)
			(layers "F.Cu" "F.Mask" "F.Paste")
			(net "GND")
		)
		(pad "T10" smd circle
			(at -30.100016 -20.025868 270)
			(size 0.4318 0.4318)
			(layers "F.Cu" "F.Mask" "F.Paste")
			(net "P5E_CPU1_PE0_RX_DN<3>")
		)
		(pad "T12" smd circle
			(at -28.472384 -20.025868 270)
			(size 0.4318 0.4318)
			(layers "F.Cu" "F.Mask" "F.Paste")
			(net "GND")
		)
		(pad "T14" smd circle
			(at -26.844498 -20.025868 270)
			(size 0.4318 0.4318)
			(layers "F.Cu" "F.Mask" "F.Paste")
			(net "P5E_CPU1_PE0_TX_DP<2>")
		)
		(pad "T16" smd circle
			(at -25.216612 -20.025868 270)
			(size 0.4318 0.4318)
			(layers "F.Cu" "F.Mask" "F.Paste")
			(net "GND")
		)
		(pad "T18" smd circle
			(at -23.58898 -20.025868 270)
			(size 0.4318 0.4318)
			(layers "F.Cu" "F.Mask" "F.Paste")
			(net "GND")
		)
		(pad "T20" smd circle
			(at -21.961094 -20.025868 270)
			(size 0.4318 0.4318)
			(layers "F.Cu" "F.Mask" "F.Paste")
			(net "M_C_CPU1_SB_DQ<20>")
		)
		(pad "T22" smd circle
			(at -20.333462 -20.025868 270)
			(size 0.4318 0.4318)
			(layers "F.Cu" "F.Mask" "F.Paste")
			(net "M_C_CPU1_SB_DQ<17>")
		)
		(pad "T24" smd circle
			(at -18.705576 -20.025868 270)
			(size 0.4318 0.4318)
			(layers "F.Cu" "F.Mask" "F.Paste")
			(net "GND")
		)
		(pad "T26" smd circle
			(at -17.07769 -20.025868 270)
			(size 0.4318 0.4318)
			(layers "F.Cu" "F.Mask" "F.Paste")
			(net "M_B_CPU1_SB_DQ<4>")
		)
		(pad "T28" smd circle
			(at -15.450058 -20.025868 270)
			(size 0.4318 0.4318)
			(layers "F.Cu" "F.Mask" "F.Paste")
			(net "M_B_CPU1_SB_DQ<1>")
		)
		(pad "T30" smd circle
			(at -13.822426 -20.025868 270)
			(size 0.4318 0.4318)
			(layers "F.Cu" "F.Mask" "F.Paste")
			(net "GND")
		)
		(pad "T32" smd circle
			(at -12.19454 -20.025868 270)
			(size 0.4318 0.4318)
			(layers "F.Cu" "F.Mask" "F.Paste")
			(net "M_C_CPU1_SB_CB<0>")
		)
		(pad "T34" smd circle
			(at -10.566654 -20.025868 270)
			(size 0.4318 0.4318)
			(layers "F.Cu" "F.Mask" "F.Paste")
			(net "M_C_CPU1_SB_CB<5>")
		)
		(pad "T36" smd circle
			(at -8.939022 -20.025868 270)
			(size 0.4318 0.4318)
			(layers "F.Cu" "F.Mask" "F.Paste")
			(net "GND")
		)
		(pad "T38" smd circle
			(at -7.311136 -20.025868 270)
			(size 0.4318 0.4318)
			(layers "F.Cu" "F.Mask" "F.Paste")
			(net "M_C_CPU1_SB_CS_N<0>")
		)
		(pad "T40" smd circle
			(at -5.68325 -20.025868 270)
			(size 0.4318 0.4318)
			(layers "F.Cu" "F.Mask" "F.Paste")
			(net "M_C_CPU1_SB_CA<4>")
		)
		(pad "T42" smd circle
			(at -4.055618 -20.025868 270)
			(size 0.4318 0.4318)
			(layers "F.Cu" "F.Mask" "F.Paste")
			(net "GND")
		)
		(pad "T44" smd circle
			(at -2.427732 -20.025868 270)
			(size 0.4318 0.4318)
			(layers "F.Cu" "F.Mask" "F.Paste")
			(net "M_B_CPU1_SB_CA<0>")
		)
		(pad "T47" smd circle
			(at 1.613916 -19.915886 270)
			(size 0.4318 0.4318)
			(layers "F.Cu" "F.Mask" "F.Paste")
			(net "M_C_CPU1_SA_PAR")
		)
		(pad "T49" smd circle
			(at 3.241802 -19.915886 270)
			(size 0.4318 0.4318)
			(layers "F.Cu" "F.Mask" "F.Paste")
			(net "GND")
		)
		(pad "T51" smd circle
			(at 4.869434 -19.915886 270)
			(size 0.4318 0.4318)
			(layers "F.Cu" "F.Mask" "F.Paste")
			(net "M_C_CPU1_SA_CA<2>")
		)
		(pad "T53" smd circle
			(at 6.49732 -19.915886 270)
			(size 0.4318 0.4318)
			(layers "F.Cu" "F.Mask" "F.Paste")
			(net "M_C_CPU1_SA_CS_N<1>")
		)
		(pad "T55" smd circle
			(at 8.124952 -19.915886 270)
			(size 0.4318 0.4318)
			(layers "F.Cu" "F.Mask" "F.Paste")
			(net "GND")
		)
		(pad "T57" smd circle
			(at 9.752838 -19.915886 270)
			(size 0.4318 0.4318)
			(layers "F.Cu" "F.Mask" "F.Paste")
			(net "M_B_CPU1_SA_DQ<28>")
		)
		(pad "T59" smd circle
			(at 11.380724 -19.915886 270)
			(size 0.4318 0.4318)
			(layers "F.Cu" "F.Mask" "F.Paste")
			(net "M_B_CPU1_SA_DQ<25>")
		)
		(pad "T61" smd circle
			(at 13.008356 -19.915886 270)
			(size 0.4318 0.4318)
			(layers "F.Cu" "F.Mask" "F.Paste")
			(net "GND")
		)
		(pad "T63" smd circle
			(at 14.635988 -19.915886 270)
			(size 0.4318 0.4318)
			(layers "F.Cu" "F.Mask" "F.Paste")
			(net "M_C_CPU1_SA_DQ<20>")
		)
		(pad "T65" smd circle
			(at 16.263874 -19.915886 270)
			(size 0.4318 0.4318)
			(layers "F.Cu" "F.Mask" "F.Paste")
			(net "M_C_CPU1_SA_DQ<17>")
		)
		(pad "T67" smd circle
			(at 17.89176 -19.915886 270)
			(size 0.4318 0.4318)
			(layers "F.Cu" "F.Mask" "F.Paste")
			(net "GND")
		)
		(pad "T69" smd circle
			(at 19.519392 -19.915886 270)
			(size 0.4318 0.4318)
			(layers "F.Cu" "F.Mask" "F.Paste")
			(net "M_B_CPU1_SA_DQ<12>")
		)
		(pad "T71" smd circle
			(at 21.147278 -19.915886 270)
			(size 0.4318 0.4318)
			(layers "F.Cu" "F.Mask" "F.Paste")
			(net "M_B_CPU1_SA_DQ<9>")
		)
		(pad "T73" smd circle
			(at 22.77491 -19.915886 270)
			(size 0.4318 0.4318)
			(layers "F.Cu" "F.Mask" "F.Paste")
			(net "GND")
		)
		(pad "T75" smd circle
			(at 24.402796 -19.915886 270)
			(size 0.4318 0.4318)
			(layers "F.Cu" "F.Mask" "F.Paste")
			(net "M_C_CPU1_SA_DQ<4>")
		)
		(pad "T77" smd circle
			(at 26.030682 -19.915886 270)
			(size 0.4318 0.4318)
			(layers "F.Cu" "F.Mask" "F.Paste")
			(net "M_C_CPU1_SA_DQ<1>")
		)
		(pad "T79" smd circle
			(at 27.658314 -19.915886 270)
			(size 0.4318 0.4318)
			(layers "F.Cu" "F.Mask" "F.Paste")
			(net "GND")
		)
		(pad "T81" smd circle
			(at 29.2862 -19.915886 270)
			(size 0.4318 0.4318)
			(layers "F.Cu" "F.Mask" "F.Paste")
			(net "UPI_CPU1_CPU0_P2P2_DP<5>")
		)
		(pad "T83" smd circle
			(at 30.914086 -19.915886 270)
			(size 0.4318 0.4318)
			(layers "F.Cu" "F.Mask" "F.Paste")
			(net "GND")
		)
		(pad "T85" smd circle
			(at 32.541718 -19.915886 270)
			(size 0.4318 0.4318)
			(layers "F.Cu" "F.Mask" "F.Paste")
			(net "PVCCFA_EHV_FIVRA_CPU1")
		)
		(pad "T87" smd circle
			(at 34.169604 -19.915886 270)
			(size 0.4318 0.4318)
			(layers "F.Cu" "F.Mask" "F.Paste")
			(net "P5E_CPU1_PE4_TX_DP<2>")
		)
		(pad "T89" smd circle
			(at 35.797236 -19.915886 270)
			(size 0.4318 0.4318)
			(layers "F.Cu" "F.Mask" "F.Paste")
			(net "PVCCFA_EHV_FIVRA_CPU1")
		)
		(pad "T91" smd oval
			(at 37.425122 -19.915886)
			(size 0.381 0.4826)
			(drill
				(offset 0 -0.0508)
			)
			(layers "F.Cu" "F.Mask" "F.Paste")
			(net "P5E_CPU1_PE4_RX_DN<2>")
		)
		(pad "U1" smd oval
			(at -37.425122 -19.555714 180)
			(size 0.381 0.4826)
			(drill
				(offset 0 -0.0508)
			)
			(layers "F.Cu" "F.Mask" "F.Paste")
			(net "UPI_CPU1_CPU0_P0P1_DN<4>")
		)
		(pad "U3" smd circle
			(at -35.797236 -19.555714 270)
			(size 0.4318 0.4318)
			(layers "F.Cu" "F.Mask" "F.Paste")
			(net "PVCCFA_EHV_CPU1")
		)
		(pad "U5" smd circle
			(at -34.169604 -19.555714 270)
			(size 0.4318 0.4318)
			(layers "F.Cu" "F.Mask" "F.Paste")
			(net "UPI_CPU0_CPU1_P1P0_DN<3>")
		)
		(pad "U7" smd circle
			(at -32.541718 -19.555714 270)
			(size 0.4318 0.4318)
			(layers "F.Cu" "F.Mask" "F.Paste")
			(net "PVCCFA_EHV_FIVRA_CPU1")
		)
		(pad "U9" smd circle
			(at -30.914086 -19.555714 270)
			(size 0.4318 0.4318)
			(layers "F.Cu" "F.Mask" "F.Paste")
			(net "P5E_CPU1_PE0_RX_DP<3>")
		)
		(pad "U11" smd circle
			(at -29.2862 -19.555714 270)
			(size 0.4318 0.4318)
			(layers "F.Cu" "F.Mask" "F.Paste")
			(net "PVCCFA_EHV_FIVRA_CPU1")
		)
		(pad "U13" smd circle
			(at -27.658314 -19.555714 270)
			(size 0.4318 0.4318)
			(layers "F.Cu" "F.Mask" "F.Paste")
			(net "P5E_CPU1_PE0_TX_DN<2>")
		)
		(pad "U15" smd circle
			(at -26.030682 -19.555714 270)
			(size 0.4318 0.4318)
			(layers "F.Cu" "F.Mask" "F.Paste")
			(net "PVCCFA_EHV_FIVRA_CPU1")
		)
		(pad "U17" smd circle
			(at -24.402796 -19.555714 270)
			(size 0.4318 0.4318)
			(layers "F.Cu" "F.Mask" "F.Paste")
			(net "NC_CPU1_HBM0_VIEWDIG0")
		)
		(pad "U19" smd circle
			(at -22.77491 -19.555714 270)
			(size 0.4318 0.4318)
			(layers "F.Cu" "F.Mask" "F.Paste")
			(net "M_C_CPU1_SB_DQ<21>")
		)
		(pad "U21" smd circle
			(at -21.147278 -19.555714 270)
			(size 0.4318 0.4318)
			(layers "F.Cu" "F.Mask" "F.Paste")
			(net "M_C_CPU1_SB_DQS_DP<2>")
		)
		(pad "U23" smd circle
			(at -19.519392 -19.555714 270)
			(size 0.4318 0.4318)
			(layers "F.Cu" "F.Mask" "F.Paste")
			(net "M_C_CPU1_SB_DQ<16>")
		)
		(pad "U25" smd circle
			(at -17.89176 -19.555714 270)
			(size 0.4318 0.4318)
			(layers "F.Cu" "F.Mask" "F.Paste")
			(net "M_B_CPU1_SB_DQ<5>")
		)
		(pad "U27" smd circle
			(at -16.263874 -19.555714 270)
			(size 0.4318 0.4318)
			(layers "F.Cu" "F.Mask" "F.Paste")
			(net "M_B_CPU1_SB_DQS_DP<0>")
		)
		(pad "U29" smd circle
			(at -14.635988 -19.555714 270)
			(size 0.4318 0.4318)
			(layers "F.Cu" "F.Mask" "F.Paste")
			(net "M_B_CPU1_SB_DQ<0>")
		)
		(pad "U31" smd circle
			(at -13.008356 -19.555714 270)
			(size 0.4318 0.4318)
			(layers "F.Cu" "F.Mask" "F.Paste")
			(net "M_C_CPU1_SB_CB<1>")
		)
		(pad "U33" smd circle
			(at -11.380724 -19.555714 270)
			(size 0.4318 0.4318)
			(layers "F.Cu" "F.Mask" "F.Paste")
			(net "M_C_CPU1_SB_DQS_DP<9>")
		)
		(pad "U35" smd circle
			(at -9.752838 -19.555714 270)
			(size 0.4318 0.4318)
			(layers "F.Cu" "F.Mask" "F.Paste")
			(net "M_C_CPU1_SB_CB<4>")
		)
		(pad "U37" smd circle
			(at -8.124952 -19.555714 270)
			(size 0.4318 0.4318)
			(layers "F.Cu" "F.Mask" "F.Paste")
			(net "M_C_CPU1_SB_CS_N<1>")
		)
		(pad "U39" smd circle
			(at -6.49732 -19.555714 270)
			(size 0.4318 0.4318)
			(layers "F.Cu" "F.Mask" "F.Paste")
			(net "GND")
		)
		(pad "U41" smd circle
			(at -4.869434 -19.555714 270)
			(size 0.4318 0.4318)
			(layers "F.Cu" "F.Mask" "F.Paste")
			(net "M_C_CPU1_SB_CA<2>")
		)
		(pad "U43" smd circle
			(at -3.241802 -19.555714 270)
			(size 0.4318 0.4318)
			(layers "F.Cu" "F.Mask" "F.Paste")
			(net "M_B_CPU1_SB_CA<1>")
		)
		(pad "U45" smd circle
			(at -1.613916 -19.555714 270)
			(size 0.4318 0.4318)
			(layers "F.Cu" "F.Mask" "F.Paste")
			(net "M_B_CPU1_CLK_DP<0>")
		)
		(pad "U48" smd circle
			(at 2.427732 -19.445732 270)
			(size 0.4318 0.4318)
			(layers "F.Cu" "F.Mask" "F.Paste")
			(net "M_C_CPU1_SA_CA<6>")
		)
		(pad "U50" smd circle
			(at 4.055618 -19.445732 270)
			(size 0.4318 0.4318)
			(layers "F.Cu" "F.Mask" "F.Paste")
			(net "M_C_CPU1_SA_CA<4>")
		)
		(pad "U52" smd circle
			(at 5.68325 -19.445732 270)
			(size 0.4318 0.4318)
			(layers "F.Cu" "F.Mask" "F.Paste")
			(net "GND")
		)
		(pad "U54" smd circle
			(at 7.311136 -19.445732 270)
			(size 0.4318 0.4318)
			(layers "F.Cu" "F.Mask" "F.Paste")
			(net "M_C_CPU1_SA_CS_N<0>")
		)
		(pad "U56" smd circle
			(at 8.939022 -19.445732 270)
			(size 0.4318 0.4318)
			(layers "F.Cu" "F.Mask" "F.Paste")
			(net "M_B_CPU1_SA_DQ<29>")
		)
		(pad "U58" smd circle
			(at 10.566654 -19.445732 270)
			(size 0.4318 0.4318)
			(layers "F.Cu" "F.Mask" "F.Paste")
			(net "M_B_CPU1_SA_DQS_DP<3>")
		)
		(pad "U60" smd circle
			(at 12.19454 -19.445732 270)
			(size 0.4318 0.4318)
			(layers "F.Cu" "F.Mask" "F.Paste")
			(net "M_B_CPU1_SA_DQ<24>")
		)
		(pad "U62" smd circle
			(at 13.822426 -19.445732 270)
			(size 0.4318 0.4318)
			(layers "F.Cu" "F.Mask" "F.Paste")
			(net "M_C_CPU1_SA_DQ<21>")
		)
		(pad "U64" smd circle
			(at 15.450058 -19.445732 270)
			(size 0.4318 0.4318)
			(layers "F.Cu" "F.Mask" "F.Paste")
			(net "M_C_CPU1_SA_DQS_DP<2>")
		)
		(pad "U66" smd circle
			(at 17.07769 -19.445732 270)
			(size 0.4318 0.4318)
			(layers "F.Cu" "F.Mask" "F.Paste")
			(net "M_C_CPU1_SA_DQ<16>")
		)
		(pad "U68" smd circle
			(at 18.705576 -19.445732 270)
			(size 0.4318 0.4318)
			(layers "F.Cu" "F.Mask" "F.Paste")
			(net "M_B_CPU1_SA_DQ<13>")
		)
		(pad "U70" smd circle
			(at 20.333462 -19.445732 270)
			(size 0.4318 0.4318)
			(layers "F.Cu" "F.Mask" "F.Paste")
			(net "M_B_CPU1_SA_DQS_DP<1>")
		)
		(pad "U72" smd circle
			(at 21.961094 -19.445732 270)
			(size 0.4318 0.4318)
			(layers "F.Cu" "F.Mask" "F.Paste")
			(net "M_B_CPU1_SA_DQ<8>")
		)
		(pad "U74" smd circle
			(at 23.58898 -19.445732 270)
			(size 0.4318 0.4318)
			(layers "F.Cu" "F.Mask" "F.Paste")
			(net "M_C_CPU1_SA_DQ<5>")
		)
		(pad "U76" smd circle
			(at 25.216612 -19.445732 270)
			(size 0.4318 0.4318)
			(layers "F.Cu" "F.Mask" "F.Paste")
			(net "M_C_CPU1_SA_DQS_DP<0>")
		)
		(pad "U78" smd circle
			(at 26.844498 -19.445732 270)
			(size 0.4318 0.4318)
			(layers "F.Cu" "F.Mask" "F.Paste")
			(net "M_C_CPU1_SA_DQ<0>")
		)
		(pad "U80" smd circle
			(at 28.472384 -19.445732 270)
			(size 0.4318 0.4318)
			(layers "F.Cu" "F.Mask" "F.Paste")
			(net "UPI_CPU1_CPU0_P2P2_DN<7>")
		)
		(pad "U82" smd circle
			(at 30.100016 -19.445732 270)
			(size 0.4318 0.4318)
			(layers "F.Cu" "F.Mask" "F.Paste")
			(net "GND")
		)
		(pad "U84" smd circle
			(at 31.727902 -19.445732 270)
			(size 0.4318 0.4318)
			(layers "F.Cu" "F.Mask" "F.Paste")
			(net "GND")
		)
		(pad "U86" smd circle
			(at 33.355534 -19.445732 270)
			(size 0.4318 0.4318)
			(layers "F.Cu" "F.Mask" "F.Paste")
			(net "P5E_CPU1_PE4_TX_DN<3>")
		)
		(pad "U88" smd circle
			(at 34.98342 -19.445732 270)
			(size 0.4318 0.4318)
			(layers "F.Cu" "F.Mask" "F.Paste")
			(net "GND")
		)
		(pad "U90" smd circle
			(at 36.611306 -19.445732 270)
			(size 0.4318 0.4318)
			(layers "F.Cu" "F.Mask" "F.Paste")
			(net "P5E_CPU1_PE4_RX_DP<3>")
		)
		(pad "V2" smd circle
			(at -36.611306 -19.086068 270)
			(size 0.4318 0.4318)
			(layers "F.Cu" "F.Mask" "F.Paste")
			(net "UPI_CPU1_CPU0_P0P1_DP<4>")
		)
		(pad "V4" smd circle
			(at -34.98342 -19.086068 270)
			(size 0.4318 0.4318)
			(layers "F.Cu" "F.Mask" "F.Paste")
			(net "GND")
		)
		(pad "V6" smd circle
			(at -33.355534 -19.086068 270)
			(size 0.4318 0.4318)
			(layers "F.Cu" "F.Mask" "F.Paste")
			(net "UPI_CPU0_CPU1_P1P0_DN<4>")
		)
		(pad "V8" smd circle
			(at -31.727902 -19.086068 270)
			(size 0.4318 0.4318)
			(layers "F.Cu" "F.Mask" "F.Paste")
			(net "GND")
		)
		(pad "V10" smd circle
			(at -30.100016 -19.086068 270)
			(size 0.4318 0.4318)
			(layers "F.Cu" "F.Mask" "F.Paste")
			(net "P5E_CPU1_PE0_RX_DN<4>")
		)
		(pad "V12" smd circle
			(at -28.472384 -19.086068 270)
			(size 0.4318 0.4318)
			(layers "F.Cu" "F.Mask" "F.Paste")
			(net "GND")
		)
		(pad "V14" smd circle
			(at -26.844498 -19.086068 270)
			(size 0.4318 0.4318)
			(layers "F.Cu" "F.Mask" "F.Paste")
			(net "P5E_CPU1_PE0_TX_DN<3>")
		)
		(pad "V16" smd circle
			(at -25.216612 -19.086068 270)
			(size 0.4318 0.4318)
			(layers "F.Cu" "F.Mask" "F.Paste")
			(net "GND")
		)
		(pad "V18" smd circle
			(at -23.58898 -19.086068 270)
			(size 0.4318 0.4318)
			(layers "F.Cu" "F.Mask" "F.Paste")
			(net "GND")
		)
		(pad "V20" smd circle
			(at -21.961094 -19.086068 270)
			(size 0.4318 0.4318)
			(layers "F.Cu" "F.Mask" "F.Paste")
			(net "GND")
		)
		(pad "V22" smd circle
			(at -20.333462 -19.086068 270)
			(size 0.4318 0.4318)
			(layers "F.Cu" "F.Mask" "F.Paste")
			(net "GND")
		)
		(pad "V24" smd circle
			(at -18.705576 -19.086068 270)
			(size 0.4318 0.4318)
			(layers "F.Cu" "F.Mask" "F.Paste")
			(net "GND")
		)
		(pad "V26" smd circle
			(at -17.07769 -19.086068 270)
			(size 0.4318 0.4318)
			(layers "F.Cu" "F.Mask" "F.Paste")
			(net "GND")
		)
		(pad "V28" smd circle
			(at -15.450058 -19.086068 270)
			(size 0.4318 0.4318)
			(layers "F.Cu" "F.Mask" "F.Paste")
			(net "GND")
		)
		(pad "V30" smd circle
			(at -13.822426 -19.086068 270)
			(size 0.4318 0.4318)
			(layers "F.Cu" "F.Mask" "F.Paste")
			(net "GND")
		)
		(pad "V32" smd circle
			(at -12.19454 -19.086068 270)
			(size 0.4318 0.4318)
			(layers "F.Cu" "F.Mask" "F.Paste")
			(net "GND")
		)
		(pad "V34" smd circle
			(at -10.566654 -19.086068 270)
			(size 0.4318 0.4318)
			(layers "F.Cu" "F.Mask" "F.Paste")
			(net "GND")
		)
		(pad "V36" smd circle
			(at -8.939022 -19.086068 270)
			(size 0.4318 0.4318)
			(layers "F.Cu" "F.Mask" "F.Paste")
			(net "GND")
		)
		(pad "V38" smd circle
			(at -7.311136 -19.086068 270)
			(size 0.4318 0.4318)
			(layers "F.Cu" "F.Mask" "F.Paste")
			(net "GND")
		)
		(pad "V40" smd circle
			(at -5.68325 -19.086068 270)
			(size 0.4318 0.4318)
			(layers "F.Cu" "F.Mask" "F.Paste")
			(net "GND")
		)
		(pad "V42" smd circle
			(at -4.055618 -19.086068 270)
			(size 0.4318 0.4318)
			(layers "F.Cu" "F.Mask" "F.Paste")
			(net "GND")
		)
		(pad "V44" smd circle
			(at -2.427732 -19.086068 270)
			(size 0.4318 0.4318)
			(layers "F.Cu" "F.Mask" "F.Paste")
			(net "GND")
		)
		(pad "V47" smd circle
			(at 1.613916 -18.976086 270)
			(size 0.4318 0.4318)
			(layers "F.Cu" "F.Mask" "F.Paste")
			(net "GND")
		)
		(pad "V49" smd circle
			(at 3.241802 -18.976086 270)
			(size 0.4318 0.4318)
			(layers "F.Cu" "F.Mask" "F.Paste")
			(net "GND")
		)
		(pad "V51" smd circle
			(at 4.869434 -18.976086 270)
			(size 0.4318 0.4318)
			(layers "F.Cu" "F.Mask" "F.Paste")
			(net "GND")
		)
		(pad "V53" smd circle
			(at 6.49732 -18.976086 270)
			(size 0.4318 0.4318)
			(layers "F.Cu" "F.Mask" "F.Paste")
			(net "GND")
		)
		(pad "V55" smd circle
			(at 8.124952 -18.976086 270)
			(size 0.4318 0.4318)
			(layers "F.Cu" "F.Mask" "F.Paste")
			(net "GND")
		)
		(pad "V57" smd circle
			(at 9.752838 -18.976086 270)
			(size 0.4318 0.4318)
			(layers "F.Cu" "F.Mask" "F.Paste")
			(net "GND")
		)
		(pad "V59" smd circle
			(at 11.380724 -18.976086 270)
			(size 0.4318 0.4318)
			(layers "F.Cu" "F.Mask" "F.Paste")
			(net "GND")
		)
		(pad "V61" smd circle
			(at 13.008356 -18.976086 270)
			(size 0.4318 0.4318)
			(layers "F.Cu" "F.Mask" "F.Paste")
			(net "GND")
		)
		(pad "V63" smd circle
			(at 14.635988 -18.976086 270)
			(size 0.4318 0.4318)
			(layers "F.Cu" "F.Mask" "F.Paste")
			(net "GND")
		)
		(pad "V65" smd circle
			(at 16.263874 -18.976086 270)
			(size 0.4318 0.4318)
			(layers "F.Cu" "F.Mask" "F.Paste")
			(net "GND")
		)
		(pad "V67" smd circle
			(at 17.89176 -18.976086 270)
			(size 0.4318 0.4318)
			(layers "F.Cu" "F.Mask" "F.Paste")
			(net "GND")
		)
		(pad "V69" smd circle
			(at 19.519392 -18.976086 270)
			(size 0.4318 0.4318)
			(layers "F.Cu" "F.Mask" "F.Paste")
			(net "GND")
		)
		(pad "V71" smd circle
			(at 21.147278 -18.976086 270)
			(size 0.4318 0.4318)
			(layers "F.Cu" "F.Mask" "F.Paste")
			(net "GND")
		)
		(pad "V73" smd circle
			(at 22.77491 -18.976086 270)
			(size 0.4318 0.4318)
			(layers "F.Cu" "F.Mask" "F.Paste")
			(net "GND")
		)
		(pad "V75" smd circle
			(at 24.402796 -18.976086 270)
			(size 0.4318 0.4318)
			(layers "F.Cu" "F.Mask" "F.Paste")
			(net "GND")
		)
		(pad "V77" smd circle
			(at 26.030682 -18.976086 270)
			(size 0.4318 0.4318)
			(layers "F.Cu" "F.Mask" "F.Paste")
			(net "GND")
		)
		(pad "V79" smd circle
			(at 27.658314 -18.976086 270)
			(size 0.4318 0.4318)
			(layers "F.Cu" "F.Mask" "F.Paste")
			(net "GND")
		)
		(pad "V81" smd circle
			(at 29.2862 -18.976086 270)
			(size 0.4318 0.4318)
			(layers "F.Cu" "F.Mask" "F.Paste")
			(net "UPI_CPU1_CPU0_P2P2_DP<7>")
		)
		(pad "V83" smd circle
			(at 30.914086 -18.976086 270)
			(size 0.4318 0.4318)
			(layers "F.Cu" "F.Mask" "F.Paste")
			(net "UPI_CPU1_CPU0_P2P2_DN<8>")
		)
		(pad "V85" smd circle
			(at 32.541718 -18.976086 270)
			(size 0.4318 0.4318)
			(layers "F.Cu" "F.Mask" "F.Paste")
			(net "P5E_CPU1_PE4_TX_DP<3>")
		)
		(pad "V87" smd circle
			(at 34.169604 -18.976086 270)
			(size 0.4318 0.4318)
			(layers "F.Cu" "F.Mask" "F.Paste")
			(net "GND")
		)
		(pad "V89" smd circle
			(at 35.797236 -18.976086 270)
			(size 0.4318 0.4318)
			(layers "F.Cu" "F.Mask" "F.Paste")
			(net "P5E_CPU1_PE4_RX_DN<3>")
		)
		(pad "V91" smd oval
			(at 37.425122 -18.976086)
			(size 0.381 0.4826)
			(drill
				(offset 0 -0.0508)
			)
			(layers "F.Cu" "F.Mask" "F.Paste")
			(net "GND")
		)
		(pad "W1" smd oval
			(at -37.425122 -18.615914 180)
			(size 0.381 0.4826)
			(drill
				(offset 0 -0.0508)
			)
			(layers "F.Cu" "F.Mask" "F.Paste")
			(net "GND")
		)
		(pad "W3" smd circle
			(at -35.797236 -18.615914 270)
			(size 0.4318 0.4318)
			(layers "F.Cu" "F.Mask" "F.Paste")
			(net "UPI_CPU1_CPU0_P0P1_DP<5>")
		)
		(pad "W5" smd circle
			(at -34.169604 -18.615914 270)
			(size 0.4318 0.4318)
			(layers "F.Cu" "F.Mask" "F.Paste")
			(net "GND")
		)
		(pad "W7" smd circle
			(at -32.541718 -18.615914 270)
			(size 0.4318 0.4318)
			(layers "F.Cu" "F.Mask" "F.Paste")
			(net "UPI_CPU0_CPU1_P1P0_DP<4>")
		)
		(pad "W9" smd circle
			(at -30.914086 -18.615914 270)
			(size 0.4318 0.4318)
			(layers "F.Cu" "F.Mask" "F.Paste")
			(net "GND")
		)
		(pad "W11" smd circle
			(at -29.2862 -18.615914 270)
			(size 0.4318 0.4318)
			(layers "F.Cu" "F.Mask" "F.Paste")
			(net "P5E_CPU1_PE0_RX_DP<4>")
		)
		(pad "W13" smd circle
			(at -27.658314 -18.615914 270)
			(size 0.4318 0.4318)
			(layers "F.Cu" "F.Mask" "F.Paste")
			(net "GND")
		)
		(pad "W15" smd circle
			(at -26.030682 -18.615914 270)
			(size 0.4318 0.4318)
			(layers "F.Cu" "F.Mask" "F.Paste")
			(net "P5E_CPU1_PE0_TX_DP<3>")
		)
		(pad "W17" smd circle
			(at -24.402796 -18.615914 270)
			(size 0.4318 0.4318)
			(layers "F.Cu" "F.Mask" "F.Paste")
			(net "NC_CPU1_HBM1_VIEWDIG0")
		)
		(pad "W19" smd circle
			(at -22.77491 -18.615914 270)
			(size 0.4318 0.4318)
			(layers "F.Cu" "F.Mask" "F.Paste")
			(net "M_C_CPU1_SB_DQ<23>")
		)
		(pad "W21" smd circle
			(at -21.147278 -18.615914 270)
			(size 0.4318 0.4318)
			(layers "F.Cu" "F.Mask" "F.Paste")
			(net "M_C_CPU1_SB_DQS_DN<7>")
		)
		(pad "W23" smd circle
			(at -19.519392 -18.615914 270)
			(size 0.4318 0.4318)
			(layers "F.Cu" "F.Mask" "F.Paste")
			(net "M_C_CPU1_SB_DQ<18>")
		)
		(pad "W25" smd circle
			(at -17.89176 -18.615914 270)
			(size 0.4318 0.4318)
			(layers "F.Cu" "F.Mask" "F.Paste")
			(net "M_B_CPU1_SB_DQ<7>")
		)
		(pad "W27" smd circle
			(at -16.263874 -18.615914 270)
			(size 0.4318 0.4318)
			(layers "F.Cu" "F.Mask" "F.Paste")
			(net "M_B_CPU1_SB_DQS_DN<5>")
		)
		(pad "W29" smd circle
			(at -14.635988 -18.615914 270)
			(size 0.4318 0.4318)
			(layers "F.Cu" "F.Mask" "F.Paste")
			(net "M_B_CPU1_SB_DQ<2>")
		)
		(pad "W31" smd circle
			(at -13.008356 -18.615914 270)
			(size 0.4318 0.4318)
			(layers "F.Cu" "F.Mask" "F.Paste")
			(net "M_C_CPU1_SB_CB<3>")
		)
		(pad "W33" smd circle
			(at -11.380724 -18.615914 270)
			(size 0.4318 0.4318)
			(layers "F.Cu" "F.Mask" "F.Paste")
			(net "M_C_CPU1_SB_DQS_DN<4>")
		)
		(pad "W35" smd circle
			(at -9.752838 -18.615914 270)
			(size 0.4318 0.4318)
			(layers "F.Cu" "F.Mask" "F.Paste")
			(net "M_C_CPU1_SB_CB<6>")
		)
		(pad "W37" smd circle
			(at -8.124952 -18.615914 270)
			(size 0.4318 0.4318)
			(layers "F.Cu" "F.Mask" "F.Paste")
			(net "M_C_CPU1_SB_CS_N<3>")
		)
		(pad "W39" smd circle
			(at -6.49732 -18.615914 270)
			(size 0.4318 0.4318)
			(layers "F.Cu" "F.Mask" "F.Paste")
			(net "GND")
		)
		(pad "W41" smd circle
			(at -4.869434 -18.615914 270)
			(size 0.4318 0.4318)
			(layers "F.Cu" "F.Mask" "F.Paste")
			(net "M_C_CPU1_SB_CA<3>")
		)
		(pad "W43" smd circle
			(at -3.241802 -18.615914 270)
			(size 0.4318 0.4318)
			(layers "F.Cu" "F.Mask" "F.Paste")
			(net "M_B_CPU1_SA_PAR")
		)
		(pad "W45" smd circle
			(at -1.613916 -18.615914 270)
			(size 0.4318 0.4318)
			(layers "F.Cu" "F.Mask" "F.Paste")
			(net "M_B_CPU1_CLK_DN<1>")
		)
		(pad "W48" smd circle
			(at 2.427732 -18.505932 270)
			(size 0.4318 0.4318)
			(layers "F.Cu" "F.Mask" "F.Paste")
			(net "M_C_CPU1_SB_CA<0>")
		)
		(pad "W50" smd circle
			(at 4.055618 -18.505932 270)
			(size 0.4318 0.4318)
			(layers "F.Cu" "F.Mask" "F.Paste")
			(net "M_C_CPU1_SA_CA<5>")
		)
		(pad "W52" smd circle
			(at 5.68325 -18.505932 270)
			(size 0.4318 0.4318)
			(layers "F.Cu" "F.Mask" "F.Paste")
			(net "GND")
		)
		(pad "W54" smd circle
			(at 7.311136 -18.505932 270)
			(size 0.4318 0.4318)
			(layers "F.Cu" "F.Mask" "F.Paste")
			(net "M_C_CPU1_SA_CS_N<2>")
		)
		(pad "W56" smd circle
			(at 8.939022 -18.505932 270)
			(size 0.4318 0.4318)
			(layers "F.Cu" "F.Mask" "F.Paste")
			(net "M_B_CPU1_SA_DQ<31>")
		)
		(pad "W58" smd circle
			(at 10.566654 -18.505932 270)
			(size 0.4318 0.4318)
			(layers "F.Cu" "F.Mask" "F.Paste")
			(net "M_B_CPU1_SA_DQS_DP<8>")
		)
		(pad "W60" smd circle
			(at 12.19454 -18.505932 270)
			(size 0.4318 0.4318)
			(layers "F.Cu" "F.Mask" "F.Paste")
			(net "M_B_CPU1_SA_DQ<26>")
		)
		(pad "W62" smd circle
			(at 13.822426 -18.505932 270)
			(size 0.4318 0.4318)
			(layers "F.Cu" "F.Mask" "F.Paste")
			(net "M_C_CPU1_SA_DQ<23>")
		)
		(pad "W64" smd circle
			(at 15.450058 -18.505932 270)
			(size 0.4318 0.4318)
			(layers "F.Cu" "F.Mask" "F.Paste")
			(net "M_C_CPU1_SA_DQS_DP<7>")
		)
		(pad "W66" smd circle
			(at 17.07769 -18.505932 270)
			(size 0.4318 0.4318)
			(layers "F.Cu" "F.Mask" "F.Paste")
			(net "M_C_CPU1_SA_DQ<18>")
		)
		(pad "W68" smd circle
			(at 18.705576 -18.505932 270)
			(size 0.4318 0.4318)
			(layers "F.Cu" "F.Mask" "F.Paste")
			(net "M_B_CPU1_SA_DQ<15>")
		)
		(pad "W70" smd circle
			(at 20.333462 -18.505932 270)
			(size 0.4318 0.4318)
			(layers "F.Cu" "F.Mask" "F.Paste")
			(net "M_B_CPU1_SA_DQS_DP<6>")
		)
		(pad "W72" smd circle
			(at 21.961094 -18.505932 270)
			(size 0.4318 0.4318)
			(layers "F.Cu" "F.Mask" "F.Paste")
			(net "M_B_CPU1_SA_DQ<10>")
		)
		(pad "W74" smd circle
			(at 23.58898 -18.505932 270)
			(size 0.4318 0.4318)
			(layers "F.Cu" "F.Mask" "F.Paste")
			(net "M_C_CPU1_SA_DQ<7>")
		)
		(pad "W76" smd circle
			(at 25.216612 -18.505932 270)
			(size 0.4318 0.4318)
			(layers "F.Cu" "F.Mask" "F.Paste")
			(net "M_C_CPU1_SA_DQS_DN<5>")
		)
		(pad "W78" smd circle
			(at 26.844498 -18.505932 270)
			(size 0.4318 0.4318)
			(layers "F.Cu" "F.Mask" "F.Paste")
			(net "M_C_CPU1_SA_DQ<2>")
		)
		(pad "W80" smd circle
			(at 28.472384 -18.505932 270)
			(size 0.4318 0.4318)
			(layers "F.Cu" "F.Mask" "F.Paste")
			(net "PVCCFA_EHV_FIVRA_CPU1")
		)
		(pad "W82" smd circle
			(at 30.100016 -18.505932 270)
			(size 0.4318 0.4318)
			(layers "F.Cu" "F.Mask" "F.Paste")
			(net "UPI_CPU1_CPU0_P2P2_DP<9>")
		)
		(pad "W84" smd circle
			(at 31.727902 -18.505932 270)
			(size 0.4318 0.4318)
			(layers "F.Cu" "F.Mask" "F.Paste")
			(net "GND")
		)
		(pad "W86" smd circle
			(at 33.355534 -18.505932 270)
			(size 0.4318 0.4318)
			(layers "F.Cu" "F.Mask" "F.Paste")
			(net "P5E_CPU1_PE4_TX_DN<4>")
		)
		(pad "W88" smd circle
			(at 34.98342 -18.505932 270)
			(size 0.4318 0.4318)
			(layers "F.Cu" "F.Mask" "F.Paste")
			(net "GND")
		)
		(pad "W90" smd circle
			(at 36.611306 -18.505932 270)
			(size 0.4318 0.4318)
			(layers "F.Cu" "F.Mask" "F.Paste")
			(net "P5E_CPU1_PE4_RX_DP<4>")
		)
		(pad "Y2" smd circle
			(at -36.611306 -18.146268 270)
			(size 0.4318 0.4318)
			(layers "F.Cu" "F.Mask" "F.Paste")
			(net "UPI_CPU1_CPU0_P0P1_DN<5>")
		)
		(pad "Y4" smd circle
			(at -34.98342 -18.146268 270)
			(size 0.4318 0.4318)
			(layers "F.Cu" "F.Mask" "F.Paste")
			(net "GND")
		)
		(pad "Y6" smd circle
			(at -33.355534 -18.146268 270)
			(size 0.4318 0.4318)
			(layers "F.Cu" "F.Mask" "F.Paste")
			(net "UPI_CPU0_CPU1_P1P0_DP<5>")
		)
		(pad "Y8" smd circle
			(at -31.727902 -18.146268 270)
			(size 0.4318 0.4318)
			(layers "F.Cu" "F.Mask" "F.Paste")
			(net "GND")
		)
		(pad "Y10" smd circle
			(at -30.100016 -18.146268 270)
			(size 0.4318 0.4318)
			(layers "F.Cu" "F.Mask" "F.Paste")
			(net "P5E_CPU1_PE0_RX_DP<5>")
		)
		(pad "Y12" smd circle
			(at -28.472384 -18.146268 270)
			(size 0.4318 0.4318)
			(layers "F.Cu" "F.Mask" "F.Paste")
			(net "GND")
		)
		(pad "Y14" smd circle
			(at -26.844498 -18.146268 270)
			(size 0.4318 0.4318)
			(layers "F.Cu" "F.Mask" "F.Paste")
			(net "P5E_CPU1_PE0_TX_DP<4>")
		)
		(pad "Y16" smd circle
			(at -25.216612 -18.146268 270)
			(size 0.4318 0.4318)
			(layers "F.Cu" "F.Mask" "F.Paste")
			(net "GND")
		)
		(pad "Y18" smd circle
			(at -23.58898 -18.146268 270)
			(size 0.4318 0.4318)
			(layers "F.Cu" "F.Mask" "F.Paste")
			(net "GND")
		)
		(pad "Y20" smd circle
			(at -21.961094 -18.146268 270)
			(size 0.4318 0.4318)
			(layers "F.Cu" "F.Mask" "F.Paste")
			(net "M_C_CPU1_SB_DQ<22>")
		)
		(pad "Y22" smd circle
			(at -20.333462 -18.146268 270)
			(size 0.4318 0.4318)
			(layers "F.Cu" "F.Mask" "F.Paste")
			(net "M_C_CPU1_SB_DQ<19>")
		)
		(pad "Y24" smd circle
			(at -18.705576 -18.146268 270)
			(size 0.4318 0.4318)
			(layers "F.Cu" "F.Mask" "F.Paste")
			(net "GND")
		)
		(pad "Y26" smd circle
			(at -17.07769 -18.146268 270)
			(size 0.4318 0.4318)
			(layers "F.Cu" "F.Mask" "F.Paste")
			(net "M_B_CPU1_SB_DQ<6>")
		)
		(pad "Y28" smd circle
			(at -15.450058 -18.146268 270)
			(size 0.4318 0.4318)
			(layers "F.Cu" "F.Mask" "F.Paste")
			(net "M_B_CPU1_SB_DQ<3>")
		)
		(pad "Y30" smd circle
			(at -13.822426 -18.146268 270)
			(size 0.4318 0.4318)
			(layers "F.Cu" "F.Mask" "F.Paste")
			(net "GND")
		)
		(pad "Y32" smd circle
			(at -12.19454 -18.146268 270)
			(size 0.4318 0.4318)
			(layers "F.Cu" "F.Mask" "F.Paste")
			(net "M_C_CPU1_SB_CB<2>")
		)
		(pad "Y34" smd circle
			(at -10.566654 -18.146268 270)
			(size 0.4318 0.4318)
			(layers "F.Cu" "F.Mask" "F.Paste")
			(net "M_C_CPU1_SB_CB<7>")
		)
		(pad "Y36" smd circle
			(at -8.939022 -18.146268 270)
			(size 0.4318 0.4318)
			(layers "F.Cu" "F.Mask" "F.Paste")
			(net "GND")
		)
		(pad "Y38" smd circle
			(at -7.311136 -18.146268 270)
			(size 0.4318 0.4318)
			(layers "F.Cu" "F.Mask" "F.Paste")
			(net "M_C_CPU1_SB_CS_N<2>")
		)
		(pad "Y40" smd circle
			(at -5.68325 -18.146268 270)
			(size 0.4318 0.4318)
			(layers "F.Cu" "F.Mask" "F.Paste")
			(net "M_C_CPU1_SB_CA<5>")
		)
		(pad "Y42" smd circle
			(at -4.055618 -18.146268 270)
			(size 0.4318 0.4318)
			(layers "F.Cu" "F.Mask" "F.Paste")
			(net "GND")
		)
		(pad "Y44" smd circle
			(at -2.427732 -18.146268 270)
			(size 0.4318 0.4318)
			(layers "F.Cu" "F.Mask" "F.Paste")
			(net "M_B_CPU1_SA_CA<6>")
		)
		(pad "Y47" smd circle
			(at 1.613916 -18.036286 270)
			(size 0.4318 0.4318)
			(layers "F.Cu" "F.Mask" "F.Paste")
			(net "M_C_CPU1_SB_CA<1>")
		)
		(pad "Y49" smd circle
			(at 3.241802 -18.036286 270)
			(size 0.4318 0.4318)
			(layers "F.Cu" "F.Mask" "F.Paste")
			(net "GND")
		)
		(pad "Y51" smd circle
			(at 4.869434 -18.036286 270)
			(size 0.4318 0.4318)
			(layers "F.Cu" "F.Mask" "F.Paste")
			(net "M_C_CPU1_SA_CA<3>")
		)
		(pad "Y53" smd circle
			(at 6.49732 -18.036286 270)
			(size 0.4318 0.4318)
			(layers "F.Cu" "F.Mask" "F.Paste")
			(net "M_C_CPU1_SA_CS_N<3>")
		)
		(pad "Y55" smd circle
			(at 8.124952 -18.036286 270)
			(size 0.4318 0.4318)
			(layers "F.Cu" "F.Mask" "F.Paste")
			(net "GND")
		)
		(pad "Y57" smd circle
			(at 9.752838 -18.036286 270)
			(size 0.4318 0.4318)
			(layers "F.Cu" "F.Mask" "F.Paste")
			(net "M_B_CPU1_SA_DQ<30>")
		)
		(pad "Y59" smd circle
			(at 11.380724 -18.036286 270)
			(size 0.4318 0.4318)
			(layers "F.Cu" "F.Mask" "F.Paste")
			(net "M_B_CPU1_SA_DQ<27>")
		)
		(pad "Y61" smd circle
			(at 13.008356 -18.036286 270)
			(size 0.4318 0.4318)
			(layers "F.Cu" "F.Mask" "F.Paste")
			(net "GND")
		)
		(pad "Y63" smd circle
			(at 14.635988 -18.036286 270)
			(size 0.4318 0.4318)
			(layers "F.Cu" "F.Mask" "F.Paste")
			(net "M_C_CPU1_SA_DQ<22>")
		)
		(pad "Y65" smd circle
			(at 16.263874 -18.036286 270)
			(size 0.4318 0.4318)
			(layers "F.Cu" "F.Mask" "F.Paste")
			(net "M_C_CPU1_SA_DQ<19>")
		)
		(pad "Y67" smd circle
			(at 17.89176 -18.036286 270)
			(size 0.4318 0.4318)
			(layers "F.Cu" "F.Mask" "F.Paste")
			(net "GND")
		)
		(pad "Y69" smd circle
			(at 19.519392 -18.036286 270)
			(size 0.4318 0.4318)
			(layers "F.Cu" "F.Mask" "F.Paste")
			(net "M_B_CPU1_SA_DQ<14>")
		)
		(pad "Y71" smd circle
			(at 21.147278 -18.036286 270)
			(size 0.4318 0.4318)
			(layers "F.Cu" "F.Mask" "F.Paste")
			(net "M_B_CPU1_SA_DQ<11>")
		)
		(pad "Y73" smd circle
			(at 22.77491 -18.036286 270)
			(size 0.4318 0.4318)
			(layers "F.Cu" "F.Mask" "F.Paste")
			(net "GND")
		)
		(pad "Y75" smd circle
			(at 24.402796 -18.036286 270)
			(size 0.4318 0.4318)
			(layers "F.Cu" "F.Mask" "F.Paste")
			(net "M_C_CPU1_SA_DQ<6>")
		)
		(pad "Y77" smd circle
			(at 26.030682 -18.036286 270)
			(size 0.4318 0.4318)
			(layers "F.Cu" "F.Mask" "F.Paste")
			(net "M_C_CPU1_SA_DQ<3>")
		)
		(pad "Y79" smd circle
			(at 27.658314 -18.036286 270)
			(size 0.4318 0.4318)
			(layers "F.Cu" "F.Mask" "F.Paste")
			(net "PVCCFA_EHV_FIVRA_CPU1")
		)
		(pad "Y81" smd circle
			(at 29.2862 -18.036286 270)
			(size 0.4318 0.4318)
			(layers "F.Cu" "F.Mask" "F.Paste")
			(net "UPI_CPU1_CPU0_P2P2_DN<9>")
		)
		(pad "Y83" smd circle
			(at 30.914086 -18.036286 270)
			(size 0.4318 0.4318)
			(layers "F.Cu" "F.Mask" "F.Paste")
			(net "UPI_CPU1_CPU0_P2P2_DP<8>")
		)
		(pad "Y85" smd circle
			(at 32.541718 -18.036286 270)
			(size 0.4318 0.4318)
			(layers "F.Cu" "F.Mask" "F.Paste")
			(net "PVCCFA_EHV_FIVRA_CPU1")
		)
		(pad "Y87" smd circle
			(at 34.169604 -18.036286 270)
			(size 0.4318 0.4318)
			(layers "F.Cu" "F.Mask" "F.Paste")
			(net "P5E_CPU1_PE4_TX_DP<4>")
		)
		(pad "Y89" smd circle
			(at 35.797236 -18.036286 270)
			(size 0.4318 0.4318)
			(layers "F.Cu" "F.Mask" "F.Paste")
			(net "PVCCFA_EHV_FIVRA_CPU1")
		)
		(pad "Y91" smd oval
			(at 37.425122 -18.036286)
			(size 0.381 0.4826)
			(drill
				(offset 0 -0.0508)
			)
			(layers "F.Cu" "F.Mask" "F.Paste")
			(net "P5E_CPU1_PE4_RX_DN<4>")
		)
		(zone
			(layer "F.Cu")
			(hatch none 0.5)
			(connect_pads
				(clearance 0)
			)
			(min_thickness 0.25)
			(keepout
				(tracks not_allowed)
				(vias allowed)
				(pads allowed)
				(copperpour not_allowed)
				(footprints allowed)
			)
			(placement
				(enabled no)
				(sheetname "")
			)
			(fill
				(thermal_gap 0.5)
				(thermal_bridge_width 0.5)
				(island_removal_mode 0)
			)
			(polygon
				(pts
					(arc
						(start 84.67725 -220.9673)
						(mid 84.641329 -220.982179)
						(end 84.62645 -221.0181)
					)
					(arc
						(start 84.62645 -221.0181)
						(mid 84.630561 -221.038119)
						(end 84.642198 -221.05493)
					)
					(arc
						(start 84.642198 -221.05493)
						(mid 84.739458 -221.123652)
						(end 84.856066 -221.147894)
					)
					(arc
						(start 84.856066 -221.147894)
						(mid 85.062612 -221.06234)
						(end 85.148166 -220.855794)
					)
					(arc
						(start 85.148166 -220.855794)
						(mid 85.124344 -220.740509)
						(end 85.05698 -220.643958)
					)
					(arc
						(start 85.05698 -220.643958)
						(mid 85.039752 -220.631389)
						(end 85.01888 -220.62694)
					)
					(arc
						(start 85.01888 -220.62694)
						(mid 84.982959 -220.641819)
						(end 84.96808 -220.67774)
					)
					(arc
						(start 84.96808 -220.67774)
						(mid 84.970255 -220.692194)
						(end 84.976462 -220.705426)
					)
					(xy 84.991194 -220.720158) (xy 84.991448 -220.720412)
					(arc
						(start 84.99221 -220.721174)
						(mid 85.033189 -220.783022)
						(end 85.047582 -220.855794)
					)
					(arc
						(start 85.047582 -220.855794)
						(mid 84.991488 -220.991216)
						(end 84.856066 -221.04731)
					)
					(arc
						(start 84.856066 -221.04731)
						(mid 84.782444 -221.032594)
						(end 84.720176 -220.990668)
					)
					(xy 84.719668 -220.99016)
					(arc
						(start 84.70519 -220.975682)
						(mid 84.691834 -220.969446)
						(end 84.67725 -220.9673)
					)
				)
			)
		)
		(zone
			(layer "F.Cu")
			(hatch none 0.5)
			(connect_pads
				(clearance 0)
			)
			(min_thickness 0.25)
			(keepout
				(tracks not_allowed)
				(vias allowed)
				(pads allowed)
				(copperpour not_allowed)
				(footprints allowed)
			)
			(placement
				(enabled no)
				(sheetname "")
			)
			(fill
				(thermal_gap 0.5)
				(thermal_bridge_width 0.5)
				(island_removal_mode 0)
			)
			(polygon
				(pts
					(arc
						(start 84.808314 -248.73331)
						(mid 84.7933 -248.769288)
						(end 84.808314 -248.805192)
					)
					(arc
						(start 84.808314 -248.805192)
						(mid 84.825436 -248.816543)
						(end 84.845652 -248.820178)
					)
					(arc
						(start 84.845652 -248.820178)
						(mid 84.96302 -248.799963)
						(end 85.062568 -248.73458)
					)
					(arc
						(start 85.062568 -248.73458)
						(mid 85.148104 -248.528078)
						(end 85.062568 -248.321576)
					)
					(arc
						(start 85.062568 -248.321576)
						(mid 84.964175 -248.256787)
						(end 84.848192 -248.236232)
					)
					(arc
						(start 84.848192 -248.236232)
						(mid 84.827183 -248.239432)
						(end 84.80933 -248.250964)
					)
					(arc
						(start 84.80933 -248.250964)
						(mid 84.794316 -248.286942)
						(end 84.80933 -248.322846)
					)
					(arc
						(start 84.80933 -248.322846)
						(mid 84.821151 -248.331588)
						(end 84.834984 -248.336562)
					)
					(xy 84.855558 -248.336562) (xy 84.856066 -248.336562)
					(arc
						(start 84.857082 -248.336562)
						(mid 84.929787 -248.3514)
						(end 84.991448 -248.392696)
					)
					(arc
						(start 84.991448 -248.392696)
						(mid 85.047525 -248.528078)
						(end 84.991448 -248.66346)
					)
					(arc
						(start 84.991448 -248.66346)
						(mid 84.928982 -248.705109)
						(end 84.855304 -248.719594)
					)
					(xy 84.854542 -248.719594)
					(arc
						(start 84.833968 -248.719594)
						(mid 84.820144 -248.724585)
						(end 84.808314 -248.73331)
					)
				)
			)
		)
		(zone
			(layer "F.Cu")
			(hatch none 0.5)
			(connect_pads
				(clearance 0)
			)
			(min_thickness 0.25)
			(keepout
				(tracks not_allowed)
				(vias allowed)
				(pads allowed)
				(copperpour not_allowed)
				(footprints allowed)
			)
			(placement
				(enabled no)
				(sheetname "")
			)
			(fill
				(thermal_gap 0.5)
				(thermal_bridge_width 0.5)
				(island_removal_mode 0)
			)
			(polygon
				(pts
					(arc
						(start 84.808314 -247.105678)
						(mid 84.793553 -247.141492)
						(end 84.808314 -247.177306)
					)
					(arc
						(start 84.808314 -247.177306)
						(mid 84.825436 -247.188657)
						(end 84.845652 -247.192292)
					)
					(arc
						(start 84.845652 -247.192292)
						(mid 84.962993 -247.172198)
						(end 85.062568 -247.106948)
					)
					(arc
						(start 85.062568 -247.106948)
						(mid 85.148104 -246.900446)
						(end 85.062568 -246.693944)
					)
					(arc
						(start 85.062568 -246.693944)
						(mid 84.964206 -246.629015)
						(end 84.848192 -246.608346)
					)
					(arc
						(start 84.848192 -246.608346)
						(mid 84.82717 -246.611534)
						(end 84.80933 -246.623078)
					)
					(arc
						(start 84.80933 -246.623078)
						(mid 84.794316 -246.659056)
						(end 84.80933 -246.69496)
					)
					(arc
						(start 84.80933 -246.69496)
						(mid 84.821135 -246.703743)
						(end 84.834984 -246.708676)
					)
					(xy 84.855558 -246.708676) (xy 84.856066 -246.708676)
					(arc
						(start 84.857082 -246.708676)
						(mid 84.929817 -246.72363)
						(end 84.991448 -246.765064)
					)
					(arc
						(start 84.991448 -246.765064)
						(mid 85.047525 -246.900446)
						(end 84.991448 -247.035828)
					)
					(arc
						(start 84.991448 -247.035828)
						(mid 84.928983 -247.077506)
						(end 84.855304 -247.091962)
					)
					(xy 84.854542 -247.091708)
					(arc
						(start 84.833968 -247.091708)
						(mid 84.820106 -247.096798)
						(end 84.808314 -247.105678)
					)
				)
			)
		)
		(zone
			(layer "F.Cu")
			(hatch none 0.5)
			(connect_pads
				(clearance 0)
			)
			(min_thickness 0.25)
			(keepout
				(tracks not_allowed)
				(vias allowed)
				(pads allowed)
				(copperpour not_allowed)
				(footprints allowed)
			)
			(placement
				(enabled no)
				(sheetname "")
			)
			(fill
				(thermal_gap 0.5)
				(thermal_bridge_width 0.5)
				(island_removal_mode 0)
			)
			(polygon
				(pts
					(arc
						(start 84.808314 -245.477792)
						(mid 84.7933 -245.51377)
						(end 84.808314 -245.549674)
					)
					(arc
						(start 84.808314 -245.549674)
						(mid 84.825436 -245.561025)
						(end 84.845652 -245.56466)
					)
					(arc
						(start 84.845652 -245.56466)
						(mid 84.96302 -245.544445)
						(end 85.062568 -245.479062)
					)
					(arc
						(start 85.062568 -245.479062)
						(mid 85.148104 -245.27256)
						(end 85.062568 -245.066058)
					)
					(arc
						(start 85.062568 -245.066058)
						(mid 84.964175 -245.001269)
						(end 84.848192 -244.980714)
					)
					(arc
						(start 84.848192 -244.980714)
						(mid 84.827183 -244.983914)
						(end 84.80933 -244.995446)
					)
					(arc
						(start 84.80933 -244.995446)
						(mid 84.794316 -245.031424)
						(end 84.80933 -245.067328)
					)
					(arc
						(start 84.80933 -245.067328)
						(mid 84.821135 -245.076111)
						(end 84.834984 -245.081044)
					)
					(xy 84.855558 -245.081044) (xy 84.856066 -245.081044)
					(arc
						(start 84.857082 -245.081044)
						(mid 84.929787 -245.095882)
						(end 84.991448 -245.137178)
					)
					(arc
						(start 84.991448 -245.137178)
						(mid 85.047705 -245.272724)
						(end 84.991448 -245.408196)
					)
					(arc
						(start 84.991448 -245.408196)
						(mid 84.928953 -245.449707)
						(end 84.855304 -245.464076)
					)
					(xy 84.854542 -245.464076)
					(arc
						(start 84.833968 -245.464076)
						(mid 84.820144 -245.469067)
						(end 84.808314 -245.477792)
					)
				)
			)
		)
		(zone
			(layer "F.Cu")
			(hatch none 0.5)
			(connect_pads
				(clearance 0)
			)
			(min_thickness 0.25)
			(keepout
				(tracks not_allowed)
				(vias allowed)
				(pads allowed)
				(copperpour not_allowed)
				(footprints allowed)
			)
			(placement
				(enabled no)
				(sheetname "")
			)
			(fill
				(thermal_gap 0.5)
				(thermal_bridge_width 0.5)
				(island_removal_mode 0)
			)
			(polygon
				(pts
					(arc
						(start 84.808314 -243.85016)
						(mid 84.793553 -243.885974)
						(end 84.808314 -243.921788)
					)
					(arc
						(start 84.808314 -243.921788)
						(mid 84.825436 -243.933139)
						(end 84.845652 -243.936774)
					)
					(arc
						(start 84.845652 -243.936774)
						(mid 84.962993 -243.91668)
						(end 85.062568 -243.85143)
					)
					(arc
						(start 85.062568 -243.85143)
						(mid 85.148104 -243.644928)
						(end 85.062568 -243.438426)
					)
					(arc
						(start 85.062568 -243.438426)
						(mid 84.964206 -243.373497)
						(end 84.848192 -243.352828)
					)
					(arc
						(start 84.848192 -243.352828)
						(mid 84.82717 -243.356016)
						(end 84.80933 -243.36756)
					)
					(arc
						(start 84.80933 -243.36756)
						(mid 84.794315 -243.403628)
						(end 84.80933 -243.439696)
					)
					(arc
						(start 84.80933 -243.439696)
						(mid 84.821184 -243.448272)
						(end 84.834984 -243.453158)
					)
					(xy 84.855558 -243.453158) (xy 84.856066 -243.453158)
					(arc
						(start 84.857082 -243.453158)
						(mid 84.929817 -243.468112)
						(end 84.991448 -243.509546)
					)
					(arc
						(start 84.991448 -243.509546)
						(mid 85.047525 -243.644928)
						(end 84.991448 -243.78031)
					)
					(arc
						(start 84.991448 -243.78031)
						(mid 84.928997 -243.822042)
						(end 84.855304 -243.836444)
					)
					(xy 84.854542 -243.83619)
					(arc
						(start 84.833968 -243.83619)
						(mid 84.820106 -243.84128)
						(end 84.808314 -243.85016)
					)
				)
			)
		)
		(zone
			(layer "F.Cu")
			(hatch none 0.5)
			(connect_pads
				(clearance 0)
			)
			(min_thickness 0.25)
			(keepout
				(tracks not_allowed)
				(vias allowed)
				(pads allowed)
				(copperpour not_allowed)
				(footprints allowed)
			)
			(placement
				(enabled no)
				(sheetname "")
			)
			(fill
				(thermal_gap 0.5)
				(thermal_bridge_width 0.5)
				(island_removal_mode 0)
			)
			(polygon
				(pts
					(arc
						(start 84.808314 -242.222274)
						(mid 84.7933 -242.258252)
						(end 84.808314 -242.294156)
					)
					(arc
						(start 84.808314 -242.294156)
						(mid 84.825467 -242.305367)
						(end 84.845652 -242.308888)
					)
					(arc
						(start 84.845652 -242.308888)
						(mid 84.962993 -242.288794)
						(end 85.062568 -242.223544)
					)
					(arc
						(start 85.062568 -242.223544)
						(mid 85.148104 -242.017042)
						(end 85.062568 -241.81054)
					)
					(arc
						(start 85.062568 -241.81054)
						(mid 84.964175 -241.745751)
						(end 84.848192 -241.725196)
					)
					(arc
						(start 84.848192 -241.725196)
						(mid 84.827183 -241.728396)
						(end 84.80933 -241.739928)
					)
					(arc
						(start 84.80933 -241.739928)
						(mid 84.794316 -241.775906)
						(end 84.80933 -241.81181)
					)
					(arc
						(start 84.80933 -241.81181)
						(mid 84.821151 -241.820552)
						(end 84.834984 -241.825526)
					)
					(xy 84.855558 -241.825526) (xy 84.856066 -241.825526)
					(arc
						(start 84.857082 -241.825526)
						(mid 84.929787 -241.840364)
						(end 84.991448 -241.88166)
					)
					(arc
						(start 84.991448 -241.88166)
						(mid 85.047525 -242.017042)
						(end 84.991448 -242.152424)
					)
					(arc
						(start 84.991448 -242.152424)
						(mid 84.928982 -242.194073)
						(end 84.855304 -242.208558)
					)
					(xy 84.854542 -242.208304)
					(arc
						(start 84.833968 -242.208304)
						(mid 84.820106 -242.213394)
						(end 84.808314 -242.222274)
					)
				)
			)
		)
		(zone
			(layer "F.Cu")
			(hatch none 0.5)
			(connect_pads
				(clearance 0)
			)
			(min_thickness 0.25)
			(keepout
				(tracks not_allowed)
				(vias allowed)
				(pads allowed)
				(copperpour not_allowed)
				(footprints allowed)
			)
			(placement
				(enabled no)
				(sheetname "")
			)
			(fill
				(thermal_gap 0.5)
				(thermal_bridge_width 0.5)
				(island_removal_mode 0)
			)
			(polygon
				(pts
					(arc
						(start 84.808314 -240.594388)
						(mid 84.7933 -240.630366)
						(end 84.808314 -240.66627)
					)
					(arc
						(start 84.808314 -240.66627)
						(mid 84.825436 -240.677621)
						(end 84.845652 -240.681256)
					)
					(arc
						(start 84.845652 -240.681256)
						(mid 84.96302 -240.661041)
						(end 85.062568 -240.595658)
					)
					(arc
						(start 85.062568 -240.595658)
						(mid 85.148104 -240.389156)
						(end 85.062568 -240.182654)
					)
					(arc
						(start 85.062568 -240.182654)
						(mid 84.964175 -240.117865)
						(end 84.848192 -240.09731)
					)
					(arc
						(start 84.848192 -240.09731)
						(mid 84.827183 -240.10051)
						(end 84.80933 -240.112042)
					)
					(arc
						(start 84.80933 -240.112042)
						(mid 84.794316 -240.14802)
						(end 84.80933 -240.183924)
					)
					(arc
						(start 84.80933 -240.183924)
						(mid 84.821135 -240.192707)
						(end 84.834984 -240.19764)
					)
					(xy 84.855558 -240.19764) (xy 84.856066 -240.19764)
					(arc
						(start 84.857082 -240.19764)
						(mid 84.929787 -240.212478)
						(end 84.991448 -240.253774)
					)
					(arc
						(start 84.991448 -240.253774)
						(mid 85.047705 -240.38932)
						(end 84.991448 -240.524792)
					)
					(arc
						(start 84.991448 -240.524792)
						(mid 84.928953 -240.566303)
						(end 84.855304 -240.580672)
					)
					(xy 84.854542 -240.580672)
					(arc
						(start 84.833968 -240.580672)
						(mid 84.820144 -240.585663)
						(end 84.808314 -240.594388)
					)
				)
			)
		)
		(zone
			(layer "F.Cu")
			(hatch none 0.5)
			(connect_pads
				(clearance 0)
			)
			(min_thickness 0.25)
			(keepout
				(tracks not_allowed)
				(vias allowed)
				(pads allowed)
				(copperpour not_allowed)
				(footprints allowed)
			)
			(placement
				(enabled no)
				(sheetname "")
			)
			(fill
				(thermal_gap 0.5)
				(thermal_bridge_width 0.5)
				(island_removal_mode 0)
			)
			(polygon
				(pts
					(arc
						(start 84.808314 -238.966756)
						(mid 84.7933 -239.002734)
						(end 84.808314 -239.038638)
					)
					(arc
						(start 84.808314 -239.038638)
						(mid 84.825467 -239.049849)
						(end 84.845652 -239.05337)
					)
					(arc
						(start 84.845652 -239.05337)
						(mid 84.962993 -239.033276)
						(end 85.062568 -238.968026)
					)
					(arc
						(start 85.062568 -238.968026)
						(mid 85.148104 -238.761524)
						(end 85.062568 -238.555022)
					)
					(arc
						(start 85.062568 -238.555022)
						(mid 84.964175 -238.490233)
						(end 84.848192 -238.469678)
					)
					(arc
						(start 84.848192 -238.469678)
						(mid 84.827183 -238.472878)
						(end 84.80933 -238.48441)
					)
					(arc
						(start 84.80933 -238.48441)
						(mid 84.794316 -238.520388)
						(end 84.80933 -238.556292)
					)
					(arc
						(start 84.80933 -238.556292)
						(mid 84.821151 -238.565034)
						(end 84.834984 -238.570008)
					)
					(xy 84.855558 -238.570008) (xy 84.856066 -238.570008)
					(arc
						(start 84.857082 -238.570008)
						(mid 84.929787 -238.584846)
						(end 84.991448 -238.626142)
					)
					(arc
						(start 84.991448 -238.626142)
						(mid 85.047525 -238.761524)
						(end 84.991448 -238.896906)
					)
					(arc
						(start 84.991448 -238.896906)
						(mid 84.928982 -238.938555)
						(end 84.855304 -238.95304)
					)
					(xy 84.854542 -238.952786)
					(arc
						(start 84.833968 -238.952786)
						(mid 84.820106 -238.957876)
						(end 84.808314 -238.966756)
					)
				)
			)
		)
		(zone
			(layer "F.Cu")
			(hatch none 0.5)
			(connect_pads
				(clearance 0)
			)
			(min_thickness 0.25)
			(keepout
				(tracks not_allowed)
				(vias allowed)
				(pads allowed)
				(copperpour not_allowed)
				(footprints allowed)
			)
			(placement
				(enabled no)
				(sheetname "")
			)
			(fill
				(thermal_gap 0.5)
				(thermal_bridge_width 0.5)
				(island_removal_mode 0)
			)
			(polygon
				(pts
					(arc
						(start 84.808314 -237.33887)
						(mid 84.7933 -237.374848)
						(end 84.808314 -237.410752)
					)
					(arc
						(start 84.808314 -237.410752)
						(mid 84.825436 -237.422103)
						(end 84.845652 -237.425738)
					)
					(arc
						(start 84.845652 -237.425738)
						(mid 84.962993 -237.405644)
						(end 85.062568 -237.340394)
					)
					(arc
						(start 85.062568 -237.340394)
						(mid 85.148104 -237.133892)
						(end 85.062568 -236.92739)
					)
					(arc
						(start 85.062568 -236.92739)
						(mid 84.964206 -236.862461)
						(end 84.848192 -236.841792)
					)
					(arc
						(start 84.848192 -236.841792)
						(mid 84.82717 -236.84498)
						(end 84.80933 -236.856524)
					)
					(arc
						(start 84.80933 -236.856524)
						(mid 84.794316 -236.892502)
						(end 84.80933 -236.928406)
					)
					(arc
						(start 84.80933 -236.928406)
						(mid 84.821135 -236.937189)
						(end 84.834984 -236.942122)
					)
					(xy 84.855558 -236.942122) (xy 84.856066 -236.942122)
					(arc
						(start 84.857082 -236.942122)
						(mid 84.929787 -236.95696)
						(end 84.991448 -236.998256)
					)
					(arc
						(start 84.991448 -236.998256)
						(mid 85.047705 -237.133802)
						(end 84.991448 -237.269274)
					)
					(arc
						(start 84.991448 -237.269274)
						(mid 84.928953 -237.310785)
						(end 84.855304 -237.325154)
					)
					(xy 84.854542 -237.325154)
					(arc
						(start 84.833968 -237.325154)
						(mid 84.820144 -237.330145)
						(end 84.808314 -237.33887)
					)
				)
			)
		)
		(zone
			(layer "F.Cu")
			(hatch none 0.5)
			(connect_pads
				(clearance 0)
			)
			(min_thickness 0.25)
			(keepout
				(tracks not_allowed)
				(vias allowed)
				(pads allowed)
				(copperpour not_allowed)
				(footprints allowed)
			)
			(placement
				(enabled no)
				(sheetname "")
			)
			(fill
				(thermal_gap 0.5)
				(thermal_bridge_width 0.5)
				(island_removal_mode 0)
			)
			(polygon
				(pts
					(arc
						(start 84.808314 -235.711238)
						(mid 84.793553 -235.747052)
						(end 84.808314 -235.782866)
					)
					(arc
						(start 84.808314 -235.782866)
						(mid 84.825436 -235.794217)
						(end 84.845652 -235.797852)
					)
					(arc
						(start 84.845652 -235.797852)
						(mid 84.962993 -235.777758)
						(end 85.062568 -235.712508)
					)
					(arc
						(start 85.062568 -235.712508)
						(mid 85.148104 -235.506006)
						(end 85.062568 -235.299504)
					)
					(arc
						(start 85.062568 -235.299504)
						(mid 84.964206 -235.234575)
						(end 84.848192 -235.213906)
					)
					(arc
						(start 84.848192 -235.213906)
						(mid 84.827143 -235.217217)
						(end 84.80933 -235.228892)
					)
					(arc
						(start 84.80933 -235.228892)
						(mid 84.794316 -235.26487)
						(end 84.80933 -235.300774)
					)
					(arc
						(start 84.80933 -235.300774)
						(mid 84.821151 -235.309516)
						(end 84.834984 -235.31449)
					)
					(xy 84.855558 -235.31449) (xy 84.856066 -235.31449)
					(arc
						(start 84.857082 -235.31449)
						(mid 84.929787 -235.329328)
						(end 84.991448 -235.370624)
					)
					(arc
						(start 84.991448 -235.370624)
						(mid 85.047525 -235.506006)
						(end 84.991448 -235.641388)
					)
					(arc
						(start 84.991448 -235.641388)
						(mid 84.928997 -235.68312)
						(end 84.855304 -235.697522)
					)
					(xy 84.854542 -235.697268)
					(arc
						(start 84.833968 -235.697268)
						(mid 84.820106 -235.702358)
						(end 84.808314 -235.711238)
					)
				)
			)
		)
		(zone
			(layer "F.Cu")
			(hatch none 0.5)
			(connect_pads
				(clearance 0)
			)
			(min_thickness 0.25)
			(keepout
				(tracks not_allowed)
				(vias allowed)
				(pads allowed)
				(copperpour not_allowed)
				(footprints allowed)
			)
			(placement
				(enabled no)
				(sheetname "")
			)
			(fill
				(thermal_gap 0.5)
				(thermal_bridge_width 0.5)
				(island_removal_mode 0)
			)
			(polygon
				(pts
					(arc
						(start 84.808314 -234.083352)
						(mid 84.7933 -234.11933)
						(end 84.808314 -234.155234)
					)
					(arc
						(start 84.808314 -234.155234)
						(mid 84.825467 -234.166445)
						(end 84.845652 -234.169966)
					)
					(arc
						(start 84.845652 -234.169966)
						(mid 84.962993 -234.149872)
						(end 85.062568 -234.084622)
					)
					(arc
						(start 85.062568 -234.084622)
						(mid 85.148104 -233.87812)
						(end 85.062568 -233.671618)
					)
					(arc
						(start 85.062568 -233.671618)
						(mid 84.964175 -233.606829)
						(end 84.848192 -233.586274)
					)
					(arc
						(start 84.848192 -233.586274)
						(mid 84.827183 -233.589474)
						(end 84.80933 -233.601006)
					)
					(arc
						(start 84.80933 -233.601006)
						(mid 84.794316 -233.636984)
						(end 84.80933 -233.672888)
					)
					(arc
						(start 84.80933 -233.672888)
						(mid 84.821151 -233.68163)
						(end 84.834984 -233.686604)
					)
					(xy 84.855558 -233.686604) (xy 84.856066 -233.686604)
					(arc
						(start 84.857082 -233.686604)
						(mid 84.929787 -233.701442)
						(end 84.991448 -233.742738)
					)
					(arc
						(start 84.991448 -233.742738)
						(mid 85.047525 -233.87812)
						(end 84.991448 -234.013502)
					)
					(arc
						(start 84.991448 -234.013502)
						(mid 84.928982 -234.055151)
						(end 84.855304 -234.069636)
					)
					(xy 84.854542 -234.069382)
					(arc
						(start 84.833968 -234.069382)
						(mid 84.820106 -234.074472)
						(end 84.808314 -234.083352)
					)
				)
			)
		)
		(zone
			(layer "F.Cu")
			(hatch none 0.5)
			(connect_pads
				(clearance 0)
			)
			(min_thickness 0.25)
			(keepout
				(tracks not_allowed)
				(vias allowed)
				(pads allowed)
				(copperpour not_allowed)
				(footprints allowed)
			)
			(placement
				(enabled no)
				(sheetname "")
			)
			(fill
				(thermal_gap 0.5)
				(thermal_bridge_width 0.5)
				(island_removal_mode 0)
			)
			(polygon
				(pts
					(arc
						(start 84.808314 -232.455466)
						(mid 84.7933 -232.491444)
						(end 84.808314 -232.527348)
					)
					(arc
						(start 84.808314 -232.527348)
						(mid 84.825436 -232.538699)
						(end 84.845652 -232.542334)
					)
					(arc
						(start 84.845652 -232.542334)
						(mid 84.962993 -232.52224)
						(end 85.062568 -232.45699)
					)
					(arc
						(start 85.062568 -232.45699)
						(mid 85.148104 -232.250488)
						(end 85.062568 -232.043986)
					)
					(arc
						(start 85.062568 -232.043986)
						(mid 84.964206 -231.979057)
						(end 84.848192 -231.958388)
					)
					(arc
						(start 84.848192 -231.958388)
						(mid 84.82717 -231.961576)
						(end 84.80933 -231.97312)
					)
					(arc
						(start 84.80933 -231.97312)
						(mid 84.794316 -232.009098)
						(end 84.80933 -232.045002)
					)
					(arc
						(start 84.80933 -232.045002)
						(mid 84.821135 -232.053785)
						(end 84.834984 -232.058718)
					)
					(xy 84.855558 -232.058718) (xy 84.856066 -232.058718)
					(arc
						(start 84.857082 -232.058718)
						(mid 84.929817 -232.073672)
						(end 84.991448 -232.115106)
					)
					(arc
						(start 84.991448 -232.115106)
						(mid 85.047525 -232.250488)
						(end 84.991448 -232.38587)
					)
					(arc
						(start 84.991448 -232.38587)
						(mid 84.928983 -232.427548)
						(end 84.855304 -232.442004)
					)
					(xy 84.854542 -232.44175)
					(arc
						(start 84.833968 -232.44175)
						(mid 84.820144 -232.446741)
						(end 84.808314 -232.455466)
					)
				)
			)
		)
		(zone
			(layer "F.Cu")
			(hatch none 0.5)
			(connect_pads
				(clearance 0)
			)
			(min_thickness 0.25)
			(keepout
				(tracks not_allowed)
				(vias allowed)
				(pads allowed)
				(copperpour not_allowed)
				(footprints allowed)
			)
			(placement
				(enabled no)
				(sheetname "")
			)
			(fill
				(thermal_gap 0.5)
				(thermal_bridge_width 0.5)
				(island_removal_mode 0)
			)
			(polygon
				(pts
					(arc
						(start 84.808314 -230.827834)
						(mid 84.7933 -230.863812)
						(end 84.808314 -230.899716)
					)
					(arc
						(start 84.808314 -230.899716)
						(mid 84.825436 -230.911067)
						(end 84.845652 -230.914702)
					)
					(arc
						(start 84.845652 -230.914702)
						(mid 84.96302 -230.894487)
						(end 85.062568 -230.829104)
					)
					(arc
						(start 85.062568 -230.829104)
						(mid 85.148104 -230.622602)
						(end 85.062568 -230.4161)
					)
					(arc
						(start 85.062568 -230.4161)
						(mid 84.964175 -230.351311)
						(end 84.848192 -230.330756)
					)
					(arc
						(start 84.848192 -230.330756)
						(mid 84.827183 -230.333956)
						(end 84.80933 -230.345488)
					)
					(arc
						(start 84.80933 -230.345488)
						(mid 84.794316 -230.381466)
						(end 84.80933 -230.41737)
					)
					(arc
						(start 84.80933 -230.41737)
						(mid 84.821151 -230.426112)
						(end 84.834984 -230.431086)
					)
					(xy 84.855558 -230.431086) (xy 84.856066 -230.431086)
					(arc
						(start 84.857082 -230.431086)
						(mid 84.929787 -230.445924)
						(end 84.991448 -230.48722)
					)
					(arc
						(start 84.991448 -230.48722)
						(mid 85.047525 -230.622602)
						(end 84.991448 -230.757984)
					)
					(arc
						(start 84.991448 -230.757984)
						(mid 84.928982 -230.799633)
						(end 84.855304 -230.814118)
					)
					(xy 84.854542 -230.813864)
					(arc
						(start 84.833968 -230.813864)
						(mid 84.820106 -230.818954)
						(end 84.808314 -230.827834)
					)
				)
			)
		)
		(zone
			(layer "F.Cu")
			(hatch none 0.5)
			(connect_pads
				(clearance 0)
			)
			(min_thickness 0.25)
			(keepout
				(tracks not_allowed)
				(vias allowed)
				(pads allowed)
				(copperpour not_allowed)
				(footprints allowed)
			)
			(placement
				(enabled no)
				(sheetname "")
			)
			(fill
				(thermal_gap 0.5)
				(thermal_bridge_width 0.5)
				(island_removal_mode 0)
			)
			(polygon
				(pts
					(arc
						(start 84.808314 -229.200202)
						(mid 84.793553 -229.236016)
						(end 84.808314 -229.27183)
					)
					(arc
						(start 84.808314 -229.27183)
						(mid 84.825436 -229.283181)
						(end 84.845652 -229.286816)
					)
					(arc
						(start 84.845652 -229.286816)
						(mid 84.962993 -229.266722)
						(end 85.062568 -229.201472)
					)
					(arc
						(start 85.062568 -229.201472)
						(mid 85.148104 -228.99497)
						(end 85.062568 -228.788468)
					)
					(arc
						(start 85.062568 -228.788468)
						(mid 84.964206 -228.723539)
						(end 84.848192 -228.70287)
					)
					(arc
						(start 84.848192 -228.70287)
						(mid 84.82717 -228.706058)
						(end 84.80933 -228.717602)
					)
					(arc
						(start 84.80933 -228.717602)
						(mid 84.794316 -228.75358)
						(end 84.80933 -228.789484)
					)
					(arc
						(start 84.80933 -228.789484)
						(mid 84.821135 -228.798267)
						(end 84.834984 -228.8032)
					)
					(xy 84.855558 -228.8032) (xy 84.856066 -228.8032)
					(arc
						(start 84.857082 -228.8032)
						(mid 84.929817 -228.818154)
						(end 84.991448 -228.859588)
					)
					(arc
						(start 84.991448 -228.859588)
						(mid 85.047525 -228.99497)
						(end 84.991448 -229.130352)
					)
					(arc
						(start 84.991448 -229.130352)
						(mid 84.928983 -229.17203)
						(end 84.855304 -229.186486)
					)
					(xy 84.854542 -229.186232)
					(arc
						(start 84.833968 -229.186232)
						(mid 84.820106 -229.191322)
						(end 84.808314 -229.200202)
					)
				)
			)
		)
		(zone
			(layer "F.Cu")
			(hatch none 0.5)
			(connect_pads
				(clearance 0)
			)
			(min_thickness 0.25)
			(keepout
				(tracks not_allowed)
				(vias allowed)
				(pads allowed)
				(copperpour not_allowed)
				(footprints allowed)
			)
			(placement
				(enabled no)
				(sheetname "")
			)
			(fill
				(thermal_gap 0.5)
				(thermal_bridge_width 0.5)
				(island_removal_mode 0)
			)
			(polygon
				(pts
					(arc
						(start 84.808314 -227.572316)
						(mid 84.7933 -227.608294)
						(end 84.808314 -227.644198)
					)
					(arc
						(start 84.808314 -227.644198)
						(mid 84.825467 -227.655409)
						(end 84.845652 -227.65893)
					)
					(arc
						(start 84.845652 -227.65893)
						(mid 84.962993 -227.638836)
						(end 85.062568 -227.573586)
					)
					(arc
						(start 85.062568 -227.573586)
						(mid 85.148104 -227.367084)
						(end 85.062568 -227.160582)
					)
					(arc
						(start 85.062568 -227.160582)
						(mid 84.964206 -227.095653)
						(end 84.848192 -227.074984)
					)
					(arc
						(start 84.848192 -227.074984)
						(mid 84.827143 -227.078295)
						(end 84.80933 -227.08997)
					)
					(arc
						(start 84.80933 -227.08997)
						(mid 84.794316 -227.125948)
						(end 84.80933 -227.161852)
					)
					(arc
						(start 84.80933 -227.161852)
						(mid 84.821151 -227.170594)
						(end 84.834984 -227.175568)
					)
					(xy 84.855558 -227.175568) (xy 84.856066 -227.175568)
					(arc
						(start 84.857082 -227.175568)
						(mid 84.929787 -227.190406)
						(end 84.991448 -227.231702)
					)
					(arc
						(start 84.991448 -227.231702)
						(mid 85.047525 -227.367084)
						(end 84.991448 -227.502466)
					)
					(arc
						(start 84.991448 -227.502466)
						(mid 84.928982 -227.544115)
						(end 84.855304 -227.5586)
					)
					(xy 84.854542 -227.558346)
					(arc
						(start 84.833968 -227.558346)
						(mid 84.820106 -227.563436)
						(end 84.808314 -227.572316)
					)
				)
			)
		)
		(zone
			(layer "F.Cu")
			(hatch none 0.5)
			(connect_pads
				(clearance 0)
			)
			(min_thickness 0.25)
			(keepout
				(tracks not_allowed)
				(vias allowed)
				(pads allowed)
				(copperpour not_allowed)
				(footprints allowed)
			)
			(placement
				(enabled no)
				(sheetname "")
			)
			(fill
				(thermal_gap 0.5)
				(thermal_bridge_width 0.5)
				(island_removal_mode 0)
			)
			(polygon
				(pts
					(arc
						(start 84.808314 -225.94443)
						(mid 84.7933 -225.980408)
						(end 84.808314 -226.016312)
					)
					(arc
						(start 84.808314 -226.016312)
						(mid 84.825436 -226.027663)
						(end 84.845652 -226.031298)
					)
					(arc
						(start 84.845652 -226.031298)
						(mid 84.96302 -226.011083)
						(end 85.062568 -225.9457)
					)
					(arc
						(start 85.062568 -225.9457)
						(mid 85.148104 -225.739198)
						(end 85.062568 -225.532696)
					)
					(arc
						(start 85.062568 -225.532696)
						(mid 84.964175 -225.467907)
						(end 84.848192 -225.447352)
					)
					(arc
						(start 84.848192 -225.447352)
						(mid 84.827183 -225.450552)
						(end 84.80933 -225.462084)
					)
					(arc
						(start 84.80933 -225.462084)
						(mid 84.794316 -225.498062)
						(end 84.80933 -225.533966)
					)
					(arc
						(start 84.80933 -225.533966)
						(mid 84.821151 -225.542708)
						(end 84.834984 -225.547682)
					)
					(xy 84.855558 -225.547682) (xy 84.856066 -225.547682)
					(arc
						(start 84.857082 -225.547682)
						(mid 84.929787 -225.56252)
						(end 84.991448 -225.603816)
					)
					(arc
						(start 84.991448 -225.603816)
						(mid 85.047525 -225.739198)
						(end 84.991448 -225.87458)
					)
					(arc
						(start 84.991448 -225.87458)
						(mid 84.928982 -225.916229)
						(end 84.855304 -225.930714)
					)
					(xy 84.854542 -225.93046)
					(arc
						(start 84.833968 -225.93046)
						(mid 84.820106 -225.93555)
						(end 84.808314 -225.94443)
					)
				)
			)
		)
		(zone
			(layer "F.Cu")
			(hatch none 0.5)
			(connect_pads
				(clearance 0)
			)
			(min_thickness 0.25)
			(keepout
				(tracks not_allowed)
				(vias allowed)
				(pads allowed)
				(copperpour not_allowed)
				(footprints allowed)
			)
			(placement
				(enabled no)
				(sheetname "")
			)
			(fill
				(thermal_gap 0.5)
				(thermal_bridge_width 0.5)
				(island_removal_mode 0)
			)
			(polygon
				(pts
					(arc
						(start 84.808314 -224.316798)
						(mid 84.793553 -224.352612)
						(end 84.808314 -224.388426)
					)
					(arc
						(start 84.808314 -224.388426)
						(mid 84.825436 -224.399777)
						(end 84.845652 -224.403412)
					)
					(arc
						(start 84.845652 -224.403412)
						(mid 84.962993 -224.383318)
						(end 85.062568 -224.318068)
					)
					(arc
						(start 85.062568 -224.318068)
						(mid 85.148104 -224.111566)
						(end 85.062568 -223.905064)
					)
					(arc
						(start 85.062568 -223.905064)
						(mid 84.964206 -223.840135)
						(end 84.848192 -223.819466)
					)
					(arc
						(start 84.848192 -223.819466)
						(mid 84.82717 -223.822654)
						(end 84.80933 -223.834198)
					)
					(arc
						(start 84.80933 -223.834198)
						(mid 84.794316 -223.870176)
						(end 84.80933 -223.90608)
					)
					(arc
						(start 84.80933 -223.90608)
						(mid 84.821135 -223.914863)
						(end 84.834984 -223.919796)
					)
					(xy 84.855558 -223.919796) (xy 84.856066 -223.919796)
					(arc
						(start 84.857082 -223.919796)
						(mid 84.929817 -223.93475)
						(end 84.991448 -223.976184)
					)
					(arc
						(start 84.991448 -223.976184)
						(mid 85.047525 -224.111566)
						(end 84.991448 -224.246948)
					)
					(arc
						(start 84.991448 -224.246948)
						(mid 84.928983 -224.288626)
						(end 84.855304 -224.303082)
					)
					(xy 84.854542 -224.302828)
					(arc
						(start 84.833968 -224.302828)
						(mid 84.820106 -224.307918)
						(end 84.808314 -224.316798)
					)
				)
			)
		)
		(zone
			(layer "F.Cu")
			(hatch none 0.5)
			(connect_pads
				(clearance 0)
			)
			(min_thickness 0.25)
			(keepout
				(tracks not_allowed)
				(vias allowed)
				(pads allowed)
				(copperpour not_allowed)
				(footprints allowed)
			)
			(placement
				(enabled no)
				(sheetname "")
			)
			(fill
				(thermal_gap 0.5)
				(thermal_bridge_width 0.5)
				(island_removal_mode 0)
			)
			(polygon
				(pts
					(arc
						(start 84.808314 -222.688912)
						(mid 84.7933 -222.72489)
						(end 84.808314 -222.760794)
					)
					(arc
						(start 84.808314 -222.760794)
						(mid 84.825467 -222.772005)
						(end 84.845652 -222.775526)
					)
					(arc
						(start 84.845652 -222.775526)
						(mid 84.962993 -222.755432)
						(end 85.062568 -222.690182)
					)
					(arc
						(start 85.062568 -222.690182)
						(mid 85.148104 -222.48368)
						(end 85.062568 -222.277178)
					)
					(arc
						(start 85.062568 -222.277178)
						(mid 84.964206 -222.212249)
						(end 84.848192 -222.19158)
					)
					(arc
						(start 84.848192 -222.19158)
						(mid 84.827143 -222.194891)
						(end 84.80933 -222.206566)
					)
					(arc
						(start 84.80933 -222.206566)
						(mid 84.794316 -222.242544)
						(end 84.80933 -222.278448)
					)
					(arc
						(start 84.80933 -222.278448)
						(mid 84.821151 -222.28719)
						(end 84.834984 -222.292164)
					)
					(xy 84.855558 -222.292164) (xy 84.856066 -222.292164)
					(arc
						(start 84.857082 -222.292164)
						(mid 84.929787 -222.307002)
						(end 84.991448 -222.348298)
					)
					(arc
						(start 84.991448 -222.348298)
						(mid 85.047525 -222.48368)
						(end 84.991448 -222.619062)
					)
					(arc
						(start 84.991448 -222.619062)
						(mid 84.928982 -222.660711)
						(end 84.855304 -222.675196)
					)
					(xy 84.854542 -222.674942)
					(arc
						(start 84.833968 -222.674942)
						(mid 84.820106 -222.680032)
						(end 84.808314 -222.688912)
					)
				)
			)
		)
		(zone
			(layer "F.Cu")
			(hatch none 0.5)
			(connect_pads
				(clearance 0)
			)
			(min_thickness 0.25)
			(keepout
				(tracks not_allowed)
				(vias allowed)
				(pads allowed)
				(copperpour not_allowed)
				(footprints allowed)
			)
			(placement
				(enabled no)
				(sheetname "")
			)
			(fill
				(thermal_gap 0.5)
				(thermal_bridge_width 0.5)
				(island_removal_mode 0)
			)
			(polygon
				(pts
					(arc
						(start 84.918296 -267.42517)
						(mid 84.903535 -267.460984)
						(end 84.918296 -267.496798)
					)
					(arc
						(start 84.918296 -267.496798)
						(mid 84.935418 -267.508149)
						(end 84.955634 -267.511784)
					)
					(arc
						(start 84.955634 -267.511784)
						(mid 85.072975 -267.49169)
						(end 85.17255 -267.42644)
					)
					(arc
						(start 85.17255 -267.42644)
						(mid 85.258086 -267.219938)
						(end 85.17255 -267.013436)
					)
					(arc
						(start 85.17255 -267.013436)
						(mid 85.074188 -266.948507)
						(end 84.958174 -266.927838)
					)
					(arc
						(start 84.958174 -266.927838)
						(mid 84.937152 -266.931026)
						(end 84.919312 -266.94257)
					)
					(arc
						(start 84.919312 -266.94257)
						(mid 84.904297 -266.978638)
						(end 84.919312 -267.014706)
					)
					(arc
						(start 84.919312 -267.014706)
						(mid 84.931166 -267.023282)
						(end 84.944966 -267.028168)
					)
					(xy 84.96554 -267.028168) (xy 84.966048 -267.028168)
					(arc
						(start 84.967064 -267.028168)
						(mid 85.039799 -267.043122)
						(end 85.10143 -267.084556)
					)
					(arc
						(start 85.10143 -267.084556)
						(mid 85.157507 -267.219938)
						(end 85.10143 -267.35532)
					)
					(arc
						(start 85.10143 -267.35532)
						(mid 85.038979 -267.397052)
						(end 84.965286 -267.411454)
					)
					(xy 84.964524 -267.4112)
					(arc
						(start 84.944204 -267.4112)
						(mid 84.930222 -267.416276)
						(end 84.918296 -267.42517)
					)
				)
			)
		)
		(zone
			(layer "F.Cu")
			(hatch none 0.5)
			(connect_pads
				(clearance 0)
			)
			(min_thickness 0.25)
			(keepout
				(tracks not_allowed)
				(vias allowed)
				(pads allowed)
				(copperpour not_allowed)
				(footprints allowed)
			)
			(placement
				(enabled no)
				(sheetname "")
			)
			(fill
				(thermal_gap 0.5)
				(thermal_bridge_width 0.5)
				(island_removal_mode 0)
			)
			(polygon
				(pts
					(arc
						(start 84.918296 -265.797284)
						(mid 84.903282 -265.833262)
						(end 84.918296 -265.869166)
					)
					(arc
						(start 84.918296 -265.869166)
						(mid 84.935449 -265.880377)
						(end 84.955634 -265.883898)
					)
					(arc
						(start 84.955634 -265.883898)
						(mid 85.072975 -265.863804)
						(end 85.17255 -265.798554)
					)
					(arc
						(start 85.17255 -265.798554)
						(mid 85.258086 -265.592052)
						(end 85.17255 -265.38555)
					)
					(arc
						(start 85.17255 -265.38555)
						(mid 85.074157 -265.320761)
						(end 84.958174 -265.300206)
					)
					(arc
						(start 84.958174 -265.300206)
						(mid 84.937165 -265.303406)
						(end 84.919312 -265.314938)
					)
					(arc
						(start 84.919312 -265.314938)
						(mid 84.904298 -265.350916)
						(end 84.919312 -265.38682)
					)
					(arc
						(start 84.919312 -265.38682)
						(mid 84.931133 -265.395562)
						(end 84.944966 -265.400536)
					)
					(xy 84.96554 -265.400536) (xy 84.966048 -265.400536)
					(arc
						(start 84.967064 -265.400536)
						(mid 85.039769 -265.415374)
						(end 85.10143 -265.45667)
					)
					(arc
						(start 85.10143 -265.45667)
						(mid 85.157507 -265.592052)
						(end 85.10143 -265.727434)
					)
					(arc
						(start 85.10143 -265.727434)
						(mid 85.038964 -265.769083)
						(end 84.965286 -265.783568)
					)
					(xy 84.964524 -265.783314)
					(arc
						(start 84.944204 -265.783314)
						(mid 84.930222 -265.78839)
						(end 84.918296 -265.797284)
					)
				)
			)
		)
		(zone
			(layer "F.Cu")
			(hatch none 0.5)
			(connect_pads
				(clearance 0)
			)
			(min_thickness 0.25)
			(keepout
				(tracks not_allowed)
				(vias allowed)
				(pads allowed)
				(copperpour not_allowed)
				(footprints allowed)
			)
			(placement
				(enabled no)
				(sheetname "")
			)
			(fill
				(thermal_gap 0.5)
				(thermal_bridge_width 0.5)
				(island_removal_mode 0)
			)
			(polygon
				(pts
					(arc
						(start 84.918296 -264.169398)
						(mid 84.903282 -264.205376)
						(end 84.918296 -264.24128)
					)
					(arc
						(start 84.918296 -264.24128)
						(mid 84.935418 -264.252631)
						(end 84.955634 -264.256266)
					)
					(arc
						(start 84.955634 -264.256266)
						(mid 85.073002 -264.236051)
						(end 85.17255 -264.170668)
					)
					(arc
						(start 85.17255 -264.170668)
						(mid 85.258086 -263.964166)
						(end 85.17255 -263.757664)
					)
					(arc
						(start 85.17255 -263.757664)
						(mid 85.074157 -263.692875)
						(end 84.958174 -263.67232)
					)
					(arc
						(start 84.958174 -263.67232)
						(mid 84.937165 -263.67552)
						(end 84.919312 -263.687052)
					)
					(arc
						(start 84.919312 -263.687052)
						(mid 84.904298 -263.72303)
						(end 84.919312 -263.758934)
					)
					(arc
						(start 84.919312 -263.758934)
						(mid 84.931133 -263.767676)
						(end 84.944966 -263.77265)
					)
					(xy 84.96554 -263.77265) (xy 84.966048 -263.77265)
					(arc
						(start 84.967064 -263.77265)
						(mid 85.039769 -263.787488)
						(end 85.10143 -263.828784)
					)
					(arc
						(start 85.10143 -263.828784)
						(mid 85.157687 -263.96433)
						(end 85.10143 -264.099802)
					)
					(arc
						(start 85.10143 -264.099802)
						(mid 85.038935 -264.141313)
						(end 84.965286 -264.155682)
					)
					(xy 84.964524 -264.155682)
					(arc
						(start 84.944204 -264.155682)
						(mid 84.93026 -264.160658)
						(end 84.918296 -264.169398)
					)
				)
			)
		)
		(zone
			(layer "F.Cu")
			(hatch none 0.5)
			(connect_pads
				(clearance 0)
			)
			(min_thickness 0.25)
			(keepout
				(tracks not_allowed)
				(vias allowed)
				(pads allowed)
				(copperpour not_allowed)
				(footprints allowed)
			)
			(placement
				(enabled no)
				(sheetname "")
			)
			(fill
				(thermal_gap 0.5)
				(thermal_bridge_width 0.5)
				(island_removal_mode 0)
			)
			(polygon
				(pts
					(arc
						(start 84.918296 -262.541766)
						(mid 84.903461 -262.57758)
						(end 84.918296 -262.613394)
					)
					(arc
						(start 84.918296 -262.613394)
						(mid 84.935418 -262.624745)
						(end 84.955634 -262.62838)
					)
					(arc
						(start 84.955634 -262.62838)
						(mid 85.072975 -262.608286)
						(end 85.17255 -262.543036)
					)
					(arc
						(start 85.17255 -262.543036)
						(mid 85.258086 -262.336534)
						(end 85.17255 -262.130032)
					)
					(arc
						(start 85.17255 -262.130032)
						(mid 85.074188 -262.065103)
						(end 84.958174 -262.044434)
					)
					(arc
						(start 84.958174 -262.044434)
						(mid 84.937152 -262.047622)
						(end 84.919312 -262.059166)
					)
					(arc
						(start 84.919312 -262.059166)
						(mid 84.904297 -262.095234)
						(end 84.919312 -262.131302)
					)
					(arc
						(start 84.919312 -262.131302)
						(mid 84.931166 -262.139878)
						(end 84.944966 -262.144764)
					)
					(xy 84.96554 -262.144764) (xy 84.966048 -262.144764)
					(arc
						(start 84.967064 -262.144764)
						(mid 85.039799 -262.159718)
						(end 85.10143 -262.201152)
					)
					(arc
						(start 85.10143 -262.201152)
						(mid 85.157507 -262.336534)
						(end 85.10143 -262.471916)
					)
					(arc
						(start 85.10143 -262.471916)
						(mid 85.038979 -262.513648)
						(end 84.965286 -262.52805)
					)
					(xy 84.964524 -262.527796)
					(arc
						(start 84.944204 -262.527796)
						(mid 84.930222 -262.532872)
						(end 84.918296 -262.541766)
					)
				)
			)
		)
		(zone
			(layer "F.Cu")
			(hatch none 0.5)
			(connect_pads
				(clearance 0)
			)
			(min_thickness 0.25)
			(keepout
				(tracks not_allowed)
				(vias allowed)
				(pads allowed)
				(copperpour not_allowed)
				(footprints allowed)
			)
			(placement
				(enabled no)
				(sheetname "")
			)
			(fill
				(thermal_gap 0.5)
				(thermal_bridge_width 0.5)
				(island_removal_mode 0)
			)
			(polygon
				(pts
					(arc
						(start 84.918296 -260.91388)
						(mid 84.903282 -260.949858)
						(end 84.918296 -260.985762)
					)
					(arc
						(start 84.918296 -260.985762)
						(mid 84.935418 -260.997113)
						(end 84.955634 -261.000748)
					)
					(arc
						(start 84.955634 -261.000748)
						(mid 85.072975 -260.980654)
						(end 85.17255 -260.915404)
					)
					(arc
						(start 85.17255 -260.915404)
						(mid 85.258086 -260.708902)
						(end 85.17255 -260.5024)
					)
					(arc
						(start 85.17255 -260.5024)
						(mid 85.074188 -260.437471)
						(end 84.958174 -260.416802)
					)
					(arc
						(start 84.958174 -260.416802)
						(mid 84.937152 -260.41999)
						(end 84.919312 -260.431534)
					)
					(arc
						(start 84.919312 -260.431534)
						(mid 84.904298 -260.467512)
						(end 84.919312 -260.503416)
					)
					(arc
						(start 84.919312 -260.503416)
						(mid 84.931117 -260.512199)
						(end 84.944966 -260.517132)
					)
					(xy 84.96554 -260.517132) (xy 84.966048 -260.517132)
					(arc
						(start 84.967064 -260.517132)
						(mid 85.039769 -260.53197)
						(end 85.10143 -260.573266)
					)
					(arc
						(start 85.10143 -260.573266)
						(mid 85.157687 -260.708812)
						(end 85.10143 -260.844284)
					)
					(arc
						(start 85.10143 -260.844284)
						(mid 85.038935 -260.885795)
						(end 84.965286 -260.900164)
					)
					(xy 84.964524 -260.900164)
					(arc
						(start 84.944204 -260.900164)
						(mid 84.930243 -260.905121)
						(end 84.918296 -260.91388)
					)
				)
			)
		)
		(zone
			(layer "F.Cu")
			(hatch none 0.5)
			(connect_pads
				(clearance 0)
			)
			(min_thickness 0.25)
			(keepout
				(tracks not_allowed)
				(vias allowed)
				(pads allowed)
				(copperpour not_allowed)
				(footprints allowed)
			)
			(placement
				(enabled no)
				(sheetname "")
			)
			(fill
				(thermal_gap 0.5)
				(thermal_bridge_width 0.5)
				(island_removal_mode 0)
			)
			(polygon
				(pts
					(arc
						(start 84.918296 -259.286248)
						(mid 84.903535 -259.322062)
						(end 84.918296 -259.357876)
					)
					(arc
						(start 84.918296 -259.357876)
						(mid 84.935418 -259.369227)
						(end 84.955634 -259.372862)
					)
					(arc
						(start 84.955634 -259.372862)
						(mid 85.072975 -259.352768)
						(end 85.17255 -259.287518)
					)
					(arc
						(start 85.17255 -259.287518)
						(mid 85.258086 -259.081016)
						(end 85.17255 -258.874514)
					)
					(arc
						(start 85.17255 -258.874514)
						(mid 85.074188 -258.809585)
						(end 84.958174 -258.788916)
					)
					(arc
						(start 84.958174 -258.788916)
						(mid 84.937125 -258.792227)
						(end 84.919312 -258.803902)
					)
					(arc
						(start 84.919312 -258.803902)
						(mid 84.904298 -258.83988)
						(end 84.919312 -258.875784)
					)
					(arc
						(start 84.919312 -258.875784)
						(mid 84.931133 -258.884526)
						(end 84.944966 -258.8895)
					)
					(xy 84.96554 -258.8895) (xy 84.966048 -258.8895)
					(arc
						(start 84.967064 -258.8895)
						(mid 85.039769 -258.904338)
						(end 85.10143 -258.945634)
					)
					(arc
						(start 85.10143 -258.945634)
						(mid 85.157507 -259.081016)
						(end 85.10143 -259.216398)
					)
					(arc
						(start 85.10143 -259.216398)
						(mid 85.038979 -259.25813)
						(end 84.965286 -259.272532)
					)
					(xy 84.964524 -259.272278)
					(arc
						(start 84.944204 -259.272278)
						(mid 84.930222 -259.277354)
						(end 84.918296 -259.286248)
					)
				)
			)
		)
		(zone
			(layer "F.Cu")
			(hatch none 0.5)
			(connect_pads
				(clearance 0)
			)
			(min_thickness 0.25)
			(keepout
				(tracks not_allowed)
				(vias allowed)
				(pads allowed)
				(copperpour not_allowed)
				(footprints allowed)
			)
			(placement
				(enabled no)
				(sheetname "")
			)
			(fill
				(thermal_gap 0.5)
				(thermal_bridge_width 0.5)
				(island_removal_mode 0)
			)
			(polygon
				(pts
					(arc
						(start 84.918296 -257.658362)
						(mid 84.903282 -257.69434)
						(end 84.918296 -257.730244)
					)
					(arc
						(start 84.918296 -257.730244)
						(mid 84.935449 -257.741455)
						(end 84.955634 -257.744976)
					)
					(arc
						(start 84.955634 -257.744976)
						(mid 85.072975 -257.724882)
						(end 85.17255 -257.659632)
					)
					(arc
						(start 85.17255 -257.659632)
						(mid 85.258086 -257.45313)
						(end 85.17255 -257.246628)
					)
					(arc
						(start 85.17255 -257.246628)
						(mid 85.074157 -257.181839)
						(end 84.958174 -257.161284)
					)
					(arc
						(start 84.958174 -257.161284)
						(mid 84.937165 -257.164484)
						(end 84.919312 -257.176016)
					)
					(arc
						(start 84.919312 -257.176016)
						(mid 84.904298 -257.211994)
						(end 84.919312 -257.247898)
					)
					(arc
						(start 84.919312 -257.247898)
						(mid 84.931133 -257.25664)
						(end 84.944966 -257.261614)
					)
					(xy 84.96554 -257.261614) (xy 84.966048 -257.261614)
					(arc
						(start 84.967064 -257.261614)
						(mid 85.039769 -257.276452)
						(end 85.10143 -257.317748)
					)
					(arc
						(start 85.10143 -257.317748)
						(mid 85.157507 -257.45313)
						(end 85.10143 -257.588512)
					)
					(arc
						(start 85.10143 -257.588512)
						(mid 85.038964 -257.630161)
						(end 84.965286 -257.644646)
					)
					(xy 84.964524 -257.644392)
					(arc
						(start 84.944204 -257.644392)
						(mid 84.930222 -257.649468)
						(end 84.918296 -257.658362)
					)
				)
			)
		)
		(zone
			(layer "F.Cu")
			(hatch none 0.5)
			(connect_pads
				(clearance 0)
			)
			(min_thickness 0.25)
			(keepout
				(tracks not_allowed)
				(vias allowed)
				(pads allowed)
				(copperpour not_allowed)
				(footprints allowed)
			)
			(placement
				(enabled no)
				(sheetname "")
			)
			(fill
				(thermal_gap 0.5)
				(thermal_bridge_width 0.5)
				(island_removal_mode 0)
			)
			(polygon
				(pts
					(arc
						(start 84.918296 -256.030476)
						(mid 84.903282 -256.066454)
						(end 84.918296 -256.102358)
					)
					(arc
						(start 84.918296 -256.102358)
						(mid 84.935418 -256.113709)
						(end 84.955634 -256.117344)
					)
					(arc
						(start 84.955634 -256.117344)
						(mid 85.072975 -256.09725)
						(end 85.17255 -256.032)
					)
					(arc
						(start 85.17255 -256.032)
						(mid 85.258086 -255.825498)
						(end 85.17255 -255.618996)
					)
					(arc
						(start 85.17255 -255.618996)
						(mid 85.074188 -255.554067)
						(end 84.958174 -255.533398)
					)
					(arc
						(start 84.958174 -255.533398)
						(mid 84.937152 -255.536586)
						(end 84.919312 -255.54813)
					)
					(arc
						(start 84.919312 -255.54813)
						(mid 84.904298 -255.584108)
						(end 84.919312 -255.620012)
					)
					(arc
						(start 84.919312 -255.620012)
						(mid 84.931117 -255.628795)
						(end 84.944966 -255.633728)
					)
					(xy 84.96554 -255.633728) (xy 84.966048 -255.633728)
					(arc
						(start 84.967064 -255.633728)
						(mid 85.039769 -255.648566)
						(end 85.10143 -255.689862)
					)
					(arc
						(start 85.10143 -255.689862)
						(mid 85.157687 -255.825408)
						(end 85.10143 -255.96088)
					)
					(arc
						(start 85.10143 -255.96088)
						(mid 85.038935 -256.002391)
						(end 84.965286 -256.01676)
					)
					(xy 84.964524 -256.01676)
					(arc
						(start 84.944204 -256.01676)
						(mid 84.930243 -256.021717)
						(end 84.918296 -256.030476)
					)
				)
			)
		)
		(zone
			(layer "F.Cu")
			(hatch none 0.5)
			(connect_pads
				(clearance 0)
			)
			(min_thickness 0.25)
			(keepout
				(tracks not_allowed)
				(vias allowed)
				(pads allowed)
				(copperpour not_allowed)
				(footprints allowed)
			)
			(placement
				(enabled no)
				(sheetname "")
			)
			(fill
				(thermal_gap 0.5)
				(thermal_bridge_width 0.5)
				(island_removal_mode 0)
			)
			(polygon
				(pts
					(arc
						(start 85.146896 -220.153484)
						(mid 85.110975 -220.168363)
						(end 85.096096 -220.204284)
					)
					(arc
						(start 85.096096 -220.204284)
						(mid 85.100328 -220.224331)
						(end 85.112098 -220.241114)
					)
					(arc
						(start 85.112098 -220.241114)
						(mid 85.209225 -220.309843)
						(end 85.325712 -220.334078)
					)
					(arc
						(start 85.325712 -220.334078)
						(mid 85.532258 -220.248524)
						(end 85.617812 -220.041978)
					)
					(arc
						(start 85.617812 -220.041978)
						(mid 85.593975 -219.926709)
						(end 85.526626 -219.830142)
					)
					(arc
						(start 85.526626 -219.830142)
						(mid 85.509531 -219.817563)
						(end 85.48878 -219.813124)
					)
					(arc
						(start 85.48878 -219.813124)
						(mid 85.452859 -219.828003)
						(end 85.43798 -219.863924)
					)
					(arc
						(start 85.43798 -219.863924)
						(mid 85.440165 -219.878372)
						(end 85.446362 -219.89161)
					)
					(xy 85.461094 -219.906342) (xy 85.461348 -219.906596)
					(arc
						(start 85.461856 -219.907358)
						(mid 85.502835 -219.969206)
						(end 85.517228 -220.041978)
					)
					(arc
						(start 85.517228 -220.041978)
						(mid 85.461134 -220.1774)
						(end 85.325712 -220.233494)
					)
					(arc
						(start 85.325712 -220.233494)
						(mid 85.252119 -220.218896)
						(end 85.189822 -220.177106)
					)
					(xy 85.189568 -220.176344)
					(arc
						(start 85.17509 -220.161866)
						(mid 85.161612 -220.155593)
						(end 85.146896 -220.153484)
					)
				)
			)
		)
		(zone
			(layer "F.Cu")
			(hatch none 0.5)
			(connect_pads
				(clearance 0)
			)
			(min_thickness 0.25)
			(keepout
				(tracks not_allowed)
				(vias allowed)
				(pads allowed)
				(copperpour not_allowed)
				(footprints allowed)
			)
			(placement
				(enabled no)
				(sheetname "")
			)
			(fill
				(thermal_gap 0.5)
				(thermal_bridge_width 0.5)
				(island_removal_mode 0)
			)
			(polygon
				(pts
					(arc
						(start 85.146896 -218.525598)
						(mid 85.110975 -218.540477)
						(end 85.096096 -218.576398)
					)
					(arc
						(start 85.096096 -218.576398)
						(mid 85.100278 -218.596582)
						(end 85.112098 -218.613482)
					)
					(arc
						(start 85.112098 -218.613482)
						(mid 85.209241 -218.682153)
						(end 85.325712 -218.706446)
					)
					(arc
						(start 85.325712 -218.706446)
						(mid 85.532258 -218.620892)
						(end 85.617812 -218.414346)
					)
					(arc
						(start 85.617812 -218.414346)
						(mid 85.594041 -218.298924)
						(end 85.526626 -218.202256)
					)
					(arc
						(start 85.526626 -218.202256)
						(mid 85.509531 -218.189677)
						(end 85.48878 -218.185238)
					)
					(arc
						(start 85.48878 -218.185238)
						(mid 85.452859 -218.200117)
						(end 85.43798 -218.236038)
					)
					(arc
						(start 85.43798 -218.236038)
						(mid 85.440119 -218.250624)
						(end 85.446362 -218.263978)
					)
					(xy 85.461094 -218.278456) (xy 85.461348 -218.278964)
					(arc
						(start 85.461856 -218.279472)
						(mid 85.502883 -218.341437)
						(end 85.517228 -218.414346)
					)
					(arc
						(start 85.517228 -218.414346)
						(mid 85.461134 -218.549768)
						(end 85.325712 -218.605862)
					)
					(arc
						(start 85.325712 -218.605862)
						(mid 85.25213 -218.591078)
						(end 85.189822 -218.54922)
					)
					(xy 85.189568 -218.548458)
					(arc
						(start 85.17509 -218.53398)
						(mid 85.161607 -218.527738)
						(end 85.146896 -218.525598)
					)
				)
			)
		)
		(zone
			(layer "F.Cu")
			(hatch none 0.5)
			(connect_pads
				(clearance 0)
			)
			(min_thickness 0.25)
			(keepout
				(tracks not_allowed)
				(vias allowed)
				(pads allowed)
				(copperpour not_allowed)
				(footprints allowed)
			)
			(placement
				(enabled no)
				(sheetname "")
			)
			(fill
				(thermal_gap 0.5)
				(thermal_bridge_width 0.5)
				(island_removal_mode 0)
			)
			(polygon
				(pts
					(arc
						(start 85.256878 -255.122934)
						(mid 85.220957 -255.137813)
						(end 85.206078 -255.173734)
					)
					(arc
						(start 85.206078 -255.173734)
						(mid 85.21031 -255.193781)
						(end 85.22208 -255.210564)
					)
					(arc
						(start 85.22208 -255.210564)
						(mid 85.319207 -255.279293)
						(end 85.435694 -255.303528)
					)
					(arc
						(start 85.435694 -255.303528)
						(mid 85.64215 -255.218064)
						(end 85.727794 -255.011682)
					)
					(arc
						(start 85.727794 -255.011682)
						(mid 85.704144 -254.896288)
						(end 85.636862 -254.799592)
					)
					(arc
						(start 85.636862 -254.799592)
						(mid 85.619634 -254.787023)
						(end 85.598762 -254.782574)
					)
					(arc
						(start 85.598762 -254.782574)
						(mid 85.562841 -254.797453)
						(end 85.547962 -254.833374)
					)
					(arc
						(start 85.547962 -254.833374)
						(mid 85.550147 -254.847822)
						(end 85.556344 -254.86106)
					)
					(xy 85.571076 -254.875792) (xy 85.57133 -254.8763)
					(arc
						(start 85.572092 -254.876808)
						(mid 85.612984 -254.938802)
						(end 85.62721 -255.011682)
					)
					(arc
						(start 85.62721 -255.011682)
						(mid 85.571116 -255.147104)
						(end 85.435694 -255.203198)
					)
					(arc
						(start 85.435694 -255.203198)
						(mid 85.362112 -255.188414)
						(end 85.299804 -255.146556)
					)
					(xy 85.29955 -255.145794)
					(arc
						(start 85.285072 -255.131316)
						(mid 85.271594 -255.125043)
						(end 85.256878 -255.122934)
					)
				)
			)
		)
		(zone
			(layer "F.Cu")
			(hatch none 0.5)
			(connect_pads
				(clearance 0)
			)
			(min_thickness 0.25)
			(keepout
				(tracks not_allowed)
				(vias allowed)
				(pads allowed)
				(copperpour not_allowed)
				(footprints allowed)
			)
			(placement
				(enabled no)
				(sheetname "")
			)
			(fill
				(thermal_gap 0.5)
				(thermal_bridge_width 0.5)
				(island_removal_mode 0)
			)
			(polygon
				(pts
					(arc
						(start 85.272118 -221.873064)
						(mid 85.25601 -221.908445)
						(end 85.269578 -221.944946)
					)
					(arc
						(start 85.269578 -221.944946)
						(mid 85.286192 -221.956856)
						(end 85.306154 -221.961202)
					)
					(arc
						(start 85.306154 -221.961202)
						(mid 85.424216 -221.945395)
						(end 85.526118 -221.883732)
					)
					(arc
						(start 85.526118 -221.883732)
						(mid 85.619094 -221.680461)
						(end 85.541104 -221.470982)
					)
					(arc
						(start 85.541104 -221.470982)
						(mid 85.445039 -221.402626)
						(end 85.329776 -221.377764)
					)
					(arc
						(start 85.329776 -221.377764)
						(mid 85.308622 -221.380231)
						(end 85.290406 -221.391226)
					)
					(arc
						(start 85.290406 -221.391226)
						(mid 85.274301 -221.426514)
						(end 85.287866 -221.462854)
					)
					(arc
						(start 85.287866 -221.462854)
						(mid 85.299255 -221.471994)
						(end 85.312758 -221.477586)
					)
					(xy 85.333586 -221.478348) (xy 85.334094 -221.478348)
					(arc
						(start 85.33511 -221.478602)
						(mid 85.407107 -221.495979)
						(end 85.46719 -221.539308)
					)
					(arc
						(start 85.46719 -221.539308)
						(mid 85.518441 -221.676689)
						(end 85.457538 -221.810072)
					)
					(arc
						(start 85.457538 -221.810072)
						(mid 85.393545 -221.849364)
						(end 85.319362 -221.861126)
					)
					(xy 85.318854 -221.860872)
					(arc
						(start 85.29828 -221.860364)
						(mid 85.284255 -221.86478)
						(end 85.272118 -221.873064)
					)
				)
			)
		)
		(zone
			(layer "F.Cu")
			(hatch none 0.5)
			(connect_pads
				(clearance 0)
			)
			(min_thickness 0.25)
			(keepout
				(tracks not_allowed)
				(vias allowed)
				(pads allowed)
				(copperpour not_allowed)
				(footprints allowed)
			)
			(placement
				(enabled no)
				(sheetname "")
			)
			(fill
				(thermal_gap 0.5)
				(thermal_bridge_width 0.5)
				(island_removal_mode 0)
			)
			(polygon
				(pts
					(arc
						(start 85.388196 -281.261058)
						(mid 85.373182 -281.297036)
						(end 85.388196 -281.33294)
					)
					(arc
						(start 85.388196 -281.33294)
						(mid 85.405318 -281.344291)
						(end 85.425534 -281.347926)
					)
					(arc
						(start 85.425534 -281.347926)
						(mid 85.542735 -281.327777)
						(end 85.642196 -281.262582)
					)
					(arc
						(start 85.642196 -281.262582)
						(mid 85.727732 -281.05608)
						(end 85.642196 -280.849578)
					)
					(arc
						(start 85.642196 -280.849578)
						(mid 85.543938 -280.784783)
						(end 85.428074 -280.76398)
					)
					(arc
						(start 85.428074 -280.76398)
						(mid 85.406911 -280.767109)
						(end 85.388958 -280.778712)
					)
					(arc
						(start 85.388958 -280.778712)
						(mid 85.374018 -280.81469)
						(end 85.388958 -280.850594)
					)
					(arc
						(start 85.388958 -280.850594)
						(mid 85.400779 -280.859336)
						(end 85.414612 -280.86431)
					)
					(xy 85.43544 -280.86431) (xy 85.435948 -280.86431)
					(arc
						(start 85.436964 -280.86431)
						(mid 85.509562 -280.879312)
						(end 85.571076 -280.920698)
					)
					(arc
						(start 85.571076 -280.920698)
						(mid 85.627153 -281.05608)
						(end 85.571076 -281.191462)
					)
					(arc
						(start 85.571076 -281.191462)
						(mid 85.508743 -281.233145)
						(end 85.435186 -281.247596)
					)
					(xy 85.434424 -281.247342)
					(arc
						(start 85.41385 -281.247342)
						(mid 85.400026 -281.252333)
						(end 85.388196 -281.261058)
					)
				)
			)
		)
		(zone
			(layer "F.Cu")
			(hatch none 0.5)
			(connect_pads
				(clearance 0)
			)
			(min_thickness 0.25)
			(keepout
				(tracks not_allowed)
				(vias allowed)
				(pads allowed)
				(copperpour not_allowed)
				(footprints allowed)
			)
			(placement
				(enabled no)
				(sheetname "")
			)
			(fill
				(thermal_gap 0.5)
				(thermal_bridge_width 0.5)
				(island_removal_mode 0)
			)
			(polygon
				(pts
					(arc
						(start 85.388196 -279.633426)
						(mid 85.373361 -279.66924)
						(end 85.388196 -279.705054)
					)
					(arc
						(start 85.388196 -279.705054)
						(mid 85.405318 -279.716405)
						(end 85.425534 -279.72004)
					)
					(arc
						(start 85.425534 -279.72004)
						(mid 85.542735 -279.699891)
						(end 85.642196 -279.634696)
					)
					(arc
						(start 85.642196 -279.634696)
						(mid 85.727732 -279.428194)
						(end 85.642196 -279.221692)
					)
					(arc
						(start 85.642196 -279.221692)
						(mid 85.543952 -279.15681)
						(end 85.428074 -279.136094)
					)
					(arc
						(start 85.428074 -279.136094)
						(mid 85.406884 -279.139346)
						(end 85.388958 -279.15108)
					)
					(arc
						(start 85.388958 -279.15108)
						(mid 85.374018 -279.187058)
						(end 85.388958 -279.222962)
					)
					(arc
						(start 85.388958 -279.222962)
						(mid 85.400779 -279.231704)
						(end 85.414612 -279.236678)
					)
					(xy 85.43544 -279.236678) (xy 85.435948 -279.236678)
					(arc
						(start 85.436964 -279.236678)
						(mid 85.509519 -279.251578)
						(end 85.571076 -279.292812)
					)
					(arc
						(start 85.571076 -279.292812)
						(mid 85.627153 -279.428194)
						(end 85.571076 -279.563576)
					)
					(arc
						(start 85.571076 -279.563576)
						(mid 85.508728 -279.605176)
						(end 85.435186 -279.61971)
					)
					(xy 85.434424 -279.619456)
					(arc
						(start 85.41385 -279.619456)
						(mid 85.399988 -279.624546)
						(end 85.388196 -279.633426)
					)
				)
			)
		)
		(zone
			(layer "F.Cu")
			(hatch none 0.5)
			(connect_pads
				(clearance 0)
			)
			(min_thickness 0.25)
			(keepout
				(tracks not_allowed)
				(vias allowed)
				(pads allowed)
				(copperpour not_allowed)
				(footprints allowed)
			)
			(placement
				(enabled no)
				(sheetname "")
			)
			(fill
				(thermal_gap 0.5)
				(thermal_bridge_width 0.5)
				(island_removal_mode 0)
			)
			(polygon
				(pts
					(arc
						(start 85.388196 -278.00554)
						(mid 85.373182 -278.041518)
						(end 85.388196 -278.077422)
					)
					(arc
						(start 85.388196 -278.077422)
						(mid 85.405349 -278.088633)
						(end 85.425534 -278.092154)
					)
					(arc
						(start 85.425534 -278.092154)
						(mid 85.542735 -278.072005)
						(end 85.642196 -278.00681)
					)
					(arc
						(start 85.642196 -278.00681)
						(mid 85.727732 -277.800308)
						(end 85.642196 -277.593806)
					)
					(arc
						(start 85.642196 -277.593806)
						(mid 85.543921 -277.529065)
						(end 85.428074 -277.508462)
					)
					(arc
						(start 85.428074 -277.508462)
						(mid 85.406924 -277.511603)
						(end 85.388958 -277.523194)
					)
					(arc
						(start 85.388958 -277.523194)
						(mid 85.374018 -277.559172)
						(end 85.388958 -277.595076)
					)
					(arc
						(start 85.388958 -277.595076)
						(mid 85.400779 -277.603818)
						(end 85.414612 -277.608792)
					)
					(xy 85.43544 -277.608792) (xy 85.435948 -277.608792)
					(arc
						(start 85.436964 -277.608792)
						(mid 85.509533 -277.623677)
						(end 85.571076 -277.664926)
					)
					(arc
						(start 85.571076 -277.664926)
						(mid 85.627153 -277.800308)
						(end 85.571076 -277.93569)
					)
					(arc
						(start 85.571076 -277.93569)
						(mid 85.508728 -277.97729)
						(end 85.435186 -277.991824)
					)
					(xy 85.434424 -277.99157)
					(arc
						(start 85.41385 -277.99157)
						(mid 85.399988 -277.99666)
						(end 85.388196 -278.00554)
					)
				)
			)
		)
		(zone
			(layer "F.Cu")
			(hatch none 0.5)
			(connect_pads
				(clearance 0)
			)
			(min_thickness 0.25)
			(keepout
				(tracks not_allowed)
				(vias allowed)
				(pads allowed)
				(copperpour not_allowed)
				(footprints allowed)
			)
			(placement
				(enabled no)
				(sheetname "")
			)
			(fill
				(thermal_gap 0.5)
				(thermal_bridge_width 0.5)
				(island_removal_mode 0)
			)
			(polygon
				(pts
					(arc
						(start 85.388196 -276.377654)
						(mid 85.373182 -276.413632)
						(end 85.388196 -276.449536)
					)
					(arc
						(start 85.388196 -276.449536)
						(mid 85.405318 -276.460887)
						(end 85.425534 -276.464522)
					)
					(arc
						(start 85.425534 -276.464522)
						(mid 85.542735 -276.444373)
						(end 85.642196 -276.379178)
					)
					(arc
						(start 85.642196 -276.379178)
						(mid 85.727732 -276.172676)
						(end 85.642196 -275.966174)
					)
					(arc
						(start 85.642196 -275.966174)
						(mid 85.543938 -275.901379)
						(end 85.428074 -275.880576)
					)
					(arc
						(start 85.428074 -275.880576)
						(mid 85.406911 -275.883705)
						(end 85.388958 -275.895308)
					)
					(arc
						(start 85.388958 -275.895308)
						(mid 85.374018 -275.931286)
						(end 85.388958 -275.96719)
					)
					(arc
						(start 85.388958 -275.96719)
						(mid 85.400779 -275.975932)
						(end 85.414612 -275.980906)
					)
					(xy 85.43544 -275.980906) (xy 85.435948 -275.980906)
					(arc
						(start 85.436964 -275.980906)
						(mid 85.509562 -275.995908)
						(end 85.571076 -276.037294)
					)
					(arc
						(start 85.571076 -276.037294)
						(mid 85.627153 -276.172676)
						(end 85.571076 -276.308058)
					)
					(arc
						(start 85.571076 -276.308058)
						(mid 85.508743 -276.349741)
						(end 85.435186 -276.364192)
					)
					(xy 85.434424 -276.363938)
					(arc
						(start 85.41385 -276.363938)
						(mid 85.400026 -276.368929)
						(end 85.388196 -276.377654)
					)
				)
			)
		)
		(zone
			(layer "F.Cu")
			(hatch none 0.5)
			(connect_pads
				(clearance 0)
			)
			(min_thickness 0.25)
			(keepout
				(tracks not_allowed)
				(vias allowed)
				(pads allowed)
				(copperpour not_allowed)
				(footprints allowed)
			)
			(placement
				(enabled no)
				(sheetname "")
			)
			(fill
				(thermal_gap 0.5)
				(thermal_bridge_width 0.5)
				(island_removal_mode 0)
			)
			(polygon
				(pts
					(arc
						(start 85.388196 -274.750022)
						(mid 85.373182 -274.786)
						(end 85.388196 -274.821904)
					)
					(arc
						(start 85.388196 -274.821904)
						(mid 85.405318 -274.833255)
						(end 85.425534 -274.83689)
					)
					(arc
						(start 85.425534 -274.83689)
						(mid 85.542763 -274.816621)
						(end 85.642196 -274.751292)
					)
					(arc
						(start 85.642196 -274.751292)
						(mid 85.727732 -274.54479)
						(end 85.642196 -274.338288)
					)
					(arc
						(start 85.642196 -274.338288)
						(mid 85.543921 -274.273547)
						(end 85.428074 -274.252944)
					)
					(arc
						(start 85.428074 -274.252944)
						(mid 85.406911 -274.256073)
						(end 85.388958 -274.267676)
					)
					(arc
						(start 85.388958 -274.267676)
						(mid 85.374018 -274.303654)
						(end 85.388958 -274.339558)
					)
					(arc
						(start 85.388958 -274.339558)
						(mid 85.400779 -274.3483)
						(end 85.414612 -274.353274)
					)
					(xy 85.43544 -274.353274) (xy 85.435948 -274.353274)
					(arc
						(start 85.436964 -274.353274)
						(mid 85.509533 -274.368159)
						(end 85.571076 -274.409408)
					)
					(arc
						(start 85.571076 -274.409408)
						(mid 85.627153 -274.54479)
						(end 85.571076 -274.680172)
					)
					(arc
						(start 85.571076 -274.680172)
						(mid 85.508728 -274.721772)
						(end 85.435186 -274.736306)
					)
					(xy 85.434424 -274.736306)
					(arc
						(start 85.41385 -274.736306)
						(mid 85.400026 -274.741297)
						(end 85.388196 -274.750022)
					)
				)
			)
		)
		(zone
			(layer "F.Cu")
			(hatch none 0.5)
			(connect_pads
				(clearance 0)
			)
			(min_thickness 0.25)
			(keepout
				(tracks not_allowed)
				(vias allowed)
				(pads allowed)
				(copperpour not_allowed)
				(footprints allowed)
			)
			(placement
				(enabled no)
				(sheetname "")
			)
			(fill
				(thermal_gap 0.5)
				(thermal_bridge_width 0.5)
				(island_removal_mode 0)
			)
			(polygon
				(pts
					(arc
						(start 85.388196 -273.12239)
						(mid 85.373361 -273.158204)
						(end 85.388196 -273.194018)
					)
					(arc
						(start 85.388196 -273.194018)
						(mid 85.405318 -273.205369)
						(end 85.425534 -273.209004)
					)
					(arc
						(start 85.425534 -273.209004)
						(mid 85.542735 -273.188855)
						(end 85.642196 -273.12366)
					)
					(arc
						(start 85.642196 -273.12366)
						(mid 85.727732 -272.917158)
						(end 85.642196 -272.710656)
					)
					(arc
						(start 85.642196 -272.710656)
						(mid 85.543938 -272.645861)
						(end 85.428074 -272.625058)
					)
					(arc
						(start 85.428074 -272.625058)
						(mid 85.406911 -272.628187)
						(end 85.388958 -272.63979)
					)
					(arc
						(start 85.388958 -272.63979)
						(mid 85.374018 -272.675768)
						(end 85.388958 -272.711672)
					)
					(arc
						(start 85.388958 -272.711672)
						(mid 85.400779 -272.720414)
						(end 85.414612 -272.725388)
					)
					(xy 85.43544 -272.725388) (xy 85.435948 -272.725388)
					(arc
						(start 85.436964 -272.725388)
						(mid 85.509562 -272.74039)
						(end 85.571076 -272.781776)
					)
					(arc
						(start 85.571076 -272.781776)
						(mid 85.627153 -272.917158)
						(end 85.571076 -273.05254)
					)
					(arc
						(start 85.571076 -273.05254)
						(mid 85.508728 -273.09414)
						(end 85.435186 -273.108674)
					)
					(xy 85.434424 -273.10842)
					(arc
						(start 85.41385 -273.10842)
						(mid 85.399988 -273.11351)
						(end 85.388196 -273.12239)
					)
				)
			)
		)
		(zone
			(layer "F.Cu")
			(hatch none 0.5)
			(connect_pads
				(clearance 0)
			)
			(min_thickness 0.25)
			(keepout
				(tracks not_allowed)
				(vias allowed)
				(pads allowed)
				(copperpour not_allowed)
				(footprints allowed)
			)
			(placement
				(enabled no)
				(sheetname "")
			)
			(fill
				(thermal_gap 0.5)
				(thermal_bridge_width 0.5)
				(island_removal_mode 0)
			)
			(polygon
				(pts
					(arc
						(start 85.388196 -271.494504)
						(mid 85.373182 -271.530482)
						(end 85.388196 -271.566386)
					)
					(arc
						(start 85.388196 -271.566386)
						(mid 85.405349 -271.577597)
						(end 85.425534 -271.581118)
					)
					(arc
						(start 85.425534 -271.581118)
						(mid 85.542735 -271.560969)
						(end 85.642196 -271.495774)
					)
					(arc
						(start 85.642196 -271.495774)
						(mid 85.727732 -271.289272)
						(end 85.642196 -271.08277)
					)
					(arc
						(start 85.642196 -271.08277)
						(mid 85.543952 -271.017888)
						(end 85.428074 -270.997172)
					)
					(arc
						(start 85.428074 -270.997172)
						(mid 85.406884 -271.000424)
						(end 85.388958 -271.012158)
					)
					(arc
						(start 85.388958 -271.012158)
						(mid 85.374018 -271.048136)
						(end 85.388958 -271.08404)
					)
					(arc
						(start 85.388958 -271.08404)
						(mid 85.400779 -271.092782)
						(end 85.414612 -271.097756)
					)
					(xy 85.43544 -271.097756) (xy 85.435948 -271.097756)
					(arc
						(start 85.436964 -271.097756)
						(mid 85.509533 -271.112641)
						(end 85.571076 -271.15389)
					)
					(arc
						(start 85.571076 -271.15389)
						(mid 85.627153 -271.289272)
						(end 85.571076 -271.424654)
					)
					(arc
						(start 85.571076 -271.424654)
						(mid 85.508728 -271.466254)
						(end 85.435186 -271.480788)
					)
					(xy 85.434424 -271.480534)
					(arc
						(start 85.41385 -271.480534)
						(mid 85.399988 -271.485624)
						(end 85.388196 -271.494504)
					)
				)
			)
		)
		(zone
			(layer "F.Cu")
			(hatch none 0.5)
			(connect_pads
				(clearance 0)
			)
			(min_thickness 0.25)
			(keepout
				(tracks not_allowed)
				(vias allowed)
				(pads allowed)
				(copperpour not_allowed)
				(footprints allowed)
			)
			(placement
				(enabled no)
				(sheetname "")
			)
			(fill
				(thermal_gap 0.5)
				(thermal_bridge_width 0.5)
				(island_removal_mode 0)
			)
			(polygon
				(pts
					(arc
						(start 85.388196 -269.866618)
						(mid 85.373182 -269.902596)
						(end 85.388196 -269.9385)
					)
					(arc
						(start 85.388196 -269.9385)
						(mid 85.405318 -269.949851)
						(end 85.425534 -269.953486)
					)
					(arc
						(start 85.425534 -269.953486)
						(mid 85.542763 -269.933217)
						(end 85.642196 -269.867888)
					)
					(arc
						(start 85.642196 -269.867888)
						(mid 85.727732 -269.661386)
						(end 85.642196 -269.454884)
					)
					(arc
						(start 85.642196 -269.454884)
						(mid 85.543921 -269.390143)
						(end 85.428074 -269.36954)
					)
					(arc
						(start 85.428074 -269.36954)
						(mid 85.406911 -269.372669)
						(end 85.388958 -269.384272)
					)
					(arc
						(start 85.388958 -269.384272)
						(mid 85.374018 -269.42025)
						(end 85.388958 -269.456154)
					)
					(arc
						(start 85.388958 -269.456154)
						(mid 85.400779 -269.464896)
						(end 85.414612 -269.46987)
					)
					(xy 85.43544 -269.46987) (xy 85.435948 -269.46987)
					(arc
						(start 85.436964 -269.46987)
						(mid 85.509533 -269.484755)
						(end 85.571076 -269.526004)
					)
					(arc
						(start 85.571076 -269.526004)
						(mid 85.627153 -269.661386)
						(end 85.571076 -269.796768)
					)
					(arc
						(start 85.571076 -269.796768)
						(mid 85.508728 -269.838368)
						(end 85.435186 -269.852902)
					)
					(xy 85.434424 -269.852902)
					(arc
						(start 85.41385 -269.852902)
						(mid 85.400026 -269.857893)
						(end 85.388196 -269.866618)
					)
				)
			)
		)
		(zone
			(layer "F.Cu")
			(hatch none 0.5)
			(connect_pads
				(clearance 0)
			)
			(min_thickness 0.25)
			(keepout
				(tracks not_allowed)
				(vias allowed)
				(pads allowed)
				(copperpour not_allowed)
				(footprints allowed)
			)
			(placement
				(enabled no)
				(sheetname "")
			)
			(fill
				(thermal_gap 0.5)
				(thermal_bridge_width 0.5)
				(island_removal_mode 0)
			)
			(polygon
				(pts
					(arc
						(start 85.388196 -268.238986)
						(mid 85.373182 -268.274964)
						(end 85.388196 -268.310868)
					)
					(arc
						(start 85.388196 -268.310868)
						(mid 85.405349 -268.322079)
						(end 85.425534 -268.3256)
					)
					(arc
						(start 85.425534 -268.3256)
						(mid 85.542735 -268.305451)
						(end 85.642196 -268.240256)
					)
					(arc
						(start 85.642196 -268.240256)
						(mid 85.727732 -268.033754)
						(end 85.642196 -267.827252)
					)
					(arc
						(start 85.642196 -267.827252)
						(mid 85.543952 -267.76237)
						(end 85.428074 -267.741654)
					)
					(arc
						(start 85.428074 -267.741654)
						(mid 85.406884 -267.744906)
						(end 85.388958 -267.75664)
					)
					(arc
						(start 85.388958 -267.75664)
						(mid 85.374018 -267.792618)
						(end 85.388958 -267.828522)
					)
					(arc
						(start 85.388958 -267.828522)
						(mid 85.400779 -267.837264)
						(end 85.414612 -267.842238)
					)
					(xy 85.43544 -267.842238) (xy 85.435948 -267.842238)
					(arc
						(start 85.436964 -267.842238)
						(mid 85.509533 -267.857123)
						(end 85.571076 -267.898372)
					)
					(arc
						(start 85.571076 -267.898372)
						(mid 85.627153 -268.033754)
						(end 85.571076 -268.169136)
					)
					(arc
						(start 85.571076 -268.169136)
						(mid 85.508728 -268.210736)
						(end 85.435186 -268.22527)
					)
					(xy 85.434424 -268.225016)
					(arc
						(start 85.41385 -268.225016)
						(mid 85.399988 -268.230106)
						(end 85.388196 -268.238986)
					)
				)
			)
		)
		(zone
			(layer "F.Cu")
			(hatch none 0.5)
			(connect_pads
				(clearance 0)
			)
			(min_thickness 0.25)
			(keepout
				(tracks not_allowed)
				(vias allowed)
				(pads allowed)
				(copperpour not_allowed)
				(footprints allowed)
			)
			(placement
				(enabled no)
				(sheetname "")
			)
			(fill
				(thermal_gap 0.5)
				(thermal_bridge_width 0.5)
				(island_removal_mode 0)
			)
			(polygon
				(pts
					(arc
						(start 85.437218 -249.520964)
						(mid 85.452007 -249.556795)
						(end 85.487764 -249.571764)
					)
					(arc
						(start 85.487764 -249.571764)
						(mid 85.507948 -249.567582)
						(end 85.524848 -249.555762)
					)
					(arc
						(start 85.524848 -249.555762)
						(mid 85.593519 -249.458619)
						(end 85.617812 -249.342148)
					)
					(arc
						(start 85.617812 -249.342148)
						(mid 85.532258 -249.135602)
						(end 85.325712 -249.050048)
					)
					(arc
						(start 85.325712 -249.050048)
						(mid 85.210455 -249.073749)
						(end 85.113876 -249.14098)
					)
					(arc
						(start 85.113876 -249.14098)
						(mid 85.101307 -249.158208)
						(end 85.096858 -249.17908)
					)
					(arc
						(start 85.096858 -249.17908)
						(mid 85.111737 -249.215001)
						(end 85.147658 -249.22988)
					)
					(arc
						(start 85.147658 -249.22988)
						(mid 85.162112 -249.227705)
						(end 85.175344 -249.221498)
					)
					(xy 85.190076 -249.206766) (xy 85.19033 -249.206512)
					(arc
						(start 85.191092 -249.20575)
						(mid 85.252969 -249.164906)
						(end 85.325712 -249.150632)
					)
					(arc
						(start 85.325712 -249.150632)
						(mid 85.461134 -249.206726)
						(end 85.517228 -249.342148)
					)
					(arc
						(start 85.517228 -249.342148)
						(mid 85.502512 -249.41577)
						(end 85.460586 -249.478038)
					)
					(xy 85.460078 -249.478292)
					(arc
						(start 85.4456 -249.49277)
						(mid 85.439327 -249.506248)
						(end 85.437218 -249.520964)
					)
				)
			)
		)
		(zone
			(layer "F.Cu")
			(hatch none 0.5)
			(connect_pads
				(clearance 0)
			)
			(min_thickness 0.25)
			(keepout
				(tracks not_allowed)
				(vias allowed)
				(pads allowed)
				(copperpour not_allowed)
				(footprints allowed)
			)
			(placement
				(enabled no)
				(sheetname "")
			)
			(fill
				(thermal_gap 0.5)
				(thermal_bridge_width 0.5)
				(island_removal_mode 0)
			)
			(polygon
				(pts
					(arc
						(start 85.5472 -286.1183)
						(mid 85.562079 -286.154221)
						(end 85.598 -286.1691)
					)
					(arc
						(start 85.598 -286.1691)
						(mid 85.618047 -286.164868)
						(end 85.63483 -286.153098)
					)
					(arc
						(start 85.63483 -286.153098)
						(mid 85.703501 -286.055955)
						(end 85.727794 -285.939484)
					)
					(arc
						(start 85.727794 -285.939484)
						(mid 85.64224 -285.732938)
						(end 85.435694 -285.647384)
					)
					(arc
						(start 85.435694 -285.647384)
						(mid 85.320437 -285.671085)
						(end 85.223858 -285.738316)
					)
					(arc
						(start 85.223858 -285.738316)
						(mid 85.211289 -285.755544)
						(end 85.20684 -285.776416)
					)
					(arc
						(start 85.20684 -285.776416)
						(mid 85.221719 -285.812337)
						(end 85.25764 -285.827216)
					)
					(arc
						(start 85.25764 -285.827216)
						(mid 85.272094 -285.825041)
						(end 85.285326 -285.818834)
					)
					(xy 85.300058 -285.804102) (xy 85.300312 -285.803848)
					(arc
						(start 85.301074 -285.803086)
						(mid 85.362951 -285.762242)
						(end 85.435694 -285.747968)
					)
					(arc
						(start 85.435694 -285.747968)
						(mid 85.571116 -285.804062)
						(end 85.62721 -285.939484)
					)
					(arc
						(start 85.62721 -285.939484)
						(mid 85.612494 -286.013106)
						(end 85.570568 -286.075374)
					)
					(xy 85.57006 -286.075628)
					(arc
						(start 85.555582 -286.090106)
						(mid 85.549309 -286.103584)
						(end 85.5472 -286.1183)
					)
				)
			)
		)
		(zone
			(layer "F.Cu")
			(hatch none 0.5)
			(connect_pads
				(clearance 0)
			)
			(min_thickness 0.25)
			(keepout
				(tracks not_allowed)
				(vias allowed)
				(pads allowed)
				(copperpour not_allowed)
				(footprints allowed)
			)
			(placement
				(enabled no)
				(sheetname "")
			)
			(fill
				(thermal_gap 0.5)
				(thermal_bridge_width 0.5)
				(island_removal_mode 0)
			)
			(polygon
				(pts
					(arc
						(start 85.5472 -284.490414)
						(mid 85.562079 -284.526335)
						(end 85.598 -284.541214)
					)
					(arc
						(start 85.598 -284.541214)
						(mid 85.618047 -284.536982)
						(end 85.63483 -284.525212)
					)
					(arc
						(start 85.63483 -284.525212)
						(mid 85.703559 -284.428085)
						(end 85.727794 -284.311598)
					)
					(arc
						(start 85.727794 -284.311598)
						(mid 85.64224 -284.105052)
						(end 85.435694 -284.019498)
					)
					(arc
						(start 85.435694 -284.019498)
						(mid 85.320409 -284.04332)
						(end 85.223858 -284.110684)
					)
					(arc
						(start 85.223858 -284.110684)
						(mid 85.21134 -284.127796)
						(end 85.20684 -284.14853)
					)
					(arc
						(start 85.20684 -284.14853)
						(mid 85.221629 -284.184616)
						(end 85.25764 -284.199584)
					)
					(arc
						(start 85.25764 -284.199584)
						(mid 85.27213 -284.197322)
						(end 85.285326 -284.190948)
					)
					(xy 85.300058 -284.17647) (xy 85.300312 -284.175962)
					(arc
						(start 85.301074 -284.1752)
						(mid 85.362951 -284.134356)
						(end 85.435694 -284.120082)
					)
					(arc
						(start 85.435694 -284.120082)
						(mid 85.571116 -284.176176)
						(end 85.62721 -284.311598)
					)
					(arc
						(start 85.62721 -284.311598)
						(mid 85.612494 -284.38522)
						(end 85.570568 -284.447488)
					)
					(xy 85.57006 -284.447996)
					(arc
						(start 85.555582 -284.462474)
						(mid 85.549346 -284.47583)
						(end 85.5472 -284.490414)
					)
				)
			)
		)
		(zone
			(layer "F.Cu")
			(hatch none 0.5)
			(connect_pads
				(clearance 0)
			)
			(min_thickness 0.25)
			(keepout
				(tracks not_allowed)
				(vias allowed)
				(pads allowed)
				(copperpour not_allowed)
				(footprints allowed)
			)
			(placement
				(enabled no)
				(sheetname "")
			)
			(fill
				(thermal_gap 0.5)
				(thermal_bridge_width 0.5)
				(island_removal_mode 0)
			)
			(polygon
				(pts
					(arc
						(start 85.5472 -282.862782)
						(mid 85.562079 -282.898703)
						(end 85.598 -282.913582)
					)
					(arc
						(start 85.598 -282.913582)
						(mid 85.618047 -282.90935)
						(end 85.63483 -282.89758)
					)
					(arc
						(start 85.63483 -282.89758)
						(mid 85.703501 -282.800437)
						(end 85.727794 -282.683966)
					)
					(arc
						(start 85.727794 -282.683966)
						(mid 85.64224 -282.47742)
						(end 85.435694 -282.391866)
					)
					(arc
						(start 85.435694 -282.391866)
						(mid 85.320437 -282.415567)
						(end 85.223858 -282.482798)
					)
					(arc
						(start 85.223858 -282.482798)
						(mid 85.211289 -282.500026)
						(end 85.20684 -282.520898)
					)
					(arc
						(start 85.20684 -282.520898)
						(mid 85.221719 -282.556819)
						(end 85.25764 -282.571698)
					)
					(arc
						(start 85.25764 -282.571698)
						(mid 85.272094 -282.569523)
						(end 85.285326 -282.563316)
					)
					(xy 85.300058 -282.548584) (xy 85.300312 -282.54833)
					(arc
						(start 85.301074 -282.547568)
						(mid 85.362951 -282.506724)
						(end 85.435694 -282.49245)
					)
					(arc
						(start 85.435694 -282.49245)
						(mid 85.571116 -282.548544)
						(end 85.62721 -282.683966)
					)
					(arc
						(start 85.62721 -282.683966)
						(mid 85.612494 -282.757588)
						(end 85.570568 -282.819856)
					)
					(xy 85.57006 -282.82011)
					(arc
						(start 85.555582 -282.834588)
						(mid 85.549309 -282.848066)
						(end 85.5472 -282.862782)
					)
				)
			)
		)
		(zone
			(layer "F.Cu")
			(hatch none 0.5)
			(connect_pads
				(clearance 0)
			)
			(min_thickness 0.25)
			(keepout
				(tracks not_allowed)
				(vias allowed)
				(pads allowed)
				(copperpour not_allowed)
				(footprints allowed)
			)
			(placement
				(enabled no)
				(sheetname "")
			)
			(fill
				(thermal_gap 0.5)
				(thermal_bridge_width 0.5)
				(island_removal_mode 0)
			)
			(polygon
				(pts
					(arc
						(start 85.61705 -219.339668)
						(mid 85.581129 -219.354547)
						(end 85.56625 -219.390468)
					)
					(arc
						(start 85.56625 -219.390468)
						(mid 85.570361 -219.410487)
						(end 85.581998 -219.427298)
					)
					(arc
						(start 85.581998 -219.427298)
						(mid 85.679258 -219.49602)
						(end 85.795866 -219.520262)
					)
					(arc
						(start 85.795866 -219.520262)
						(mid 86.002412 -219.434708)
						(end 86.087966 -219.228162)
					)
					(arc
						(start 86.087966 -219.228162)
						(mid 86.064195 -219.11274)
						(end 85.99678 -219.016072)
					)
					(arc
						(start 85.99678 -219.016072)
						(mid 85.979552 -219.003503)
						(end 85.95868 -218.999054)
					)
					(arc
						(start 85.95868 -218.999054)
						(mid 85.922759 -219.013933)
						(end 85.90788 -219.049854)
					)
					(arc
						(start 85.90788 -219.049854)
						(mid 85.910019 -219.06444)
						(end 85.916262 -219.077794)
					)
					(xy 85.930994 -219.092526) (xy 85.931248 -219.09278)
					(arc
						(start 85.93201 -219.093542)
						(mid 85.972989 -219.15539)
						(end 85.987382 -219.228162)
					)
					(arc
						(start 85.987382 -219.228162)
						(mid 85.931288 -219.363584)
						(end 85.795866 -219.419678)
					)
					(arc
						(start 85.795866 -219.419678)
						(mid 85.722244 -219.404962)
						(end 85.659976 -219.363036)
					)
					(xy 85.659468 -219.362528)
					(arc
						(start 85.64499 -219.34805)
						(mid 85.631634 -219.341814)
						(end 85.61705 -219.339668)
					)
				)
			)
		)
		(zone
			(layer "F.Cu")
			(hatch none 0.5)
			(connect_pads
				(clearance 0)
			)
			(min_thickness 0.25)
			(keepout
				(tracks not_allowed)
				(vias allowed)
				(pads allowed)
				(copperpour not_allowed)
				(footprints allowed)
			)
			(placement
				(enabled no)
				(sheetname "")
			)
			(fill
				(thermal_gap 0.5)
				(thermal_bridge_width 0.5)
				(island_removal_mode 0)
			)
			(polygon
				(pts
					(arc
						(start 85.61705 -217.711782)
						(mid 85.581129 -217.726661)
						(end 85.56625 -217.762582)
					)
					(arc
						(start 85.56625 -217.762582)
						(mid 85.570361 -217.782601)
						(end 85.581998 -217.799412)
					)
					(arc
						(start 85.581998 -217.799412)
						(mid 85.679258 -217.868134)
						(end 85.795866 -217.892376)
					)
					(arc
						(start 85.795866 -217.892376)
						(mid 86.002412 -217.806822)
						(end 86.087966 -217.600276)
					)
					(arc
						(start 86.087966 -217.600276)
						(mid 86.064144 -217.484991)
						(end 85.99678 -217.38844)
					)
					(arc
						(start 85.99678 -217.38844)
						(mid 85.979552 -217.375871)
						(end 85.95868 -217.371422)
					)
					(arc
						(start 85.95868 -217.371422)
						(mid 85.922759 -217.386301)
						(end 85.90788 -217.422222)
					)
					(arc
						(start 85.90788 -217.422222)
						(mid 85.910055 -217.436676)
						(end 85.916262 -217.449908)
					)
					(xy 85.930994 -217.46464) (xy 85.931248 -217.464894)
					(arc
						(start 85.93201 -217.465656)
						(mid 85.972989 -217.527504)
						(end 85.987382 -217.600276)
					)
					(arc
						(start 85.987382 -217.600276)
						(mid 85.931288 -217.735698)
						(end 85.795866 -217.791792)
					)
					(arc
						(start 85.795866 -217.791792)
						(mid 85.722273 -217.777194)
						(end 85.659976 -217.735404)
					)
					(xy 85.659468 -217.734642)
					(arc
						(start 85.64499 -217.720164)
						(mid 85.631634 -217.713928)
						(end 85.61705 -217.711782)
					)
				)
			)
		)
		(zone
			(layer "F.Cu")
			(hatch none 0.5)
			(connect_pads
				(clearance 0)
			)
			(min_thickness 0.25)
			(keepout
				(tracks not_allowed)
				(vias allowed)
				(pads allowed)
				(copperpour not_allowed)
				(footprints allowed)
			)
			(placement
				(enabled no)
				(sheetname "")
			)
			(fill
				(thermal_gap 0.5)
				(thermal_bridge_width 0.5)
				(island_removal_mode 0)
			)
			(polygon
				(pts
					(arc
						(start 85.726778 -254.309118)
						(mid 85.690947 -254.323907)
						(end 85.675978 -254.359664)
					)
					(arc
						(start 85.675978 -254.359664)
						(mid 85.68016 -254.379848)
						(end 85.69198 -254.396748)
					)
					(arc
						(start 85.69198 -254.396748)
						(mid 85.789123 -254.465419)
						(end 85.905594 -254.489712)
					)
					(arc
						(start 85.905594 -254.489712)
						(mid 86.11214 -254.404158)
						(end 86.197694 -254.197612)
					)
					(arc
						(start 86.197694 -254.197612)
						(mid 86.173993 -254.082355)
						(end 86.106762 -253.985776)
					)
					(arc
						(start 86.106762 -253.985776)
						(mid 86.089534 -253.973207)
						(end 86.068662 -253.968758)
					)
					(arc
						(start 86.068662 -253.968758)
						(mid 86.032741 -253.983637)
						(end 86.017862 -254.019558)
					)
					(arc
						(start 86.017862 -254.019558)
						(mid 86.020037 -254.034012)
						(end 86.026244 -254.047244)
					)
					(xy 86.040976 -254.061976) (xy 86.04123 -254.06223)
					(arc
						(start 86.041992 -254.062992)
						(mid 86.082836 -254.124869)
						(end 86.09711 -254.197612)
					)
					(arc
						(start 86.09711 -254.197612)
						(mid 86.041016 -254.333034)
						(end 85.905594 -254.389128)
					)
					(arc
						(start 85.905594 -254.389128)
						(mid 85.831972 -254.374412)
						(end 85.769704 -254.332486)
					)
					(xy 85.76945 -254.331978)
					(arc
						(start 85.754972 -254.3175)
						(mid 85.741494 -254.311227)
						(end 85.726778 -254.309118)
					)
				)
			)
		)
		(zone
			(layer "F.Cu")
			(hatch none 0.5)
			(connect_pads
				(clearance 0)
			)
			(min_thickness 0.25)
			(keepout
				(tracks not_allowed)
				(vias allowed)
				(pads allowed)
				(copperpour not_allowed)
				(footprints allowed)
			)
			(placement
				(enabled no)
				(sheetname "")
			)
			(fill
				(thermal_gap 0.5)
				(thermal_bridge_width 0.5)
				(island_removal_mode 0)
			)
			(polygon
				(pts
					(arc
						(start 85.750654 -221.06128)
						(mid 85.736147 -221.097288)
						(end 85.751162 -221.133162)
					)
					(arc
						(start 85.751162 -221.133162)
						(mid 85.768433 -221.144419)
						(end 85.788754 -221.147894)
					)
					(arc
						(start 85.788754 -221.147894)
						(mid 85.9059 -221.12667)
						(end 86.004908 -221.060518)
					)
					(arc
						(start 86.004908 -221.060518)
						(mid 86.088666 -220.85328)
						(end 86.001352 -220.647514)
					)
					(arc
						(start 86.001352 -220.647514)
						(mid 85.902272 -220.583522)
						(end 85.78596 -220.563948)
					)
					(arc
						(start 85.78596 -220.563948)
						(mid 85.765178 -220.56751)
						(end 85.747606 -220.579188)
					)
					(arc
						(start 85.747606 -220.579188)
						(mid 85.733025 -220.615107)
						(end 85.748114 -220.650816)
					)
					(arc
						(start 85.748114 -220.650816)
						(mid 85.759935 -220.659558)
						(end 85.773768 -220.664532)
					)
					(xy 85.794596 -220.664278) (xy 85.79485 -220.664278)
					(arc
						(start 85.795866 -220.664278)
						(mid 85.868696 -220.678437)
						(end 85.93074 -220.719142)
					)
					(arc
						(start 85.93074 -220.719142)
						(mid 85.988089 -220.854178)
						(end 85.933026 -220.99016)
					)
					(arc
						(start 85.933026 -220.99016)
						(mid 85.870913 -221.03226)
						(end 85.79739 -221.04731)
					)
					(xy 85.796882 -221.047056)
					(arc
						(start 85.776308 -221.04731)
						(mid 85.762446 -221.0524)
						(end 85.750654 -221.06128)
					)
				)
			)
		)
		(zone
			(layer "F.Cu")
			(hatch none 0.5)
			(connect_pads
				(clearance 0)
			)
			(min_thickness 0.25)
			(keepout
				(tracks not_allowed)
				(vias allowed)
				(pads allowed)
				(copperpour not_allowed)
				(footprints allowed)
			)
			(placement
				(enabled no)
				(sheetname "")
			)
			(fill
				(thermal_gap 0.5)
				(thermal_bridge_width 0.5)
				(island_removal_mode 0)
			)
			(polygon
				(pts
					(arc
						(start 85.907118 -250.33478)
						(mid 85.921997 -250.370701)
						(end 85.957918 -250.38558)
					)
					(arc
						(start 85.957918 -250.38558)
						(mid 85.978102 -250.381398)
						(end 85.995002 -250.369578)
					)
					(arc
						(start 85.995002 -250.369578)
						(mid 86.063588 -250.272419)
						(end 86.087712 -250.155964)
					)
					(arc
						(start 86.087712 -250.155964)
						(mid 86.002248 -249.949508)
						(end 85.795866 -249.863864)
					)
					(arc
						(start 85.795866 -249.863864)
						(mid 85.680444 -249.887635)
						(end 85.583776 -249.95505)
					)
					(arc
						(start 85.583776 -249.95505)
						(mid 85.571258 -249.972162)
						(end 85.566758 -249.992896)
					)
					(arc
						(start 85.566758 -249.992896)
						(mid 85.581547 -250.028982)
						(end 85.617558 -250.04395)
					)
					(arc
						(start 85.617558 -250.04395)
						(mid 85.63218 -250.041724)
						(end 85.645498 -250.035314)
					)
					(xy 85.659976 -250.020836) (xy 85.660484 -250.020328)
					(arc
						(start 85.660992 -250.019566)
						(mid 85.722986 -249.978674)
						(end 85.795866 -249.964448)
					)
					(arc
						(start 85.795866 -249.964448)
						(mid 85.931288 -250.020542)
						(end 85.987382 -250.155964)
					)
					(arc
						(start 85.987382 -250.155964)
						(mid 85.972583 -250.229532)
						(end 85.93074 -250.291854)
					)
					(xy 85.929978 -250.292362)
					(arc
						(start 85.9155 -250.30684)
						(mid 85.909264 -250.320196)
						(end 85.907118 -250.33478)
					)
				)
			)
		)
		(zone
			(layer "F.Cu")
			(hatch none 0.5)
			(connect_pads
				(clearance 0)
			)
			(min_thickness 0.25)
			(keepout
				(tracks not_allowed)
				(vias allowed)
				(pads allowed)
				(copperpour not_allowed)
				(footprints allowed)
			)
			(placement
				(enabled no)
				(sheetname "")
			)
			(fill
				(thermal_gap 0.5)
				(thermal_bridge_width 0.5)
				(island_removal_mode 0)
			)
			(polygon
				(pts
					(arc
						(start 86.0171 -286.932116)
						(mid 86.031979 -286.968037)
						(end 86.0679 -286.982916)
					)
					(arc
						(start 86.0679 -286.982916)
						(mid 86.087947 -286.978684)
						(end 86.10473 -286.966914)
					)
					(arc
						(start 86.10473 -286.966914)
						(mid 86.173459 -286.869787)
						(end 86.197694 -286.7533)
					)
					(arc
						(start 86.197694 -286.7533)
						(mid 86.11214 -286.546754)
						(end 85.905594 -286.4612)
					)
					(arc
						(start 85.905594 -286.4612)
						(mid 85.790309 -286.485022)
						(end 85.693758 -286.552386)
					)
					(arc
						(start 85.693758 -286.552386)
						(mid 85.68124 -286.569498)
						(end 85.67674 -286.590232)
					)
					(arc
						(start 85.67674 -286.590232)
						(mid 85.691529 -286.626318)
						(end 85.72754 -286.641286)
					)
					(arc
						(start 85.72754 -286.641286)
						(mid 85.74203 -286.639024)
						(end 85.755226 -286.63265)
					)
					(xy 85.769958 -286.618172) (xy 85.770212 -286.617664)
					(arc
						(start 85.770974 -286.616902)
						(mid 85.832851 -286.576058)
						(end 85.905594 -286.561784)
					)
					(arc
						(start 85.905594 -286.561784)
						(mid 86.041016 -286.617878)
						(end 86.09711 -286.7533)
					)
					(arc
						(start 86.09711 -286.7533)
						(mid 86.082394 -286.826922)
						(end 86.040468 -286.88919)
					)
					(xy 86.03996 -286.889698)
					(arc
						(start 86.025482 -286.904176)
						(mid 86.019246 -286.917532)
						(end 86.0171 -286.932116)
					)
				)
			)
		)
		(zone
			(layer "F.Cu")
			(hatch none 0.5)
			(connect_pads
				(clearance 0)
			)
			(min_thickness 0.25)
			(keepout
				(tracks not_allowed)
				(vias allowed)
				(pads allowed)
				(copperpour not_allowed)
				(footprints allowed)
			)
			(placement
				(enabled no)
				(sheetname "")
			)
			(fill
				(thermal_gap 0.5)
				(thermal_bridge_width 0.5)
				(island_removal_mode 0)
			)
			(polygon
				(pts
					(arc
						(start 86.0171 -285.30423)
						(mid 86.031979 -285.340151)
						(end 86.0679 -285.35503)
					)
					(arc
						(start 86.0679 -285.35503)
						(mid 86.087919 -285.350919)
						(end 86.10473 -285.339282)
					)
					(arc
						(start 86.10473 -285.339282)
						(mid 86.173452 -285.242022)
						(end 86.197694 -285.125414)
					)
					(arc
						(start 86.197694 -285.125414)
						(mid 86.11205 -284.919032)
						(end 85.905594 -284.833568)
					)
					(arc
						(start 85.905594 -284.833568)
						(mid 85.790353 -284.857284)
						(end 85.693758 -284.9245)
					)
					(arc
						(start 85.693758 -284.9245)
						(mid 85.681189 -284.941728)
						(end 85.67674 -284.9626)
					)
					(arc
						(start 85.67674 -284.9626)
						(mid 85.691619 -284.998521)
						(end 85.72754 -285.0134)
					)
					(arc
						(start 85.72754 -285.0134)
						(mid 85.742024 -285.011128)
						(end 85.755226 -285.004764)
					)
					(xy 85.769958 -284.990286) (xy 85.770212 -284.989778)
					(arc
						(start 85.770974 -284.98927)
						(mid 85.832822 -284.948291)
						(end 85.905594 -284.933898)
					)
					(arc
						(start 85.905594 -284.933898)
						(mid 86.041016 -284.989992)
						(end 86.09711 -285.125414)
					)
					(arc
						(start 86.09711 -285.125414)
						(mid 86.082394 -285.199036)
						(end 86.040468 -285.261304)
					)
					(xy 86.03996 -285.261812)
					(arc
						(start 86.025482 -285.27629)
						(mid 86.019246 -285.289646)
						(end 86.0171 -285.30423)
					)
				)
			)
		)
		(zone
			(layer "F.Cu")
			(hatch none 0.5)
			(connect_pads
				(clearance 0)
			)
			(min_thickness 0.25)
			(keepout
				(tracks not_allowed)
				(vias allowed)
				(pads allowed)
				(copperpour not_allowed)
				(footprints allowed)
			)
			(placement
				(enabled no)
				(sheetname "")
			)
			(fill
				(thermal_gap 0.5)
				(thermal_bridge_width 0.5)
				(island_removal_mode 0)
			)
			(polygon
				(pts
					(arc
						(start 86.0171 -283.676598)
						(mid 86.031979 -283.712519)
						(end 86.0679 -283.727398)
					)
					(arc
						(start 86.0679 -283.727398)
						(mid 86.087947 -283.723166)
						(end 86.10473 -283.711396)
					)
					(arc
						(start 86.10473 -283.711396)
						(mid 86.173401 -283.614253)
						(end 86.197694 -283.497782)
					)
					(arc
						(start 86.197694 -283.497782)
						(mid 86.11214 -283.291236)
						(end 85.905594 -283.205682)
					)
					(arc
						(start 85.905594 -283.205682)
						(mid 85.790337 -283.229383)
						(end 85.693758 -283.296614)
					)
					(arc
						(start 85.693758 -283.296614)
						(mid 85.681189 -283.313842)
						(end 85.67674 -283.334714)
					)
					(arc
						(start 85.67674 -283.334714)
						(mid 85.691619 -283.370635)
						(end 85.72754 -283.385514)
					)
					(arc
						(start 85.72754 -283.385514)
						(mid 85.741994 -283.383339)
						(end 85.755226 -283.377132)
					)
					(xy 85.769958 -283.3624) (xy 85.770212 -283.362146)
					(arc
						(start 85.770974 -283.361384)
						(mid 85.832851 -283.32054)
						(end 85.905594 -283.306266)
					)
					(arc
						(start 85.905594 -283.306266)
						(mid 86.041016 -283.36236)
						(end 86.09711 -283.497782)
					)
					(arc
						(start 86.09711 -283.497782)
						(mid 86.082394 -283.571404)
						(end 86.040468 -283.633672)
					)
					(xy 86.03996 -283.633926)
					(arc
						(start 86.025482 -283.648404)
						(mid 86.019209 -283.661882)
						(end 86.0171 -283.676598)
					)
				)
			)
		)
		(zone
			(layer "F.Cu")
			(hatch none 0.5)
			(connect_pads
				(clearance 0)
			)
			(min_thickness 0.25)
			(keepout
				(tracks not_allowed)
				(vias allowed)
				(pads allowed)
				(copperpour not_allowed)
				(footprints allowed)
			)
			(placement
				(enabled no)
				(sheetname "")
			)
			(fill
				(thermal_gap 0.5)
				(thermal_bridge_width 0.5)
				(island_removal_mode 0)
			)
			(polygon
				(pts
					(arc
						(start 86.08695 -220.153484)
						(mid 86.051029 -220.168363)
						(end 86.03615 -220.204284)
					)
					(arc
						(start 86.03615 -220.204284)
						(mid 86.040261 -220.224303)
						(end 86.051898 -220.241114)
					)
					(arc
						(start 86.051898 -220.241114)
						(mid 86.149158 -220.309836)
						(end 86.265766 -220.334078)
					)
					(arc
						(start 86.265766 -220.334078)
						(mid 86.472312 -220.248524)
						(end 86.557866 -220.041978)
					)
					(arc
						(start 86.557866 -220.041978)
						(mid 86.534044 -219.926693)
						(end 86.46668 -219.830142)
					)
					(arc
						(start 86.46668 -219.830142)
						(mid 86.449452 -219.817573)
						(end 86.42858 -219.813124)
					)
					(arc
						(start 86.42858 -219.813124)
						(mid 86.392659 -219.828003)
						(end 86.37778 -219.863924)
					)
					(arc
						(start 86.37778 -219.863924)
						(mid 86.379955 -219.878378)
						(end 86.386162 -219.89161)
					)
					(xy 86.400894 -219.906342) (xy 86.401148 -219.906596)
					(arc
						(start 86.40191 -219.907358)
						(mid 86.442889 -219.969206)
						(end 86.457282 -220.041978)
					)
					(arc
						(start 86.457282 -220.041978)
						(mid 86.401188 -220.1774)
						(end 86.265766 -220.233494)
					)
					(arc
						(start 86.265766 -220.233494)
						(mid 86.192173 -220.218896)
						(end 86.129876 -220.177106)
					)
					(xy 86.129368 -220.176344)
					(arc
						(start 86.11489 -220.161866)
						(mid 86.101534 -220.15563)
						(end 86.08695 -220.153484)
					)
				)
			)
		)
		(zone
			(layer "F.Cu")
			(hatch none 0.5)
			(connect_pads
				(clearance 0)
			)
			(min_thickness 0.25)
			(keepout
				(tracks not_allowed)
				(vias allowed)
				(pads allowed)
				(copperpour not_allowed)
				(footprints allowed)
			)
			(placement
				(enabled no)
				(sheetname "")
			)
			(fill
				(thermal_gap 0.5)
				(thermal_bridge_width 0.5)
				(island_removal_mode 0)
			)
			(polygon
				(pts
					(arc
						(start 86.08695 -218.525598)
						(mid 86.051029 -218.540477)
						(end 86.03615 -218.576398)
					)
					(arc
						(start 86.03615 -218.576398)
						(mid 86.04021 -218.596555)
						(end 86.051898 -218.613482)
					)
					(arc
						(start 86.051898 -218.613482)
						(mid 86.149158 -218.682204)
						(end 86.265766 -218.706446)
					)
					(arc
						(start 86.265766 -218.706446)
						(mid 86.472312 -218.620892)
						(end 86.557866 -218.414346)
					)
					(arc
						(start 86.557866 -218.414346)
						(mid 86.534095 -218.298924)
						(end 86.46668 -218.202256)
					)
					(arc
						(start 86.46668 -218.202256)
						(mid 86.449452 -218.189687)
						(end 86.42858 -218.185238)
					)
					(arc
						(start 86.42858 -218.185238)
						(mid 86.392659 -218.200117)
						(end 86.37778 -218.236038)
					)
					(arc
						(start 86.37778 -218.236038)
						(mid 86.379919 -218.250624)
						(end 86.386162 -218.263978)
					)
					(xy 86.400894 -218.278456) (xy 86.401148 -218.278964)
					(arc
						(start 86.40191 -218.279472)
						(mid 86.442937 -218.341437)
						(end 86.457282 -218.414346)
					)
					(arc
						(start 86.457282 -218.414346)
						(mid 86.401188 -218.549768)
						(end 86.265766 -218.605862)
					)
					(arc
						(start 86.265766 -218.605862)
						(mid 86.192144 -218.591146)
						(end 86.129876 -218.54922)
					)
					(xy 86.129368 -218.548458)
					(arc
						(start 86.11489 -218.53398)
						(mid 86.101534 -218.527744)
						(end 86.08695 -218.525598)
					)
				)
			)
		)
		(zone
			(layer "F.Cu")
			(hatch none 0.5)
			(connect_pads
				(clearance 0)
			)
			(min_thickness 0.25)
			(keepout
				(tracks not_allowed)
				(vias allowed)
				(pads allowed)
				(copperpour not_allowed)
				(footprints allowed)
			)
			(placement
				(enabled no)
				(sheetname "")
			)
			(fill
				(thermal_gap 0.5)
				(thermal_bridge_width 0.5)
				(island_removal_mode 0)
			)
			(polygon
				(pts
					(arc
						(start 86.08695 -216.897966)
						(mid 86.051029 -216.912845)
						(end 86.03615 -216.948766)
					)
					(arc
						(start 86.03615 -216.948766)
						(mid 86.040261 -216.968785)
						(end 86.051898 -216.985596)
					)
					(arc
						(start 86.051898 -216.985596)
						(mid 86.149158 -217.054318)
						(end 86.265766 -217.07856)
					)
					(arc
						(start 86.265766 -217.07856)
						(mid 86.472312 -216.993006)
						(end 86.557866 -216.78646)
					)
					(arc
						(start 86.557866 -216.78646)
						(mid 86.534095 -216.671038)
						(end 86.46668 -216.57437)
					)
					(arc
						(start 86.46668 -216.57437)
						(mid 86.449418 -216.561949)
						(end 86.42858 -216.557606)
					)
					(arc
						(start 86.42858 -216.557606)
						(mid 86.392659 -216.572485)
						(end 86.37778 -216.608406)
					)
					(arc
						(start 86.37778 -216.608406)
						(mid 86.379955 -216.62286)
						(end 86.386162 -216.636092)
					)
					(xy 86.400894 -216.650824) (xy 86.401148 -216.651078)
					(arc
						(start 86.40191 -216.65184)
						(mid 86.442889 -216.713688)
						(end 86.457282 -216.78646)
					)
					(arc
						(start 86.457282 -216.78646)
						(mid 86.401188 -216.921882)
						(end 86.265766 -216.977976)
					)
					(arc
						(start 86.265766 -216.977976)
						(mid 86.192144 -216.96326)
						(end 86.129876 -216.921334)
					)
					(xy 86.129368 -216.920826)
					(arc
						(start 86.11489 -216.906348)
						(mid 86.101534 -216.900112)
						(end 86.08695 -216.897966)
					)
				)
			)
		)
		(zone
			(layer "F.Cu")
			(hatch none 0.5)
			(connect_pads
				(clearance 0)
			)
			(min_thickness 0.25)
			(keepout
				(tracks not_allowed)
				(vias allowed)
				(pads allowed)
				(copperpour not_allowed)
				(footprints allowed)
			)
			(placement
				(enabled no)
				(sheetname "")
			)
			(fill
				(thermal_gap 0.5)
				(thermal_bridge_width 0.5)
				(island_removal_mode 0)
			)
			(polygon
				(pts
					(arc
						(start 86.196678 -253.495302)
						(mid 86.160847 -253.510091)
						(end 86.145878 -253.545848)
					)
					(arc
						(start 86.145878 -253.545848)
						(mid 86.15006 -253.566032)
						(end 86.16188 -253.582932)
					)
					(arc
						(start 86.16188 -253.582932)
						(mid 86.259023 -253.651603)
						(end 86.375494 -253.675896)
					)
					(arc
						(start 86.375494 -253.675896)
						(mid 86.58204 -253.590342)
						(end 86.667594 -253.383796)
					)
					(arc
						(start 86.667594 -253.383796)
						(mid 86.643944 -253.268402)
						(end 86.576662 -253.171706)
					)
					(arc
						(start 86.576662 -253.171706)
						(mid 86.559434 -253.159137)
						(end 86.538562 -253.154688)
					)
					(arc
						(start 86.538562 -253.154688)
						(mid 86.502641 -253.169567)
						(end 86.487762 -253.205488)
					)
					(arc
						(start 86.487762 -253.205488)
						(mid 86.489901 -253.220074)
						(end 86.496144 -253.233428)
					)
					(xy 86.510876 -253.247906) (xy 86.51113 -253.248414)
					(arc
						(start 86.511892 -253.249176)
						(mid 86.552736 -253.311053)
						(end 86.56701 -253.383796)
					)
					(arc
						(start 86.56701 -253.383796)
						(mid 86.510916 -253.519218)
						(end 86.375494 -253.575312)
					)
					(arc
						(start 86.375494 -253.575312)
						(mid 86.301872 -253.560596)
						(end 86.239604 -253.51867)
					)
					(xy 86.23935 -253.518162)
					(arc
						(start 86.224872 -253.503684)
						(mid 86.211394 -253.497411)
						(end 86.196678 -253.495302)
					)
				)
			)
		)
		(zone
			(layer "F.Cu")
			(hatch none 0.5)
			(connect_pads
				(clearance 0)
			)
			(min_thickness 0.25)
			(keepout
				(tracks not_allowed)
				(vias allowed)
				(pads allowed)
				(copperpour not_allowed)
				(footprints allowed)
			)
			(placement
				(enabled no)
				(sheetname "")
			)
			(fill
				(thermal_gap 0.5)
				(thermal_bridge_width 0.5)
				(island_removal_mode 0)
			)
			(polygon
				(pts
					(arc
						(start 86.487 -286.1183)
						(mid 86.501879 -286.154221)
						(end 86.5378 -286.1691)
					)
					(arc
						(start 86.5378 -286.1691)
						(mid 86.557847 -286.164868)
						(end 86.57463 -286.153098)
					)
					(arc
						(start 86.57463 -286.153098)
						(mid 86.643301 -286.055955)
						(end 86.667594 -285.939484)
					)
					(arc
						(start 86.667594 -285.939484)
						(mid 86.58204 -285.732938)
						(end 86.375494 -285.647384)
					)
					(arc
						(start 86.375494 -285.647384)
						(mid 86.260237 -285.671085)
						(end 86.163658 -285.738316)
					)
					(arc
						(start 86.163658 -285.738316)
						(mid 86.151089 -285.755544)
						(end 86.14664 -285.776416)
					)
					(arc
						(start 86.14664 -285.776416)
						(mid 86.161519 -285.812337)
						(end 86.19744 -285.827216)
					)
					(arc
						(start 86.19744 -285.827216)
						(mid 86.211894 -285.825041)
						(end 86.225126 -285.818834)
					)
					(xy 86.239858 -285.804102) (xy 86.240112 -285.803848)
					(arc
						(start 86.240874 -285.803086)
						(mid 86.302751 -285.762242)
						(end 86.375494 -285.747968)
					)
					(arc
						(start 86.375494 -285.747968)
						(mid 86.510916 -285.804062)
						(end 86.56701 -285.939484)
					)
					(arc
						(start 86.56701 -285.939484)
						(mid 86.552294 -286.013106)
						(end 86.510368 -286.075374)
					)
					(xy 86.50986 -286.075628)
					(arc
						(start 86.495382 -286.090106)
						(mid 86.489109 -286.103584)
						(end 86.487 -286.1183)
					)
				)
			)
		)
		(zone
			(layer "F.Cu")
			(hatch none 0.5)
			(connect_pads
				(clearance 0)
			)
			(min_thickness 0.25)
			(keepout
				(tracks not_allowed)
				(vias allowed)
				(pads allowed)
				(copperpour not_allowed)
				(footprints allowed)
			)
			(placement
				(enabled no)
				(sheetname "")
			)
			(fill
				(thermal_gap 0.5)
				(thermal_bridge_width 0.5)
				(island_removal_mode 0)
			)
			(polygon
				(pts
					(arc
						(start 86.487 -284.490414)
						(mid 86.501879 -284.526335)
						(end 86.5378 -284.541214)
					)
					(arc
						(start 86.5378 -284.541214)
						(mid 86.557847 -284.536982)
						(end 86.57463 -284.525212)
					)
					(arc
						(start 86.57463 -284.525212)
						(mid 86.643359 -284.428085)
						(end 86.667594 -284.311598)
					)
					(arc
						(start 86.667594 -284.311598)
						(mid 86.58204 -284.105052)
						(end 86.375494 -284.019498)
					)
					(arc
						(start 86.375494 -284.019498)
						(mid 86.260209 -284.04332)
						(end 86.163658 -284.110684)
					)
					(arc
						(start 86.163658 -284.110684)
						(mid 86.15114 -284.127796)
						(end 86.14664 -284.14853)
					)
					(arc
						(start 86.14664 -284.14853)
						(mid 86.161429 -284.184616)
						(end 86.19744 -284.199584)
					)
					(arc
						(start 86.19744 -284.199584)
						(mid 86.21193 -284.197322)
						(end 86.225126 -284.190948)
					)
					(xy 86.239858 -284.17647) (xy 86.240112 -284.175962)
					(arc
						(start 86.240874 -284.1752)
						(mid 86.302751 -284.134356)
						(end 86.375494 -284.120082)
					)
					(arc
						(start 86.375494 -284.120082)
						(mid 86.510916 -284.176176)
						(end 86.56701 -284.311598)
					)
					(arc
						(start 86.56701 -284.311598)
						(mid 86.552294 -284.38522)
						(end 86.510368 -284.447488)
					)
					(xy 86.50986 -284.447996)
					(arc
						(start 86.495382 -284.462474)
						(mid 86.489146 -284.47583)
						(end 86.487 -284.490414)
					)
				)
			)
		)
		(zone
			(layer "F.Cu")
			(hatch none 0.5)
			(connect_pads
				(clearance 0)
			)
			(min_thickness 0.25)
			(keepout
				(tracks not_allowed)
				(vias allowed)
				(pads allowed)
				(copperpour not_allowed)
				(footprints allowed)
			)
			(placement
				(enabled no)
				(sheetname "")
			)
			(fill
				(thermal_gap 0.5)
				(thermal_bridge_width 0.5)
				(island_removal_mode 0)
			)
			(polygon
				(pts
					(arc
						(start 86.55685 -219.339668)
						(mid 86.520929 -219.354547)
						(end 86.50605 -219.390468)
					)
					(arc
						(start 86.50605 -219.390468)
						(mid 86.510161 -219.410487)
						(end 86.521798 -219.427298)
					)
					(arc
						(start 86.521798 -219.427298)
						(mid 86.619058 -219.49602)
						(end 86.735666 -219.520262)
					)
					(arc
						(start 86.735666 -219.520262)
						(mid 86.942212 -219.434708)
						(end 87.027766 -219.228162)
					)
					(arc
						(start 87.027766 -219.228162)
						(mid 87.003995 -219.11274)
						(end 86.93658 -219.016072)
					)
					(arc
						(start 86.93658 -219.016072)
						(mid 86.919352 -219.003503)
						(end 86.89848 -218.999054)
					)
					(arc
						(start 86.89848 -218.999054)
						(mid 86.862559 -219.013933)
						(end 86.84768 -219.049854)
					)
					(arc
						(start 86.84768 -219.049854)
						(mid 86.849819 -219.06444)
						(end 86.856062 -219.077794)
					)
					(xy 86.870794 -219.092526) (xy 86.871048 -219.09278)
					(arc
						(start 86.87181 -219.093542)
						(mid 86.912789 -219.15539)
						(end 86.927182 -219.228162)
					)
					(arc
						(start 86.927182 -219.228162)
						(mid 86.871088 -219.363584)
						(end 86.735666 -219.419678)
					)
					(arc
						(start 86.735666 -219.419678)
						(mid 86.662044 -219.404962)
						(end 86.599776 -219.363036)
					)
					(xy 86.599268 -219.362528)
					(arc
						(start 86.58479 -219.34805)
						(mid 86.571434 -219.341814)
						(end 86.55685 -219.339668)
					)
				)
			)
		)
		(zone
			(layer "F.Cu")
			(hatch none 0.5)
			(connect_pads
				(clearance 0)
			)
			(min_thickness 0.25)
			(keepout
				(tracks not_allowed)
				(vias allowed)
				(pads allowed)
				(copperpour not_allowed)
				(footprints allowed)
			)
			(placement
				(enabled no)
				(sheetname "")
			)
			(fill
				(thermal_gap 0.5)
				(thermal_bridge_width 0.5)
				(island_removal_mode 0)
			)
			(polygon
				(pts
					(arc
						(start 86.55685 -217.711782)
						(mid 86.520929 -217.726661)
						(end 86.50605 -217.762582)
					)
					(arc
						(start 86.50605 -217.762582)
						(mid 86.510161 -217.782601)
						(end 86.521798 -217.799412)
					)
					(arc
						(start 86.521798 -217.799412)
						(mid 86.619058 -217.868134)
						(end 86.735666 -217.892376)
					)
					(arc
						(start 86.735666 -217.892376)
						(mid 86.942212 -217.806822)
						(end 87.027766 -217.600276)
					)
					(arc
						(start 87.027766 -217.600276)
						(mid 87.003944 -217.484991)
						(end 86.93658 -217.38844)
					)
					(arc
						(start 86.93658 -217.38844)
						(mid 86.919352 -217.375871)
						(end 86.89848 -217.371422)
					)
					(arc
						(start 86.89848 -217.371422)
						(mid 86.862559 -217.386301)
						(end 86.84768 -217.422222)
					)
					(arc
						(start 86.84768 -217.422222)
						(mid 86.849855 -217.436676)
						(end 86.856062 -217.449908)
					)
					(xy 86.870794 -217.46464) (xy 86.871048 -217.464894)
					(arc
						(start 86.87181 -217.465656)
						(mid 86.912789 -217.527504)
						(end 86.927182 -217.600276)
					)
					(arc
						(start 86.927182 -217.600276)
						(mid 86.871088 -217.735698)
						(end 86.735666 -217.791792)
					)
					(arc
						(start 86.735666 -217.791792)
						(mid 86.662073 -217.777194)
						(end 86.599776 -217.735404)
					)
					(xy 86.599268 -217.734642)
					(arc
						(start 86.58479 -217.720164)
						(mid 86.571434 -217.713928)
						(end 86.55685 -217.711782)
					)
				)
			)
		)
		(zone
			(layer "F.Cu")
			(hatch none 0.5)
			(connect_pads
				(clearance 0)
			)
			(min_thickness 0.25)
			(keepout
				(tracks not_allowed)
				(vias allowed)
				(pads allowed)
				(copperpour not_allowed)
				(footprints allowed)
			)
			(placement
				(enabled no)
				(sheetname "")
			)
			(fill
				(thermal_gap 0.5)
				(thermal_bridge_width 0.5)
				(island_removal_mode 0)
			)
			(polygon
				(pts
					(arc
						(start 86.9569 -286.932116)
						(mid 86.971779 -286.968037)
						(end 87.0077 -286.982916)
					)
					(arc
						(start 87.0077 -286.982916)
						(mid 87.027884 -286.978734)
						(end 87.044784 -286.966914)
					)
					(arc
						(start 87.044784 -286.966914)
						(mid 87.11337 -286.869755)
						(end 87.137494 -286.7533)
					)
					(arc
						(start 87.137494 -286.7533)
						(mid 87.05203 -286.546844)
						(end 86.845648 -286.4612)
					)
					(arc
						(start 86.845648 -286.4612)
						(mid 86.730226 -286.484971)
						(end 86.633558 -286.552386)
					)
					(arc
						(start 86.633558 -286.552386)
						(mid 86.62104 -286.569498)
						(end 86.61654 -286.590232)
					)
					(arc
						(start 86.61654 -286.590232)
						(mid 86.631329 -286.626318)
						(end 86.66734 -286.641286)
					)
					(arc
						(start 86.66734 -286.641286)
						(mid 86.681931 -286.638993)
						(end 86.69528 -286.63265)
					)
					(xy 86.709758 -286.618172) (xy 86.710266 -286.617664)
					(arc
						(start 86.710774 -286.616902)
						(mid 86.772768 -286.57601)
						(end 86.845648 -286.561784)
					)
					(arc
						(start 86.845648 -286.561784)
						(mid 86.98107 -286.617878)
						(end 87.037164 -286.7533)
					)
					(arc
						(start 87.037164 -286.7533)
						(mid 87.022365 -286.826868)
						(end 86.980522 -286.88919)
					)
					(xy 86.97976 -286.889698)
					(arc
						(start 86.965282 -286.904176)
						(mid 86.959046 -286.917532)
						(end 86.9569 -286.932116)
					)
				)
			)
		)
		(zone
			(layer "F.Cu")
			(hatch none 0.5)
			(connect_pads
				(clearance 0)
			)
			(min_thickness 0.25)
			(keepout
				(tracks not_allowed)
				(vias allowed)
				(pads allowed)
				(copperpour not_allowed)
				(footprints allowed)
			)
			(placement
				(enabled no)
				(sheetname "")
			)
			(fill
				(thermal_gap 0.5)
				(thermal_bridge_width 0.5)
				(island_removal_mode 0)
			)
			(polygon
				(pts
					(arc
						(start 86.9569 -285.30423)
						(mid 86.971779 -285.340151)
						(end 87.0077 -285.35503)
					)
					(arc
						(start 87.0077 -285.35503)
						(mid 87.027857 -285.35097)
						(end 87.044784 -285.339282)
					)
					(arc
						(start 87.044784 -285.339282)
						(mid 87.113362 -285.24199)
						(end 87.137494 -285.125414)
					)
					(arc
						(start 87.137494 -285.125414)
						(mid 87.052014 -284.919048)
						(end 86.845648 -284.833568)
					)
					(arc
						(start 86.845648 -284.833568)
						(mid 86.730269 -284.857234)
						(end 86.633558 -284.9245)
					)
					(arc
						(start 86.633558 -284.9245)
						(mid 86.620989 -284.941728)
						(end 86.61654 -284.9626)
					)
					(arc
						(start 86.61654 -284.9626)
						(mid 86.631419 -284.998521)
						(end 86.66734 -285.0134)
					)
					(arc
						(start 86.66734 -285.0134)
						(mid 86.681962 -285.011174)
						(end 86.69528 -285.004764)
					)
					(xy 86.709758 -284.990286) (xy 86.710266 -284.989778)
					(arc
						(start 86.710774 -284.98927)
						(mid 86.772739 -284.948243)
						(end 86.845648 -284.933898)
					)
					(arc
						(start 86.845648 -284.933898)
						(mid 86.98107 -284.989992)
						(end 87.037164 -285.125414)
					)
					(arc
						(start 87.037164 -285.125414)
						(mid 87.022448 -285.199036)
						(end 86.980522 -285.261304)
					)
					(xy 86.97976 -285.261812)
					(arc
						(start 86.965282 -285.27629)
						(mid 86.959046 -285.289646)
						(end 86.9569 -285.30423)
					)
				)
			)
		)
		(zone
			(layer "F.Cu")
			(hatch none 0.5)
			(connect_pads
				(clearance 0)
			)
			(min_thickness 0.25)
			(keepout
				(tracks not_allowed)
				(vias allowed)
				(pads allowed)
				(copperpour not_allowed)
				(footprints allowed)
			)
			(placement
				(enabled no)
				(sheetname "")
			)
			(fill
				(thermal_gap 0.5)
				(thermal_bridge_width 0.5)
				(island_removal_mode 0)
			)
			(polygon
				(pts
					(arc
						(start 87.026496 -218.525598)
						(mid 86.990575 -218.540477)
						(end 86.975696 -218.576398)
					)
					(arc
						(start 86.975696 -218.576398)
						(mid 86.979878 -218.596582)
						(end 86.991698 -218.613482)
					)
					(arc
						(start 86.991698 -218.613482)
						(mid 87.088841 -218.682153)
						(end 87.205312 -218.706446)
					)
					(arc
						(start 87.205312 -218.706446)
						(mid 87.411858 -218.620892)
						(end 87.497412 -218.414346)
					)
					(arc
						(start 87.497412 -218.414346)
						(mid 87.473641 -218.298924)
						(end 87.406226 -218.202256)
					)
					(arc
						(start 87.406226 -218.202256)
						(mid 87.389131 -218.189677)
						(end 87.36838 -218.185238)
					)
					(arc
						(start 87.36838 -218.185238)
						(mid 87.332459 -218.200117)
						(end 87.31758 -218.236038)
					)
					(arc
						(start 87.31758 -218.236038)
						(mid 87.319719 -218.250624)
						(end 87.325962 -218.263978)
					)
					(xy 87.340694 -218.278456) (xy 87.340948 -218.278964)
					(arc
						(start 87.341456 -218.279472)
						(mid 87.382483 -218.341437)
						(end 87.396828 -218.414346)
					)
					(arc
						(start 87.396828 -218.414346)
						(mid 87.340734 -218.549768)
						(end 87.205312 -218.605862)
					)
					(arc
						(start 87.205312 -218.605862)
						(mid 87.13173 -218.591078)
						(end 87.069422 -218.54922)
					)
					(xy 87.069168 -218.548458)
					(arc
						(start 87.05469 -218.53398)
						(mid 87.041207 -218.527738)
						(end 87.026496 -218.525598)
					)
				)
			)
		)
		(zone
			(layer "F.Cu")
			(hatch none 0.5)
			(connect_pads
				(clearance 0)
			)
			(min_thickness 0.25)
			(keepout
				(tracks not_allowed)
				(vias allowed)
				(pads allowed)
				(copperpour not_allowed)
				(footprints allowed)
			)
			(placement
				(enabled no)
				(sheetname "")
			)
			(fill
				(thermal_gap 0.5)
				(thermal_bridge_width 0.5)
				(island_removal_mode 0)
			)
			(polygon
				(pts
					(arc
						(start 87.026496 -216.897966)
						(mid 86.990575 -216.912845)
						(end 86.975696 -216.948766)
					)
					(arc
						(start 86.975696 -216.948766)
						(mid 86.979928 -216.968813)
						(end 86.991698 -216.985596)
					)
					(arc
						(start 86.991698 -216.985596)
						(mid 87.088841 -217.054267)
						(end 87.205312 -217.07856)
					)
					(arc
						(start 87.205312 -217.07856)
						(mid 87.411858 -216.993006)
						(end 87.497412 -216.78646)
					)
					(arc
						(start 87.497412 -216.78646)
						(mid 87.473641 -216.671038)
						(end 87.406226 -216.57437)
					)
					(arc
						(start 87.406226 -216.57437)
						(mid 87.38908 -216.562)
						(end 87.36838 -216.557606)
					)
					(arc
						(start 87.36838 -216.557606)
						(mid 87.332459 -216.572485)
						(end 87.31758 -216.608406)
					)
					(arc
						(start 87.31758 -216.608406)
						(mid 87.319755 -216.62286)
						(end 87.325962 -216.636092)
					)
					(xy 87.340694 -216.650824) (xy 87.340948 -216.651078)
					(arc
						(start 87.341456 -216.65184)
						(mid 87.382488 -216.713674)
						(end 87.396828 -216.78646)
					)
					(arc
						(start 87.396828 -216.78646)
						(mid 87.340734 -216.921882)
						(end 87.205312 -216.977976)
					)
					(arc
						(start 87.205312 -216.977976)
						(mid 87.13169 -216.96326)
						(end 87.069422 -216.921334)
					)
					(xy 87.069168 -216.920826)
					(arc
						(start 87.05469 -216.906348)
						(mid 87.041212 -216.900075)
						(end 87.026496 -216.897966)
					)
				)
			)
		)
		(zone
			(layer "F.Cu")
			(hatch none 0.5)
			(connect_pads
				(clearance 0)
			)
			(min_thickness 0.25)
			(keepout
				(tracks not_allowed)
				(vias allowed)
				(pads allowed)
				(copperpour not_allowed)
				(footprints allowed)
			)
			(placement
				(enabled no)
				(sheetname "")
			)
			(fill
				(thermal_gap 0.5)
				(thermal_bridge_width 0.5)
				(island_removal_mode 0)
			)
			(polygon
				(pts
					(arc
						(start 87.4268 -287.745932)
						(mid 87.441679 -287.781853)
						(end 87.4776 -287.796732)
					)
					(arc
						(start 87.4776 -287.796732)
						(mid 87.497619 -287.792621)
						(end 87.51443 -287.780984)
					)
					(arc
						(start 87.51443 -287.780984)
						(mid 87.583152 -287.683724)
						(end 87.607394 -287.567116)
					)
					(arc
						(start 87.607394 -287.567116)
						(mid 87.52175 -287.360734)
						(end 87.315294 -287.27527)
					)
					(arc
						(start 87.315294 -287.27527)
						(mid 87.200053 -287.298986)
						(end 87.103458 -287.366202)
					)
					(arc
						(start 87.103458 -287.366202)
						(mid 87.090889 -287.38343)
						(end 87.08644 -287.404302)
					)
					(arc
						(start 87.08644 -287.404302)
						(mid 87.101319 -287.440223)
						(end 87.13724 -287.455102)
					)
					(arc
						(start 87.13724 -287.455102)
						(mid 87.15173 -287.45284)
						(end 87.164926 -287.446466)
					)
					(xy 87.179658 -287.431988) (xy 87.179912 -287.43148)
					(arc
						(start 87.180674 -287.430972)
						(mid 87.242522 -287.389993)
						(end 87.315294 -287.3756)
					)
					(arc
						(start 87.315294 -287.3756)
						(mid 87.450716 -287.431694)
						(end 87.50681 -287.567116)
					)
					(arc
						(start 87.50681 -287.567116)
						(mid 87.492094 -287.640738)
						(end 87.450168 -287.703006)
					)
					(xy 87.44966 -287.703514)
					(arc
						(start 87.435182 -287.717992)
						(mid 87.428946 -287.731348)
						(end 87.4268 -287.745932)
					)
				)
			)
		)
		(zone
			(layer "F.Cu")
			(hatch none 0.5)
			(connect_pads
				(clearance 0)
			)
			(min_thickness 0.25)
			(keepout
				(tracks not_allowed)
				(vias allowed)
				(pads allowed)
				(copperpour not_allowed)
				(footprints allowed)
			)
			(placement
				(enabled no)
				(sheetname "")
			)
			(fill
				(thermal_gap 0.5)
				(thermal_bridge_width 0.5)
				(island_removal_mode 0)
			)
			(polygon
				(pts
					(arc
						(start 87.4268 -286.1183)
						(mid 87.441679 -286.154221)
						(end 87.4776 -286.1691)
					)
					(arc
						(start 87.4776 -286.1691)
						(mid 87.497647 -286.164868)
						(end 87.51443 -286.153098)
					)
					(arc
						(start 87.51443 -286.153098)
						(mid 87.583101 -286.055955)
						(end 87.607394 -285.939484)
					)
					(arc
						(start 87.607394 -285.939484)
						(mid 87.52184 -285.732938)
						(end 87.315294 -285.647384)
					)
					(arc
						(start 87.315294 -285.647384)
						(mid 87.200037 -285.671085)
						(end 87.103458 -285.738316)
					)
					(arc
						(start 87.103458 -285.738316)
						(mid 87.090889 -285.755544)
						(end 87.08644 -285.776416)
					)
					(arc
						(start 87.08644 -285.776416)
						(mid 87.101319 -285.812337)
						(end 87.13724 -285.827216)
					)
					(arc
						(start 87.13724 -285.827216)
						(mid 87.151694 -285.825041)
						(end 87.164926 -285.818834)
					)
					(xy 87.179658 -285.804102) (xy 87.179912 -285.803848)
					(arc
						(start 87.180674 -285.803086)
						(mid 87.242551 -285.762242)
						(end 87.315294 -285.747968)
					)
					(arc
						(start 87.315294 -285.747968)
						(mid 87.450716 -285.804062)
						(end 87.50681 -285.939484)
					)
					(arc
						(start 87.50681 -285.939484)
						(mid 87.492094 -286.013106)
						(end 87.450168 -286.075374)
					)
					(xy 87.44966 -286.075628)
					(arc
						(start 87.435182 -286.090106)
						(mid 87.428909 -286.103584)
						(end 87.4268 -286.1183)
					)
				)
			)
		)
		(zone
			(layer "F.Cu")
			(hatch none 0.5)
			(connect_pads
				(clearance 0)
			)
			(min_thickness 0.25)
			(keepout
				(tracks not_allowed)
				(vias allowed)
				(pads allowed)
				(copperpour not_allowed)
				(footprints allowed)
			)
			(placement
				(enabled no)
				(sheetname "")
			)
			(fill
				(thermal_gap 0.5)
				(thermal_bridge_width 0.5)
				(island_removal_mode 0)
			)
			(polygon
				(pts
					(arc
						(start 87.49665 -217.711782)
						(mid 87.460729 -217.726661)
						(end 87.44585 -217.762582)
					)
					(arc
						(start 87.44585 -217.762582)
						(mid 87.449961 -217.782601)
						(end 87.461598 -217.799412)
					)
					(arc
						(start 87.461598 -217.799412)
						(mid 87.558858 -217.868134)
						(end 87.675466 -217.892376)
					)
					(arc
						(start 87.675466 -217.892376)
						(mid 87.882012 -217.806822)
						(end 87.967566 -217.600276)
					)
					(arc
						(start 87.967566 -217.600276)
						(mid 87.943744 -217.484991)
						(end 87.87638 -217.38844)
					)
					(arc
						(start 87.87638 -217.38844)
						(mid 87.859152 -217.375871)
						(end 87.83828 -217.371422)
					)
					(arc
						(start 87.83828 -217.371422)
						(mid 87.802359 -217.386301)
						(end 87.78748 -217.422222)
					)
					(arc
						(start 87.78748 -217.422222)
						(mid 87.789655 -217.436676)
						(end 87.795862 -217.449908)
					)
					(xy 87.810594 -217.46464) (xy 87.810848 -217.464894)
					(arc
						(start 87.81161 -217.465656)
						(mid 87.852589 -217.527504)
						(end 87.866982 -217.600276)
					)
					(arc
						(start 87.866982 -217.600276)
						(mid 87.810888 -217.735698)
						(end 87.675466 -217.791792)
					)
					(arc
						(start 87.675466 -217.791792)
						(mid 87.601873 -217.777194)
						(end 87.539576 -217.735404)
					)
					(xy 87.539068 -217.734642)
					(arc
						(start 87.52459 -217.720164)
						(mid 87.511234 -217.713928)
						(end 87.49665 -217.711782)
					)
				)
			)
		)
		(zone
			(layer "F.Cu")
			(hatch none 0.5)
			(connect_pads
				(clearance 0)
			)
			(min_thickness 0.25)
			(keepout
				(tracks not_allowed)
				(vias allowed)
				(pads allowed)
				(copperpour not_allowed)
				(footprints allowed)
			)
			(placement
				(enabled no)
				(sheetname "")
			)
			(fill
				(thermal_gap 0.5)
				(thermal_bridge_width 0.5)
				(island_removal_mode 0)
			)
			(polygon
				(pts
					(arc
						(start 87.49665 -216.083896)
						(mid 87.460729 -216.098775)
						(end 87.44585 -216.134696)
					)
					(arc
						(start 87.44585 -216.134696)
						(mid 87.44991 -216.154853)
						(end 87.461598 -216.17178)
					)
					(arc
						(start 87.461598 -216.17178)
						(mid 87.558858 -216.240502)
						(end 87.675466 -216.264744)
					)
					(arc
						(start 87.675466 -216.264744)
						(mid 87.882012 -216.17919)
						(end 87.967566 -215.972644)
					)
					(arc
						(start 87.967566 -215.972644)
						(mid 87.943795 -215.857222)
						(end 87.87638 -215.760554)
					)
					(arc
						(start 87.87638 -215.760554)
						(mid 87.859152 -215.747985)
						(end 87.83828 -215.743536)
					)
					(arc
						(start 87.83828 -215.743536)
						(mid 87.802359 -215.758415)
						(end 87.78748 -215.794336)
					)
					(arc
						(start 87.78748 -215.794336)
						(mid 87.789619 -215.808922)
						(end 87.795862 -215.822276)
					)
					(xy 87.810594 -215.836754) (xy 87.810848 -215.837262)
					(arc
						(start 87.81161 -215.83777)
						(mid 87.852637 -215.899735)
						(end 87.866982 -215.972644)
					)
					(arc
						(start 87.866982 -215.972644)
						(mid 87.810888 -216.108066)
						(end 87.675466 -216.16416)
					)
					(arc
						(start 87.675466 -216.16416)
						(mid 87.601844 -216.149444)
						(end 87.539576 -216.107518)
					)
					(xy 87.539068 -216.106756)
					(arc
						(start 87.52459 -216.092278)
						(mid 87.511234 -216.086042)
						(end 87.49665 -216.083896)
					)
				)
			)
		)
		(zone
			(layer "F.Cu")
			(hatch none 0.5)
			(connect_pads
				(clearance 0)
			)
			(min_thickness 0.25)
			(keepout
				(tracks not_allowed)
				(vias allowed)
				(pads allowed)
				(copperpour not_allowed)
				(footprints allowed)
			)
			(placement
				(enabled no)
				(sheetname "")
			)
			(fill
				(thermal_gap 0.5)
				(thermal_bridge_width 0.5)
				(island_removal_mode 0)
			)
			(polygon
				(pts
					(arc
						(start 87.8967 -288.560002)
						(mid 87.911579 -288.595923)
						(end 87.9475 -288.610802)
					)
					(arc
						(start 87.9475 -288.610802)
						(mid 87.967547 -288.60657)
						(end 87.98433 -288.5948)
					)
					(arc
						(start 87.98433 -288.5948)
						(mid 88.053001 -288.497657)
						(end 88.077294 -288.381186)
					)
					(arc
						(start 88.077294 -288.381186)
						(mid 87.99174 -288.17464)
						(end 87.785194 -288.089086)
					)
					(arc
						(start 87.785194 -288.089086)
						(mid 87.669937 -288.112787)
						(end 87.573358 -288.180018)
					)
					(arc
						(start 87.573358 -288.180018)
						(mid 87.560789 -288.197246)
						(end 87.55634 -288.218118)
					)
					(arc
						(start 87.55634 -288.218118)
						(mid 87.571219 -288.254039)
						(end 87.60714 -288.268918)
					)
					(arc
						(start 87.60714 -288.268918)
						(mid 87.621594 -288.266743)
						(end 87.634826 -288.260536)
					)
					(xy 87.649558 -288.245804) (xy 87.649812 -288.24555)
					(arc
						(start 87.650574 -288.244788)
						(mid 87.712451 -288.203944)
						(end 87.785194 -288.18967)
					)
					(arc
						(start 87.785194 -288.18967)
						(mid 87.920616 -288.245764)
						(end 87.97671 -288.381186)
					)
					(arc
						(start 87.97671 -288.381186)
						(mid 87.961994 -288.454808)
						(end 87.920068 -288.517076)
					)
					(xy 87.91956 -288.51733)
					(arc
						(start 87.905082 -288.531808)
						(mid 87.898809 -288.545286)
						(end 87.8967 -288.560002)
					)
				)
			)
		)
		(zone
			(layer "F.Cu")
			(hatch none 0.5)
			(connect_pads
				(clearance 0)
			)
			(min_thickness 0.25)
			(keepout
				(tracks not_allowed)
				(vias allowed)
				(pads allowed)
				(copperpour not_allowed)
				(footprints allowed)
			)
			(placement
				(enabled no)
				(sheetname "")
			)
			(fill
				(thermal_gap 0.5)
				(thermal_bridge_width 0.5)
				(island_removal_mode 0)
			)
			(polygon
				(pts
					(arc
						(start 87.8967 -286.932116)
						(mid 87.911579 -286.968037)
						(end 87.9475 -286.982916)
					)
					(arc
						(start 87.9475 -286.982916)
						(mid 87.967547 -286.978684)
						(end 87.98433 -286.966914)
					)
					(arc
						(start 87.98433 -286.966914)
						(mid 88.053059 -286.869787)
						(end 88.077294 -286.7533)
					)
					(arc
						(start 88.077294 -286.7533)
						(mid 87.99174 -286.546754)
						(end 87.785194 -286.4612)
					)
					(arc
						(start 87.785194 -286.4612)
						(mid 87.669909 -286.485022)
						(end 87.573358 -286.552386)
					)
					(arc
						(start 87.573358 -286.552386)
						(mid 87.56084 -286.569498)
						(end 87.55634 -286.590232)
					)
					(arc
						(start 87.55634 -286.590232)
						(mid 87.571129 -286.626318)
						(end 87.60714 -286.641286)
					)
					(arc
						(start 87.60714 -286.641286)
						(mid 87.62163 -286.639024)
						(end 87.634826 -286.63265)
					)
					(xy 87.649558 -286.618172) (xy 87.649812 -286.617664)
					(arc
						(start 87.650574 -286.616902)
						(mid 87.712451 -286.576058)
						(end 87.785194 -286.561784)
					)
					(arc
						(start 87.785194 -286.561784)
						(mid 87.920616 -286.617878)
						(end 87.97671 -286.7533)
					)
					(arc
						(start 87.97671 -286.7533)
						(mid 87.961994 -286.826922)
						(end 87.920068 -286.88919)
					)
					(xy 87.91956 -286.889698)
					(arc
						(start 87.905082 -286.904176)
						(mid 87.898846 -286.917532)
						(end 87.8967 -286.932116)
					)
				)
			)
		)
		(zone
			(layer "F.Cu")
			(hatch none 0.5)
			(connect_pads
				(clearance 0)
			)
			(min_thickness 0.25)
			(keepout
				(tracks not_allowed)
				(vias allowed)
				(pads allowed)
				(copperpour not_allowed)
				(footprints allowed)
			)
			(placement
				(enabled no)
				(sheetname "")
			)
			(fill
				(thermal_gap 0.5)
				(thermal_bridge_width 0.5)
				(island_removal_mode 0)
			)
			(polygon
				(pts
					(arc
						(start 87.96655 -216.897966)
						(mid 87.930629 -216.912845)
						(end 87.91575 -216.948766)
					)
					(arc
						(start 87.91575 -216.948766)
						(mid 87.919861 -216.968785)
						(end 87.931498 -216.985596)
					)
					(arc
						(start 87.931498 -216.985596)
						(mid 88.028758 -217.054318)
						(end 88.145366 -217.07856)
					)
					(arc
						(start 88.145366 -217.07856)
						(mid 88.351912 -216.993006)
						(end 88.437466 -216.78646)
					)
					(arc
						(start 88.437466 -216.78646)
						(mid 88.413695 -216.671038)
						(end 88.34628 -216.57437)
					)
					(arc
						(start 88.34628 -216.57437)
						(mid 88.329018 -216.561949)
						(end 88.30818 -216.557606)
					)
					(arc
						(start 88.30818 -216.557606)
						(mid 88.272259 -216.572485)
						(end 88.25738 -216.608406)
					)
					(arc
						(start 88.25738 -216.608406)
						(mid 88.259555 -216.62286)
						(end 88.265762 -216.636092)
					)
					(xy 88.280494 -216.650824) (xy 88.280748 -216.651078)
					(arc
						(start 88.28151 -216.65184)
						(mid 88.322489 -216.713688)
						(end 88.336882 -216.78646)
					)
					(arc
						(start 88.336882 -216.78646)
						(mid 88.280788 -216.921882)
						(end 88.145366 -216.977976)
					)
					(arc
						(start 88.145366 -216.977976)
						(mid 88.071744 -216.96326)
						(end 88.009476 -216.921334)
					)
					(xy 88.008968 -216.920826)
					(arc
						(start 87.99449 -216.906348)
						(mid 87.981134 -216.900112)
						(end 87.96655 -216.897966)
					)
				)
			)
		)
		(zone
			(layer "F.Cu")
			(hatch none 0.5)
			(connect_pads
				(clearance 0)
			)
			(min_thickness 0.25)
			(keepout
				(tracks not_allowed)
				(vias allowed)
				(pads allowed)
				(copperpour not_allowed)
				(footprints allowed)
			)
			(placement
				(enabled no)
				(sheetname "")
			)
			(fill
				(thermal_gap 0.5)
				(thermal_bridge_width 0.5)
				(island_removal_mode 0)
			)
			(polygon
				(pts
					(arc
						(start 87.96655 -215.27008)
						(mid 87.930629 -215.284959)
						(end 87.91575 -215.32088)
					)
					(arc
						(start 87.91575 -215.32088)
						(mid 87.919845 -215.340915)
						(end 87.931498 -215.35771)
					)
					(arc
						(start 87.931498 -215.35771)
						(mid 88.028758 -215.426432)
						(end 88.145366 -215.450674)
					)
					(arc
						(start 88.145366 -215.450674)
						(mid 88.351912 -215.36512)
						(end 88.437466 -215.158574)
					)
					(arc
						(start 88.437466 -215.158574)
						(mid 88.413644 -215.043289)
						(end 88.34628 -214.946738)
					)
					(arc
						(start 88.34628 -214.946738)
						(mid 88.329052 -214.934169)
						(end 88.30818 -214.92972)
					)
					(arc
						(start 88.30818 -214.92972)
						(mid 88.272259 -214.944599)
						(end 88.25738 -214.98052)
					)
					(arc
						(start 88.25738 -214.98052)
						(mid 88.259555 -214.994974)
						(end 88.265762 -215.008206)
					)
					(xy 88.280494 -215.022938) (xy 88.280748 -215.023192)
					(arc
						(start 88.28151 -215.023954)
						(mid 88.322489 -215.085802)
						(end 88.336882 -215.158574)
					)
					(arc
						(start 88.336882 -215.158574)
						(mid 88.280788 -215.293996)
						(end 88.145366 -215.35009)
					)
					(arc
						(start 88.145366 -215.35009)
						(mid 88.071773 -215.335492)
						(end 88.009476 -215.293702)
					)
					(xy 88.008968 -215.29294)
					(arc
						(start 87.99449 -215.278462)
						(mid 87.981134 -215.272226)
						(end 87.96655 -215.27008)
					)
				)
			)
		)
		(zone
			(layer "F.Cu")
			(hatch none 0.5)
			(connect_pads
				(clearance 0)
			)
			(min_thickness 0.25)
			(keepout
				(tracks not_allowed)
				(vias allowed)
				(pads allowed)
				(copperpour not_allowed)
				(footprints allowed)
			)
			(placement
				(enabled no)
				(sheetname "")
			)
			(fill
				(thermal_gap 0.5)
				(thermal_bridge_width 0.5)
				(island_removal_mode 0)
			)
			(polygon
				(pts
					(arc
						(start 88.3666 -287.745932)
						(mid 88.381479 -287.781853)
						(end 88.4174 -287.796732)
					)
					(arc
						(start 88.4174 -287.796732)
						(mid 88.437419 -287.792621)
						(end 88.45423 -287.780984)
					)
					(arc
						(start 88.45423 -287.780984)
						(mid 88.522952 -287.683724)
						(end 88.547194 -287.567116)
					)
					(arc
						(start 88.547194 -287.567116)
						(mid 88.46155 -287.360734)
						(end 88.255094 -287.27527)
					)
					(arc
						(start 88.255094 -287.27527)
						(mid 88.139853 -287.298986)
						(end 88.043258 -287.366202)
					)
					(arc
						(start 88.043258 -287.366202)
						(mid 88.030689 -287.38343)
						(end 88.02624 -287.404302)
					)
					(arc
						(start 88.02624 -287.404302)
						(mid 88.041119 -287.440223)
						(end 88.07704 -287.455102)
					)
					(arc
						(start 88.07704 -287.455102)
						(mid 88.09153 -287.45284)
						(end 88.104726 -287.446466)
					)
					(xy 88.119458 -287.431988) (xy 88.119712 -287.43148)
					(arc
						(start 88.120474 -287.430972)
						(mid 88.182322 -287.389993)
						(end 88.255094 -287.3756)
					)
					(arc
						(start 88.255094 -287.3756)
						(mid 88.390516 -287.431694)
						(end 88.44661 -287.567116)
					)
					(arc
						(start 88.44661 -287.567116)
						(mid 88.431894 -287.640738)
						(end 88.389968 -287.703006)
					)
					(xy 88.38946 -287.703514)
					(arc
						(start 88.374982 -287.717992)
						(mid 88.368746 -287.731348)
						(end 88.3666 -287.745932)
					)
				)
			)
		)
		(zone
			(layer "F.Cu")
			(hatch none 0.5)
			(connect_pads
				(clearance 0)
			)
			(min_thickness 0.25)
			(keepout
				(tracks not_allowed)
				(vias allowed)
				(pads allowed)
				(copperpour not_allowed)
				(footprints allowed)
			)
			(placement
				(enabled no)
				(sheetname "")
			)
			(fill
				(thermal_gap 0.5)
				(thermal_bridge_width 0.5)
				(island_removal_mode 0)
			)
			(polygon
				(pts
					(arc
						(start 88.43645 -216.083896)
						(mid 88.400529 -216.098775)
						(end 88.38565 -216.134696)
					)
					(arc
						(start 88.38565 -216.134696)
						(mid 88.38971 -216.154853)
						(end 88.401398 -216.17178)
					)
					(arc
						(start 88.401398 -216.17178)
						(mid 88.498658 -216.240502)
						(end 88.615266 -216.264744)
					)
					(arc
						(start 88.615266 -216.264744)
						(mid 88.821812 -216.17919)
						(end 88.907366 -215.972644)
					)
					(arc
						(start 88.907366 -215.972644)
						(mid 88.883595 -215.857222)
						(end 88.81618 -215.760554)
					)
					(arc
						(start 88.81618 -215.760554)
						(mid 88.798952 -215.747985)
						(end 88.77808 -215.743536)
					)
					(arc
						(start 88.77808 -215.743536)
						(mid 88.742159 -215.758415)
						(end 88.72728 -215.794336)
					)
					(arc
						(start 88.72728 -215.794336)
						(mid 88.729419 -215.808922)
						(end 88.735662 -215.822276)
					)
					(xy 88.750394 -215.836754) (xy 88.750648 -215.837262)
					(arc
						(start 88.75141 -215.83777)
						(mid 88.792437 -215.899735)
						(end 88.806782 -215.972644)
					)
					(arc
						(start 88.806782 -215.972644)
						(mid 88.750688 -216.108066)
						(end 88.615266 -216.16416)
					)
					(arc
						(start 88.615266 -216.16416)
						(mid 88.541644 -216.149444)
						(end 88.479376 -216.107518)
					)
					(xy 88.478868 -216.106756)
					(arc
						(start 88.46439 -216.092278)
						(mid 88.451034 -216.086042)
						(end 88.43645 -216.083896)
					)
				)
			)
		)
		(zone
			(layer "F.Cu")
			(hatch none 0.5)
			(connect_pads
				(clearance 0)
			)
			(min_thickness 0.25)
			(keepout
				(tracks not_allowed)
				(vias allowed)
				(pads allowed)
				(copperpour not_allowed)
				(footprints allowed)
			)
			(placement
				(enabled no)
				(sheetname "")
			)
			(fill
				(thermal_gap 0.5)
				(thermal_bridge_width 0.5)
				(island_removal_mode 0)
			)
			(polygon
				(pts
					(arc
						(start 88.8365 -288.560002)
						(mid 88.851379 -288.595923)
						(end 88.8873 -288.610802)
					)
					(arc
						(start 88.8873 -288.610802)
						(mid 88.907484 -288.60662)
						(end 88.924384 -288.5948)
					)
					(arc
						(start 88.924384 -288.5948)
						(mid 88.992912 -288.497625)
						(end 89.017094 -288.381186)
					)
					(arc
						(start 89.017094 -288.381186)
						(mid 88.931704 -288.174655)
						(end 88.725248 -288.089086)
					)
					(arc
						(start 88.725248 -288.089086)
						(mid 88.609854 -288.112736)
						(end 88.513158 -288.180018)
					)
					(arc
						(start 88.513158 -288.180018)
						(mid 88.500589 -288.197246)
						(end 88.49614 -288.218118)
					)
					(arc
						(start 88.49614 -288.218118)
						(mid 88.511019 -288.254039)
						(end 88.54694 -288.268918)
					)
					(arc
						(start 88.54694 -288.268918)
						(mid 88.561526 -288.266779)
						(end 88.57488 -288.260536)
					)
					(xy 88.589358 -288.245804) (xy 88.589866 -288.24555)
					(arc
						(start 88.590374 -288.244788)
						(mid 88.652368 -288.203896)
						(end 88.725248 -288.18967)
					)
					(arc
						(start 88.725248 -288.18967)
						(mid 88.86067 -288.245764)
						(end 88.916764 -288.381186)
					)
					(arc
						(start 88.916764 -288.381186)
						(mid 88.90198 -288.454768)
						(end 88.860122 -288.517076)
					)
					(xy 88.85936 -288.51733)
					(arc
						(start 88.844882 -288.531808)
						(mid 88.83864 -288.545291)
						(end 88.8365 -288.560002)
					)
				)
			)
		)
		(zone
			(layer "F.Cu")
			(hatch none 0.5)
			(connect_pads
				(clearance 0)
			)
			(min_thickness 0.25)
			(keepout
				(tracks not_allowed)
				(vias allowed)
				(pads allowed)
				(copperpour not_allowed)
				(footprints allowed)
			)
			(placement
				(enabled no)
				(sheetname "")
			)
			(fill
				(thermal_gap 0.5)
				(thermal_bridge_width 0.5)
				(island_removal_mode 0)
			)
			(polygon
				(pts
					(arc
						(start 88.906096 -215.27008)
						(mid 88.870175 -215.284959)
						(end 88.855296 -215.32088)
					)
					(arc
						(start 88.855296 -215.32088)
						(mid 88.859528 -215.340927)
						(end 88.871298 -215.35771)
					)
					(arc
						(start 88.871298 -215.35771)
						(mid 88.968425 -215.426439)
						(end 89.084912 -215.450674)
					)
					(arc
						(start 89.084912 -215.450674)
						(mid 89.291458 -215.36512)
						(end 89.377012 -215.158574)
					)
					(arc
						(start 89.377012 -215.158574)
						(mid 89.353175 -215.043305)
						(end 89.285826 -214.946738)
					)
					(arc
						(start 89.285826 -214.946738)
						(mid 89.268731 -214.934159)
						(end 89.24798 -214.92972)
					)
					(arc
						(start 89.24798 -214.92972)
						(mid 89.212059 -214.944599)
						(end 89.19718 -214.98052)
					)
					(arc
						(start 89.19718 -214.98052)
						(mid 89.199365 -214.994968)
						(end 89.205562 -215.008206)
					)
					(xy 89.220294 -215.022938) (xy 89.220548 -215.023192)
					(arc
						(start 89.221056 -215.023954)
						(mid 89.262035 -215.085802)
						(end 89.276428 -215.158574)
					)
					(arc
						(start 89.276428 -215.158574)
						(mid 89.220334 -215.293996)
						(end 89.084912 -215.35009)
					)
					(arc
						(start 89.084912 -215.35009)
						(mid 89.011319 -215.335492)
						(end 88.949022 -215.293702)
					)
					(xy 88.948768 -215.29294)
					(arc
						(start 88.93429 -215.278462)
						(mid 88.920812 -215.272189)
						(end 88.906096 -215.27008)
					)
				)
			)
		)
		(zone
			(layer "F.Cu")
			(hatch none 0.5)
			(connect_pads
				(clearance 0)
			)
			(min_thickness 0.25)
			(keepout
				(tracks not_allowed)
				(vias allowed)
				(pads allowed)
				(copperpour not_allowed)
				(footprints allowed)
			)
			(placement
				(enabled no)
				(sheetname "")
			)
			(fill
				(thermal_gap 0.5)
				(thermal_bridge_width 0.5)
				(island_removal_mode 0)
			)
			(polygon
				(pts
					(arc
						(start 89.81948 -215.111076)
						(mid 89.783666 -215.096241)
						(end 89.747852 -215.111076)
					)
					(arc
						(start 89.747852 -215.111076)
						(mid 89.736501 -215.128198)
						(end 89.732866 -215.148414)
					)
					(arc
						(start 89.732866 -215.148414)
						(mid 89.753015 -215.265615)
						(end 89.81821 -215.365076)
					)
					(arc
						(start 89.81821 -215.365076)
						(mid 90.024712 -215.450612)
						(end 90.231214 -215.365076)
					)
					(arc
						(start 90.231214 -215.365076)
						(mid 90.296096 -215.266832)
						(end 90.316812 -215.150954)
					)
					(arc
						(start 90.316812 -215.150954)
						(mid 90.313624 -215.129932)
						(end 90.30208 -215.112092)
					)
					(arc
						(start 90.30208 -215.112092)
						(mid 90.266177 -215.097257)
						(end 90.230198 -215.112092)
					)
					(arc
						(start 90.230198 -215.112092)
						(mid 90.221475 -215.123788)
						(end 90.216482 -215.137492)
					)
					(xy 90.216482 -215.15832) (xy 90.216482 -215.158828)
					(arc
						(start 90.216482 -215.159844)
						(mid 90.20148 -215.232442)
						(end 90.160094 -215.293956)
					)
					(arc
						(start 90.160094 -215.293956)
						(mid 90.024712 -215.350033)
						(end 89.88933 -215.293956)
					)
					(arc
						(start 89.88933 -215.293956)
						(mid 89.84773 -215.231608)
						(end 89.833196 -215.158066)
					)
					(xy 89.83345 -215.157304)
					(arc
						(start 89.83345 -215.13673)
						(mid 89.82836 -215.122868)
						(end 89.81948 -215.111076)
					)
				)
			)
		)
		(zone
			(layer "F.Cu")
			(hatch none 0.5)
			(connect_pads
				(clearance 0)
			)
			(min_thickness 0.25)
			(keepout
				(tracks not_allowed)
				(vias allowed)
				(pads allowed)
				(copperpour not_allowed)
				(footprints allowed)
			)
			(placement
				(enabled no)
				(sheetname "")
			)
			(fill
				(thermal_gap 0.5)
				(thermal_bridge_width 0.5)
				(island_removal_mode 0)
			)
			(polygon
				(pts
					(arc
						(start 89.870026 -288.428684)
						(mid 89.906004 -288.443698)
						(end 89.941908 -288.428684)
					)
					(arc
						(start 89.941908 -288.428684)
						(mid 89.953259 -288.411562)
						(end 89.956894 -288.391346)
					)
					(arc
						(start 89.956894 -288.391346)
						(mid 89.936625 -288.274117)
						(end 89.871296 -288.174684)
					)
					(arc
						(start 89.871296 -288.174684)
						(mid 89.664794 -288.089148)
						(end 89.458292 -288.174684)
					)
					(arc
						(start 89.458292 -288.174684)
						(mid 89.393551 -288.272959)
						(end 89.372948 -288.388806)
					)
					(arc
						(start 89.372948 -288.388806)
						(mid 89.376148 -288.409815)
						(end 89.38768 -288.427668)
					)
					(arc
						(start 89.38768 -288.427668)
						(mid 89.423658 -288.442682)
						(end 89.459562 -288.427668)
					)
					(arc
						(start 89.459562 -288.427668)
						(mid 89.468285 -288.415972)
						(end 89.473278 -288.402268)
					)
					(xy 89.473278 -288.38144) (xy 89.473278 -288.380932)
					(arc
						(start 89.473278 -288.379916)
						(mid 89.488163 -288.307347)
						(end 89.529412 -288.245804)
					)
					(arc
						(start 89.529412 -288.245804)
						(mid 89.664794 -288.189727)
						(end 89.800176 -288.245804)
					)
					(arc
						(start 89.800176 -288.245804)
						(mid 89.841776 -288.308152)
						(end 89.85631 -288.381694)
					)
					(xy 89.856056 -288.382456)
					(arc
						(start 89.856056 -288.40303)
						(mid 89.861146 -288.416892)
						(end 89.870026 -288.428684)
					)
				)
			)
		)
		(zone
			(layer "F.Cu")
			(hatch none 0.5)
			(connect_pads
				(clearance 0)
			)
			(min_thickness 0.25)
			(keepout
				(tracks not_allowed)
				(vias allowed)
				(pads allowed)
				(copperpour not_allowed)
				(footprints allowed)
			)
			(placement
				(enabled no)
				(sheetname "")
			)
			(fill
				(thermal_gap 0.5)
				(thermal_bridge_width 0.5)
				(island_removal_mode 0)
			)
			(polygon
				(pts
					(arc
						(start 90.289634 -214.297006)
						(mid 90.25373 -214.282246)
						(end 90.217752 -214.297006)
					)
					(arc
						(start 90.217752 -214.297006)
						(mid 90.206353 -214.314246)
						(end 90.202766 -214.334598)
					)
					(arc
						(start 90.202766 -214.334598)
						(mid 90.223035 -214.451827)
						(end 90.288364 -214.55126)
					)
					(arc
						(start 90.288364 -214.55126)
						(mid 90.494866 -214.636796)
						(end 90.701368 -214.55126)
					)
					(arc
						(start 90.701368 -214.55126)
						(mid 90.766157 -214.452867)
						(end 90.786712 -214.336884)
					)
					(arc
						(start 90.786712 -214.336884)
						(mid 90.783512 -214.315875)
						(end 90.77198 -214.298022)
					)
					(arc
						(start 90.77198 -214.298022)
						(mid 90.736076 -214.283262)
						(end 90.700098 -214.298022)
					)
					(arc
						(start 90.700098 -214.298022)
						(mid 90.691356 -214.309843)
						(end 90.686382 -214.323676)
					)
					(xy 90.686382 -214.344504) (xy 90.686382 -214.344758)
					(arc
						(start 90.686382 -214.345774)
						(mid 90.671544 -214.418479)
						(end 90.630248 -214.48014)
					)
					(arc
						(start 90.630248 -214.48014)
						(mid 90.494866 -214.536217)
						(end 90.359484 -214.48014)
					)
					(arc
						(start 90.359484 -214.48014)
						(mid 90.317835 -214.417674)
						(end 90.30335 -214.343996)
					)
					(xy 90.303604 -214.343488)
					(arc
						(start 90.303604 -214.322914)
						(mid 90.298548 -214.308916)
						(end 90.289634 -214.297006)
					)
				)
			)
		)
		(zone
			(layer "F.Cu")
			(hatch none 0.5)
			(connect_pads
				(clearance 0)
			)
			(min_thickness 0.25)
			(keepout
				(tracks not_allowed)
				(vias allowed)
				(pads allowed)
				(copperpour not_allowed)
				(footprints allowed)
			)
			(placement
				(enabled no)
				(sheetname "")
			)
			(fill
				(thermal_gap 0.5)
				(thermal_bridge_width 0.5)
				(island_removal_mode 0)
			)
			(polygon
				(pts
					(arc
						(start 90.81008 -288.428684)
						(mid 90.845894 -288.443519)
						(end 90.881708 -288.428684)
					)
					(arc
						(start 90.881708 -288.428684)
						(mid 90.893059 -288.411562)
						(end 90.896694 -288.391346)
					)
					(arc
						(start 90.896694 -288.391346)
						(mid 90.876545 -288.274145)
						(end 90.81135 -288.174684)
					)
					(arc
						(start 90.81135 -288.174684)
						(mid 90.604848 -288.089148)
						(end 90.398346 -288.174684)
					)
					(arc
						(start 90.398346 -288.174684)
						(mid 90.333464 -288.272928)
						(end 90.312748 -288.388806)
					)
					(arc
						(start 90.312748 -288.388806)
						(mid 90.315936 -288.409828)
						(end 90.32748 -288.427668)
					)
					(arc
						(start 90.32748 -288.427668)
						(mid 90.363458 -288.442682)
						(end 90.399362 -288.427668)
					)
					(arc
						(start 90.399362 -288.427668)
						(mid 90.408085 -288.415972)
						(end 90.413078 -288.402268)
					)
					(xy 90.413078 -288.38144) (xy 90.413078 -288.380932)
					(arc
						(start 90.413078 -288.379916)
						(mid 90.42808 -288.307318)
						(end 90.469466 -288.245804)
					)
					(arc
						(start 90.469466 -288.245804)
						(mid 90.604848 -288.189727)
						(end 90.74023 -288.245804)
					)
					(arc
						(start 90.74023 -288.245804)
						(mid 90.78183 -288.308152)
						(end 90.796364 -288.381694)
					)
					(xy 90.79611 -288.382456)
					(arc
						(start 90.79611 -288.40303)
						(mid 90.8012 -288.416892)
						(end 90.81008 -288.428684)
					)
				)
			)
		)
		(zone
			(layer "F.Cu")
			(hatch none 0.5)
			(connect_pads
				(clearance 0)
			)
			(min_thickness 0.25)
			(keepout
				(tracks not_allowed)
				(vias allowed)
				(pads allowed)
				(copperpour not_allowed)
				(footprints allowed)
			)
			(placement
				(enabled no)
				(sheetname "")
			)
			(fill
				(thermal_gap 0.5)
				(thermal_bridge_width 0.5)
				(island_removal_mode 0)
			)
			(polygon
				(pts
					(arc
						(start 91.229434 -214.297006)
						(mid 91.19353 -214.282246)
						(end 91.157552 -214.297006)
					)
					(arc
						(start 91.157552 -214.297006)
						(mid 91.146153 -214.314246)
						(end 91.142566 -214.334598)
					)
					(arc
						(start 91.142566 -214.334598)
						(mid 91.162835 -214.451827)
						(end 91.228164 -214.55126)
					)
					(arc
						(start 91.228164 -214.55126)
						(mid 91.434666 -214.636796)
						(end 91.641168 -214.55126)
					)
					(arc
						(start 91.641168 -214.55126)
						(mid 91.705957 -214.452867)
						(end 91.726512 -214.336884)
					)
					(arc
						(start 91.726512 -214.336884)
						(mid 91.723312 -214.315875)
						(end 91.71178 -214.298022)
					)
					(arc
						(start 91.71178 -214.298022)
						(mid 91.675876 -214.283262)
						(end 91.639898 -214.298022)
					)
					(arc
						(start 91.639898 -214.298022)
						(mid 91.631156 -214.309843)
						(end 91.626182 -214.323676)
					)
					(xy 91.626182 -214.344504) (xy 91.626182 -214.344758)
					(arc
						(start 91.626182 -214.345774)
						(mid 91.611344 -214.418479)
						(end 91.570048 -214.48014)
					)
					(arc
						(start 91.570048 -214.48014)
						(mid 91.434666 -214.536217)
						(end 91.299284 -214.48014)
					)
					(arc
						(start 91.299284 -214.48014)
						(mid 91.257635 -214.417674)
						(end 91.24315 -214.343996)
					)
					(xy 91.243404 -214.343488)
					(arc
						(start 91.243404 -214.322914)
						(mid 91.238348 -214.308916)
						(end 91.229434 -214.297006)
					)
				)
			)
		)
		(zone
			(layer "F.Cu")
			(hatch none 0.5)
			(connect_pads
				(clearance 0)
			)
			(min_thickness 0.25)
			(keepout
				(tracks not_allowed)
				(vias allowed)
				(pads allowed)
				(copperpour not_allowed)
				(footprints allowed)
			)
			(placement
				(enabled no)
				(sheetname "")
			)
			(fill
				(thermal_gap 0.5)
				(thermal_bridge_width 0.5)
				(island_removal_mode 0)
			)
			(polygon
				(pts
					(arc
						(start 91.279726 -289.242754)
						(mid 91.315704 -289.257694)
						(end 91.351608 -289.242754)
					)
					(arc
						(start 91.351608 -289.242754)
						(mid 91.363007 -289.225514)
						(end 91.366594 -289.205162)
					)
					(arc
						(start 91.366594 -289.205162)
						(mid 91.346325 -289.087933)
						(end 91.280996 -288.9885)
					)
					(arc
						(start 91.280996 -288.9885)
						(mid 91.074494 -288.902964)
						(end 90.867992 -288.9885)
					)
					(arc
						(start 90.867992 -288.9885)
						(mid 90.803203 -289.086893)
						(end 90.782648 -289.202876)
					)
					(arc
						(start 90.782648 -289.202876)
						(mid 90.785848 -289.223885)
						(end 90.79738 -289.241738)
					)
					(arc
						(start 90.79738 -289.241738)
						(mid 90.833358 -289.256678)
						(end 90.869262 -289.241738)
					)
					(arc
						(start 90.869262 -289.241738)
						(mid 90.878004 -289.229917)
						(end 90.882978 -289.216084)
					)
					(xy 90.882978 -289.195256) (xy 90.882978 -289.195002)
					(arc
						(start 90.882978 -289.193986)
						(mid 90.897816 -289.121281)
						(end 90.939112 -289.05962)
					)
					(arc
						(start 90.939112 -289.05962)
						(mid 91.074494 -289.003543)
						(end 91.209876 -289.05962)
					)
					(arc
						(start 91.209876 -289.05962)
						(mid 91.251525 -289.122086)
						(end 91.26601 -289.195764)
					)
					(xy 91.265756 -289.196272)
					(arc
						(start 91.265756 -289.216846)
						(mid 91.270812 -289.230844)
						(end 91.279726 -289.242754)
					)
				)
			)
		)
		(zone
			(layer "F.Cu")
			(hatch none 0.5)
			(connect_pads
				(clearance 0)
			)
			(min_thickness 0.25)
			(keepout
				(tracks not_allowed)
				(vias allowed)
				(pads allowed)
				(copperpour not_allowed)
				(footprints allowed)
			)
			(placement
				(enabled no)
				(sheetname "")
			)
			(fill
				(thermal_gap 0.5)
				(thermal_bridge_width 0.5)
				(island_removal_mode 0)
			)
			(polygon
				(pts
					(arc
						(start 92.169234 -214.297006)
						(mid 92.13333 -214.282246)
						(end 92.097352 -214.297006)
					)
					(arc
						(start 92.097352 -214.297006)
						(mid 92.085953 -214.314246)
						(end 92.082366 -214.334598)
					)
					(arc
						(start 92.082366 -214.334598)
						(mid 92.102635 -214.451827)
						(end 92.167964 -214.55126)
					)
					(arc
						(start 92.167964 -214.55126)
						(mid 92.374466 -214.636796)
						(end 92.580968 -214.55126)
					)
					(arc
						(start 92.580968 -214.55126)
						(mid 92.645757 -214.452867)
						(end 92.666312 -214.336884)
					)
					(arc
						(start 92.666312 -214.336884)
						(mid 92.663112 -214.315875)
						(end 92.65158 -214.298022)
					)
					(arc
						(start 92.65158 -214.298022)
						(mid 92.615676 -214.283262)
						(end 92.579698 -214.298022)
					)
					(arc
						(start 92.579698 -214.298022)
						(mid 92.570956 -214.309843)
						(end 92.565982 -214.323676)
					)
					(xy 92.565982 -214.344504) (xy 92.565982 -214.344758)
					(arc
						(start 92.565982 -214.345774)
						(mid 92.551144 -214.418479)
						(end 92.509848 -214.48014)
					)
					(arc
						(start 92.509848 -214.48014)
						(mid 92.374466 -214.536217)
						(end 92.239084 -214.48014)
					)
					(arc
						(start 92.239084 -214.48014)
						(mid 92.197435 -214.417674)
						(end 92.18295 -214.343996)
					)
					(xy 92.183204 -214.343488)
					(arc
						(start 92.183204 -214.322914)
						(mid 92.178148 -214.308916)
						(end 92.169234 -214.297006)
					)
				)
			)
		)
		(zone
			(layer "F.Cu")
			(hatch none 0.5)
			(connect_pads
				(clearance 0)
			)
			(min_thickness 0.25)
			(keepout
				(tracks not_allowed)
				(vias allowed)
				(pads allowed)
				(copperpour not_allowed)
				(footprints allowed)
			)
			(placement
				(enabled no)
				(sheetname "")
			)
			(fill
				(thermal_gap 0.5)
				(thermal_bridge_width 0.5)
				(island_removal_mode 0)
			)
			(polygon
				(pts
					(arc
						(start 92.219526 -289.242754)
						(mid 92.255504 -289.257694)
						(end 92.291408 -289.242754)
					)
					(arc
						(start 92.291408 -289.242754)
						(mid 92.302807 -289.225514)
						(end 92.306394 -289.205162)
					)
					(arc
						(start 92.306394 -289.205162)
						(mid 92.286125 -289.087933)
						(end 92.220796 -288.9885)
					)
					(arc
						(start 92.220796 -288.9885)
						(mid 92.014294 -288.902964)
						(end 91.807792 -288.9885)
					)
					(arc
						(start 91.807792 -288.9885)
						(mid 91.743003 -289.086893)
						(end 91.722448 -289.202876)
					)
					(arc
						(start 91.722448 -289.202876)
						(mid 91.725648 -289.223885)
						(end 91.73718 -289.241738)
					)
					(arc
						(start 91.73718 -289.241738)
						(mid 91.773158 -289.256678)
						(end 91.809062 -289.241738)
					)
					(arc
						(start 91.809062 -289.241738)
						(mid 91.817804 -289.229917)
						(end 91.822778 -289.216084)
					)
					(xy 91.822778 -289.195256) (xy 91.822778 -289.195002)
					(arc
						(start 91.822778 -289.193986)
						(mid 91.837616 -289.121281)
						(end 91.878912 -289.05962)
					)
					(arc
						(start 91.878912 -289.05962)
						(mid 92.014294 -289.003543)
						(end 92.149676 -289.05962)
					)
					(arc
						(start 92.149676 -289.05962)
						(mid 92.191325 -289.122086)
						(end 92.20581 -289.195764)
					)
					(xy 92.205556 -289.196272)
					(arc
						(start 92.205556 -289.216846)
						(mid 92.210612 -289.230844)
						(end 92.219526 -289.242754)
					)
				)
			)
		)
		(zone
			(layer "F.Cu")
			(hatch none 0.5)
			(connect_pads
				(clearance 0)
			)
			(min_thickness 0.25)
			(keepout
				(tracks not_allowed)
				(vias allowed)
				(pads allowed)
				(copperpour not_allowed)
				(footprints allowed)
			)
			(placement
				(enabled no)
				(sheetname "")
			)
			(fill
				(thermal_gap 0.5)
				(thermal_bridge_width 0.5)
				(island_removal_mode 0)
			)
			(polygon
				(pts
					(arc
						(start 93.109034 -214.297006)
						(mid 93.07313 -214.282246)
						(end 93.037152 -214.297006)
					)
					(arc
						(start 93.037152 -214.297006)
						(mid 93.025753 -214.314246)
						(end 93.022166 -214.334598)
					)
					(arc
						(start 93.022166 -214.334598)
						(mid 93.042435 -214.451827)
						(end 93.107764 -214.55126)
					)
					(arc
						(start 93.107764 -214.55126)
						(mid 93.314266 -214.636796)
						(end 93.520768 -214.55126)
					)
					(arc
						(start 93.520768 -214.55126)
						(mid 93.585557 -214.452867)
						(end 93.606112 -214.336884)
					)
					(arc
						(start 93.606112 -214.336884)
						(mid 93.602912 -214.315875)
						(end 93.59138 -214.298022)
					)
					(arc
						(start 93.59138 -214.298022)
						(mid 93.555476 -214.283262)
						(end 93.519498 -214.298022)
					)
					(arc
						(start 93.519498 -214.298022)
						(mid 93.510756 -214.309843)
						(end 93.505782 -214.323676)
					)
					(xy 93.505782 -214.344504) (xy 93.505782 -214.344758)
					(arc
						(start 93.505782 -214.345774)
						(mid 93.490944 -214.418479)
						(end 93.449648 -214.48014)
					)
					(arc
						(start 93.449648 -214.48014)
						(mid 93.314266 -214.536217)
						(end 93.178884 -214.48014)
					)
					(arc
						(start 93.178884 -214.48014)
						(mid 93.137235 -214.417674)
						(end 93.12275 -214.343996)
					)
					(xy 93.123004 -214.343488)
					(arc
						(start 93.123004 -214.322914)
						(mid 93.117948 -214.308916)
						(end 93.109034 -214.297006)
					)
				)
			)
		)
		(zone
			(layer "F.Cu")
			(hatch none 0.5)
			(connect_pads
				(clearance 0)
			)
			(min_thickness 0.25)
			(keepout
				(tracks not_allowed)
				(vias allowed)
				(pads allowed)
				(copperpour not_allowed)
				(footprints allowed)
			)
			(placement
				(enabled no)
				(sheetname "")
			)
			(fill
				(thermal_gap 0.5)
				(thermal_bridge_width 0.5)
				(island_removal_mode 0)
			)
			(polygon
				(pts
					(arc
						(start 93.159326 -289.242754)
						(mid 93.195304 -289.257694)
						(end 93.231208 -289.242754)
					)
					(arc
						(start 93.231208 -289.242754)
						(mid 93.242607 -289.225514)
						(end 93.246194 -289.205162)
					)
					(arc
						(start 93.246194 -289.205162)
						(mid 93.225925 -289.087933)
						(end 93.160596 -288.9885)
					)
					(arc
						(start 93.160596 -288.9885)
						(mid 92.954094 -288.902964)
						(end 92.747592 -288.9885)
					)
					(arc
						(start 92.747592 -288.9885)
						(mid 92.682803 -289.086893)
						(end 92.662248 -289.202876)
					)
					(arc
						(start 92.662248 -289.202876)
						(mid 92.665448 -289.223885)
						(end 92.67698 -289.241738)
					)
					(arc
						(start 92.67698 -289.241738)
						(mid 92.712958 -289.256678)
						(end 92.748862 -289.241738)
					)
					(arc
						(start 92.748862 -289.241738)
						(mid 92.757604 -289.229917)
						(end 92.762578 -289.216084)
					)
					(xy 92.762578 -289.195256) (xy 92.762578 -289.195002)
					(arc
						(start 92.762578 -289.193986)
						(mid 92.777416 -289.121281)
						(end 92.818712 -289.05962)
					)
					(arc
						(start 92.818712 -289.05962)
						(mid 92.954094 -289.003543)
						(end 93.089476 -289.05962)
					)
					(arc
						(start 93.089476 -289.05962)
						(mid 93.131125 -289.122086)
						(end 93.14561 -289.195764)
					)
					(xy 93.145356 -289.196272)
					(arc
						(start 93.145356 -289.216846)
						(mid 93.150412 -289.230844)
						(end 93.159326 -289.242754)
					)
				)
			)
		)
		(zone
			(layer "F.Cu")
			(hatch none 0.5)
			(connect_pads
				(clearance 0)
			)
			(min_thickness 0.25)
			(keepout
				(tracks not_allowed)
				(vias allowed)
				(pads allowed)
				(copperpour not_allowed)
				(footprints allowed)
			)
			(placement
				(enabled no)
				(sheetname "")
			)
			(fill
				(thermal_gap 0.5)
				(thermal_bridge_width 0.5)
				(island_removal_mode 0)
			)
			(polygon
				(pts
					(arc
						(start 94.048834 -214.297006)
						(mid 94.01293 -214.282246)
						(end 93.976952 -214.297006)
					)
					(arc
						(start 93.976952 -214.297006)
						(mid 93.965553 -214.314246)
						(end 93.961966 -214.334598)
					)
					(arc
						(start 93.961966 -214.334598)
						(mid 93.982235 -214.451827)
						(end 94.047564 -214.55126)
					)
					(arc
						(start 94.047564 -214.55126)
						(mid 94.254066 -214.636796)
						(end 94.460568 -214.55126)
					)
					(arc
						(start 94.460568 -214.55126)
						(mid 94.525357 -214.452867)
						(end 94.545912 -214.336884)
					)
					(arc
						(start 94.545912 -214.336884)
						(mid 94.542712 -214.315875)
						(end 94.53118 -214.298022)
					)
					(arc
						(start 94.53118 -214.298022)
						(mid 94.495276 -214.283262)
						(end 94.459298 -214.298022)
					)
					(arc
						(start 94.459298 -214.298022)
						(mid 94.450556 -214.309843)
						(end 94.445582 -214.323676)
					)
					(xy 94.445582 -214.344504) (xy 94.445582 -214.344758)
					(arc
						(start 94.445582 -214.345774)
						(mid 94.430744 -214.418479)
						(end 94.389448 -214.48014)
					)
					(arc
						(start 94.389448 -214.48014)
						(mid 94.254066 -214.536217)
						(end 94.118684 -214.48014)
					)
					(arc
						(start 94.118684 -214.48014)
						(mid 94.077035 -214.417674)
						(end 94.06255 -214.343996)
					)
					(xy 94.062804 -214.343488)
					(arc
						(start 94.062804 -214.322914)
						(mid 94.057748 -214.308916)
						(end 94.048834 -214.297006)
					)
				)
			)
		)
		(zone
			(layer "F.Cu")
			(hatch none 0.5)
			(connect_pads
				(clearance 0)
			)
			(min_thickness 0.25)
			(keepout
				(tracks not_allowed)
				(vias allowed)
				(pads allowed)
				(copperpour not_allowed)
				(footprints allowed)
			)
			(placement
				(enabled no)
				(sheetname "")
			)
			(fill
				(thermal_gap 0.5)
				(thermal_bridge_width 0.5)
				(island_removal_mode 0)
			)
			(polygon
				(pts
					(arc
						(start 94.099126 -289.242754)
						(mid 94.135104 -289.257694)
						(end 94.171008 -289.242754)
					)
					(arc
						(start 94.171008 -289.242754)
						(mid 94.182407 -289.225514)
						(end 94.185994 -289.205162)
					)
					(arc
						(start 94.185994 -289.205162)
						(mid 94.165725 -289.087933)
						(end 94.100396 -288.9885)
					)
					(arc
						(start 94.100396 -288.9885)
						(mid 93.893894 -288.902964)
						(end 93.687392 -288.9885)
					)
					(arc
						(start 93.687392 -288.9885)
						(mid 93.622603 -289.086893)
						(end 93.602048 -289.202876)
					)
					(arc
						(start 93.602048 -289.202876)
						(mid 93.605248 -289.223885)
						(end 93.61678 -289.241738)
					)
					(arc
						(start 93.61678 -289.241738)
						(mid 93.652758 -289.256678)
						(end 93.688662 -289.241738)
					)
					(arc
						(start 93.688662 -289.241738)
						(mid 93.697404 -289.229917)
						(end 93.702378 -289.216084)
					)
					(xy 93.702378 -289.195256) (xy 93.702378 -289.195002)
					(arc
						(start 93.702378 -289.193986)
						(mid 93.717216 -289.121281)
						(end 93.758512 -289.05962)
					)
					(arc
						(start 93.758512 -289.05962)
						(mid 93.893894 -289.003543)
						(end 94.029276 -289.05962)
					)
					(arc
						(start 94.029276 -289.05962)
						(mid 94.070925 -289.122086)
						(end 94.08541 -289.195764)
					)
					(xy 94.085156 -289.196272)
					(arc
						(start 94.085156 -289.216846)
						(mid 94.090212 -289.230844)
						(end 94.099126 -289.242754)
					)
				)
			)
		)
		(zone
			(layer "F.Cu")
			(hatch none 0.5)
			(connect_pads
				(clearance 0)
			)
			(min_thickness 0.25)
			(keepout
				(tracks not_allowed)
				(vias allowed)
				(pads allowed)
				(copperpour not_allowed)
				(footprints allowed)
			)
			(placement
				(enabled no)
				(sheetname "")
			)
			(fill
				(thermal_gap 0.5)
				(thermal_bridge_width 0.5)
				(island_removal_mode 0)
			)
			(polygon
				(pts
					(arc
						(start 94.988634 -214.297006)
						(mid 94.95273 -214.282246)
						(end 94.916752 -214.297006)
					)
					(arc
						(start 94.916752 -214.297006)
						(mid 94.905353 -214.314246)
						(end 94.901766 -214.334598)
					)
					(arc
						(start 94.901766 -214.334598)
						(mid 94.922035 -214.451827)
						(end 94.987364 -214.55126)
					)
					(arc
						(start 94.987364 -214.55126)
						(mid 95.193866 -214.636796)
						(end 95.400368 -214.55126)
					)
					(arc
						(start 95.400368 -214.55126)
						(mid 95.465157 -214.452867)
						(end 95.485712 -214.336884)
					)
					(arc
						(start 95.485712 -214.336884)
						(mid 95.482512 -214.315875)
						(end 95.47098 -214.298022)
					)
					(arc
						(start 95.47098 -214.298022)
						(mid 95.435076 -214.283262)
						(end 95.399098 -214.298022)
					)
					(arc
						(start 95.399098 -214.298022)
						(mid 95.390356 -214.309843)
						(end 95.385382 -214.323676)
					)
					(xy 95.385382 -214.344504) (xy 95.385382 -214.344758)
					(arc
						(start 95.385382 -214.345774)
						(mid 95.370544 -214.418479)
						(end 95.329248 -214.48014)
					)
					(arc
						(start 95.329248 -214.48014)
						(mid 95.193866 -214.536217)
						(end 95.058484 -214.48014)
					)
					(arc
						(start 95.058484 -214.48014)
						(mid 95.016835 -214.417674)
						(end 95.00235 -214.343996)
					)
					(xy 95.002604 -214.343488)
					(arc
						(start 95.002604 -214.322914)
						(mid 94.997548 -214.308916)
						(end 94.988634 -214.297006)
					)
				)
			)
		)
		(zone
			(layer "F.Cu")
			(hatch none 0.5)
			(connect_pads
				(clearance 0)
			)
			(min_thickness 0.25)
			(keepout
				(tracks not_allowed)
				(vias allowed)
				(pads allowed)
				(copperpour not_allowed)
				(footprints allowed)
			)
			(placement
				(enabled no)
				(sheetname "")
			)
			(fill
				(thermal_gap 0.5)
				(thermal_bridge_width 0.5)
				(island_removal_mode 0)
			)
			(polygon
				(pts
					(arc
						(start 95.038926 -289.242754)
						(mid 95.074904 -289.257694)
						(end 95.110808 -289.242754)
					)
					(arc
						(start 95.110808 -289.242754)
						(mid 95.122207 -289.225514)
						(end 95.125794 -289.205162)
					)
					(arc
						(start 95.125794 -289.205162)
						(mid 95.105525 -289.087933)
						(end 95.040196 -288.9885)
					)
					(arc
						(start 95.040196 -288.9885)
						(mid 94.833694 -288.902964)
						(end 94.627192 -288.9885)
					)
					(arc
						(start 94.627192 -288.9885)
						(mid 94.562403 -289.086893)
						(end 94.541848 -289.202876)
					)
					(arc
						(start 94.541848 -289.202876)
						(mid 94.545048 -289.223885)
						(end 94.55658 -289.241738)
					)
					(arc
						(start 94.55658 -289.241738)
						(mid 94.592558 -289.256678)
						(end 94.628462 -289.241738)
					)
					(arc
						(start 94.628462 -289.241738)
						(mid 94.637204 -289.229917)
						(end 94.642178 -289.216084)
					)
					(xy 94.642178 -289.195256) (xy 94.642178 -289.195002)
					(arc
						(start 94.642178 -289.193986)
						(mid 94.657016 -289.121281)
						(end 94.698312 -289.05962)
					)
					(arc
						(start 94.698312 -289.05962)
						(mid 94.833694 -289.003543)
						(end 94.969076 -289.05962)
					)
					(arc
						(start 94.969076 -289.05962)
						(mid 95.010725 -289.122086)
						(end 95.02521 -289.195764)
					)
					(xy 95.024956 -289.196272)
					(arc
						(start 95.024956 -289.216846)
						(mid 95.030012 -289.230844)
						(end 95.038926 -289.242754)
					)
				)
			)
		)
		(zone
			(layer "F.Cu")
			(hatch none 0.5)
			(connect_pads
				(clearance 0)
			)
			(min_thickness 0.25)
			(keepout
				(tracks not_allowed)
				(vias allowed)
				(pads allowed)
				(copperpour not_allowed)
				(footprints allowed)
			)
			(placement
				(enabled no)
				(sheetname "")
			)
			(fill
				(thermal_gap 0.5)
				(thermal_bridge_width 0.5)
				(island_removal_mode 0)
			)
			(polygon
				(pts
					(arc
						(start 95.928434 -214.297006)
						(mid 95.89253 -214.282246)
						(end 95.856552 -214.297006)
					)
					(arc
						(start 95.856552 -214.297006)
						(mid 95.845153 -214.314246)
						(end 95.841566 -214.334598)
					)
					(arc
						(start 95.841566 -214.334598)
						(mid 95.861835 -214.451827)
						(end 95.927164 -214.55126)
					)
					(arc
						(start 95.927164 -214.55126)
						(mid 96.133666 -214.636796)
						(end 96.340168 -214.55126)
					)
					(arc
						(start 96.340168 -214.55126)
						(mid 96.404957 -214.452867)
						(end 96.425512 -214.336884)
					)
					(arc
						(start 96.425512 -214.336884)
						(mid 96.422312 -214.315875)
						(end 96.41078 -214.298022)
					)
					(arc
						(start 96.41078 -214.298022)
						(mid 96.374876 -214.283262)
						(end 96.338898 -214.298022)
					)
					(arc
						(start 96.338898 -214.298022)
						(mid 96.330156 -214.309843)
						(end 96.325182 -214.323676)
					)
					(xy 96.325182 -214.344504) (xy 96.325182 -214.344758)
					(arc
						(start 96.325182 -214.345774)
						(mid 96.310344 -214.418479)
						(end 96.269048 -214.48014)
					)
					(arc
						(start 96.269048 -214.48014)
						(mid 96.133666 -214.536217)
						(end 95.998284 -214.48014)
					)
					(arc
						(start 95.998284 -214.48014)
						(mid 95.956635 -214.417674)
						(end 95.94215 -214.343996)
					)
					(xy 95.942404 -214.343488)
					(arc
						(start 95.942404 -214.322914)
						(mid 95.937348 -214.308916)
						(end 95.928434 -214.297006)
					)
				)
			)
		)
		(zone
			(layer "F.Cu")
			(hatch none 0.5)
			(connect_pads
				(clearance 0)
			)
			(min_thickness 0.25)
			(keepout
				(tracks not_allowed)
				(vias allowed)
				(pads allowed)
				(copperpour not_allowed)
				(footprints allowed)
			)
			(placement
				(enabled no)
				(sheetname "")
			)
			(fill
				(thermal_gap 0.5)
				(thermal_bridge_width 0.5)
				(island_removal_mode 0)
			)
			(polygon
				(pts
					(arc
						(start 95.978726 -289.242754)
						(mid 96.014704 -289.257694)
						(end 96.050608 -289.242754)
					)
					(arc
						(start 96.050608 -289.242754)
						(mid 96.062007 -289.225514)
						(end 96.065594 -289.205162)
					)
					(arc
						(start 96.065594 -289.205162)
						(mid 96.045325 -289.087933)
						(end 95.979996 -288.9885)
					)
					(arc
						(start 95.979996 -288.9885)
						(mid 95.773494 -288.902964)
						(end 95.566992 -288.9885)
					)
					(arc
						(start 95.566992 -288.9885)
						(mid 95.502203 -289.086893)
						(end 95.481648 -289.202876)
					)
					(arc
						(start 95.481648 -289.202876)
						(mid 95.484848 -289.223885)
						(end 95.49638 -289.241738)
					)
					(arc
						(start 95.49638 -289.241738)
						(mid 95.532358 -289.256678)
						(end 95.568262 -289.241738)
					)
					(arc
						(start 95.568262 -289.241738)
						(mid 95.577004 -289.229917)
						(end 95.581978 -289.216084)
					)
					(xy 95.581978 -289.195256) (xy 95.581978 -289.195002)
					(arc
						(start 95.581978 -289.193986)
						(mid 95.596816 -289.121281)
						(end 95.638112 -289.05962)
					)
					(arc
						(start 95.638112 -289.05962)
						(mid 95.773494 -289.003543)
						(end 95.908876 -289.05962)
					)
					(arc
						(start 95.908876 -289.05962)
						(mid 95.950525 -289.122086)
						(end 95.96501 -289.195764)
					)
					(xy 95.964756 -289.196272)
					(arc
						(start 95.964756 -289.216846)
						(mid 95.969812 -289.230844)
						(end 95.978726 -289.242754)
					)
				)
			)
		)
		(zone
			(layer "F.Cu")
			(hatch none 0.5)
			(connect_pads
				(clearance 0)
			)
			(min_thickness 0.25)
			(keepout
				(tracks not_allowed)
				(vias allowed)
				(pads allowed)
				(copperpour not_allowed)
				(footprints allowed)
			)
			(placement
				(enabled no)
				(sheetname "")
			)
			(fill
				(thermal_gap 0.5)
				(thermal_bridge_width 0.5)
				(island_removal_mode 0)
			)
			(polygon
				(pts
					(arc
						(start 96.868234 -214.297006)
						(mid 96.83233 -214.282246)
						(end 96.796352 -214.297006)
					)
					(arc
						(start 96.796352 -214.297006)
						(mid 96.784953 -214.314246)
						(end 96.781366 -214.334598)
					)
					(arc
						(start 96.781366 -214.334598)
						(mid 96.801635 -214.451827)
						(end 96.866964 -214.55126)
					)
					(arc
						(start 96.866964 -214.55126)
						(mid 97.073466 -214.636796)
						(end 97.279968 -214.55126)
					)
					(arc
						(start 97.279968 -214.55126)
						(mid 97.344757 -214.452867)
						(end 97.365312 -214.336884)
					)
					(arc
						(start 97.365312 -214.336884)
						(mid 97.362112 -214.315875)
						(end 97.35058 -214.298022)
					)
					(arc
						(start 97.35058 -214.298022)
						(mid 97.314676 -214.283262)
						(end 97.278698 -214.298022)
					)
					(arc
						(start 97.278698 -214.298022)
						(mid 97.269956 -214.309843)
						(end 97.264982 -214.323676)
					)
					(xy 97.264982 -214.344504) (xy 97.264982 -214.344758)
					(arc
						(start 97.264982 -214.345774)
						(mid 97.250144 -214.418479)
						(end 97.208848 -214.48014)
					)
					(arc
						(start 97.208848 -214.48014)
						(mid 97.073466 -214.536217)
						(end 96.938084 -214.48014)
					)
					(arc
						(start 96.938084 -214.48014)
						(mid 96.896435 -214.417674)
						(end 96.88195 -214.343996)
					)
					(xy 96.882204 -214.343488)
					(arc
						(start 96.882204 -214.322914)
						(mid 96.877148 -214.308916)
						(end 96.868234 -214.297006)
					)
				)
			)
		)
		(zone
			(layer "F.Cu")
			(hatch none 0.5)
			(connect_pads
				(clearance 0)
			)
			(min_thickness 0.25)
			(keepout
				(tracks not_allowed)
				(vias allowed)
				(pads allowed)
				(copperpour not_allowed)
				(footprints allowed)
			)
			(placement
				(enabled no)
				(sheetname "")
			)
			(fill
				(thermal_gap 0.5)
				(thermal_bridge_width 0.5)
				(island_removal_mode 0)
			)
			(polygon
				(pts
					(arc
						(start 96.918526 -289.242754)
						(mid 96.954504 -289.257694)
						(end 96.990408 -289.242754)
					)
					(arc
						(start 96.990408 -289.242754)
						(mid 97.001807 -289.225514)
						(end 97.005394 -289.205162)
					)
					(arc
						(start 97.005394 -289.205162)
						(mid 96.985125 -289.087933)
						(end 96.919796 -288.9885)
					)
					(arc
						(start 96.919796 -288.9885)
						(mid 96.713294 -288.902964)
						(end 96.506792 -288.9885)
					)
					(arc
						(start 96.506792 -288.9885)
						(mid 96.442003 -289.086893)
						(end 96.421448 -289.202876)
					)
					(arc
						(start 96.421448 -289.202876)
						(mid 96.424648 -289.223885)
						(end 96.43618 -289.241738)
					)
					(arc
						(start 96.43618 -289.241738)
						(mid 96.472158 -289.256678)
						(end 96.508062 -289.241738)
					)
					(arc
						(start 96.508062 -289.241738)
						(mid 96.516804 -289.229917)
						(end 96.521778 -289.216084)
					)
					(xy 96.521778 -289.195256) (xy 96.521778 -289.195002)
					(arc
						(start 96.521778 -289.193986)
						(mid 96.536616 -289.121281)
						(end 96.577912 -289.05962)
					)
					(arc
						(start 96.577912 -289.05962)
						(mid 96.713294 -289.003543)
						(end 96.848676 -289.05962)
					)
					(arc
						(start 96.848676 -289.05962)
						(mid 96.890325 -289.122086)
						(end 96.90481 -289.195764)
					)
					(xy 96.904556 -289.196272)
					(arc
						(start 96.904556 -289.216846)
						(mid 96.909612 -289.230844)
						(end 96.918526 -289.242754)
					)
				)
			)
		)
		(zone
			(layer "F.Cu")
			(hatch none 0.5)
			(connect_pads
				(clearance 0)
			)
			(min_thickness 0.25)
			(keepout
				(tracks not_allowed)
				(vias allowed)
				(pads allowed)
				(copperpour not_allowed)
				(footprints allowed)
			)
			(placement
				(enabled no)
				(sheetname "")
			)
			(fill
				(thermal_gap 0.5)
				(thermal_bridge_width 0.5)
				(island_removal_mode 0)
			)
			(polygon
				(pts
					(arc
						(start 97.808034 -214.297006)
						(mid 97.77213 -214.282246)
						(end 97.736152 -214.297006)
					)
					(arc
						(start 97.736152 -214.297006)
						(mid 97.724753 -214.314246)
						(end 97.721166 -214.334598)
					)
					(arc
						(start 97.721166 -214.334598)
						(mid 97.741435 -214.451827)
						(end 97.806764 -214.55126)
					)
					(arc
						(start 97.806764 -214.55126)
						(mid 98.013266 -214.636796)
						(end 98.219768 -214.55126)
					)
					(arc
						(start 98.219768 -214.55126)
						(mid 98.284557 -214.452867)
						(end 98.305112 -214.336884)
					)
					(arc
						(start 98.305112 -214.336884)
						(mid 98.301912 -214.315875)
						(end 98.29038 -214.298022)
					)
					(arc
						(start 98.29038 -214.298022)
						(mid 98.254476 -214.283262)
						(end 98.218498 -214.298022)
					)
					(arc
						(start 98.218498 -214.298022)
						(mid 98.209756 -214.309843)
						(end 98.204782 -214.323676)
					)
					(xy 98.204782 -214.344504) (xy 98.204782 -214.344758)
					(arc
						(start 98.204782 -214.345774)
						(mid 98.189944 -214.418479)
						(end 98.148648 -214.48014)
					)
					(arc
						(start 98.148648 -214.48014)
						(mid 98.013266 -214.536217)
						(end 97.877884 -214.48014)
					)
					(arc
						(start 97.877884 -214.48014)
						(mid 97.836235 -214.417674)
						(end 97.82175 -214.343996)
					)
					(xy 97.822004 -214.343488)
					(arc
						(start 97.822004 -214.322914)
						(mid 97.816948 -214.308916)
						(end 97.808034 -214.297006)
					)
				)
			)
		)
		(zone
			(layer "F.Cu")
			(hatch none 0.5)
			(connect_pads
				(clearance 0)
			)
			(min_thickness 0.25)
			(keepout
				(tracks not_allowed)
				(vias allowed)
				(pads allowed)
				(copperpour not_allowed)
				(footprints allowed)
			)
			(placement
				(enabled no)
				(sheetname "")
			)
			(fill
				(thermal_gap 0.5)
				(thermal_bridge_width 0.5)
				(island_removal_mode 0)
			)
			(polygon
				(pts
					(arc
						(start 97.858326 -289.242754)
						(mid 97.894304 -289.257694)
						(end 97.930208 -289.242754)
					)
					(arc
						(start 97.930208 -289.242754)
						(mid 97.941607 -289.225514)
						(end 97.945194 -289.205162)
					)
					(arc
						(start 97.945194 -289.205162)
						(mid 97.924925 -289.087933)
						(end 97.859596 -288.9885)
					)
					(arc
						(start 97.859596 -288.9885)
						(mid 97.653094 -288.902964)
						(end 97.446592 -288.9885)
					)
					(arc
						(start 97.446592 -288.9885)
						(mid 97.381803 -289.086893)
						(end 97.361248 -289.202876)
					)
					(arc
						(start 97.361248 -289.202876)
						(mid 97.364448 -289.223885)
						(end 97.37598 -289.241738)
					)
					(arc
						(start 97.37598 -289.241738)
						(mid 97.411958 -289.256678)
						(end 97.447862 -289.241738)
					)
					(arc
						(start 97.447862 -289.241738)
						(mid 97.456604 -289.229917)
						(end 97.461578 -289.216084)
					)
					(xy 97.461578 -289.195256) (xy 97.461578 -289.195002)
					(arc
						(start 97.461578 -289.193986)
						(mid 97.476416 -289.121281)
						(end 97.517712 -289.05962)
					)
					(arc
						(start 97.517712 -289.05962)
						(mid 97.653094 -289.003543)
						(end 97.788476 -289.05962)
					)
					(arc
						(start 97.788476 -289.05962)
						(mid 97.830125 -289.122086)
						(end 97.84461 -289.195764)
					)
					(xy 97.844356 -289.196272)
					(arc
						(start 97.844356 -289.216846)
						(mid 97.849412 -289.230844)
						(end 97.858326 -289.242754)
					)
				)
			)
		)
		(zone
			(layer "F.Cu")
			(hatch none 0.5)
			(connect_pads
				(clearance 0)
			)
			(min_thickness 0.25)
			(keepout
				(tracks not_allowed)
				(vias allowed)
				(pads allowed)
				(copperpour not_allowed)
				(footprints allowed)
			)
			(placement
				(enabled no)
				(sheetname "")
			)
			(fill
				(thermal_gap 0.5)
				(thermal_bridge_width 0.5)
				(island_removal_mode 0)
			)
			(polygon
				(pts
					(arc
						(start 98.747834 -214.297006)
						(mid 98.71193 -214.282246)
						(end 98.675952 -214.297006)
					)
					(arc
						(start 98.675952 -214.297006)
						(mid 98.664553 -214.314246)
						(end 98.660966 -214.334598)
					)
					(arc
						(start 98.660966 -214.334598)
						(mid 98.681235 -214.451827)
						(end 98.746564 -214.55126)
					)
					(arc
						(start 98.746564 -214.55126)
						(mid 98.953066 -214.636796)
						(end 99.159568 -214.55126)
					)
					(arc
						(start 99.159568 -214.55126)
						(mid 99.224357 -214.452867)
						(end 99.244912 -214.336884)
					)
					(arc
						(start 99.244912 -214.336884)
						(mid 99.241712 -214.315875)
						(end 99.23018 -214.298022)
					)
					(arc
						(start 99.23018 -214.298022)
						(mid 99.194276 -214.283262)
						(end 99.158298 -214.298022)
					)
					(arc
						(start 99.158298 -214.298022)
						(mid 99.149556 -214.309843)
						(end 99.144582 -214.323676)
					)
					(xy 99.144582 -214.344504) (xy 99.144582 -214.344758)
					(arc
						(start 99.144582 -214.345774)
						(mid 99.129744 -214.418479)
						(end 99.088448 -214.48014)
					)
					(arc
						(start 99.088448 -214.48014)
						(mid 98.953066 -214.536217)
						(end 98.817684 -214.48014)
					)
					(arc
						(start 98.817684 -214.48014)
						(mid 98.776035 -214.417674)
						(end 98.76155 -214.343996)
					)
					(xy 98.761804 -214.343488)
					(arc
						(start 98.761804 -214.322914)
						(mid 98.756748 -214.308916)
						(end 98.747834 -214.297006)
					)
				)
			)
		)
		(zone
			(layer "F.Cu")
			(hatch none 0.5)
			(connect_pads
				(clearance 0)
			)
			(min_thickness 0.25)
			(keepout
				(tracks not_allowed)
				(vias allowed)
				(pads allowed)
				(copperpour not_allowed)
				(footprints allowed)
			)
			(placement
				(enabled no)
				(sheetname "")
			)
			(fill
				(thermal_gap 0.5)
				(thermal_bridge_width 0.5)
				(island_removal_mode 0)
			)
			(polygon
				(pts
					(arc
						(start 98.798126 -289.242754)
						(mid 98.834104 -289.257694)
						(end 98.870008 -289.242754)
					)
					(arc
						(start 98.870008 -289.242754)
						(mid 98.881407 -289.225514)
						(end 98.884994 -289.205162)
					)
					(arc
						(start 98.884994 -289.205162)
						(mid 98.864725 -289.087933)
						(end 98.799396 -288.9885)
					)
					(arc
						(start 98.799396 -288.9885)
						(mid 98.592894 -288.902964)
						(end 98.386392 -288.9885)
					)
					(arc
						(start 98.386392 -288.9885)
						(mid 98.321603 -289.086893)
						(end 98.301048 -289.202876)
					)
					(arc
						(start 98.301048 -289.202876)
						(mid 98.304248 -289.223885)
						(end 98.31578 -289.241738)
					)
					(arc
						(start 98.31578 -289.241738)
						(mid 98.351758 -289.256678)
						(end 98.387662 -289.241738)
					)
					(arc
						(start 98.387662 -289.241738)
						(mid 98.396404 -289.229917)
						(end 98.401378 -289.216084)
					)
					(xy 98.401378 -289.195256) (xy 98.401378 -289.195002)
					(arc
						(start 98.401378 -289.193986)
						(mid 98.416216 -289.121281)
						(end 98.457512 -289.05962)
					)
					(arc
						(start 98.457512 -289.05962)
						(mid 98.592894 -289.003543)
						(end 98.728276 -289.05962)
					)
					(arc
						(start 98.728276 -289.05962)
						(mid 98.769925 -289.122086)
						(end 98.78441 -289.195764)
					)
					(xy 98.784156 -289.196272)
					(arc
						(start 98.784156 -289.216846)
						(mid 98.789212 -289.230844)
						(end 98.798126 -289.242754)
					)
				)
			)
		)
		(zone
			(layer "F.Cu")
			(hatch none 0.5)
			(connect_pads
				(clearance 0)
			)
			(min_thickness 0.25)
			(keepout
				(tracks not_allowed)
				(vias allowed)
				(pads allowed)
				(copperpour not_allowed)
				(footprints allowed)
			)
			(placement
				(enabled no)
				(sheetname "")
			)
			(fill
				(thermal_gap 0.5)
				(thermal_bridge_width 0.5)
				(island_removal_mode 0)
			)
			(polygon
				(pts
					(arc
						(start 99.687634 -214.297006)
						(mid 99.65173 -214.282246)
						(end 99.615752 -214.297006)
					)
					(arc
						(start 99.615752 -214.297006)
						(mid 99.604353 -214.314246)
						(end 99.600766 -214.334598)
					)
					(arc
						(start 99.600766 -214.334598)
						(mid 99.621035 -214.451827)
						(end 99.686364 -214.55126)
					)
					(arc
						(start 99.686364 -214.55126)
						(mid 99.892866 -214.636796)
						(end 100.099368 -214.55126)
					)
					(arc
						(start 100.099368 -214.55126)
						(mid 100.164157 -214.452867)
						(end 100.184712 -214.336884)
					)
					(arc
						(start 100.184712 -214.336884)
						(mid 100.181512 -214.315875)
						(end 100.16998 -214.298022)
					)
					(arc
						(start 100.16998 -214.298022)
						(mid 100.134076 -214.283262)
						(end 100.098098 -214.298022)
					)
					(arc
						(start 100.098098 -214.298022)
						(mid 100.089356 -214.309843)
						(end 100.084382 -214.323676)
					)
					(xy 100.084382 -214.344504) (xy 100.084382 -214.344758)
					(arc
						(start 100.084382 -214.345774)
						(mid 100.069544 -214.418479)
						(end 100.028248 -214.48014)
					)
					(arc
						(start 100.028248 -214.48014)
						(mid 99.892866 -214.536217)
						(end 99.757484 -214.48014)
					)
					(arc
						(start 99.757484 -214.48014)
						(mid 99.715835 -214.417674)
						(end 99.70135 -214.343996)
					)
					(xy 99.701604 -214.343488)
					(arc
						(start 99.701604 -214.322914)
						(mid 99.696548 -214.308916)
						(end 99.687634 -214.297006)
					)
				)
			)
		)
		(zone
			(layer "F.Cu")
			(hatch none 0.5)
			(connect_pads
				(clearance 0)
			)
			(min_thickness 0.25)
			(keepout
				(tracks not_allowed)
				(vias allowed)
				(pads allowed)
				(copperpour not_allowed)
				(footprints allowed)
			)
			(placement
				(enabled no)
				(sheetname "")
			)
			(fill
				(thermal_gap 0.5)
				(thermal_bridge_width 0.5)
				(island_removal_mode 0)
			)
			(polygon
				(pts
					(arc
						(start 99.737926 -289.242754)
						(mid 99.773904 -289.257694)
						(end 99.809808 -289.242754)
					)
					(arc
						(start 99.809808 -289.242754)
						(mid 99.821207 -289.225514)
						(end 99.824794 -289.205162)
					)
					(arc
						(start 99.824794 -289.205162)
						(mid 99.804525 -289.087933)
						(end 99.739196 -288.9885)
					)
					(arc
						(start 99.739196 -288.9885)
						(mid 99.532694 -288.902964)
						(end 99.326192 -288.9885)
					)
					(arc
						(start 99.326192 -288.9885)
						(mid 99.261403 -289.086893)
						(end 99.240848 -289.202876)
					)
					(arc
						(start 99.240848 -289.202876)
						(mid 99.244048 -289.223885)
						(end 99.25558 -289.241738)
					)
					(arc
						(start 99.25558 -289.241738)
						(mid 99.291558 -289.256678)
						(end 99.327462 -289.241738)
					)
					(arc
						(start 99.327462 -289.241738)
						(mid 99.336204 -289.229917)
						(end 99.341178 -289.216084)
					)
					(xy 99.341178 -289.195256) (xy 99.341178 -289.195002)
					(arc
						(start 99.341178 -289.193986)
						(mid 99.356016 -289.121281)
						(end 99.397312 -289.05962)
					)
					(arc
						(start 99.397312 -289.05962)
						(mid 99.532694 -289.003543)
						(end 99.668076 -289.05962)
					)
					(arc
						(start 99.668076 -289.05962)
						(mid 99.709725 -289.122086)
						(end 99.72421 -289.195764)
					)
					(xy 99.723956 -289.196272)
					(arc
						(start 99.723956 -289.216846)
						(mid 99.729012 -289.230844)
						(end 99.737926 -289.242754)
					)
				)
			)
		)
		(zone
			(layer "F.Cu")
			(hatch none 0.5)
			(connect_pads
				(clearance 0)
			)
			(min_thickness 0.25)
			(keepout
				(tracks not_allowed)
				(vias allowed)
				(pads allowed)
				(copperpour not_allowed)
				(footprints allowed)
			)
			(placement
				(enabled no)
				(sheetname "")
			)
			(fill
				(thermal_gap 0.5)
				(thermal_bridge_width 0.5)
				(island_removal_mode 0)
			)
			(polygon
				(pts
					(arc
						(start 100.627434 -214.297006)
						(mid 100.59153 -214.282246)
						(end 100.555552 -214.297006)
					)
					(arc
						(start 100.555552 -214.297006)
						(mid 100.544153 -214.314246)
						(end 100.540566 -214.334598)
					)
					(arc
						(start 100.540566 -214.334598)
						(mid 100.560835 -214.451827)
						(end 100.626164 -214.55126)
					)
					(arc
						(start 100.626164 -214.55126)
						(mid 100.832666 -214.636796)
						(end 101.039168 -214.55126)
					)
					(arc
						(start 101.039168 -214.55126)
						(mid 101.103957 -214.452867)
						(end 101.124512 -214.336884)
					)
					(arc
						(start 101.124512 -214.336884)
						(mid 101.121312 -214.315875)
						(end 101.10978 -214.298022)
					)
					(arc
						(start 101.10978 -214.298022)
						(mid 101.073876 -214.283262)
						(end 101.037898 -214.298022)
					)
					(arc
						(start 101.037898 -214.298022)
						(mid 101.029156 -214.309843)
						(end 101.024182 -214.323676)
					)
					(xy 101.024182 -214.344504) (xy 101.024182 -214.344758)
					(arc
						(start 101.024182 -214.345774)
						(mid 101.009344 -214.418479)
						(end 100.968048 -214.48014)
					)
					(arc
						(start 100.968048 -214.48014)
						(mid 100.832666 -214.536217)
						(end 100.697284 -214.48014)
					)
					(arc
						(start 100.697284 -214.48014)
						(mid 100.655635 -214.417674)
						(end 100.64115 -214.343996)
					)
					(xy 100.641404 -214.343488)
					(arc
						(start 100.641404 -214.322914)
						(mid 100.636348 -214.308916)
						(end 100.627434 -214.297006)
					)
				)
			)
		)
		(zone
			(layer "F.Cu")
			(hatch none 0.5)
			(connect_pads
				(clearance 0)
			)
			(min_thickness 0.25)
			(keepout
				(tracks not_allowed)
				(vias allowed)
				(pads allowed)
				(copperpour not_allowed)
				(footprints allowed)
			)
			(placement
				(enabled no)
				(sheetname "")
			)
			(fill
				(thermal_gap 0.5)
				(thermal_bridge_width 0.5)
				(island_removal_mode 0)
			)
			(polygon
				(pts
					(arc
						(start 100.677726 -289.242754)
						(mid 100.713704 -289.257694)
						(end 100.749608 -289.242754)
					)
					(arc
						(start 100.749608 -289.242754)
						(mid 100.761007 -289.225514)
						(end 100.764594 -289.205162)
					)
					(arc
						(start 100.764594 -289.205162)
						(mid 100.744325 -289.087933)
						(end 100.678996 -288.9885)
					)
					(arc
						(start 100.678996 -288.9885)
						(mid 100.472494 -288.902964)
						(end 100.265992 -288.9885)
					)
					(arc
						(start 100.265992 -288.9885)
						(mid 100.201203 -289.086893)
						(end 100.180648 -289.202876)
					)
					(arc
						(start 100.180648 -289.202876)
						(mid 100.183848 -289.223885)
						(end 100.19538 -289.241738)
					)
					(arc
						(start 100.19538 -289.241738)
						(mid 100.231358 -289.256678)
						(end 100.267262 -289.241738)
					)
					(arc
						(start 100.267262 -289.241738)
						(mid 100.276004 -289.229917)
						(end 100.280978 -289.216084)
					)
					(xy 100.280978 -289.195256) (xy 100.280978 -289.195002)
					(arc
						(start 100.280978 -289.193986)
						(mid 100.295816 -289.121281)
						(end 100.337112 -289.05962)
					)
					(arc
						(start 100.337112 -289.05962)
						(mid 100.472494 -289.003543)
						(end 100.607876 -289.05962)
					)
					(arc
						(start 100.607876 -289.05962)
						(mid 100.649525 -289.122086)
						(end 100.66401 -289.195764)
					)
					(xy 100.663756 -289.196272)
					(arc
						(start 100.663756 -289.216846)
						(mid 100.668812 -289.230844)
						(end 100.677726 -289.242754)
					)
				)
			)
		)
		(zone
			(layer "F.Cu")
			(hatch none 0.5)
			(connect_pads
				(clearance 0)
			)
			(min_thickness 0.25)
			(keepout
				(tracks not_allowed)
				(vias allowed)
				(pads allowed)
				(copperpour not_allowed)
				(footprints allowed)
			)
			(placement
				(enabled no)
				(sheetname "")
			)
			(fill
				(thermal_gap 0.5)
				(thermal_bridge_width 0.5)
				(island_removal_mode 0)
			)
			(polygon
				(pts
					(arc
						(start 101.567234 -214.297006)
						(mid 101.53133 -214.282246)
						(end 101.495352 -214.297006)
					)
					(arc
						(start 101.495352 -214.297006)
						(mid 101.483953 -214.314246)
						(end 101.480366 -214.334598)
					)
					(arc
						(start 101.480366 -214.334598)
						(mid 101.500635 -214.451827)
						(end 101.565964 -214.55126)
					)
					(arc
						(start 101.565964 -214.55126)
						(mid 101.772466 -214.636796)
						(end 101.978968 -214.55126)
					)
					(arc
						(start 101.978968 -214.55126)
						(mid 102.043757 -214.452867)
						(end 102.064312 -214.336884)
					)
					(arc
						(start 102.064312 -214.336884)
						(mid 102.061112 -214.315875)
						(end 102.04958 -214.298022)
					)
					(arc
						(start 102.04958 -214.298022)
						(mid 102.013676 -214.283262)
						(end 101.977698 -214.298022)
					)
					(arc
						(start 101.977698 -214.298022)
						(mid 101.968956 -214.309843)
						(end 101.963982 -214.323676)
					)
					(xy 101.963982 -214.344504) (xy 101.963982 -214.344758)
					(arc
						(start 101.963982 -214.345774)
						(mid 101.949144 -214.418479)
						(end 101.907848 -214.48014)
					)
					(arc
						(start 101.907848 -214.48014)
						(mid 101.772466 -214.536217)
						(end 101.637084 -214.48014)
					)
					(arc
						(start 101.637084 -214.48014)
						(mid 101.595435 -214.417674)
						(end 101.58095 -214.343996)
					)
					(xy 101.581204 -214.343488)
					(arc
						(start 101.581204 -214.322914)
						(mid 101.576148 -214.308916)
						(end 101.567234 -214.297006)
					)
				)
			)
		)
		(zone
			(layer "F.Cu")
			(hatch none 0.5)
			(connect_pads
				(clearance 0)
			)
			(min_thickness 0.25)
			(keepout
				(tracks not_allowed)
				(vias allowed)
				(pads allowed)
				(copperpour not_allowed)
				(footprints allowed)
			)
			(placement
				(enabled no)
				(sheetname "")
			)
			(fill
				(thermal_gap 0.5)
				(thermal_bridge_width 0.5)
				(island_removal_mode 0)
			)
			(polygon
				(pts
					(arc
						(start 101.617526 -289.242754)
						(mid 101.653504 -289.257694)
						(end 101.689408 -289.242754)
					)
					(arc
						(start 101.689408 -289.242754)
						(mid 101.700807 -289.225514)
						(end 101.704394 -289.205162)
					)
					(arc
						(start 101.704394 -289.205162)
						(mid 101.684125 -289.087933)
						(end 101.618796 -288.9885)
					)
					(arc
						(start 101.618796 -288.9885)
						(mid 101.412294 -288.902964)
						(end 101.205792 -288.9885)
					)
					(arc
						(start 101.205792 -288.9885)
						(mid 101.141003 -289.086893)
						(end 101.120448 -289.202876)
					)
					(arc
						(start 101.120448 -289.202876)
						(mid 101.123648 -289.223885)
						(end 101.13518 -289.241738)
					)
					(arc
						(start 101.13518 -289.241738)
						(mid 101.171158 -289.256678)
						(end 101.207062 -289.241738)
					)
					(arc
						(start 101.207062 -289.241738)
						(mid 101.215804 -289.229917)
						(end 101.220778 -289.216084)
					)
					(xy 101.220778 -289.195256) (xy 101.220778 -289.195002)
					(arc
						(start 101.220778 -289.193986)
						(mid 101.235616 -289.121281)
						(end 101.276912 -289.05962)
					)
					(arc
						(start 101.276912 -289.05962)
						(mid 101.412294 -289.003543)
						(end 101.547676 -289.05962)
					)
					(arc
						(start 101.547676 -289.05962)
						(mid 101.589325 -289.122086)
						(end 101.60381 -289.195764)
					)
					(xy 101.603556 -289.196272)
					(arc
						(start 101.603556 -289.216846)
						(mid 101.608612 -289.230844)
						(end 101.617526 -289.242754)
					)
				)
			)
		)
		(zone
			(layer "F.Cu")
			(hatch none 0.5)
			(connect_pads
				(clearance 0)
			)
			(min_thickness 0.25)
			(keepout
				(tracks not_allowed)
				(vias allowed)
				(pads allowed)
				(copperpour not_allowed)
				(footprints allowed)
			)
			(placement
				(enabled no)
				(sheetname "")
			)
			(fill
				(thermal_gap 0.5)
				(thermal_bridge_width 0.5)
				(island_removal_mode 0)
			)
			(polygon
				(pts
					(arc
						(start 102.507034 -214.297006)
						(mid 102.47113 -214.282246)
						(end 102.435152 -214.297006)
					)
					(arc
						(start 102.435152 -214.297006)
						(mid 102.423753 -214.314246)
						(end 102.420166 -214.334598)
					)
					(arc
						(start 102.420166 -214.334598)
						(mid 102.440435 -214.451827)
						(end 102.505764 -214.55126)
					)
					(arc
						(start 102.505764 -214.55126)
						(mid 102.712266 -214.636796)
						(end 102.918768 -214.55126)
					)
					(arc
						(start 102.918768 -214.55126)
						(mid 102.983557 -214.452867)
						(end 103.004112 -214.336884)
					)
					(arc
						(start 103.004112 -214.336884)
						(mid 103.000912 -214.315875)
						(end 102.98938 -214.298022)
					)
					(arc
						(start 102.98938 -214.298022)
						(mid 102.953476 -214.283262)
						(end 102.917498 -214.298022)
					)
					(arc
						(start 102.917498 -214.298022)
						(mid 102.908756 -214.309843)
						(end 102.903782 -214.323676)
					)
					(xy 102.903782 -214.344504) (xy 102.903782 -214.344758)
					(arc
						(start 102.903782 -214.345774)
						(mid 102.888944 -214.418479)
						(end 102.847648 -214.48014)
					)
					(arc
						(start 102.847648 -214.48014)
						(mid 102.712266 -214.536217)
						(end 102.576884 -214.48014)
					)
					(arc
						(start 102.576884 -214.48014)
						(mid 102.535235 -214.417674)
						(end 102.52075 -214.343996)
					)
					(xy 102.521004 -214.343488)
					(arc
						(start 102.521004 -214.322914)
						(mid 102.515948 -214.308916)
						(end 102.507034 -214.297006)
					)
				)
			)
		)
		(zone
			(layer "F.Cu")
			(hatch none 0.5)
			(connect_pads
				(clearance 0)
			)
			(min_thickness 0.25)
			(keepout
				(tracks not_allowed)
				(vias allowed)
				(pads allowed)
				(copperpour not_allowed)
				(footprints allowed)
			)
			(placement
				(enabled no)
				(sheetname "")
			)
			(fill
				(thermal_gap 0.5)
				(thermal_bridge_width 0.5)
				(island_removal_mode 0)
			)
			(polygon
				(pts
					(arc
						(start 102.557326 -289.242754)
						(mid 102.593304 -289.257694)
						(end 102.629208 -289.242754)
					)
					(arc
						(start 102.629208 -289.242754)
						(mid 102.640607 -289.225514)
						(end 102.644194 -289.205162)
					)
					(arc
						(start 102.644194 -289.205162)
						(mid 102.623925 -289.087933)
						(end 102.558596 -288.9885)
					)
					(arc
						(start 102.558596 -288.9885)
						(mid 102.352094 -288.902964)
						(end 102.145592 -288.9885)
					)
					(arc
						(start 102.145592 -288.9885)
						(mid 102.080803 -289.086893)
						(end 102.060248 -289.202876)
					)
					(arc
						(start 102.060248 -289.202876)
						(mid 102.063448 -289.223885)
						(end 102.07498 -289.241738)
					)
					(arc
						(start 102.07498 -289.241738)
						(mid 102.110958 -289.256678)
						(end 102.146862 -289.241738)
					)
					(arc
						(start 102.146862 -289.241738)
						(mid 102.155604 -289.229917)
						(end 102.160578 -289.216084)
					)
					(xy 102.160578 -289.195256) (xy 102.160578 -289.195002)
					(arc
						(start 102.160578 -289.193986)
						(mid 102.175416 -289.121281)
						(end 102.216712 -289.05962)
					)
					(arc
						(start 102.216712 -289.05962)
						(mid 102.352094 -289.003543)
						(end 102.487476 -289.05962)
					)
					(arc
						(start 102.487476 -289.05962)
						(mid 102.529125 -289.122086)
						(end 102.54361 -289.195764)
					)
					(xy 102.543356 -289.196272)
					(arc
						(start 102.543356 -289.216846)
						(mid 102.548412 -289.230844)
						(end 102.557326 -289.242754)
					)
				)
			)
		)
		(zone
			(layer "F.Cu")
			(hatch none 0.5)
			(connect_pads
				(clearance 0)
			)
			(min_thickness 0.25)
			(keepout
				(tracks not_allowed)
				(vias allowed)
				(pads allowed)
				(copperpour not_allowed)
				(footprints allowed)
			)
			(placement
				(enabled no)
				(sheetname "")
			)
			(fill
				(thermal_gap 0.5)
				(thermal_bridge_width 0.5)
				(island_removal_mode 0)
			)
			(polygon
				(pts
					(arc
						(start 103.446834 -214.297006)
						(mid 103.41093 -214.282246)
						(end 103.374952 -214.297006)
					)
					(arc
						(start 103.374952 -214.297006)
						(mid 103.363553 -214.314246)
						(end 103.359966 -214.334598)
					)
					(arc
						(start 103.359966 -214.334598)
						(mid 103.380235 -214.451827)
						(end 103.445564 -214.55126)
					)
					(arc
						(start 103.445564 -214.55126)
						(mid 103.652066 -214.636796)
						(end 103.858568 -214.55126)
					)
					(arc
						(start 103.858568 -214.55126)
						(mid 103.923357 -214.452867)
						(end 103.943912 -214.336884)
					)
					(arc
						(start 103.943912 -214.336884)
						(mid 103.940712 -214.315875)
						(end 103.92918 -214.298022)
					)
					(arc
						(start 103.92918 -214.298022)
						(mid 103.893276 -214.283262)
						(end 103.857298 -214.298022)
					)
					(arc
						(start 103.857298 -214.298022)
						(mid 103.848556 -214.309843)
						(end 103.843582 -214.323676)
					)
					(xy 103.843582 -214.344504) (xy 103.843582 -214.344758)
					(arc
						(start 103.843582 -214.345774)
						(mid 103.828744 -214.418479)
						(end 103.787448 -214.48014)
					)
					(arc
						(start 103.787448 -214.48014)
						(mid 103.652066 -214.536217)
						(end 103.516684 -214.48014)
					)
					(arc
						(start 103.516684 -214.48014)
						(mid 103.475035 -214.417674)
						(end 103.46055 -214.343996)
					)
					(xy 103.460804 -214.343488)
					(arc
						(start 103.460804 -214.322914)
						(mid 103.455748 -214.308916)
						(end 103.446834 -214.297006)
					)
				)
			)
		)
		(zone
			(layer "F.Cu")
			(hatch none 0.5)
			(connect_pads
				(clearance 0)
			)
			(min_thickness 0.25)
			(keepout
				(tracks not_allowed)
				(vias allowed)
				(pads allowed)
				(copperpour not_allowed)
				(footprints allowed)
			)
			(placement
				(enabled no)
				(sheetname "")
			)
			(fill
				(thermal_gap 0.5)
				(thermal_bridge_width 0.5)
				(island_removal_mode 0)
			)
			(polygon
				(pts
					(arc
						(start 103.497126 -289.242754)
						(mid 103.533104 -289.257694)
						(end 103.569008 -289.242754)
					)
					(arc
						(start 103.569008 -289.242754)
						(mid 103.580407 -289.225514)
						(end 103.583994 -289.205162)
					)
					(arc
						(start 103.583994 -289.205162)
						(mid 103.563725 -289.087933)
						(end 103.498396 -288.9885)
					)
					(arc
						(start 103.498396 -288.9885)
						(mid 103.291894 -288.902964)
						(end 103.085392 -288.9885)
					)
					(arc
						(start 103.085392 -288.9885)
						(mid 103.020603 -289.086893)
						(end 103.000048 -289.202876)
					)
					(arc
						(start 103.000048 -289.202876)
						(mid 103.003248 -289.223885)
						(end 103.01478 -289.241738)
					)
					(arc
						(start 103.01478 -289.241738)
						(mid 103.050758 -289.256678)
						(end 103.086662 -289.241738)
					)
					(arc
						(start 103.086662 -289.241738)
						(mid 103.095404 -289.229917)
						(end 103.100378 -289.216084)
					)
					(xy 103.100378 -289.195256) (xy 103.100378 -289.195002)
					(arc
						(start 103.100378 -289.193986)
						(mid 103.115216 -289.121281)
						(end 103.156512 -289.05962)
					)
					(arc
						(start 103.156512 -289.05962)
						(mid 103.291894 -289.003543)
						(end 103.427276 -289.05962)
					)
					(arc
						(start 103.427276 -289.05962)
						(mid 103.468925 -289.122086)
						(end 103.48341 -289.195764)
					)
					(xy 103.483156 -289.196272)
					(arc
						(start 103.483156 -289.216846)
						(mid 103.488212 -289.230844)
						(end 103.497126 -289.242754)
					)
				)
			)
		)
		(zone
			(layer "F.Cu")
			(hatch none 0.5)
			(connect_pads
				(clearance 0)
			)
			(min_thickness 0.25)
			(keepout
				(tracks not_allowed)
				(vias allowed)
				(pads allowed)
				(copperpour not_allowed)
				(footprints allowed)
			)
			(placement
				(enabled no)
				(sheetname "")
			)
			(fill
				(thermal_gap 0.5)
				(thermal_bridge_width 0.5)
				(island_removal_mode 0)
			)
			(polygon
				(pts
					(arc
						(start 104.386634 -214.297006)
						(mid 104.35073 -214.282246)
						(end 104.314752 -214.297006)
					)
					(arc
						(start 104.314752 -214.297006)
						(mid 104.303353 -214.314246)
						(end 104.299766 -214.334598)
					)
					(arc
						(start 104.299766 -214.334598)
						(mid 104.320035 -214.451827)
						(end 104.385364 -214.55126)
					)
					(arc
						(start 104.385364 -214.55126)
						(mid 104.591866 -214.636796)
						(end 104.798368 -214.55126)
					)
					(arc
						(start 104.798368 -214.55126)
						(mid 104.863157 -214.452867)
						(end 104.883712 -214.336884)
					)
					(arc
						(start 104.883712 -214.336884)
						(mid 104.880512 -214.315875)
						(end 104.86898 -214.298022)
					)
					(arc
						(start 104.86898 -214.298022)
						(mid 104.833076 -214.283262)
						(end 104.797098 -214.298022)
					)
					(arc
						(start 104.797098 -214.298022)
						(mid 104.788356 -214.309843)
						(end 104.783382 -214.323676)
					)
					(xy 104.783382 -214.344504) (xy 104.783382 -214.344758)
					(arc
						(start 104.783382 -214.345774)
						(mid 104.768544 -214.418479)
						(end 104.727248 -214.48014)
					)
					(arc
						(start 104.727248 -214.48014)
						(mid 104.591866 -214.536217)
						(end 104.456484 -214.48014)
					)
					(arc
						(start 104.456484 -214.48014)
						(mid 104.414835 -214.417674)
						(end 104.40035 -214.343996)
					)
					(xy 104.400604 -214.343488)
					(arc
						(start 104.400604 -214.322914)
						(mid 104.395548 -214.308916)
						(end 104.386634 -214.297006)
					)
				)
			)
		)
		(zone
			(layer "F.Cu")
			(hatch none 0.5)
			(connect_pads
				(clearance 0)
			)
			(min_thickness 0.25)
			(keepout
				(tracks not_allowed)
				(vias allowed)
				(pads allowed)
				(copperpour not_allowed)
				(footprints allowed)
			)
			(placement
				(enabled no)
				(sheetname "")
			)
			(fill
				(thermal_gap 0.5)
				(thermal_bridge_width 0.5)
				(island_removal_mode 0)
			)
			(polygon
				(pts
					(arc
						(start 104.436926 -289.242754)
						(mid 104.472904 -289.257694)
						(end 104.508808 -289.242754)
					)
					(arc
						(start 104.508808 -289.242754)
						(mid 104.520207 -289.225514)
						(end 104.523794 -289.205162)
					)
					(arc
						(start 104.523794 -289.205162)
						(mid 104.503525 -289.087933)
						(end 104.438196 -288.9885)
					)
					(arc
						(start 104.438196 -288.9885)
						(mid 104.231694 -288.902964)
						(end 104.025192 -288.9885)
					)
					(arc
						(start 104.025192 -288.9885)
						(mid 103.960403 -289.086893)
						(end 103.939848 -289.202876)
					)
					(arc
						(start 103.939848 -289.202876)
						(mid 103.943048 -289.223885)
						(end 103.95458 -289.241738)
					)
					(arc
						(start 103.95458 -289.241738)
						(mid 103.990558 -289.256678)
						(end 104.026462 -289.241738)
					)
					(arc
						(start 104.026462 -289.241738)
						(mid 104.035204 -289.229917)
						(end 104.040178 -289.216084)
					)
					(xy 104.040178 -289.195256) (xy 104.040178 -289.195002)
					(arc
						(start 104.040178 -289.193986)
						(mid 104.055016 -289.121281)
						(end 104.096312 -289.05962)
					)
					(arc
						(start 104.096312 -289.05962)
						(mid 104.231694 -289.003543)
						(end 104.367076 -289.05962)
					)
					(arc
						(start 104.367076 -289.05962)
						(mid 104.408725 -289.122086)
						(end 104.42321 -289.195764)
					)
					(xy 104.422956 -289.196272)
					(arc
						(start 104.422956 -289.216846)
						(mid 104.428012 -289.230844)
						(end 104.436926 -289.242754)
					)
				)
			)
		)
		(zone
			(layer "F.Cu")
			(hatch none 0.5)
			(connect_pads
				(clearance 0)
			)
			(min_thickness 0.25)
			(keepout
				(tracks not_allowed)
				(vias allowed)
				(pads allowed)
				(copperpour not_allowed)
				(footprints allowed)
			)
			(placement
				(enabled no)
				(sheetname "")
			)
			(fill
				(thermal_gap 0.5)
				(thermal_bridge_width 0.5)
				(island_removal_mode 0)
			)
			(polygon
				(pts
					(arc
						(start 105.326434 -214.297006)
						(mid 105.29053 -214.282246)
						(end 105.254552 -214.297006)
					)
					(arc
						(start 105.254552 -214.297006)
						(mid 105.243153 -214.314246)
						(end 105.239566 -214.334598)
					)
					(arc
						(start 105.239566 -214.334598)
						(mid 105.259835 -214.451827)
						(end 105.325164 -214.55126)
					)
					(arc
						(start 105.325164 -214.55126)
						(mid 105.531666 -214.636796)
						(end 105.738168 -214.55126)
					)
					(arc
						(start 105.738168 -214.55126)
						(mid 105.802957 -214.452867)
						(end 105.823512 -214.336884)
					)
					(arc
						(start 105.823512 -214.336884)
						(mid 105.820312 -214.315875)
						(end 105.80878 -214.298022)
					)
					(arc
						(start 105.80878 -214.298022)
						(mid 105.772876 -214.283262)
						(end 105.736898 -214.298022)
					)
					(arc
						(start 105.736898 -214.298022)
						(mid 105.728156 -214.309843)
						(end 105.723182 -214.323676)
					)
					(xy 105.723182 -214.344504) (xy 105.723182 -214.344758)
					(arc
						(start 105.723182 -214.345774)
						(mid 105.708344 -214.418479)
						(end 105.667048 -214.48014)
					)
					(arc
						(start 105.667048 -214.48014)
						(mid 105.531666 -214.536217)
						(end 105.396284 -214.48014)
					)
					(arc
						(start 105.396284 -214.48014)
						(mid 105.354635 -214.417674)
						(end 105.34015 -214.343996)
					)
					(xy 105.340404 -214.343488)
					(arc
						(start 105.340404 -214.322914)
						(mid 105.335348 -214.308916)
						(end 105.326434 -214.297006)
					)
				)
			)
		)
		(zone
			(layer "F.Cu")
			(hatch none 0.5)
			(connect_pads
				(clearance 0)
			)
			(min_thickness 0.25)
			(keepout
				(tracks not_allowed)
				(vias allowed)
				(pads allowed)
				(copperpour not_allowed)
				(footprints allowed)
			)
			(placement
				(enabled no)
				(sheetname "")
			)
			(fill
				(thermal_gap 0.5)
				(thermal_bridge_width 0.5)
				(island_removal_mode 0)
			)
			(polygon
				(pts
					(arc
						(start 105.376726 -289.242754)
						(mid 105.412704 -289.257694)
						(end 105.448608 -289.242754)
					)
					(arc
						(start 105.448608 -289.242754)
						(mid 105.460007 -289.225514)
						(end 105.463594 -289.205162)
					)
					(arc
						(start 105.463594 -289.205162)
						(mid 105.443325 -289.087933)
						(end 105.377996 -288.9885)
					)
					(arc
						(start 105.377996 -288.9885)
						(mid 105.171494 -288.902964)
						(end 104.964992 -288.9885)
					)
					(arc
						(start 104.964992 -288.9885)
						(mid 104.900203 -289.086893)
						(end 104.879648 -289.202876)
					)
					(arc
						(start 104.879648 -289.202876)
						(mid 104.882848 -289.223885)
						(end 104.89438 -289.241738)
					)
					(arc
						(start 104.89438 -289.241738)
						(mid 104.930358 -289.256678)
						(end 104.966262 -289.241738)
					)
					(arc
						(start 104.966262 -289.241738)
						(mid 104.975004 -289.229917)
						(end 104.979978 -289.216084)
					)
					(xy 104.979978 -289.195256) (xy 104.979978 -289.195002)
					(arc
						(start 104.979978 -289.193986)
						(mid 104.994816 -289.121281)
						(end 105.036112 -289.05962)
					)
					(arc
						(start 105.036112 -289.05962)
						(mid 105.171494 -289.003543)
						(end 105.306876 -289.05962)
					)
					(arc
						(start 105.306876 -289.05962)
						(mid 105.348525 -289.122086)
						(end 105.36301 -289.195764)
					)
					(xy 105.362756 -289.196272)
					(arc
						(start 105.362756 -289.216846)
						(mid 105.367812 -289.230844)
						(end 105.376726 -289.242754)
					)
				)
			)
		)
		(zone
			(layer "F.Cu")
			(hatch none 0.5)
			(connect_pads
				(clearance 0)
			)
			(min_thickness 0.25)
			(keepout
				(tracks not_allowed)
				(vias allowed)
				(pads allowed)
				(copperpour not_allowed)
				(footprints allowed)
			)
			(placement
				(enabled no)
				(sheetname "")
			)
			(fill
				(thermal_gap 0.5)
				(thermal_bridge_width 0.5)
				(island_removal_mode 0)
			)
			(polygon
				(pts
					(arc
						(start 106.266234 -214.297006)
						(mid 106.23033 -214.282246)
						(end 106.194352 -214.297006)
					)
					(arc
						(start 106.194352 -214.297006)
						(mid 106.182953 -214.314246)
						(end 106.179366 -214.334598)
					)
					(arc
						(start 106.179366 -214.334598)
						(mid 106.199635 -214.451827)
						(end 106.264964 -214.55126)
					)
					(arc
						(start 106.264964 -214.55126)
						(mid 106.471466 -214.636796)
						(end 106.677968 -214.55126)
					)
					(arc
						(start 106.677968 -214.55126)
						(mid 106.742757 -214.452867)
						(end 106.763312 -214.336884)
					)
					(arc
						(start 106.763312 -214.336884)
						(mid 106.760112 -214.315875)
						(end 106.74858 -214.298022)
					)
					(arc
						(start 106.74858 -214.298022)
						(mid 106.712676 -214.283262)
						(end 106.676698 -214.298022)
					)
					(arc
						(start 106.676698 -214.298022)
						(mid 106.667956 -214.309843)
						(end 106.662982 -214.323676)
					)
					(xy 106.662982 -214.344504) (xy 106.662982 -214.344758)
					(arc
						(start 106.662982 -214.345774)
						(mid 106.648144 -214.418479)
						(end 106.606848 -214.48014)
					)
					(arc
						(start 106.606848 -214.48014)
						(mid 106.471466 -214.536217)
						(end 106.336084 -214.48014)
					)
					(arc
						(start 106.336084 -214.48014)
						(mid 106.294435 -214.417674)
						(end 106.27995 -214.343996)
					)
					(xy 106.280204 -214.343488)
					(arc
						(start 106.280204 -214.322914)
						(mid 106.275148 -214.308916)
						(end 106.266234 -214.297006)
					)
				)
			)
		)
		(zone
			(layer "F.Cu")
			(hatch none 0.5)
			(connect_pads
				(clearance 0)
			)
			(min_thickness 0.25)
			(keepout
				(tracks not_allowed)
				(vias allowed)
				(pads allowed)
				(copperpour not_allowed)
				(footprints allowed)
			)
			(placement
				(enabled no)
				(sheetname "")
			)
			(fill
				(thermal_gap 0.5)
				(thermal_bridge_width 0.5)
				(island_removal_mode 0)
			)
			(polygon
				(pts
					(arc
						(start 106.316526 -289.242754)
						(mid 106.352504 -289.257694)
						(end 106.388408 -289.242754)
					)
					(arc
						(start 106.388408 -289.242754)
						(mid 106.399807 -289.225514)
						(end 106.403394 -289.205162)
					)
					(arc
						(start 106.403394 -289.205162)
						(mid 106.383125 -289.087933)
						(end 106.317796 -288.9885)
					)
					(arc
						(start 106.317796 -288.9885)
						(mid 106.111294 -288.902964)
						(end 105.904792 -288.9885)
					)
					(arc
						(start 105.904792 -288.9885)
						(mid 105.840003 -289.086893)
						(end 105.819448 -289.202876)
					)
					(arc
						(start 105.819448 -289.202876)
						(mid 105.822648 -289.223885)
						(end 105.83418 -289.241738)
					)
					(arc
						(start 105.83418 -289.241738)
						(mid 105.870158 -289.256678)
						(end 105.906062 -289.241738)
					)
					(arc
						(start 105.906062 -289.241738)
						(mid 105.914804 -289.229917)
						(end 105.919778 -289.216084)
					)
					(xy 105.919778 -289.195256) (xy 105.919778 -289.195002)
					(arc
						(start 105.919778 -289.193986)
						(mid 105.934616 -289.121281)
						(end 105.975912 -289.05962)
					)
					(arc
						(start 105.975912 -289.05962)
						(mid 106.111294 -289.003543)
						(end 106.246676 -289.05962)
					)
					(arc
						(start 106.246676 -289.05962)
						(mid 106.288325 -289.122086)
						(end 106.30281 -289.195764)
					)
					(xy 106.302556 -289.196272)
					(arc
						(start 106.302556 -289.216846)
						(mid 106.307612 -289.230844)
						(end 106.316526 -289.242754)
					)
				)
			)
		)
		(zone
			(layer "F.Cu")
			(hatch none 0.5)
			(connect_pads
				(clearance 0)
			)
			(min_thickness 0.25)
			(keepout
				(tracks not_allowed)
				(vias allowed)
				(pads allowed)
				(copperpour not_allowed)
				(footprints allowed)
			)
			(placement
				(enabled no)
				(sheetname "")
			)
			(fill
				(thermal_gap 0.5)
				(thermal_bridge_width 0.5)
				(island_removal_mode 0)
			)
			(polygon
				(pts
					(arc
						(start 107.206034 -214.297006)
						(mid 107.17013 -214.282246)
						(end 107.134152 -214.297006)
					)
					(arc
						(start 107.134152 -214.297006)
						(mid 107.122753 -214.314246)
						(end 107.119166 -214.334598)
					)
					(arc
						(start 107.119166 -214.334598)
						(mid 107.139435 -214.451827)
						(end 107.204764 -214.55126)
					)
					(arc
						(start 107.204764 -214.55126)
						(mid 107.411266 -214.636796)
						(end 107.617768 -214.55126)
					)
					(arc
						(start 107.617768 -214.55126)
						(mid 107.682557 -214.452867)
						(end 107.703112 -214.336884)
					)
					(arc
						(start 107.703112 -214.336884)
						(mid 107.699912 -214.315875)
						(end 107.68838 -214.298022)
					)
					(arc
						(start 107.68838 -214.298022)
						(mid 107.652476 -214.283262)
						(end 107.616498 -214.298022)
					)
					(arc
						(start 107.616498 -214.298022)
						(mid 107.607756 -214.309843)
						(end 107.602782 -214.323676)
					)
					(xy 107.602782 -214.344504) (xy 107.602782 -214.344758)
					(arc
						(start 107.602782 -214.345774)
						(mid 107.587944 -214.418479)
						(end 107.546648 -214.48014)
					)
					(arc
						(start 107.546648 -214.48014)
						(mid 107.411266 -214.536217)
						(end 107.275884 -214.48014)
					)
					(arc
						(start 107.275884 -214.48014)
						(mid 107.234235 -214.417674)
						(end 107.21975 -214.343996)
					)
					(xy 107.220004 -214.343488)
					(arc
						(start 107.220004 -214.322914)
						(mid 107.214948 -214.308916)
						(end 107.206034 -214.297006)
					)
				)
			)
		)
		(zone
			(layer "F.Cu")
			(hatch none 0.5)
			(connect_pads
				(clearance 0)
			)
			(min_thickness 0.25)
			(keepout
				(tracks not_allowed)
				(vias allowed)
				(pads allowed)
				(copperpour not_allowed)
				(footprints allowed)
			)
			(placement
				(enabled no)
				(sheetname "")
			)
			(fill
				(thermal_gap 0.5)
				(thermal_bridge_width 0.5)
				(island_removal_mode 0)
			)
			(polygon
				(pts
					(arc
						(start 107.256326 -289.242754)
						(mid 107.292304 -289.257694)
						(end 107.328208 -289.242754)
					)
					(arc
						(start 107.328208 -289.242754)
						(mid 107.339607 -289.225514)
						(end 107.343194 -289.205162)
					)
					(arc
						(start 107.343194 -289.205162)
						(mid 107.322925 -289.087933)
						(end 107.257596 -288.9885)
					)
					(arc
						(start 107.257596 -288.9885)
						(mid 107.051094 -288.902964)
						(end 106.844592 -288.9885)
					)
					(arc
						(start 106.844592 -288.9885)
						(mid 106.779803 -289.086893)
						(end 106.759248 -289.202876)
					)
					(arc
						(start 106.759248 -289.202876)
						(mid 106.762448 -289.223885)
						(end 106.77398 -289.241738)
					)
					(arc
						(start 106.77398 -289.241738)
						(mid 106.809958 -289.256678)
						(end 106.845862 -289.241738)
					)
					(arc
						(start 106.845862 -289.241738)
						(mid 106.854604 -289.229917)
						(end 106.859578 -289.216084)
					)
					(xy 106.859578 -289.195256) (xy 106.859578 -289.195002)
					(arc
						(start 106.859578 -289.193986)
						(mid 106.874416 -289.121281)
						(end 106.915712 -289.05962)
					)
					(arc
						(start 106.915712 -289.05962)
						(mid 107.051094 -289.003543)
						(end 107.186476 -289.05962)
					)
					(arc
						(start 107.186476 -289.05962)
						(mid 107.228125 -289.122086)
						(end 107.24261 -289.195764)
					)
					(xy 107.242356 -289.196272)
					(arc
						(start 107.242356 -289.216846)
						(mid 107.247412 -289.230844)
						(end 107.256326 -289.242754)
					)
				)
			)
		)
		(zone
			(layer "F.Cu")
			(hatch none 0.5)
			(connect_pads
				(clearance 0)
			)
			(min_thickness 0.25)
			(keepout
				(tracks not_allowed)
				(vias allowed)
				(pads allowed)
				(copperpour not_allowed)
				(footprints allowed)
			)
			(placement
				(enabled no)
				(sheetname "")
			)
			(fill
				(thermal_gap 0.5)
				(thermal_bridge_width 0.5)
				(island_removal_mode 0)
			)
			(polygon
				(pts
					(arc
						(start 108.145834 -214.297006)
						(mid 108.10993 -214.282246)
						(end 108.073952 -214.297006)
					)
					(arc
						(start 108.073952 -214.297006)
						(mid 108.062553 -214.314246)
						(end 108.058966 -214.334598)
					)
					(arc
						(start 108.058966 -214.334598)
						(mid 108.079235 -214.451827)
						(end 108.144564 -214.55126)
					)
					(arc
						(start 108.144564 -214.55126)
						(mid 108.351066 -214.636796)
						(end 108.557568 -214.55126)
					)
					(arc
						(start 108.557568 -214.55126)
						(mid 108.622357 -214.452867)
						(end 108.642912 -214.336884)
					)
					(arc
						(start 108.642912 -214.336884)
						(mid 108.639712 -214.315875)
						(end 108.62818 -214.298022)
					)
					(arc
						(start 108.62818 -214.298022)
						(mid 108.592276 -214.283262)
						(end 108.556298 -214.298022)
					)
					(arc
						(start 108.556298 -214.298022)
						(mid 108.547556 -214.309843)
						(end 108.542582 -214.323676)
					)
					(xy 108.542582 -214.344504) (xy 108.542582 -214.344758)
					(arc
						(start 108.542582 -214.345774)
						(mid 108.527744 -214.418479)
						(end 108.486448 -214.48014)
					)
					(arc
						(start 108.486448 -214.48014)
						(mid 108.351066 -214.536217)
						(end 108.215684 -214.48014)
					)
					(arc
						(start 108.215684 -214.48014)
						(mid 108.174035 -214.417674)
						(end 108.15955 -214.343996)
					)
					(xy 108.159804 -214.343488)
					(arc
						(start 108.159804 -214.322914)
						(mid 108.154748 -214.308916)
						(end 108.145834 -214.297006)
					)
				)
			)
		)
		(zone
			(layer "F.Cu")
			(hatch none 0.5)
			(connect_pads
				(clearance 0)
			)
			(min_thickness 0.25)
			(keepout
				(tracks not_allowed)
				(vias allowed)
				(pads allowed)
				(copperpour not_allowed)
				(footprints allowed)
			)
			(placement
				(enabled no)
				(sheetname "")
			)
			(fill
				(thermal_gap 0.5)
				(thermal_bridge_width 0.5)
				(island_removal_mode 0)
			)
			(polygon
				(pts
					(arc
						(start 108.196126 -289.242754)
						(mid 108.232104 -289.257694)
						(end 108.268008 -289.242754)
					)
					(arc
						(start 108.268008 -289.242754)
						(mid 108.279407 -289.225514)
						(end 108.282994 -289.205162)
					)
					(arc
						(start 108.282994 -289.205162)
						(mid 108.262725 -289.087933)
						(end 108.197396 -288.9885)
					)
					(arc
						(start 108.197396 -288.9885)
						(mid 107.990894 -288.902964)
						(end 107.784392 -288.9885)
					)
					(arc
						(start 107.784392 -288.9885)
						(mid 107.719603 -289.086893)
						(end 107.699048 -289.202876)
					)
					(arc
						(start 107.699048 -289.202876)
						(mid 107.702248 -289.223885)
						(end 107.71378 -289.241738)
					)
					(arc
						(start 107.71378 -289.241738)
						(mid 107.749758 -289.256678)
						(end 107.785662 -289.241738)
					)
					(arc
						(start 107.785662 -289.241738)
						(mid 107.794404 -289.229917)
						(end 107.799378 -289.216084)
					)
					(xy 107.799378 -289.195256) (xy 107.799378 -289.195002)
					(arc
						(start 107.799378 -289.193986)
						(mid 107.814216 -289.121281)
						(end 107.855512 -289.05962)
					)
					(arc
						(start 107.855512 -289.05962)
						(mid 107.990894 -289.003543)
						(end 108.126276 -289.05962)
					)
					(arc
						(start 108.126276 -289.05962)
						(mid 108.167925 -289.122086)
						(end 108.18241 -289.195764)
					)
					(xy 108.182156 -289.196272)
					(arc
						(start 108.182156 -289.216846)
						(mid 108.187212 -289.230844)
						(end 108.196126 -289.242754)
					)
				)
			)
		)
		(zone
			(layer "F.Cu")
			(hatch none 0.5)
			(connect_pads
				(clearance 0)
			)
			(min_thickness 0.25)
			(keepout
				(tracks not_allowed)
				(vias allowed)
				(pads allowed)
				(copperpour not_allowed)
				(footprints allowed)
			)
			(placement
				(enabled no)
				(sheetname "")
			)
			(fill
				(thermal_gap 0.5)
				(thermal_bridge_width 0.5)
				(island_removal_mode 0)
			)
			(polygon
				(pts
					(arc
						(start 108.61548 -215.111076)
						(mid 108.579666 -215.096241)
						(end 108.543852 -215.111076)
					)
					(arc
						(start 108.543852 -215.111076)
						(mid 108.532501 -215.128198)
						(end 108.528866 -215.148414)
					)
					(arc
						(start 108.528866 -215.148414)
						(mid 108.549015 -215.265615)
						(end 108.61421 -215.365076)
					)
					(arc
						(start 108.61421 -215.365076)
						(mid 108.820712 -215.450612)
						(end 109.027214 -215.365076)
					)
					(arc
						(start 109.027214 -215.365076)
						(mid 109.092096 -215.266832)
						(end 109.112812 -215.150954)
					)
					(arc
						(start 109.112812 -215.150954)
						(mid 109.109624 -215.129932)
						(end 109.09808 -215.112092)
					)
					(arc
						(start 109.09808 -215.112092)
						(mid 109.062177 -215.097257)
						(end 109.026198 -215.112092)
					)
					(arc
						(start 109.026198 -215.112092)
						(mid 109.017475 -215.123788)
						(end 109.012482 -215.137492)
					)
					(xy 109.012482 -215.15832) (xy 109.012482 -215.158828)
					(arc
						(start 109.012482 -215.159844)
						(mid 108.99748 -215.232442)
						(end 108.956094 -215.293956)
					)
					(arc
						(start 108.956094 -215.293956)
						(mid 108.820712 -215.350033)
						(end 108.68533 -215.293956)
					)
					(arc
						(start 108.68533 -215.293956)
						(mid 108.64373 -215.231608)
						(end 108.629196 -215.158066)
					)
					(xy 108.62945 -215.157304)
					(arc
						(start 108.62945 -215.13673)
						(mid 108.62436 -215.122868)
						(end 108.61548 -215.111076)
					)
				)
			)
		)
		(zone
			(layer "F.Cu")
			(hatch none 0.5)
			(connect_pads
				(clearance 0)
			)
			(min_thickness 0.25)
			(keepout
				(tracks not_allowed)
				(vias allowed)
				(pads allowed)
				(copperpour not_allowed)
				(footprints allowed)
			)
			(placement
				(enabled no)
				(sheetname "")
			)
			(fill
				(thermal_gap 0.5)
				(thermal_bridge_width 0.5)
				(island_removal_mode 0)
			)
			(polygon
				(pts
					(arc
						(start 109.135926 -289.242754)
						(mid 109.171904 -289.257694)
						(end 109.207808 -289.242754)
					)
					(arc
						(start 109.207808 -289.242754)
						(mid 109.219207 -289.225514)
						(end 109.222794 -289.205162)
					)
					(arc
						(start 109.222794 -289.205162)
						(mid 109.202525 -289.087933)
						(end 109.137196 -288.9885)
					)
					(arc
						(start 109.137196 -288.9885)
						(mid 108.930694 -288.902964)
						(end 108.724192 -288.9885)
					)
					(arc
						(start 108.724192 -288.9885)
						(mid 108.659403 -289.086893)
						(end 108.638848 -289.202876)
					)
					(arc
						(start 108.638848 -289.202876)
						(mid 108.642048 -289.223885)
						(end 108.65358 -289.241738)
					)
					(arc
						(start 108.65358 -289.241738)
						(mid 108.689558 -289.256678)
						(end 108.725462 -289.241738)
					)
					(arc
						(start 108.725462 -289.241738)
						(mid 108.734204 -289.229917)
						(end 108.739178 -289.216084)
					)
					(xy 108.739178 -289.195256) (xy 108.739178 -289.195002)
					(arc
						(start 108.739178 -289.193986)
						(mid 108.754016 -289.121281)
						(end 108.795312 -289.05962)
					)
					(arc
						(start 108.795312 -289.05962)
						(mid 108.930694 -289.003543)
						(end 109.066076 -289.05962)
					)
					(arc
						(start 109.066076 -289.05962)
						(mid 109.107725 -289.122086)
						(end 109.12221 -289.195764)
					)
					(xy 109.121956 -289.196272)
					(arc
						(start 109.121956 -289.216846)
						(mid 109.127012 -289.230844)
						(end 109.135926 -289.242754)
					)
				)
			)
		)
		(zone
			(layer "F.Cu")
			(hatch none 0.5)
			(connect_pads
				(clearance 0)
			)
			(min_thickness 0.25)
			(keepout
				(tracks not_allowed)
				(vias allowed)
				(pads allowed)
				(copperpour not_allowed)
				(footprints allowed)
			)
			(placement
				(enabled no)
				(sheetname "")
			)
			(fill
				(thermal_gap 0.5)
				(thermal_bridge_width 0.5)
				(island_removal_mode 0)
			)
			(polygon
				(pts
					(arc
						(start 109.55528 -215.111076)
						(mid 109.519466 -215.096241)
						(end 109.483652 -215.111076)
					)
					(arc
						(start 109.483652 -215.111076)
						(mid 109.472301 -215.128198)
						(end 109.468666 -215.148414)
					)
					(arc
						(start 109.468666 -215.148414)
						(mid 109.488815 -215.265615)
						(end 109.55401 -215.365076)
					)
					(arc
						(start 109.55401 -215.365076)
						(mid 109.760512 -215.450612)
						(end 109.967014 -215.365076)
					)
					(arc
						(start 109.967014 -215.365076)
						(mid 110.031896 -215.266832)
						(end 110.052612 -215.150954)
					)
					(arc
						(start 110.052612 -215.150954)
						(mid 110.049424 -215.129932)
						(end 110.03788 -215.112092)
					)
					(arc
						(start 110.03788 -215.112092)
						(mid 110.001977 -215.097257)
						(end 109.965998 -215.112092)
					)
					(arc
						(start 109.965998 -215.112092)
						(mid 109.957275 -215.123788)
						(end 109.952282 -215.137492)
					)
					(xy 109.952282 -215.15832) (xy 109.952282 -215.158828)
					(arc
						(start 109.952282 -215.159844)
						(mid 109.93728 -215.232442)
						(end 109.895894 -215.293956)
					)
					(arc
						(start 109.895894 -215.293956)
						(mid 109.760512 -215.350033)
						(end 109.62513 -215.293956)
					)
					(arc
						(start 109.62513 -215.293956)
						(mid 109.58353 -215.231608)
						(end 109.568996 -215.158066)
					)
					(xy 109.56925 -215.157304)
					(arc
						(start 109.56925 -215.13673)
						(mid 109.56416 -215.122868)
						(end 109.55528 -215.111076)
					)
				)
			)
		)
		(zone
			(layer "F.Cu")
			(hatch none 0.5)
			(connect_pads
				(clearance 0)
			)
			(min_thickness 0.25)
			(keepout
				(tracks not_allowed)
				(vias allowed)
				(pads allowed)
				(copperpour not_allowed)
				(footprints allowed)
			)
			(placement
				(enabled no)
				(sheetname "")
			)
			(fill
				(thermal_gap 0.5)
				(thermal_bridge_width 0.5)
				(island_removal_mode 0)
			)
			(polygon
				(pts
					(arc
						(start 109.605826 -288.428684)
						(mid 109.641804 -288.443698)
						(end 109.677708 -288.428684)
					)
					(arc
						(start 109.677708 -288.428684)
						(mid 109.689059 -288.411562)
						(end 109.692694 -288.391346)
					)
					(arc
						(start 109.692694 -288.391346)
						(mid 109.672425 -288.274117)
						(end 109.607096 -288.174684)
					)
					(arc
						(start 109.607096 -288.174684)
						(mid 109.400594 -288.089148)
						(end 109.194092 -288.174684)
					)
					(arc
						(start 109.194092 -288.174684)
						(mid 109.129351 -288.272959)
						(end 109.108748 -288.388806)
					)
					(arc
						(start 109.108748 -288.388806)
						(mid 109.111948 -288.409815)
						(end 109.12348 -288.427668)
					)
					(arc
						(start 109.12348 -288.427668)
						(mid 109.159458 -288.442682)
						(end 109.195362 -288.427668)
					)
					(arc
						(start 109.195362 -288.427668)
						(mid 109.204085 -288.415972)
						(end 109.209078 -288.402268)
					)
					(xy 109.209078 -288.38144) (xy 109.209078 -288.380932)
					(arc
						(start 109.209078 -288.379916)
						(mid 109.223963 -288.307347)
						(end 109.265212 -288.245804)
					)
					(arc
						(start 109.265212 -288.245804)
						(mid 109.400594 -288.189727)
						(end 109.535976 -288.245804)
					)
					(arc
						(start 109.535976 -288.245804)
						(mid 109.577576 -288.308152)
						(end 109.59211 -288.381694)
					)
					(xy 109.591856 -288.382456)
					(arc
						(start 109.591856 -288.40303)
						(mid 109.596946 -288.416892)
						(end 109.605826 -288.428684)
					)
				)
			)
		)
		(zone
			(layer "F.Cu")
			(hatch none 0.5)
			(connect_pads
				(clearance 0)
			)
			(min_thickness 0.25)
			(keepout
				(tracks not_allowed)
				(vias allowed)
				(pads allowed)
				(copperpour not_allowed)
				(footprints allowed)
			)
			(placement
				(enabled no)
				(sheetname "")
			)
			(fill
				(thermal_gap 0.5)
				(thermal_bridge_width 0.5)
				(island_removal_mode 0)
			)
			(polygon
				(pts
					(arc
						(start 110.495334 -215.111076)
						(mid 110.459431 -215.096241)
						(end 110.423452 -215.111076)
					)
					(arc
						(start 110.423452 -215.111076)
						(mid 110.412101 -215.128198)
						(end 110.408466 -215.148414)
					)
					(arc
						(start 110.408466 -215.148414)
						(mid 110.428735 -215.265643)
						(end 110.494064 -215.365076)
					)
					(arc
						(start 110.494064 -215.365076)
						(mid 110.700566 -215.450612)
						(end 110.907068 -215.365076)
					)
					(arc
						(start 110.907068 -215.365076)
						(mid 110.971809 -215.266801)
						(end 110.992412 -215.150954)
					)
					(arc
						(start 110.992412 -215.150954)
						(mid 110.989212 -215.129945)
						(end 110.97768 -215.112092)
					)
					(arc
						(start 110.97768 -215.112092)
						(mid 110.941777 -215.097257)
						(end 110.905798 -215.112092)
					)
					(arc
						(start 110.905798 -215.112092)
						(mid 110.897075 -215.123788)
						(end 110.892082 -215.137492)
					)
					(xy 110.892082 -215.15832) (xy 110.892082 -215.158828)
					(arc
						(start 110.892082 -215.159844)
						(mid 110.877197 -215.232413)
						(end 110.835948 -215.293956)
					)
					(arc
						(start 110.835948 -215.293956)
						(mid 110.700566 -215.350033)
						(end 110.565184 -215.293956)
					)
					(arc
						(start 110.565184 -215.293956)
						(mid 110.523584 -215.231608)
						(end 110.50905 -215.158066)
					)
					(xy 110.509304 -215.157304)
					(arc
						(start 110.509304 -215.13673)
						(mid 110.504214 -215.122868)
						(end 110.495334 -215.111076)
					)
				)
			)
		)
		(zone
			(layer "F.Cu")
			(hatch none 0.5)
			(connect_pads
				(clearance 0)
			)
			(min_thickness 0.25)
			(keepout
				(tracks not_allowed)
				(vias allowed)
				(pads allowed)
				(copperpour not_allowed)
				(footprints allowed)
			)
			(placement
				(enabled no)
				(sheetname "")
			)
			(fill
				(thermal_gap 0.5)
				(thermal_bridge_width 0.5)
				(island_removal_mode 0)
			)
			(polygon
				(pts
					(arc
						(start 110.54588 -288.428684)
						(mid 110.581694 -288.443519)
						(end 110.617508 -288.428684)
					)
					(arc
						(start 110.617508 -288.428684)
						(mid 110.628859 -288.411562)
						(end 110.632494 -288.391346)
					)
					(arc
						(start 110.632494 -288.391346)
						(mid 110.612345 -288.274145)
						(end 110.54715 -288.174684)
					)
					(arc
						(start 110.54715 -288.174684)
						(mid 110.340648 -288.089148)
						(end 110.134146 -288.174684)
					)
					(arc
						(start 110.134146 -288.174684)
						(mid 110.069264 -288.272928)
						(end 110.048548 -288.388806)
					)
					(arc
						(start 110.048548 -288.388806)
						(mid 110.051736 -288.409828)
						(end 110.06328 -288.427668)
					)
					(arc
						(start 110.06328 -288.427668)
						(mid 110.099258 -288.442682)
						(end 110.135162 -288.427668)
					)
					(arc
						(start 110.135162 -288.427668)
						(mid 110.143885 -288.415972)
						(end 110.148878 -288.402268)
					)
					(xy 110.148878 -288.38144) (xy 110.148878 -288.380932)
					(arc
						(start 110.148878 -288.379916)
						(mid 110.16388 -288.307318)
						(end 110.205266 -288.245804)
					)
					(arc
						(start 110.205266 -288.245804)
						(mid 110.340648 -288.189727)
						(end 110.47603 -288.245804)
					)
					(arc
						(start 110.47603 -288.245804)
						(mid 110.51763 -288.308152)
						(end 110.532164 -288.381694)
					)
					(xy 110.53191 -288.382456)
					(arc
						(start 110.53191 -288.40303)
						(mid 110.537 -288.416892)
						(end 110.54588 -288.428684)
					)
				)
			)
		)
		(zone
			(layer "F.Cu")
			(hatch none 0.5)
			(connect_pads
				(clearance 0)
			)
			(min_thickness 0.25)
			(keepout
				(tracks not_allowed)
				(vias allowed)
				(pads allowed)
				(copperpour not_allowed)
				(footprints allowed)
			)
			(placement
				(enabled no)
				(sheetname "")
			)
			(fill
				(thermal_gap 0.5)
				(thermal_bridge_width 0.5)
				(island_removal_mode 0)
			)
			(polygon
				(pts
					(arc
						(start 111.43488 -215.111076)
						(mid 111.399066 -215.096241)
						(end 111.363252 -215.111076)
					)
					(arc
						(start 111.363252 -215.111076)
						(mid 111.351901 -215.128198)
						(end 111.348266 -215.148414)
					)
					(arc
						(start 111.348266 -215.148414)
						(mid 111.368415 -215.265615)
						(end 111.43361 -215.365076)
					)
					(arc
						(start 111.43361 -215.365076)
						(mid 111.640112 -215.450612)
						(end 111.846614 -215.365076)
					)
					(arc
						(start 111.846614 -215.365076)
						(mid 111.911496 -215.266832)
						(end 111.932212 -215.150954)
					)
					(arc
						(start 111.932212 -215.150954)
						(mid 111.929024 -215.129932)
						(end 111.91748 -215.112092)
					)
					(arc
						(start 111.91748 -215.112092)
						(mid 111.881577 -215.097257)
						(end 111.845598 -215.112092)
					)
					(arc
						(start 111.845598 -215.112092)
						(mid 111.836875 -215.123788)
						(end 111.831882 -215.137492)
					)
					(xy 111.831882 -215.15832) (xy 111.831882 -215.158828)
					(arc
						(start 111.831882 -215.159844)
						(mid 111.81688 -215.232442)
						(end 111.775494 -215.293956)
					)
					(arc
						(start 111.775494 -215.293956)
						(mid 111.640112 -215.350033)
						(end 111.50473 -215.293956)
					)
					(arc
						(start 111.50473 -215.293956)
						(mid 111.46313 -215.231608)
						(end 111.448596 -215.158066)
					)
					(xy 111.44885 -215.157304)
					(arc
						(start 111.44885 -215.13673)
						(mid 111.44376 -215.122868)
						(end 111.43488 -215.111076)
					)
				)
			)
		)
		(zone
			(layer "F.Cu")
			(hatch none 0.5)
			(connect_pads
				(clearance 0)
			)
			(min_thickness 0.25)
			(keepout
				(tracks not_allowed)
				(vias allowed)
				(pads allowed)
				(copperpour not_allowed)
				(footprints allowed)
			)
			(placement
				(enabled no)
				(sheetname "")
			)
			(fill
				(thermal_gap 0.5)
				(thermal_bridge_width 0.5)
				(island_removal_mode 0)
			)
			(polygon
				(pts
					(arc
						(start 111.48568 -288.428684)
						(mid 111.521494 -288.443519)
						(end 111.557308 -288.428684)
					)
					(arc
						(start 111.557308 -288.428684)
						(mid 111.568659 -288.411562)
						(end 111.572294 -288.391346)
					)
					(arc
						(start 111.572294 -288.391346)
						(mid 111.552145 -288.274145)
						(end 111.48695 -288.174684)
					)
					(arc
						(start 111.48695 -288.174684)
						(mid 111.280448 -288.089148)
						(end 111.073946 -288.174684)
					)
					(arc
						(start 111.073946 -288.174684)
						(mid 111.009064 -288.272928)
						(end 110.988348 -288.388806)
					)
					(arc
						(start 110.988348 -288.388806)
						(mid 110.991536 -288.409828)
						(end 111.00308 -288.427668)
					)
					(arc
						(start 111.00308 -288.427668)
						(mid 111.039058 -288.442682)
						(end 111.074962 -288.427668)
					)
					(arc
						(start 111.074962 -288.427668)
						(mid 111.083685 -288.415972)
						(end 111.088678 -288.402268)
					)
					(xy 111.088678 -288.38144) (xy 111.088678 -288.380932)
					(arc
						(start 111.088678 -288.379916)
						(mid 111.10368 -288.307318)
						(end 111.145066 -288.245804)
					)
					(arc
						(start 111.145066 -288.245804)
						(mid 111.280448 -288.189727)
						(end 111.41583 -288.245804)
					)
					(arc
						(start 111.41583 -288.245804)
						(mid 111.45743 -288.308152)
						(end 111.471964 -288.381694)
					)
					(xy 111.47171 -288.382456)
					(arc
						(start 111.47171 -288.40303)
						(mid 111.4768 -288.416892)
						(end 111.48568 -288.428684)
					)
				)
			)
		)
		(zone
			(layer "F.Cu")
			(hatch none 0.5)
			(connect_pads
				(clearance 0)
			)
			(min_thickness 0.25)
			(keepout
				(tracks not_allowed)
				(vias allowed)
				(pads allowed)
				(copperpour not_allowed)
				(footprints allowed)
			)
			(placement
				(enabled no)
				(sheetname "")
			)
			(fill
				(thermal_gap 0.5)
				(thermal_bridge_width 0.5)
				(island_removal_mode 0)
			)
			(polygon
				(pts
					(arc
						(start 112.37468 -215.111076)
						(mid 112.338866 -215.096241)
						(end 112.303052 -215.111076)
					)
					(arc
						(start 112.303052 -215.111076)
						(mid 112.291701 -215.128198)
						(end 112.288066 -215.148414)
					)
					(arc
						(start 112.288066 -215.148414)
						(mid 112.308215 -215.265615)
						(end 112.37341 -215.365076)
					)
					(arc
						(start 112.37341 -215.365076)
						(mid 112.579912 -215.450612)
						(end 112.786414 -215.365076)
					)
					(arc
						(start 112.786414 -215.365076)
						(mid 112.851296 -215.266832)
						(end 112.872012 -215.150954)
					)
					(arc
						(start 112.872012 -215.150954)
						(mid 112.868824 -215.129932)
						(end 112.85728 -215.112092)
					)
					(arc
						(start 112.85728 -215.112092)
						(mid 112.821377 -215.097257)
						(end 112.785398 -215.112092)
					)
					(arc
						(start 112.785398 -215.112092)
						(mid 112.776675 -215.123788)
						(end 112.771682 -215.137492)
					)
					(xy 112.771682 -215.15832) (xy 112.771682 -215.158828)
					(arc
						(start 112.771682 -215.159844)
						(mid 112.75668 -215.232442)
						(end 112.715294 -215.293956)
					)
					(arc
						(start 112.715294 -215.293956)
						(mid 112.579912 -215.350033)
						(end 112.44453 -215.293956)
					)
					(arc
						(start 112.44453 -215.293956)
						(mid 112.40293 -215.231608)
						(end 112.388396 -215.158066)
					)
					(xy 112.38865 -215.157304)
					(arc
						(start 112.38865 -215.13673)
						(mid 112.38356 -215.122868)
						(end 112.37468 -215.111076)
					)
				)
			)
		)
		(zone
			(layer "F.Cu")
			(hatch none 0.5)
			(connect_pads
				(clearance 0)
			)
			(min_thickness 0.25)
			(keepout
				(tracks not_allowed)
				(vias allowed)
				(pads allowed)
				(copperpour not_allowed)
				(footprints allowed)
			)
			(placement
				(enabled no)
				(sheetname "")
			)
			(fill
				(thermal_gap 0.5)
				(thermal_bridge_width 0.5)
				(island_removal_mode 0)
			)
			(polygon
				(pts
					(arc
						(start 112.42548 -288.428684)
						(mid 112.461294 -288.443519)
						(end 112.497108 -288.428684)
					)
					(arc
						(start 112.497108 -288.428684)
						(mid 112.508459 -288.411562)
						(end 112.512094 -288.391346)
					)
					(arc
						(start 112.512094 -288.391346)
						(mid 112.491945 -288.274145)
						(end 112.42675 -288.174684)
					)
					(arc
						(start 112.42675 -288.174684)
						(mid 112.220248 -288.089148)
						(end 112.013746 -288.174684)
					)
					(arc
						(start 112.013746 -288.174684)
						(mid 111.948864 -288.272928)
						(end 111.928148 -288.388806)
					)
					(arc
						(start 111.928148 -288.388806)
						(mid 111.931336 -288.409828)
						(end 111.94288 -288.427668)
					)
					(arc
						(start 111.94288 -288.427668)
						(mid 111.978858 -288.442682)
						(end 112.014762 -288.427668)
					)
					(arc
						(start 112.014762 -288.427668)
						(mid 112.023485 -288.415972)
						(end 112.028478 -288.402268)
					)
					(xy 112.028478 -288.38144) (xy 112.028478 -288.380932)
					(arc
						(start 112.028478 -288.379916)
						(mid 112.04348 -288.307318)
						(end 112.084866 -288.245804)
					)
					(arc
						(start 112.084866 -288.245804)
						(mid 112.220248 -288.189727)
						(end 112.35563 -288.245804)
					)
					(arc
						(start 112.35563 -288.245804)
						(mid 112.39723 -288.308152)
						(end 112.411764 -288.381694)
					)
					(xy 112.41151 -288.382456)
					(arc
						(start 112.41151 -288.40303)
						(mid 112.4166 -288.416892)
						(end 112.42548 -288.428684)
					)
				)
			)
		)
		(zone
			(layer "F.Cu")
			(hatch none 0.5)
			(connect_pads
				(clearance 0)
			)
			(min_thickness 0.25)
			(keepout
				(tracks not_allowed)
				(vias allowed)
				(pads allowed)
				(copperpour not_allowed)
				(footprints allowed)
			)
			(placement
				(enabled no)
				(sheetname "")
			)
			(fill
				(thermal_gap 0.5)
				(thermal_bridge_width 0.5)
				(island_removal_mode 0)
			)
			(polygon
				(pts
					(arc
						(start 113.31448 -215.111076)
						(mid 113.278666 -215.096241)
						(end 113.242852 -215.111076)
					)
					(arc
						(start 113.242852 -215.111076)
						(mid 113.231501 -215.128198)
						(end 113.227866 -215.148414)
					)
					(arc
						(start 113.227866 -215.148414)
						(mid 113.248015 -215.265615)
						(end 113.31321 -215.365076)
					)
					(arc
						(start 113.31321 -215.365076)
						(mid 113.519712 -215.450612)
						(end 113.726214 -215.365076)
					)
					(arc
						(start 113.726214 -215.365076)
						(mid 113.791096 -215.266832)
						(end 113.811812 -215.150954)
					)
					(arc
						(start 113.811812 -215.150954)
						(mid 113.808624 -215.129932)
						(end 113.79708 -215.112092)
					)
					(arc
						(start 113.79708 -215.112092)
						(mid 113.761177 -215.097257)
						(end 113.725198 -215.112092)
					)
					(arc
						(start 113.725198 -215.112092)
						(mid 113.716475 -215.123788)
						(end 113.711482 -215.137492)
					)
					(xy 113.711482 -215.15832) (xy 113.711482 -215.158828)
					(arc
						(start 113.711482 -215.159844)
						(mid 113.69648 -215.232442)
						(end 113.655094 -215.293956)
					)
					(arc
						(start 113.655094 -215.293956)
						(mid 113.519712 -215.350033)
						(end 113.38433 -215.293956)
					)
					(arc
						(start 113.38433 -215.293956)
						(mid 113.34273 -215.231608)
						(end 113.328196 -215.158066)
					)
					(xy 113.32845 -215.157304)
					(arc
						(start 113.32845 -215.13673)
						(mid 113.32336 -215.122868)
						(end 113.31448 -215.111076)
					)
				)
			)
		)
		(zone
			(layer "F.Cu")
			(hatch none 0.5)
			(connect_pads
				(clearance 0)
			)
			(min_thickness 0.25)
			(keepout
				(tracks not_allowed)
				(vias allowed)
				(pads allowed)
				(copperpour not_allowed)
				(footprints allowed)
			)
			(placement
				(enabled no)
				(sheetname "")
			)
			(fill
				(thermal_gap 0.5)
				(thermal_bridge_width 0.5)
				(island_removal_mode 0)
			)
			(polygon
				(pts
					(arc
						(start 113.365026 -288.428684)
						(mid 113.401004 -288.443698)
						(end 113.436908 -288.428684)
					)
					(arc
						(start 113.436908 -288.428684)
						(mid 113.448259 -288.411562)
						(end 113.451894 -288.391346)
					)
					(arc
						(start 113.451894 -288.391346)
						(mid 113.431625 -288.274117)
						(end 113.366296 -288.174684)
					)
					(arc
						(start 113.366296 -288.174684)
						(mid 113.159794 -288.089148)
						(end 112.953292 -288.174684)
					)
					(arc
						(start 112.953292 -288.174684)
						(mid 112.888551 -288.272959)
						(end 112.867948 -288.388806)
					)
					(arc
						(start 112.867948 -288.388806)
						(mid 112.871148 -288.409815)
						(end 112.88268 -288.427668)
					)
					(arc
						(start 112.88268 -288.427668)
						(mid 112.918658 -288.442682)
						(end 112.954562 -288.427668)
					)
					(arc
						(start 112.954562 -288.427668)
						(mid 112.963285 -288.415972)
						(end 112.968278 -288.402268)
					)
					(xy 112.968278 -288.38144) (xy 112.968278 -288.380932)
					(arc
						(start 112.968278 -288.379916)
						(mid 112.983163 -288.307347)
						(end 113.024412 -288.245804)
					)
					(arc
						(start 113.024412 -288.245804)
						(mid 113.159794 -288.189727)
						(end 113.295176 -288.245804)
					)
					(arc
						(start 113.295176 -288.245804)
						(mid 113.336776 -288.308152)
						(end 113.35131 -288.381694)
					)
					(xy 113.351056 -288.382456)
					(arc
						(start 113.351056 -288.40303)
						(mid 113.356146 -288.416892)
						(end 113.365026 -288.428684)
					)
				)
			)
		)
		(zone
			(layer "F.Cu")
			(hatch none 0.5)
			(connect_pads
				(clearance 0)
			)
			(min_thickness 0.25)
			(keepout
				(tracks not_allowed)
				(vias allowed)
				(pads allowed)
				(copperpour not_allowed)
				(footprints allowed)
			)
			(placement
				(enabled no)
				(sheetname "")
			)
			(fill
				(thermal_gap 0.5)
				(thermal_bridge_width 0.5)
				(island_removal_mode 0)
			)
			(polygon
				(pts
					(arc
						(start 114.254534 -215.111076)
						(mid 114.218631 -215.096241)
						(end 114.182652 -215.111076)
					)
					(arc
						(start 114.182652 -215.111076)
						(mid 114.171301 -215.128198)
						(end 114.167666 -215.148414)
					)
					(arc
						(start 114.167666 -215.148414)
						(mid 114.187935 -215.265643)
						(end 114.253264 -215.365076)
					)
					(arc
						(start 114.253264 -215.365076)
						(mid 114.459766 -215.450612)
						(end 114.666268 -215.365076)
					)
					(arc
						(start 114.666268 -215.365076)
						(mid 114.731009 -215.266801)
						(end 114.751612 -215.150954)
					)
					(arc
						(start 114.751612 -215.150954)
						(mid 114.748412 -215.129945)
						(end 114.73688 -215.112092)
					)
					(arc
						(start 114.73688 -215.112092)
						(mid 114.700977 -215.097257)
						(end 114.664998 -215.112092)
					)
					(arc
						(start 114.664998 -215.112092)
						(mid 114.656275 -215.123788)
						(end 114.651282 -215.137492)
					)
					(xy 114.651282 -215.15832) (xy 114.651282 -215.158828)
					(arc
						(start 114.651282 -215.159844)
						(mid 114.636397 -215.232413)
						(end 114.595148 -215.293956)
					)
					(arc
						(start 114.595148 -215.293956)
						(mid 114.459766 -215.350033)
						(end 114.324384 -215.293956)
					)
					(arc
						(start 114.324384 -215.293956)
						(mid 114.282784 -215.231608)
						(end 114.26825 -215.158066)
					)
					(xy 114.268504 -215.157304)
					(arc
						(start 114.268504 -215.13673)
						(mid 114.263414 -215.122868)
						(end 114.254534 -215.111076)
					)
				)
			)
		)
		(zone
			(layer "F.Cu")
			(hatch none 0.5)
			(connect_pads
				(clearance 0)
			)
			(min_thickness 0.25)
			(keepout
				(tracks not_allowed)
				(vias allowed)
				(pads allowed)
				(copperpour not_allowed)
				(footprints allowed)
			)
			(placement
				(enabled no)
				(sheetname "")
			)
			(fill
				(thermal_gap 0.5)
				(thermal_bridge_width 0.5)
				(island_removal_mode 0)
			)
			(polygon
				(pts
					(arc
						(start 114.30508 -288.428684)
						(mid 114.340894 -288.443519)
						(end 114.376708 -288.428684)
					)
					(arc
						(start 114.376708 -288.428684)
						(mid 114.388059 -288.411562)
						(end 114.391694 -288.391346)
					)
					(arc
						(start 114.391694 -288.391346)
						(mid 114.371545 -288.274145)
						(end 114.30635 -288.174684)
					)
					(arc
						(start 114.30635 -288.174684)
						(mid 114.099848 -288.089148)
						(end 113.893346 -288.174684)
					)
					(arc
						(start 113.893346 -288.174684)
						(mid 113.828464 -288.272928)
						(end 113.807748 -288.388806)
					)
					(arc
						(start 113.807748 -288.388806)
						(mid 113.810936 -288.409828)
						(end 113.82248 -288.427668)
					)
					(arc
						(start 113.82248 -288.427668)
						(mid 113.858458 -288.442682)
						(end 113.894362 -288.427668)
					)
					(arc
						(start 113.894362 -288.427668)
						(mid 113.903085 -288.415972)
						(end 113.908078 -288.402268)
					)
					(xy 113.908078 -288.38144) (xy 113.908078 -288.380932)
					(arc
						(start 113.908078 -288.379916)
						(mid 113.92308 -288.307318)
						(end 113.964466 -288.245804)
					)
					(arc
						(start 113.964466 -288.245804)
						(mid 114.099848 -288.189727)
						(end 114.23523 -288.245804)
					)
					(arc
						(start 114.23523 -288.245804)
						(mid 114.27683 -288.308152)
						(end 114.291364 -288.381694)
					)
					(xy 114.29111 -288.382456)
					(arc
						(start 114.29111 -288.40303)
						(mid 114.2962 -288.416892)
						(end 114.30508 -288.428684)
					)
				)
			)
		)
		(zone
			(layer "F.Cu")
			(hatch none 0.5)
			(connect_pads
				(clearance 0)
			)
			(min_thickness 0.25)
			(keepout
				(tracks not_allowed)
				(vias allowed)
				(pads allowed)
				(copperpour not_allowed)
				(footprints allowed)
			)
			(placement
				(enabled no)
				(sheetname "")
			)
			(fill
				(thermal_gap 0.5)
				(thermal_bridge_width 0.5)
				(island_removal_mode 0)
			)
			(polygon
				(pts
					(arc
						(start 114.724434 -214.297006)
						(mid 114.68853 -214.282246)
						(end 114.652552 -214.297006)
					)
					(arc
						(start 114.652552 -214.297006)
						(mid 114.641153 -214.314246)
						(end 114.637566 -214.334598)
					)
					(arc
						(start 114.637566 -214.334598)
						(mid 114.657835 -214.451827)
						(end 114.723164 -214.55126)
					)
					(arc
						(start 114.723164 -214.55126)
						(mid 114.929666 -214.636796)
						(end 115.136168 -214.55126)
					)
					(arc
						(start 115.136168 -214.55126)
						(mid 115.200957 -214.452867)
						(end 115.221512 -214.336884)
					)
					(arc
						(start 115.221512 -214.336884)
						(mid 115.218312 -214.315875)
						(end 115.20678 -214.298022)
					)
					(arc
						(start 115.20678 -214.298022)
						(mid 115.170876 -214.283262)
						(end 115.134898 -214.298022)
					)
					(arc
						(start 115.134898 -214.298022)
						(mid 115.126156 -214.309843)
						(end 115.121182 -214.323676)
					)
					(xy 115.121182 -214.344504) (xy 115.121182 -214.344758)
					(arc
						(start 115.121182 -214.345774)
						(mid 115.106344 -214.418479)
						(end 115.065048 -214.48014)
					)
					(arc
						(start 115.065048 -214.48014)
						(mid 114.929666 -214.536217)
						(end 114.794284 -214.48014)
					)
					(arc
						(start 114.794284 -214.48014)
						(mid 114.752635 -214.417674)
						(end 114.73815 -214.343996)
					)
					(xy 114.738404 -214.343488)
					(arc
						(start 114.738404 -214.322914)
						(mid 114.733348 -214.308916)
						(end 114.724434 -214.297006)
					)
				)
			)
		)
		(zone
			(layer "F.Cu")
			(hatch none 0.5)
			(connect_pads
				(clearance 0)
			)
			(min_thickness 0.25)
			(keepout
				(tracks not_allowed)
				(vias allowed)
				(pads allowed)
				(copperpour not_allowed)
				(footprints allowed)
			)
			(placement
				(enabled no)
				(sheetname "")
			)
			(fill
				(thermal_gap 0.5)
				(thermal_bridge_width 0.5)
				(island_removal_mode 0)
			)
			(polygon
				(pts
					(arc
						(start 115.24488 -288.428684)
						(mid 115.280694 -288.443519)
						(end 115.316508 -288.428684)
					)
					(arc
						(start 115.316508 -288.428684)
						(mid 115.327859 -288.411562)
						(end 115.331494 -288.391346)
					)
					(arc
						(start 115.331494 -288.391346)
						(mid 115.311345 -288.274145)
						(end 115.24615 -288.174684)
					)
					(arc
						(start 115.24615 -288.174684)
						(mid 115.039648 -288.089148)
						(end 114.833146 -288.174684)
					)
					(arc
						(start 114.833146 -288.174684)
						(mid 114.768264 -288.272928)
						(end 114.747548 -288.388806)
					)
					(arc
						(start 114.747548 -288.388806)
						(mid 114.750736 -288.409828)
						(end 114.76228 -288.427668)
					)
					(arc
						(start 114.76228 -288.427668)
						(mid 114.798258 -288.442682)
						(end 114.834162 -288.427668)
					)
					(arc
						(start 114.834162 -288.427668)
						(mid 114.842885 -288.415972)
						(end 114.847878 -288.402268)
					)
					(xy 114.847878 -288.38144) (xy 114.847878 -288.380932)
					(arc
						(start 114.847878 -288.379916)
						(mid 114.86288 -288.307318)
						(end 114.904266 -288.245804)
					)
					(arc
						(start 114.904266 -288.245804)
						(mid 115.039648 -288.189727)
						(end 115.17503 -288.245804)
					)
					(arc
						(start 115.17503 -288.245804)
						(mid 115.21663 -288.308152)
						(end 115.231164 -288.381694)
					)
					(xy 115.23091 -288.382456)
					(arc
						(start 115.23091 -288.40303)
						(mid 115.236 -288.416892)
						(end 115.24488 -288.428684)
					)
				)
			)
		)
		(zone
			(layer "F.Cu")
			(hatch none 0.5)
			(connect_pads
				(clearance 0)
			)
			(min_thickness 0.25)
			(keepout
				(tracks not_allowed)
				(vias allowed)
				(pads allowed)
				(copperpour not_allowed)
				(footprints allowed)
			)
			(placement
				(enabled no)
				(sheetname "")
			)
			(fill
				(thermal_gap 0.5)
				(thermal_bridge_width 0.5)
				(island_removal_mode 0)
			)
			(polygon
				(pts
					(arc
						(start 115.664234 -214.297006)
						(mid 115.62833 -214.282246)
						(end 115.592352 -214.297006)
					)
					(arc
						(start 115.592352 -214.297006)
						(mid 115.580953 -214.314246)
						(end 115.577366 -214.334598)
					)
					(arc
						(start 115.577366 -214.334598)
						(mid 115.597635 -214.451827)
						(end 115.662964 -214.55126)
					)
					(arc
						(start 115.662964 -214.55126)
						(mid 115.869466 -214.636796)
						(end 116.075968 -214.55126)
					)
					(arc
						(start 116.075968 -214.55126)
						(mid 116.140757 -214.452867)
						(end 116.161312 -214.336884)
					)
					(arc
						(start 116.161312 -214.336884)
						(mid 116.158112 -214.315875)
						(end 116.14658 -214.298022)
					)
					(arc
						(start 116.14658 -214.298022)
						(mid 116.110676 -214.283262)
						(end 116.074698 -214.298022)
					)
					(arc
						(start 116.074698 -214.298022)
						(mid 116.065956 -214.309843)
						(end 116.060982 -214.323676)
					)
					(xy 116.060982 -214.344504) (xy 116.060982 -214.344758)
					(arc
						(start 116.060982 -214.345774)
						(mid 116.046144 -214.418479)
						(end 116.004848 -214.48014)
					)
					(arc
						(start 116.004848 -214.48014)
						(mid 115.869466 -214.536217)
						(end 115.734084 -214.48014)
					)
					(arc
						(start 115.734084 -214.48014)
						(mid 115.692435 -214.417674)
						(end 115.67795 -214.343996)
					)
					(xy 115.678204 -214.343488)
					(arc
						(start 115.678204 -214.322914)
						(mid 115.673148 -214.308916)
						(end 115.664234 -214.297006)
					)
				)
			)
		)
		(zone
			(layer "F.Cu")
			(hatch none 0.5)
			(connect_pads
				(clearance 0)
			)
			(min_thickness 0.25)
			(keepout
				(tracks not_allowed)
				(vias allowed)
				(pads allowed)
				(copperpour not_allowed)
				(footprints allowed)
			)
			(placement
				(enabled no)
				(sheetname "")
			)
			(fill
				(thermal_gap 0.5)
				(thermal_bridge_width 0.5)
				(island_removal_mode 0)
			)
			(polygon
				(pts
					(arc
						(start 115.714526 -289.242754)
						(mid 115.750504 -289.257694)
						(end 115.786408 -289.242754)
					)
					(arc
						(start 115.786408 -289.242754)
						(mid 115.797807 -289.225514)
						(end 115.801394 -289.205162)
					)
					(arc
						(start 115.801394 -289.205162)
						(mid 115.781125 -289.087933)
						(end 115.715796 -288.9885)
					)
					(arc
						(start 115.715796 -288.9885)
						(mid 115.509294 -288.902964)
						(end 115.302792 -288.9885)
					)
					(arc
						(start 115.302792 -288.9885)
						(mid 115.238003 -289.086893)
						(end 115.217448 -289.202876)
					)
					(arc
						(start 115.217448 -289.202876)
						(mid 115.220648 -289.223885)
						(end 115.23218 -289.241738)
					)
					(arc
						(start 115.23218 -289.241738)
						(mid 115.268158 -289.256678)
						(end 115.304062 -289.241738)
					)
					(arc
						(start 115.304062 -289.241738)
						(mid 115.312804 -289.229917)
						(end 115.317778 -289.216084)
					)
					(xy 115.317778 -289.195256) (xy 115.317778 -289.195002)
					(arc
						(start 115.317778 -289.193986)
						(mid 115.332616 -289.121281)
						(end 115.373912 -289.05962)
					)
					(arc
						(start 115.373912 -289.05962)
						(mid 115.509294 -289.003543)
						(end 115.644676 -289.05962)
					)
					(arc
						(start 115.644676 -289.05962)
						(mid 115.686325 -289.122086)
						(end 115.70081 -289.195764)
					)
					(xy 115.700556 -289.196272)
					(arc
						(start 115.700556 -289.216846)
						(mid 115.705612 -289.230844)
						(end 115.714526 -289.242754)
					)
				)
			)
		)
		(zone
			(layer "F.Cu")
			(hatch none 0.5)
			(connect_pads
				(clearance 0)
			)
			(min_thickness 0.25)
			(keepout
				(tracks not_allowed)
				(vias allowed)
				(pads allowed)
				(copperpour not_allowed)
				(footprints allowed)
			)
			(placement
				(enabled no)
				(sheetname "")
			)
			(fill
				(thermal_gap 0.5)
				(thermal_bridge_width 0.5)
				(island_removal_mode 0)
			)
			(polygon
				(pts
					(arc
						(start 116.604034 -214.297006)
						(mid 116.56813 -214.282246)
						(end 116.532152 -214.297006)
					)
					(arc
						(start 116.532152 -214.297006)
						(mid 116.520753 -214.314246)
						(end 116.517166 -214.334598)
					)
					(arc
						(start 116.517166 -214.334598)
						(mid 116.537435 -214.451827)
						(end 116.602764 -214.55126)
					)
					(arc
						(start 116.602764 -214.55126)
						(mid 116.809266 -214.636796)
						(end 117.015768 -214.55126)
					)
					(arc
						(start 117.015768 -214.55126)
						(mid 117.080557 -214.452867)
						(end 117.101112 -214.336884)
					)
					(arc
						(start 117.101112 -214.336884)
						(mid 117.097912 -214.315875)
						(end 117.08638 -214.298022)
					)
					(arc
						(start 117.08638 -214.298022)
						(mid 117.050476 -214.283262)
						(end 117.014498 -214.298022)
					)
					(arc
						(start 117.014498 -214.298022)
						(mid 117.005756 -214.309843)
						(end 117.000782 -214.323676)
					)
					(xy 117.000782 -214.344504) (xy 117.000782 -214.344758)
					(arc
						(start 117.000782 -214.345774)
						(mid 116.985944 -214.418479)
						(end 116.944648 -214.48014)
					)
					(arc
						(start 116.944648 -214.48014)
						(mid 116.809266 -214.536217)
						(end 116.673884 -214.48014)
					)
					(arc
						(start 116.673884 -214.48014)
						(mid 116.632235 -214.417674)
						(end 116.61775 -214.343996)
					)
					(xy 116.618004 -214.343488)
					(arc
						(start 116.618004 -214.322914)
						(mid 116.612948 -214.308916)
						(end 116.604034 -214.297006)
					)
				)
			)
		)
		(zone
			(layer "F.Cu")
			(hatch none 0.5)
			(connect_pads
				(clearance 0)
			)
			(min_thickness 0.25)
			(keepout
				(tracks not_allowed)
				(vias allowed)
				(pads allowed)
				(copperpour not_allowed)
				(footprints allowed)
			)
			(placement
				(enabled no)
				(sheetname "")
			)
			(fill
				(thermal_gap 0.5)
				(thermal_bridge_width 0.5)
				(island_removal_mode 0)
			)
			(polygon
				(pts
					(arc
						(start 116.654326 -289.242754)
						(mid 116.690304 -289.257694)
						(end 116.726208 -289.242754)
					)
					(arc
						(start 116.726208 -289.242754)
						(mid 116.737607 -289.225514)
						(end 116.741194 -289.205162)
					)
					(arc
						(start 116.741194 -289.205162)
						(mid 116.720925 -289.087933)
						(end 116.655596 -288.9885)
					)
					(arc
						(start 116.655596 -288.9885)
						(mid 116.449094 -288.902964)
						(end 116.242592 -288.9885)
					)
					(arc
						(start 116.242592 -288.9885)
						(mid 116.177803 -289.086893)
						(end 116.157248 -289.202876)
					)
					(arc
						(start 116.157248 -289.202876)
						(mid 116.160448 -289.223885)
						(end 116.17198 -289.241738)
					)
					(arc
						(start 116.17198 -289.241738)
						(mid 116.207958 -289.256678)
						(end 116.243862 -289.241738)
					)
					(arc
						(start 116.243862 -289.241738)
						(mid 116.252604 -289.229917)
						(end 116.257578 -289.216084)
					)
					(xy 116.257578 -289.195256) (xy 116.257578 -289.195002)
					(arc
						(start 116.257578 -289.193986)
						(mid 116.272416 -289.121281)
						(end 116.313712 -289.05962)
					)
					(arc
						(start 116.313712 -289.05962)
						(mid 116.449094 -289.003543)
						(end 116.584476 -289.05962)
					)
					(arc
						(start 116.584476 -289.05962)
						(mid 116.626125 -289.122086)
						(end 116.64061 -289.195764)
					)
					(xy 116.640356 -289.196272)
					(arc
						(start 116.640356 -289.216846)
						(mid 116.645412 -289.230844)
						(end 116.654326 -289.242754)
					)
				)
			)
		)
		(zone
			(layer "F.Cu")
			(hatch none 0.5)
			(connect_pads
				(clearance 0)
			)
			(min_thickness 0.25)
			(keepout
				(tracks not_allowed)
				(vias allowed)
				(pads allowed)
				(copperpour not_allowed)
				(footprints allowed)
			)
			(placement
				(enabled no)
				(sheetname "")
			)
			(fill
				(thermal_gap 0.5)
				(thermal_bridge_width 0.5)
				(island_removal_mode 0)
			)
			(polygon
				(pts
					(arc
						(start 117.543834 -214.297006)
						(mid 117.50793 -214.282246)
						(end 117.471952 -214.297006)
					)
					(arc
						(start 117.471952 -214.297006)
						(mid 117.460553 -214.314246)
						(end 117.456966 -214.334598)
					)
					(arc
						(start 117.456966 -214.334598)
						(mid 117.477235 -214.451827)
						(end 117.542564 -214.55126)
					)
					(arc
						(start 117.542564 -214.55126)
						(mid 117.749066 -214.636796)
						(end 117.955568 -214.55126)
					)
					(arc
						(start 117.955568 -214.55126)
						(mid 118.020357 -214.452867)
						(end 118.040912 -214.336884)
					)
					(arc
						(start 118.040912 -214.336884)
						(mid 118.037712 -214.315875)
						(end 118.02618 -214.298022)
					)
					(arc
						(start 118.02618 -214.298022)
						(mid 117.990276 -214.283262)
						(end 117.954298 -214.298022)
					)
					(arc
						(start 117.954298 -214.298022)
						(mid 117.945556 -214.309843)
						(end 117.940582 -214.323676)
					)
					(xy 117.940582 -214.344504) (xy 117.940582 -214.344758)
					(arc
						(start 117.940582 -214.345774)
						(mid 117.925744 -214.418479)
						(end 117.884448 -214.48014)
					)
					(arc
						(start 117.884448 -214.48014)
						(mid 117.749066 -214.536217)
						(end 117.613684 -214.48014)
					)
					(arc
						(start 117.613684 -214.48014)
						(mid 117.572035 -214.417674)
						(end 117.55755 -214.343996)
					)
					(xy 117.557804 -214.343488)
					(arc
						(start 117.557804 -214.322914)
						(mid 117.552748 -214.308916)
						(end 117.543834 -214.297006)
					)
				)
			)
		)
		(zone
			(layer "F.Cu")
			(hatch none 0.5)
			(connect_pads
				(clearance 0)
			)
			(min_thickness 0.25)
			(keepout
				(tracks not_allowed)
				(vias allowed)
				(pads allowed)
				(copperpour not_allowed)
				(footprints allowed)
			)
			(placement
				(enabled no)
				(sheetname "")
			)
			(fill
				(thermal_gap 0.5)
				(thermal_bridge_width 0.5)
				(island_removal_mode 0)
			)
			(polygon
				(pts
					(arc
						(start 117.594126 -289.242754)
						(mid 117.630104 -289.257694)
						(end 117.666008 -289.242754)
					)
					(arc
						(start 117.666008 -289.242754)
						(mid 117.677407 -289.225514)
						(end 117.680994 -289.205162)
					)
					(arc
						(start 117.680994 -289.205162)
						(mid 117.660725 -289.087933)
						(end 117.595396 -288.9885)
					)
					(arc
						(start 117.595396 -288.9885)
						(mid 117.388894 -288.902964)
						(end 117.182392 -288.9885)
					)
					(arc
						(start 117.182392 -288.9885)
						(mid 117.117603 -289.086893)
						(end 117.097048 -289.202876)
					)
					(arc
						(start 117.097048 -289.202876)
						(mid 117.100248 -289.223885)
						(end 117.11178 -289.241738)
					)
					(arc
						(start 117.11178 -289.241738)
						(mid 117.147758 -289.256678)
						(end 117.183662 -289.241738)
					)
					(arc
						(start 117.183662 -289.241738)
						(mid 117.192404 -289.229917)
						(end 117.197378 -289.216084)
					)
					(xy 117.197378 -289.195256) (xy 117.197378 -289.195002)
					(arc
						(start 117.197378 -289.193986)
						(mid 117.212216 -289.121281)
						(end 117.253512 -289.05962)
					)
					(arc
						(start 117.253512 -289.05962)
						(mid 117.388894 -289.003543)
						(end 117.524276 -289.05962)
					)
					(arc
						(start 117.524276 -289.05962)
						(mid 117.565925 -289.122086)
						(end 117.58041 -289.195764)
					)
					(xy 117.580156 -289.196272)
					(arc
						(start 117.580156 -289.216846)
						(mid 117.585212 -289.230844)
						(end 117.594126 -289.242754)
					)
				)
			)
		)
		(zone
			(layer "F.Cu")
			(hatch none 0.5)
			(connect_pads
				(clearance 0)
			)
			(min_thickness 0.25)
			(keepout
				(tracks not_allowed)
				(vias allowed)
				(pads allowed)
				(copperpour not_allowed)
				(footprints allowed)
			)
			(placement
				(enabled no)
				(sheetname "")
			)
			(fill
				(thermal_gap 0.5)
				(thermal_bridge_width 0.5)
				(island_removal_mode 0)
			)
			(polygon
				(pts
					(arc
						(start 118.483634 -214.297006)
						(mid 118.44773 -214.282246)
						(end 118.411752 -214.297006)
					)
					(arc
						(start 118.411752 -214.297006)
						(mid 118.400353 -214.314246)
						(end 118.396766 -214.334598)
					)
					(arc
						(start 118.396766 -214.334598)
						(mid 118.417035 -214.451827)
						(end 118.482364 -214.55126)
					)
					(arc
						(start 118.482364 -214.55126)
						(mid 118.688866 -214.636796)
						(end 118.895368 -214.55126)
					)
					(arc
						(start 118.895368 -214.55126)
						(mid 118.960157 -214.452867)
						(end 118.980712 -214.336884)
					)
					(arc
						(start 118.980712 -214.336884)
						(mid 118.977512 -214.315875)
						(end 118.96598 -214.298022)
					)
					(arc
						(start 118.96598 -214.298022)
						(mid 118.930076 -214.283262)
						(end 118.894098 -214.298022)
					)
					(arc
						(start 118.894098 -214.298022)
						(mid 118.885356 -214.309843)
						(end 118.880382 -214.323676)
					)
					(xy 118.880382 -214.344504) (xy 118.880382 -214.344758)
					(arc
						(start 118.880382 -214.345774)
						(mid 118.865544 -214.418479)
						(end 118.824248 -214.48014)
					)
					(arc
						(start 118.824248 -214.48014)
						(mid 118.688866 -214.536217)
						(end 118.553484 -214.48014)
					)
					(arc
						(start 118.553484 -214.48014)
						(mid 118.511835 -214.417674)
						(end 118.49735 -214.343996)
					)
					(xy 118.497604 -214.343488)
					(arc
						(start 118.497604 -214.322914)
						(mid 118.492548 -214.308916)
						(end 118.483634 -214.297006)
					)
				)
			)
		)
		(zone
			(layer "F.Cu")
			(hatch none 0.5)
			(connect_pads
				(clearance 0)
			)
			(min_thickness 0.25)
			(keepout
				(tracks not_allowed)
				(vias allowed)
				(pads allowed)
				(copperpour not_allowed)
				(footprints allowed)
			)
			(placement
				(enabled no)
				(sheetname "")
			)
			(fill
				(thermal_gap 0.5)
				(thermal_bridge_width 0.5)
				(island_removal_mode 0)
			)
			(polygon
				(pts
					(arc
						(start 118.533926 -289.242754)
						(mid 118.569904 -289.257694)
						(end 118.605808 -289.242754)
					)
					(arc
						(start 118.605808 -289.242754)
						(mid 118.617207 -289.225514)
						(end 118.620794 -289.205162)
					)
					(arc
						(start 118.620794 -289.205162)
						(mid 118.600525 -289.087933)
						(end 118.535196 -288.9885)
					)
					(arc
						(start 118.535196 -288.9885)
						(mid 118.328694 -288.902964)
						(end 118.122192 -288.9885)
					)
					(arc
						(start 118.122192 -288.9885)
						(mid 118.057403 -289.086893)
						(end 118.036848 -289.202876)
					)
					(arc
						(start 118.036848 -289.202876)
						(mid 118.040048 -289.223885)
						(end 118.05158 -289.241738)
					)
					(arc
						(start 118.05158 -289.241738)
						(mid 118.087558 -289.256678)
						(end 118.123462 -289.241738)
					)
					(arc
						(start 118.123462 -289.241738)
						(mid 118.132204 -289.229917)
						(end 118.137178 -289.216084)
					)
					(xy 118.137178 -289.195256) (xy 118.137178 -289.195002)
					(arc
						(start 118.137178 -289.193986)
						(mid 118.152016 -289.121281)
						(end 118.193312 -289.05962)
					)
					(arc
						(start 118.193312 -289.05962)
						(mid 118.328694 -289.003543)
						(end 118.464076 -289.05962)
					)
					(arc
						(start 118.464076 -289.05962)
						(mid 118.505725 -289.122086)
						(end 118.52021 -289.195764)
					)
					(xy 118.519956 -289.196272)
					(arc
						(start 118.519956 -289.216846)
						(mid 118.525012 -289.230844)
						(end 118.533926 -289.242754)
					)
				)
			)
		)
		(zone
			(layer "F.Cu")
			(hatch none 0.5)
			(connect_pads
				(clearance 0)
			)
			(min_thickness 0.25)
			(keepout
				(tracks not_allowed)
				(vias allowed)
				(pads allowed)
				(copperpour not_allowed)
				(footprints allowed)
			)
			(placement
				(enabled no)
				(sheetname "")
			)
			(fill
				(thermal_gap 0.5)
				(thermal_bridge_width 0.5)
				(island_removal_mode 0)
			)
			(polygon
				(pts
					(arc
						(start 119.423434 -214.297006)
						(mid 119.38753 -214.282246)
						(end 119.351552 -214.297006)
					)
					(arc
						(start 119.351552 -214.297006)
						(mid 119.340153 -214.314246)
						(end 119.336566 -214.334598)
					)
					(arc
						(start 119.336566 -214.334598)
						(mid 119.356835 -214.451827)
						(end 119.422164 -214.55126)
					)
					(arc
						(start 119.422164 -214.55126)
						(mid 119.628666 -214.636796)
						(end 119.835168 -214.55126)
					)
					(arc
						(start 119.835168 -214.55126)
						(mid 119.899957 -214.452867)
						(end 119.920512 -214.336884)
					)
					(arc
						(start 119.920512 -214.336884)
						(mid 119.917312 -214.315875)
						(end 119.90578 -214.298022)
					)
					(arc
						(start 119.90578 -214.298022)
						(mid 119.869876 -214.283262)
						(end 119.833898 -214.298022)
					)
					(arc
						(start 119.833898 -214.298022)
						(mid 119.825156 -214.309843)
						(end 119.820182 -214.323676)
					)
					(xy 119.820182 -214.344504) (xy 119.820182 -214.344758)
					(arc
						(start 119.820182 -214.345774)
						(mid 119.805344 -214.418479)
						(end 119.764048 -214.48014)
					)
					(arc
						(start 119.764048 -214.48014)
						(mid 119.628666 -214.536217)
						(end 119.493284 -214.48014)
					)
					(arc
						(start 119.493284 -214.48014)
						(mid 119.451635 -214.417674)
						(end 119.43715 -214.343996)
					)
					(xy 119.437404 -214.343488)
					(arc
						(start 119.437404 -214.322914)
						(mid 119.432348 -214.308916)
						(end 119.423434 -214.297006)
					)
				)
			)
		)
		(zone
			(layer "F.Cu")
			(hatch none 0.5)
			(connect_pads
				(clearance 0)
			)
			(min_thickness 0.25)
			(keepout
				(tracks not_allowed)
				(vias allowed)
				(pads allowed)
				(copperpour not_allowed)
				(footprints allowed)
			)
			(placement
				(enabled no)
				(sheetname "")
			)
			(fill
				(thermal_gap 0.5)
				(thermal_bridge_width 0.5)
				(island_removal_mode 0)
			)
			(polygon
				(pts
					(arc
						(start 119.473726 -289.242754)
						(mid 119.509704 -289.257694)
						(end 119.545608 -289.242754)
					)
					(arc
						(start 119.545608 -289.242754)
						(mid 119.557007 -289.225514)
						(end 119.560594 -289.205162)
					)
					(arc
						(start 119.560594 -289.205162)
						(mid 119.540325 -289.087933)
						(end 119.474996 -288.9885)
					)
					(arc
						(start 119.474996 -288.9885)
						(mid 119.268494 -288.902964)
						(end 119.061992 -288.9885)
					)
					(arc
						(start 119.061992 -288.9885)
						(mid 118.997203 -289.086893)
						(end 118.976648 -289.202876)
					)
					(arc
						(start 118.976648 -289.202876)
						(mid 118.979848 -289.223885)
						(end 118.99138 -289.241738)
					)
					(arc
						(start 118.99138 -289.241738)
						(mid 119.027358 -289.256678)
						(end 119.063262 -289.241738)
					)
					(arc
						(start 119.063262 -289.241738)
						(mid 119.072004 -289.229917)
						(end 119.076978 -289.216084)
					)
					(xy 119.076978 -289.195256) (xy 119.076978 -289.195002)
					(arc
						(start 119.076978 -289.193986)
						(mid 119.091816 -289.121281)
						(end 119.133112 -289.05962)
					)
					(arc
						(start 119.133112 -289.05962)
						(mid 119.268494 -289.003543)
						(end 119.403876 -289.05962)
					)
					(arc
						(start 119.403876 -289.05962)
						(mid 119.445525 -289.122086)
						(end 119.46001 -289.195764)
					)
					(xy 119.459756 -289.196272)
					(arc
						(start 119.459756 -289.216846)
						(mid 119.464812 -289.230844)
						(end 119.473726 -289.242754)
					)
				)
			)
		)
		(zone
			(layer "F.Cu")
			(hatch none 0.5)
			(connect_pads
				(clearance 0)
			)
			(min_thickness 0.25)
			(keepout
				(tracks not_allowed)
				(vias allowed)
				(pads allowed)
				(copperpour not_allowed)
				(footprints allowed)
			)
			(placement
				(enabled no)
				(sheetname "")
			)
			(fill
				(thermal_gap 0.5)
				(thermal_bridge_width 0.5)
				(island_removal_mode 0)
			)
			(polygon
				(pts
					(arc
						(start 120.363234 -214.297006)
						(mid 120.32733 -214.282246)
						(end 120.291352 -214.297006)
					)
					(arc
						(start 120.291352 -214.297006)
						(mid 120.279953 -214.314246)
						(end 120.276366 -214.334598)
					)
					(arc
						(start 120.276366 -214.334598)
						(mid 120.296635 -214.451827)
						(end 120.361964 -214.55126)
					)
					(arc
						(start 120.361964 -214.55126)
						(mid 120.568466 -214.636796)
						(end 120.774968 -214.55126)
					)
					(arc
						(start 120.774968 -214.55126)
						(mid 120.839757 -214.452867)
						(end 120.860312 -214.336884)
					)
					(arc
						(start 120.860312 -214.336884)
						(mid 120.857112 -214.315875)
						(end 120.84558 -214.298022)
					)
					(arc
						(start 120.84558 -214.298022)
						(mid 120.809676 -214.283262)
						(end 120.773698 -214.298022)
					)
					(arc
						(start 120.773698 -214.298022)
						(mid 120.764956 -214.309843)
						(end 120.759982 -214.323676)
					)
					(xy 120.759982 -214.344504) (xy 120.759982 -214.344758)
					(arc
						(start 120.759982 -214.345774)
						(mid 120.745144 -214.418479)
						(end 120.703848 -214.48014)
					)
					(arc
						(start 120.703848 -214.48014)
						(mid 120.568466 -214.536217)
						(end 120.433084 -214.48014)
					)
					(arc
						(start 120.433084 -214.48014)
						(mid 120.391435 -214.417674)
						(end 120.37695 -214.343996)
					)
					(xy 120.377204 -214.343488)
					(arc
						(start 120.377204 -214.322914)
						(mid 120.372148 -214.308916)
						(end 120.363234 -214.297006)
					)
				)
			)
		)
		(zone
			(layer "F.Cu")
			(hatch none 0.5)
			(connect_pads
				(clearance 0)
			)
			(min_thickness 0.25)
			(keepout
				(tracks not_allowed)
				(vias allowed)
				(pads allowed)
				(copperpour not_allowed)
				(footprints allowed)
			)
			(placement
				(enabled no)
				(sheetname "")
			)
			(fill
				(thermal_gap 0.5)
				(thermal_bridge_width 0.5)
				(island_removal_mode 0)
			)
			(polygon
				(pts
					(arc
						(start 120.413526 -289.242754)
						(mid 120.449504 -289.257694)
						(end 120.485408 -289.242754)
					)
					(arc
						(start 120.485408 -289.242754)
						(mid 120.496807 -289.225514)
						(end 120.500394 -289.205162)
					)
					(arc
						(start 120.500394 -289.205162)
						(mid 120.480125 -289.087933)
						(end 120.414796 -288.9885)
					)
					(arc
						(start 120.414796 -288.9885)
						(mid 120.208294 -288.902964)
						(end 120.001792 -288.9885)
					)
					(arc
						(start 120.001792 -288.9885)
						(mid 119.937003 -289.086893)
						(end 119.916448 -289.202876)
					)
					(arc
						(start 119.916448 -289.202876)
						(mid 119.919648 -289.223885)
						(end 119.93118 -289.241738)
					)
					(arc
						(start 119.93118 -289.241738)
						(mid 119.967158 -289.256678)
						(end 120.003062 -289.241738)
					)
					(arc
						(start 120.003062 -289.241738)
						(mid 120.011804 -289.229917)
						(end 120.016778 -289.216084)
					)
					(xy 120.016778 -289.195256) (xy 120.016778 -289.195002)
					(arc
						(start 120.016778 -289.193986)
						(mid 120.031616 -289.121281)
						(end 120.072912 -289.05962)
					)
					(arc
						(start 120.072912 -289.05962)
						(mid 120.208294 -289.003543)
						(end 120.343676 -289.05962)
					)
					(arc
						(start 120.343676 -289.05962)
						(mid 120.385325 -289.122086)
						(end 120.39981 -289.195764)
					)
					(xy 120.399556 -289.196272)
					(arc
						(start 120.399556 -289.216846)
						(mid 120.404612 -289.230844)
						(end 120.413526 -289.242754)
					)
				)
			)
		)
		(zone
			(layer "F.Cu")
			(hatch none 0.5)
			(connect_pads
				(clearance 0)
			)
			(min_thickness 0.25)
			(keepout
				(tracks not_allowed)
				(vias allowed)
				(pads allowed)
				(copperpour not_allowed)
				(footprints allowed)
			)
			(placement
				(enabled no)
				(sheetname "")
			)
			(fill
				(thermal_gap 0.5)
				(thermal_bridge_width 0.5)
				(island_removal_mode 0)
			)
			(polygon
				(pts
					(arc
						(start 121.303034 -214.297006)
						(mid 121.26713 -214.282246)
						(end 121.231152 -214.297006)
					)
					(arc
						(start 121.231152 -214.297006)
						(mid 121.219753 -214.314246)
						(end 121.216166 -214.334598)
					)
					(arc
						(start 121.216166 -214.334598)
						(mid 121.236435 -214.451827)
						(end 121.301764 -214.55126)
					)
					(arc
						(start 121.301764 -214.55126)
						(mid 121.508266 -214.636796)
						(end 121.714768 -214.55126)
					)
					(arc
						(start 121.714768 -214.55126)
						(mid 121.779557 -214.452867)
						(end 121.800112 -214.336884)
					)
					(arc
						(start 121.800112 -214.336884)
						(mid 121.796912 -214.315875)
						(end 121.78538 -214.298022)
					)
					(arc
						(start 121.78538 -214.298022)
						(mid 121.749476 -214.283262)
						(end 121.713498 -214.298022)
					)
					(arc
						(start 121.713498 -214.298022)
						(mid 121.704756 -214.309843)
						(end 121.699782 -214.323676)
					)
					(xy 121.699782 -214.344504) (xy 121.699782 -214.344758)
					(arc
						(start 121.699782 -214.345774)
						(mid 121.684944 -214.418479)
						(end 121.643648 -214.48014)
					)
					(arc
						(start 121.643648 -214.48014)
						(mid 121.508266 -214.536217)
						(end 121.372884 -214.48014)
					)
					(arc
						(start 121.372884 -214.48014)
						(mid 121.331235 -214.417674)
						(end 121.31675 -214.343996)
					)
					(xy 121.317004 -214.343488)
					(arc
						(start 121.317004 -214.322914)
						(mid 121.311948 -214.308916)
						(end 121.303034 -214.297006)
					)
				)
			)
		)
		(zone
			(layer "F.Cu")
			(hatch none 0.5)
			(connect_pads
				(clearance 0)
			)
			(min_thickness 0.25)
			(keepout
				(tracks not_allowed)
				(vias allowed)
				(pads allowed)
				(copperpour not_allowed)
				(footprints allowed)
			)
			(placement
				(enabled no)
				(sheetname "")
			)
			(fill
				(thermal_gap 0.5)
				(thermal_bridge_width 0.5)
				(island_removal_mode 0)
			)
			(polygon
				(pts
					(arc
						(start 121.353326 -289.242754)
						(mid 121.389304 -289.257694)
						(end 121.425208 -289.242754)
					)
					(arc
						(start 121.425208 -289.242754)
						(mid 121.436607 -289.225514)
						(end 121.440194 -289.205162)
					)
					(arc
						(start 121.440194 -289.205162)
						(mid 121.419925 -289.087933)
						(end 121.354596 -288.9885)
					)
					(arc
						(start 121.354596 -288.9885)
						(mid 121.148094 -288.902964)
						(end 120.941592 -288.9885)
					)
					(arc
						(start 120.941592 -288.9885)
						(mid 120.876803 -289.086893)
						(end 120.856248 -289.202876)
					)
					(arc
						(start 120.856248 -289.202876)
						(mid 120.859448 -289.223885)
						(end 120.87098 -289.241738)
					)
					(arc
						(start 120.87098 -289.241738)
						(mid 120.906958 -289.256678)
						(end 120.942862 -289.241738)
					)
					(arc
						(start 120.942862 -289.241738)
						(mid 120.951604 -289.229917)
						(end 120.956578 -289.216084)
					)
					(xy 120.956578 -289.195256) (xy 120.956578 -289.195002)
					(arc
						(start 120.956578 -289.193986)
						(mid 120.971416 -289.121281)
						(end 121.012712 -289.05962)
					)
					(arc
						(start 121.012712 -289.05962)
						(mid 121.148094 -289.003543)
						(end 121.283476 -289.05962)
					)
					(arc
						(start 121.283476 -289.05962)
						(mid 121.325125 -289.122086)
						(end 121.33961 -289.195764)
					)
					(xy 121.339356 -289.196272)
					(arc
						(start 121.339356 -289.216846)
						(mid 121.344412 -289.230844)
						(end 121.353326 -289.242754)
					)
				)
			)
		)
		(zone
			(layer "F.Cu")
			(hatch none 0.5)
			(connect_pads
				(clearance 0)
			)
			(min_thickness 0.25)
			(keepout
				(tracks not_allowed)
				(vias allowed)
				(pads allowed)
				(copperpour not_allowed)
				(footprints allowed)
			)
			(placement
				(enabled no)
				(sheetname "")
			)
			(fill
				(thermal_gap 0.5)
				(thermal_bridge_width 0.5)
				(island_removal_mode 0)
			)
			(polygon
				(pts
					(arc
						(start 122.242834 -214.297006)
						(mid 122.20693 -214.282246)
						(end 122.170952 -214.297006)
					)
					(arc
						(start 122.170952 -214.297006)
						(mid 122.159553 -214.314246)
						(end 122.155966 -214.334598)
					)
					(arc
						(start 122.155966 -214.334598)
						(mid 122.176235 -214.451827)
						(end 122.241564 -214.55126)
					)
					(arc
						(start 122.241564 -214.55126)
						(mid 122.448066 -214.636796)
						(end 122.654568 -214.55126)
					)
					(arc
						(start 122.654568 -214.55126)
						(mid 122.719357 -214.452867)
						(end 122.739912 -214.336884)
					)
					(arc
						(start 122.739912 -214.336884)
						(mid 122.736712 -214.315875)
						(end 122.72518 -214.298022)
					)
					(arc
						(start 122.72518 -214.298022)
						(mid 122.689276 -214.283262)
						(end 122.653298 -214.298022)
					)
					(arc
						(start 122.653298 -214.298022)
						(mid 122.644556 -214.309843)
						(end 122.639582 -214.323676)
					)
					(xy 122.639582 -214.344504) (xy 122.639582 -214.344758)
					(arc
						(start 122.639582 -214.345774)
						(mid 122.624744 -214.418479)
						(end 122.583448 -214.48014)
					)
					(arc
						(start 122.583448 -214.48014)
						(mid 122.448066 -214.536217)
						(end 122.312684 -214.48014)
					)
					(arc
						(start 122.312684 -214.48014)
						(mid 122.271035 -214.417674)
						(end 122.25655 -214.343996)
					)
					(xy 122.256804 -214.343488)
					(arc
						(start 122.256804 -214.322914)
						(mid 122.251748 -214.308916)
						(end 122.242834 -214.297006)
					)
				)
			)
		)
		(zone
			(layer "F.Cu")
			(hatch none 0.5)
			(connect_pads
				(clearance 0)
			)
			(min_thickness 0.25)
			(keepout
				(tracks not_allowed)
				(vias allowed)
				(pads allowed)
				(copperpour not_allowed)
				(footprints allowed)
			)
			(placement
				(enabled no)
				(sheetname "")
			)
			(fill
				(thermal_gap 0.5)
				(thermal_bridge_width 0.5)
				(island_removal_mode 0)
			)
			(polygon
				(pts
					(arc
						(start 122.293126 -289.242754)
						(mid 122.329104 -289.257694)
						(end 122.365008 -289.242754)
					)
					(arc
						(start 122.365008 -289.242754)
						(mid 122.376407 -289.225514)
						(end 122.379994 -289.205162)
					)
					(arc
						(start 122.379994 -289.205162)
						(mid 122.359725 -289.087933)
						(end 122.294396 -288.9885)
					)
					(arc
						(start 122.294396 -288.9885)
						(mid 122.087894 -288.902964)
						(end 121.881392 -288.9885)
					)
					(arc
						(start 121.881392 -288.9885)
						(mid 121.816603 -289.086893)
						(end 121.796048 -289.202876)
					)
					(arc
						(start 121.796048 -289.202876)
						(mid 121.799248 -289.223885)
						(end 121.81078 -289.241738)
					)
					(arc
						(start 121.81078 -289.241738)
						(mid 121.846758 -289.256678)
						(end 121.882662 -289.241738)
					)
					(arc
						(start 121.882662 -289.241738)
						(mid 121.891404 -289.229917)
						(end 121.896378 -289.216084)
					)
					(xy 121.896378 -289.195256) (xy 121.896378 -289.195002)
					(arc
						(start 121.896378 -289.193986)
						(mid 121.911216 -289.121281)
						(end 121.952512 -289.05962)
					)
					(arc
						(start 121.952512 -289.05962)
						(mid 122.087894 -289.003543)
						(end 122.223276 -289.05962)
					)
					(arc
						(start 122.223276 -289.05962)
						(mid 122.264925 -289.122086)
						(end 122.27941 -289.195764)
					)
					(xy 122.279156 -289.196272)
					(arc
						(start 122.279156 -289.216846)
						(mid 122.284212 -289.230844)
						(end 122.293126 -289.242754)
					)
				)
			)
		)
		(zone
			(layer "F.Cu")
			(hatch none 0.5)
			(connect_pads
				(clearance 0)
			)
			(min_thickness 0.25)
			(keepout
				(tracks not_allowed)
				(vias allowed)
				(pads allowed)
				(copperpour not_allowed)
				(footprints allowed)
			)
			(placement
				(enabled no)
				(sheetname "")
			)
			(fill
				(thermal_gap 0.5)
				(thermal_bridge_width 0.5)
				(island_removal_mode 0)
			)
			(polygon
				(pts
					(arc
						(start 123.182634 -214.297006)
						(mid 123.14673 -214.282246)
						(end 123.110752 -214.297006)
					)
					(arc
						(start 123.110752 -214.297006)
						(mid 123.099353 -214.314246)
						(end 123.095766 -214.334598)
					)
					(arc
						(start 123.095766 -214.334598)
						(mid 123.116035 -214.451827)
						(end 123.181364 -214.55126)
					)
					(arc
						(start 123.181364 -214.55126)
						(mid 123.387866 -214.636796)
						(end 123.594368 -214.55126)
					)
					(arc
						(start 123.594368 -214.55126)
						(mid 123.659157 -214.452867)
						(end 123.679712 -214.336884)
					)
					(arc
						(start 123.679712 -214.336884)
						(mid 123.676512 -214.315875)
						(end 123.66498 -214.298022)
					)
					(arc
						(start 123.66498 -214.298022)
						(mid 123.629076 -214.283262)
						(end 123.593098 -214.298022)
					)
					(arc
						(start 123.593098 -214.298022)
						(mid 123.584356 -214.309843)
						(end 123.579382 -214.323676)
					)
					(xy 123.579382 -214.344504) (xy 123.579382 -214.344758)
					(arc
						(start 123.579382 -214.345774)
						(mid 123.564544 -214.418479)
						(end 123.523248 -214.48014)
					)
					(arc
						(start 123.523248 -214.48014)
						(mid 123.387866 -214.536217)
						(end 123.252484 -214.48014)
					)
					(arc
						(start 123.252484 -214.48014)
						(mid 123.210835 -214.417674)
						(end 123.19635 -214.343996)
					)
					(xy 123.196604 -214.343488)
					(arc
						(start 123.196604 -214.322914)
						(mid 123.191548 -214.308916)
						(end 123.182634 -214.297006)
					)
				)
			)
		)
		(zone
			(layer "F.Cu")
			(hatch none 0.5)
			(connect_pads
				(clearance 0)
			)
			(min_thickness 0.25)
			(keepout
				(tracks not_allowed)
				(vias allowed)
				(pads allowed)
				(copperpour not_allowed)
				(footprints allowed)
			)
			(placement
				(enabled no)
				(sheetname "")
			)
			(fill
				(thermal_gap 0.5)
				(thermal_bridge_width 0.5)
				(island_removal_mode 0)
			)
			(polygon
				(pts
					(arc
						(start 123.232926 -289.242754)
						(mid 123.268904 -289.257694)
						(end 123.304808 -289.242754)
					)
					(arc
						(start 123.304808 -289.242754)
						(mid 123.316207 -289.225514)
						(end 123.319794 -289.205162)
					)
					(arc
						(start 123.319794 -289.205162)
						(mid 123.299525 -289.087933)
						(end 123.234196 -288.9885)
					)
					(arc
						(start 123.234196 -288.9885)
						(mid 123.027694 -288.902964)
						(end 122.821192 -288.9885)
					)
					(arc
						(start 122.821192 -288.9885)
						(mid 122.756403 -289.086893)
						(end 122.735848 -289.202876)
					)
					(arc
						(start 122.735848 -289.202876)
						(mid 122.739048 -289.223885)
						(end 122.75058 -289.241738)
					)
					(arc
						(start 122.75058 -289.241738)
						(mid 122.786558 -289.256678)
						(end 122.822462 -289.241738)
					)
					(arc
						(start 122.822462 -289.241738)
						(mid 122.831204 -289.229917)
						(end 122.836178 -289.216084)
					)
					(xy 122.836178 -289.195256) (xy 122.836178 -289.195002)
					(arc
						(start 122.836178 -289.193986)
						(mid 122.851016 -289.121281)
						(end 122.892312 -289.05962)
					)
					(arc
						(start 122.892312 -289.05962)
						(mid 123.027694 -289.003543)
						(end 123.163076 -289.05962)
					)
					(arc
						(start 123.163076 -289.05962)
						(mid 123.204725 -289.122086)
						(end 123.21921 -289.195764)
					)
					(xy 123.218956 -289.196272)
					(arc
						(start 123.218956 -289.216846)
						(mid 123.224012 -289.230844)
						(end 123.232926 -289.242754)
					)
				)
			)
		)
		(zone
			(layer "F.Cu")
			(hatch none 0.5)
			(connect_pads
				(clearance 0)
			)
			(min_thickness 0.25)
			(keepout
				(tracks not_allowed)
				(vias allowed)
				(pads allowed)
				(copperpour not_allowed)
				(footprints allowed)
			)
			(placement
				(enabled no)
				(sheetname "")
			)
			(fill
				(thermal_gap 0.5)
				(thermal_bridge_width 0.5)
				(island_removal_mode 0)
			)
			(polygon
				(pts
					(arc
						(start 124.122434 -214.297006)
						(mid 124.08653 -214.282246)
						(end 124.050552 -214.297006)
					)
					(arc
						(start 124.050552 -214.297006)
						(mid 124.039153 -214.314246)
						(end 124.035566 -214.334598)
					)
					(arc
						(start 124.035566 -214.334598)
						(mid 124.055835 -214.451827)
						(end 124.121164 -214.55126)
					)
					(arc
						(start 124.121164 -214.55126)
						(mid 124.327666 -214.636796)
						(end 124.534168 -214.55126)
					)
					(arc
						(start 124.534168 -214.55126)
						(mid 124.598957 -214.452867)
						(end 124.619512 -214.336884)
					)
					(arc
						(start 124.619512 -214.336884)
						(mid 124.616312 -214.315875)
						(end 124.60478 -214.298022)
					)
					(arc
						(start 124.60478 -214.298022)
						(mid 124.568876 -214.283262)
						(end 124.532898 -214.298022)
					)
					(arc
						(start 124.532898 -214.298022)
						(mid 124.524156 -214.309843)
						(end 124.519182 -214.323676)
					)
					(xy 124.519182 -214.344504) (xy 124.519182 -214.344758)
					(arc
						(start 124.519182 -214.345774)
						(mid 124.504344 -214.418479)
						(end 124.463048 -214.48014)
					)
					(arc
						(start 124.463048 -214.48014)
						(mid 124.327666 -214.536217)
						(end 124.192284 -214.48014)
					)
					(arc
						(start 124.192284 -214.48014)
						(mid 124.150635 -214.417674)
						(end 124.13615 -214.343996)
					)
					(xy 124.136404 -214.343488)
					(arc
						(start 124.136404 -214.322914)
						(mid 124.131348 -214.308916)
						(end 124.122434 -214.297006)
					)
				)
			)
		)
		(zone
			(layer "F.Cu")
			(hatch none 0.5)
			(connect_pads
				(clearance 0)
			)
			(min_thickness 0.25)
			(keepout
				(tracks not_allowed)
				(vias allowed)
				(pads allowed)
				(copperpour not_allowed)
				(footprints allowed)
			)
			(placement
				(enabled no)
				(sheetname "")
			)
			(fill
				(thermal_gap 0.5)
				(thermal_bridge_width 0.5)
				(island_removal_mode 0)
			)
			(polygon
				(pts
					(arc
						(start 124.172726 -289.242754)
						(mid 124.208704 -289.257694)
						(end 124.244608 -289.242754)
					)
					(arc
						(start 124.244608 -289.242754)
						(mid 124.256007 -289.225514)
						(end 124.259594 -289.205162)
					)
					(arc
						(start 124.259594 -289.205162)
						(mid 124.239325 -289.087933)
						(end 124.173996 -288.9885)
					)
					(arc
						(start 124.173996 -288.9885)
						(mid 123.967494 -288.902964)
						(end 123.760992 -288.9885)
					)
					(arc
						(start 123.760992 -288.9885)
						(mid 123.696203 -289.086893)
						(end 123.675648 -289.202876)
					)
					(arc
						(start 123.675648 -289.202876)
						(mid 123.678848 -289.223885)
						(end 123.69038 -289.241738)
					)
					(arc
						(start 123.69038 -289.241738)
						(mid 123.726358 -289.256678)
						(end 123.762262 -289.241738)
					)
					(arc
						(start 123.762262 -289.241738)
						(mid 123.771004 -289.229917)
						(end 123.775978 -289.216084)
					)
					(xy 123.775978 -289.195256) (xy 123.775978 -289.195002)
					(arc
						(start 123.775978 -289.193986)
						(mid 123.790816 -289.121281)
						(end 123.832112 -289.05962)
					)
					(arc
						(start 123.832112 -289.05962)
						(mid 123.967494 -289.003543)
						(end 124.102876 -289.05962)
					)
					(arc
						(start 124.102876 -289.05962)
						(mid 124.144525 -289.122086)
						(end 124.15901 -289.195764)
					)
					(xy 124.158756 -289.196272)
					(arc
						(start 124.158756 -289.216846)
						(mid 124.163812 -289.230844)
						(end 124.172726 -289.242754)
					)
				)
			)
		)
		(zone
			(layer "F.Cu")
			(hatch none 0.5)
			(connect_pads
				(clearance 0)
			)
			(min_thickness 0.25)
			(keepout
				(tracks not_allowed)
				(vias allowed)
				(pads allowed)
				(copperpour not_allowed)
				(footprints allowed)
			)
			(placement
				(enabled no)
				(sheetname "")
			)
			(fill
				(thermal_gap 0.5)
				(thermal_bridge_width 0.5)
				(island_removal_mode 0)
			)
			(polygon
				(pts
					(arc
						(start 125.062234 -214.297006)
						(mid 125.02633 -214.282246)
						(end 124.990352 -214.297006)
					)
					(arc
						(start 124.990352 -214.297006)
						(mid 124.978953 -214.314246)
						(end 124.975366 -214.334598)
					)
					(arc
						(start 124.975366 -214.334598)
						(mid 124.995635 -214.451827)
						(end 125.060964 -214.55126)
					)
					(arc
						(start 125.060964 -214.55126)
						(mid 125.267466 -214.636796)
						(end 125.473968 -214.55126)
					)
					(arc
						(start 125.473968 -214.55126)
						(mid 125.538757 -214.452867)
						(end 125.559312 -214.336884)
					)
					(arc
						(start 125.559312 -214.336884)
						(mid 125.556112 -214.315875)
						(end 125.54458 -214.298022)
					)
					(arc
						(start 125.54458 -214.298022)
						(mid 125.508676 -214.283262)
						(end 125.472698 -214.298022)
					)
					(arc
						(start 125.472698 -214.298022)
						(mid 125.463956 -214.309843)
						(end 125.458982 -214.323676)
					)
					(xy 125.458982 -214.344504) (xy 125.458982 -214.344758)
					(arc
						(start 125.458982 -214.345774)
						(mid 125.444144 -214.418479)
						(end 125.402848 -214.48014)
					)
					(arc
						(start 125.402848 -214.48014)
						(mid 125.267466 -214.536217)
						(end 125.132084 -214.48014)
					)
					(arc
						(start 125.132084 -214.48014)
						(mid 125.090435 -214.417674)
						(end 125.07595 -214.343996)
					)
					(xy 125.076204 -214.343488)
					(arc
						(start 125.076204 -214.322914)
						(mid 125.071148 -214.308916)
						(end 125.062234 -214.297006)
					)
				)
			)
		)
		(zone
			(layer "F.Cu")
			(hatch none 0.5)
			(connect_pads
				(clearance 0)
			)
			(min_thickness 0.25)
			(keepout
				(tracks not_allowed)
				(vias allowed)
				(pads allowed)
				(copperpour not_allowed)
				(footprints allowed)
			)
			(placement
				(enabled no)
				(sheetname "")
			)
			(fill
				(thermal_gap 0.5)
				(thermal_bridge_width 0.5)
				(island_removal_mode 0)
			)
			(polygon
				(pts
					(arc
						(start 125.112526 -289.242754)
						(mid 125.148504 -289.257694)
						(end 125.184408 -289.242754)
					)
					(arc
						(start 125.184408 -289.242754)
						(mid 125.195807 -289.225514)
						(end 125.199394 -289.205162)
					)
					(arc
						(start 125.199394 -289.205162)
						(mid 125.179125 -289.087933)
						(end 125.113796 -288.9885)
					)
					(arc
						(start 125.113796 -288.9885)
						(mid 124.907294 -288.902964)
						(end 124.700792 -288.9885)
					)
					(arc
						(start 124.700792 -288.9885)
						(mid 124.636003 -289.086893)
						(end 124.615448 -289.202876)
					)
					(arc
						(start 124.615448 -289.202876)
						(mid 124.618648 -289.223885)
						(end 124.63018 -289.241738)
					)
					(arc
						(start 124.63018 -289.241738)
						(mid 124.666158 -289.256678)
						(end 124.702062 -289.241738)
					)
					(arc
						(start 124.702062 -289.241738)
						(mid 124.710804 -289.229917)
						(end 124.715778 -289.216084)
					)
					(xy 124.715778 -289.195256) (xy 124.715778 -289.195002)
					(arc
						(start 124.715778 -289.193986)
						(mid 124.730616 -289.121281)
						(end 124.771912 -289.05962)
					)
					(arc
						(start 124.771912 -289.05962)
						(mid 124.907294 -289.003543)
						(end 125.042676 -289.05962)
					)
					(arc
						(start 125.042676 -289.05962)
						(mid 125.084325 -289.122086)
						(end 125.09881 -289.195764)
					)
					(xy 125.098556 -289.196272)
					(arc
						(start 125.098556 -289.216846)
						(mid 125.103612 -289.230844)
						(end 125.112526 -289.242754)
					)
				)
			)
		)
		(zone
			(layer "F.Cu")
			(hatch none 0.5)
			(connect_pads
				(clearance 0)
			)
			(min_thickness 0.25)
			(keepout
				(tracks not_allowed)
				(vias allowed)
				(pads allowed)
				(copperpour not_allowed)
				(footprints allowed)
			)
			(placement
				(enabled no)
				(sheetname "")
			)
			(fill
				(thermal_gap 0.5)
				(thermal_bridge_width 0.5)
				(island_removal_mode 0)
			)
			(polygon
				(pts
					(arc
						(start 126.002034 -214.297006)
						(mid 125.96613 -214.282246)
						(end 125.930152 -214.297006)
					)
					(arc
						(start 125.930152 -214.297006)
						(mid 125.918753 -214.314246)
						(end 125.915166 -214.334598)
					)
					(arc
						(start 125.915166 -214.334598)
						(mid 125.935435 -214.451827)
						(end 126.000764 -214.55126)
					)
					(arc
						(start 126.000764 -214.55126)
						(mid 126.207266 -214.636796)
						(end 126.413768 -214.55126)
					)
					(arc
						(start 126.413768 -214.55126)
						(mid 126.478557 -214.452867)
						(end 126.499112 -214.336884)
					)
					(arc
						(start 126.499112 -214.336884)
						(mid 126.495912 -214.315875)
						(end 126.48438 -214.298022)
					)
					(arc
						(start 126.48438 -214.298022)
						(mid 126.448476 -214.283262)
						(end 126.412498 -214.298022)
					)
					(arc
						(start 126.412498 -214.298022)
						(mid 126.403756 -214.309843)
						(end 126.398782 -214.323676)
					)
					(xy 126.398782 -214.344504) (xy 126.398782 -214.344758)
					(arc
						(start 126.398782 -214.345774)
						(mid 126.383944 -214.418479)
						(end 126.342648 -214.48014)
					)
					(arc
						(start 126.342648 -214.48014)
						(mid 126.207266 -214.536217)
						(end 126.071884 -214.48014)
					)
					(arc
						(start 126.071884 -214.48014)
						(mid 126.030235 -214.417674)
						(end 126.01575 -214.343996)
					)
					(xy 126.016004 -214.343488)
					(arc
						(start 126.016004 -214.322914)
						(mid 126.010948 -214.308916)
						(end 126.002034 -214.297006)
					)
				)
			)
		)
		(zone
			(layer "F.Cu")
			(hatch none 0.5)
			(connect_pads
				(clearance 0)
			)
			(min_thickness 0.25)
			(keepout
				(tracks not_allowed)
				(vias allowed)
				(pads allowed)
				(copperpour not_allowed)
				(footprints allowed)
			)
			(placement
				(enabled no)
				(sheetname "")
			)
			(fill
				(thermal_gap 0.5)
				(thermal_bridge_width 0.5)
				(island_removal_mode 0)
			)
			(polygon
				(pts
					(arc
						(start 126.052326 -289.242754)
						(mid 126.088304 -289.257694)
						(end 126.124208 -289.242754)
					)
					(arc
						(start 126.124208 -289.242754)
						(mid 126.135607 -289.225514)
						(end 126.139194 -289.205162)
					)
					(arc
						(start 126.139194 -289.205162)
						(mid 126.118925 -289.087933)
						(end 126.053596 -288.9885)
					)
					(arc
						(start 126.053596 -288.9885)
						(mid 125.847094 -288.902964)
						(end 125.640592 -288.9885)
					)
					(arc
						(start 125.640592 -288.9885)
						(mid 125.575803 -289.086893)
						(end 125.555248 -289.202876)
					)
					(arc
						(start 125.555248 -289.202876)
						(mid 125.558448 -289.223885)
						(end 125.56998 -289.241738)
					)
					(arc
						(start 125.56998 -289.241738)
						(mid 125.605958 -289.256678)
						(end 125.641862 -289.241738)
					)
					(arc
						(start 125.641862 -289.241738)
						(mid 125.650604 -289.229917)
						(end 125.655578 -289.216084)
					)
					(xy 125.655578 -289.195256) (xy 125.655578 -289.195002)
					(arc
						(start 125.655578 -289.193986)
						(mid 125.670416 -289.121281)
						(end 125.711712 -289.05962)
					)
					(arc
						(start 125.711712 -289.05962)
						(mid 125.847094 -289.003543)
						(end 125.982476 -289.05962)
					)
					(arc
						(start 125.982476 -289.05962)
						(mid 126.024125 -289.122086)
						(end 126.03861 -289.195764)
					)
					(xy 126.038356 -289.196272)
					(arc
						(start 126.038356 -289.216846)
						(mid 126.043412 -289.230844)
						(end 126.052326 -289.242754)
					)
				)
			)
		)
		(zone
			(layer "F.Cu")
			(hatch none 0.5)
			(connect_pads
				(clearance 0)
			)
			(min_thickness 0.25)
			(keepout
				(tracks not_allowed)
				(vias allowed)
				(pads allowed)
				(copperpour not_allowed)
				(footprints allowed)
			)
			(placement
				(enabled no)
				(sheetname "")
			)
			(fill
				(thermal_gap 0.5)
				(thermal_bridge_width 0.5)
				(island_removal_mode 0)
			)
			(polygon
				(pts
					(arc
						(start 126.941834 -214.297006)
						(mid 126.90593 -214.282246)
						(end 126.869952 -214.297006)
					)
					(arc
						(start 126.869952 -214.297006)
						(mid 126.858553 -214.314246)
						(end 126.854966 -214.334598)
					)
					(arc
						(start 126.854966 -214.334598)
						(mid 126.875235 -214.451827)
						(end 126.940564 -214.55126)
					)
					(arc
						(start 126.940564 -214.55126)
						(mid 127.147066 -214.636796)
						(end 127.353568 -214.55126)
					)
					(arc
						(start 127.353568 -214.55126)
						(mid 127.418357 -214.452867)
						(end 127.438912 -214.336884)
					)
					(arc
						(start 127.438912 -214.336884)
						(mid 127.435712 -214.315875)
						(end 127.42418 -214.298022)
					)
					(arc
						(start 127.42418 -214.298022)
						(mid 127.388276 -214.283262)
						(end 127.352298 -214.298022)
					)
					(arc
						(start 127.352298 -214.298022)
						(mid 127.343556 -214.309843)
						(end 127.338582 -214.323676)
					)
					(xy 127.338582 -214.344504) (xy 127.338582 -214.344758)
					(arc
						(start 127.338582 -214.345774)
						(mid 127.323744 -214.418479)
						(end 127.282448 -214.48014)
					)
					(arc
						(start 127.282448 -214.48014)
						(mid 127.147066 -214.536217)
						(end 127.011684 -214.48014)
					)
					(arc
						(start 127.011684 -214.48014)
						(mid 126.970035 -214.417674)
						(end 126.95555 -214.343996)
					)
					(xy 126.955804 -214.343488)
					(arc
						(start 126.955804 -214.322914)
						(mid 126.950748 -214.308916)
						(end 126.941834 -214.297006)
					)
				)
			)
		)
		(zone
			(layer "F.Cu")
			(hatch none 0.5)
			(connect_pads
				(clearance 0)
			)
			(min_thickness 0.25)
			(keepout
				(tracks not_allowed)
				(vias allowed)
				(pads allowed)
				(copperpour not_allowed)
				(footprints allowed)
			)
			(placement
				(enabled no)
				(sheetname "")
			)
			(fill
				(thermal_gap 0.5)
				(thermal_bridge_width 0.5)
				(island_removal_mode 0)
			)
			(polygon
				(pts
					(arc
						(start 126.992126 -289.242754)
						(mid 127.028104 -289.257694)
						(end 127.064008 -289.242754)
					)
					(arc
						(start 127.064008 -289.242754)
						(mid 127.075407 -289.225514)
						(end 127.078994 -289.205162)
					)
					(arc
						(start 127.078994 -289.205162)
						(mid 127.058725 -289.087933)
						(end 126.993396 -288.9885)
					)
					(arc
						(start 126.993396 -288.9885)
						(mid 126.786894 -288.902964)
						(end 126.580392 -288.9885)
					)
					(arc
						(start 126.580392 -288.9885)
						(mid 126.515603 -289.086893)
						(end 126.495048 -289.202876)
					)
					(arc
						(start 126.495048 -289.202876)
						(mid 126.498248 -289.223885)
						(end 126.50978 -289.241738)
					)
					(arc
						(start 126.50978 -289.241738)
						(mid 126.545758 -289.256678)
						(end 126.581662 -289.241738)
					)
					(arc
						(start 126.581662 -289.241738)
						(mid 126.590404 -289.229917)
						(end 126.595378 -289.216084)
					)
					(xy 126.595378 -289.195256) (xy 126.595378 -289.195002)
					(arc
						(start 126.595378 -289.193986)
						(mid 126.610216 -289.121281)
						(end 126.651512 -289.05962)
					)
					(arc
						(start 126.651512 -289.05962)
						(mid 126.786894 -289.003543)
						(end 126.922276 -289.05962)
					)
					(arc
						(start 126.922276 -289.05962)
						(mid 126.963925 -289.122086)
						(end 126.97841 -289.195764)
					)
					(xy 126.978156 -289.196272)
					(arc
						(start 126.978156 -289.216846)
						(mid 126.983212 -289.230844)
						(end 126.992126 -289.242754)
					)
				)
			)
		)
		(zone
			(layer "F.Cu")
			(hatch none 0.5)
			(connect_pads
				(clearance 0)
			)
			(min_thickness 0.25)
			(keepout
				(tracks not_allowed)
				(vias allowed)
				(pads allowed)
				(copperpour not_allowed)
				(footprints allowed)
			)
			(placement
				(enabled no)
				(sheetname "")
			)
			(fill
				(thermal_gap 0.5)
				(thermal_bridge_width 0.5)
				(island_removal_mode 0)
			)
			(polygon
				(pts
					(arc
						(start 127.881634 -214.297006)
						(mid 127.84573 -214.282246)
						(end 127.809752 -214.297006)
					)
					(arc
						(start 127.809752 -214.297006)
						(mid 127.798353 -214.314246)
						(end 127.794766 -214.334598)
					)
					(arc
						(start 127.794766 -214.334598)
						(mid 127.815035 -214.451827)
						(end 127.880364 -214.55126)
					)
					(arc
						(start 127.880364 -214.55126)
						(mid 128.086866 -214.636796)
						(end 128.293368 -214.55126)
					)
					(arc
						(start 128.293368 -214.55126)
						(mid 128.358157 -214.452867)
						(end 128.378712 -214.336884)
					)
					(arc
						(start 128.378712 -214.336884)
						(mid 128.375512 -214.315875)
						(end 128.36398 -214.298022)
					)
					(arc
						(start 128.36398 -214.298022)
						(mid 128.328076 -214.283262)
						(end 128.292098 -214.298022)
					)
					(arc
						(start 128.292098 -214.298022)
						(mid 128.283356 -214.309843)
						(end 128.278382 -214.323676)
					)
					(xy 128.278382 -214.344504) (xy 128.278382 -214.344758)
					(arc
						(start 128.278382 -214.345774)
						(mid 128.263544 -214.418479)
						(end 128.222248 -214.48014)
					)
					(arc
						(start 128.222248 -214.48014)
						(mid 128.086866 -214.536217)
						(end 127.951484 -214.48014)
					)
					(arc
						(start 127.951484 -214.48014)
						(mid 127.909835 -214.417674)
						(end 127.89535 -214.343996)
					)
					(xy 127.895604 -214.343488)
					(arc
						(start 127.895604 -214.322914)
						(mid 127.890548 -214.308916)
						(end 127.881634 -214.297006)
					)
				)
			)
		)
		(zone
			(layer "F.Cu")
			(hatch none 0.5)
			(connect_pads
				(clearance 0)
			)
			(min_thickness 0.25)
			(keepout
				(tracks not_allowed)
				(vias allowed)
				(pads allowed)
				(copperpour not_allowed)
				(footprints allowed)
			)
			(placement
				(enabled no)
				(sheetname "")
			)
			(fill
				(thermal_gap 0.5)
				(thermal_bridge_width 0.5)
				(island_removal_mode 0)
			)
			(polygon
				(pts
					(arc
						(start 127.931926 -289.242754)
						(mid 127.967904 -289.257694)
						(end 128.003808 -289.242754)
					)
					(arc
						(start 128.003808 -289.242754)
						(mid 128.015207 -289.225514)
						(end 128.018794 -289.205162)
					)
					(arc
						(start 128.018794 -289.205162)
						(mid 127.998525 -289.087933)
						(end 127.933196 -288.9885)
					)
					(arc
						(start 127.933196 -288.9885)
						(mid 127.726694 -288.902964)
						(end 127.520192 -288.9885)
					)
					(arc
						(start 127.520192 -288.9885)
						(mid 127.455403 -289.086893)
						(end 127.434848 -289.202876)
					)
					(arc
						(start 127.434848 -289.202876)
						(mid 127.438048 -289.223885)
						(end 127.44958 -289.241738)
					)
					(arc
						(start 127.44958 -289.241738)
						(mid 127.485558 -289.256678)
						(end 127.521462 -289.241738)
					)
					(arc
						(start 127.521462 -289.241738)
						(mid 127.530204 -289.229917)
						(end 127.535178 -289.216084)
					)
					(xy 127.535178 -289.195256) (xy 127.535178 -289.195002)
					(arc
						(start 127.535178 -289.193986)
						(mid 127.550016 -289.121281)
						(end 127.591312 -289.05962)
					)
					(arc
						(start 127.591312 -289.05962)
						(mid 127.726694 -289.003543)
						(end 127.862076 -289.05962)
					)
					(arc
						(start 127.862076 -289.05962)
						(mid 127.903725 -289.122086)
						(end 127.91821 -289.195764)
					)
					(xy 127.917956 -289.196272)
					(arc
						(start 127.917956 -289.216846)
						(mid 127.923012 -289.230844)
						(end 127.931926 -289.242754)
					)
				)
			)
		)
		(zone
			(layer "F.Cu")
			(hatch none 0.5)
			(connect_pads
				(clearance 0)
			)
			(min_thickness 0.25)
			(keepout
				(tracks not_allowed)
				(vias allowed)
				(pads allowed)
				(copperpour not_allowed)
				(footprints allowed)
			)
			(placement
				(enabled no)
				(sheetname "")
			)
			(fill
				(thermal_gap 0.5)
				(thermal_bridge_width 0.5)
				(island_removal_mode 0)
			)
			(polygon
				(pts
					(arc
						(start 128.821434 -214.297006)
						(mid 128.78553 -214.282246)
						(end 128.749552 -214.297006)
					)
					(arc
						(start 128.749552 -214.297006)
						(mid 128.738153 -214.314246)
						(end 128.734566 -214.334598)
					)
					(arc
						(start 128.734566 -214.334598)
						(mid 128.754835 -214.451827)
						(end 128.820164 -214.55126)
					)
					(arc
						(start 128.820164 -214.55126)
						(mid 129.026666 -214.636796)
						(end 129.233168 -214.55126)
					)
					(arc
						(start 129.233168 -214.55126)
						(mid 129.297957 -214.452867)
						(end 129.318512 -214.336884)
					)
					(arc
						(start 129.318512 -214.336884)
						(mid 129.315312 -214.315875)
						(end 129.30378 -214.298022)
					)
					(arc
						(start 129.30378 -214.298022)
						(mid 129.267876 -214.283262)
						(end 129.231898 -214.298022)
					)
					(arc
						(start 129.231898 -214.298022)
						(mid 129.223156 -214.309843)
						(end 129.218182 -214.323676)
					)
					(xy 129.218182 -214.344504) (xy 129.218182 -214.344758)
					(arc
						(start 129.218182 -214.345774)
						(mid 129.203344 -214.418479)
						(end 129.162048 -214.48014)
					)
					(arc
						(start 129.162048 -214.48014)
						(mid 129.026666 -214.536217)
						(end 128.891284 -214.48014)
					)
					(arc
						(start 128.891284 -214.48014)
						(mid 128.849635 -214.417674)
						(end 128.83515 -214.343996)
					)
					(xy 128.835404 -214.343488)
					(arc
						(start 128.835404 -214.322914)
						(mid 128.830348 -214.308916)
						(end 128.821434 -214.297006)
					)
				)
			)
		)
		(zone
			(layer "F.Cu")
			(hatch none 0.5)
			(connect_pads
				(clearance 0)
			)
			(min_thickness 0.25)
			(keepout
				(tracks not_allowed)
				(vias allowed)
				(pads allowed)
				(copperpour not_allowed)
				(footprints allowed)
			)
			(placement
				(enabled no)
				(sheetname "")
			)
			(fill
				(thermal_gap 0.5)
				(thermal_bridge_width 0.5)
				(island_removal_mode 0)
			)
			(polygon
				(pts
					(arc
						(start 128.871726 -289.242754)
						(mid 128.907704 -289.257694)
						(end 128.943608 -289.242754)
					)
					(arc
						(start 128.943608 -289.242754)
						(mid 128.955007 -289.225514)
						(end 128.958594 -289.205162)
					)
					(arc
						(start 128.958594 -289.205162)
						(mid 128.938325 -289.087933)
						(end 128.872996 -288.9885)
					)
					(arc
						(start 128.872996 -288.9885)
						(mid 128.666494 -288.902964)
						(end 128.459992 -288.9885)
					)
					(arc
						(start 128.459992 -288.9885)
						(mid 128.395203 -289.086893)
						(end 128.374648 -289.202876)
					)
					(arc
						(start 128.374648 -289.202876)
						(mid 128.377848 -289.223885)
						(end 128.38938 -289.241738)
					)
					(arc
						(start 128.38938 -289.241738)
						(mid 128.425358 -289.256678)
						(end 128.461262 -289.241738)
					)
					(arc
						(start 128.461262 -289.241738)
						(mid 128.470004 -289.229917)
						(end 128.474978 -289.216084)
					)
					(xy 128.474978 -289.195256) (xy 128.474978 -289.195002)
					(arc
						(start 128.474978 -289.193986)
						(mid 128.489816 -289.121281)
						(end 128.531112 -289.05962)
					)
					(arc
						(start 128.531112 -289.05962)
						(mid 128.666494 -289.003543)
						(end 128.801876 -289.05962)
					)
					(arc
						(start 128.801876 -289.05962)
						(mid 128.843525 -289.122086)
						(end 128.85801 -289.195764)
					)
					(xy 128.857756 -289.196272)
					(arc
						(start 128.857756 -289.216846)
						(mid 128.862812 -289.230844)
						(end 128.871726 -289.242754)
					)
				)
			)
		)
		(zone
			(layer "F.Cu")
			(hatch none 0.5)
			(connect_pads
				(clearance 0)
			)
			(min_thickness 0.25)
			(keepout
				(tracks not_allowed)
				(vias allowed)
				(pads allowed)
				(copperpour not_allowed)
				(footprints allowed)
			)
			(placement
				(enabled no)
				(sheetname "")
			)
			(fill
				(thermal_gap 0.5)
				(thermal_bridge_width 0.5)
				(island_removal_mode 0)
			)
			(polygon
				(pts
					(arc
						(start 129.761234 -214.297006)
						(mid 129.72533 -214.282246)
						(end 129.689352 -214.297006)
					)
					(arc
						(start 129.689352 -214.297006)
						(mid 129.677953 -214.314246)
						(end 129.674366 -214.334598)
					)
					(arc
						(start 129.674366 -214.334598)
						(mid 129.694635 -214.451827)
						(end 129.759964 -214.55126)
					)
					(arc
						(start 129.759964 -214.55126)
						(mid 129.966466 -214.636796)
						(end 130.172968 -214.55126)
					)
					(arc
						(start 130.172968 -214.55126)
						(mid 130.237757 -214.452867)
						(end 130.258312 -214.336884)
					)
					(arc
						(start 130.258312 -214.336884)
						(mid 130.255112 -214.315875)
						(end 130.24358 -214.298022)
					)
					(arc
						(start 130.24358 -214.298022)
						(mid 130.207676 -214.283262)
						(end 130.171698 -214.298022)
					)
					(arc
						(start 130.171698 -214.298022)
						(mid 130.162956 -214.309843)
						(end 130.157982 -214.323676)
					)
					(xy 130.157982 -214.344504) (xy 130.157982 -214.344758)
					(arc
						(start 130.157982 -214.345774)
						(mid 130.143144 -214.418479)
						(end 130.101848 -214.48014)
					)
					(arc
						(start 130.101848 -214.48014)
						(mid 129.966466 -214.536217)
						(end 129.831084 -214.48014)
					)
					(arc
						(start 129.831084 -214.48014)
						(mid 129.789435 -214.417674)
						(end 129.77495 -214.343996)
					)
					(xy 129.775204 -214.343488)
					(arc
						(start 129.775204 -214.322914)
						(mid 129.770148 -214.308916)
						(end 129.761234 -214.297006)
					)
				)
			)
		)
		(zone
			(layer "F.Cu")
			(hatch none 0.5)
			(connect_pads
				(clearance 0)
			)
			(min_thickness 0.25)
			(keepout
				(tracks not_allowed)
				(vias allowed)
				(pads allowed)
				(copperpour not_allowed)
				(footprints allowed)
			)
			(placement
				(enabled no)
				(sheetname "")
			)
			(fill
				(thermal_gap 0.5)
				(thermal_bridge_width 0.5)
				(island_removal_mode 0)
			)
			(polygon
				(pts
					(arc
						(start 129.811526 -289.242754)
						(mid 129.847504 -289.257694)
						(end 129.883408 -289.242754)
					)
					(arc
						(start 129.883408 -289.242754)
						(mid 129.894807 -289.225514)
						(end 129.898394 -289.205162)
					)
					(arc
						(start 129.898394 -289.205162)
						(mid 129.878125 -289.087933)
						(end 129.812796 -288.9885)
					)
					(arc
						(start 129.812796 -288.9885)
						(mid 129.606294 -288.902964)
						(end 129.399792 -288.9885)
					)
					(arc
						(start 129.399792 -288.9885)
						(mid 129.335003 -289.086893)
						(end 129.314448 -289.202876)
					)
					(arc
						(start 129.314448 -289.202876)
						(mid 129.317648 -289.223885)
						(end 129.32918 -289.241738)
					)
					(arc
						(start 129.32918 -289.241738)
						(mid 129.365158 -289.256678)
						(end 129.401062 -289.241738)
					)
					(arc
						(start 129.401062 -289.241738)
						(mid 129.409804 -289.229917)
						(end 129.414778 -289.216084)
					)
					(xy 129.414778 -289.195256) (xy 129.414778 -289.195002)
					(arc
						(start 129.414778 -289.193986)
						(mid 129.429616 -289.121281)
						(end 129.470912 -289.05962)
					)
					(arc
						(start 129.470912 -289.05962)
						(mid 129.606294 -289.003543)
						(end 129.741676 -289.05962)
					)
					(arc
						(start 129.741676 -289.05962)
						(mid 129.783325 -289.122086)
						(end 129.79781 -289.195764)
					)
					(xy 129.797556 -289.196272)
					(arc
						(start 129.797556 -289.216846)
						(mid 129.802612 -289.230844)
						(end 129.811526 -289.242754)
					)
				)
			)
		)
		(zone
			(layer "F.Cu")
			(hatch none 0.5)
			(connect_pads
				(clearance 0)
			)
			(min_thickness 0.25)
			(keepout
				(tracks not_allowed)
				(vias allowed)
				(pads allowed)
				(copperpour not_allowed)
				(footprints allowed)
			)
			(placement
				(enabled no)
				(sheetname "")
			)
			(fill
				(thermal_gap 0.5)
				(thermal_bridge_width 0.5)
				(island_removal_mode 0)
			)
			(polygon
				(pts
					(arc
						(start 130.701034 -214.297006)
						(mid 130.66513 -214.282246)
						(end 130.629152 -214.297006)
					)
					(arc
						(start 130.629152 -214.297006)
						(mid 130.617753 -214.314246)
						(end 130.614166 -214.334598)
					)
					(arc
						(start 130.614166 -214.334598)
						(mid 130.634435 -214.451827)
						(end 130.699764 -214.55126)
					)
					(arc
						(start 130.699764 -214.55126)
						(mid 130.906266 -214.636796)
						(end 131.112768 -214.55126)
					)
					(arc
						(start 131.112768 -214.55126)
						(mid 131.177557 -214.452867)
						(end 131.198112 -214.336884)
					)
					(arc
						(start 131.198112 -214.336884)
						(mid 131.194912 -214.315875)
						(end 131.18338 -214.298022)
					)
					(arc
						(start 131.18338 -214.298022)
						(mid 131.147476 -214.283262)
						(end 131.111498 -214.298022)
					)
					(arc
						(start 131.111498 -214.298022)
						(mid 131.102756 -214.309843)
						(end 131.097782 -214.323676)
					)
					(xy 131.097782 -214.344504) (xy 131.097782 -214.344758)
					(arc
						(start 131.097782 -214.345774)
						(mid 131.082944 -214.418479)
						(end 131.041648 -214.48014)
					)
					(arc
						(start 131.041648 -214.48014)
						(mid 130.906266 -214.536217)
						(end 130.770884 -214.48014)
					)
					(arc
						(start 130.770884 -214.48014)
						(mid 130.729235 -214.417674)
						(end 130.71475 -214.343996)
					)
					(xy 130.715004 -214.343488)
					(arc
						(start 130.715004 -214.322914)
						(mid 130.709948 -214.308916)
						(end 130.701034 -214.297006)
					)
				)
			)
		)
		(zone
			(layer "F.Cu")
			(hatch none 0.5)
			(connect_pads
				(clearance 0)
			)
			(min_thickness 0.25)
			(keepout
				(tracks not_allowed)
				(vias allowed)
				(pads allowed)
				(copperpour not_allowed)
				(footprints allowed)
			)
			(placement
				(enabled no)
				(sheetname "")
			)
			(fill
				(thermal_gap 0.5)
				(thermal_bridge_width 0.5)
				(island_removal_mode 0)
			)
			(polygon
				(pts
					(arc
						(start 130.751326 -289.242754)
						(mid 130.787304 -289.257694)
						(end 130.823208 -289.242754)
					)
					(arc
						(start 130.823208 -289.242754)
						(mid 130.834607 -289.225514)
						(end 130.838194 -289.205162)
					)
					(arc
						(start 130.838194 -289.205162)
						(mid 130.817925 -289.087933)
						(end 130.752596 -288.9885)
					)
					(arc
						(start 130.752596 -288.9885)
						(mid 130.546094 -288.902964)
						(end 130.339592 -288.9885)
					)
					(arc
						(start 130.339592 -288.9885)
						(mid 130.274803 -289.086893)
						(end 130.254248 -289.202876)
					)
					(arc
						(start 130.254248 -289.202876)
						(mid 130.257448 -289.223885)
						(end 130.26898 -289.241738)
					)
					(arc
						(start 130.26898 -289.241738)
						(mid 130.304958 -289.256678)
						(end 130.340862 -289.241738)
					)
					(arc
						(start 130.340862 -289.241738)
						(mid 130.349604 -289.229917)
						(end 130.354578 -289.216084)
					)
					(xy 130.354578 -289.195256) (xy 130.354578 -289.195002)
					(arc
						(start 130.354578 -289.193986)
						(mid 130.369416 -289.121281)
						(end 130.410712 -289.05962)
					)
					(arc
						(start 130.410712 -289.05962)
						(mid 130.546094 -289.003543)
						(end 130.681476 -289.05962)
					)
					(arc
						(start 130.681476 -289.05962)
						(mid 130.723125 -289.122086)
						(end 130.73761 -289.195764)
					)
					(xy 130.737356 -289.196272)
					(arc
						(start 130.737356 -289.216846)
						(mid 130.742412 -289.230844)
						(end 130.751326 -289.242754)
					)
				)
			)
		)
		(zone
			(layer "F.Cu")
			(hatch none 0.5)
			(connect_pads
				(clearance 0)
			)
			(min_thickness 0.25)
			(keepout
				(tracks not_allowed)
				(vias allowed)
				(pads allowed)
				(copperpour not_allowed)
				(footprints allowed)
			)
			(placement
				(enabled no)
				(sheetname "")
			)
			(fill
				(thermal_gap 0.5)
				(thermal_bridge_width 0.5)
				(island_removal_mode 0)
			)
			(polygon
				(pts
					(arc
						(start 131.640834 -214.297006)
						(mid 131.60493 -214.282246)
						(end 131.568952 -214.297006)
					)
					(arc
						(start 131.568952 -214.297006)
						(mid 131.557553 -214.314246)
						(end 131.553966 -214.334598)
					)
					(arc
						(start 131.553966 -214.334598)
						(mid 131.574235 -214.451827)
						(end 131.639564 -214.55126)
					)
					(arc
						(start 131.639564 -214.55126)
						(mid 131.846066 -214.636796)
						(end 132.052568 -214.55126)
					)
					(arc
						(start 132.052568 -214.55126)
						(mid 132.117357 -214.452867)
						(end 132.137912 -214.336884)
					)
					(arc
						(start 132.137912 -214.336884)
						(mid 132.134712 -214.315875)
						(end 132.12318 -214.298022)
					)
					(arc
						(start 132.12318 -214.298022)
						(mid 132.087276 -214.283262)
						(end 132.051298 -214.298022)
					)
					(arc
						(start 132.051298 -214.298022)
						(mid 132.042556 -214.309843)
						(end 132.037582 -214.323676)
					)
					(xy 132.037582 -214.344504) (xy 132.037582 -214.344758)
					(arc
						(start 132.037582 -214.345774)
						(mid 132.022744 -214.418479)
						(end 131.981448 -214.48014)
					)
					(arc
						(start 131.981448 -214.48014)
						(mid 131.846066 -214.536217)
						(end 131.710684 -214.48014)
					)
					(arc
						(start 131.710684 -214.48014)
						(mid 131.669035 -214.417674)
						(end 131.65455 -214.343996)
					)
					(xy 131.654804 -214.343488)
					(arc
						(start 131.654804 -214.322914)
						(mid 131.649748 -214.308916)
						(end 131.640834 -214.297006)
					)
				)
			)
		)
		(zone
			(layer "F.Cu")
			(hatch none 0.5)
			(connect_pads
				(clearance 0)
			)
			(min_thickness 0.25)
			(keepout
				(tracks not_allowed)
				(vias allowed)
				(pads allowed)
				(copperpour not_allowed)
				(footprints allowed)
			)
			(placement
				(enabled no)
				(sheetname "")
			)
			(fill
				(thermal_gap 0.5)
				(thermal_bridge_width 0.5)
				(island_removal_mode 0)
			)
			(polygon
				(pts
					(arc
						(start 131.691126 -289.242754)
						(mid 131.727104 -289.257694)
						(end 131.763008 -289.242754)
					)
					(arc
						(start 131.763008 -289.242754)
						(mid 131.774407 -289.225514)
						(end 131.777994 -289.205162)
					)
					(arc
						(start 131.777994 -289.205162)
						(mid 131.757725 -289.087933)
						(end 131.692396 -288.9885)
					)
					(arc
						(start 131.692396 -288.9885)
						(mid 131.485894 -288.902964)
						(end 131.279392 -288.9885)
					)
					(arc
						(start 131.279392 -288.9885)
						(mid 131.214603 -289.086893)
						(end 131.194048 -289.202876)
					)
					(arc
						(start 131.194048 -289.202876)
						(mid 131.197248 -289.223885)
						(end 131.20878 -289.241738)
					)
					(arc
						(start 131.20878 -289.241738)
						(mid 131.244758 -289.256678)
						(end 131.280662 -289.241738)
					)
					(arc
						(start 131.280662 -289.241738)
						(mid 131.289404 -289.229917)
						(end 131.294378 -289.216084)
					)
					(xy 131.294378 -289.195256) (xy 131.294378 -289.195002)
					(arc
						(start 131.294378 -289.193986)
						(mid 131.309216 -289.121281)
						(end 131.350512 -289.05962)
					)
					(arc
						(start 131.350512 -289.05962)
						(mid 131.485894 -289.003543)
						(end 131.621276 -289.05962)
					)
					(arc
						(start 131.621276 -289.05962)
						(mid 131.662925 -289.122086)
						(end 131.67741 -289.195764)
					)
					(xy 131.677156 -289.196272)
					(arc
						(start 131.677156 -289.216846)
						(mid 131.682212 -289.230844)
						(end 131.691126 -289.242754)
					)
				)
			)
		)
		(zone
			(layer "F.Cu")
			(hatch none 0.5)
			(connect_pads
				(clearance 0)
			)
			(min_thickness 0.25)
			(keepout
				(tracks not_allowed)
				(vias allowed)
				(pads allowed)
				(copperpour not_allowed)
				(footprints allowed)
			)
			(placement
				(enabled no)
				(sheetname "")
			)
			(fill
				(thermal_gap 0.5)
				(thermal_bridge_width 0.5)
				(island_removal_mode 0)
			)
			(polygon
				(pts
					(arc
						(start 132.580634 -214.297006)
						(mid 132.54473 -214.282246)
						(end 132.508752 -214.297006)
					)
					(arc
						(start 132.508752 -214.297006)
						(mid 132.497353 -214.314246)
						(end 132.493766 -214.334598)
					)
					(arc
						(start 132.493766 -214.334598)
						(mid 132.514035 -214.451827)
						(end 132.579364 -214.55126)
					)
					(arc
						(start 132.579364 -214.55126)
						(mid 132.785866 -214.636796)
						(end 132.992368 -214.55126)
					)
					(arc
						(start 132.992368 -214.55126)
						(mid 133.057157 -214.452867)
						(end 133.077712 -214.336884)
					)
					(arc
						(start 133.077712 -214.336884)
						(mid 133.074512 -214.315875)
						(end 133.06298 -214.298022)
					)
					(arc
						(start 133.06298 -214.298022)
						(mid 133.027076 -214.283262)
						(end 132.991098 -214.298022)
					)
					(arc
						(start 132.991098 -214.298022)
						(mid 132.982356 -214.309843)
						(end 132.977382 -214.323676)
					)
					(xy 132.977382 -214.344504) (xy 132.977382 -214.344758)
					(arc
						(start 132.977382 -214.345774)
						(mid 132.962544 -214.418479)
						(end 132.921248 -214.48014)
					)
					(arc
						(start 132.921248 -214.48014)
						(mid 132.785866 -214.536217)
						(end 132.650484 -214.48014)
					)
					(arc
						(start 132.650484 -214.48014)
						(mid 132.608835 -214.417674)
						(end 132.59435 -214.343996)
					)
					(xy 132.594604 -214.343488)
					(arc
						(start 132.594604 -214.322914)
						(mid 132.589548 -214.308916)
						(end 132.580634 -214.297006)
					)
				)
			)
		)
		(zone
			(layer "F.Cu")
			(hatch none 0.5)
			(connect_pads
				(clearance 0)
			)
			(min_thickness 0.25)
			(keepout
				(tracks not_allowed)
				(vias allowed)
				(pads allowed)
				(copperpour not_allowed)
				(footprints allowed)
			)
			(placement
				(enabled no)
				(sheetname "")
			)
			(fill
				(thermal_gap 0.5)
				(thermal_bridge_width 0.5)
				(island_removal_mode 0)
			)
			(polygon
				(pts
					(arc
						(start 132.630926 -289.242754)
						(mid 132.666904 -289.257694)
						(end 132.702808 -289.242754)
					)
					(arc
						(start 132.702808 -289.242754)
						(mid 132.714207 -289.225514)
						(end 132.717794 -289.205162)
					)
					(arc
						(start 132.717794 -289.205162)
						(mid 132.697525 -289.087933)
						(end 132.632196 -288.9885)
					)
					(arc
						(start 132.632196 -288.9885)
						(mid 132.425694 -288.902964)
						(end 132.219192 -288.9885)
					)
					(arc
						(start 132.219192 -288.9885)
						(mid 132.154403 -289.086893)
						(end 132.133848 -289.202876)
					)
					(arc
						(start 132.133848 -289.202876)
						(mid 132.137048 -289.223885)
						(end 132.14858 -289.241738)
					)
					(arc
						(start 132.14858 -289.241738)
						(mid 132.184558 -289.256678)
						(end 132.220462 -289.241738)
					)
					(arc
						(start 132.220462 -289.241738)
						(mid 132.229204 -289.229917)
						(end 132.234178 -289.216084)
					)
					(xy 132.234178 -289.195256) (xy 132.234178 -289.195002)
					(arc
						(start 132.234178 -289.193986)
						(mid 132.249016 -289.121281)
						(end 132.290312 -289.05962)
					)
					(arc
						(start 132.290312 -289.05962)
						(mid 132.425694 -289.003543)
						(end 132.561076 -289.05962)
					)
					(arc
						(start 132.561076 -289.05962)
						(mid 132.602725 -289.122086)
						(end 132.61721 -289.195764)
					)
					(xy 132.616956 -289.196272)
					(arc
						(start 132.616956 -289.216846)
						(mid 132.622012 -289.230844)
						(end 132.630926 -289.242754)
					)
				)
			)
		)
		(zone
			(layer "F.Cu")
			(hatch none 0.5)
			(connect_pads
				(clearance 0)
			)
			(min_thickness 0.25)
			(keepout
				(tracks not_allowed)
				(vias allowed)
				(pads allowed)
				(copperpour not_allowed)
				(footprints allowed)
			)
			(placement
				(enabled no)
				(sheetname "")
			)
			(fill
				(thermal_gap 0.5)
				(thermal_bridge_width 0.5)
				(island_removal_mode 0)
			)
			(polygon
				(pts
					(arc
						(start 133.05028 -215.111076)
						(mid 133.014466 -215.096241)
						(end 132.978652 -215.111076)
					)
					(arc
						(start 132.978652 -215.111076)
						(mid 132.967301 -215.128198)
						(end 132.963666 -215.148414)
					)
					(arc
						(start 132.963666 -215.148414)
						(mid 132.983815 -215.265615)
						(end 133.04901 -215.365076)
					)
					(arc
						(start 133.04901 -215.365076)
						(mid 133.255512 -215.450612)
						(end 133.462014 -215.365076)
					)
					(arc
						(start 133.462014 -215.365076)
						(mid 133.526896 -215.266832)
						(end 133.547612 -215.150954)
					)
					(arc
						(start 133.547612 -215.150954)
						(mid 133.544424 -215.129932)
						(end 133.53288 -215.112092)
					)
					(arc
						(start 133.53288 -215.112092)
						(mid 133.496977 -215.097257)
						(end 133.460998 -215.112092)
					)
					(arc
						(start 133.460998 -215.112092)
						(mid 133.452275 -215.123788)
						(end 133.447282 -215.137492)
					)
					(xy 133.447282 -215.15832) (xy 133.447282 -215.158828)
					(arc
						(start 133.447282 -215.159844)
						(mid 133.43228 -215.232442)
						(end 133.390894 -215.293956)
					)
					(arc
						(start 133.390894 -215.293956)
						(mid 133.255512 -215.350033)
						(end 133.12013 -215.293956)
					)
					(arc
						(start 133.12013 -215.293956)
						(mid 133.07853 -215.231608)
						(end 133.063996 -215.158066)
					)
					(xy 133.06425 -215.157304)
					(arc
						(start 133.06425 -215.13673)
						(mid 133.05916 -215.122868)
						(end 133.05028 -215.111076)
					)
				)
			)
		)
		(zone
			(layer "F.Cu")
			(hatch none 0.5)
			(connect_pads
				(clearance 0)
			)
			(min_thickness 0.25)
			(keepout
				(tracks not_allowed)
				(vias allowed)
				(pads allowed)
				(copperpour not_allowed)
				(footprints allowed)
			)
			(placement
				(enabled no)
				(sheetname "")
			)
			(fill
				(thermal_gap 0.5)
				(thermal_bridge_width 0.5)
				(island_removal_mode 0)
			)
			(polygon
				(pts
					(arc
						(start 133.570726 -289.242754)
						(mid 133.606704 -289.257694)
						(end 133.642608 -289.242754)
					)
					(arc
						(start 133.642608 -289.242754)
						(mid 133.654007 -289.225514)
						(end 133.657594 -289.205162)
					)
					(arc
						(start 133.657594 -289.205162)
						(mid 133.637325 -289.087933)
						(end 133.571996 -288.9885)
					)
					(arc
						(start 133.571996 -288.9885)
						(mid 133.365494 -288.902964)
						(end 133.158992 -288.9885)
					)
					(arc
						(start 133.158992 -288.9885)
						(mid 133.094203 -289.086893)
						(end 133.073648 -289.202876)
					)
					(arc
						(start 133.073648 -289.202876)
						(mid 133.076848 -289.223885)
						(end 133.08838 -289.241738)
					)
					(arc
						(start 133.08838 -289.241738)
						(mid 133.124358 -289.256678)
						(end 133.160262 -289.241738)
					)
					(arc
						(start 133.160262 -289.241738)
						(mid 133.169004 -289.229917)
						(end 133.173978 -289.216084)
					)
					(xy 133.173978 -289.195256) (xy 133.173978 -289.195002)
					(arc
						(start 133.173978 -289.193986)
						(mid 133.188816 -289.121281)
						(end 133.230112 -289.05962)
					)
					(arc
						(start 133.230112 -289.05962)
						(mid 133.365494 -289.003543)
						(end 133.500876 -289.05962)
					)
					(arc
						(start 133.500876 -289.05962)
						(mid 133.542525 -289.122086)
						(end 133.55701 -289.195764)
					)
					(xy 133.556756 -289.196272)
					(arc
						(start 133.556756 -289.216846)
						(mid 133.561812 -289.230844)
						(end 133.570726 -289.242754)
					)
				)
			)
		)
		(zone
			(layer "F.Cu")
			(hatch none 0.5)
			(connect_pads
				(clearance 0)
			)
			(min_thickness 0.25)
			(keepout
				(tracks not_allowed)
				(vias allowed)
				(pads allowed)
				(copperpour not_allowed)
				(footprints allowed)
			)
			(placement
				(enabled no)
				(sheetname "")
			)
			(fill
				(thermal_gap 0.5)
				(thermal_bridge_width 0.5)
				(island_removal_mode 0)
			)
			(polygon
				(pts
					(arc
						(start 133.990334 -215.111076)
						(mid 133.954431 -215.096241)
						(end 133.918452 -215.111076)
					)
					(arc
						(start 133.918452 -215.111076)
						(mid 133.907101 -215.128198)
						(end 133.903466 -215.148414)
					)
					(arc
						(start 133.903466 -215.148414)
						(mid 133.923735 -215.265643)
						(end 133.989064 -215.365076)
					)
					(arc
						(start 133.989064 -215.365076)
						(mid 134.195566 -215.450612)
						(end 134.402068 -215.365076)
					)
					(arc
						(start 134.402068 -215.365076)
						(mid 134.466809 -215.266801)
						(end 134.487412 -215.150954)
					)
					(arc
						(start 134.487412 -215.150954)
						(mid 134.484212 -215.129945)
						(end 134.47268 -215.112092)
					)
					(arc
						(start 134.47268 -215.112092)
						(mid 134.436777 -215.097257)
						(end 134.400798 -215.112092)
					)
					(arc
						(start 134.400798 -215.112092)
						(mid 134.392075 -215.123788)
						(end 134.387082 -215.137492)
					)
					(xy 134.387082 -215.15832) (xy 134.387082 -215.158828)
					(arc
						(start 134.387082 -215.159844)
						(mid 134.372197 -215.232413)
						(end 134.330948 -215.293956)
					)
					(arc
						(start 134.330948 -215.293956)
						(mid 134.195566 -215.350033)
						(end 134.060184 -215.293956)
					)
					(arc
						(start 134.060184 -215.293956)
						(mid 134.018584 -215.231608)
						(end 134.00405 -215.158066)
					)
					(xy 134.004304 -215.157304)
					(arc
						(start 134.004304 -215.13673)
						(mid 133.999214 -215.122868)
						(end 133.990334 -215.111076)
					)
				)
			)
		)
		(zone
			(layer "F.Cu")
			(hatch none 0.5)
			(connect_pads
				(clearance 0)
			)
			(min_thickness 0.25)
			(keepout
				(tracks not_allowed)
				(vias allowed)
				(pads allowed)
				(copperpour not_allowed)
				(footprints allowed)
			)
			(placement
				(enabled no)
				(sheetname "")
			)
			(fill
				(thermal_gap 0.5)
				(thermal_bridge_width 0.5)
				(island_removal_mode 0)
			)
			(polygon
				(pts
					(arc
						(start 134.04088 -288.428684)
						(mid 134.076694 -288.443519)
						(end 134.112508 -288.428684)
					)
					(arc
						(start 134.112508 -288.428684)
						(mid 134.123859 -288.411562)
						(end 134.127494 -288.391346)
					)
					(arc
						(start 134.127494 -288.391346)
						(mid 134.107345 -288.274145)
						(end 134.04215 -288.174684)
					)
					(arc
						(start 134.04215 -288.174684)
						(mid 133.835648 -288.089148)
						(end 133.629146 -288.174684)
					)
					(arc
						(start 133.629146 -288.174684)
						(mid 133.564264 -288.272928)
						(end 133.543548 -288.388806)
					)
					(arc
						(start 133.543548 -288.388806)
						(mid 133.546736 -288.409828)
						(end 133.55828 -288.427668)
					)
					(arc
						(start 133.55828 -288.427668)
						(mid 133.594258 -288.442682)
						(end 133.630162 -288.427668)
					)
					(arc
						(start 133.630162 -288.427668)
						(mid 133.638885 -288.415972)
						(end 133.643878 -288.402268)
					)
					(xy 133.643878 -288.38144) (xy 133.643878 -288.380932)
					(arc
						(start 133.643878 -288.379916)
						(mid 133.65888 -288.307318)
						(end 133.700266 -288.245804)
					)
					(arc
						(start 133.700266 -288.245804)
						(mid 133.835648 -288.189727)
						(end 133.97103 -288.245804)
					)
					(arc
						(start 133.97103 -288.245804)
						(mid 134.01263 -288.308152)
						(end 134.027164 -288.381694)
					)
					(xy 134.02691 -288.382456)
					(arc
						(start 134.02691 -288.40303)
						(mid 134.032 -288.416892)
						(end 134.04088 -288.428684)
					)
				)
			)
		)
		(zone
			(layer "F.Cu")
			(hatch none 0.5)
			(connect_pads
				(clearance 0)
			)
			(min_thickness 0.25)
			(keepout
				(tracks not_allowed)
				(vias allowed)
				(pads allowed)
				(copperpour not_allowed)
				(footprints allowed)
			)
			(placement
				(enabled no)
				(sheetname "")
			)
			(fill
				(thermal_gap 0.5)
				(thermal_bridge_width 0.5)
				(island_removal_mode 0)
			)
			(polygon
				(pts
					(arc
						(start 134.954264 -288.26968)
						(mid 134.990185 -288.254801)
						(end 135.005064 -288.21888)
					)
					(arc
						(start 135.005064 -288.21888)
						(mid 135.000832 -288.198833)
						(end 134.989062 -288.18205)
					)
					(arc
						(start 134.989062 -288.18205)
						(mid 134.891935 -288.113321)
						(end 134.775448 -288.089086)
					)
					(arc
						(start 134.775448 -288.089086)
						(mid 134.568902 -288.17464)
						(end 134.483348 -288.381186)
					)
					(arc
						(start 134.483348 -288.381186)
						(mid 134.507049 -288.496443)
						(end 134.57428 -288.593022)
					)
					(arc
						(start 134.57428 -288.593022)
						(mid 134.591508 -288.605591)
						(end 134.61238 -288.61004)
					)
					(arc
						(start 134.61238 -288.61004)
						(mid 134.648301 -288.595161)
						(end 134.66318 -288.55924)
					)
					(arc
						(start 134.66318 -288.55924)
						(mid 134.660995 -288.544792)
						(end 134.654798 -288.531554)
					)
					(xy 134.640066 -288.516822) (xy 134.639812 -288.516568)
					(arc
						(start 134.63905 -288.515806)
						(mid 134.598206 -288.453929)
						(end 134.583932 -288.381186)
					)
					(arc
						(start 134.583932 -288.381186)
						(mid 134.640026 -288.245764)
						(end 134.775448 -288.18967)
					)
					(arc
						(start 134.775448 -288.18967)
						(mid 134.849041 -288.204268)
						(end 134.911338 -288.246058)
					)
					(xy 134.911592 -288.24682)
					(arc
						(start 134.92607 -288.261298)
						(mid 134.939548 -288.267571)
						(end 134.954264 -288.26968)
					)
				)
			)
		)
		(zone
			(layer "F.Cu")
			(hatch none 0.5)
			(connect_pads
				(clearance 0)
			)
			(min_thickness 0.25)
			(keepout
				(tracks not_allowed)
				(vias allowed)
				(pads allowed)
				(copperpour not_allowed)
				(footprints allowed)
			)
			(placement
				(enabled no)
				(sheetname "")
			)
			(fill
				(thermal_gap 0.5)
				(thermal_bridge_width 0.5)
				(island_removal_mode 0)
			)
			(polygon
				(pts
					(arc
						(start 135.02386 -214.979758)
						(mid 135.008981 -214.943837)
						(end 134.97306 -214.928958)
					)
					(arc
						(start 134.97306 -214.928958)
						(mid 134.952876 -214.93314)
						(end 134.935976 -214.94496)
					)
					(arc
						(start 134.935976 -214.94496)
						(mid 134.867305 -215.042103)
						(end 134.843012 -215.158574)
					)
					(arc
						(start 134.843012 -215.158574)
						(mid 134.928566 -215.36512)
						(end 135.135112 -215.450674)
					)
					(arc
						(start 135.135112 -215.450674)
						(mid 135.250518 -215.426887)
						(end 135.347202 -215.359488)
					)
					(arc
						(start 135.347202 -215.359488)
						(mid 135.35972 -215.342376)
						(end 135.36422 -215.321642)
					)
					(arc
						(start 135.36422 -215.321642)
						(mid 135.349341 -215.285721)
						(end 135.31342 -215.270842)
					)
					(arc
						(start 135.31342 -215.270842)
						(mid 135.298834 -215.272981)
						(end 135.28548 -215.279224)
					)
					(xy 135.271002 -215.293956) (xy 135.270494 -215.29421)
					(arc
						(start 135.269986 -215.294972)
						(mid 135.207992 -215.335864)
						(end 135.135112 -215.35009)
					)
					(arc
						(start 135.135112 -215.35009)
						(mid 134.99969 -215.293996)
						(end 134.943596 -215.158574)
					)
					(arc
						(start 134.943596 -215.158574)
						(mid 134.95838 -215.084992)
						(end 135.000238 -215.022684)
					)
					(xy 135.001 -215.02243)
					(arc
						(start 135.015478 -215.007952)
						(mid 135.02172 -214.994469)
						(end 135.02386 -214.979758)
					)
				)
			)
		)
		(zone
			(layer "F.Cu")
			(hatch none 0.5)
			(connect_pads
				(clearance 0)
			)
			(min_thickness 0.25)
			(keepout
				(tracks not_allowed)
				(vias allowed)
				(pads allowed)
				(copperpour not_allowed)
				(footprints allowed)
			)
			(placement
				(enabled no)
				(sheetname "")
			)
			(fill
				(thermal_gap 0.5)
				(thermal_bridge_width 0.5)
				(island_removal_mode 0)
			)
			(polygon
				(pts
					(arc
						(start 135.42391 -287.455864)
						(mid 135.459831 -287.440985)
						(end 135.47471 -287.405064)
					)
					(arc
						(start 135.47471 -287.405064)
						(mid 135.47065 -287.384907)
						(end 135.458962 -287.36798)
					)
					(arc
						(start 135.458962 -287.36798)
						(mid 135.36167 -287.299402)
						(end 135.245094 -287.27527)
					)
					(arc
						(start 135.245094 -287.27527)
						(mid 135.038728 -287.36075)
						(end 134.953248 -287.567116)
					)
					(arc
						(start 134.953248 -287.567116)
						(mid 134.976898 -287.68251)
						(end 135.04418 -287.779206)
					)
					(arc
						(start 135.04418 -287.779206)
						(mid 135.061408 -287.791775)
						(end 135.08228 -287.796224)
					)
					(arc
						(start 135.08228 -287.796224)
						(mid 135.118201 -287.781345)
						(end 135.13308 -287.745424)
					)
					(arc
						(start 135.13308 -287.745424)
						(mid 135.130941 -287.730838)
						(end 135.124698 -287.717484)
					)
					(xy 135.109966 -287.703006) (xy 135.109458 -287.702498)
					(arc
						(start 135.10895 -287.70199)
						(mid 135.067923 -287.640025)
						(end 135.053578 -287.567116)
					)
					(arc
						(start 135.053578 -287.567116)
						(mid 135.109672 -287.431694)
						(end 135.245094 -287.3756)
					)
					(arc
						(start 135.245094 -287.3756)
						(mid 135.318716 -287.390316)
						(end 135.380984 -287.432242)
					)
					(xy 135.381492 -287.433004)
					(arc
						(start 135.39597 -287.447482)
						(mid 135.409326 -287.453718)
						(end 135.42391 -287.455864)
					)
				)
			)
		)
		(zone
			(layer "F.Cu")
			(hatch none 0.5)
			(connect_pads
				(clearance 0)
			)
			(min_thickness 0.25)
			(keepout
				(tracks not_allowed)
				(vias allowed)
				(pads allowed)
				(copperpour not_allowed)
				(footprints allowed)
			)
			(placement
				(enabled no)
				(sheetname "")
			)
			(fill
				(thermal_gap 0.5)
				(thermal_bridge_width 0.5)
				(island_removal_mode 0)
			)
			(polygon
				(pts
					(arc
						(start 135.49376 -215.793828)
						(mid 135.478881 -215.757907)
						(end 135.44296 -215.743028)
					)
					(arc
						(start 135.44296 -215.743028)
						(mid 135.422941 -215.747139)
						(end 135.40613 -215.758776)
					)
					(arc
						(start 135.40613 -215.758776)
						(mid 135.337408 -215.856036)
						(end 135.313166 -215.972644)
					)
					(arc
						(start 135.313166 -215.972644)
						(mid 135.39872 -216.17919)
						(end 135.605266 -216.264744)
					)
					(arc
						(start 135.605266 -216.264744)
						(mid 135.720551 -216.240922)
						(end 135.817102 -216.173558)
					)
					(arc
						(start 135.817102 -216.173558)
						(mid 135.829671 -216.15633)
						(end 135.83412 -216.135458)
					)
					(arc
						(start 135.83412 -216.135458)
						(mid 135.819241 -216.099537)
						(end 135.78332 -216.084658)
					)
					(arc
						(start 135.78332 -216.084658)
						(mid 135.768866 -216.086833)
						(end 135.755634 -216.09304)
					)
					(xy 135.740902 -216.107772) (xy 135.740648 -216.108026)
					(arc
						(start 135.739886 -216.108788)
						(mid 135.678038 -216.149767)
						(end 135.605266 -216.16416)
					)
					(arc
						(start 135.605266 -216.16416)
						(mid 135.469844 -216.108066)
						(end 135.41375 -215.972644)
					)
					(arc
						(start 135.41375 -215.972644)
						(mid 135.428466 -215.899022)
						(end 135.470392 -215.836754)
					)
					(xy 135.4709 -215.836246)
					(arc
						(start 135.485378 -215.821768)
						(mid 135.491614 -215.808412)
						(end 135.49376 -215.793828)
					)
				)
			)
		)
		(zone
			(layer "F.Cu")
			(hatch none 0.5)
			(connect_pads
				(clearance 0)
			)
			(min_thickness 0.25)
			(keepout
				(tracks not_allowed)
				(vias allowed)
				(pads allowed)
				(copperpour not_allowed)
				(footprints allowed)
			)
			(placement
				(enabled no)
				(sheetname "")
			)
			(fill
				(thermal_gap 0.5)
				(thermal_bridge_width 0.5)
				(island_removal_mode 0)
			)
			(polygon
				(pts
					(arc
						(start 135.89381 -288.26968)
						(mid 135.929731 -288.254801)
						(end 135.94461 -288.21888)
					)
					(arc
						(start 135.94461 -288.21888)
						(mid 135.940499 -288.198861)
						(end 135.928862 -288.18205)
					)
					(arc
						(start 135.928862 -288.18205)
						(mid 135.831602 -288.113328)
						(end 135.714994 -288.089086)
					)
					(arc
						(start 135.714994 -288.089086)
						(mid 135.508612 -288.17473)
						(end 135.423148 -288.381186)
					)
					(arc
						(start 135.423148 -288.381186)
						(mid 135.446864 -288.496427)
						(end 135.51408 -288.593022)
					)
					(arc
						(start 135.51408 -288.593022)
						(mid 135.531308 -288.605591)
						(end 135.55218 -288.61004)
					)
					(arc
						(start 135.55218 -288.61004)
						(mid 135.588101 -288.595161)
						(end 135.60298 -288.55924)
					)
					(arc
						(start 135.60298 -288.55924)
						(mid 135.600805 -288.544786)
						(end 135.594598 -288.531554)
					)
					(xy 135.579866 -288.516822) (xy 135.579358 -288.516568)
					(arc
						(start 135.57885 -288.515806)
						(mid 135.537871 -288.453958)
						(end 135.523478 -288.381186)
					)
					(arc
						(start 135.523478 -288.381186)
						(mid 135.579572 -288.245764)
						(end 135.714994 -288.18967)
					)
					(arc
						(start 135.714994 -288.18967)
						(mid 135.788587 -288.204268)
						(end 135.850884 -288.246058)
					)
					(xy 135.851392 -288.24682)
					(arc
						(start 135.86587 -288.261298)
						(mid 135.879226 -288.267534)
						(end 135.89381 -288.26968)
					)
				)
			)
		)
		(zone
			(layer "F.Cu")
			(hatch none 0.5)
			(connect_pads
				(clearance 0)
			)
			(min_thickness 0.25)
			(keepout
				(tracks not_allowed)
				(vias allowed)
				(pads allowed)
				(copperpour not_allowed)
				(footprints allowed)
			)
			(placement
				(enabled no)
				(sheetname "")
			)
			(fill
				(thermal_gap 0.5)
				(thermal_bridge_width 0.5)
				(island_removal_mode 0)
			)
			(polygon
				(pts
					(arc
						(start 135.89381 -286.641794)
						(mid 135.929641 -286.627005)
						(end 135.94461 -286.591248)
					)
					(arc
						(start 135.94461 -286.591248)
						(mid 135.94055 -286.571091)
						(end 135.928862 -286.554164)
					)
					(arc
						(start 135.928862 -286.554164)
						(mid 135.831602 -286.485442)
						(end 135.714994 -286.4612)
					)
					(arc
						(start 135.714994 -286.4612)
						(mid 135.508612 -286.546844)
						(end 135.423148 -286.7533)
					)
					(arc
						(start 135.423148 -286.7533)
						(mid 135.446798 -286.868694)
						(end 135.51408 -286.96539)
					)
					(arc
						(start 135.51408 -286.96539)
						(mid 135.531342 -286.977811)
						(end 135.55218 -286.982154)
					)
					(arc
						(start 135.55218 -286.982154)
						(mid 135.588101 -286.967275)
						(end 135.60298 -286.931354)
					)
					(arc
						(start 135.60298 -286.931354)
						(mid 135.600805 -286.9169)
						(end 135.594598 -286.903668)
					)
					(xy 135.579866 -286.88919) (xy 135.579358 -286.888682)
					(arc
						(start 135.57885 -286.88792)
						(mid 135.537871 -286.826072)
						(end 135.523478 -286.7533)
					)
					(arc
						(start 135.523478 -286.7533)
						(mid 135.579572 -286.617878)
						(end 135.714994 -286.561784)
					)
					(arc
						(start 135.714994 -286.561784)
						(mid 135.788616 -286.5765)
						(end 135.850884 -286.618426)
					)
					(xy 135.851392 -286.618934)
					(arc
						(start 135.86587 -286.633412)
						(mid 135.879226 -286.639648)
						(end 135.89381 -286.641794)
					)
				)
			)
		)
		(zone
			(layer "F.Cu")
			(hatch none 0.5)
			(connect_pads
				(clearance 0)
			)
			(min_thickness 0.25)
			(keepout
				(tracks not_allowed)
				(vias allowed)
				(pads allowed)
				(copperpour not_allowed)
				(footprints allowed)
			)
			(placement
				(enabled no)
				(sheetname "")
			)
			(fill
				(thermal_gap 0.5)
				(thermal_bridge_width 0.5)
				(island_removal_mode 0)
			)
			(polygon
				(pts
					(arc
						(start 135.96366 -216.607644)
						(mid 135.948781 -216.571723)
						(end 135.91286 -216.556844)
					)
					(arc
						(start 135.91286 -216.556844)
						(mid 135.892813 -216.561076)
						(end 135.87603 -216.572846)
					)
					(arc
						(start 135.87603 -216.572846)
						(mid 135.807301 -216.669973)
						(end 135.783066 -216.78646)
					)
					(arc
						(start 135.783066 -216.78646)
						(mid 135.86862 -216.993006)
						(end 136.075166 -217.07856)
					)
					(arc
						(start 136.075166 -217.07856)
						(mid 136.190451 -217.054738)
						(end 136.287002 -216.987374)
					)
					(arc
						(start 136.287002 -216.987374)
						(mid 136.29952 -216.970262)
						(end 136.30402 -216.949528)
					)
					(arc
						(start 136.30402 -216.949528)
						(mid 136.289141 -216.913607)
						(end 136.25322 -216.898728)
					)
					(arc
						(start 136.25322 -216.898728)
						(mid 136.238772 -216.900751)
						(end 136.225534 -216.906856)
					)
					(xy 136.210802 -216.921588) (xy 136.210548 -216.922096)
					(arc
						(start 136.209786 -216.922604)
						(mid 136.147938 -216.963583)
						(end 136.075166 -216.977976)
					)
					(arc
						(start 136.075166 -216.977976)
						(mid 135.939744 -216.921882)
						(end 135.88365 -216.78646)
					)
					(arc
						(start 135.88365 -216.78646)
						(mid 135.898366 -216.712838)
						(end 135.940292 -216.65057)
					)
					(xy 135.9408 -216.650062)
					(arc
						(start 135.955278 -216.635584)
						(mid 135.961514 -216.622228)
						(end 135.96366 -216.607644)
					)
				)
			)
		)
		(zone
			(layer "F.Cu")
			(hatch none 0.5)
			(connect_pads
				(clearance 0)
			)
			(min_thickness 0.25)
			(keepout
				(tracks not_allowed)
				(vias allowed)
				(pads allowed)
				(copperpour not_allowed)
				(footprints allowed)
			)
			(placement
				(enabled no)
				(sheetname "")
			)
			(fill
				(thermal_gap 0.5)
				(thermal_bridge_width 0.5)
				(island_removal_mode 0)
			)
			(polygon
				(pts
					(arc
						(start 135.96366 -214.979758)
						(mid 135.948781 -214.943837)
						(end 135.91286 -214.928958)
					)
					(arc
						(start 135.91286 -214.928958)
						(mid 135.892813 -214.93319)
						(end 135.87603 -214.94496)
					)
					(arc
						(start 135.87603 -214.94496)
						(mid 135.807359 -215.042103)
						(end 135.783066 -215.158574)
					)
					(arc
						(start 135.783066 -215.158574)
						(mid 135.86862 -215.36512)
						(end 136.075166 -215.450674)
					)
					(arc
						(start 136.075166 -215.450674)
						(mid 136.190492 -215.426921)
						(end 136.287002 -215.359488)
					)
					(arc
						(start 136.287002 -215.359488)
						(mid 136.29952 -215.342376)
						(end 136.30402 -215.321642)
					)
					(arc
						(start 136.30402 -215.321642)
						(mid 136.289141 -215.285721)
						(end 136.25322 -215.270842)
					)
					(arc
						(start 136.25322 -215.270842)
						(mid 136.238766 -215.273017)
						(end 136.225534 -215.279224)
					)
					(xy 136.210802 -215.293956) (xy 136.210548 -215.29421)
					(arc
						(start 136.209786 -215.294972)
						(mid 136.147909 -215.335816)
						(end 136.075166 -215.35009)
					)
					(arc
						(start 136.075166 -215.35009)
						(mid 135.939744 -215.293996)
						(end 135.88365 -215.158574)
					)
					(arc
						(start 135.88365 -215.158574)
						(mid 135.898366 -215.084952)
						(end 135.940292 -215.022684)
					)
					(xy 135.9408 -215.02243)
					(arc
						(start 135.955278 -215.007952)
						(mid 135.961551 -214.994474)
						(end 135.96366 -214.979758)
					)
				)
			)
		)
		(zone
			(layer "F.Cu")
			(hatch none 0.5)
			(connect_pads
				(clearance 0)
			)
			(min_thickness 0.25)
			(keepout
				(tracks not_allowed)
				(vias allowed)
				(pads allowed)
				(copperpour not_allowed)
				(footprints allowed)
			)
			(placement
				(enabled no)
				(sheetname "")
			)
			(fill
				(thermal_gap 0.5)
				(thermal_bridge_width 0.5)
				(island_removal_mode 0)
			)
			(polygon
				(pts
					(arc
						(start 136.36371 -287.455864)
						(mid 136.399631 -287.440985)
						(end 136.41451 -287.405064)
					)
					(arc
						(start 136.41451 -287.405064)
						(mid 136.41045 -287.384907)
						(end 136.398762 -287.36798)
					)
					(arc
						(start 136.398762 -287.36798)
						(mid 136.30147 -287.299402)
						(end 136.184894 -287.27527)
					)
					(arc
						(start 136.184894 -287.27527)
						(mid 135.978528 -287.36075)
						(end 135.893048 -287.567116)
					)
					(arc
						(start 135.893048 -287.567116)
						(mid 135.916698 -287.68251)
						(end 135.98398 -287.779206)
					)
					(arc
						(start 135.98398 -287.779206)
						(mid 136.001208 -287.791775)
						(end 136.02208 -287.796224)
					)
					(arc
						(start 136.02208 -287.796224)
						(mid 136.058001 -287.781345)
						(end 136.07288 -287.745424)
					)
					(arc
						(start 136.07288 -287.745424)
						(mid 136.070741 -287.730838)
						(end 136.064498 -287.717484)
					)
					(xy 136.049766 -287.703006) (xy 136.049258 -287.702498)
					(arc
						(start 136.04875 -287.70199)
						(mid 136.007723 -287.640025)
						(end 135.993378 -287.567116)
					)
					(arc
						(start 135.993378 -287.567116)
						(mid 136.049472 -287.431694)
						(end 136.184894 -287.3756)
					)
					(arc
						(start 136.184894 -287.3756)
						(mid 136.258516 -287.390316)
						(end 136.320784 -287.432242)
					)
					(xy 136.321292 -287.433004)
					(arc
						(start 136.33577 -287.447482)
						(mid 136.349126 -287.453718)
						(end 136.36371 -287.455864)
					)
				)
			)
		)
		(zone
			(layer "F.Cu")
			(hatch none 0.5)
			(connect_pads
				(clearance 0)
			)
			(min_thickness 0.25)
			(keepout
				(tracks not_allowed)
				(vias allowed)
				(pads allowed)
				(copperpour not_allowed)
				(footprints allowed)
			)
			(placement
				(enabled no)
				(sheetname "")
			)
			(fill
				(thermal_gap 0.5)
				(thermal_bridge_width 0.5)
				(island_removal_mode 0)
			)
			(polygon
				(pts
					(arc
						(start 136.36371 -285.827978)
						(mid 136.399631 -285.813099)
						(end 136.41451 -285.777178)
					)
					(arc
						(start 136.41451 -285.777178)
						(mid 136.410399 -285.757159)
						(end 136.398762 -285.740348)
					)
					(arc
						(start 136.398762 -285.740348)
						(mid 136.301502 -285.671626)
						(end 136.184894 -285.647384)
					)
					(arc
						(start 136.184894 -285.647384)
						(mid 135.978512 -285.733028)
						(end 135.893048 -285.939484)
					)
					(arc
						(start 135.893048 -285.939484)
						(mid 135.916764 -286.054725)
						(end 135.98398 -286.15132)
					)
					(arc
						(start 135.98398 -286.15132)
						(mid 136.001208 -286.163889)
						(end 136.02208 -286.168338)
					)
					(arc
						(start 136.02208 -286.168338)
						(mid 136.058001 -286.153459)
						(end 136.07288 -286.117538)
					)
					(arc
						(start 136.07288 -286.117538)
						(mid 136.070705 -286.103084)
						(end 136.064498 -286.089852)
					)
					(xy 136.049766 -286.07512) (xy 136.049258 -286.074866)
					(arc
						(start 136.04875 -286.074104)
						(mid 136.007771 -286.012256)
						(end 135.993378 -285.939484)
					)
					(arc
						(start 135.993378 -285.939484)
						(mid 136.049472 -285.804062)
						(end 136.184894 -285.747968)
					)
					(arc
						(start 136.184894 -285.747968)
						(mid 136.258487 -285.762566)
						(end 136.320784 -285.804356)
					)
					(xy 136.321292 -285.805118)
					(arc
						(start 136.33577 -285.819596)
						(mid 136.349126 -285.825832)
						(end 136.36371 -285.827978)
					)
				)
			)
		)
		(zone
			(layer "F.Cu")
			(hatch none 0.5)
			(connect_pads
				(clearance 0)
			)
			(min_thickness 0.25)
			(keepout
				(tracks not_allowed)
				(vias allowed)
				(pads allowed)
				(copperpour not_allowed)
				(footprints allowed)
			)
			(placement
				(enabled no)
				(sheetname "")
			)
			(fill
				(thermal_gap 0.5)
				(thermal_bridge_width 0.5)
				(island_removal_mode 0)
			)
			(polygon
				(pts
					(arc
						(start 136.43356 -217.42146)
						(mid 136.418681 -217.385539)
						(end 136.38276 -217.37066)
					)
					(arc
						(start 136.38276 -217.37066)
						(mid 136.362713 -217.374892)
						(end 136.34593 -217.386662)
					)
					(arc
						(start 136.34593 -217.386662)
						(mid 136.277259 -217.483805)
						(end 136.252966 -217.600276)
					)
					(arc
						(start 136.252966 -217.600276)
						(mid 136.33852 -217.806822)
						(end 136.545066 -217.892376)
					)
					(arc
						(start 136.545066 -217.892376)
						(mid 136.660392 -217.868623)
						(end 136.756902 -217.80119)
					)
					(arc
						(start 136.756902 -217.80119)
						(mid 136.76942 -217.784078)
						(end 136.77392 -217.763344)
					)
					(arc
						(start 136.77392 -217.763344)
						(mid 136.759041 -217.727423)
						(end 136.72312 -217.712544)
					)
					(arc
						(start 136.72312 -217.712544)
						(mid 136.708666 -217.714719)
						(end 136.695434 -217.720926)
					)
					(xy 136.680702 -217.735658) (xy 136.680448 -217.735912)
					(arc
						(start 136.679686 -217.736674)
						(mid 136.617809 -217.777518)
						(end 136.545066 -217.791792)
					)
					(arc
						(start 136.545066 -217.791792)
						(mid 136.409644 -217.735698)
						(end 136.35355 -217.600276)
					)
					(arc
						(start 136.35355 -217.600276)
						(mid 136.368266 -217.526654)
						(end 136.410192 -217.464386)
					)
					(xy 136.4107 -217.464132)
					(arc
						(start 136.425178 -217.449654)
						(mid 136.431451 -217.436176)
						(end 136.43356 -217.42146)
					)
				)
			)
		)
		(zone
			(layer "F.Cu")
			(hatch none 0.5)
			(connect_pads
				(clearance 0)
			)
			(min_thickness 0.25)
			(keepout
				(tracks not_allowed)
				(vias allowed)
				(pads allowed)
				(copperpour not_allowed)
				(footprints allowed)
			)
			(placement
				(enabled no)
				(sheetname "")
			)
			(fill
				(thermal_gap 0.5)
				(thermal_bridge_width 0.5)
				(island_removal_mode 0)
			)
			(polygon
				(pts
					(arc
						(start 136.43356 -215.793828)
						(mid 136.418681 -215.757907)
						(end 136.38276 -215.743028)
					)
					(arc
						(start 136.38276 -215.743028)
						(mid 136.362741 -215.747139)
						(end 136.34593 -215.758776)
					)
					(arc
						(start 136.34593 -215.758776)
						(mid 136.277208 -215.856036)
						(end 136.252966 -215.972644)
					)
					(arc
						(start 136.252966 -215.972644)
						(mid 136.33852 -216.17919)
						(end 136.545066 -216.264744)
					)
					(arc
						(start 136.545066 -216.264744)
						(mid 136.660351 -216.240922)
						(end 136.756902 -216.173558)
					)
					(arc
						(start 136.756902 -216.173558)
						(mid 136.769471 -216.15633)
						(end 136.77392 -216.135458)
					)
					(arc
						(start 136.77392 -216.135458)
						(mid 136.759041 -216.099537)
						(end 136.72312 -216.084658)
					)
					(arc
						(start 136.72312 -216.084658)
						(mid 136.708666 -216.086833)
						(end 136.695434 -216.09304)
					)
					(xy 136.680702 -216.107772) (xy 136.680448 -216.108026)
					(arc
						(start 136.679686 -216.108788)
						(mid 136.617838 -216.149767)
						(end 136.545066 -216.16416)
					)
					(arc
						(start 136.545066 -216.16416)
						(mid 136.409644 -216.108066)
						(end 136.35355 -215.972644)
					)
					(arc
						(start 136.35355 -215.972644)
						(mid 136.368266 -215.899022)
						(end 136.410192 -215.836754)
					)
					(xy 136.4107 -215.836246)
					(arc
						(start 136.425178 -215.821768)
						(mid 136.431414 -215.808412)
						(end 136.43356 -215.793828)
					)
				)
			)
		)
		(zone
			(layer "F.Cu")
			(hatch none 0.5)
			(connect_pads
				(clearance 0)
			)
			(min_thickness 0.25)
			(keepout
				(tracks not_allowed)
				(vias allowed)
				(pads allowed)
				(copperpour not_allowed)
				(footprints allowed)
			)
			(placement
				(enabled no)
				(sheetname "")
			)
			(fill
				(thermal_gap 0.5)
				(thermal_bridge_width 0.5)
				(island_removal_mode 0)
			)
			(polygon
				(pts
					(arc
						(start 136.833864 -286.641794)
						(mid 136.869695 -286.627005)
						(end 136.884664 -286.591248)
					)
					(arc
						(start 136.884664 -286.591248)
						(mid 136.880482 -286.571064)
						(end 136.868662 -286.554164)
					)
					(arc
						(start 136.868662 -286.554164)
						(mid 136.771519 -286.485493)
						(end 136.655048 -286.4612)
					)
					(arc
						(start 136.655048 -286.4612)
						(mid 136.448502 -286.546754)
						(end 136.362948 -286.7533)
					)
					(arc
						(start 136.362948 -286.7533)
						(mid 136.386598 -286.868694)
						(end 136.45388 -286.96539)
					)
					(arc
						(start 136.45388 -286.96539)
						(mid 136.471142 -286.977811)
						(end 136.49198 -286.982154)
					)
					(arc
						(start 136.49198 -286.982154)
						(mid 136.527901 -286.967275)
						(end 136.54278 -286.931354)
					)
					(arc
						(start 136.54278 -286.931354)
						(mid 136.540605 -286.9169)
						(end 136.534398 -286.903668)
					)
					(xy 136.519666 -286.88919) (xy 136.519412 -286.888682)
					(arc
						(start 136.51865 -286.88792)
						(mid 136.477806 -286.826043)
						(end 136.463532 -286.7533)
					)
					(arc
						(start 136.463532 -286.7533)
						(mid 136.519626 -286.617878)
						(end 136.655048 -286.561784)
					)
					(arc
						(start 136.655048 -286.561784)
						(mid 136.72867 -286.5765)
						(end 136.790938 -286.618426)
					)
					(xy 136.791192 -286.618934)
					(arc
						(start 136.80567 -286.633412)
						(mid 136.819148 -286.639685)
						(end 136.833864 -286.641794)
					)
				)
			)
		)
		(zone
			(layer "F.Cu")
			(hatch none 0.5)
			(connect_pads
				(clearance 0)
			)
			(min_thickness 0.25)
			(keepout
				(tracks not_allowed)
				(vias allowed)
				(pads allowed)
				(copperpour not_allowed)
				(footprints allowed)
			)
			(placement
				(enabled no)
				(sheetname "")
			)
			(fill
				(thermal_gap 0.5)
				(thermal_bridge_width 0.5)
				(island_removal_mode 0)
			)
			(polygon
				(pts
					(arc
						(start 136.833864 -285.014162)
						(mid 136.869785 -284.999283)
						(end 136.884664 -284.963362)
					)
					(arc
						(start 136.884664 -284.963362)
						(mid 136.880482 -284.943178)
						(end 136.868662 -284.926278)
					)
					(arc
						(start 136.868662 -284.926278)
						(mid 136.771487 -284.85775)
						(end 136.655048 -284.833568)
					)
					(arc
						(start 136.655048 -284.833568)
						(mid 136.448592 -284.919032)
						(end 136.362948 -285.125414)
					)
					(arc
						(start 136.362948 -285.125414)
						(mid 136.386598 -285.240808)
						(end 136.45388 -285.337504)
					)
					(arc
						(start 136.45388 -285.337504)
						(mid 136.471108 -285.350073)
						(end 136.49198 -285.354522)
					)
					(arc
						(start 136.49198 -285.354522)
						(mid 136.527901 -285.339643)
						(end 136.54278 -285.303722)
					)
					(arc
						(start 136.54278 -285.303722)
						(mid 136.540641 -285.289136)
						(end 136.534398 -285.275782)
					)
					(xy 136.519666 -285.261304) (xy 136.519412 -285.260796)
					(arc
						(start 136.51865 -285.260288)
						(mid 136.477758 -285.198294)
						(end 136.463532 -285.125414)
					)
					(arc
						(start 136.463532 -285.125414)
						(mid 136.519626 -284.989992)
						(end 136.655048 -284.933898)
					)
					(arc
						(start 136.655048 -284.933898)
						(mid 136.72863 -284.948682)
						(end 136.790938 -284.99054)
					)
					(xy 136.791192 -284.991302)
					(arc
						(start 136.80567 -285.00578)
						(mid 136.819153 -285.012022)
						(end 136.833864 -285.014162)
					)
				)
			)
		)
		(zone
			(layer "F.Cu")
			(hatch none 0.5)
			(connect_pads
				(clearance 0)
			)
			(min_thickness 0.25)
			(keepout
				(tracks not_allowed)
				(vias allowed)
				(pads allowed)
				(copperpour not_allowed)
				(footprints allowed)
			)
			(placement
				(enabled no)
				(sheetname "")
			)
			(fill
				(thermal_gap 0.5)
				(thermal_bridge_width 0.5)
				(island_removal_mode 0)
			)
			(polygon
				(pts
					(arc
						(start 136.90346 -218.23553)
						(mid 136.888581 -218.199609)
						(end 136.85266 -218.18473)
					)
					(arc
						(start 136.85266 -218.18473)
						(mid 136.832503 -218.18879)
						(end 136.815576 -218.200478)
					)
					(arc
						(start 136.815576 -218.200478)
						(mid 136.746854 -218.297738)
						(end 136.722612 -218.414346)
					)
					(arc
						(start 136.722612 -218.414346)
						(mid 136.808166 -218.620892)
						(end 137.014712 -218.706446)
					)
					(arc
						(start 137.014712 -218.706446)
						(mid 137.130134 -218.682675)
						(end 137.226802 -218.61526)
					)
					(arc
						(start 137.226802 -218.61526)
						(mid 137.239371 -218.598032)
						(end 137.24382 -218.57716)
					)
					(arc
						(start 137.24382 -218.57716)
						(mid 137.228941 -218.541239)
						(end 137.19302 -218.52636)
					)
					(arc
						(start 137.19302 -218.52636)
						(mid 137.178434 -218.528499)
						(end 137.16508 -218.534742)
					)
					(xy 137.150602 -218.549474) (xy 137.150094 -218.549728)
					(arc
						(start 137.149586 -218.55049)
						(mid 137.087621 -218.591517)
						(end 137.014712 -218.605862)
					)
					(arc
						(start 137.014712 -218.605862)
						(mid 136.87929 -218.549768)
						(end 136.823196 -218.414346)
					)
					(arc
						(start 136.823196 -218.414346)
						(mid 136.837912 -218.340724)
						(end 136.879838 -218.278456)
					)
					(xy 136.8806 -218.277948)
					(arc
						(start 136.895078 -218.26347)
						(mid 136.901314 -218.250114)
						(end 136.90346 -218.23553)
					)
				)
			)
		)
		(zone
			(layer "F.Cu")
			(hatch none 0.5)
			(connect_pads
				(clearance 0)
			)
			(min_thickness 0.25)
			(keepout
				(tracks not_allowed)
				(vias allowed)
				(pads allowed)
				(copperpour not_allowed)
				(footprints allowed)
			)
			(placement
				(enabled no)
				(sheetname "")
			)
			(fill
				(thermal_gap 0.5)
				(thermal_bridge_width 0.5)
				(island_removal_mode 0)
			)
			(polygon
				(pts
					(arc
						(start 136.90346 -216.607644)
						(mid 136.888581 -216.571723)
						(end 136.85266 -216.556844)
					)
					(arc
						(start 136.85266 -216.556844)
						(mid 136.832476 -216.561026)
						(end 136.815576 -216.572846)
					)
					(arc
						(start 136.815576 -216.572846)
						(mid 136.746905 -216.669989)
						(end 136.722612 -216.78646)
					)
					(arc
						(start 136.722612 -216.78646)
						(mid 136.808166 -216.993006)
						(end 137.014712 -217.07856)
					)
					(arc
						(start 137.014712 -217.07856)
						(mid 137.130134 -217.054789)
						(end 137.226802 -216.987374)
					)
					(arc
						(start 137.226802 -216.987374)
						(mid 137.23932 -216.970262)
						(end 137.24382 -216.949528)
					)
					(arc
						(start 137.24382 -216.949528)
						(mid 137.228941 -216.913607)
						(end 137.19302 -216.898728)
					)
					(arc
						(start 137.19302 -216.898728)
						(mid 137.17844 -216.900713)
						(end 137.16508 -216.906856)
					)
					(xy 137.150602 -216.921588) (xy 137.150094 -216.922096)
					(arc
						(start 137.149586 -216.922604)
						(mid 137.087621 -216.963631)
						(end 137.014712 -216.977976)
					)
					(arc
						(start 137.014712 -216.977976)
						(mid 136.87929 -216.921882)
						(end 136.823196 -216.78646)
					)
					(arc
						(start 136.823196 -216.78646)
						(mid 136.837995 -216.712892)
						(end 136.879838 -216.65057)
					)
					(xy 136.8806 -216.650062)
					(arc
						(start 136.895078 -216.635584)
						(mid 136.901314 -216.622228)
						(end 136.90346 -216.607644)
					)
				)
			)
		)
		(zone
			(layer "F.Cu")
			(hatch none 0.5)
			(connect_pads
				(clearance 0)
			)
			(min_thickness 0.25)
			(keepout
				(tracks not_allowed)
				(vias allowed)
				(pads allowed)
				(copperpour not_allowed)
				(footprints allowed)
			)
			(placement
				(enabled no)
				(sheetname "")
			)
			(fill
				(thermal_gap 0.5)
				(thermal_bridge_width 0.5)
				(island_removal_mode 0)
			)
			(polygon
				(pts
					(arc
						(start 137.30351 -285.827978)
						(mid 137.339431 -285.813099)
						(end 137.35431 -285.777178)
					)
					(arc
						(start 137.35431 -285.777178)
						(mid 137.350199 -285.757159)
						(end 137.338562 -285.740348)
					)
					(arc
						(start 137.338562 -285.740348)
						(mid 137.241302 -285.671626)
						(end 137.124694 -285.647384)
					)
					(arc
						(start 137.124694 -285.647384)
						(mid 136.918312 -285.733028)
						(end 136.832848 -285.939484)
					)
					(arc
						(start 136.832848 -285.939484)
						(mid 136.856564 -286.054725)
						(end 136.92378 -286.15132)
					)
					(arc
						(start 136.92378 -286.15132)
						(mid 136.941008 -286.163889)
						(end 136.96188 -286.168338)
					)
					(arc
						(start 136.96188 -286.168338)
						(mid 136.997801 -286.153459)
						(end 137.01268 -286.117538)
					)
					(arc
						(start 137.01268 -286.117538)
						(mid 137.010505 -286.103084)
						(end 137.004298 -286.089852)
					)
					(xy 136.989566 -286.07512) (xy 136.989058 -286.074866)
					(arc
						(start 136.98855 -286.074104)
						(mid 136.947571 -286.012256)
						(end 136.933178 -285.939484)
					)
					(arc
						(start 136.933178 -285.939484)
						(mid 136.989272 -285.804062)
						(end 137.124694 -285.747968)
					)
					(arc
						(start 137.124694 -285.747968)
						(mid 137.198287 -285.762566)
						(end 137.260584 -285.804356)
					)
					(xy 137.261092 -285.805118)
					(arc
						(start 137.27557 -285.819596)
						(mid 137.288926 -285.825832)
						(end 137.30351 -285.827978)
					)
				)
			)
		)
		(zone
			(layer "F.Cu")
			(hatch none 0.5)
			(connect_pads
				(clearance 0)
			)
			(min_thickness 0.25)
			(keepout
				(tracks not_allowed)
				(vias allowed)
				(pads allowed)
				(copperpour not_allowed)
				(footprints allowed)
			)
			(placement
				(enabled no)
				(sheetname "")
			)
			(fill
				(thermal_gap 0.5)
				(thermal_bridge_width 0.5)
				(island_removal_mode 0)
			)
			(polygon
				(pts
					(arc
						(start 137.30351 -284.200092)
						(mid 137.339341 -284.185303)
						(end 137.35431 -284.149546)
					)
					(arc
						(start 137.35431 -284.149546)
						(mid 137.35025 -284.129389)
						(end 137.338562 -284.112462)
					)
					(arc
						(start 137.338562 -284.112462)
						(mid 137.241302 -284.04374)
						(end 137.124694 -284.019498)
					)
					(arc
						(start 137.124694 -284.019498)
						(mid 136.918312 -284.105142)
						(end 136.832848 -284.311598)
					)
					(arc
						(start 136.832848 -284.311598)
						(mid 136.856498 -284.426992)
						(end 136.92378 -284.523688)
					)
					(arc
						(start 136.92378 -284.523688)
						(mid 136.941008 -284.536257)
						(end 136.96188 -284.540706)
					)
					(arc
						(start 136.96188 -284.540706)
						(mid 136.997801 -284.525827)
						(end 137.01268 -284.489906)
					)
					(arc
						(start 137.01268 -284.489906)
						(mid 137.010541 -284.47532)
						(end 137.004298 -284.461966)
					)
					(xy 136.989566 -284.447488) (xy 136.989058 -284.44698)
					(arc
						(start 136.98855 -284.446218)
						(mid 136.947571 -284.38437)
						(end 136.933178 -284.311598)
					)
					(arc
						(start 136.933178 -284.311598)
						(mid 136.989272 -284.176176)
						(end 137.124694 -284.120082)
					)
					(arc
						(start 137.124694 -284.120082)
						(mid 137.198316 -284.134798)
						(end 137.260584 -284.176724)
					)
					(xy 137.261092 -284.177232)
					(arc
						(start 137.27557 -284.19171)
						(mid 137.288926 -284.197946)
						(end 137.30351 -284.200092)
					)
				)
			)
		)
		(zone
			(layer "F.Cu")
			(hatch none 0.5)
			(connect_pads
				(clearance 0)
			)
			(min_thickness 0.25)
			(keepout
				(tracks not_allowed)
				(vias allowed)
				(pads allowed)
				(copperpour not_allowed)
				(footprints allowed)
			)
			(placement
				(enabled no)
				(sheetname "")
			)
			(fill
				(thermal_gap 0.5)
				(thermal_bridge_width 0.5)
				(island_removal_mode 0)
			)
			(polygon
				(pts
					(arc
						(start 137.37336 -219.049346)
						(mid 137.358481 -219.013425)
						(end 137.32256 -218.998546)
					)
					(arc
						(start 137.32256 -218.998546)
						(mid 137.302513 -219.002778)
						(end 137.28573 -219.014548)
					)
					(arc
						(start 137.28573 -219.014548)
						(mid 137.217001 -219.111675)
						(end 137.192766 -219.228162)
					)
					(arc
						(start 137.192766 -219.228162)
						(mid 137.27832 -219.434708)
						(end 137.484866 -219.520262)
					)
					(arc
						(start 137.484866 -219.520262)
						(mid 137.600151 -219.49644)
						(end 137.696702 -219.429076)
					)
					(arc
						(start 137.696702 -219.429076)
						(mid 137.70922 -219.411964)
						(end 137.71372 -219.39123)
					)
					(arc
						(start 137.71372 -219.39123)
						(mid 137.698841 -219.355309)
						(end 137.66292 -219.34043)
					)
					(arc
						(start 137.66292 -219.34043)
						(mid 137.648472 -219.342453)
						(end 137.635234 -219.348558)
					)
					(xy 137.620502 -219.36329) (xy 137.620248 -219.363798)
					(arc
						(start 137.619486 -219.364306)
						(mid 137.557638 -219.405285)
						(end 137.484866 -219.419678)
					)
					(arc
						(start 137.484866 -219.419678)
						(mid 137.349444 -219.363584)
						(end 137.29335 -219.228162)
					)
					(arc
						(start 137.29335 -219.228162)
						(mid 137.308066 -219.15454)
						(end 137.349992 -219.092272)
					)
					(xy 137.3505 -219.091764)
					(arc
						(start 137.364978 -219.077286)
						(mid 137.371214 -219.06393)
						(end 137.37336 -219.049346)
					)
				)
			)
		)
		(zone
			(layer "F.Cu")
			(hatch none 0.5)
			(connect_pads
				(clearance 0)
			)
			(min_thickness 0.25)
			(keepout
				(tracks not_allowed)
				(vias allowed)
				(pads allowed)
				(copperpour not_allowed)
				(footprints allowed)
			)
			(placement
				(enabled no)
				(sheetname "")
			)
			(fill
				(thermal_gap 0.5)
				(thermal_bridge_width 0.5)
				(island_removal_mode 0)
			)
			(polygon
				(pts
					(arc
						(start 137.37336 -217.42146)
						(mid 137.358481 -217.385539)
						(end 137.32256 -217.37066)
					)
					(arc
						(start 137.32256 -217.37066)
						(mid 137.302513 -217.374892)
						(end 137.28573 -217.386662)
					)
					(arc
						(start 137.28573 -217.386662)
						(mid 137.217059 -217.483805)
						(end 137.192766 -217.600276)
					)
					(arc
						(start 137.192766 -217.600276)
						(mid 137.27832 -217.806822)
						(end 137.484866 -217.892376)
					)
					(arc
						(start 137.484866 -217.892376)
						(mid 137.600192 -217.868623)
						(end 137.696702 -217.80119)
					)
					(arc
						(start 137.696702 -217.80119)
						(mid 137.70922 -217.784078)
						(end 137.71372 -217.763344)
					)
					(arc
						(start 137.71372 -217.763344)
						(mid 137.698841 -217.727423)
						(end 137.66292 -217.712544)
					)
					(arc
						(start 137.66292 -217.712544)
						(mid 137.648466 -217.714719)
						(end 137.635234 -217.720926)
					)
					(xy 137.620502 -217.735658) (xy 137.620248 -217.735912)
					(arc
						(start 137.619486 -217.736674)
						(mid 137.557609 -217.777518)
						(end 137.484866 -217.791792)
					)
					(arc
						(start 137.484866 -217.791792)
						(mid 137.349444 -217.735698)
						(end 137.29335 -217.600276)
					)
					(arc
						(start 137.29335 -217.600276)
						(mid 137.308066 -217.526654)
						(end 137.349992 -217.464386)
					)
					(xy 137.3505 -217.464132)
					(arc
						(start 137.364978 -217.449654)
						(mid 137.371251 -217.436176)
						(end 137.37336 -217.42146)
					)
				)
			)
		)
		(zone
			(layer "F.Cu")
			(hatch none 0.5)
			(connect_pads
				(clearance 0)
			)
			(min_thickness 0.25)
			(keepout
				(tracks not_allowed)
				(vias allowed)
				(pads allowed)
				(copperpour not_allowed)
				(footprints allowed)
			)
			(placement
				(enabled no)
				(sheetname "")
			)
			(fill
				(thermal_gap 0.5)
				(thermal_bridge_width 0.5)
				(island_removal_mode 0)
			)
			(polygon
				(pts
					(arc
						(start 137.532364 -249.950732)
						(mid 137.547199 -249.914918)
						(end 137.532364 -249.879104)
					)
					(arc
						(start 137.532364 -249.879104)
						(mid 137.515242 -249.867753)
						(end 137.495026 -249.864118)
					)
					(arc
						(start 137.495026 -249.864118)
						(mid 137.377825 -249.884267)
						(end 137.278364 -249.949462)
					)
					(arc
						(start 137.278364 -249.949462)
						(mid 137.192828 -250.155964)
						(end 137.278364 -250.362466)
					)
					(arc
						(start 137.278364 -250.362466)
						(mid 137.376608 -250.427348)
						(end 137.492486 -250.448064)
					)
					(arc
						(start 137.492486 -250.448064)
						(mid 137.513676 -250.444812)
						(end 137.531602 -250.433078)
					)
					(arc
						(start 137.531602 -250.433078)
						(mid 137.546362 -250.397174)
						(end 137.531602 -250.361196)
					)
					(arc
						(start 137.531602 -250.361196)
						(mid 137.519781 -250.352454)
						(end 137.505948 -250.34748)
					)
					(xy 137.48512 -250.34748) (xy 137.484612 -250.34748)
					(arc
						(start 137.483596 -250.34748)
						(mid 137.411041 -250.33258)
						(end 137.349484 -250.291346)
					)
					(arc
						(start 137.349484 -250.291346)
						(mid 137.293407 -250.155964)
						(end 137.349484 -250.020582)
					)
					(arc
						(start 137.349484 -250.020582)
						(mid 137.411832 -249.978982)
						(end 137.485374 -249.964448)
					)
					(xy 137.486136 -249.964702)
					(arc
						(start 137.50671 -249.964702)
						(mid 137.520572 -249.959612)
						(end 137.532364 -249.950732)
					)
				)
			)
		)
		(zone
			(layer "F.Cu")
			(hatch none 0.5)
			(connect_pads
				(clearance 0)
			)
			(min_thickness 0.25)
			(keepout
				(tracks not_allowed)
				(vias allowed)
				(pads allowed)
				(copperpour not_allowed)
				(footprints allowed)
			)
			(placement
				(enabled no)
				(sheetname "")
			)
			(fill
				(thermal_gap 0.5)
				(thermal_bridge_width 0.5)
				(island_removal_mode 0)
			)
			(polygon
				(pts
					(arc
						(start 137.77341 -286.641794)
						(mid 137.809241 -286.627005)
						(end 137.82421 -286.591248)
					)
					(arc
						(start 137.82421 -286.591248)
						(mid 137.82015 -286.571091)
						(end 137.808462 -286.554164)
					)
					(arc
						(start 137.808462 -286.554164)
						(mid 137.711202 -286.485442)
						(end 137.594594 -286.4612)
					)
					(arc
						(start 137.594594 -286.4612)
						(mid 137.388212 -286.546844)
						(end 137.302748 -286.7533)
					)
					(arc
						(start 137.302748 -286.7533)
						(mid 137.326398 -286.868694)
						(end 137.39368 -286.96539)
					)
					(arc
						(start 137.39368 -286.96539)
						(mid 137.410942 -286.977811)
						(end 137.43178 -286.982154)
					)
					(arc
						(start 137.43178 -286.982154)
						(mid 137.467701 -286.967275)
						(end 137.48258 -286.931354)
					)
					(arc
						(start 137.48258 -286.931354)
						(mid 137.480405 -286.9169)
						(end 137.474198 -286.903668)
					)
					(xy 137.459466 -286.88919) (xy 137.458958 -286.888682)
					(arc
						(start 137.45845 -286.88792)
						(mid 137.417471 -286.826072)
						(end 137.403078 -286.7533)
					)
					(arc
						(start 137.403078 -286.7533)
						(mid 137.459172 -286.617878)
						(end 137.594594 -286.561784)
					)
					(arc
						(start 137.594594 -286.561784)
						(mid 137.668216 -286.5765)
						(end 137.730484 -286.618426)
					)
					(xy 137.730992 -286.618934)
					(arc
						(start 137.74547 -286.633412)
						(mid 137.758826 -286.639648)
						(end 137.77341 -286.641794)
					)
				)
			)
		)
		(zone
			(layer "F.Cu")
			(hatch none 0.5)
			(connect_pads
				(clearance 0)
			)
			(min_thickness 0.25)
			(keepout
				(tracks not_allowed)
				(vias allowed)
				(pads allowed)
				(copperpour not_allowed)
				(footprints allowed)
			)
			(placement
				(enabled no)
				(sheetname "")
			)
			(fill
				(thermal_gap 0.5)
				(thermal_bridge_width 0.5)
				(island_removal_mode 0)
			)
			(polygon
				(pts
					(arc
						(start 137.77341 -285.014162)
						(mid 137.809331 -284.999283)
						(end 137.82421 -284.963362)
					)
					(arc
						(start 137.82421 -284.963362)
						(mid 137.82015 -284.943205)
						(end 137.808462 -284.926278)
					)
					(arc
						(start 137.808462 -284.926278)
						(mid 137.71117 -284.8577)
						(end 137.594594 -284.833568)
					)
					(arc
						(start 137.594594 -284.833568)
						(mid 137.388228 -284.919048)
						(end 137.302748 -285.125414)
					)
					(arc
						(start 137.302748 -285.125414)
						(mid 137.326398 -285.240808)
						(end 137.39368 -285.337504)
					)
					(arc
						(start 137.39368 -285.337504)
						(mid 137.410908 -285.350073)
						(end 137.43178 -285.354522)
					)
					(arc
						(start 137.43178 -285.354522)
						(mid 137.467701 -285.339643)
						(end 137.48258 -285.303722)
					)
					(arc
						(start 137.48258 -285.303722)
						(mid 137.480441 -285.289136)
						(end 137.474198 -285.275782)
					)
					(xy 137.459466 -285.261304) (xy 137.458958 -285.260796)
					(arc
						(start 137.45845 -285.260288)
						(mid 137.417423 -285.198323)
						(end 137.403078 -285.125414)
					)
					(arc
						(start 137.403078 -285.125414)
						(mid 137.459172 -284.989992)
						(end 137.594594 -284.933898)
					)
					(arc
						(start 137.594594 -284.933898)
						(mid 137.668216 -284.948614)
						(end 137.730484 -284.99054)
					)
					(xy 137.730992 -284.991302)
					(arc
						(start 137.74547 -285.00578)
						(mid 137.758826 -285.012016)
						(end 137.77341 -285.014162)
					)
				)
			)
		)
		(zone
			(layer "F.Cu")
			(hatch none 0.5)
			(connect_pads
				(clearance 0)
			)
			(min_thickness 0.25)
			(keepout
				(tracks not_allowed)
				(vias allowed)
				(pads allowed)
				(copperpour not_allowed)
				(footprints allowed)
			)
			(placement
				(enabled no)
				(sheetname "")
			)
			(fill
				(thermal_gap 0.5)
				(thermal_bridge_width 0.5)
				(island_removal_mode 0)
			)
			(polygon
				(pts
					(arc
						(start 137.77341 -283.386276)
						(mid 137.809331 -283.371397)
						(end 137.82421 -283.335476)
					)
					(arc
						(start 137.82421 -283.335476)
						(mid 137.820099 -283.315457)
						(end 137.808462 -283.298646)
					)
					(arc
						(start 137.808462 -283.298646)
						(mid 137.711202 -283.229924)
						(end 137.594594 -283.205682)
					)
					(arc
						(start 137.594594 -283.205682)
						(mid 137.388212 -283.291326)
						(end 137.302748 -283.497782)
					)
					(arc
						(start 137.302748 -283.497782)
						(mid 137.326464 -283.613023)
						(end 137.39368 -283.709618)
					)
					(arc
						(start 137.39368 -283.709618)
						(mid 137.410908 -283.722187)
						(end 137.43178 -283.726636)
					)
					(arc
						(start 137.43178 -283.726636)
						(mid 137.467701 -283.711757)
						(end 137.48258 -283.675836)
					)
					(arc
						(start 137.48258 -283.675836)
						(mid 137.480405 -283.661382)
						(end 137.474198 -283.64815)
					)
					(xy 137.459466 -283.633418) (xy 137.458958 -283.633164)
					(arc
						(start 137.45845 -283.632402)
						(mid 137.417471 -283.570554)
						(end 137.403078 -283.497782)
					)
					(arc
						(start 137.403078 -283.497782)
						(mid 137.459172 -283.36236)
						(end 137.594594 -283.306266)
					)
					(arc
						(start 137.594594 -283.306266)
						(mid 137.668187 -283.320864)
						(end 137.730484 -283.362654)
					)
					(xy 137.730992 -283.363416)
					(arc
						(start 137.74547 -283.377894)
						(mid 137.758826 -283.38413)
						(end 137.77341 -283.386276)
					)
				)
			)
		)
		(zone
			(layer "F.Cu")
			(hatch none 0.5)
			(connect_pads
				(clearance 0)
			)
			(min_thickness 0.25)
			(keepout
				(tracks not_allowed)
				(vias allowed)
				(pads allowed)
				(copperpour not_allowed)
				(footprints allowed)
			)
			(placement
				(enabled no)
				(sheetname "")
			)
			(fill
				(thermal_gap 0.5)
				(thermal_bridge_width 0.5)
				(island_removal_mode 0)
			)
			(polygon
				(pts
					(arc
						(start 137.84326 -219.863162)
						(mid 137.828381 -219.827241)
						(end 137.79246 -219.812362)
					)
					(arc
						(start 137.79246 -219.812362)
						(mid 137.772413 -219.816594)
						(end 137.75563 -219.828364)
					)
					(arc
						(start 137.75563 -219.828364)
						(mid 137.686959 -219.925507)
						(end 137.662666 -220.041978)
					)
					(arc
						(start 137.662666 -220.041978)
						(mid 137.74822 -220.248524)
						(end 137.954766 -220.334078)
					)
					(arc
						(start 137.954766 -220.334078)
						(mid 138.070092 -220.310325)
						(end 138.166602 -220.242892)
					)
					(arc
						(start 138.166602 -220.242892)
						(mid 138.17912 -220.22578)
						(end 138.18362 -220.205046)
					)
					(arc
						(start 138.18362 -220.205046)
						(mid 138.168741 -220.169125)
						(end 138.13282 -220.154246)
					)
					(arc
						(start 138.13282 -220.154246)
						(mid 138.118366 -220.156421)
						(end 138.105134 -220.162628)
					)
					(xy 138.090402 -220.17736) (xy 138.090148 -220.177614)
					(arc
						(start 138.089386 -220.178376)
						(mid 138.027509 -220.21922)
						(end 137.954766 -220.233494)
					)
					(arc
						(start 137.954766 -220.233494)
						(mid 137.819344 -220.1774)
						(end 137.76325 -220.041978)
					)
					(arc
						(start 137.76325 -220.041978)
						(mid 137.777966 -219.968356)
						(end 137.819892 -219.906088)
					)
					(xy 137.8204 -219.905834)
					(arc
						(start 137.834878 -219.891356)
						(mid 137.841151 -219.877878)
						(end 137.84326 -219.863162)
					)
				)
			)
		)
		(zone
			(layer "F.Cu")
			(hatch none 0.5)
			(connect_pads
				(clearance 0)
			)
			(min_thickness 0.25)
			(keepout
				(tracks not_allowed)
				(vias allowed)
				(pads allowed)
				(copperpour not_allowed)
				(footprints allowed)
			)
			(placement
				(enabled no)
				(sheetname "")
			)
			(fill
				(thermal_gap 0.5)
				(thermal_bridge_width 0.5)
				(island_removal_mode 0)
			)
			(polygon
				(pts
					(arc
						(start 137.84326 -218.23553)
						(mid 137.828381 -218.199609)
						(end 137.79246 -218.18473)
					)
					(arc
						(start 137.79246 -218.18473)
						(mid 137.772441 -218.188841)
						(end 137.75563 -218.200478)
					)
					(arc
						(start 137.75563 -218.200478)
						(mid 137.686908 -218.297738)
						(end 137.662666 -218.414346)
					)
					(arc
						(start 137.662666 -218.414346)
						(mid 137.74822 -218.620892)
						(end 137.954766 -218.706446)
					)
					(arc
						(start 137.954766 -218.706446)
						(mid 138.070051 -218.682624)
						(end 138.166602 -218.61526)
					)
					(arc
						(start 138.166602 -218.61526)
						(mid 138.179171 -218.598032)
						(end 138.18362 -218.57716)
					)
					(arc
						(start 138.18362 -218.57716)
						(mid 138.168741 -218.541239)
						(end 138.13282 -218.52636)
					)
					(arc
						(start 138.13282 -218.52636)
						(mid 138.118366 -218.528535)
						(end 138.105134 -218.534742)
					)
					(xy 138.090402 -218.549474) (xy 138.090148 -218.549728)
					(arc
						(start 138.089386 -218.55049)
						(mid 138.027538 -218.591469)
						(end 137.954766 -218.605862)
					)
					(arc
						(start 137.954766 -218.605862)
						(mid 137.819344 -218.549768)
						(end 137.76325 -218.414346)
					)
					(arc
						(start 137.76325 -218.414346)
						(mid 137.777966 -218.340724)
						(end 137.819892 -218.278456)
					)
					(xy 137.8204 -218.277948)
					(arc
						(start 137.834878 -218.26347)
						(mid 137.841114 -218.250114)
						(end 137.84326 -218.23553)
					)
				)
			)
		)
		(zone
			(layer "F.Cu")
			(hatch none 0.5)
			(connect_pads
				(clearance 0)
			)
			(min_thickness 0.25)
			(keepout
				(tracks not_allowed)
				(vias allowed)
				(pads allowed)
				(copperpour not_allowed)
				(footprints allowed)
			)
			(placement
				(enabled no)
				(sheetname "")
			)
			(fill
				(thermal_gap 0.5)
				(thermal_bridge_width 0.5)
				(island_removal_mode 0)
			)
			(polygon
				(pts
					(arc
						(start 137.84326 -216.607644)
						(mid 137.828381 -216.571723)
						(end 137.79246 -216.556844)
					)
					(arc
						(start 137.79246 -216.556844)
						(mid 137.772413 -216.561076)
						(end 137.75563 -216.572846)
					)
					(arc
						(start 137.75563 -216.572846)
						(mid 137.686901 -216.669973)
						(end 137.662666 -216.78646)
					)
					(arc
						(start 137.662666 -216.78646)
						(mid 137.74822 -216.993006)
						(end 137.954766 -217.07856)
					)
					(arc
						(start 137.954766 -217.07856)
						(mid 138.070051 -217.054738)
						(end 138.166602 -216.987374)
					)
					(arc
						(start 138.166602 -216.987374)
						(mid 138.17912 -216.970262)
						(end 138.18362 -216.949528)
					)
					(arc
						(start 138.18362 -216.949528)
						(mid 138.168741 -216.913607)
						(end 138.13282 -216.898728)
					)
					(arc
						(start 138.13282 -216.898728)
						(mid 138.118372 -216.900751)
						(end 138.105134 -216.906856)
					)
					(xy 138.090402 -216.921588) (xy 138.090148 -216.922096)
					(arc
						(start 138.089386 -216.922604)
						(mid 138.027538 -216.963583)
						(end 137.954766 -216.977976)
					)
					(arc
						(start 137.954766 -216.977976)
						(mid 137.819344 -216.921882)
						(end 137.76325 -216.78646)
					)
					(arc
						(start 137.76325 -216.78646)
						(mid 137.777966 -216.712838)
						(end 137.819892 -216.65057)
					)
					(xy 137.8204 -216.650062)
					(arc
						(start 137.834878 -216.635584)
						(mid 137.841114 -216.622228)
						(end 137.84326 -216.607644)
					)
				)
			)
		)
		(zone
			(layer "F.Cu")
			(hatch none 0.5)
			(connect_pads
				(clearance 0)
			)
			(min_thickness 0.25)
			(keepout
				(tracks not_allowed)
				(vias allowed)
				(pads allowed)
				(copperpour not_allowed)
				(footprints allowed)
			)
			(placement
				(enabled no)
				(sheetname "")
			)
			(fill
				(thermal_gap 0.5)
				(thermal_bridge_width 0.5)
				(island_removal_mode 0)
			)
			(polygon
				(pts
					(arc
						(start 138.002264 -249.136916)
						(mid 138.017099 -249.101013)
						(end 138.002264 -249.065034)
					)
					(arc
						(start 138.002264 -249.065034)
						(mid 137.985111 -249.053823)
						(end 137.964926 -249.050302)
					)
					(arc
						(start 137.964926 -249.050302)
						(mid 137.847725 -249.070451)
						(end 137.748264 -249.135646)
					)
					(arc
						(start 137.748264 -249.135646)
						(mid 137.662728 -249.342148)
						(end 137.748264 -249.54865)
					)
					(arc
						(start 137.748264 -249.54865)
						(mid 137.846539 -249.613391)
						(end 137.962386 -249.633994)
					)
					(arc
						(start 137.962386 -249.633994)
						(mid 137.983536 -249.630853)
						(end 138.001502 -249.619262)
					)
					(arc
						(start 138.001502 -249.619262)
						(mid 138.016262 -249.583358)
						(end 138.001502 -249.54738)
					)
					(arc
						(start 138.001502 -249.54738)
						(mid 137.989681 -249.538638)
						(end 137.975848 -249.533664)
					)
					(xy 137.95502 -249.533664) (xy 137.954512 -249.533664)
					(arc
						(start 137.953496 -249.533664)
						(mid 137.880927 -249.518779)
						(end 137.819384 -249.47753)
					)
					(arc
						(start 137.819384 -249.47753)
						(mid 137.763307 -249.342148)
						(end 137.819384 -249.206766)
					)
					(arc
						(start 137.819384 -249.206766)
						(mid 137.881732 -249.165166)
						(end 137.955274 -249.150632)
					)
					(xy 137.956036 -249.150886)
					(arc
						(start 137.97661 -249.150886)
						(mid 137.990472 -249.145796)
						(end 138.002264 -249.136916)
					)
				)
			)
		)
		(zone
			(layer "F.Cu")
			(hatch none 0.5)
			(connect_pads
				(clearance 0)
			)
			(min_thickness 0.25)
			(keepout
				(tracks not_allowed)
				(vias allowed)
				(pads allowed)
				(copperpour not_allowed)
				(footprints allowed)
			)
			(placement
				(enabled no)
				(sheetname "")
			)
			(fill
				(thermal_gap 0.5)
				(thermal_bridge_width 0.5)
				(island_removal_mode 0)
			)
			(polygon
				(pts
					(arc
						(start 138.112246 -253.178564)
						(mid 138.127081 -253.142661)
						(end 138.112246 -253.106682)
					)
					(arc
						(start 138.112246 -253.106682)
						(mid 138.095093 -253.095471)
						(end 138.074908 -253.09195)
					)
					(arc
						(start 138.074908 -253.09195)
						(mid 137.957567 -253.112044)
						(end 137.857992 -253.177294)
					)
					(arc
						(start 137.857992 -253.177294)
						(mid 137.772456 -253.383796)
						(end 137.857992 -253.590298)
					)
					(arc
						(start 137.857992 -253.590298)
						(mid 137.956354 -253.655227)
						(end 138.072368 -253.675896)
					)
					(arc
						(start 138.072368 -253.675896)
						(mid 138.093417 -253.672585)
						(end 138.11123 -253.66091)
					)
					(arc
						(start 138.11123 -253.66091)
						(mid 138.126065 -253.625007)
						(end 138.11123 -253.589028)
					)
					(arc
						(start 138.11123 -253.589028)
						(mid 138.099409 -253.580286)
						(end 138.085576 -253.575312)
					)
					(xy 138.065002 -253.575312) (xy 138.064494 -253.575312)
					(arc
						(start 138.063478 -253.575312)
						(mid 137.990773 -253.560474)
						(end 137.929112 -253.519178)
					)
					(arc
						(start 137.929112 -253.519178)
						(mid 137.873035 -253.383796)
						(end 137.929112 -253.248414)
					)
					(arc
						(start 137.929112 -253.248414)
						(mid 137.991578 -253.206765)
						(end 138.065256 -253.19228)
					)
					(xy 138.066018 -253.192534)
					(arc
						(start 138.086592 -253.192534)
						(mid 138.100454 -253.187444)
						(end 138.112246 -253.178564)
					)
				)
			)
		)
		(zone
			(layer "F.Cu")
			(hatch none 0.5)
			(connect_pads
				(clearance 0)
			)
			(min_thickness 0.25)
			(keepout
				(tracks not_allowed)
				(vias allowed)
				(pads allowed)
				(copperpour not_allowed)
				(footprints allowed)
			)
			(placement
				(enabled no)
				(sheetname "")
			)
			(fill
				(thermal_gap 0.5)
				(thermal_bridge_width 0.5)
				(island_removal_mode 0)
			)
			(polygon
				(pts
					(arc
						(start 138.24331 -285.827978)
						(mid 138.279231 -285.813099)
						(end 138.29411 -285.777178)
					)
					(arc
						(start 138.29411 -285.777178)
						(mid 138.289999 -285.757159)
						(end 138.278362 -285.740348)
					)
					(arc
						(start 138.278362 -285.740348)
						(mid 138.181102 -285.671626)
						(end 138.064494 -285.647384)
					)
					(arc
						(start 138.064494 -285.647384)
						(mid 137.858112 -285.733028)
						(end 137.772648 -285.939484)
					)
					(arc
						(start 137.772648 -285.939484)
						(mid 137.796364 -286.054725)
						(end 137.86358 -286.15132)
					)
					(arc
						(start 137.86358 -286.15132)
						(mid 137.880808 -286.163889)
						(end 137.90168 -286.168338)
					)
					(arc
						(start 137.90168 -286.168338)
						(mid 137.937601 -286.153459)
						(end 137.95248 -286.117538)
					)
					(arc
						(start 137.95248 -286.117538)
						(mid 137.950305 -286.103084)
						(end 137.944098 -286.089852)
					)
					(xy 137.929366 -286.07512) (xy 137.928858 -286.074866)
					(arc
						(start 137.92835 -286.074104)
						(mid 137.887371 -286.012256)
						(end 137.872978 -285.939484)
					)
					(arc
						(start 137.872978 -285.939484)
						(mid 137.929072 -285.804062)
						(end 138.064494 -285.747968)
					)
					(arc
						(start 138.064494 -285.747968)
						(mid 138.138087 -285.762566)
						(end 138.200384 -285.804356)
					)
					(xy 138.200892 -285.805118)
					(arc
						(start 138.21537 -285.819596)
						(mid 138.228726 -285.825832)
						(end 138.24331 -285.827978)
					)
				)
			)
		)
		(zone
			(layer "F.Cu")
			(hatch none 0.5)
			(connect_pads
				(clearance 0)
			)
			(min_thickness 0.25)
			(keepout
				(tracks not_allowed)
				(vias allowed)
				(pads allowed)
				(copperpour not_allowed)
				(footprints allowed)
			)
			(placement
				(enabled no)
				(sheetname "")
			)
			(fill
				(thermal_gap 0.5)
				(thermal_bridge_width 0.5)
				(island_removal_mode 0)
			)
			(polygon
				(pts
					(arc
						(start 138.24331 -284.200092)
						(mid 138.279141 -284.185303)
						(end 138.29411 -284.149546)
					)
					(arc
						(start 138.29411 -284.149546)
						(mid 138.29005 -284.129389)
						(end 138.278362 -284.112462)
					)
					(arc
						(start 138.278362 -284.112462)
						(mid 138.181102 -284.04374)
						(end 138.064494 -284.019498)
					)
					(arc
						(start 138.064494 -284.019498)
						(mid 137.858112 -284.105142)
						(end 137.772648 -284.311598)
					)
					(arc
						(start 137.772648 -284.311598)
						(mid 137.796298 -284.426992)
						(end 137.86358 -284.523688)
					)
					(arc
						(start 137.86358 -284.523688)
						(mid 137.880808 -284.536257)
						(end 137.90168 -284.540706)
					)
					(arc
						(start 137.90168 -284.540706)
						(mid 137.937601 -284.525827)
						(end 137.95248 -284.489906)
					)
					(arc
						(start 137.95248 -284.489906)
						(mid 137.950341 -284.47532)
						(end 137.944098 -284.461966)
					)
					(xy 137.929366 -284.447488) (xy 137.928858 -284.44698)
					(arc
						(start 137.92835 -284.446218)
						(mid 137.887371 -284.38437)
						(end 137.872978 -284.311598)
					)
					(arc
						(start 137.872978 -284.311598)
						(mid 137.929072 -284.176176)
						(end 138.064494 -284.120082)
					)
					(arc
						(start 138.064494 -284.120082)
						(mid 138.138116 -284.134798)
						(end 138.200384 -284.176724)
					)
					(xy 138.200892 -284.177232)
					(arc
						(start 138.21537 -284.19171)
						(mid 138.228726 -284.197946)
						(end 138.24331 -284.200092)
					)
				)
			)
		)
		(zone
			(layer "F.Cu")
			(hatch none 0.5)
			(connect_pads
				(clearance 0)
			)
			(min_thickness 0.25)
			(keepout
				(tracks not_allowed)
				(vias allowed)
				(pads allowed)
				(copperpour not_allowed)
				(footprints allowed)
			)
			(placement
				(enabled no)
				(sheetname "")
			)
			(fill
				(thermal_gap 0.5)
				(thermal_bridge_width 0.5)
				(island_removal_mode 0)
			)
			(polygon
				(pts
					(arc
						(start 138.24331 -282.57246)
						(mid 138.279231 -282.557581)
						(end 138.29411 -282.52166)
					)
					(arc
						(start 138.29411 -282.52166)
						(mid 138.289999 -282.501641)
						(end 138.278362 -282.48483)
					)
					(arc
						(start 138.278362 -282.48483)
						(mid 138.181102 -282.416108)
						(end 138.064494 -282.391866)
					)
					(arc
						(start 138.064494 -282.391866)
						(mid 137.858112 -282.47751)
						(end 137.772648 -282.683966)
					)
					(arc
						(start 137.772648 -282.683966)
						(mid 137.796364 -282.799207)
						(end 137.86358 -282.895802)
					)
					(arc
						(start 137.86358 -282.895802)
						(mid 137.880808 -282.908371)
						(end 137.90168 -282.91282)
					)
					(arc
						(start 137.90168 -282.91282)
						(mid 137.937601 -282.897941)
						(end 137.95248 -282.86202)
					)
					(arc
						(start 137.95248 -282.86202)
						(mid 137.950305 -282.847566)
						(end 137.944098 -282.834334)
					)
					(xy 137.929366 -282.819602) (xy 137.928858 -282.819348)
					(arc
						(start 137.92835 -282.818586)
						(mid 137.887371 -282.756738)
						(end 137.872978 -282.683966)
					)
					(arc
						(start 137.872978 -282.683966)
						(mid 137.929072 -282.548544)
						(end 138.064494 -282.49245)
					)
					(arc
						(start 138.064494 -282.49245)
						(mid 138.138116 -282.507166)
						(end 138.200384 -282.549092)
					)
					(xy 138.200892 -282.5496)
					(arc
						(start 138.21537 -282.564078)
						(mid 138.228726 -282.570314)
						(end 138.24331 -282.57246)
					)
				)
			)
		)
		(zone
			(layer "F.Cu")
			(hatch none 0.5)
			(connect_pads
				(clearance 0)
			)
			(min_thickness 0.25)
			(keepout
				(tracks not_allowed)
				(vias allowed)
				(pads allowed)
				(copperpour not_allowed)
				(footprints allowed)
			)
			(placement
				(enabled no)
				(sheetname "")
			)
			(fill
				(thermal_gap 0.5)
				(thermal_bridge_width 0.5)
				(island_removal_mode 0)
			)
			(polygon
				(pts
					(arc
						(start 138.31316 -220.676978)
						(mid 138.298281 -220.641057)
						(end 138.26236 -220.626178)
					)
					(arc
						(start 138.26236 -220.626178)
						(mid 138.242313 -220.63041)
						(end 138.22553 -220.64218)
					)
					(arc
						(start 138.22553 -220.64218)
						(mid 138.156859 -220.739323)
						(end 138.132566 -220.855794)
					)
					(arc
						(start 138.132566 -220.855794)
						(mid 138.21812 -221.06234)
						(end 138.424666 -221.147894)
					)
					(arc
						(start 138.424666 -221.147894)
						(mid 138.539992 -221.124141)
						(end 138.636502 -221.056708)
					)
					(arc
						(start 138.636502 -221.056708)
						(mid 138.64902 -221.039596)
						(end 138.65352 -221.018862)
					)
					(arc
						(start 138.65352 -221.018862)
						(mid 138.638641 -220.982941)
						(end 138.60272 -220.968062)
					)
					(arc
						(start 138.60272 -220.968062)
						(mid 138.588266 -220.970237)
						(end 138.575034 -220.976444)
					)
					(xy 138.560302 -220.991176) (xy 138.560048 -220.99143)
					(arc
						(start 138.559286 -220.992192)
						(mid 138.497409 -221.033036)
						(end 138.424666 -221.04731)
					)
					(arc
						(start 138.424666 -221.04731)
						(mid 138.289244 -220.991216)
						(end 138.23315 -220.855794)
					)
					(arc
						(start 138.23315 -220.855794)
						(mid 138.247866 -220.782172)
						(end 138.289792 -220.719904)
					)
					(xy 138.2903 -220.71965)
					(arc
						(start 138.304778 -220.705172)
						(mid 138.311051 -220.691694)
						(end 138.31316 -220.676978)
					)
				)
			)
		)
		(zone
			(layer "F.Cu")
			(hatch none 0.5)
			(connect_pads
				(clearance 0)
			)
			(min_thickness 0.25)
			(keepout
				(tracks not_allowed)
				(vias allowed)
				(pads allowed)
				(copperpour not_allowed)
				(footprints allowed)
			)
			(placement
				(enabled no)
				(sheetname "")
			)
			(fill
				(thermal_gap 0.5)
				(thermal_bridge_width 0.5)
				(island_removal_mode 0)
			)
			(polygon
				(pts
					(arc
						(start 138.31316 -219.049346)
						(mid 138.298281 -219.013425)
						(end 138.26236 -218.998546)
					)
					(arc
						(start 138.26236 -218.998546)
						(mid 138.242313 -219.002778)
						(end 138.22553 -219.014548)
					)
					(arc
						(start 138.22553 -219.014548)
						(mid 138.156801 -219.111675)
						(end 138.132566 -219.228162)
					)
					(arc
						(start 138.132566 -219.228162)
						(mid 138.21812 -219.434708)
						(end 138.424666 -219.520262)
					)
					(arc
						(start 138.424666 -219.520262)
						(mid 138.539951 -219.49644)
						(end 138.636502 -219.429076)
					)
					(arc
						(start 138.636502 -219.429076)
						(mid 138.64902 -219.411964)
						(end 138.65352 -219.39123)
					)
					(arc
						(start 138.65352 -219.39123)
						(mid 138.638641 -219.355309)
						(end 138.60272 -219.34043)
					)
					(arc
						(start 138.60272 -219.34043)
						(mid 138.588272 -219.342453)
						(end 138.575034 -219.348558)
					)
					(xy 138.560302 -219.36329) (xy 138.560048 -219.363798)
					(arc
						(start 138.559286 -219.364306)
						(mid 138.497438 -219.405285)
						(end 138.424666 -219.419678)
					)
					(arc
						(start 138.424666 -219.419678)
						(mid 138.289244 -219.363584)
						(end 138.23315 -219.228162)
					)
					(arc
						(start 138.23315 -219.228162)
						(mid 138.247866 -219.15454)
						(end 138.289792 -219.092272)
					)
					(xy 138.2903 -219.091764)
					(arc
						(start 138.304778 -219.077286)
						(mid 138.311014 -219.06393)
						(end 138.31316 -219.049346)
					)
				)
			)
		)
		(zone
			(layer "F.Cu")
			(hatch none 0.5)
			(connect_pads
				(clearance 0)
			)
			(min_thickness 0.25)
			(keepout
				(tracks not_allowed)
				(vias allowed)
				(pads allowed)
				(copperpour not_allowed)
				(footprints allowed)
			)
			(placement
				(enabled no)
				(sheetname "")
			)
			(fill
				(thermal_gap 0.5)
				(thermal_bridge_width 0.5)
				(island_removal_mode 0)
			)
			(polygon
				(pts
					(arc
						(start 138.31316 -217.42146)
						(mid 138.298281 -217.385539)
						(end 138.26236 -217.37066)
					)
					(arc
						(start 138.26236 -217.37066)
						(mid 138.242313 -217.374892)
						(end 138.22553 -217.386662)
					)
					(arc
						(start 138.22553 -217.386662)
						(mid 138.156859 -217.483805)
						(end 138.132566 -217.600276)
					)
					(arc
						(start 138.132566 -217.600276)
						(mid 138.21812 -217.806822)
						(end 138.424666 -217.892376)
					)
					(arc
						(start 138.424666 -217.892376)
						(mid 138.539992 -217.868623)
						(end 138.636502 -217.80119)
					)
					(arc
						(start 138.636502 -217.80119)
						(mid 138.64902 -217.784078)
						(end 138.65352 -217.763344)
					)
					(arc
						(start 138.65352 -217.763344)
						(mid 138.638641 -217.727423)
						(end 138.60272 -217.712544)
					)
					(arc
						(start 138.60272 -217.712544)
						(mid 138.588266 -217.714719)
						(end 138.575034 -217.720926)
					)
					(xy 138.560302 -217.735658) (xy 138.560048 -217.735912)
					(arc
						(start 138.559286 -217.736674)
						(mid 138.497409 -217.777518)
						(end 138.424666 -217.791792)
					)
					(arc
						(start 138.424666 -217.791792)
						(mid 138.289244 -217.735698)
						(end 138.23315 -217.600276)
					)
					(arc
						(start 138.23315 -217.600276)
						(mid 138.247866 -217.526654)
						(end 138.289792 -217.464386)
					)
					(xy 138.2903 -217.464132)
					(arc
						(start 138.304778 -217.449654)
						(mid 138.311051 -217.436176)
						(end 138.31316 -217.42146)
					)
				)
			)
		)
		(zone
			(layer "F.Cu")
			(hatch none 0.5)
			(connect_pads
				(clearance 0)
			)
			(min_thickness 0.25)
			(keepout
				(tracks not_allowed)
				(vias allowed)
				(pads allowed)
				(copperpour not_allowed)
				(footprints allowed)
			)
			(placement
				(enabled no)
				(sheetname "")
			)
			(fill
				(thermal_gap 0.5)
				(thermal_bridge_width 0.5)
				(island_removal_mode 0)
			)
			(polygon
				(pts
					(arc
						(start 138.472164 -248.3231)
						(mid 138.486999 -248.287197)
						(end 138.472164 -248.251218)
					)
					(arc
						(start 138.472164 -248.251218)
						(mid 138.455042 -248.239867)
						(end 138.434826 -248.236232)
					)
					(arc
						(start 138.434826 -248.236232)
						(mid 138.317625 -248.256381)
						(end 138.218164 -248.321576)
					)
					(arc
						(start 138.218164 -248.321576)
						(mid 138.132628 -248.528078)
						(end 138.218164 -248.73458)
					)
					(arc
						(start 138.218164 -248.73458)
						(mid 138.316422 -248.799375)
						(end 138.432286 -248.820178)
					)
					(arc
						(start 138.432286 -248.820178)
						(mid 138.453449 -248.817049)
						(end 138.471402 -248.805446)
					)
					(arc
						(start 138.471402 -248.805446)
						(mid 138.486162 -248.769542)
						(end 138.471402 -248.733564)
					)
					(arc
						(start 138.471402 -248.733564)
						(mid 138.459581 -248.724822)
						(end 138.445748 -248.719848)
					)
					(xy 138.42492 -248.719848) (xy 138.424412 -248.719848)
					(arc
						(start 138.423396 -248.719848)
						(mid 138.350798 -248.704846)
						(end 138.289284 -248.66346)
					)
					(arc
						(start 138.289284 -248.66346)
						(mid 138.233207 -248.528078)
						(end 138.289284 -248.392696)
					)
					(arc
						(start 138.289284 -248.392696)
						(mid 138.351617 -248.351013)
						(end 138.425174 -248.336562)
					)
					(xy 138.425936 -248.336816)
					(arc
						(start 138.44651 -248.336816)
						(mid 138.460334 -248.331825)
						(end 138.472164 -248.3231)
					)
				)
			)
		)
		(zone
			(layer "F.Cu")
			(hatch none 0.5)
			(connect_pads
				(clearance 0)
			)
			(min_thickness 0.25)
			(keepout
				(tracks not_allowed)
				(vias allowed)
				(pads allowed)
				(copperpour not_allowed)
				(footprints allowed)
			)
			(placement
				(enabled no)
				(sheetname "")
			)
			(fill
				(thermal_gap 0.5)
				(thermal_bridge_width 0.5)
				(island_removal_mode 0)
			)
			(polygon
				(pts
					(arc
						(start 138.5824 -280.037032)
						(mid 138.597161 -280.001218)
						(end 138.5824 -279.965404)
					)
					(arc
						(start 138.5824 -279.965404)
						(mid 138.56516 -279.954005)
						(end 138.544808 -279.950418)
					)
					(arc
						(start 138.544808 -279.950418)
						(mid 138.427607 -279.970567)
						(end 138.328146 -280.035762)
					)
					(arc
						(start 138.328146 -280.035762)
						(mid 138.24261 -280.242264)
						(end 138.328146 -280.448766)
					)
					(arc
						(start 138.328146 -280.448766)
						(mid 138.42639 -280.513648)
						(end 138.542268 -280.534364)
					)
					(arc
						(start 138.542268 -280.534364)
						(mid 138.563458 -280.531112)
						(end 138.581384 -280.519378)
					)
					(arc
						(start 138.581384 -280.519378)
						(mid 138.596144 -280.483474)
						(end 138.581384 -280.447496)
					)
					(arc
						(start 138.581384 -280.447496)
						(mid 138.569563 -280.438754)
						(end 138.55573 -280.43378)
					)
					(xy 138.534902 -280.43378) (xy 138.534394 -280.43378)
					(arc
						(start 138.533378 -280.43378)
						(mid 138.460809 -280.418895)
						(end 138.399266 -280.377646)
					)
					(arc
						(start 138.399266 -280.377646)
						(mid 138.343189 -280.242264)
						(end 138.399266 -280.106882)
					)
					(arc
						(start 138.399266 -280.106882)
						(mid 138.461614 -280.065282)
						(end 138.535156 -280.050748)
					)
					(xy 138.535918 -280.051002)
					(arc
						(start 138.556492 -280.051002)
						(mid 138.570474 -280.045926)
						(end 138.5824 -280.037032)
					)
				)
			)
		)
		(zone
			(layer "F.Cu")
			(hatch none 0.5)
			(connect_pads
				(clearance 0)
			)
			(min_thickness 0.25)
			(keepout
				(tracks not_allowed)
				(vias allowed)
				(pads allowed)
				(copperpour not_allowed)
				(footprints allowed)
			)
			(placement
				(enabled no)
				(sheetname "")
			)
			(fill
				(thermal_gap 0.5)
				(thermal_bridge_width 0.5)
				(island_removal_mode 0)
			)
			(polygon
				(pts
					(arc
						(start 138.5824 -278.4094)
						(mid 138.59716 -278.373496)
						(end 138.5824 -278.337518)
					)
					(arc
						(start 138.5824 -278.337518)
						(mid 138.56516 -278.326119)
						(end 138.544808 -278.322532)
					)
					(arc
						(start 138.544808 -278.322532)
						(mid 138.427607 -278.342681)
						(end 138.328146 -278.407876)
					)
					(arc
						(start 138.328146 -278.407876)
						(mid 138.24261 -278.614378)
						(end 138.328146 -278.82088)
					)
					(arc
						(start 138.328146 -278.82088)
						(mid 138.426404 -278.885675)
						(end 138.542268 -278.906478)
					)
					(arc
						(start 138.542268 -278.906478)
						(mid 138.563431 -278.903349)
						(end 138.581384 -278.891746)
					)
					(arc
						(start 138.581384 -278.891746)
						(mid 138.596144 -278.855842)
						(end 138.581384 -278.819864)
					)
					(arc
						(start 138.581384 -278.819864)
						(mid 138.569563 -278.811122)
						(end 138.55573 -278.806148)
					)
					(xy 138.534902 -278.806148) (xy 138.534394 -278.806148)
					(arc
						(start 138.533378 -278.806148)
						(mid 138.46078 -278.791146)
						(end 138.399266 -278.74976)
					)
					(arc
						(start 138.399266 -278.74976)
						(mid 138.343189 -278.614378)
						(end 138.399266 -278.478996)
					)
					(arc
						(start 138.399266 -278.478996)
						(mid 138.461599 -278.437313)
						(end 138.535156 -278.422862)
					)
					(xy 138.535918 -278.423116)
					(arc
						(start 138.556492 -278.423116)
						(mid 138.570453 -278.418159)
						(end 138.5824 -278.4094)
					)
				)
			)
		)
		(zone
			(layer "F.Cu")
			(hatch none 0.5)
			(connect_pads
				(clearance 0)
			)
			(min_thickness 0.25)
			(keepout
				(tracks not_allowed)
				(vias allowed)
				(pads allowed)
				(copperpour not_allowed)
				(footprints allowed)
			)
			(placement
				(enabled no)
				(sheetname "")
			)
			(fill
				(thermal_gap 0.5)
				(thermal_bridge_width 0.5)
				(island_removal_mode 0)
			)
			(polygon
				(pts
					(arc
						(start 138.5824 -276.781514)
						(mid 138.59716 -276.74561)
						(end 138.5824 -276.709632)
					)
					(arc
						(start 138.5824 -276.709632)
						(mid 138.565129 -276.698375)
						(end 138.544808 -276.6949)
					)
					(arc
						(start 138.544808 -276.6949)
						(mid 138.427607 -276.715049)
						(end 138.328146 -276.780244)
					)
					(arc
						(start 138.328146 -276.780244)
						(mid 138.24261 -276.986746)
						(end 138.328146 -277.193248)
					)
					(arc
						(start 138.328146 -277.193248)
						(mid 138.426421 -277.257989)
						(end 138.542268 -277.278592)
					)
					(arc
						(start 138.542268 -277.278592)
						(mid 138.563418 -277.275451)
						(end 138.581384 -277.26386)
					)
					(arc
						(start 138.581384 -277.26386)
						(mid 138.596144 -277.227956)
						(end 138.581384 -277.191978)
					)
					(arc
						(start 138.581384 -277.191978)
						(mid 138.569563 -277.183236)
						(end 138.55573 -277.178262)
					)
					(xy 138.534902 -277.178262) (xy 138.534394 -277.178262)
					(arc
						(start 138.533378 -277.178262)
						(mid 138.460809 -277.163377)
						(end 138.399266 -277.122128)
					)
					(arc
						(start 138.399266 -277.122128)
						(mid 138.343189 -276.986746)
						(end 138.399266 -276.851364)
					)
					(arc
						(start 138.399266 -276.851364)
						(mid 138.461614 -276.809764)
						(end 138.535156 -276.79523)
					)
					(xy 138.535918 -276.795484)
					(arc
						(start 138.556492 -276.795484)
						(mid 138.57049 -276.790428)
						(end 138.5824 -276.781514)
					)
				)
			)
		)
		(zone
			(layer "F.Cu")
			(hatch none 0.5)
			(connect_pads
				(clearance 0)
			)
			(min_thickness 0.25)
			(keepout
				(tracks not_allowed)
				(vias allowed)
				(pads allowed)
				(copperpour not_allowed)
				(footprints allowed)
			)
			(placement
				(enabled no)
				(sheetname "")
			)
			(fill
				(thermal_gap 0.5)
				(thermal_bridge_width 0.5)
				(island_removal_mode 0)
			)
			(polygon
				(pts
					(arc
						(start 138.5824 -275.153628)
						(mid 138.597161 -275.117814)
						(end 138.5824 -275.082)
					)
					(arc
						(start 138.5824 -275.082)
						(mid 138.56516 -275.070601)
						(end 138.544808 -275.067014)
					)
					(arc
						(start 138.544808 -275.067014)
						(mid 138.427607 -275.087163)
						(end 138.328146 -275.152358)
					)
					(arc
						(start 138.328146 -275.152358)
						(mid 138.24261 -275.35886)
						(end 138.328146 -275.565362)
					)
					(arc
						(start 138.328146 -275.565362)
						(mid 138.42639 -275.630244)
						(end 138.542268 -275.65096)
					)
					(arc
						(start 138.542268 -275.65096)
						(mid 138.563458 -275.647708)
						(end 138.581384 -275.635974)
					)
					(arc
						(start 138.581384 -275.635974)
						(mid 138.596144 -275.60007)
						(end 138.581384 -275.564092)
					)
					(arc
						(start 138.581384 -275.564092)
						(mid 138.569563 -275.55535)
						(end 138.55573 -275.550376)
					)
					(xy 138.534902 -275.550376) (xy 138.534394 -275.550376)
					(arc
						(start 138.533378 -275.550376)
						(mid 138.460823 -275.535476)
						(end 138.399266 -275.494242)
					)
					(arc
						(start 138.399266 -275.494242)
						(mid 138.343189 -275.35886)
						(end 138.399266 -275.223478)
					)
					(arc
						(start 138.399266 -275.223478)
						(mid 138.461614 -275.181878)
						(end 138.535156 -275.167344)
					)
					(xy 138.535918 -275.167598)
					(arc
						(start 138.556492 -275.167598)
						(mid 138.570474 -275.162522)
						(end 138.5824 -275.153628)
					)
				)
			)
		)
		(zone
			(layer "F.Cu")
			(hatch none 0.5)
			(connect_pads
				(clearance 0)
			)
			(min_thickness 0.25)
			(keepout
				(tracks not_allowed)
				(vias allowed)
				(pads allowed)
				(copperpour not_allowed)
				(footprints allowed)
			)
			(placement
				(enabled no)
				(sheetname "")
			)
			(fill
				(thermal_gap 0.5)
				(thermal_bridge_width 0.5)
				(island_removal_mode 0)
			)
			(polygon
				(pts
					(arc
						(start 138.5824 -273.525996)
						(mid 138.59716 -273.490092)
						(end 138.5824 -273.454114)
					)
					(arc
						(start 138.5824 -273.454114)
						(mid 138.565129 -273.442857)
						(end 138.544808 -273.439382)
					)
					(arc
						(start 138.544808 -273.439382)
						(mid 138.427607 -273.459531)
						(end 138.328146 -273.524726)
					)
					(arc
						(start 138.328146 -273.524726)
						(mid 138.24261 -273.731228)
						(end 138.328146 -273.93773)
					)
					(arc
						(start 138.328146 -273.93773)
						(mid 138.426421 -274.002471)
						(end 138.542268 -274.023074)
					)
					(arc
						(start 138.542268 -274.023074)
						(mid 138.563418 -274.019933)
						(end 138.581384 -274.008342)
					)
					(arc
						(start 138.581384 -274.008342)
						(mid 138.596144 -273.972438)
						(end 138.581384 -273.93646)
					)
					(arc
						(start 138.581384 -273.93646)
						(mid 138.569563 -273.927718)
						(end 138.55573 -273.922744)
					)
					(xy 138.534902 -273.922744) (xy 138.534394 -273.922744)
					(arc
						(start 138.533378 -273.922744)
						(mid 138.460809 -273.907859)
						(end 138.399266 -273.86661)
					)
					(arc
						(start 138.399266 -273.86661)
						(mid 138.343189 -273.731228)
						(end 138.399266 -273.595846)
					)
					(arc
						(start 138.399266 -273.595846)
						(mid 138.461614 -273.554246)
						(end 138.535156 -273.539712)
					)
					(xy 138.535918 -273.539966)
					(arc
						(start 138.556492 -273.539966)
						(mid 138.57049 -273.53491)
						(end 138.5824 -273.525996)
					)
				)
			)
		)
		(zone
			(layer "F.Cu")
			(hatch none 0.5)
			(connect_pads
				(clearance 0)
			)
			(min_thickness 0.25)
			(keepout
				(tracks not_allowed)
				(vias allowed)
				(pads allowed)
				(copperpour not_allowed)
				(footprints allowed)
			)
			(placement
				(enabled no)
				(sheetname "")
			)
			(fill
				(thermal_gap 0.5)
				(thermal_bridge_width 0.5)
				(island_removal_mode 0)
			)
			(polygon
				(pts
					(arc
						(start 138.5824 -271.89811)
						(mid 138.597161 -271.862296)
						(end 138.5824 -271.826482)
					)
					(arc
						(start 138.5824 -271.826482)
						(mid 138.56516 -271.815083)
						(end 138.544808 -271.811496)
					)
					(arc
						(start 138.544808 -271.811496)
						(mid 138.427607 -271.831645)
						(end 138.328146 -271.89684)
					)
					(arc
						(start 138.328146 -271.89684)
						(mid 138.24261 -272.103342)
						(end 138.328146 -272.309844)
					)
					(arc
						(start 138.328146 -272.309844)
						(mid 138.42639 -272.374726)
						(end 138.542268 -272.395442)
					)
					(arc
						(start 138.542268 -272.395442)
						(mid 138.563458 -272.39219)
						(end 138.581384 -272.380456)
					)
					(arc
						(start 138.581384 -272.380456)
						(mid 138.596144 -272.344552)
						(end 138.581384 -272.308574)
					)
					(arc
						(start 138.581384 -272.308574)
						(mid 138.569563 -272.299832)
						(end 138.55573 -272.294858)
					)
					(xy 138.534902 -272.294858) (xy 138.534394 -272.294858)
					(arc
						(start 138.533378 -272.294858)
						(mid 138.460823 -272.279958)
						(end 138.399266 -272.238724)
					)
					(arc
						(start 138.399266 -272.238724)
						(mid 138.343189 -272.103342)
						(end 138.399266 -271.96796)
					)
					(arc
						(start 138.399266 -271.96796)
						(mid 138.461614 -271.92636)
						(end 138.535156 -271.911826)
					)
					(xy 138.535918 -271.91208)
					(arc
						(start 138.556492 -271.91208)
						(mid 138.570474 -271.907004)
						(end 138.5824 -271.89811)
					)
				)
			)
		)
		(zone
			(layer "F.Cu")
			(hatch none 0.5)
			(connect_pads
				(clearance 0)
			)
			(min_thickness 0.25)
			(keepout
				(tracks not_allowed)
				(vias allowed)
				(pads allowed)
				(copperpour not_allowed)
				(footprints allowed)
			)
			(placement
				(enabled no)
				(sheetname "")
			)
			(fill
				(thermal_gap 0.5)
				(thermal_bridge_width 0.5)
				(island_removal_mode 0)
			)
			(polygon
				(pts
					(arc
						(start 138.5824 -270.270478)
						(mid 138.59716 -270.234574)
						(end 138.5824 -270.198596)
					)
					(arc
						(start 138.5824 -270.198596)
						(mid 138.56516 -270.187197)
						(end 138.544808 -270.18361)
					)
					(arc
						(start 138.544808 -270.18361)
						(mid 138.427607 -270.203759)
						(end 138.328146 -270.268954)
					)
					(arc
						(start 138.328146 -270.268954)
						(mid 138.24261 -270.475456)
						(end 138.328146 -270.681958)
					)
					(arc
						(start 138.328146 -270.681958)
						(mid 138.426404 -270.746753)
						(end 138.542268 -270.767556)
					)
					(arc
						(start 138.542268 -270.767556)
						(mid 138.563431 -270.764427)
						(end 138.581384 -270.752824)
					)
					(arc
						(start 138.581384 -270.752824)
						(mid 138.596144 -270.71692)
						(end 138.581384 -270.680942)
					)
					(arc
						(start 138.581384 -270.680942)
						(mid 138.569563 -270.6722)
						(end 138.55573 -270.667226)
					)
					(xy 138.534902 -270.667226) (xy 138.534394 -270.667226)
					(arc
						(start 138.533378 -270.667226)
						(mid 138.460809 -270.652341)
						(end 138.399266 -270.611092)
					)
					(arc
						(start 138.399266 -270.611092)
						(mid 138.343189 -270.47562)
						(end 138.399266 -270.340074)
					)
					(arc
						(start 138.399266 -270.340074)
						(mid 138.461644 -270.298611)
						(end 138.535156 -270.284194)
					)
					(xy 138.535918 -270.284194)
					(arc
						(start 138.556492 -270.284194)
						(mid 138.570453 -270.279237)
						(end 138.5824 -270.270478)
					)
				)
			)
		)
		(zone
			(layer "F.Cu")
			(hatch none 0.5)
			(connect_pads
				(clearance 0)
			)
			(min_thickness 0.25)
			(keepout
				(tracks not_allowed)
				(vias allowed)
				(pads allowed)
				(copperpour not_allowed)
				(footprints allowed)
			)
			(placement
				(enabled no)
				(sheetname "")
			)
			(fill
				(thermal_gap 0.5)
				(thermal_bridge_width 0.5)
				(island_removal_mode 0)
			)
			(polygon
				(pts
					(arc
						(start 138.5824 -268.642592)
						(mid 138.59716 -268.606688)
						(end 138.5824 -268.57071)
					)
					(arc
						(start 138.5824 -268.57071)
						(mid 138.565129 -268.559453)
						(end 138.544808 -268.555978)
					)
					(arc
						(start 138.544808 -268.555978)
						(mid 138.427607 -268.576127)
						(end 138.328146 -268.641322)
					)
					(arc
						(start 138.328146 -268.641322)
						(mid 138.24261 -268.847824)
						(end 138.328146 -269.054326)
					)
					(arc
						(start 138.328146 -269.054326)
						(mid 138.426421 -269.119067)
						(end 138.542268 -269.13967)
					)
					(arc
						(start 138.542268 -269.13967)
						(mid 138.563418 -269.136529)
						(end 138.581384 -269.124938)
					)
					(arc
						(start 138.581384 -269.124938)
						(mid 138.596144 -269.089034)
						(end 138.581384 -269.053056)
					)
					(arc
						(start 138.581384 -269.053056)
						(mid 138.569563 -269.044314)
						(end 138.55573 -269.03934)
					)
					(xy 138.534902 -269.03934) (xy 138.534394 -269.03934)
					(arc
						(start 138.533378 -269.03934)
						(mid 138.460809 -269.024455)
						(end 138.399266 -268.983206)
					)
					(arc
						(start 138.399266 -268.983206)
						(mid 138.343189 -268.847824)
						(end 138.399266 -268.712442)
					)
					(arc
						(start 138.399266 -268.712442)
						(mid 138.461614 -268.670842)
						(end 138.535156 -268.656308)
					)
					(xy 138.535918 -268.656562)
					(arc
						(start 138.556492 -268.656562)
						(mid 138.57049 -268.651506)
						(end 138.5824 -268.642592)
					)
				)
			)
		)
		(zone
			(layer "F.Cu")
			(hatch none 0.5)
			(connect_pads
				(clearance 0)
			)
			(min_thickness 0.25)
			(keepout
				(tracks not_allowed)
				(vias allowed)
				(pads allowed)
				(copperpour not_allowed)
				(footprints allowed)
			)
			(placement
				(enabled no)
				(sheetname "")
			)
			(fill
				(thermal_gap 0.5)
				(thermal_bridge_width 0.5)
				(island_removal_mode 0)
			)
			(polygon
				(pts
					(arc
						(start 138.5824 -267.014706)
						(mid 138.597161 -266.978892)
						(end 138.5824 -266.943078)
					)
					(arc
						(start 138.5824 -266.943078)
						(mid 138.56516 -266.931679)
						(end 138.544808 -266.928092)
					)
					(arc
						(start 138.544808 -266.928092)
						(mid 138.427607 -266.948241)
						(end 138.328146 -267.013436)
					)
					(arc
						(start 138.328146 -267.013436)
						(mid 138.24261 -267.219938)
						(end 138.328146 -267.42644)
					)
					(arc
						(start 138.328146 -267.42644)
						(mid 138.42639 -267.491322)
						(end 138.542268 -267.512038)
					)
					(arc
						(start 138.542268 -267.512038)
						(mid 138.563431 -267.508909)
						(end 138.581384 -267.497306)
					)
					(arc
						(start 138.581384 -267.497306)
						(mid 138.596324 -267.461238)
						(end 138.581384 -267.42517)
					)
					(arc
						(start 138.581384 -267.42517)
						(mid 138.569563 -267.416428)
						(end 138.55573 -267.411454)
					)
					(xy 138.534902 -267.411454) (xy 138.534394 -267.411454)
					(arc
						(start 138.533378 -267.411454)
						(mid 138.460823 -267.396554)
						(end 138.399266 -267.35532)
					)
					(arc
						(start 138.399266 -267.35532)
						(mid 138.343189 -267.219938)
						(end 138.399266 -267.084556)
					)
					(arc
						(start 138.399266 -267.084556)
						(mid 138.461614 -267.042956)
						(end 138.535156 -267.028422)
					)
					(xy 138.535918 -267.028676)
					(arc
						(start 138.556492 -267.028676)
						(mid 138.570474 -267.0236)
						(end 138.5824 -267.014706)
					)
				)
			)
		)
		(zone
			(layer "F.Cu")
			(hatch none 0.5)
			(connect_pads
				(clearance 0)
			)
			(min_thickness 0.25)
			(keepout
				(tracks not_allowed)
				(vias allowed)
				(pads allowed)
				(copperpour not_allowed)
				(footprints allowed)
			)
			(placement
				(enabled no)
				(sheetname "")
			)
			(fill
				(thermal_gap 0.5)
				(thermal_bridge_width 0.5)
				(island_removal_mode 0)
			)
			(polygon
				(pts
					(arc
						(start 138.5824 -265.387074)
						(mid 138.59716 -265.35117)
						(end 138.5824 -265.315192)
					)
					(arc
						(start 138.5824 -265.315192)
						(mid 138.56516 -265.303793)
						(end 138.544808 -265.300206)
					)
					(arc
						(start 138.544808 -265.300206)
						(mid 138.427579 -265.320475)
						(end 138.328146 -265.385804)
					)
					(arc
						(start 138.328146 -265.385804)
						(mid 138.24261 -265.592216)
						(end 138.328146 -265.798554)
					)
					(arc
						(start 138.328146 -265.798554)
						(mid 138.426404 -265.863349)
						(end 138.542268 -265.884152)
					)
					(arc
						(start 138.542268 -265.884152)
						(mid 138.563431 -265.881023)
						(end 138.581384 -265.86942)
					)
					(arc
						(start 138.581384 -265.86942)
						(mid 138.596144 -265.833516)
						(end 138.581384 -265.797538)
					)
					(arc
						(start 138.581384 -265.797538)
						(mid 138.569563 -265.788796)
						(end 138.55573 -265.783822)
					)
					(xy 138.534902 -265.783822) (xy 138.534394 -265.783822)
					(arc
						(start 138.533378 -265.783822)
						(mid 138.460809 -265.768937)
						(end 138.399266 -265.727688)
					)
					(arc
						(start 138.399266 -265.727688)
						(mid 138.343189 -265.592216)
						(end 138.399266 -265.45667)
					)
					(arc
						(start 138.399266 -265.45667)
						(mid 138.461644 -265.415207)
						(end 138.535156 -265.40079)
					)
					(xy 138.535918 -265.40079)
					(arc
						(start 138.556492 -265.40079)
						(mid 138.570453 -265.395833)
						(end 138.5824 -265.387074)
					)
				)
			)
		)
		(zone
			(layer "F.Cu")
			(hatch none 0.5)
			(connect_pads
				(clearance 0)
			)
			(min_thickness 0.25)
			(keepout
				(tracks not_allowed)
				(vias allowed)
				(pads allowed)
				(copperpour not_allowed)
				(footprints allowed)
			)
			(placement
				(enabled no)
				(sheetname "")
			)
			(fill
				(thermal_gap 0.5)
				(thermal_bridge_width 0.5)
				(island_removal_mode 0)
			)
			(polygon
				(pts
					(arc
						(start 138.5824 -253.99238)
						(mid 138.597161 -253.956566)
						(end 138.5824 -253.920752)
					)
					(arc
						(start 138.5824 -253.920752)
						(mid 138.56516 -253.909353)
						(end 138.544808 -253.905766)
					)
					(arc
						(start 138.544808 -253.905766)
						(mid 138.427607 -253.925915)
						(end 138.328146 -253.99111)
					)
					(arc
						(start 138.328146 -253.99111)
						(mid 138.24261 -254.197612)
						(end 138.328146 -254.404114)
					)
					(arc
						(start 138.328146 -254.404114)
						(mid 138.42639 -254.468996)
						(end 138.542268 -254.489712)
					)
					(arc
						(start 138.542268 -254.489712)
						(mid 138.563431 -254.486583)
						(end 138.581384 -254.47498)
					)
					(arc
						(start 138.581384 -254.47498)
						(mid 138.596144 -254.439076)
						(end 138.581384 -254.403098)
					)
					(arc
						(start 138.581384 -254.403098)
						(mid 138.569563 -254.394356)
						(end 138.55573 -254.389382)
					)
					(xy 138.534902 -254.389382) (xy 138.534394 -254.389382)
					(arc
						(start 138.533378 -254.389382)
						(mid 138.46078 -254.37438)
						(end 138.399266 -254.332994)
					)
					(arc
						(start 138.399266 -254.332994)
						(mid 138.343189 -254.197612)
						(end 138.399266 -254.06223)
					)
					(arc
						(start 138.399266 -254.06223)
						(mid 138.461614 -254.02063)
						(end 138.535156 -254.006096)
					)
					(xy 138.535918 -254.00635)
					(arc
						(start 138.556492 -254.00635)
						(mid 138.570474 -254.001274)
						(end 138.5824 -253.99238)
					)
				)
			)
		)
		(zone
			(layer "F.Cu")
			(hatch none 0.5)
			(connect_pads
				(clearance 0)
			)
			(min_thickness 0.25)
			(keepout
				(tracks not_allowed)
				(vias allowed)
				(pads allowed)
				(copperpour not_allowed)
				(footprints allowed)
			)
			(placement
				(enabled no)
				(sheetname "")
			)
			(fill
				(thermal_gap 0.5)
				(thermal_bridge_width 0.5)
				(island_removal_mode 0)
			)
			(polygon
				(pts
					(arc
						(start 138.713464 -285.014162)
						(mid 138.749385 -284.999283)
						(end 138.764264 -284.963362)
					)
					(arc
						(start 138.764264 -284.963362)
						(mid 138.760082 -284.943178)
						(end 138.748262 -284.926278)
					)
					(arc
						(start 138.748262 -284.926278)
						(mid 138.651087 -284.85775)
						(end 138.534648 -284.833568)
					)
					(arc
						(start 138.534648 -284.833568)
						(mid 138.328192 -284.919032)
						(end 138.242548 -285.125414)
					)
					(arc
						(start 138.242548 -285.125414)
						(mid 138.266198 -285.240808)
						(end 138.33348 -285.337504)
					)
					(arc
						(start 138.33348 -285.337504)
						(mid 138.350708 -285.350073)
						(end 138.37158 -285.354522)
					)
					(arc
						(start 138.37158 -285.354522)
						(mid 138.407501 -285.339643)
						(end 138.42238 -285.303722)
					)
					(arc
						(start 138.42238 -285.303722)
						(mid 138.420241 -285.289136)
						(end 138.413998 -285.275782)
					)
					(xy 138.399266 -285.261304) (xy 138.399012 -285.260796)
					(arc
						(start 138.39825 -285.260288)
						(mid 138.357358 -285.198294)
						(end 138.343132 -285.125414)
					)
					(arc
						(start 138.343132 -285.125414)
						(mid 138.399226 -284.989992)
						(end 138.534648 -284.933898)
					)
					(arc
						(start 138.534648 -284.933898)
						(mid 138.60823 -284.948682)
						(end 138.670538 -284.99054)
					)
					(xy 138.670792 -284.991302)
					(arc
						(start 138.68527 -285.00578)
						(mid 138.698753 -285.012022)
						(end 138.713464 -285.014162)
					)
				)
			)
		)
		(zone
			(layer "F.Cu")
			(hatch none 0.5)
			(connect_pads
				(clearance 0)
			)
			(min_thickness 0.25)
			(keepout
				(tracks not_allowed)
				(vias allowed)
				(pads allowed)
				(copperpour not_allowed)
				(footprints allowed)
			)
			(placement
				(enabled no)
				(sheetname "")
			)
			(fill
				(thermal_gap 0.5)
				(thermal_bridge_width 0.5)
				(island_removal_mode 0)
			)
			(polygon
				(pts
					(arc
						(start 138.713464 -283.386276)
						(mid 138.749385 -283.371397)
						(end 138.764264 -283.335476)
					)
					(arc
						(start 138.764264 -283.335476)
						(mid 138.760032 -283.315429)
						(end 138.748262 -283.298646)
					)
					(arc
						(start 138.748262 -283.298646)
						(mid 138.651135 -283.229917)
						(end 138.534648 -283.205682)
					)
					(arc
						(start 138.534648 -283.205682)
						(mid 138.328102 -283.291236)
						(end 138.242548 -283.497782)
					)
					(arc
						(start 138.242548 -283.497782)
						(mid 138.266249 -283.613039)
						(end 138.33348 -283.709618)
					)
					(arc
						(start 138.33348 -283.709618)
						(mid 138.350708 -283.722187)
						(end 138.37158 -283.726636)
					)
					(arc
						(start 138.37158 -283.726636)
						(mid 138.407501 -283.711757)
						(end 138.42238 -283.675836)
					)
					(arc
						(start 138.42238 -283.675836)
						(mid 138.420195 -283.661388)
						(end 138.413998 -283.64815)
					)
					(xy 138.399266 -283.633418) (xy 138.399012 -283.633164)
					(arc
						(start 138.39825 -283.632402)
						(mid 138.357406 -283.570525)
						(end 138.343132 -283.497782)
					)
					(arc
						(start 138.343132 -283.497782)
						(mid 138.399226 -283.36236)
						(end 138.534648 -283.306266)
					)
					(arc
						(start 138.534648 -283.306266)
						(mid 138.608241 -283.320864)
						(end 138.670538 -283.362654)
					)
					(xy 138.670792 -283.363416)
					(arc
						(start 138.68527 -283.377894)
						(mid 138.698748 -283.384167)
						(end 138.713464 -283.386276)
					)
				)
			)
		)
		(zone
			(layer "F.Cu")
			(hatch none 0.5)
			(connect_pads
				(clearance 0)
			)
			(min_thickness 0.25)
			(keepout
				(tracks not_allowed)
				(vias allowed)
				(pads allowed)
				(copperpour not_allowed)
				(footprints allowed)
			)
			(placement
				(enabled no)
				(sheetname "")
			)
			(fill
				(thermal_gap 0.5)
				(thermal_bridge_width 0.5)
				(island_removal_mode 0)
			)
			(polygon
				(pts
					(arc
						(start 138.713464 -281.758644)
						(mid 138.749385 -281.743765)
						(end 138.764264 -281.707844)
					)
					(arc
						(start 138.764264 -281.707844)
						(mid 138.760082 -281.68766)
						(end 138.748262 -281.67076)
					)
					(arc
						(start 138.748262 -281.67076)
						(mid 138.651087 -281.602232)
						(end 138.534648 -281.57805)
					)
					(arc
						(start 138.534648 -281.57805)
						(mid 138.328192 -281.663514)
						(end 138.242548 -281.869896)
					)
					(arc
						(start 138.242548 -281.869896)
						(mid 138.266198 -281.98529)
						(end 138.33348 -282.081986)
					)
					(arc
						(start 138.33348 -282.081986)
						(mid 138.350708 -282.094555)
						(end 138.37158 -282.099004)
					)
					(arc
						(start 138.37158 -282.099004)
						(mid 138.407501 -282.084125)
						(end 138.42238 -282.048204)
					)
					(arc
						(start 138.42238 -282.048204)
						(mid 138.420241 -282.033618)
						(end 138.413998 -282.020264)
					)
					(xy 138.399266 -282.005786) (xy 138.399012 -282.005278)
					(arc
						(start 138.39825 -282.00477)
						(mid 138.357358 -281.942776)
						(end 138.343132 -281.869896)
					)
					(arc
						(start 138.343132 -281.869896)
						(mid 138.399226 -281.734474)
						(end 138.534648 -281.67838)
					)
					(arc
						(start 138.534648 -281.67838)
						(mid 138.60823 -281.693164)
						(end 138.670538 -281.735022)
					)
					(xy 138.670792 -281.735784)
					(arc
						(start 138.68527 -281.750262)
						(mid 138.698753 -281.756504)
						(end 138.713464 -281.758644)
					)
				)
			)
		)
		(zone
			(layer "F.Cu")
			(hatch none 0.5)
			(connect_pads
				(clearance 0)
			)
			(min_thickness 0.25)
			(keepout
				(tracks not_allowed)
				(vias allowed)
				(pads allowed)
				(copperpour not_allowed)
				(footprints allowed)
			)
			(placement
				(enabled no)
				(sheetname "")
			)
			(fill
				(thermal_gap 0.5)
				(thermal_bridge_width 0.5)
				(island_removal_mode 0)
			)
			(polygon
				(pts
					(arc
						(start 138.78306 -221.491048)
						(mid 138.768181 -221.455127)
						(end 138.73226 -221.440248)
					)
					(arc
						(start 138.73226 -221.440248)
						(mid 138.712103 -221.444308)
						(end 138.695176 -221.455996)
					)
					(arc
						(start 138.695176 -221.455996)
						(mid 138.626454 -221.553256)
						(end 138.602212 -221.669864)
					)
					(arc
						(start 138.602212 -221.669864)
						(mid 138.687766 -221.87641)
						(end 138.894312 -221.961964)
					)
					(arc
						(start 138.894312 -221.961964)
						(mid 139.009734 -221.938193)
						(end 139.106402 -221.870778)
					)
					(arc
						(start 139.106402 -221.870778)
						(mid 139.118971 -221.85355)
						(end 139.12342 -221.832678)
					)
					(arc
						(start 139.12342 -221.832678)
						(mid 139.108541 -221.796757)
						(end 139.07262 -221.781878)
					)
					(arc
						(start 139.07262 -221.781878)
						(mid 139.058034 -221.784017)
						(end 139.04468 -221.79026)
					)
					(xy 139.030202 -221.804992) (xy 139.029694 -221.805246)
					(arc
						(start 139.029186 -221.806008)
						(mid 138.967221 -221.847035)
						(end 138.894312 -221.86138)
					)
					(arc
						(start 138.894312 -221.86138)
						(mid 138.75889 -221.805286)
						(end 138.702796 -221.669864)
					)
					(arc
						(start 138.702796 -221.669864)
						(mid 138.717512 -221.596242)
						(end 138.759438 -221.533974)
					)
					(xy 138.7602 -221.533466)
					(arc
						(start 138.774678 -221.518988)
						(mid 138.780914 -221.505632)
						(end 138.78306 -221.491048)
					)
				)
			)
		)
		(zone
			(layer "F.Cu")
			(hatch none 0.5)
			(connect_pads
				(clearance 0)
			)
			(min_thickness 0.25)
			(keepout
				(tracks not_allowed)
				(vias allowed)
				(pads allowed)
				(copperpour not_allowed)
				(footprints allowed)
			)
			(placement
				(enabled no)
				(sheetname "")
			)
			(fill
				(thermal_gap 0.5)
				(thermal_bridge_width 0.5)
				(island_removal_mode 0)
			)
			(polygon
				(pts
					(arc
						(start 138.78306 -219.863162)
						(mid 138.768181 -219.827241)
						(end 138.73226 -219.812362)
					)
					(arc
						(start 138.73226 -219.812362)
						(mid 138.712076 -219.816544)
						(end 138.695176 -219.828364)
					)
					(arc
						(start 138.695176 -219.828364)
						(mid 138.626505 -219.925507)
						(end 138.602212 -220.041978)
					)
					(arc
						(start 138.602212 -220.041978)
						(mid 138.687766 -220.248524)
						(end 138.894312 -220.334078)
					)
					(arc
						(start 138.894312 -220.334078)
						(mid 139.009718 -220.310291)
						(end 139.106402 -220.242892)
					)
					(arc
						(start 139.106402 -220.242892)
						(mid 139.11892 -220.22578)
						(end 139.12342 -220.205046)
					)
					(arc
						(start 139.12342 -220.205046)
						(mid 139.108541 -220.169125)
						(end 139.07262 -220.154246)
					)
					(arc
						(start 139.07262 -220.154246)
						(mid 139.058034 -220.156385)
						(end 139.04468 -220.162628)
					)
					(xy 139.030202 -220.17736) (xy 139.029694 -220.177614)
					(arc
						(start 139.029186 -220.178376)
						(mid 138.967192 -220.219268)
						(end 138.894312 -220.233494)
					)
					(arc
						(start 138.894312 -220.233494)
						(mid 138.75889 -220.1774)
						(end 138.702796 -220.041978)
					)
					(arc
						(start 138.702796 -220.041978)
						(mid 138.71758 -219.968396)
						(end 138.759438 -219.906088)
					)
					(xy 138.7602 -219.905834)
					(arc
						(start 138.774678 -219.891356)
						(mid 138.78092 -219.877873)
						(end 138.78306 -219.863162)
					)
				)
			)
		)
		(zone
			(layer "F.Cu")
			(hatch none 0.5)
			(connect_pads
				(clearance 0)
			)
			(min_thickness 0.25)
			(keepout
				(tracks not_allowed)
				(vias allowed)
				(pads allowed)
				(copperpour not_allowed)
				(footprints allowed)
			)
			(placement
				(enabled no)
				(sheetname "")
			)
			(fill
				(thermal_gap 0.5)
				(thermal_bridge_width 0.5)
				(island_removal_mode 0)
			)
			(polygon
				(pts
					(arc
						(start 138.942064 -247.50903)
						(mid 138.956825 -247.473216)
						(end 138.942064 -247.437402)
					)
					(arc
						(start 138.942064 -247.437402)
						(mid 138.924942 -247.426051)
						(end 138.904726 -247.422416)
					)
					(arc
						(start 138.904726 -247.422416)
						(mid 138.787385 -247.44251)
						(end 138.68781 -247.50776)
					)
					(arc
						(start 138.68781 -247.50776)
						(mid 138.602274 -247.714262)
						(end 138.68781 -247.920764)
					)
					(arc
						(start 138.68781 -247.920764)
						(mid 138.786172 -247.985693)
						(end 138.902186 -248.006362)
					)
					(arc
						(start 138.902186 -248.006362)
						(mid 138.923235 -248.003051)
						(end 138.941048 -247.991376)
					)
					(arc
						(start 138.941048 -247.991376)
						(mid 138.955883 -247.955473)
						(end 138.941048 -247.919494)
					)
					(arc
						(start 138.941048 -247.919494)
						(mid 138.929227 -247.910752)
						(end 138.915394 -247.905778)
					)
					(xy 138.89482 -247.905778) (xy 138.894312 -247.905778)
					(arc
						(start 138.893296 -247.905778)
						(mid 138.820591 -247.89094)
						(end 138.75893 -247.849644)
					)
					(arc
						(start 138.75893 -247.849644)
						(mid 138.702853 -247.714262)
						(end 138.75893 -247.57888)
					)
					(arc
						(start 138.75893 -247.57888)
						(mid 138.821396 -247.537231)
						(end 138.895074 -247.522746)
					)
					(xy 138.895836 -247.523)
					(arc
						(start 138.916156 -247.523)
						(mid 138.930138 -247.517924)
						(end 138.942064 -247.50903)
					)
				)
			)
		)
		(zone
			(layer "F.Cu")
			(hatch none 0.5)
			(connect_pads
				(clearance 0)
			)
			(min_thickness 0.25)
			(keepout
				(tracks not_allowed)
				(vias allowed)
				(pads allowed)
				(copperpour not_allowed)
				(footprints allowed)
			)
			(placement
				(enabled no)
				(sheetname "")
			)
			(fill
				(thermal_gap 0.5)
				(thermal_bridge_width 0.5)
				(island_removal_mode 0)
			)
			(polygon
				(pts
					(arc
						(start 138.942064 -245.881398)
						(mid 138.956899 -245.845495)
						(end 138.942064 -245.809516)
					)
					(arc
						(start 138.942064 -245.809516)
						(mid 138.924911 -245.798305)
						(end 138.904726 -245.794784)
					)
					(arc
						(start 138.904726 -245.794784)
						(mid 138.787385 -245.814878)
						(end 138.68781 -245.880128)
					)
					(arc
						(start 138.68781 -245.880128)
						(mid 138.602274 -246.08663)
						(end 138.68781 -246.293132)
					)
					(arc
						(start 138.68781 -246.293132)
						(mid 138.786203 -246.357921)
						(end 138.902186 -246.378476)
					)
					(arc
						(start 138.902186 -246.378476)
						(mid 138.923195 -246.375276)
						(end 138.941048 -246.363744)
					)
					(arc
						(start 138.941048 -246.363744)
						(mid 138.955883 -246.327841)
						(end 138.941048 -246.291862)
					)
					(arc
						(start 138.941048 -246.291862)
						(mid 138.929227 -246.28312)
						(end 138.915394 -246.278146)
					)
					(xy 138.89482 -246.278146) (xy 138.894312 -246.278146)
					(arc
						(start 138.893296 -246.278146)
						(mid 138.820591 -246.263308)
						(end 138.75893 -246.222012)
					)
					(arc
						(start 138.75893 -246.222012)
						(mid 138.702853 -246.08663)
						(end 138.75893 -245.951248)
					)
					(arc
						(start 138.75893 -245.951248)
						(mid 138.821396 -245.909599)
						(end 138.895074 -245.895114)
					)
					(xy 138.895836 -245.895368)
					(arc
						(start 138.916156 -245.895368)
						(mid 138.930138 -245.890292)
						(end 138.942064 -245.881398)
					)
				)
			)
		)
		(zone
			(layer "F.Cu")
			(hatch none 0.5)
			(connect_pads
				(clearance 0)
			)
			(min_thickness 0.25)
			(keepout
				(tracks not_allowed)
				(vias allowed)
				(pads allowed)
				(copperpour not_allowed)
				(footprints allowed)
			)
			(placement
				(enabled no)
				(sheetname "")
			)
			(fill
				(thermal_gap 0.5)
				(thermal_bridge_width 0.5)
				(island_removal_mode 0)
			)
			(polygon
				(pts
					(arc
						(start 138.942064 -244.253512)
						(mid 138.956825 -244.217698)
						(end 138.942064 -244.181884)
					)
					(arc
						(start 138.942064 -244.181884)
						(mid 138.924942 -244.170533)
						(end 138.904726 -244.166898)
					)
					(arc
						(start 138.904726 -244.166898)
						(mid 138.787385 -244.186992)
						(end 138.68781 -244.252242)
					)
					(arc
						(start 138.68781 -244.252242)
						(mid 138.602274 -244.458744)
						(end 138.68781 -244.665246)
					)
					(arc
						(start 138.68781 -244.665246)
						(mid 138.786172 -244.730175)
						(end 138.902186 -244.750844)
					)
					(arc
						(start 138.902186 -244.750844)
						(mid 138.923235 -244.747533)
						(end 138.941048 -244.735858)
					)
					(arc
						(start 138.941048 -244.735858)
						(mid 138.955883 -244.699955)
						(end 138.941048 -244.663976)
					)
					(arc
						(start 138.941048 -244.663976)
						(mid 138.929227 -244.655234)
						(end 138.915394 -244.65026)
					)
					(xy 138.89482 -244.65026) (xy 138.894312 -244.65026)
					(arc
						(start 138.893296 -244.65026)
						(mid 138.820591 -244.635422)
						(end 138.75893 -244.594126)
					)
					(arc
						(start 138.75893 -244.594126)
						(mid 138.702853 -244.458744)
						(end 138.75893 -244.323362)
					)
					(arc
						(start 138.75893 -244.323362)
						(mid 138.821381 -244.28163)
						(end 138.895074 -244.267228)
					)
					(xy 138.895836 -244.267482)
					(arc
						(start 138.916156 -244.267482)
						(mid 138.930138 -244.262406)
						(end 138.942064 -244.253512)
					)
				)
			)
		)
		(zone
			(layer "F.Cu")
			(hatch none 0.5)
			(connect_pads
				(clearance 0)
			)
			(min_thickness 0.25)
			(keepout
				(tracks not_allowed)
				(vias allowed)
				(pads allowed)
				(copperpour not_allowed)
				(footprints allowed)
			)
			(placement
				(enabled no)
				(sheetname "")
			)
			(fill
				(thermal_gap 0.5)
				(thermal_bridge_width 0.5)
				(island_removal_mode 0)
			)
			(polygon
				(pts
					(arc
						(start 138.942064 -242.62588)
						(mid 138.956899 -242.589977)
						(end 138.942064 -242.553998)
					)
					(arc
						(start 138.942064 -242.553998)
						(mid 138.924942 -242.542647)
						(end 138.904726 -242.539012)
					)
					(arc
						(start 138.904726 -242.539012)
						(mid 138.787385 -242.559106)
						(end 138.68781 -242.624356)
					)
					(arc
						(start 138.68781 -242.624356)
						(mid 138.602274 -242.830858)
						(end 138.68781 -243.03736)
					)
					(arc
						(start 138.68781 -243.03736)
						(mid 138.786172 -243.102289)
						(end 138.902186 -243.122958)
					)
					(arc
						(start 138.902186 -243.122958)
						(mid 138.923208 -243.11977)
						(end 138.941048 -243.108226)
					)
					(arc
						(start 138.941048 -243.108226)
						(mid 138.955883 -243.072323)
						(end 138.941048 -243.036344)
					)
					(arc
						(start 138.941048 -243.036344)
						(mid 138.929243 -243.027561)
						(end 138.915394 -243.022628)
					)
					(xy 138.89482 -243.022628) (xy 138.894312 -243.022628)
					(arc
						(start 138.893296 -243.022628)
						(mid 138.820591 -243.00779)
						(end 138.75893 -242.966494)
					)
					(arc
						(start 138.75893 -242.966494)
						(mid 138.702853 -242.831022)
						(end 138.75893 -242.695476)
					)
					(arc
						(start 138.75893 -242.695476)
						(mid 138.821425 -242.653965)
						(end 138.895074 -242.639596)
					)
					(xy 138.895836 -242.639596)
					(arc
						(start 138.916156 -242.639596)
						(mid 138.930117 -242.634639)
						(end 138.942064 -242.62588)
					)
				)
			)
		)
		(zone
			(layer "F.Cu")
			(hatch none 0.5)
			(connect_pads
				(clearance 0)
			)
			(min_thickness 0.25)
			(keepout
				(tracks not_allowed)
				(vias allowed)
				(pads allowed)
				(copperpour not_allowed)
				(footprints allowed)
			)
			(placement
				(enabled no)
				(sheetname "")
			)
			(fill
				(thermal_gap 0.5)
				(thermal_bridge_width 0.5)
				(island_removal_mode 0)
			)
			(polygon
				(pts
					(arc
						(start 138.942064 -240.997994)
						(mid 138.956899 -240.962091)
						(end 138.942064 -240.926112)
					)
					(arc
						(start 138.942064 -240.926112)
						(mid 138.924911 -240.914901)
						(end 138.904726 -240.91138)
					)
					(arc
						(start 138.904726 -240.91138)
						(mid 138.787385 -240.931474)
						(end 138.68781 -240.996724)
					)
					(arc
						(start 138.68781 -240.996724)
						(mid 138.602274 -241.203226)
						(end 138.68781 -241.409728)
					)
					(arc
						(start 138.68781 -241.409728)
						(mid 138.786203 -241.474517)
						(end 138.902186 -241.495072)
					)
					(arc
						(start 138.902186 -241.495072)
						(mid 138.923195 -241.491872)
						(end 138.941048 -241.48034)
					)
					(arc
						(start 138.941048 -241.48034)
						(mid 138.955883 -241.444437)
						(end 138.941048 -241.408458)
					)
					(arc
						(start 138.941048 -241.408458)
						(mid 138.929227 -241.399716)
						(end 138.915394 -241.394742)
					)
					(xy 138.89482 -241.394742) (xy 138.894312 -241.394742)
					(arc
						(start 138.893296 -241.394742)
						(mid 138.820591 -241.379904)
						(end 138.75893 -241.338608)
					)
					(arc
						(start 138.75893 -241.338608)
						(mid 138.702853 -241.203226)
						(end 138.75893 -241.067844)
					)
					(arc
						(start 138.75893 -241.067844)
						(mid 138.821396 -241.026195)
						(end 138.895074 -241.01171)
					)
					(xy 138.895836 -241.011964)
					(arc
						(start 138.916156 -241.011964)
						(mid 138.930138 -241.006888)
						(end 138.942064 -240.997994)
					)
				)
			)
		)
		(zone
			(layer "F.Cu")
			(hatch none 0.5)
			(connect_pads
				(clearance 0)
			)
			(min_thickness 0.25)
			(keepout
				(tracks not_allowed)
				(vias allowed)
				(pads allowed)
				(copperpour not_allowed)
				(footprints allowed)
			)
			(placement
				(enabled no)
				(sheetname "")
			)
			(fill
				(thermal_gap 0.5)
				(thermal_bridge_width 0.5)
				(island_removal_mode 0)
			)
			(polygon
				(pts
					(arc
						(start 138.942064 -239.370108)
						(mid 138.956825 -239.334294)
						(end 138.942064 -239.29848)
					)
					(arc
						(start 138.942064 -239.29848)
						(mid 138.924942 -239.287129)
						(end 138.904726 -239.283494)
					)
					(arc
						(start 138.904726 -239.283494)
						(mid 138.787385 -239.303588)
						(end 138.68781 -239.368838)
					)
					(arc
						(start 138.68781 -239.368838)
						(mid 138.602274 -239.57534)
						(end 138.68781 -239.781842)
					)
					(arc
						(start 138.68781 -239.781842)
						(mid 138.786172 -239.846771)
						(end 138.902186 -239.86744)
					)
					(arc
						(start 138.902186 -239.86744)
						(mid 138.923235 -239.864129)
						(end 138.941048 -239.852454)
					)
					(arc
						(start 138.941048 -239.852454)
						(mid 138.955883 -239.816551)
						(end 138.941048 -239.780572)
					)
					(arc
						(start 138.941048 -239.780572)
						(mid 138.929227 -239.77183)
						(end 138.915394 -239.766856)
					)
					(xy 138.89482 -239.766856) (xy 138.894312 -239.766856)
					(arc
						(start 138.893296 -239.766856)
						(mid 138.820591 -239.752018)
						(end 138.75893 -239.710722)
					)
					(arc
						(start 138.75893 -239.710722)
						(mid 138.702853 -239.57534)
						(end 138.75893 -239.439958)
					)
					(arc
						(start 138.75893 -239.439958)
						(mid 138.821381 -239.398226)
						(end 138.895074 -239.383824)
					)
					(xy 138.895836 -239.384078)
					(arc
						(start 138.916156 -239.384078)
						(mid 138.930138 -239.379002)
						(end 138.942064 -239.370108)
					)
				)
			)
		)
		(zone
			(layer "F.Cu")
			(hatch none 0.5)
			(connect_pads
				(clearance 0)
			)
			(min_thickness 0.25)
			(keepout
				(tracks not_allowed)
				(vias allowed)
				(pads allowed)
				(copperpour not_allowed)
				(footprints allowed)
			)
			(placement
				(enabled no)
				(sheetname "")
			)
			(fill
				(thermal_gap 0.5)
				(thermal_bridge_width 0.5)
				(island_removal_mode 0)
			)
			(polygon
				(pts
					(arc
						(start 138.942064 -237.742476)
						(mid 138.956899 -237.706573)
						(end 138.942064 -237.670594)
					)
					(arc
						(start 138.942064 -237.670594)
						(mid 138.924942 -237.659243)
						(end 138.904726 -237.655608)
					)
					(arc
						(start 138.904726 -237.655608)
						(mid 138.787358 -237.675823)
						(end 138.68781 -237.741206)
					)
					(arc
						(start 138.68781 -237.741206)
						(mid 138.602274 -237.947618)
						(end 138.68781 -238.153956)
					)
					(arc
						(start 138.68781 -238.153956)
						(mid 138.786172 -238.218885)
						(end 138.902186 -238.239554)
					)
					(arc
						(start 138.902186 -238.239554)
						(mid 138.923208 -238.236366)
						(end 138.941048 -238.224822)
					)
					(arc
						(start 138.941048 -238.224822)
						(mid 138.955883 -238.188919)
						(end 138.941048 -238.15294)
					)
					(arc
						(start 138.941048 -238.15294)
						(mid 138.929243 -238.144157)
						(end 138.915394 -238.139224)
					)
					(xy 138.89482 -238.139224) (xy 138.894312 -238.139224)
					(arc
						(start 138.893296 -238.139224)
						(mid 138.820591 -238.124386)
						(end 138.75893 -238.08309)
					)
					(arc
						(start 138.75893 -238.08309)
						(mid 138.702853 -237.947618)
						(end 138.75893 -237.812072)
					)
					(arc
						(start 138.75893 -237.812072)
						(mid 138.821425 -237.770561)
						(end 138.895074 -237.756192)
					)
					(xy 138.895836 -237.756192)
					(arc
						(start 138.916156 -237.756192)
						(mid 138.9301 -237.751216)
						(end 138.942064 -237.742476)
					)
				)
			)
		)
		(zone
			(layer "F.Cu")
			(hatch none 0.5)
			(connect_pads
				(clearance 0)
			)
			(min_thickness 0.25)
			(keepout
				(tracks not_allowed)
				(vias allowed)
				(pads allowed)
				(copperpour not_allowed)
				(footprints allowed)
			)
			(placement
				(enabled no)
				(sheetname "")
			)
			(fill
				(thermal_gap 0.5)
				(thermal_bridge_width 0.5)
				(island_removal_mode 0)
			)
			(polygon
				(pts
					(arc
						(start 138.942064 -236.11459)
						(mid 138.956825 -236.078776)
						(end 138.942064 -236.042962)
					)
					(arc
						(start 138.942064 -236.042962)
						(mid 138.924942 -236.031611)
						(end 138.904726 -236.027976)
					)
					(arc
						(start 138.904726 -236.027976)
						(mid 138.787385 -236.04807)
						(end 138.68781 -236.11332)
					)
					(arc
						(start 138.68781 -236.11332)
						(mid 138.602274 -236.319822)
						(end 138.68781 -236.526324)
					)
					(arc
						(start 138.68781 -236.526324)
						(mid 138.786172 -236.591253)
						(end 138.902186 -236.611922)
					)
					(arc
						(start 138.902186 -236.611922)
						(mid 138.923208 -236.608734)
						(end 138.941048 -236.59719)
					)
					(arc
						(start 138.941048 -236.59719)
						(mid 138.956063 -236.561122)
						(end 138.941048 -236.525054)
					)
					(arc
						(start 138.941048 -236.525054)
						(mid 138.929194 -236.516478)
						(end 138.915394 -236.511592)
					)
					(xy 138.89482 -236.511592) (xy 138.894312 -236.511592)
					(arc
						(start 138.893296 -236.511592)
						(mid 138.820561 -236.496638)
						(end 138.75893 -236.455204)
					)
					(arc
						(start 138.75893 -236.455204)
						(mid 138.702853 -236.319822)
						(end 138.75893 -236.18444)
					)
					(arc
						(start 138.75893 -236.18444)
						(mid 138.821381 -236.142708)
						(end 138.895074 -236.128306)
					)
					(xy 138.895836 -236.12856)
					(arc
						(start 138.916156 -236.12856)
						(mid 138.930138 -236.123484)
						(end 138.942064 -236.11459)
					)
				)
			)
		)
		(zone
			(layer "F.Cu")
			(hatch none 0.5)
			(connect_pads
				(clearance 0)
			)
			(min_thickness 0.25)
			(keepout
				(tracks not_allowed)
				(vias allowed)
				(pads allowed)
				(copperpour not_allowed)
				(footprints allowed)
			)
			(placement
				(enabled no)
				(sheetname "")
			)
			(fill
				(thermal_gap 0.5)
				(thermal_bridge_width 0.5)
				(island_removal_mode 0)
			)
			(polygon
				(pts
					(arc
						(start 138.942064 -234.486958)
						(mid 138.956899 -234.451055)
						(end 138.942064 -234.415076)
					)
					(arc
						(start 138.942064 -234.415076)
						(mid 138.924942 -234.403725)
						(end 138.904726 -234.40009)
					)
					(arc
						(start 138.904726 -234.40009)
						(mid 138.787358 -234.420305)
						(end 138.68781 -234.485688)
					)
					(arc
						(start 138.68781 -234.485688)
						(mid 138.602274 -234.69219)
						(end 138.68781 -234.898692)
					)
					(arc
						(start 138.68781 -234.898692)
						(mid 138.786203 -234.963481)
						(end 138.902186 -234.984036)
					)
					(arc
						(start 138.902186 -234.984036)
						(mid 138.923195 -234.980836)
						(end 138.941048 -234.969304)
					)
					(arc
						(start 138.941048 -234.969304)
						(mid 138.955883 -234.933401)
						(end 138.941048 -234.897422)
					)
					(arc
						(start 138.941048 -234.897422)
						(mid 138.929227 -234.88868)
						(end 138.915394 -234.883706)
					)
					(xy 138.89482 -234.883706) (xy 138.894312 -234.883706)
					(arc
						(start 138.893296 -234.883706)
						(mid 138.820591 -234.868868)
						(end 138.75893 -234.827572)
					)
					(arc
						(start 138.75893 -234.827572)
						(mid 138.702853 -234.6921)
						(end 138.75893 -234.556554)
					)
					(arc
						(start 138.75893 -234.556554)
						(mid 138.821425 -234.515043)
						(end 138.895074 -234.500674)
					)
					(xy 138.895836 -234.500674)
					(arc
						(start 138.916156 -234.500674)
						(mid 138.9301 -234.495698)
						(end 138.942064 -234.486958)
					)
				)
			)
		)
		(zone
			(layer "F.Cu")
			(hatch none 0.5)
			(connect_pads
				(clearance 0)
			)
			(min_thickness 0.25)
			(keepout
				(tracks not_allowed)
				(vias allowed)
				(pads allowed)
				(copperpour not_allowed)
				(footprints allowed)
			)
			(placement
				(enabled no)
				(sheetname "")
			)
			(fill
				(thermal_gap 0.5)
				(thermal_bridge_width 0.5)
				(island_removal_mode 0)
			)
			(polygon
				(pts
					(arc
						(start 138.942064 -232.859072)
						(mid 138.956899 -232.823169)
						(end 138.942064 -232.78719)
					)
					(arc
						(start 138.942064 -232.78719)
						(mid 138.924911 -232.775979)
						(end 138.904726 -232.772458)
					)
					(arc
						(start 138.904726 -232.772458)
						(mid 138.787385 -232.792552)
						(end 138.68781 -232.857802)
					)
					(arc
						(start 138.68781 -232.857802)
						(mid 138.602274 -233.064304)
						(end 138.68781 -233.270806)
					)
					(arc
						(start 138.68781 -233.270806)
						(mid 138.786172 -233.335735)
						(end 138.902186 -233.356404)
					)
					(arc
						(start 138.902186 -233.356404)
						(mid 138.923235 -233.353093)
						(end 138.941048 -233.341418)
					)
					(arc
						(start 138.941048 -233.341418)
						(mid 138.955883 -233.305515)
						(end 138.941048 -233.269536)
					)
					(arc
						(start 138.941048 -233.269536)
						(mid 138.929227 -233.260794)
						(end 138.915394 -233.25582)
					)
					(xy 138.89482 -233.25582) (xy 138.894312 -233.25582)
					(arc
						(start 138.893296 -233.25582)
						(mid 138.820591 -233.240982)
						(end 138.75893 -233.199686)
					)
					(arc
						(start 138.75893 -233.199686)
						(mid 138.702853 -233.064304)
						(end 138.75893 -232.928922)
					)
					(arc
						(start 138.75893 -232.928922)
						(mid 138.821396 -232.887273)
						(end 138.895074 -232.872788)
					)
					(xy 138.895836 -232.873042)
					(arc
						(start 138.916156 -232.873042)
						(mid 138.930138 -232.867966)
						(end 138.942064 -232.859072)
					)
				)
			)
		)
		(zone
			(layer "F.Cu")
			(hatch none 0.5)
			(connect_pads
				(clearance 0)
			)
			(min_thickness 0.25)
			(keepout
				(tracks not_allowed)
				(vias allowed)
				(pads allowed)
				(copperpour not_allowed)
				(footprints allowed)
			)
			(placement
				(enabled no)
				(sheetname "")
			)
			(fill
				(thermal_gap 0.5)
				(thermal_bridge_width 0.5)
				(island_removal_mode 0)
			)
			(polygon
				(pts
					(arc
						(start 138.942064 -231.231186)
						(mid 138.956825 -231.195372)
						(end 138.942064 -231.159558)
					)
					(arc
						(start 138.942064 -231.159558)
						(mid 138.924942 -231.148207)
						(end 138.904726 -231.144572)
					)
					(arc
						(start 138.904726 -231.144572)
						(mid 138.787385 -231.164666)
						(end 138.68781 -231.229916)
					)
					(arc
						(start 138.68781 -231.229916)
						(mid 138.602274 -231.436418)
						(end 138.68781 -231.64292)
					)
					(arc
						(start 138.68781 -231.64292)
						(mid 138.786172 -231.707849)
						(end 138.902186 -231.728518)
					)
					(arc
						(start 138.902186 -231.728518)
						(mid 138.923208 -231.72533)
						(end 138.941048 -231.713786)
					)
					(arc
						(start 138.941048 -231.713786)
						(mid 138.955883 -231.677883)
						(end 138.941048 -231.641904)
					)
					(arc
						(start 138.941048 -231.641904)
						(mid 138.929243 -231.633121)
						(end 138.915394 -231.628188)
					)
					(xy 138.89482 -231.628188) (xy 138.894312 -231.628188)
					(arc
						(start 138.893296 -231.628188)
						(mid 138.820561 -231.613234)
						(end 138.75893 -231.5718)
					)
					(arc
						(start 138.75893 -231.5718)
						(mid 138.702853 -231.436418)
						(end 138.75893 -231.301036)
					)
					(arc
						(start 138.75893 -231.301036)
						(mid 138.821395 -231.259358)
						(end 138.895074 -231.244902)
					)
					(xy 138.895836 -231.245156)
					(arc
						(start 138.916156 -231.245156)
						(mid 138.930138 -231.24008)
						(end 138.942064 -231.231186)
					)
				)
			)
		)
		(zone
			(layer "F.Cu")
			(hatch none 0.5)
			(connect_pads
				(clearance 0)
			)
			(min_thickness 0.25)
			(keepout
				(tracks not_allowed)
				(vias allowed)
				(pads allowed)
				(copperpour not_allowed)
				(footprints allowed)
			)
			(placement
				(enabled no)
				(sheetname "")
			)
			(fill
				(thermal_gap 0.5)
				(thermal_bridge_width 0.5)
				(island_removal_mode 0)
			)
			(polygon
				(pts
					(arc
						(start 138.942064 -229.603554)
						(mid 138.956899 -229.567651)
						(end 138.942064 -229.531672)
					)
					(arc
						(start 138.942064 -229.531672)
						(mid 138.924942 -229.520321)
						(end 138.904726 -229.516686)
					)
					(arc
						(start 138.904726 -229.516686)
						(mid 138.787358 -229.536901)
						(end 138.68781 -229.602284)
					)
					(arc
						(start 138.68781 -229.602284)
						(mid 138.602274 -229.808786)
						(end 138.68781 -230.015288)
					)
					(arc
						(start 138.68781 -230.015288)
						(mid 138.786203 -230.080077)
						(end 138.902186 -230.100632)
					)
					(arc
						(start 138.902186 -230.100632)
						(mid 138.923195 -230.097432)
						(end 138.941048 -230.0859)
					)
					(arc
						(start 138.941048 -230.0859)
						(mid 138.955883 -230.049997)
						(end 138.941048 -230.014018)
					)
					(arc
						(start 138.941048 -230.014018)
						(mid 138.929227 -230.005276)
						(end 138.915394 -230.000302)
					)
					(xy 138.89482 -230.000302) (xy 138.894312 -230.000302)
					(arc
						(start 138.893296 -230.000302)
						(mid 138.820591 -229.985464)
						(end 138.75893 -229.944168)
					)
					(arc
						(start 138.75893 -229.944168)
						(mid 138.702853 -229.808786)
						(end 138.75893 -229.673404)
					)
					(arc
						(start 138.75893 -229.673404)
						(mid 138.821396 -229.631755)
						(end 138.895074 -229.61727)
					)
					(xy 138.895836 -229.61727)
					(arc
						(start 138.916156 -229.61727)
						(mid 138.9301 -229.612294)
						(end 138.942064 -229.603554)
					)
				)
			)
		)
		(zone
			(layer "F.Cu")
			(hatch none 0.5)
			(connect_pads
				(clearance 0)
			)
			(min_thickness 0.25)
			(keepout
				(tracks not_allowed)
				(vias allowed)
				(pads allowed)
				(copperpour not_allowed)
				(footprints allowed)
			)
			(placement
				(enabled no)
				(sheetname "")
			)
			(fill
				(thermal_gap 0.5)
				(thermal_bridge_width 0.5)
				(island_removal_mode 0)
			)
			(polygon
				(pts
					(arc
						(start 138.942064 -227.975668)
						(mid 138.956825 -227.939854)
						(end 138.942064 -227.90404)
					)
					(arc
						(start 138.942064 -227.90404)
						(mid 138.924942 -227.892689)
						(end 138.904726 -227.889054)
					)
					(arc
						(start 138.904726 -227.889054)
						(mid 138.787385 -227.909148)
						(end 138.68781 -227.974398)
					)
					(arc
						(start 138.68781 -227.974398)
						(mid 138.602274 -228.1809)
						(end 138.68781 -228.387402)
					)
					(arc
						(start 138.68781 -228.387402)
						(mid 138.786172 -228.452331)
						(end 138.902186 -228.473)
					)
					(arc
						(start 138.902186 -228.473)
						(mid 138.923208 -228.469812)
						(end 138.941048 -228.458268)
					)
					(arc
						(start 138.941048 -228.458268)
						(mid 138.955883 -228.422365)
						(end 138.941048 -228.386386)
					)
					(arc
						(start 138.941048 -228.386386)
						(mid 138.929243 -228.377603)
						(end 138.915394 -228.37267)
					)
					(xy 138.89482 -228.37267) (xy 138.894312 -228.37267)
					(arc
						(start 138.893296 -228.37267)
						(mid 138.820561 -228.357716)
						(end 138.75893 -228.316282)
					)
					(arc
						(start 138.75893 -228.316282)
						(mid 138.702853 -228.1809)
						(end 138.75893 -228.045518)
					)
					(arc
						(start 138.75893 -228.045518)
						(mid 138.821395 -228.00384)
						(end 138.895074 -227.989384)
					)
					(xy 138.895836 -227.989638)
					(arc
						(start 138.916156 -227.989638)
						(mid 138.930138 -227.984562)
						(end 138.942064 -227.975668)
					)
				)
			)
		)
		(zone
			(layer "F.Cu")
			(hatch none 0.5)
			(connect_pads
				(clearance 0)
			)
			(min_thickness 0.25)
			(keepout
				(tracks not_allowed)
				(vias allowed)
				(pads allowed)
				(copperpour not_allowed)
				(footprints allowed)
			)
			(placement
				(enabled no)
				(sheetname "")
			)
			(fill
				(thermal_gap 0.5)
				(thermal_bridge_width 0.5)
				(island_removal_mode 0)
			)
			(polygon
				(pts
					(arc
						(start 138.942064 -226.348036)
						(mid 138.956899 -226.312133)
						(end 138.942064 -226.276154)
					)
					(arc
						(start 138.942064 -226.276154)
						(mid 138.924942 -226.264803)
						(end 138.904726 -226.261168)
					)
					(arc
						(start 138.904726 -226.261168)
						(mid 138.787358 -226.281383)
						(end 138.68781 -226.346766)
					)
					(arc
						(start 138.68781 -226.346766)
						(mid 138.602274 -226.553268)
						(end 138.68781 -226.75977)
					)
					(arc
						(start 138.68781 -226.75977)
						(mid 138.786203 -226.824559)
						(end 138.902186 -226.845114)
					)
					(arc
						(start 138.902186 -226.845114)
						(mid 138.923195 -226.841914)
						(end 138.941048 -226.830382)
					)
					(arc
						(start 138.941048 -226.830382)
						(mid 138.955883 -226.794479)
						(end 138.941048 -226.7585)
					)
					(arc
						(start 138.941048 -226.7585)
						(mid 138.929227 -226.749758)
						(end 138.915394 -226.744784)
					)
					(xy 138.89482 -226.744784) (xy 138.894312 -226.744784)
					(arc
						(start 138.893296 -226.744784)
						(mid 138.820591 -226.729946)
						(end 138.75893 -226.68865)
					)
					(arc
						(start 138.75893 -226.68865)
						(mid 138.702853 -226.553268)
						(end 138.75893 -226.417886)
					)
					(arc
						(start 138.75893 -226.417886)
						(mid 138.821396 -226.376237)
						(end 138.895074 -226.361752)
					)
					(xy 138.895836 -226.362006)
					(arc
						(start 138.916156 -226.362006)
						(mid 138.930138 -226.35693)
						(end 138.942064 -226.348036)
					)
				)
			)
		)
		(zone
			(layer "F.Cu")
			(hatch none 0.5)
			(connect_pads
				(clearance 0)
			)
			(min_thickness 0.25)
			(keepout
				(tracks not_allowed)
				(vias allowed)
				(pads allowed)
				(copperpour not_allowed)
				(footprints allowed)
			)
			(placement
				(enabled no)
				(sheetname "")
			)
			(fill
				(thermal_gap 0.5)
				(thermal_bridge_width 0.5)
				(island_removal_mode 0)
			)
			(polygon
				(pts
					(arc
						(start 138.942064 -224.72015)
						(mid 138.956899 -224.684247)
						(end 138.942064 -224.648268)
					)
					(arc
						(start 138.942064 -224.648268)
						(mid 138.924911 -224.637057)
						(end 138.904726 -224.633536)
					)
					(arc
						(start 138.904726 -224.633536)
						(mid 138.787385 -224.65363)
						(end 138.68781 -224.71888)
					)
					(arc
						(start 138.68781 -224.71888)
						(mid 138.602274 -224.925382)
						(end 138.68781 -225.131884)
					)
					(arc
						(start 138.68781 -225.131884)
						(mid 138.786172 -225.196813)
						(end 138.902186 -225.217482)
					)
					(arc
						(start 138.902186 -225.217482)
						(mid 138.923235 -225.214171)
						(end 138.941048 -225.202496)
					)
					(arc
						(start 138.941048 -225.202496)
						(mid 138.955883 -225.166593)
						(end 138.941048 -225.130614)
					)
					(arc
						(start 138.941048 -225.130614)
						(mid 138.929227 -225.121872)
						(end 138.915394 -225.116898)
					)
					(xy 138.89482 -225.116898) (xy 138.894312 -225.116898)
					(arc
						(start 138.893296 -225.116898)
						(mid 138.820591 -225.10206)
						(end 138.75893 -225.060764)
					)
					(arc
						(start 138.75893 -225.060764)
						(mid 138.702853 -224.925382)
						(end 138.75893 -224.79)
					)
					(arc
						(start 138.75893 -224.79)
						(mid 138.821396 -224.748351)
						(end 138.895074 -224.733866)
					)
					(xy 138.895836 -224.73412)
					(arc
						(start 138.916156 -224.73412)
						(mid 138.930138 -224.729044)
						(end 138.942064 -224.72015)
					)
				)
			)
		)
		(zone
			(layer "F.Cu")
			(hatch none 0.5)
			(connect_pads
				(clearance 0)
			)
			(min_thickness 0.25)
			(keepout
				(tracks not_allowed)
				(vias allowed)
				(pads allowed)
				(copperpour not_allowed)
				(footprints allowed)
			)
			(placement
				(enabled no)
				(sheetname "")
			)
			(fill
				(thermal_gap 0.5)
				(thermal_bridge_width 0.5)
				(island_removal_mode 0)
			)
			(polygon
				(pts
					(arc
						(start 138.942064 -223.092264)
						(mid 138.956825 -223.05645)
						(end 138.942064 -223.020636)
					)
					(arc
						(start 138.942064 -223.020636)
						(mid 138.924942 -223.009285)
						(end 138.904726 -223.00565)
					)
					(arc
						(start 138.904726 -223.00565)
						(mid 138.787385 -223.025744)
						(end 138.68781 -223.090994)
					)
					(arc
						(start 138.68781 -223.090994)
						(mid 138.602274 -223.297496)
						(end 138.68781 -223.503998)
					)
					(arc
						(start 138.68781 -223.503998)
						(mid 138.786172 -223.568927)
						(end 138.902186 -223.589596)
					)
					(arc
						(start 138.902186 -223.589596)
						(mid 138.923208 -223.586408)
						(end 138.941048 -223.574864)
					)
					(arc
						(start 138.941048 -223.574864)
						(mid 138.955883 -223.538961)
						(end 138.941048 -223.502982)
					)
					(arc
						(start 138.941048 -223.502982)
						(mid 138.929243 -223.494199)
						(end 138.915394 -223.489266)
					)
					(xy 138.89482 -223.489266) (xy 138.894312 -223.489266)
					(arc
						(start 138.893296 -223.489266)
						(mid 138.820561 -223.474312)
						(end 138.75893 -223.432878)
					)
					(arc
						(start 138.75893 -223.432878)
						(mid 138.702853 -223.297496)
						(end 138.75893 -223.162114)
					)
					(arc
						(start 138.75893 -223.162114)
						(mid 138.821395 -223.120436)
						(end 138.895074 -223.10598)
					)
					(xy 138.895836 -223.106234)
					(arc
						(start 138.916156 -223.106234)
						(mid 138.930138 -223.101158)
						(end 138.942064 -223.092264)
					)
				)
			)
		)
		(zone
			(layer "F.Cu")
			(hatch none 0.5)
			(connect_pads
				(clearance 0)
			)
			(min_thickness 0.25)
			(keepout
				(tracks not_allowed)
				(vias allowed)
				(pads allowed)
				(copperpour not_allowed)
				(footprints allowed)
			)
			(placement
				(enabled no)
				(sheetname "")
			)
			(fill
				(thermal_gap 0.5)
				(thermal_bridge_width 0.5)
				(island_removal_mode 0)
			)
			(polygon
				(pts
					(arc
						(start 139.052046 -264.573258)
						(mid 139.066881 -264.537355)
						(end 139.052046 -264.501376)
					)
					(arc
						(start 139.052046 -264.501376)
						(mid 139.034924 -264.490025)
						(end 139.014708 -264.48639)
					)
					(arc
						(start 139.014708 -264.48639)
						(mid 138.89734 -264.506605)
						(end 138.797792 -264.571988)
					)
					(arc
						(start 138.797792 -264.571988)
						(mid 138.712256 -264.77849)
						(end 138.797792 -264.984992)
					)
					(arc
						(start 138.797792 -264.984992)
						(mid 138.896185 -265.049781)
						(end 139.012168 -265.070336)
					)
					(arc
						(start 139.012168 -265.070336)
						(mid 139.033177 -265.067136)
						(end 139.05103 -265.055604)
					)
					(arc
						(start 139.05103 -265.055604)
						(mid 139.065865 -265.019701)
						(end 139.05103 -264.983722)
					)
					(arc
						(start 139.05103 -264.983722)
						(mid 139.039209 -264.97498)
						(end 139.025376 -264.970006)
					)
					(xy 139.004802 -264.970006) (xy 139.004294 -264.970006)
					(arc
						(start 139.003278 -264.970006)
						(mid 138.930573 -264.955168)
						(end 138.868912 -264.913872)
					)
					(arc
						(start 138.868912 -264.913872)
						(mid 138.812835 -264.7784)
						(end 138.868912 -264.642854)
					)
					(arc
						(start 138.868912 -264.642854)
						(mid 138.931407 -264.601343)
						(end 139.005056 -264.586974)
					)
					(xy 139.005818 -264.586974)
					(arc
						(start 139.026392 -264.586974)
						(mid 139.040216 -264.581983)
						(end 139.052046 -264.573258)
					)
				)
			)
		)
		(zone
			(layer "F.Cu")
			(hatch none 0.5)
			(connect_pads
				(clearance 0)
			)
			(min_thickness 0.25)
			(keepout
				(tracks not_allowed)
				(vias allowed)
				(pads allowed)
				(copperpour not_allowed)
				(footprints allowed)
			)
			(placement
				(enabled no)
				(sheetname "")
			)
			(fill
				(thermal_gap 0.5)
				(thermal_bridge_width 0.5)
				(island_removal_mode 0)
			)
			(polygon
				(pts
					(arc
						(start 139.052046 -262.945372)
						(mid 139.066881 -262.909469)
						(end 139.052046 -262.87349)
					)
					(arc
						(start 139.052046 -262.87349)
						(mid 139.034893 -262.862279)
						(end 139.014708 -262.858758)
					)
					(arc
						(start 139.014708 -262.858758)
						(mid 138.897367 -262.878852)
						(end 138.797792 -262.944102)
					)
					(arc
						(start 138.797792 -262.944102)
						(mid 138.712256 -263.150604)
						(end 138.797792 -263.357106)
					)
					(arc
						(start 138.797792 -263.357106)
						(mid 138.896154 -263.422035)
						(end 139.012168 -263.442704)
					)
					(arc
						(start 139.012168 -263.442704)
						(mid 139.033217 -263.439393)
						(end 139.05103 -263.427718)
					)
					(arc
						(start 139.05103 -263.427718)
						(mid 139.065865 -263.391815)
						(end 139.05103 -263.355836)
					)
					(arc
						(start 139.05103 -263.355836)
						(mid 139.039209 -263.347094)
						(end 139.025376 -263.34212)
					)
					(xy 139.004802 -263.34212) (xy 139.004294 -263.34212)
					(arc
						(start 139.003278 -263.34212)
						(mid 138.930573 -263.327282)
						(end 138.868912 -263.285986)
					)
					(arc
						(start 138.868912 -263.285986)
						(mid 138.812835 -263.150604)
						(end 138.868912 -263.015222)
					)
					(arc
						(start 138.868912 -263.015222)
						(mid 138.931378 -262.973573)
						(end 139.005056 -262.959088)
					)
					(xy 139.005818 -262.959342)
					(arc
						(start 139.026392 -262.959342)
						(mid 139.040254 -262.954252)
						(end 139.052046 -262.945372)
					)
				)
			)
		)
		(zone
			(layer "F.Cu")
			(hatch none 0.5)
			(connect_pads
				(clearance 0)
			)
			(min_thickness 0.25)
			(keepout
				(tracks not_allowed)
				(vias allowed)
				(pads allowed)
				(copperpour not_allowed)
				(footprints allowed)
			)
			(placement
				(enabled no)
				(sheetname "")
			)
			(fill
				(thermal_gap 0.5)
				(thermal_bridge_width 0.5)
				(island_removal_mode 0)
			)
			(polygon
				(pts
					(arc
						(start 139.052046 -261.317486)
						(mid 139.066807 -261.281672)
						(end 139.052046 -261.245858)
					)
					(arc
						(start 139.052046 -261.245858)
						(mid 139.034924 -261.234507)
						(end 139.014708 -261.230872)
					)
					(arc
						(start 139.014708 -261.230872)
						(mid 138.897367 -261.250966)
						(end 138.797792 -261.316216)
					)
					(arc
						(start 138.797792 -261.316216)
						(mid 138.712256 -261.522718)
						(end 138.797792 -261.72922)
					)
					(arc
						(start 138.797792 -261.72922)
						(mid 138.896154 -261.794149)
						(end 139.012168 -261.814818)
					)
					(arc
						(start 139.012168 -261.814818)
						(mid 139.03319 -261.81163)
						(end 139.05103 -261.800086)
					)
					(arc
						(start 139.05103 -261.800086)
						(mid 139.065865 -261.764183)
						(end 139.05103 -261.728204)
					)
					(arc
						(start 139.05103 -261.728204)
						(mid 139.039225 -261.719421)
						(end 139.025376 -261.714488)
					)
					(xy 139.004802 -261.714488) (xy 139.004294 -261.714488)
					(arc
						(start 139.003278 -261.714488)
						(mid 138.930543 -261.699534)
						(end 138.868912 -261.6581)
					)
					(arc
						(start 138.868912 -261.6581)
						(mid 138.812835 -261.522718)
						(end 138.868912 -261.387336)
					)
					(arc
						(start 138.868912 -261.387336)
						(mid 138.931377 -261.345658)
						(end 139.005056 -261.331202)
					)
					(xy 139.005818 -261.331456)
					(arc
						(start 139.026392 -261.331456)
						(mid 139.040254 -261.326366)
						(end 139.052046 -261.317486)
					)
				)
			)
		)
		(zone
			(layer "F.Cu")
			(hatch none 0.5)
			(connect_pads
				(clearance 0)
			)
			(min_thickness 0.25)
			(keepout
				(tracks not_allowed)
				(vias allowed)
				(pads allowed)
				(copperpour not_allowed)
				(footprints allowed)
			)
			(placement
				(enabled no)
				(sheetname "")
			)
			(fill
				(thermal_gap 0.5)
				(thermal_bridge_width 0.5)
				(island_removal_mode 0)
			)
			(polygon
				(pts
					(arc
						(start 139.052046 -259.689854)
						(mid 139.066881 -259.653951)
						(end 139.052046 -259.617972)
					)
					(arc
						(start 139.052046 -259.617972)
						(mid 139.034924 -259.606621)
						(end 139.014708 -259.602986)
					)
					(arc
						(start 139.014708 -259.602986)
						(mid 138.89734 -259.623201)
						(end 138.797792 -259.688584)
					)
					(arc
						(start 138.797792 -259.688584)
						(mid 138.712256 -259.895086)
						(end 138.797792 -260.101588)
					)
					(arc
						(start 138.797792 -260.101588)
						(mid 138.896185 -260.166377)
						(end 139.012168 -260.186932)
					)
					(arc
						(start 139.012168 -260.186932)
						(mid 139.033177 -260.183732)
						(end 139.05103 -260.1722)
					)
					(arc
						(start 139.05103 -260.1722)
						(mid 139.065865 -260.136297)
						(end 139.05103 -260.100318)
					)
					(arc
						(start 139.05103 -260.100318)
						(mid 139.039209 -260.091576)
						(end 139.025376 -260.086602)
					)
					(xy 139.004802 -260.086602) (xy 139.004294 -260.086602)
					(arc
						(start 139.003278 -260.086602)
						(mid 138.930573 -260.071764)
						(end 138.868912 -260.030468)
					)
					(arc
						(start 138.868912 -260.030468)
						(mid 138.812835 -259.895086)
						(end 138.868912 -259.759704)
					)
					(arc
						(start 138.868912 -259.759704)
						(mid 138.931378 -259.718055)
						(end 139.005056 -259.70357)
					)
					(xy 139.005818 -259.70357)
					(arc
						(start 139.026392 -259.70357)
						(mid 139.040216 -259.698579)
						(end 139.052046 -259.689854)
					)
				)
			)
		)
		(zone
			(layer "F.Cu")
			(hatch none 0.5)
			(connect_pads
				(clearance 0)
			)
			(min_thickness 0.25)
			(keepout
				(tracks not_allowed)
				(vias allowed)
				(pads allowed)
				(copperpour not_allowed)
				(footprints allowed)
			)
			(placement
				(enabled no)
				(sheetname "")
			)
			(fill
				(thermal_gap 0.5)
				(thermal_bridge_width 0.5)
				(island_removal_mode 0)
			)
			(polygon
				(pts
					(arc
						(start 139.052046 -258.061968)
						(mid 139.066881 -258.026065)
						(end 139.052046 -257.990086)
					)
					(arc
						(start 139.052046 -257.990086)
						(mid 139.034893 -257.978875)
						(end 139.014708 -257.975354)
					)
					(arc
						(start 139.014708 -257.975354)
						(mid 138.897367 -257.995448)
						(end 138.797792 -258.060698)
					)
					(arc
						(start 138.797792 -258.060698)
						(mid 138.712256 -258.2672)
						(end 138.797792 -258.473702)
					)
					(arc
						(start 138.797792 -258.473702)
						(mid 138.896154 -258.538631)
						(end 139.012168 -258.5593)
					)
					(arc
						(start 139.012168 -258.5593)
						(mid 139.033217 -258.555989)
						(end 139.05103 -258.544314)
					)
					(arc
						(start 139.05103 -258.544314)
						(mid 139.065865 -258.508411)
						(end 139.05103 -258.472432)
					)
					(arc
						(start 139.05103 -258.472432)
						(mid 139.039209 -258.46369)
						(end 139.025376 -258.458716)
					)
					(xy 139.004802 -258.458716) (xy 139.004294 -258.458716)
					(arc
						(start 139.003278 -258.458716)
						(mid 138.930573 -258.443878)
						(end 138.868912 -258.402582)
					)
					(arc
						(start 138.868912 -258.402582)
						(mid 138.812835 -258.2672)
						(end 138.868912 -258.131818)
					)
					(arc
						(start 138.868912 -258.131818)
						(mid 138.931378 -258.090169)
						(end 139.005056 -258.075684)
					)
					(xy 139.005818 -258.075938)
					(arc
						(start 139.026392 -258.075938)
						(mid 139.040254 -258.070848)
						(end 139.052046 -258.061968)
					)
				)
			)
		)
		(zone
			(layer "F.Cu")
			(hatch none 0.5)
			(connect_pads
				(clearance 0)
			)
			(min_thickness 0.25)
			(keepout
				(tracks not_allowed)
				(vias allowed)
				(pads allowed)
				(copperpour not_allowed)
				(footprints allowed)
			)
			(placement
				(enabled no)
				(sheetname "")
			)
			(fill
				(thermal_gap 0.5)
				(thermal_bridge_width 0.5)
				(island_removal_mode 0)
			)
			(polygon
				(pts
					(arc
						(start 139.052046 -256.434082)
						(mid 139.066807 -256.398268)
						(end 139.052046 -256.362454)
					)
					(arc
						(start 139.052046 -256.362454)
						(mid 139.034924 -256.351103)
						(end 139.014708 -256.347468)
					)
					(arc
						(start 139.014708 -256.347468)
						(mid 138.897367 -256.367562)
						(end 138.797792 -256.432812)
					)
					(arc
						(start 138.797792 -256.432812)
						(mid 138.712256 -256.639314)
						(end 138.797792 -256.845816)
					)
					(arc
						(start 138.797792 -256.845816)
						(mid 138.896154 -256.910745)
						(end 139.012168 -256.931414)
					)
					(arc
						(start 139.012168 -256.931414)
						(mid 139.03319 -256.928226)
						(end 139.05103 -256.916682)
					)
					(arc
						(start 139.05103 -256.916682)
						(mid 139.065865 -256.880779)
						(end 139.05103 -256.8448)
					)
					(arc
						(start 139.05103 -256.8448)
						(mid 139.039225 -256.836017)
						(end 139.025376 -256.831084)
					)
					(xy 139.004802 -256.831084) (xy 139.004294 -256.831084)
					(arc
						(start 139.003278 -256.831084)
						(mid 138.930543 -256.81613)
						(end 138.868912 -256.774696)
					)
					(arc
						(start 138.868912 -256.774696)
						(mid 138.812835 -256.639314)
						(end 138.868912 -256.503932)
					)
					(arc
						(start 138.868912 -256.503932)
						(mid 138.931377 -256.462254)
						(end 139.005056 -256.447798)
					)
					(xy 139.005818 -256.448052)
					(arc
						(start 139.026392 -256.448052)
						(mid 139.040254 -256.442962)
						(end 139.052046 -256.434082)
					)
				)
			)
		)
		(zone
			(layer "F.Cu")
			(hatch none 0.5)
			(connect_pads
				(clearance 0)
			)
			(min_thickness 0.25)
			(keepout
				(tracks not_allowed)
				(vias allowed)
				(pads allowed)
				(copperpour not_allowed)
				(footprints allowed)
			)
			(placement
				(enabled no)
				(sheetname "")
			)
			(fill
				(thermal_gap 0.5)
				(thermal_bridge_width 0.5)
				(island_removal_mode 0)
			)
			(polygon
				(pts
					(arc
						(start 139.052046 -254.80645)
						(mid 139.066881 -254.770547)
						(end 139.052046 -254.734568)
					)
					(arc
						(start 139.052046 -254.734568)
						(mid 139.034924 -254.723217)
						(end 139.014708 -254.719582)
					)
					(arc
						(start 139.014708 -254.719582)
						(mid 138.89734 -254.739797)
						(end 138.797792 -254.80518)
					)
					(arc
						(start 138.797792 -254.80518)
						(mid 138.712256 -255.011682)
						(end 138.797792 -255.218184)
					)
					(arc
						(start 138.797792 -255.218184)
						(mid 138.896185 -255.282973)
						(end 139.012168 -255.303528)
					)
					(arc
						(start 139.012168 -255.303528)
						(mid 139.033177 -255.300328)
						(end 139.05103 -255.288796)
					)
					(arc
						(start 139.05103 -255.288796)
						(mid 139.065865 -255.252893)
						(end 139.05103 -255.216914)
					)
					(arc
						(start 139.05103 -255.216914)
						(mid 139.039209 -255.208172)
						(end 139.025376 -255.203198)
					)
					(xy 139.004802 -255.203198) (xy 139.004294 -255.203198)
					(arc
						(start 139.003278 -255.203198)
						(mid 138.930573 -255.18836)
						(end 138.868912 -255.147064)
					)
					(arc
						(start 138.868912 -255.147064)
						(mid 138.812835 -255.011682)
						(end 138.868912 -254.8763)
					)
					(arc
						(start 138.868912 -254.8763)
						(mid 138.931378 -254.834651)
						(end 139.005056 -254.820166)
					)
					(xy 139.005818 -254.820166)
					(arc
						(start 139.026392 -254.820166)
						(mid 139.040216 -254.815175)
						(end 139.052046 -254.80645)
					)
				)
			)
		)
	)
	(footprint ""
		(layer "F.Cu")
		(at 368.1984 -101.171248 -90)
		(property "Reference" "R1381"
			(at 0 0 270)
			(layer "F.SilkS")
			(hide yes)
			(effects
				(font
					(size 1.27 1.27)
				)
			)
		)
		(property "Value" ""
			(at 0 0 270)
			(layer "F.Fab")
			(effects
				(font
					(size 1.27 1.27)
				)
			)
		)
		(duplicate_pad_numbers_are_jumpers no)
		(fp_line
			(start -0.7874 0.4064)
			(end -0.7874 -0.4064)
			(stroke
				(width 0.1524)
				(type default)
			)
			(layer "F.SilkS")
		)
		(fp_line
			(start 0.7874 0.4064)
			(end -0.7874 0.4064)
			(stroke
				(width 0.1524)
				(type default)
			)
			(layer "F.SilkS")
		)
		(fp_line
			(start -0.7874 -0.4064)
			(end 0.7874 -0.4064)
			(stroke
				(width 0.1524)
				(type default)
			)
			(layer "F.SilkS")
		)
		(fp_line
			(start 0.7874 -0.4064)
			(end 0.7874 0.4064)
			(stroke
				(width 0.1524)
				(type default)
			)
			(layer "F.SilkS")
		)
		(fp_line
			(start -0.67945 0.3048)
			(end -0.67945 -0.305054)
			(stroke
				(width 0.1)
				(type default)
			)
			(layer "F.Fab")
		)
		(fp_line
			(start -0.12065 0.3048)
			(end -0.67945 0.3048)
			(stroke
				(width 0.1)
				(type default)
			)
			(layer "F.Fab")
		)
		(fp_line
			(start 0.120396 0.3048)
			(end 0.120396 0.2794)
			(stroke
				(width 0.1)
				(type default)
			)
			(layer "F.Fab")
		)
		(fp_line
			(start 0.67945 0.3048)
			(end 0.120396 0.3048)
			(stroke
				(width 0.1)
				(type default)
			)
			(layer "F.Fab")
		)
		(fp_line
			(start -0.12065 0.2794)
			(end -0.12065 0.3048)
			(stroke
				(width 0.1)
				(type default)
			)
			(layer "F.Fab")
		)
		(fp_line
			(start 0.120396 0.2794)
			(end -0.12065 0.2794)
			(stroke
				(width 0.1)
				(type default)
			)
			(layer "F.Fab")
		)
		(fp_line
			(start -0.12065 -0.2794)
			(end 0.12065 -0.2794)
			(stroke
				(width 0.1)
				(type default)
			)
			(layer "F.Fab")
		)
		(fp_line
			(start 0.12065 -0.2794)
			(end 0.12065 -0.3048)
			(stroke
				(width 0.1)
				(type default)
			)
			(layer "F.Fab")
		)
		(fp_line
			(start 0.12065 -0.3048)
			(end 0.67945 -0.3048)
			(stroke
				(width 0.1)
				(type default)
			)
			(layer "F.Fab")
		)
		(fp_line
			(start 0.67945 -0.3048)
			(end 0.67945 0.3048)
			(stroke
				(width 0.1)
				(type default)
			)
			(layer "F.Fab")
		)
		(fp_line
			(start -0.67945 -0.305054)
			(end -0.12065 -0.305054)
			(stroke
				(width 0.1)
				(type default)
			)
			(layer "F.Fab")
		)
		(fp_line
			(start -0.12065 -0.305054)
			(end -0.12065 -0.2794)
			(stroke
				(width 0.1)
				(type default)
			)
			(layer "F.Fab")
		)
		(pad "1" smd circle
			(at -0.40005 0 270)
			(size 0 0)
			(layers "F.Cu" "F.Mask" "F.Paste")
			(net "P3V3_AUX")
		)
		(pad "2" smd circle
			(at 0.40005 0 270)
			(size 0 0)
			(layers "F.Cu" "F.Mask" "F.Paste")
			(net "FM_BMC_CPU_FBRK_OUT_N")
		)
	)
	(footprint ""
		(layer "F.Cu")
		(at 120.37822 -417.383468)
		(property "Reference" "R3509"
			(at 0 0 0)
			(layer "F.SilkS")
			(hide yes)
			(effects
				(font
					(size 1.27 1.27)
				)
			)
		)
		(property "Value" ""
			(at 0 0 0)
			(layer "F.Fab")
			(effects
				(font
					(size 1.27 1.27)
				)
			)
		)
		(duplicate_pad_numbers_are_jumpers no)
		(fp_line
			(start -0.7874 -0.4064)
			(end 0.7874 -0.4064)
			(stroke
				(width 0.1524)
				(type default)
			)
			(layer "F.SilkS")
		)
		(fp_line
			(start -0.7874 0.4064)
			(end -0.7874 -0.4064)
			(stroke
				(width 0.1524)
				(type default)
			)
			(layer "F.SilkS")
		)
		(fp_line
			(start 0.7874 -0.4064)
			(end 0.7874 0.4064)
			(stroke
				(width 0.1524)
				(type default)
			)
			(layer "F.SilkS")
		)
		(fp_line
			(start 0.7874 0.4064)
			(end -0.7874 0.4064)
			(stroke
				(width 0.1524)
				(type default)
			)
			(layer "F.SilkS")
		)
		(fp_line
			(start -0.67945 -0.305054)
			(end -0.12065 -0.305054)
			(stroke
				(width 0.1)
				(type default)
			)
			(layer "F.Fab")
		)
		(fp_line
			(start -0.67945 0.3048)
			(end -0.67945 -0.305054)
			(stroke
				(width 0.1)
				(type default)
			)
			(layer "F.Fab")
		)
		(fp_line
			(start -0.12065 -0.305054)
			(end -0.12065 -0.2794)
			(stroke
				(width 0.1)
				(type default)
			)
			(layer "F.Fab")
		)
		(fp_line
			(start -0.12065 -0.2794)
			(end 0.12065 -0.2794)
			(stroke
				(width 0.1)
				(type default)
			)
			(layer "F.Fab")
		)
		(fp_line
			(start -0.12065 0.2794)
			(end -0.12065 0.3048)
			(stroke
				(width 0.1)
				(type default)
			)
			(layer "F.Fab")
		)
		(fp_line
			(start -0.12065 0.3048)
			(end -0.67945 0.3048)
			(stroke
				(width 0.1)
				(type default)
			)
			(layer "F.Fab")
		)
		(fp_line
			(start 0.120396 0.2794)
			(end -0.12065 0.2794)
			(stroke
				(width 0.1)
				(type default)
			)
			(layer "F.Fab")
		)
		(fp_line
			(start 0.120396 0.3048)
			(end 0.120396 0.2794)
			(stroke
				(width 0.1)
				(type default)
			)
			(layer "F.Fab")
		)
		(fp_line
			(start 0.12065 -0.3048)
			(end 0.67945 -0.3048)
			(stroke
				(width 0.1)
				(type default)
			)
			(layer "F.Fab")
		)
		(fp_line
			(start 0.12065 -0.2794)
			(end 0.12065 -0.3048)
			(stroke
				(width 0.1)
				(type default)
			)
			(layer "F.Fab")
		)
		(fp_line
			(start 0.67945 -0.3048)
			(end 0.67945 0.3048)
			(stroke
				(width 0.1)
				(type default)
			)
			(layer "F.Fab")
		)
		(fp_line
			(start 0.67945 0.3048)
			(end 0.120396 0.3048)
			(stroke
				(width 0.1)
				(type default)
			)
			(layer "F.Fab")
		)
		(pad "1" smd circle
			(at -0.40005 0)
			(size 0 0)
			(layers "F.Cu" "F.Mask" "F.Paste")
			(net "GPU_FPGA_RST_R1_BUF_N")
		)
		(pad "2" smd circle
			(at 0.40005 0)
			(size 0 0)
			(layers "F.Cu" "F.Mask" "F.Paste")
			(net "GND")
		)
	)
	(footprint ""
		(layer "F.Cu")
		(at 277.64994 -96.329754)
		(property "Reference" "R721"
			(at 0 0 0)
			(layer "F.SilkS")
			(hide yes)
			(effects
				(font
					(size 1.27 1.27)
				)
			)
		)
		(property "Value" ""
			(at 0 0 0)
			(layer "F.Fab")
			(effects
				(font
					(size 1.27 1.27)
				)
			)
		)
		(duplicate_pad_numbers_are_jumpers no)
		(fp_line
			(start -0.7874 -0.4064)
			(end 0.7874 -0.4064)
			(stroke
				(width 0.1524)
				(type default)
			)
			(layer "F.SilkS")
		)
		(fp_line
			(start -0.7874 0.4064)
			(end -0.7874 -0.4064)
			(stroke
				(width 0.1524)
				(type default)
			)
			(layer "F.SilkS")
		)
		(fp_line
			(start 0.7874 -0.4064)
			(end 0.7874 0.4064)
			(stroke
				(width 0.1524)
				(type default)
			)
			(layer "F.SilkS")
		)
		(fp_line
			(start 0.7874 0.4064)
			(end -0.7874 0.4064)
			(stroke
				(width 0.1524)
				(type default)
			)
			(layer "F.SilkS")
		)
		(fp_line
			(start -0.67945 -0.305054)
			(end -0.12065 -0.305054)
			(stroke
				(width 0.1)
				(type default)
			)
			(layer "F.Fab")
		)
		(fp_line
			(start -0.67945 0.3048)
			(end -0.67945 -0.305054)
			(stroke
				(width 0.1)
				(type default)
			)
			(layer "F.Fab")
		)
		(fp_line
			(start -0.12065 -0.305054)
			(end -0.12065 -0.2794)
			(stroke
				(width 0.1)
				(type default)
			)
			(layer "F.Fab")
		)
		(fp_line
			(start -0.12065 -0.2794)
			(end 0.12065 -0.2794)
			(stroke
				(width 0.1)
				(type default)
			)
			(layer "F.Fab")
		)
		(fp_line
			(start -0.12065 0.2794)
			(end -0.12065 0.3048)
			(stroke
				(width 0.1)
				(type default)
			)
			(layer "F.Fab")
		)
		(fp_line
			(start -0.12065 0.3048)
			(end -0.67945 0.3048)
			(stroke
				(width 0.1)
				(type default)
			)
			(layer "F.Fab")
		)
		(fp_line
			(start 0.120396 0.2794)
			(end -0.12065 0.2794)
			(stroke
				(width 0.1)
				(type default)
			)
			(layer "F.Fab")
		)
		(fp_line
			(start 0.120396 0.3048)
			(end 0.120396 0.2794)
			(stroke
				(width 0.1)
				(type default)
			)
			(layer "F.Fab")
		)
		(fp_line
			(start 0.12065 -0.3048)
			(end 0.67945 -0.3048)
			(stroke
				(width 0.1)
				(type default)
			)
			(layer "F.Fab")
		)
		(fp_line
			(start 0.12065 -0.2794)
			(end 0.12065 -0.3048)
			(stroke
				(width 0.1)
				(type default)
			)
			(layer "F.Fab")
		)
		(fp_line
			(start 0.67945 -0.3048)
			(end 0.67945 0.3048)
			(stroke
				(width 0.1)
				(type default)
			)
			(layer "F.Fab")
		)
		(fp_line
			(start 0.67945 0.3048)
			(end 0.120396 0.3048)
			(stroke
				(width 0.1)
				(type default)
			)
			(layer "F.Fab")
		)
		(pad "1" smd circle
			(at -0.40005 0)
			(size 0 0)
			(layers "F.Cu" "F.Mask" "F.Paste")
			(net "P3V3_AUX")
		)
		(pad "2" smd circle
			(at 0.40005 0)
			(size 0 0)
			(layers "F.Cu" "F.Mask" "F.Paste")
			(net "MB_FRU_ADDR0")
		)
	)
	(footprint ""
		(layer "F.Cu")
		(at 135.05688 -92.674948 -90)
		(property "Reference" "R4408"
			(at 0 0 270)
			(layer "F.SilkS")
			(hide yes)
			(effects
				(font
					(size 1.27 1.27)
				)
			)
		)
		(property "Value" ""
			(at 0 0 270)
			(layer "F.Fab")
			(effects
				(font
					(size 1.27 1.27)
				)
			)
		)
		(duplicate_pad_numbers_are_jumpers no)
		(fp_line
			(start -0.7874 0.4064)
			(end -0.7874 -0.4064)
			(stroke
				(width 0.1524)
				(type default)
			)
			(layer "F.SilkS")
		)
		(fp_line
			(start 0.7874 0.4064)
			(end -0.7874 0.4064)
			(stroke
				(width 0.1524)
				(type default)
			)
			(layer "F.SilkS")
		)
		(fp_line
			(start -0.7874 -0.4064)
			(end 0.7874 -0.4064)
			(stroke
				(width 0.1524)
				(type default)
			)
			(layer "F.SilkS")
		)
		(fp_line
			(start 0.7874 -0.4064)
			(end 0.7874 0.4064)
			(stroke
				(width 0.1524)
				(type default)
			)
			(layer "F.SilkS")
		)
		(fp_line
			(start -0.67945 0.3048)
			(end -0.67945 -0.305054)
			(stroke
				(width 0.1)
				(type default)
			)
			(layer "F.Fab")
		)
		(fp_line
			(start -0.12065 0.3048)
			(end -0.67945 0.3048)
			(stroke
				(width 0.1)
				(type default)
			)
			(layer "F.Fab")
		)
		(fp_line
			(start 0.120396 0.3048)
			(end 0.120396 0.2794)
			(stroke
				(width 0.1)
				(type default)
			)
			(layer "F.Fab")
		)
		(fp_line
			(start 0.67945 0.3048)
			(end 0.120396 0.3048)
			(stroke
				(width 0.1)
				(type default)
			)
			(layer "F.Fab")
		)
		(fp_line
			(start -0.12065 0.2794)
			(end -0.12065 0.3048)
			(stroke
				(width 0.1)
				(type default)
			)
			(layer "F.Fab")
		)
		(fp_line
			(start 0.120396 0.2794)
			(end -0.12065 0.2794)
			(stroke
				(width 0.1)
				(type default)
			)
			(layer "F.Fab")
		)
		(fp_line
			(start -0.12065 -0.2794)
			(end 0.12065 -0.2794)
			(stroke
				(width 0.1)
				(type default)
			)
			(layer "F.Fab")
		)
		(fp_line
			(start 0.12065 -0.2794)
			(end 0.12065 -0.3048)
			(stroke
				(width 0.1)
				(type default)
			)
			(layer "F.Fab")
		)
		(fp_line
			(start 0.12065 -0.3048)
			(end 0.67945 -0.3048)
			(stroke
				(width 0.1)
				(type default)
			)
			(layer "F.Fab")
		)
		(fp_line
			(start 0.67945 -0.3048)
			(end 0.67945 0.3048)
			(stroke
				(width 0.1)
				(type default)
			)
			(layer "F.Fab")
		)
		(fp_line
			(start -0.67945 -0.305054)
			(end -0.12065 -0.305054)
			(stroke
				(width 0.1)
				(type default)
			)
			(layer "F.Fab")
		)
		(fp_line
			(start -0.12065 -0.305054)
			(end -0.12065 -0.2794)
			(stroke
				(width 0.1)
				(type default)
			)
			(layer "F.Fab")
		)
		(pad "1" smd circle
			(at -0.40005 0 270)
			(size 0 0)
			(layers "F.Cu" "F.Mask" "F.Paste")
			(net "H_CPU1_MEMHOT_OUT_VT_N")
		)
		(pad "2" smd circle
			(at 0.40005 0 270)
			(size 0 0)
			(layers "F.Cu" "F.Mask" "F.Paste")
			(net "H_CPU1_MEMHOT_OUT_LVC1_N")
		)
	)
	(footprint ""
		(layer "F.Cu")
		(at 28.578048 -76.289916)
		(property "Reference" "C1809"
			(at 0 0 0)
			(layer "F.SilkS")
			(hide yes)
			(effects
				(font
					(size 1.27 1.27)
				)
			)
		)
		(property "Value" ""
			(at 0 0 0)
			(layer "F.Fab")
			(effects
				(font
					(size 1.27 1.27)
				)
			)
		)
		(duplicate_pad_numbers_are_jumpers no)
		(fp_line
			(start -0.7874 -0.4064)
			(end 0.7874 -0.4064)
			(stroke
				(width 0.1524)
				(type default)
			)
			(layer "F.SilkS")
		)
		(fp_line
			(start -0.7874 0.4064)
			(end -0.7874 -0.4064)
			(stroke
				(width 0.1524)
				(type default)
			)
			(layer "F.SilkS")
		)
		(fp_line
			(start 0.7874 -0.4064)
			(end 0.7874 0.4064)
			(stroke
				(width 0.1524)
				(type default)
			)
			(layer "F.SilkS")
		)
		(fp_line
			(start 0.7874 0.4064)
			(end -0.7874 0.4064)
			(stroke
				(width 0.1524)
				(type default)
			)
			(layer "F.SilkS")
		)
		(fp_line
			(start -0.67945 -0.305054)
			(end -0.12065 -0.305054)
			(stroke
				(width 0.1)
				(type default)
			)
			(layer "F.Fab")
		)
		(fp_line
			(start -0.67945 0.3048)
			(end -0.67945 -0.305054)
			(stroke
				(width 0.1)
				(type default)
			)
			(layer "F.Fab")
		)
		(fp_line
			(start -0.12065 -0.305054)
			(end -0.12065 -0.2794)
			(stroke
				(width 0.1)
				(type default)
			)
			(layer "F.Fab")
		)
		(fp_line
			(start -0.12065 -0.2794)
			(end 0.12065 -0.2794)
			(stroke
				(width 0.1)
				(type default)
			)
			(layer "F.Fab")
		)
		(fp_line
			(start -0.12065 0.2794)
			(end -0.12065 0.3048)
			(stroke
				(width 0.1)
				(type default)
			)
			(layer "F.Fab")
		)
		(fp_line
			(start -0.12065 0.3048)
			(end -0.67945 0.3048)
			(stroke
				(width 0.1)
				(type default)
			)
			(layer "F.Fab")
		)
		(fp_line
			(start 0.120396 0.2794)
			(end -0.12065 0.2794)
			(stroke
				(width 0.1)
				(type default)
			)
			(layer "F.Fab")
		)
		(fp_line
			(start 0.120396 0.3048)
			(end 0.120396 0.2794)
			(stroke
				(width 0.1)
				(type default)
			)
			(layer "F.Fab")
		)
		(fp_line
			(start 0.12065 -0.3048)
			(end 0.67945 -0.3048)
			(stroke
				(width 0.1)
				(type default)
			)
			(layer "F.Fab")
		)
		(fp_line
			(start 0.12065 -0.2794)
			(end 0.12065 -0.3048)
			(stroke
				(width 0.1)
				(type default)
			)
			(layer "F.Fab")
		)
		(fp_line
			(start 0.67945 -0.3048)
			(end 0.67945 0.3048)
			(stroke
				(width 0.1)
				(type default)
			)
			(layer "F.Fab")
		)
		(fp_line
			(start 0.67945 0.3048)
			(end 0.120396 0.3048)
			(stroke
				(width 0.1)
				(type default)
			)
			(layer "F.Fab")
		)
		(pad "1" smd circle
			(at -0.40005 0)
			(size 0 0)
			(layers "F.Cu" "F.Mask" "F.Paste")
			(net "P3V3_AUX")
		)
		(pad "2" smd circle
			(at 0.40005 0)
			(size 0 0)
			(layers "F.Cu" "F.Mask" "F.Paste")
			(net "GND")
		)
	)
	(footprint ""
		(layer "F.Cu")
		(at 256.47269 -39.482522 90)
		(property "Reference" "PC2214"
			(at 0 0 90)
			(layer "F.SilkS")
			(hide yes)
			(effects
				(font
					(size 1.27 1.27)
				)
			)
		)
		(property "Value" ""
			(at 0 0 90)
			(layer "F.Fab")
			(effects
				(font
					(size 1.27 1.27)
				)
			)
		)
		(duplicate_pad_numbers_are_jumpers no)
		(fp_line
			(start 0.7874 -0.4064)
			(end 0.7874 0.4064)
			(stroke
				(width 0.1524)
				(type default)
			)
			(layer "F.SilkS")
		)
		(fp_line
			(start -0.7874 -0.4064)
			(end 0.7874 -0.4064)
			(stroke
				(width 0.1524)
				(type default)
			)
			(layer "F.SilkS")
		)
		(fp_line
			(start 0.7874 0.4064)
			(end -0.7874 0.4064)
			(stroke
				(width 0.1524)
				(type default)
			)
			(layer "F.SilkS")
		)
		(fp_line
			(start -0.7874 0.4064)
			(end -0.7874 -0.4064)
			(stroke
				(width 0.1524)
				(type default)
			)
			(layer "F.SilkS")
		)
		(fp_line
			(start -0.12065 -0.305054)
			(end -0.12065 -0.2794)
			(stroke
				(width 0.1)
				(type default)
			)
			(layer "F.Fab")
		)
		(fp_line
			(start -0.67945 -0.305054)
			(end -0.12065 -0.305054)
			(stroke
				(width 0.1)
				(type default)
			)
			(layer "F.Fab")
		)
		(fp_line
			(start 0.67945 -0.3048)
			(end 0.67945 0.3048)
			(stroke
				(width 0.1)
				(type default)
			)
			(layer "F.Fab")
		)
		(fp_line
			(start 0.12065 -0.3048)
			(end 0.67945 -0.3048)
			(stroke
				(width 0.1)
				(type default)
			)
			(layer "F.Fab")
		)
		(fp_line
			(start 0.12065 -0.2794)
			(end 0.12065 -0.3048)
			(stroke
				(width 0.1)
				(type default)
			)
			(layer "F.Fab")
		)
		(fp_line
			(start -0.12065 -0.2794)
			(end 0.12065 -0.2794)
			(stroke
				(width 0.1)
				(type default)
			)
			(layer "F.Fab")
		)
		(fp_line
			(start 0.120396 0.2794)
			(end -0.12065 0.2794)
			(stroke
				(width 0.1)
				(type default)
			)
			(layer "F.Fab")
		)
		(fp_line
			(start -0.12065 0.2794)
			(end -0.12065 0.3048)
			(stroke
				(width 0.1)
				(type default)
			)
			(layer "F.Fab")
		)
		(fp_line
			(start 0.67945 0.3048)
			(end 0.120396 0.3048)
			(stroke
				(width 0.1)
				(type default)
			)
			(layer "F.Fab")
		)
		(fp_line
			(start 0.120396 0.3048)
			(end 0.120396 0.2794)
			(stroke
				(width 0.1)
				(type default)
			)
			(layer "F.Fab")
		)
		(fp_line
			(start -0.12065 0.3048)
			(end -0.67945 0.3048)
			(stroke
				(width 0.1)
				(type default)
			)
			(layer "F.Fab")
		)
		(fp_line
			(start -0.67945 0.3048)
			(end -0.67945 -0.305054)
			(stroke
				(width 0.1)
				(type default)
			)
			(layer "F.Fab")
		)
		(pad "1" smd circle
			(at -0.40005 0 90)
			(size 0 0)
			(layers "F.Cu" "F.Mask" "F.Paste")
			(net "P12V_E1S_0")
		)
		(pad "2" smd circle
			(at 0.40005 0 90)
			(size 0 0)
			(layers "F.Cu" "F.Mask" "F.Paste")
			(net "P12V_E1S_GATE_0")
		)
	)
	(footprint ""
		(layer "F.Cu")
		(at 366.3696 -409.194 180)
		(property "Reference" "R4738"
			(at 0 0 180)
			(layer "F.SilkS")
			(hide yes)
			(effects
				(font
					(size 1.27 1.27)
				)
			)
		)
		(property "Value" ""
			(at 0 0 180)
			(layer "F.Fab")
			(effects
				(font
					(size 1.27 1.27)
				)
			)
		)
		(duplicate_pad_numbers_are_jumpers no)
		(fp_line
			(start 0.7874 0.4064)
			(end -0.7874 0.4064)
			(stroke
				(width 0.1524)
				(type default)
			)
			(layer "F.SilkS")
		)
		(fp_line
			(start 0.7874 -0.4064)
			(end 0.7874 0.4064)
			(stroke
				(width 0.1524)
				(type default)
			)
			(layer "F.SilkS")
		)
		(fp_line
			(start -0.7874 0.4064)
			(end -0.7874 -0.4064)
			(stroke
				(width 0.1524)
				(type default)
			)
			(layer "F.SilkS")
		)
		(fp_line
			(start -0.7874 -0.4064)
			(end 0.7874 -0.4064)
			(stroke
				(width 0.1524)
				(type default)
			)
			(layer "F.SilkS")
		)
		(fp_line
			(start 0.67945 0.3048)
			(end 0.120396 0.3048)
			(stroke
				(width 0.1)
				(type default)
			)
			(layer "F.Fab")
		)
		(fp_line
			(start 0.67945 -0.3048)
			(end 0.67945 0.3048)
			(stroke
				(width 0.1)
				(type default)
			)
			(layer "F.Fab")
		)
		(fp_line
			(start 0.12065 -0.2794)
			(end 0.12065 -0.3048)
			(stroke
				(width 0.1)
				(type default)
			)
			(layer "F.Fab")
		)
		(fp_line
			(start 0.12065 -0.3048)
			(end 0.67945 -0.3048)
			(stroke
				(width 0.1)
				(type default)
			)
			(layer "F.Fab")
		)
		(fp_line
			(start 0.120396 0.3048)
			(end 0.120396 0.2794)
			(stroke
				(width 0.1)
				(type default)
			)
			(layer "F.Fab")
		)
		(fp_line
			(start 0.120396 0.2794)
			(end -0.12065 0.2794)
			(stroke
				(width 0.1)
				(type default)
			)
			(layer "F.Fab")
		)
		(fp_line
			(start -0.12065 0.3048)
			(end -0.67945 0.3048)
			(stroke
				(width 0.1)
				(type default)
			)
			(layer "F.Fab")
		)
		(fp_line
			(start -0.12065 0.2794)
			(end -0.12065 0.3048)
			(stroke
				(width 0.1)
				(type default)
			)
			(layer "F.Fab")
		)
		(fp_line
			(start -0.12065 -0.2794)
			(end 0.12065 -0.2794)
			(stroke
				(width 0.1)
				(type default)
			)
			(layer "F.Fab")
		)
		(fp_line
			(start -0.12065 -0.305054)
			(end -0.12065 -0.2794)
			(stroke
				(width 0.1)
				(type default)
			)
			(layer "F.Fab")
		)
		(fp_line
			(start -0.67945 0.3048)
			(end -0.67945 -0.305054)
			(stroke
				(width 0.1)
				(type default)
			)
			(layer "F.Fab")
		)
		(fp_line
			(start -0.67945 -0.305054)
			(end -0.12065 -0.305054)
			(stroke
				(width 0.1)
				(type default)
			)
			(layer "F.Fab")
		)
		(pad "1" smd circle
			(at -0.40005 0 180)
			(size 0 0)
			(layers "F.Cu" "F.Mask" "F.Paste")
			(net "PRSNT_CABLE_SWB_B1_N")
		)
		(pad "2" smd circle
			(at 0.40005 0 180)
			(size 0 0)
			(layers "F.Cu" "F.Mask" "F.Paste")
			(net "GND")
		)
	)
	(footprint ""
		(layer "F.Cu")
		(at 454.066148 -258.091686)
		(property "Reference" "J16"
			(at -0.279908 -81.779872 0)
			(unlocked yes)
			(layer "F.SilkS")
			(effects
				(font
					(size 0.7874 0.5842)
					(thickness 0.1524)
				)
				(justify left)
			)
		)
		(property "Value" ""
			(at 0 0 0)
			(layer "F.Fab")
			(effects
				(font
					(size 1.27 1.27)
				)
			)
		)
		(duplicate_pad_numbers_are_jumpers no)
		(fp_line
			(start -3.24993 -79.248762)
			(end -3.24993 -75.578462)
			(stroke
				(width 0.1524)
				(type default)
			)
			(layer "F.SilkS")
		)
		(fp_line
			(start -3.24993 -72.837802)
			(end -3.24993 81.000092)
			(stroke
				(width 0.1524)
				(type default)
			)
			(layer "F.SilkS")
		)
		(fp_line
			(start -3.24993 81.000092)
			(end 3.24993 81.000092)
			(stroke
				(width 0.1524)
				(type default)
			)
			(layer "F.SilkS")
		)
		(fp_line
			(start 3.24993 -81.000092)
			(end -2.162048 -81.000092)
			(stroke
				(width 0.1524)
				(type default)
			)
			(layer "F.SilkS")
		)
		(fp_line
			(start 3.24993 -72.00011)
			(end -3.24993 -72.00011)
			(stroke
				(width 0.1524)
				(type default)
			)
			(layer "F.SilkS")
		)
		(fp_line
			(start 3.24993 72.00011)
			(end -3.24993 72.00011)
			(stroke
				(width 0.1524)
				(type default)
			)
			(layer "F.SilkS")
		)
		(fp_line
			(start 3.24993 81.000092)
			(end 3.24993 -81.000092)
			(stroke
				(width 0.1524)
				(type default)
			)
			(layer "F.SilkS")
		)
		(fp_poly
			(pts
				(xy -4.165092 -63.746126) (xy -3.332988 -63.330074) (xy -4.165092 -62.914022)
			)
			(stroke
				(width 0)
				(type default)
			)
			(fill yes)
			(layer "F.SilkS")
		)
		(fp_line
			(start -3.24993 -81.000092)
			(end -3.24993 81.000092)
			(stroke
				(width 0.1)
				(type default)
			)
			(layer "F.Fab")
		)
		(fp_line
			(start -3.24993 81.000092)
			(end 3.24993 81.000092)
			(stroke
				(width 0.1)
				(type default)
			)
			(layer "F.Fab")
		)
		(fp_line
			(start 3.24993 -81.000092)
			(end -3.24993 -81.000092)
			(stroke
				(width 0.1)
				(type default)
			)
			(layer "F.Fab")
		)
		(fp_line
			(start 3.24993 -72.00011)
			(end -3.24993 -72.00011)
			(stroke
				(width 0.1)
				(type default)
			)
			(layer "F.Fab")
		)
		(fp_line
			(start 3.24993 -71.000112)
			(end -3.24993 -71.000112)
			(stroke
				(width 0.1)
				(type default)
			)
			(layer "F.Fab")
		)
		(fp_line
			(start 3.24993 71.000112)
			(end -3.24993 71.000112)
			(stroke
				(width 0.1)
				(type default)
			)
			(layer "F.Fab")
		)
		(fp_line
			(start 3.24993 72.00011)
			(end -3.24993 72.00011)
			(stroke
				(width 0.1)
				(type default)
			)
			(layer "F.Fab")
		)
		(fp_line
			(start 3.24993 81.000092)
			(end 3.24993 -81.000092)
			(stroke
				(width 0.1)
				(type default)
			)
			(layer "F.Fab")
		)
		(fp_poly
			(pts
				(xy -4.445 -63.832994) (xy -4.445 -62.816994) (xy -3.429 -63.324994)
			)
			(stroke
				(width 0)
				(type default)
			)
			(fill yes)
			(layer "F.Fab")
		)
		(pad "1" smd rect
			(at -2.050034 -63.324994 270)
			(size 0.519938 1.4986)
			(layers "F.Cu" "F.Mask" "F.Paste")
			(net "P12V_S3_AUX_CPU0_NVDIMM")
		)
		(pad "2" smd rect
			(at -2.050034 -62.47511 270)
			(size 0.519938 1.4986)
			(layers "F.Cu" "F.Mask" "F.Paste")
			(net "TP_CHH_CPU0_DIMM2_FRU_0")
		)
		(pad "3" smd rect
			(at -2.050034 -61.624972 270)
			(size 0.519938 1.4986)
			(layers "F.Cu" "F.Mask" "F.Paste")
			(net "P3V3_AUX")
		)
		(pad "4" smd rect
			(at -2.050034 -60.775088 270)
			(size 0.519938 1.4986)
			(layers "F.Cu" "F.Mask" "F.Paste")
			(net "I3C_SPD_DDREFGH_CPU0_LVC1_SCL_7")
		)
		(pad "5" smd rect
			(at -2.050034 -59.92495 270)
			(size 0.519938 1.4986)
			(layers "F.Cu" "F.Mask" "F.Paste")
			(net "I3C_SPD_DDREFGH_CPU0_LVC1_SDA")
		)
		(pad "6" smd rect
			(at -2.050034 -59.075066 270)
			(size 0.519938 1.4986)
			(layers "F.Cu" "F.Mask" "F.Paste")
			(net "GND")
		)
		(pad "7" smd rect
			(at -2.050034 -58.224928 270)
			(size 0.519938 1.4986)
			(layers "F.Cu" "F.Mask" "F.Paste")
			(net "M_H_CPU0_SA_DQ<0>")
		)
		(pad "8" smd rect
			(at -2.050034 -57.375044 270)
			(size 0.519938 1.4986)
			(layers "F.Cu" "F.Mask" "F.Paste")
			(net "GND")
		)
		(pad "9" smd rect
			(at -2.050034 -56.524906 270)
			(size 0.519938 1.4986)
			(layers "F.Cu" "F.Mask" "F.Paste")
			(net "M_H_CPU0_SA_DQ<1>")
		)
		(pad "10" smd rect
			(at -2.050034 -55.675022 270)
			(size 0.519938 1.4986)
			(layers "F.Cu" "F.Mask" "F.Paste")
			(net "GND")
		)
		(pad "11" smd rect
			(at -2.050034 -54.824884 270)
			(size 0.519938 1.4986)
			(layers "F.Cu" "F.Mask" "F.Paste")
			(net "M_H_CPU0_SA_DQS_DP<0>")
		)
		(pad "12" smd rect
			(at -2.050034 -53.975 270)
			(size 0.519938 1.4986)
			(layers "F.Cu" "F.Mask" "F.Paste")
			(net "M_H_CPU0_SA_DQS_DN<0>")
		)
		(pad "13" smd rect
			(at -2.050034 -53.125116 270)
			(size 0.519938 1.4986)
			(layers "F.Cu" "F.Mask" "F.Paste")
			(net "GND")
		)
		(pad "14" smd rect
			(at -2.050034 -52.274978 270)
			(size 0.519938 1.4986)
			(layers "F.Cu" "F.Mask" "F.Paste")
			(net "M_H_CPU0_SA_DQ<4>")
		)
		(pad "15" smd rect
			(at -2.050034 -51.425094 270)
			(size 0.519938 1.4986)
			(layers "F.Cu" "F.Mask" "F.Paste")
			(net "GND")
		)
		(pad "16" smd rect
			(at -2.050034 -50.574956 270)
			(size 0.519938 1.4986)
			(layers "F.Cu" "F.Mask" "F.Paste")
			(net "M_H_CPU0_SA_DQ<5>")
		)
		(pad "17" smd rect
			(at -2.050034 -49.725072 270)
			(size 0.519938 1.4986)
			(layers "F.Cu" "F.Mask" "F.Paste")
			(net "GND")
		)
		(pad "18" smd rect
			(at -2.050034 -48.874934 270)
			(size 0.519938 1.4986)
			(layers "F.Cu" "F.Mask" "F.Paste")
			(net "M_H_CPU0_SA_DQ<8>")
		)
		(pad "19" smd rect
			(at -2.050034 -48.02505 270)
			(size 0.519938 1.4986)
			(layers "F.Cu" "F.Mask" "F.Paste")
			(net "GND")
		)
		(pad "20" smd rect
			(at -2.050034 -47.174912 270)
			(size 0.519938 1.4986)
			(layers "F.Cu" "F.Mask" "F.Paste")
			(net "M_H_CPU0_SA_DQ<9>")
		)
		(pad "21" smd rect
			(at -2.050034 -46.325028 270)
			(size 0.519938 1.4986)
			(layers "F.Cu" "F.Mask" "F.Paste")
			(net "GND")
		)
		(pad "22" smd rect
			(at -2.050034 -45.47489 270)
			(size 0.519938 1.4986)
			(layers "F.Cu" "F.Mask" "F.Paste")
			(net "M_H_CPU0_SA_DQS_DP<1>")
		)
		(pad "23" smd rect
			(at -2.050034 -44.625006 270)
			(size 0.519938 1.4986)
			(layers "F.Cu" "F.Mask" "F.Paste")
			(net "M_H_CPU0_SA_DQS_DN<1>")
		)
		(pad "24" smd rect
			(at -2.050034 -43.775122 270)
			(size 0.519938 1.4986)
			(layers "F.Cu" "F.Mask" "F.Paste")
			(net "GND")
		)
		(pad "25" smd rect
			(at -2.050034 -42.924984 270)
			(size 0.519938 1.4986)
			(layers "F.Cu" "F.Mask" "F.Paste")
			(net "M_H_CPU0_SA_DQ<12>")
		)
		(pad "26" smd rect
			(at -2.050034 -42.0751 270)
			(size 0.519938 1.4986)
			(layers "F.Cu" "F.Mask" "F.Paste")
			(net "GND")
		)
		(pad "27" smd rect
			(at -2.050034 -41.224962 270)
			(size 0.519938 1.4986)
			(layers "F.Cu" "F.Mask" "F.Paste")
			(net "M_H_CPU0_SA_DQ<13>")
		)
		(pad "28" smd rect
			(at -2.050034 -40.375078 270)
			(size 0.519938 1.4986)
			(layers "F.Cu" "F.Mask" "F.Paste")
			(net "GND")
		)
		(pad "29" smd rect
			(at -2.050034 -39.52494 270)
			(size 0.519938 1.4986)
			(layers "F.Cu" "F.Mask" "F.Paste")
			(net "M_H_CPU0_SA_DQ<16>")
		)
		(pad "30" smd rect
			(at -2.050034 -38.675056 270)
			(size 0.519938 1.4986)
			(layers "F.Cu" "F.Mask" "F.Paste")
			(net "GND")
		)
		(pad "31" smd rect
			(at -2.050034 -37.824918 270)
			(size 0.519938 1.4986)
			(layers "F.Cu" "F.Mask" "F.Paste")
			(net "M_H_CPU0_SA_DQ<17>")
		)
		(pad "32" smd rect
			(at -2.050034 -36.975034 270)
			(size 0.519938 1.4986)
			(layers "F.Cu" "F.Mask" "F.Paste")
			(net "GND")
		)
		(pad "33" smd rect
			(at -2.050034 -36.124896 270)
			(size 0.519938 1.4986)
			(layers "F.Cu" "F.Mask" "F.Paste")
			(net "M_H_CPU0_SA_DQS_DP<2>")
		)
		(pad "34" smd rect
			(at -2.050034 -35.275012 270)
			(size 0.519938 1.4986)
			(layers "F.Cu" "F.Mask" "F.Paste")
			(net "M_H_CPU0_SA_DQS_DN<2>")
		)
		(pad "35" smd rect
			(at -2.050034 -34.425128 270)
			(size 0.519938 1.4986)
			(layers "F.Cu" "F.Mask" "F.Paste")
			(net "GND")
		)
		(pad "36" smd rect
			(at -2.050034 -33.57499 270)
			(size 0.519938 1.4986)
			(layers "F.Cu" "F.Mask" "F.Paste")
			(net "M_H_CPU0_SA_DQ<20>")
		)
		(pad "37" smd rect
			(at -2.050034 -32.725106 270)
			(size 0.519938 1.4986)
			(layers "F.Cu" "F.Mask" "F.Paste")
			(net "GND")
		)
		(pad "38" smd rect
			(at -2.050034 -31.874968 270)
			(size 0.519938 1.4986)
			(layers "F.Cu" "F.Mask" "F.Paste")
			(net "M_H_CPU0_SA_DQ<21>")
		)
		(pad "39" smd rect
			(at -2.050034 -31.025084 270)
			(size 0.519938 1.4986)
			(layers "F.Cu" "F.Mask" "F.Paste")
			(net "GND")
		)
		(pad "40" smd rect
			(at -2.050034 -30.174946 270)
			(size 0.519938 1.4986)
			(layers "F.Cu" "F.Mask" "F.Paste")
			(net "M_H_CPU0_SA_DQ<24>")
		)
		(pad "41" smd rect
			(at -2.050034 -29.325062 270)
			(size 0.519938 1.4986)
			(layers "F.Cu" "F.Mask" "F.Paste")
			(net "GND")
		)
		(pad "42" smd rect
			(at -2.050034 -28.474924 270)
			(size 0.519938 1.4986)
			(layers "F.Cu" "F.Mask" "F.Paste")
			(net "M_H_CPU0_SA_DQ<25>")
		)
		(pad "43" smd rect
			(at -2.050034 -27.62504 270)
			(size 0.519938 1.4986)
			(layers "F.Cu" "F.Mask" "F.Paste")
			(net "GND")
		)
		(pad "44" smd rect
			(at -2.050034 -26.774902 270)
			(size 0.519938 1.4986)
			(layers "F.Cu" "F.Mask" "F.Paste")
			(net "M_H_CPU0_SA_DQS_DP<3>")
		)
		(pad "45" smd rect
			(at -2.050034 -25.925018 270)
			(size 0.519938 1.4986)
			(layers "F.Cu" "F.Mask" "F.Paste")
			(net "M_H_CPU0_SA_DQS_DN<3>")
		)
		(pad "46" smd rect
			(at -2.050034 -25.07488 270)
			(size 0.519938 1.4986)
			(layers "F.Cu" "F.Mask" "F.Paste")
			(net "GND")
		)
		(pad "47" smd rect
			(at -2.050034 -24.224996 270)
			(size 0.519938 1.4986)
			(layers "F.Cu" "F.Mask" "F.Paste")
			(net "M_H_CPU0_SA_DQ<28>")
		)
		(pad "48" smd rect
			(at -2.050034 -23.375112 270)
			(size 0.519938 1.4986)
			(layers "F.Cu" "F.Mask" "F.Paste")
			(net "GND")
		)
		(pad "49" smd rect
			(at -2.050034 -22.524974 270)
			(size 0.519938 1.4986)
			(layers "F.Cu" "F.Mask" "F.Paste")
			(net "M_H_CPU0_SA_DQ<29>")
		)
		(pad "50" smd rect
			(at -2.050034 -21.67509 270)
			(size 0.519938 1.4986)
			(layers "F.Cu" "F.Mask" "F.Paste")
			(net "GND")
		)
		(pad "51" smd rect
			(at -2.050034 -20.824952 270)
			(size 0.519938 1.4986)
			(layers "F.Cu" "F.Mask" "F.Paste")
			(net "M_H_CPU0_SA_CB<0>")
		)
		(pad "52" smd rect
			(at -2.050034 -19.975068 270)
			(size 0.519938 1.4986)
			(layers "F.Cu" "F.Mask" "F.Paste")
			(net "GND")
		)
		(pad "53" smd rect
			(at -2.050034 -19.12493 270)
			(size 0.519938 1.4986)
			(layers "F.Cu" "F.Mask" "F.Paste")
			(net "M_H_CPU0_SA_CB<1>")
		)
		(pad "54" smd rect
			(at -2.050034 -18.275046 270)
			(size 0.519938 1.4986)
			(layers "F.Cu" "F.Mask" "F.Paste")
			(net "GND")
		)
		(pad "55" smd rect
			(at -2.050034 -17.424908 270)
			(size 0.519938 1.4986)
			(layers "F.Cu" "F.Mask" "F.Paste")
			(net "M_H_CPU0_SA_DQS_DP<4>")
		)
		(pad "56" smd rect
			(at -2.050034 -16.575024 270)
			(size 0.519938 1.4986)
			(layers "F.Cu" "F.Mask" "F.Paste")
			(net "M_H_CPU0_SA_DQS_DN<4>")
		)
		(pad "57" smd rect
			(at -2.050034 -15.724886 270)
			(size 0.519938 1.4986)
			(layers "F.Cu" "F.Mask" "F.Paste")
			(net "GND")
		)
		(pad "58" smd rect
			(at -2.050034 -14.875002 270)
			(size 0.519938 1.4986)
			(layers "F.Cu" "F.Mask" "F.Paste")
			(net "M_H_CPU0_SA_CB<4>")
		)
		(pad "59" smd rect
			(at -2.050034 -14.025118 270)
			(size 0.519938 1.4986)
			(layers "F.Cu" "F.Mask" "F.Paste")
			(net "GND")
		)
		(pad "60" smd rect
			(at -2.050034 -13.17498 270)
			(size 0.519938 1.4986)
			(layers "F.Cu" "F.Mask" "F.Paste")
			(net "M_H_CPU0_SA_CB<5>")
		)
		(pad "61" smd rect
			(at -2.050034 -12.325096 270)
			(size 0.519938 1.4986)
			(layers "F.Cu" "F.Mask" "F.Paste")
			(net "GND")
		)
		(pad "62" smd rect
			(at -2.050034 -11.474958 270)
			(size 0.519938 1.4986)
			(layers "F.Cu" "F.Mask" "F.Paste")
			(net "M_H_CPU0_ALERT_N")
		)
		(pad "63" smd rect
			(at -2.050034 -10.625074 270)
			(size 0.519938 1.4986)
			(layers "F.Cu" "F.Mask" "F.Paste")
			(net "GND")
		)
		(pad "64" smd rect
			(at -2.050034 -9.774936 270)
			(size 0.519938 1.4986)
			(layers "F.Cu" "F.Mask" "F.Paste")
			(net "M_H_CPU0_SA_CS_N<2>")
		)
		(pad "65" smd rect
			(at -2.050034 -8.925052 270)
			(size 0.519938 1.4986)
			(layers "F.Cu" "F.Mask" "F.Paste")
			(net "GND")
		)
		(pad "66" smd rect
			(at -2.050034 -8.074914 270)
			(size 0.519938 1.4986)
			(layers "F.Cu" "F.Mask" "F.Paste")
			(net "M_H_CPU0_SA_CA<0>")
		)
		(pad "67" smd rect
			(at -2.050034 -7.22503 270)
			(size 0.519938 1.4986)
			(layers "F.Cu" "F.Mask" "F.Paste")
			(net "GND")
		)
		(pad "68" smd rect
			(at -2.050034 -6.374892 270)
			(size 0.519938 1.4986)
			(layers "F.Cu" "F.Mask" "F.Paste")
			(net "M_H_CPU0_SA_CA<2>")
		)
		(pad "69" smd rect
			(at -2.050034 -5.525008 270)
			(size 0.519938 1.4986)
			(layers "F.Cu" "F.Mask" "F.Paste")
			(net "GND")
		)
		(pad "70" smd rect
			(at -2.050034 -4.675124 270)
			(size 0.519938 1.4986)
			(layers "F.Cu" "F.Mask" "F.Paste")
			(net "M_H_CPU0_SA_CA<4>")
		)
		(pad "71" smd rect
			(at -2.050034 -3.824986 270)
			(size 0.519938 1.4986)
			(layers "F.Cu" "F.Mask" "F.Paste")
			(net "GND")
		)
		(pad "72" smd rect
			(at -2.050034 -2.975102 270)
			(size 0.519938 1.4986)
			(layers "F.Cu" "F.Mask" "F.Paste")
			(net "M_H_CPU0_SA_CA<6>")
		)
		(pad "73" smd rect
			(at -2.050034 -2.124964 270)
			(size 0.519938 1.4986)
			(layers "F.Cu" "F.Mask" "F.Paste")
			(net "GND")
		)
		(pad "74" smd rect
			(at -2.050034 -1.27508 270)
			(size 0.519938 1.4986)
			(layers "F.Cu" "F.Mask" "F.Paste")
			(net "M_H_CPU0_SA_PAR")
		)
		(pad "75" smd rect
			(at -2.050034 -0.424942 270)
			(size 0.519938 1.4986)
			(layers "F.Cu" "F.Mask" "F.Paste")
			(net "GND")
		)
		(pad "76" smd rect
			(at -2.050034 5.525008 270)
			(size 0.519938 1.4986)
			(layers "F.Cu" "F.Mask" "F.Paste")
			(net "M_H_CPU0_SB_CA<0>")
		)
		(pad "77" smd rect
			(at -2.050034 6.374892 270)
			(size 0.519938 1.4986)
			(layers "F.Cu" "F.Mask" "F.Paste")
			(net "GND")
		)
		(pad "78" smd rect
			(at -2.050034 7.22503 270)
			(size 0.519938 1.4986)
			(layers "F.Cu" "F.Mask" "F.Paste")
			(net "M_H_CPU0_SB_CA<2>")
		)
		(pad "79" smd rect
			(at -2.050034 8.074914 270)
			(size 0.519938 1.4986)
			(layers "F.Cu" "F.Mask" "F.Paste")
			(net "GND")
		)
		(pad "80" smd rect
			(at -2.050034 8.925052 270)
			(size 0.519938 1.4986)
			(layers "F.Cu" "F.Mask" "F.Paste")
			(net "M_H_CPU0_SB_CA<4>")
		)
		(pad "81" smd rect
			(at -2.050034 9.774936 270)
			(size 0.519938 1.4986)
			(layers "F.Cu" "F.Mask" "F.Paste")
			(net "GND")
		)
		(pad "82" smd rect
			(at -2.050034 10.625074 270)
			(size 0.519938 1.4986)
			(layers "F.Cu" "F.Mask" "F.Paste")
			(net "M_H_CPU0_SB_CA<6>")
		)
		(pad "83" smd rect
			(at -2.050034 11.474958 270)
			(size 0.519938 1.4986)
			(layers "F.Cu" "F.Mask" "F.Paste")
			(net "GND")
		)
		(pad "84" smd rect
			(at -2.050034 12.325096 270)
			(size 0.519938 1.4986)
			(layers "F.Cu" "F.Mask" "F.Paste")
			(net "M_H_CPU0_SB_CS_N<2>")
		)
		(pad "85" smd rect
			(at -2.050034 13.17498 270)
			(size 0.519938 1.4986)
			(layers "F.Cu" "F.Mask" "F.Paste")
			(net "GND")
		)
		(pad "86" smd rect
			(at -2.050034 14.025118 270)
			(size 0.519938 1.4986)
			(layers "F.Cu" "F.Mask" "F.Paste")
			(net "M_H_CPU0_SA_RSP<1>")
		)
		(pad "87" smd rect
			(at -2.050034 14.875002 270)
			(size 0.519938 1.4986)
			(layers "F.Cu" "F.Mask" "F.Paste")
			(net "M_H_CPU0_SB_RSP<1>")
		)
		(pad "88" smd rect
			(at -2.050034 15.724886 270)
			(size 0.519938 1.4986)
			(layers "F.Cu" "F.Mask" "F.Paste")
			(net "GND")
		)
		(pad "89" smd rect
			(at -2.050034 16.575024 270)
			(size 0.519938 1.4986)
			(layers "F.Cu" "F.Mask" "F.Paste")
			(net "M_H_CPU0_SB_CB<4>")
		)
		(pad "90" smd rect
			(at -2.050034 17.424908 270)
			(size 0.519938 1.4986)
			(layers "F.Cu" "F.Mask" "F.Paste")
			(net "GND")
		)
		(pad "91" smd rect
			(at -2.050034 18.275046 270)
			(size 0.519938 1.4986)
			(layers "F.Cu" "F.Mask" "F.Paste")
			(net "M_H_CPU0_SB_CB<5>")
		)
		(pad "92" smd rect
			(at -2.050034 19.12493 270)
			(size 0.519938 1.4986)
			(layers "F.Cu" "F.Mask" "F.Paste")
			(net "GND")
		)
		(pad "93" smd rect
			(at -2.050034 19.975068 270)
			(size 0.519938 1.4986)
			(layers "F.Cu" "F.Mask" "F.Paste")
			(net "M_H_CPU0_SB_DQS_DP<9>")
		)
		(pad "94" smd rect
			(at -2.050034 20.824952 270)
			(size 0.519938 1.4986)
			(layers "F.Cu" "F.Mask" "F.Paste")
			(net "M_H_CPU0_SB_DQS_DN<9>")
		)
		(pad "95" smd rect
			(at -2.050034 21.67509 270)
			(size 0.519938 1.4986)
			(layers "F.Cu" "F.Mask" "F.Paste")
			(net "GND")
		)
		(pad "96" smd rect
			(at -2.050034 22.524974 270)
			(size 0.519938 1.4986)
			(layers "F.Cu" "F.Mask" "F.Paste")
			(net "M_H_CPU0_SB_CB<0>")
		)
		(pad "97" smd rect
			(at -2.050034 23.375112 270)
			(size 0.519938 1.4986)
			(layers "F.Cu" "F.Mask" "F.Paste")
			(net "GND")
		)
		(pad "98" smd rect
			(at -2.050034 24.224996 270)
			(size 0.519938 1.4986)
			(layers "F.Cu" "F.Mask" "F.Paste")
			(net "M_H_CPU0_SB_CB<1>")
		)
		(pad "99" smd rect
			(at -2.050034 25.07488 270)
			(size 0.519938 1.4986)
			(layers "F.Cu" "F.Mask" "F.Paste")
			(net "GND")
		)
		(pad "100" smd rect
			(at -2.050034 25.925018 270)
			(size 0.519938 1.4986)
			(layers "F.Cu" "F.Mask" "F.Paste")
			(net "M_H_CPU0_SB_DQ<0>")
		)
		(pad "101" smd rect
			(at -2.050034 26.774902 270)
			(size 0.519938 1.4986)
			(layers "F.Cu" "F.Mask" "F.Paste")
			(net "GND")
		)
		(pad "102" smd rect
			(at -2.050034 27.62504 270)
			(size 0.519938 1.4986)
			(layers "F.Cu" "F.Mask" "F.Paste")
			(net "M_H_CPU0_SB_DQ<1>")
		)
		(pad "103" smd rect
			(at -2.050034 28.474924 270)
			(size 0.519938 1.4986)
			(layers "F.Cu" "F.Mask" "F.Paste")
			(net "GND")
		)
		(pad "104" smd rect
			(at -2.050034 29.325062 270)
			(size 0.519938 1.4986)
			(layers "F.Cu" "F.Mask" "F.Paste")
			(net "M_H_CPU0_SB_DQS_DP<0>")
		)
		(pad "105" smd rect
			(at -2.050034 30.174946 270)
			(size 0.519938 1.4986)
			(layers "F.Cu" "F.Mask" "F.Paste")
			(net "M_H_CPU0_SB_DQS_DN<0>")
		)
		(pad "106" smd rect
			(at -2.050034 31.025084 270)
			(size 0.519938 1.4986)
			(layers "F.Cu" "F.Mask" "F.Paste")
			(net "GND")
		)
		(pad "107" smd rect
			(at -2.050034 31.874968 270)
			(size 0.519938 1.4986)
			(layers "F.Cu" "F.Mask" "F.Paste")
			(net "M_H_CPU0_SB_DQ<4>")
		)
		(pad "108" smd rect
			(at -2.050034 32.725106 270)
			(size 0.519938 1.4986)
			(layers "F.Cu" "F.Mask" "F.Paste")
			(net "GND")
		)
		(pad "109" smd rect
			(at -2.050034 33.57499 270)
			(size 0.519938 1.4986)
			(layers "F.Cu" "F.Mask" "F.Paste")
			(net "M_H_CPU0_SB_DQ<5>")
		)
		(pad "110" smd rect
			(at -2.050034 34.425128 270)
			(size 0.519938 1.4986)
			(layers "F.Cu" "F.Mask" "F.Paste")
			(net "GND")
		)
		(pad "111" smd rect
			(at -2.050034 35.275012 270)
			(size 0.519938 1.4986)
			(layers "F.Cu" "F.Mask" "F.Paste")
			(net "M_H_CPU0_SB_DQ<8>")
		)
		(pad "112" smd rect
			(at -2.050034 36.124896 270)
			(size 0.519938 1.4986)
			(layers "F.Cu" "F.Mask" "F.Paste")
			(net "GND")
		)
		(pad "113" smd rect
			(at -2.050034 36.975034 270)
			(size 0.519938 1.4986)
			(layers "F.Cu" "F.Mask" "F.Paste")
			(net "M_H_CPU0_SB_DQ<9>")
		)
		(pad "114" smd rect
			(at -2.050034 37.824918 270)
			(size 0.519938 1.4986)
			(layers "F.Cu" "F.Mask" "F.Paste")
			(net "GND")
		)
		(pad "115" smd rect
			(at -2.050034 38.675056 270)
			(size 0.519938 1.4986)
			(layers "F.Cu" "F.Mask" "F.Paste")
			(net "M_H_CPU0_SB_DQS_DP<1>")
		)
		(pad "116" smd rect
			(at -2.050034 39.52494 270)
			(size 0.519938 1.4986)
			(layers "F.Cu" "F.Mask" "F.Paste")
			(net "M_H_CPU0_SB_DQS_DN<1>")
		)
		(pad "117" smd rect
			(at -2.050034 40.375078 270)
			(size 0.519938 1.4986)
			(layers "F.Cu" "F.Mask" "F.Paste")
			(net "GND")
		)
		(pad "118" smd rect
			(at -2.050034 41.224962 270)
			(size 0.519938 1.4986)
			(layers "F.Cu" "F.Mask" "F.Paste")
			(net "M_H_CPU0_SB_DQ<12>")
		)
		(pad "119" smd rect
			(at -2.050034 42.0751 270)
			(size 0.519938 1.4986)
			(layers "F.Cu" "F.Mask" "F.Paste")
			(net "GND")
		)
		(pad "120" smd rect
			(at -2.050034 42.924984 270)
			(size 0.519938 1.4986)
			(layers "F.Cu" "F.Mask" "F.Paste")
			(net "M_H_CPU0_SB_DQ<13>")
		)
		(pad "121" smd rect
			(at -2.050034 43.775122 270)
			(size 0.519938 1.4986)
			(layers "F.Cu" "F.Mask" "F.Paste")
			(net "GND")
		)
		(pad "122" smd rect
			(at -2.050034 44.625006 270)
			(size 0.519938 1.4986)
			(layers "F.Cu" "F.Mask" "F.Paste")
			(net "M_H_CPU0_SB_DQ<16>")
		)
		(pad "123" smd rect
			(at -2.050034 45.47489 270)
			(size 0.519938 1.4986)
			(layers "F.Cu" "F.Mask" "F.Paste")
			(net "GND")
		)
		(pad "124" smd rect
			(at -2.050034 46.325028 270)
			(size 0.519938 1.4986)
			(layers "F.Cu" "F.Mask" "F.Paste")
			(net "M_H_CPU0_SB_DQ<17>")
		)
		(pad "125" smd rect
			(at -2.050034 47.174912 270)
			(size 0.519938 1.4986)
			(layers "F.Cu" "F.Mask" "F.Paste")
			(net "GND")
		)
		(pad "126" smd rect
			(at -2.050034 48.02505 270)
			(size 0.519938 1.4986)
			(layers "F.Cu" "F.Mask" "F.Paste")
			(net "M_H_CPU0_SB_DQS_DP<2>")
		)
		(pad "127" smd rect
			(at -2.050034 48.874934 270)
			(size 0.519938 1.4986)
			(layers "F.Cu" "F.Mask" "F.Paste")
			(net "M_H_CPU0_SB_DQS_DN<2>")
		)
		(pad "128" smd rect
			(at -2.050034 49.725072 270)
			(size 0.519938 1.4986)
			(layers "F.Cu" "F.Mask" "F.Paste")
			(net "GND")
		)
		(pad "129" smd rect
			(at -2.050034 50.574956 270)
			(size 0.519938 1.4986)
			(layers "F.Cu" "F.Mask" "F.Paste")
			(net "M_H_CPU0_SB_DQ<20>")
		)
		(pad "130" smd rect
			(at -2.050034 51.425094 270)
			(size 0.519938 1.4986)
			(layers "F.Cu" "F.Mask" "F.Paste")
			(net "GND")
		)
		(pad "131" smd rect
			(at -2.050034 52.274978 270)
			(size 0.519938 1.4986)
			(layers "F.Cu" "F.Mask" "F.Paste")
			(net "M_H_CPU0_SB_DQ<21>")
		)
		(pad "132" smd rect
			(at -2.050034 53.125116 270)
			(size 0.519938 1.4986)
			(layers "F.Cu" "F.Mask" "F.Paste")
			(net "GND")
		)
		(pad "133" smd rect
			(at -2.050034 53.975 270)
			(size 0.519938 1.4986)
			(layers "F.Cu" "F.Mask" "F.Paste")
			(net "M_H_CPU0_SB_DQ<24>")
		)
		(pad "134" smd rect
			(at -2.050034 54.824884 270)
			(size 0.519938 1.4986)
			(layers "F.Cu" "F.Mask" "F.Paste")
			(net "GND")
		)
		(pad "135" smd rect
			(at -2.050034 55.675022 270)
			(size 0.519938 1.4986)
			(layers "F.Cu" "F.Mask" "F.Paste")
			(net "M_H_CPU0_SB_DQ<25>")
		)
		(pad "136" smd rect
			(at -2.050034 56.524906 270)
			(size 0.519938 1.4986)
			(layers "F.Cu" "F.Mask" "F.Paste")
			(net "GND")
		)
		(pad "137" smd rect
			(at -2.050034 57.375044 270)
			(size 0.519938 1.4986)
			(layers "F.Cu" "F.Mask" "F.Paste")
			(net "M_H_CPU0_SB_DQS_DP<3>")
		)
		(pad "138" smd rect
			(at -2.050034 58.224928 270)
			(size 0.519938 1.4986)
			(layers "F.Cu" "F.Mask" "F.Paste")
			(net "M_H_CPU0_SB_DQS_DN<3>")
		)
		(pad "139" smd rect
			(at -2.050034 59.075066 270)
			(size 0.519938 1.4986)
			(layers "F.Cu" "F.Mask" "F.Paste")
			(net "GND")
		)
		(pad "140" smd rect
			(at -2.050034 59.92495 270)
			(size 0.519938 1.4986)
			(layers "F.Cu" "F.Mask" "F.Paste")
			(net "M_H_CPU0_SB_DQ<28>")
		)
		(pad "141" smd rect
			(at -2.050034 60.775088 270)
			(size 0.519938 1.4986)
			(layers "F.Cu" "F.Mask" "F.Paste")
			(net "GND")
		)
		(pad "142" smd rect
			(at -2.050034 61.624972 270)
			(size 0.519938 1.4986)
			(layers "F.Cu" "F.Mask" "F.Paste")
			(net "M_H_CPU0_SB_DQ<29>")
		)
		(pad "143" smd rect
			(at -2.050034 62.47511 270)
			(size 0.519938 1.4986)
			(layers "F.Cu" "F.Mask" "F.Paste")
			(net "GND")
		)
		(pad "144" smd rect
			(at -2.050034 63.324994 270)
			(size 0.519938 1.4986)
			(layers "F.Cu" "F.Mask" "F.Paste")
			(net "TP_CHH_CPU0_DIMM2_FRU_1")
		)
		(pad "145" smd rect
			(at 2.050034 -63.324994 270)
			(size 0.519938 1.4986)
			(layers "F.Cu" "F.Mask" "F.Paste")
			(net "P12V_S3_AUX_CPU0_NVDIMM")
		)
		(pad "146" smd rect
			(at 2.050034 -62.47511 270)
			(size 0.519938 1.4986)
			(layers "F.Cu" "F.Mask" "F.Paste")
			(net "P12V_S3_AUX_CPU0_NVDIMM")
		)
		(pad "147" smd rect
			(at 2.050034 -61.624972 270)
			(size 0.519938 1.4986)
			(layers "F.Cu" "F.Mask" "F.Paste")
			(net "PWRGD_CHH_CPU0_DIMM2")
		)
		(pad "148" smd rect
			(at 2.050034 -60.775088 270)
			(size 0.519938 1.4986)
			(layers "F.Cu" "F.Mask" "F.Paste")
			(net "PD_CHH_CPU0_DIMM2_SAA")
		)
		(pad "149" smd rect
			(at 2.050034 -59.92495 270)
			(size 0.519938 1.4986)
			(layers "F.Cu" "F.Mask" "F.Paste")
			(net "TP_CHH_CPU0_DIMM2_FRU_2")
		)
		(pad "150" smd rect
			(at 2.050034 -59.075066 270)
			(size 0.519938 1.4986)
			(layers "F.Cu" "F.Mask" "F.Paste")
			(net "TP_CHH_CPU0_DIMM2_FRU_3")
		)
		(pad "151" smd rect
			(at 2.050034 -58.224928 270)
			(size 0.519938 1.4986)
			(layers "F.Cu" "F.Mask" "F.Paste")
			(net "GND")
		)
		(pad "152" smd rect
			(at 2.050034 -57.375044 270)
			(size 0.519938 1.4986)
			(layers "F.Cu" "F.Mask" "F.Paste")
			(net "M_H_CPU0_SA_DQ<2>")
		)
		(pad "153" smd rect
			(at 2.050034 -56.524906 270)
			(size 0.519938 1.4986)
			(layers "F.Cu" "F.Mask" "F.Paste")
			(net "GND")
		)
		(pad "154" smd rect
			(at 2.050034 -55.675022 270)
			(size 0.519938 1.4986)
			(layers "F.Cu" "F.Mask" "F.Paste")
			(net "M_H_CPU0_SA_DQ<3>")
		)
		(pad "155" smd rect
			(at 2.050034 -54.824884 270)
			(size 0.519938 1.4986)
			(layers "F.Cu" "F.Mask" "F.Paste")
			(net "GND")
		)
		(pad "156" smd rect
			(at 2.050034 -53.975 270)
			(size 0.519938 1.4986)
			(layers "F.Cu" "F.Mask" "F.Paste")
			(net "M_H_CPU0_SA_DQS_DN<5>")
		)
		(pad "157" smd rect
			(at 2.050034 -53.125116 270)
			(size 0.519938 1.4986)
			(layers "F.Cu" "F.Mask" "F.Paste")
			(net "M_H_CPU0_SA_DQS_DP<5>")
		)
		(pad "158" smd rect
			(at 2.050034 -52.274978 270)
			(size 0.519938 1.4986)
			(layers "F.Cu" "F.Mask" "F.Paste")
			(net "GND")
		)
		(pad "159" smd rect
			(at 2.050034 -51.425094 270)
			(size 0.519938 1.4986)
			(layers "F.Cu" "F.Mask" "F.Paste")
			(net "M_H_CPU0_SA_DQ<6>")
		)
		(pad "160" smd rect
			(at 2.050034 -50.574956 270)
			(size 0.519938 1.4986)
			(layers "F.Cu" "F.Mask" "F.Paste")
			(net "GND")
		)
		(pad "161" smd rect
			(at 2.050034 -49.725072 270)
			(size 0.519938 1.4986)
			(layers "F.Cu" "F.Mask" "F.Paste")
			(net "M_H_CPU0_SA_DQ<7>")
		)
		(pad "162" smd rect
			(at 2.050034 -48.874934 270)
			(size 0.519938 1.4986)
			(layers "F.Cu" "F.Mask" "F.Paste")
			(net "GND")
		)
		(pad "163" smd rect
			(at 2.050034 -48.02505 270)
			(size 0.519938 1.4986)
			(layers "F.Cu" "F.Mask" "F.Paste")
			(net "M_H_CPU0_SA_DQ<10>")
		)
		(pad "164" smd rect
			(at 2.050034 -47.174912 270)
			(size 0.519938 1.4986)
			(layers "F.Cu" "F.Mask" "F.Paste")
			(net "GND")
		)
		(pad "165" smd rect
			(at 2.050034 -46.325028 270)
			(size 0.519938 1.4986)
			(layers "F.Cu" "F.Mask" "F.Paste")
			(net "M_H_CPU0_SA_DQ<11>")
		)
		(pad "166" smd rect
			(at 2.050034 -45.47489 270)
			(size 0.519938 1.4986)
			(layers "F.Cu" "F.Mask" "F.Paste")
			(net "GND")
		)
		(pad "167" smd rect
			(at 2.050034 -44.625006 270)
			(size 0.519938 1.4986)
			(layers "F.Cu" "F.Mask" "F.Paste")
			(net "M_H_CPU0_SA_DQS_DN<6>")
		)
		(pad "168" smd rect
			(at 2.050034 -43.775122 270)
			(size 0.519938 1.4986)
			(layers "F.Cu" "F.Mask" "F.Paste")
			(net "M_H_CPU0_SA_DQS_DP<6>")
		)
		(pad "169" smd rect
			(at 2.050034 -42.924984 270)
			(size 0.519938 1.4986)
			(layers "F.Cu" "F.Mask" "F.Paste")
			(net "GND")
		)
		(pad "170" smd rect
			(at 2.050034 -42.0751 270)
			(size 0.519938 1.4986)
			(layers "F.Cu" "F.Mask" "F.Paste")
			(net "M_H_CPU0_SA_DQ<14>")
		)
		(pad "171" smd rect
			(at 2.050034 -41.224962 270)
			(size 0.519938 1.4986)
			(layers "F.Cu" "F.Mask" "F.Paste")
			(net "GND")
		)
		(pad "172" smd rect
			(at 2.050034 -40.375078 270)
			(size 0.519938 1.4986)
			(layers "F.Cu" "F.Mask" "F.Paste")
			(net "M_H_CPU0_SA_DQ<15>")
		)
		(pad "173" smd rect
			(at 2.050034 -39.52494 270)
			(size 0.519938 1.4986)
			(layers "F.Cu" "F.Mask" "F.Paste")
			(net "GND")
		)
		(pad "174" smd rect
			(at 2.050034 -38.675056 270)
			(size 0.519938 1.4986)
			(layers "F.Cu" "F.Mask" "F.Paste")
			(net "M_H_CPU0_SA_DQ<18>")
		)
		(pad "175" smd rect
			(at 2.050034 -37.824918 270)
			(size 0.519938 1.4986)
			(layers "F.Cu" "F.Mask" "F.Paste")
			(net "GND")
		)
		(pad "176" smd rect
			(at 2.050034 -36.975034 270)
			(size 0.519938 1.4986)
			(layers "F.Cu" "F.Mask" "F.Paste")
			(net "M_H_CPU0_SA_DQ<19>")
		)
		(pad "177" smd rect
			(at 2.050034 -36.124896 270)
			(size 0.519938 1.4986)
			(layers "F.Cu" "F.Mask" "F.Paste")
			(net "GND")
		)
		(pad "178" smd rect
			(at 2.050034 -35.275012 270)
			(size 0.519938 1.4986)
			(layers "F.Cu" "F.Mask" "F.Paste")
			(net "M_H_CPU0_SA_DQS_DN<7>")
		)
		(pad "179" smd rect
			(at 2.050034 -34.425128 270)
			(size 0.519938 1.4986)
			(layers "F.Cu" "F.Mask" "F.Paste")
			(net "M_H_CPU0_SA_DQS_DP<7>")
		)
		(pad "180" smd rect
			(at 2.050034 -33.57499 270)
			(size 0.519938 1.4986)
			(layers "F.Cu" "F.Mask" "F.Paste")
			(net "GND")
		)
		(pad "181" smd rect
			(at 2.050034 -32.725106 270)
			(size 0.519938 1.4986)
			(layers "F.Cu" "F.Mask" "F.Paste")
			(net "M_H_CPU0_SA_DQ<22>")
		)
		(pad "182" smd rect
			(at 2.050034 -31.874968 270)
			(size 0.519938 1.4986)
			(layers "F.Cu" "F.Mask" "F.Paste")
			(net "GND")
		)
		(pad "183" smd rect
			(at 2.050034 -31.025084 270)
			(size 0.519938 1.4986)
			(layers "F.Cu" "F.Mask" "F.Paste")
			(net "M_H_CPU0_SA_DQ<23>")
		)
		(pad "184" smd rect
			(at 2.050034 -30.174946 270)
			(size 0.519938 1.4986)
			(layers "F.Cu" "F.Mask" "F.Paste")
			(net "GND")
		)
		(pad "185" smd rect
			(at 2.050034 -29.325062 270)
			(size 0.519938 1.4986)
			(layers "F.Cu" "F.Mask" "F.Paste")
			(net "M_H_CPU0_SA_DQ<26>")
		)
		(pad "186" smd rect
			(at 2.050034 -28.474924 270)
			(size 0.519938 1.4986)
			(layers "F.Cu" "F.Mask" "F.Paste")
			(net "GND")
		)
		(pad "187" smd rect
			(at 2.050034 -27.62504 270)
			(size 0.519938 1.4986)
			(layers "F.Cu" "F.Mask" "F.Paste")
			(net "M_H_CPU0_SA_DQ<27>")
		)
		(pad "188" smd rect
			(at 2.050034 -26.774902 270)
			(size 0.519938 1.4986)
			(layers "F.Cu" "F.Mask" "F.Paste")
			(net "GND")
		)
		(pad "189" smd rect
			(at 2.050034 -25.925018 270)
			(size 0.519938 1.4986)
			(layers "F.Cu" "F.Mask" "F.Paste")
			(net "M_H_CPU0_SA_DQS_DN<8>")
		)
		(pad "190" smd rect
			(at 2.050034 -25.07488 270)
			(size 0.519938 1.4986)
			(layers "F.Cu" "F.Mask" "F.Paste")
			(net "M_H_CPU0_SA_DQS_DP<8>")
		)
		(pad "191" smd rect
			(at 2.050034 -24.224996 270)
			(size 0.519938 1.4986)
			(layers "F.Cu" "F.Mask" "F.Paste")
			(net "GND")
		)
		(pad "192" smd rect
			(at 2.050034 -23.375112 270)
			(size 0.519938 1.4986)
			(layers "F.Cu" "F.Mask" "F.Paste")
			(net "M_H_CPU0_SA_DQ<30>")
		)
		(pad "193" smd rect
			(at 2.050034 -22.524974 270)
			(size 0.519938 1.4986)
			(layers "F.Cu" "F.Mask" "F.Paste")
			(net "GND")
		)
		(pad "194" smd rect
			(at 2.050034 -21.67509 270)
			(size 0.519938 1.4986)
			(layers "F.Cu" "F.Mask" "F.Paste")
			(net "M_H_CPU0_SA_DQ<31>")
		)
		(pad "195" smd rect
			(at 2.050034 -20.824952 270)
			(size 0.519938 1.4986)
			(layers "F.Cu" "F.Mask" "F.Paste")
			(net "GND")
		)
		(pad "196" smd rect
			(at 2.050034 -19.975068 270)
			(size 0.519938 1.4986)
			(layers "F.Cu" "F.Mask" "F.Paste")
			(net "M_H_CPU0_SA_CB<2>")
		)
		(pad "197" smd rect
			(at 2.050034 -19.12493 270)
			(size 0.519938 1.4986)
			(layers "F.Cu" "F.Mask" "F.Paste")
			(net "GND")
		)
		(pad "198" smd rect
			(at 2.050034 -18.275046 270)
			(size 0.519938 1.4986)
			(layers "F.Cu" "F.Mask" "F.Paste")
			(net "M_H_CPU0_SA_CB<3>")
		)
		(pad "199" smd rect
			(at 2.050034 -17.424908 270)
			(size 0.519938 1.4986)
			(layers "F.Cu" "F.Mask" "F.Paste")
			(net "GND")
		)
		(pad "200" smd rect
			(at 2.050034 -16.575024 270)
			(size 0.519938 1.4986)
			(layers "F.Cu" "F.Mask" "F.Paste")
			(net "M_H_CPU0_SA_DQS_DN<9>")
		)
		(pad "201" smd rect
			(at 2.050034 -15.724886 270)
			(size 0.519938 1.4986)
			(layers "F.Cu" "F.Mask" "F.Paste")
			(net "M_H_CPU0_SA_DQS_DP<9>")
		)
		(pad "202" smd rect
			(at 2.050034 -14.875002 270)
			(size 0.519938 1.4986)
			(layers "F.Cu" "F.Mask" "F.Paste")
			(net "GND")
		)
		(pad "203" smd rect
			(at 2.050034 -14.025118 270)
			(size 0.519938 1.4986)
			(layers "F.Cu" "F.Mask" "F.Paste")
			(net "M_H_CPU0_SA_CB<6>")
		)
		(pad "204" smd rect
			(at 2.050034 -13.17498 270)
			(size 0.519938 1.4986)
			(layers "F.Cu" "F.Mask" "F.Paste")
			(net "GND")
		)
		(pad "205" smd rect
			(at 2.050034 -12.325096 270)
			(size 0.519938 1.4986)
			(layers "F.Cu" "F.Mask" "F.Paste")
			(net "M_H_CPU0_SA_CB<7>")
		)
		(pad "206" smd rect
			(at 2.050034 -11.474958 270)
			(size 0.519938 1.4986)
			(layers "F.Cu" "F.Mask" "F.Paste")
			(net "GND")
		)
		(pad "207" smd rect
			(at 2.050034 -10.625074 270)
			(size 0.519938 1.4986)
			(layers "F.Cu" "F.Mask" "F.Paste")
			(net "RST_M_GH_CPU0_FPGA_N")
		)
		(pad "208" smd rect
			(at 2.050034 -9.774936 270)
			(size 0.519938 1.4986)
			(layers "F.Cu" "F.Mask" "F.Paste")
			(net "GND")
		)
		(pad "209" smd rect
			(at 2.050034 -8.925052 270)
			(size 0.519938 1.4986)
			(layers "F.Cu" "F.Mask" "F.Paste")
			(net "M_H_CPU0_SA_CS_N<3>")
		)
		(pad "210" smd rect
			(at 2.050034 -8.074914 270)
			(size 0.519938 1.4986)
			(layers "F.Cu" "F.Mask" "F.Paste")
			(net "GND")
		)
		(pad "211" smd rect
			(at 2.050034 -7.22503 270)
			(size 0.519938 1.4986)
			(layers "F.Cu" "F.Mask" "F.Paste")
			(net "M_H_CPU0_SA_CA<1>")
		)
		(pad "212" smd rect
			(at 2.050034 -6.374892 270)
			(size 0.519938 1.4986)
			(layers "F.Cu" "F.Mask" "F.Paste")
			(net "GND")
		)
		(pad "213" smd rect
			(at 2.050034 -5.525008 270)
			(size 0.519938 1.4986)
			(layers "F.Cu" "F.Mask" "F.Paste")
			(net "M_H_CPU0_SA_CA<3>")
		)
		(pad "214" smd rect
			(at 2.050034 -4.675124 270)
			(size 0.519938 1.4986)
			(layers "F.Cu" "F.Mask" "F.Paste")
			(net "GND")
		)
		(pad "215" smd rect
			(at 2.050034 -3.824986 270)
			(size 0.519938 1.4986)
			(layers "F.Cu" "F.Mask" "F.Paste")
			(net "M_H_CPU0_SA_CA<5>")
		)
		(pad "216" smd rect
			(at 2.050034 -2.975102 270)
			(size 0.519938 1.4986)
			(layers "F.Cu" "F.Mask" "F.Paste")
			(net "GND")
		)
		(pad "217" smd rect
			(at 2.050034 -2.124964 270)
			(size 0.519938 1.4986)
			(layers "F.Cu" "F.Mask" "F.Paste")
			(net "M_H_CPU0_CLK_DP<1>")
		)
		(pad "218" smd rect
			(at 2.050034 -1.27508 270)
			(size 0.519938 1.4986)
			(layers "F.Cu" "F.Mask" "F.Paste")
			(net "M_H_CPU0_CLK_DN<1>")
		)
		(pad "219" smd rect
			(at 2.050034 -0.424942 270)
			(size 0.519938 1.4986)
			(layers "F.Cu" "F.Mask" "F.Paste")
			(net "GND")
		)
		(pad "220" smd rect
			(at 2.050034 5.525008 270)
			(size 0.519938 1.4986)
			(layers "F.Cu" "F.Mask" "F.Paste")
			(net "TP_CHH_CPU0_DIMM2_FRU_4")
		)
		(pad "221" smd rect
			(at 2.050034 6.374892 270)
			(size 0.519938 1.4986)
			(layers "F.Cu" "F.Mask" "F.Paste")
			(net "M_H_CPU0_SB_CA<1>")
		)
		(pad "222" smd rect
			(at 2.050034 7.22503 270)
			(size 0.519938 1.4986)
			(layers "F.Cu" "F.Mask" "F.Paste")
			(net "GND")
		)
		(pad "223" smd rect
			(at 2.050034 8.074914 270)
			(size 0.519938 1.4986)
			(layers "F.Cu" "F.Mask" "F.Paste")
			(net "M_H_CPU0_SB_CA<3>")
		)
		(pad "224" smd rect
			(at 2.050034 8.925052 270)
			(size 0.519938 1.4986)
			(layers "F.Cu" "F.Mask" "F.Paste")
			(net "GND")
		)
		(pad "225" smd rect
			(at 2.050034 9.774936 270)
			(size 0.519938 1.4986)
			(layers "F.Cu" "F.Mask" "F.Paste")
			(net "M_H_CPU0_SB_CA<5>")
		)
		(pad "226" smd rect
			(at 2.050034 10.625074 270)
			(size 0.519938 1.4986)
			(layers "F.Cu" "F.Mask" "F.Paste")
			(net "GND")
		)
		(pad "227" smd rect
			(at 2.050034 11.474958 270)
			(size 0.519938 1.4986)
			(layers "F.Cu" "F.Mask" "F.Paste")
			(net "M_H_CPU0_SB_PAR")
		)
		(pad "228" smd rect
			(at 2.050034 12.325096 270)
			(size 0.519938 1.4986)
			(layers "F.Cu" "F.Mask" "F.Paste")
			(net "GND")
		)
		(pad "229" smd rect
			(at 2.050034 13.17498 270)
			(size 0.519938 1.4986)
			(layers "F.Cu" "F.Mask" "F.Paste")
			(net "M_H_CPU0_SB_CS_N<3>")
		)
		(pad "230" smd rect
			(at 2.050034 14.025118 270)
			(size 0.519938 1.4986)
			(layers "F.Cu" "F.Mask" "F.Paste")
			(net "GND")
		)
		(pad "231" smd rect
			(at 2.050034 14.875002 270)
			(size 0.519938 1.4986)
			(layers "F.Cu" "F.Mask" "F.Paste")
			(net "TP_CHH_CPU0_DIMM2_FRU_5")
		)
		(pad "232" smd rect
			(at 2.050034 15.724886 270)
			(size 0.519938 1.4986)
			(layers "F.Cu" "F.Mask" "F.Paste")
			(net "TP_CHH_CPU0_DIMM2_FRU_6")
		)
		(pad "233" smd rect
			(at 2.050034 16.575024 270)
			(size 0.519938 1.4986)
			(layers "F.Cu" "F.Mask" "F.Paste")
			(net "GND")
		)
		(pad "234" smd rect
			(at 2.050034 17.424908 270)
			(size 0.519938 1.4986)
			(layers "F.Cu" "F.Mask" "F.Paste")
			(net "M_H_CPU0_SB_CB<6>")
		)
		(pad "235" smd rect
			(at 2.050034 18.275046 270)
			(size 0.519938 1.4986)
			(layers "F.Cu" "F.Mask" "F.Paste")
			(net "GND")
		)
		(pad "236" smd rect
			(at 2.050034 19.12493 270)
			(size 0.519938 1.4986)
			(layers "F.Cu" "F.Mask" "F.Paste")
			(net "M_H_CPU0_SB_CB<7>")
		)
		(pad "237" smd rect
			(at 2.050034 19.975068 270)
			(size 0.519938 1.4986)
			(layers "F.Cu" "F.Mask" "F.Paste")
			(net "GND")
		)
		(pad "238" smd rect
			(at 2.050034 20.824952 270)
			(size 0.519938 1.4986)
			(layers "F.Cu" "F.Mask" "F.Paste")
			(net "M_H_CPU0_SB_DQS_DN<4>")
		)
		(pad "239" smd rect
			(at 2.050034 21.67509 270)
			(size 0.519938 1.4986)
			(layers "F.Cu" "F.Mask" "F.Paste")
			(net "M_H_CPU0_SB_DQS_DP<4>")
		)
		(pad "240" smd rect
			(at 2.050034 22.524974 270)
			(size 0.519938 1.4986)
			(layers "F.Cu" "F.Mask" "F.Paste")
			(net "GND")
		)
		(pad "241" smd rect
			(at 2.050034 23.375112 270)
			(size 0.519938 1.4986)
			(layers "F.Cu" "F.Mask" "F.Paste")
			(net "M_H_CPU0_SB_CB<2>")
		)
		(pad "242" smd rect
			(at 2.050034 24.224996 270)
			(size 0.519938 1.4986)
			(layers "F.Cu" "F.Mask" "F.Paste")
			(net "GND")
		)
		(pad "243" smd rect
			(at 2.050034 25.07488 270)
			(size 0.519938 1.4986)
			(layers "F.Cu" "F.Mask" "F.Paste")
			(net "M_H_CPU0_SB_CB<3>")
		)
		(pad "244" smd rect
			(at 2.050034 25.925018 270)
			(size 0.519938 1.4986)
			(layers "F.Cu" "F.Mask" "F.Paste")
			(net "GND")
		)
		(pad "245" smd rect
			(at 2.050034 26.774902 270)
			(size 0.519938 1.4986)
			(layers "F.Cu" "F.Mask" "F.Paste")
			(net "M_H_CPU0_SB_DQ<2>")
		)
		(pad "246" smd rect
			(at 2.050034 27.62504 270)
			(size 0.519938 1.4986)
			(layers "F.Cu" "F.Mask" "F.Paste")
			(net "GND")
		)
		(pad "247" smd rect
			(at 2.050034 28.474924 270)
			(size 0.519938 1.4986)
			(layers "F.Cu" "F.Mask" "F.Paste")
			(net "M_H_CPU0_SB_DQ<3>")
		)
		(pad "248" smd rect
			(at 2.050034 29.325062 270)
			(size 0.519938 1.4986)
			(layers "F.Cu" "F.Mask" "F.Paste")
			(net "GND")
		)
		(pad "249" smd rect
			(at 2.050034 30.174946 270)
			(size 0.519938 1.4986)
			(layers "F.Cu" "F.Mask" "F.Paste")
			(net "M_H_CPU0_SB_DQS_DN<5>")
		)
		(pad "250" smd rect
			(at 2.050034 31.025084 270)
			(size 0.519938 1.4986)
			(layers "F.Cu" "F.Mask" "F.Paste")
			(net "M_H_CPU0_SB_DQS_DP<5>")
		)
		(pad "251" smd rect
			(at 2.050034 31.874968 270)
			(size 0.519938 1.4986)
			(layers "F.Cu" "F.Mask" "F.Paste")
			(net "GND")
		)
		(pad "252" smd rect
			(at 2.050034 32.725106 270)
			(size 0.519938 1.4986)
			(layers "F.Cu" "F.Mask" "F.Paste")
			(net "M_H_CPU0_SB_DQ<6>")
		)
		(pad "253" smd rect
			(at 2.050034 33.57499 270)
			(size 0.519938 1.4986)
			(layers "F.Cu" "F.Mask" "F.Paste")
			(net "GND")
		)
		(pad "254" smd rect
			(at 2.050034 34.425128 270)
			(size 0.519938 1.4986)
			(layers "F.Cu" "F.Mask" "F.Paste")
			(net "M_H_CPU0_SB_DQ<7>")
		)
		(pad "255" smd rect
			(at 2.050034 35.275012 270)
			(size 0.519938 1.4986)
			(layers "F.Cu" "F.Mask" "F.Paste")
			(net "GND")
		)
		(pad "256" smd rect
			(at 2.050034 36.124896 270)
			(size 0.519938 1.4986)
			(layers "F.Cu" "F.Mask" "F.Paste")
			(net "M_H_CPU0_SB_DQ<10>")
		)
		(pad "257" smd rect
			(at 2.050034 36.975034 270)
			(size 0.519938 1.4986)
			(layers "F.Cu" "F.Mask" "F.Paste")
			(net "GND")
		)
		(pad "258" smd rect
			(at 2.050034 37.824918 270)
			(size 0.519938 1.4986)
			(layers "F.Cu" "F.Mask" "F.Paste")
			(net "M_H_CPU0_SB_DQ<11>")
		)
		(pad "259" smd rect
			(at 2.050034 38.675056 270)
			(size 0.519938 1.4986)
			(layers "F.Cu" "F.Mask" "F.Paste")
			(net "GND")
		)
		(pad "260" smd rect
			(at 2.050034 39.52494 270)
			(size 0.519938 1.4986)
			(layers "F.Cu" "F.Mask" "F.Paste")
			(net "M_H_CPU0_SB_DQS_DN<6>")
		)
		(pad "261" smd rect
			(at 2.050034 40.375078 270)
			(size 0.519938 1.4986)
			(layers "F.Cu" "F.Mask" "F.Paste")
			(net "M_H_CPU0_SB_DQS_DP<6>")
		)
		(pad "262" smd rect
			(at 2.050034 41.224962 270)
			(size 0.519938 1.4986)
			(layers "F.Cu" "F.Mask" "F.Paste")
			(net "GND")
		)
		(pad "263" smd rect
			(at 2.050034 42.0751 270)
			(size 0.519938 1.4986)
			(layers "F.Cu" "F.Mask" "F.Paste")
			(net "M_H_CPU0_SB_DQ<14>")
		)
		(pad "264" smd rect
			(at 2.050034 42.924984 270)
			(size 0.519938 1.4986)
			(layers "F.Cu" "F.Mask" "F.Paste")
			(net "GND")
		)
		(pad "265" smd rect
			(at 2.050034 43.775122 270)
			(size 0.519938 1.4986)
			(layers "F.Cu" "F.Mask" "F.Paste")
			(net "M_H_CPU0_SB_DQ<15>")
		)
		(pad "266" smd rect
			(at 2.050034 44.625006 270)
			(size 0.519938 1.4986)
			(layers "F.Cu" "F.Mask" "F.Paste")
			(net "GND")
		)
		(pad "267" smd rect
			(at 2.050034 45.47489 270)
			(size 0.519938 1.4986)
			(layers "F.Cu" "F.Mask" "F.Paste")
			(net "M_H_CPU0_SB_DQ<18>")
		)
		(pad "268" smd rect
			(at 2.050034 46.325028 270)
			(size 0.519938 1.4986)
			(layers "F.Cu" "F.Mask" "F.Paste")
			(net "GND")
		)
		(pad "269" smd rect
			(at 2.050034 47.174912 270)
			(size 0.519938 1.4986)
			(layers "F.Cu" "F.Mask" "F.Paste")
			(net "M_H_CPU0_SB_DQ<19>")
		)
		(pad "270" smd rect
			(at 2.050034 48.02505 270)
			(size 0.519938 1.4986)
			(layers "F.Cu" "F.Mask" "F.Paste")
			(net "GND")
		)
		(pad "271" smd rect
			(at 2.050034 48.874934 270)
			(size 0.519938 1.4986)
			(layers "F.Cu" "F.Mask" "F.Paste")
			(net "M_H_CPU0_SB_DQS_DN<7>")
		)
		(pad "272" smd rect
			(at 2.050034 49.725072 270)
			(size 0.519938 1.4986)
			(layers "F.Cu" "F.Mask" "F.Paste")
			(net "M_H_CPU0_SB_DQS_DP<7>")
		)
		(pad "273" smd rect
			(at 2.050034 50.574956 270)
			(size 0.519938 1.4986)
			(layers "F.Cu" "F.Mask" "F.Paste")
			(net "GND")
		)
		(pad "274" smd rect
			(at 2.050034 51.425094 270)
			(size 0.519938 1.4986)
			(layers "F.Cu" "F.Mask" "F.Paste")
			(net "M_H_CPU0_SB_DQ<22>")
		)
		(pad "275" smd rect
			(at 2.050034 52.274978 270)
			(size 0.519938 1.4986)
			(layers "F.Cu" "F.Mask" "F.Paste")
			(net "GND")
		)
		(pad "276" smd rect
			(at 2.050034 53.125116 270)
			(size 0.519938 1.4986)
			(layers "F.Cu" "F.Mask" "F.Paste")
			(net "M_H_CPU0_SB_DQ<23>")
		)
		(pad "277" smd rect
			(at 2.050034 53.975 270)
			(size 0.519938 1.4986)
			(layers "F.Cu" "F.Mask" "F.Paste")
			(net "GND")
		)
		(pad "278" smd rect
			(at 2.050034 54.824884 270)
			(size 0.519938 1.4986)
			(layers "F.Cu" "F.Mask" "F.Paste")
			(net "M_H_CPU0_SB_DQ<26>")
		)
		(pad "279" smd rect
			(at 2.050034 55.675022 270)
			(size 0.519938 1.4986)
			(layers "F.Cu" "F.Mask" "F.Paste")
			(net "GND")
		)
		(pad "280" smd rect
			(at 2.050034 56.524906 270)
			(size 0.519938 1.4986)
			(layers "F.Cu" "F.Mask" "F.Paste")
			(net "M_H_CPU0_SB_DQ<27>")
		)
		(pad "281" smd rect
			(at 2.050034 57.375044 270)
			(size 0.519938 1.4986)
			(layers "F.Cu" "F.Mask" "F.Paste")
			(net "GND")
		)
		(pad "282" smd rect
			(at 2.050034 58.224928 270)
			(size 0.519938 1.4986)
			(layers "F.Cu" "F.Mask" "F.Paste")
			(net "M_H_CPU0_SB_DQS_DN<8>")
		)
		(pad "283" smd rect
			(at 2.050034 59.075066 270)
			(size 0.519938 1.4986)
			(layers "F.Cu" "F.Mask" "F.Paste")
			(net "M_H_CPU0_SB_DQS_DP<8>")
		)
		(pad "284" smd rect
			(at 2.050034 59.92495 270)
			(size 0.519938 1.4986)
			(layers "F.Cu" "F.Mask" "F.Paste")
			(net "GND")
		)
		(pad "285" smd rect
			(at 2.050034 60.775088 270)
			(size 0.519938 1.4986)
			(layers "F.Cu" "F.Mask" "F.Paste")
			(net "M_H_CPU0_SB_DQ<30>")
		)
		(pad "286" smd rect
			(at 2.050034 61.624972 270)
			(size 0.519938 1.4986)
			(layers "F.Cu" "F.Mask" "F.Paste")
			(net "GND")
		)
		(pad "287" smd rect
			(at 2.050034 62.47511 270)
			(size 0.519938 1.4986)
			(layers "F.Cu" "F.Mask" "F.Paste")
			(net "M_H_CPU0_SB_DQ<31>")
		)
		(pad "288" smd rect
			(at 2.050034 63.324994 270)
			(size 0.519938 1.4986)
			(layers "F.Cu" "F.Mask" "F.Paste")
			(net "GND")
		)
		(pad "G1" thru_hole oval
			(at 0 -68.97497)
			(size 2.8194 1.5748)
			(drill oval 2.4384 1.1938)
			(layers "*.Cu" "*.Mask")
			(remove_unused_layers no)
			(net "GND")
			(clearance 0.127)
			(thermal_gap 0.127)
		)
		(pad "G2" thru_hole oval
			(at 0 3.875024)
			(size 2.8194 1.5748)
			(drill oval 2.4384 1.1938)
			(layers "*.Cu" "*.Mask")
			(remove_unused_layers no)
			(net "GND")
			(clearance 0.127)
			(thermal_gap 0.127)
		)
		(pad "G3" thru_hole oval
			(at 0 68.97497)
			(size 2.8194 1.5748)
			(drill oval 2.4384 1.1938)
			(layers "*.Cu" "*.Mask")
			(remove_unused_layers no)
			(net "GND")
			(clearance 0.127)
			(thermal_gap 0.127)
		)
	)
	(footprint ""
		(layer "F.Cu")
		(at 150.83028 -34.623756 180)
		(property "Reference" "R3304"
			(at 0 0 180)
			(layer "F.SilkS")
			(hide yes)
			(effects
				(font
					(size 1.27 1.27)
				)
			)
		)
		(property "Value" ""
			(at 0 0 180)
			(layer "F.Fab")
			(effects
				(font
					(size 1.27 1.27)
				)
			)
		)
		(duplicate_pad_numbers_are_jumpers no)
		(fp_line
			(start 0.7874 0.4064)
			(end -0.7874 0.4064)
			(stroke
				(width 0.1524)
				(type default)
			)
			(layer "F.SilkS")
		)
		(fp_line
			(start 0.7874 -0.4064)
			(end 0.7874 0.4064)
			(stroke
				(width 0.1524)
				(type default)
			)
			(layer "F.SilkS")
		)
		(fp_line
			(start -0.7874 0.4064)
			(end -0.7874 -0.4064)
			(stroke
				(width 0.1524)
				(type default)
			)
			(layer "F.SilkS")
		)
		(fp_line
			(start -0.7874 -0.4064)
			(end 0.7874 -0.4064)
			(stroke
				(width 0.1524)
				(type default)
			)
			(layer "F.SilkS")
		)
		(fp_line
			(start 0.67945 0.3048)
			(end 0.120396 0.3048)
			(stroke
				(width 0.1)
				(type default)
			)
			(layer "F.Fab")
		)
		(fp_line
			(start 0.67945 -0.3048)
			(end 0.67945 0.3048)
			(stroke
				(width 0.1)
				(type default)
			)
			(layer "F.Fab")
		)
		(fp_line
			(start 0.12065 -0.2794)
			(end 0.12065 -0.3048)
			(stroke
				(width 0.1)
				(type default)
			)
			(layer "F.Fab")
		)
		(fp_line
			(start 0.12065 -0.3048)
			(end 0.67945 -0.3048)
			(stroke
				(width 0.1)
				(type default)
			)
			(layer "F.Fab")
		)
		(fp_line
			(start 0.120396 0.3048)
			(end 0.120396 0.2794)
			(stroke
				(width 0.1)
				(type default)
			)
			(layer "F.Fab")
		)
		(fp_line
			(start 0.120396 0.2794)
			(end -0.12065 0.2794)
			(stroke
				(width 0.1)
				(type default)
			)
			(layer "F.Fab")
		)
		(fp_line
			(start -0.12065 0.3048)
			(end -0.67945 0.3048)
			(stroke
				(width 0.1)
				(type default)
			)
			(layer "F.Fab")
		)
		(fp_line
			(start -0.12065 0.2794)
			(end -0.12065 0.3048)
			(stroke
				(width 0.1)
				(type default)
			)
			(layer "F.Fab")
		)
		(fp_line
			(start -0.12065 -0.2794)
			(end 0.12065 -0.2794)
			(stroke
				(width 0.1)
				(type default)
			)
			(layer "F.Fab")
		)
		(fp_line
			(start -0.12065 -0.305054)
			(end -0.12065 -0.2794)
			(stroke
				(width 0.1)
				(type default)
			)
			(layer "F.Fab")
		)
		(fp_line
			(start -0.67945 0.3048)
			(end -0.67945 -0.305054)
			(stroke
				(width 0.1)
				(type default)
			)
			(layer "F.Fab")
		)
		(fp_line
			(start -0.67945 -0.305054)
			(end -0.12065 -0.305054)
			(stroke
				(width 0.1)
				(type default)
			)
			(layer "F.Fab")
		)
		(pad "1" smd circle
			(at -0.40005 0 180)
			(size 0 0)
			(layers "F.Cu" "F.Mask" "F.Paste")
			(net "OCP_SFF_PRSNT_ALL_R_N")
		)
		(pad "2" smd circle
			(at 0.40005 0 180)
			(size 0 0)
			(layers "F.Cu" "F.Mask" "F.Paste")
			(net "OCP_SFF_PRSNT_ALL_R3_N")
		)
	)
	(footprint ""
		(layer "F.Cu")
		(at 32.780478 -437.688228 180)
		(property "Reference" "R2991"
			(at 0 0 180)
			(layer "F.SilkS")
			(hide yes)
			(effects
				(font
					(size 1.27 1.27)
				)
			)
		)
		(property "Value" ""
			(at 0 0 180)
			(layer "F.Fab")
			(effects
				(font
					(size 1.27 1.27)
				)
			)
		)
		(duplicate_pad_numbers_are_jumpers no)
		(fp_line
			(start 0.7874 0.4064)
			(end -0.7874 0.4064)
			(stroke
				(width 0.1524)
				(type default)
			)
			(layer "F.SilkS")
		)
		(fp_line
			(start 0.7874 -0.4064)
			(end 0.7874 0.4064)
			(stroke
				(width 0.1524)
				(type default)
			)
			(layer "F.SilkS")
		)
		(fp_line
			(start -0.7874 0.4064)
			(end -0.7874 -0.4064)
			(stroke
				(width 0.1524)
				(type default)
			)
			(layer "F.SilkS")
		)
		(fp_line
			(start -0.7874 -0.4064)
			(end 0.7874 -0.4064)
			(stroke
				(width 0.1524)
				(type default)
			)
			(layer "F.SilkS")
		)
		(fp_line
			(start 0.67945 0.3048)
			(end 0.120396 0.3048)
			(stroke
				(width 0.1)
				(type default)
			)
			(layer "F.Fab")
		)
		(fp_line
			(start 0.67945 -0.3048)
			(end 0.67945 0.3048)
			(stroke
				(width 0.1)
				(type default)
			)
			(layer "F.Fab")
		)
		(fp_line
			(start 0.12065 -0.2794)
			(end 0.12065 -0.3048)
			(stroke
				(width 0.1)
				(type default)
			)
			(layer "F.Fab")
		)
		(fp_line
			(start 0.12065 -0.3048)
			(end 0.67945 -0.3048)
			(stroke
				(width 0.1)
				(type default)
			)
			(layer "F.Fab")
		)
		(fp_line
			(start 0.120396 0.3048)
			(end 0.120396 0.2794)
			(stroke
				(width 0.1)
				(type default)
			)
			(layer "F.Fab")
		)
		(fp_line
			(start 0.120396 0.2794)
			(end -0.12065 0.2794)
			(stroke
				(width 0.1)
				(type default)
			)
			(layer "F.Fab")
		)
		(fp_line
			(start -0.12065 0.3048)
			(end -0.67945 0.3048)
			(stroke
				(width 0.1)
				(type default)
			)
			(layer "F.Fab")
		)
		(fp_line
			(start -0.12065 0.2794)
			(end -0.12065 0.3048)
			(stroke
				(width 0.1)
				(type default)
			)
			(layer "F.Fab")
		)
		(fp_line
			(start -0.12065 -0.2794)
			(end 0.12065 -0.2794)
			(stroke
				(width 0.1)
				(type default)
			)
			(layer "F.Fab")
		)
		(fp_line
			(start -0.12065 -0.305054)
			(end -0.12065 -0.2794)
			(stroke
				(width 0.1)
				(type default)
			)
			(layer "F.Fab")
		)
		(fp_line
			(start -0.67945 0.3048)
			(end -0.67945 -0.305054)
			(stroke
				(width 0.1)
				(type default)
			)
			(layer "F.Fab")
		)
		(fp_line
			(start -0.67945 -0.305054)
			(end -0.12065 -0.305054)
			(stroke
				(width 0.1)
				(type default)
			)
			(layer "F.Fab")
		)
		(pad "1" smd circle
			(at -0.40005 0 180)
			(size 0 0)
			(layers "F.Cu" "F.Mask" "F.Paste")
			(net "SMB_2_BMC_GPU_BUF_R_SDA")
		)
		(pad "2" smd circle
			(at 0.40005 0 180)
			(size 0 0)
			(layers "F.Cu" "F.Mask" "F.Paste")
			(net "SMB_2_BMC_GPU_BUF_SDA")
		)
	)
	(footprint ""
		(layer "F.Cu")
		(at 447.482214 -117.193822)
		(property "Reference" "R1123"
			(at 0 0 0)
			(layer "F.SilkS")
			(hide yes)
			(effects
				(font
					(size 1.27 1.27)
				)
			)
		)
		(property "Value" ""
			(at 0 0 0)
			(layer "F.Fab")
			(effects
				(font
					(size 1.27 1.27)
				)
			)
		)
		(duplicate_pad_numbers_are_jumpers no)
		(fp_line
			(start -0.7874 -0.4064)
			(end 0.7874 -0.4064)
			(stroke
				(width 0.1524)
				(type default)
			)
			(layer "F.SilkS")
		)
		(fp_line
			(start -0.7874 0.4064)
			(end -0.7874 -0.4064)
			(stroke
				(width 0.1524)
				(type default)
			)
			(layer "F.SilkS")
		)
		(fp_line
			(start 0.7874 -0.4064)
			(end 0.7874 0.4064)
			(stroke
				(width 0.1524)
				(type default)
			)
			(layer "F.SilkS")
		)
		(fp_line
			(start 0.7874 0.4064)
			(end -0.7874 0.4064)
			(stroke
				(width 0.1524)
				(type default)
			)
			(layer "F.SilkS")
		)
		(fp_line
			(start -0.67945 -0.305054)
			(end -0.12065 -0.305054)
			(stroke
				(width 0.1)
				(type default)
			)
			(layer "F.Fab")
		)
		(fp_line
			(start -0.67945 0.3048)
			(end -0.67945 -0.305054)
			(stroke
				(width 0.1)
				(type default)
			)
			(layer "F.Fab")
		)
		(fp_line
			(start -0.12065 -0.305054)
			(end -0.12065 -0.2794)
			(stroke
				(width 0.1)
				(type default)
			)
			(layer "F.Fab")
		)
		(fp_line
			(start -0.12065 -0.2794)
			(end 0.12065 -0.2794)
			(stroke
				(width 0.1)
				(type default)
			)
			(layer "F.Fab")
		)
		(fp_line
			(start -0.12065 0.2794)
			(end -0.12065 0.3048)
			(stroke
				(width 0.1)
				(type default)
			)
			(layer "F.Fab")
		)
		(fp_line
			(start -0.12065 0.3048)
			(end -0.67945 0.3048)
			(stroke
				(width 0.1)
				(type default)
			)
			(layer "F.Fab")
		)
		(fp_line
			(start 0.120396 0.2794)
			(end -0.12065 0.2794)
			(stroke
				(width 0.1)
				(type default)
			)
			(layer "F.Fab")
		)
		(fp_line
			(start 0.120396 0.3048)
			(end 0.120396 0.2794)
			(stroke
				(width 0.1)
				(type default)
			)
			(layer "F.Fab")
		)
		(fp_line
			(start 0.12065 -0.3048)
			(end 0.67945 -0.3048)
			(stroke
				(width 0.1)
				(type default)
			)
			(layer "F.Fab")
		)
		(fp_line
			(start 0.12065 -0.2794)
			(end 0.12065 -0.3048)
			(stroke
				(width 0.1)
				(type default)
			)
			(layer "F.Fab")
		)
		(fp_line
			(start 0.67945 -0.3048)
			(end 0.67945 0.3048)
			(stroke
				(width 0.1)
				(type default)
			)
			(layer "F.Fab")
		)
		(fp_line
			(start 0.67945 0.3048)
			(end 0.120396 0.3048)
			(stroke
				(width 0.1)
				(type default)
			)
			(layer "F.Fab")
		)
		(pad "1" smd circle
			(at -0.40005 0)
			(size 0 0)
			(layers "F.Cu" "F.Mask" "F.Paste")
			(net "P3V3_AUX")
		)
		(pad "2" smd circle
			(at 0.40005 0)
			(size 0 0)
			(layers "F.Cu" "F.Mask" "F.Paste")
			(net "PD_SMB_OCP1_HP_ADD2")
		)
	)
	(footprint ""
		(layer "F.Cu")
		(at 428.179992 -391.505948)
		(property "Reference" "Q70"
			(at 0.462788 -1.93675 0)
			(unlocked yes)
			(layer "F.SilkS")
			(effects
				(font
					(size 0.7874 0.5842)
					(thickness 0.1524)
				)
				(justify left)
			)
		)
		(property "Value" ""
			(at 0 0 0)
			(layer "F.Fab")
			(effects
				(font
					(size 1.27 1.27)
				)
			)
		)
		(duplicate_pad_numbers_are_jumpers no)
		(fp_line
			(start -1.332738 -1.100074)
			(end -0.4826 -1.100074)
			(stroke
				(width 0.1524)
				(type default)
			)
			(layer "F.SilkS")
		)
		(fp_line
			(start -1.332738 1.100074)
			(end -1.332738 -1.100074)
			(stroke
				(width 0.1524)
				(type default)
			)
			(layer "F.SilkS")
		)
		(fp_line
			(start -0.4826 -1.100074)
			(end 0 -0.541274)
			(stroke
				(width 0.1524)
				(type default)
			)
			(layer "F.SilkS")
		)
		(fp_line
			(start 0 -0.541274)
			(end 0.4826 -1.100074)
			(stroke
				(width 0.1524)
				(type default)
			)
			(layer "F.SilkS")
		)
		(fp_line
			(start 0.4826 -1.100074)
			(end 1.332738 -1.100074)
			(stroke
				(width 0.1524)
				(type default)
			)
			(layer "F.SilkS")
		)
		(fp_line
			(start 1.332738 -1.100074)
			(end 1.332738 1.100074)
			(stroke
				(width 0.1524)
				(type default)
			)
			(layer "F.SilkS")
		)
		(fp_line
			(start 1.332738 1.100074)
			(end -1.332738 1.100074)
			(stroke
				(width 0.1524)
				(type default)
			)
			(layer "F.SilkS")
		)
		(fp_poly
			(pts
				(xy -0.613918 -2.146808) (xy -0.964946 -1.444752) (xy -1.315974 -2.146808)
			)
			(stroke
				(width 0)
				(type default)
			)
			(fill yes)
			(layer "F.SilkS")
		)
		(fp_line
			(start -0.674878 -1.100074)
			(end 0.674878 -1.100074)
			(stroke
				(width 0.1)
				(type default)
			)
			(layer "F.Fab")
		)
		(fp_line
			(start -0.674878 1.100074)
			(end -0.674878 -1.100074)
			(stroke
				(width 0.1)
				(type default)
			)
			(layer "F.Fab")
		)
		(fp_line
			(start 0.674878 -1.100074)
			(end 0.674878 1.100074)
			(stroke
				(width 0.1)
				(type default)
			)
			(layer "F.Fab")
		)
		(fp_line
			(start 0.674878 1.100074)
			(end -0.674878 1.100074)
			(stroke
				(width 0.1)
				(type default)
			)
			(layer "F.Fab")
		)
		(fp_poly
			(pts
				(xy -2.2352 -0.298958) (xy -2.2352 -1.001014) (xy -1.533144 -0.649986)
			)
			(stroke
				(width 0)
				(type default)
			)
			(fill yes)
			(layer "F.Fab")
		)
		(pad "1" smd rect
			(at -0.94996 -0.649986 90)
			(size 0.4318 0.508)
			(layers "F.Cu" "F.Mask" "F.Paste")
			(net "GND")
		)
		(pad "2" smd rect
			(at -0.94996 0 90)
			(size 0.4318 0.508)
			(layers "F.Cu" "F.Mask" "F.Paste")
			(net "FM_SWB_BIC_READY_N")
		)
		(pad "3" smd rect
			(at -0.94996 0.649986 90)
			(size 0.4318 0.508)
			(layers "F.Cu" "F.Mask" "F.Paste")
			(net "FM_SWB_BIC_READY_ISO_N")
		)
		(pad "4" smd rect
			(at 0.94996 0.649986 90)
			(size 0.4318 0.508)
			(layers "F.Cu" "F.Mask" "F.Paste")
			(net "GND")
		)
		(pad "5" smd rect
			(at 0.94996 0 90)
			(size 0.4318 0.508)
			(layers "F.Cu" "F.Mask" "F.Paste")
			(net "FM_SWB_BIC_READY")
		)
		(pad "6" smd rect
			(at 0.94996 -0.649986 90)
			(size 0.4318 0.508)
			(layers "F.Cu" "F.Mask" "F.Paste")
			(net "FM_SWB_BIC_READY")
		)
	)
	(footprint ""
		(layer "F.Cu")
		(at 116.13388 -407.16073 -90)
		(property "Reference" "Q67"
			(at 0.973836 1.916176 90)
			(unlocked yes)
			(layer "F.SilkS")
			(effects
				(font
					(size 0.7874 0.5842)
					(thickness 0.1524)
				)
				(justify left)
			)
		)
		(property "Value" ""
			(at 0 0 270)
			(layer "F.Fab")
			(effects
				(font
					(size 1.27 1.27)
				)
			)
		)
		(duplicate_pad_numbers_are_jumpers no)
		(fp_line
			(start -1.332738 1.100074)
			(end -1.332738 -1.100074)
			(stroke
				(width 0.1524)
				(type default)
			)
			(layer "F.SilkS")
		)
		(fp_line
			(start 1.332738 1.100074)
			(end -1.332738 1.100074)
			(stroke
				(width 0.1524)
				(type default)
			)
			(layer "F.SilkS")
		)
		(fp_line
			(start 0 -0.541274)
			(end 0.4826 -1.100074)
			(stroke
				(width 0.1524)
				(type default)
			)
			(layer "F.SilkS")
		)
		(fp_line
			(start -1.332738 -1.100074)
			(end -0.4826 -1.100074)
			(stroke
				(width 0.1524)
				(type default)
			)
			(layer "F.SilkS")
		)
		(fp_line
			(start -0.4826 -1.100074)
			(end 0 -0.541274)
			(stroke
				(width 0.1524)
				(type default)
			)
			(layer "F.SilkS")
		)
		(fp_line
			(start 0.4826 -1.100074)
			(end 1.332738 -1.100074)
			(stroke
				(width 0.1524)
				(type default)
			)
			(layer "F.SilkS")
		)
		(fp_line
			(start 1.332738 -1.100074)
			(end 1.332738 1.100074)
			(stroke
				(width 0.1524)
				(type default)
			)
			(layer "F.SilkS")
		)
		(fp_poly
			(pts
				(xy -1.72974 -1.81737) (xy -1.481582 -1.072896) (xy -2.226056 -1.321054)
			)
			(stroke
				(width 0)
				(type default)
			)
			(fill yes)
			(layer "F.SilkS")
		)
		(fp_line
			(start -0.674878 1.100074)
			(end -0.674878 -1.100074)
			(stroke
				(width 0.1)
				(type default)
			)
			(layer "F.Fab")
		)
		(fp_line
			(start 0.674878 1.100074)
			(end -0.674878 1.100074)
			(stroke
				(width 0.1)
				(type default)
			)
			(layer "F.Fab")
		)
		(fp_line
			(start -0.674878 -1.100074)
			(end 0.674878 -1.100074)
			(stroke
				(width 0.1)
				(type default)
			)
			(layer "F.Fab")
		)
		(fp_line
			(start 0.674878 -1.100074)
			(end 0.674878 1.100074)
			(stroke
				(width 0.1)
				(type default)
			)
			(layer "F.Fab")
		)
		(fp_poly
			(pts
				(xy -2.2352 -0.298958) (xy -2.2352 -1.001014) (xy -1.533144 -0.649986)
			)
			(stroke
				(width 0)
				(type default)
			)
			(fill yes)
			(layer "F.Fab")
		)
		(pad "1" smd rect
			(at -0.94996 -0.649986)
			(size 0.4318 0.508)
			(layers "F.Cu" "F.Mask" "F.Paste")
			(net "GND")
		)
		(pad "2" smd rect
			(at -0.94996 0)
			(size 0.4318 0.508)
			(layers "F.Cu" "F.Mask" "F.Paste")
			(net "BIC_MONITER")
		)
		(pad "3" smd rect
			(at -0.94996 0.649986)
			(size 0.4318 0.508)
			(layers "F.Cu" "F.Mask" "F.Paste")
			(net "BIC_MONITER_ISO")
		)
		(pad "4" smd rect
			(at 0.94996 0.649986)
			(size 0.4318 0.508)
			(layers "F.Cu" "F.Mask" "F.Paste")
			(net "GND")
		)
		(pad "5" smd rect
			(at 0.94996 0)
			(size 0.4318 0.508)
			(layers "F.Cu" "F.Mask" "F.Paste")
			(net "BIC_MONITER_N")
		)
		(pad "6" smd rect
			(at 0.94996 -0.649986)
			(size 0.4318 0.508)
			(layers "F.Cu" "F.Mask" "F.Paste")
			(net "BIC_MONITER_N")
		)
	)
	(footprint ""
		(layer "F.Cu")
		(at 49.57318 -171.473368 180)
		(property "Reference" "PR4249"
			(at 0 0 180)
			(layer "F.SilkS")
			(hide yes)
			(effects
				(font
					(size 1.27 1.27)
				)
			)
		)
		(property "Value" ""
			(at 0 0 180)
			(layer "F.Fab")
			(effects
				(font
					(size 1.27 1.27)
				)
			)
		)
		(duplicate_pad_numbers_are_jumpers no)
		(fp_line
			(start 0.7874 0.4064)
			(end -0.7874 0.4064)
			(stroke
				(width 0.1524)
				(type default)
			)
			(layer "F.SilkS")
		)
		(fp_line
			(start 0.7874 -0.4064)
			(end 0.7874 0.4064)
			(stroke
				(width 0.1524)
				(type default)
			)
			(layer "F.SilkS")
		)
		(fp_line
			(start -0.7874 0.4064)
			(end -0.7874 -0.4064)
			(stroke
				(width 0.1524)
				(type default)
			)
			(layer "F.SilkS")
		)
		(fp_line
			(start -0.7874 -0.4064)
			(end 0.7874 -0.4064)
			(stroke
				(width 0.1524)
				(type default)
			)
			(layer "F.SilkS")
		)
		(fp_line
			(start 0.67945 0.3048)
			(end 0.120396 0.3048)
			(stroke
				(width 0.1)
				(type default)
			)
			(layer "F.Fab")
		)
		(fp_line
			(start 0.67945 -0.3048)
			(end 0.67945 0.3048)
			(stroke
				(width 0.1)
				(type default)
			)
			(layer "F.Fab")
		)
		(fp_line
			(start 0.12065 -0.2794)
			(end 0.12065 -0.3048)
			(stroke
				(width 0.1)
				(type default)
			)
			(layer "F.Fab")
		)
		(fp_line
			(start 0.12065 -0.3048)
			(end 0.67945 -0.3048)
			(stroke
				(width 0.1)
				(type default)
			)
			(layer "F.Fab")
		)
		(fp_line
			(start 0.120396 0.3048)
			(end 0.120396 0.2794)
			(stroke
				(width 0.1)
				(type default)
			)
			(layer "F.Fab")
		)
		(fp_line
			(start 0.120396 0.2794)
			(end -0.12065 0.2794)
			(stroke
				(width 0.1)
				(type default)
			)
			(layer "F.Fab")
		)
		(fp_line
			(start -0.12065 0.3048)
			(end -0.67945 0.3048)
			(stroke
				(width 0.1)
				(type default)
			)
			(layer "F.Fab")
		)
		(fp_line
			(start -0.12065 0.2794)
			(end -0.12065 0.3048)
			(stroke
				(width 0.1)
				(type default)
			)
			(layer "F.Fab")
		)
		(fp_line
			(start -0.12065 -0.2794)
			(end 0.12065 -0.2794)
			(stroke
				(width 0.1)
				(type default)
			)
			(layer "F.Fab")
		)
		(fp_line
			(start -0.12065 -0.305054)
			(end -0.12065 -0.2794)
			(stroke
				(width 0.1)
				(type default)
			)
			(layer "F.Fab")
		)
		(fp_line
			(start -0.67945 0.3048)
			(end -0.67945 -0.305054)
			(stroke
				(width 0.1)
				(type default)
			)
			(layer "F.Fab")
		)
		(fp_line
			(start -0.67945 -0.305054)
			(end -0.12065 -0.305054)
			(stroke
				(width 0.1)
				(type default)
			)
			(layer "F.Fab")
		)
		(pad "1" smd circle
			(at -0.40005 0 180)
			(size 0 0)
			(layers "F.Cu" "F.Mask" "F.Paste")
			(net "PVCCFA_EHV_CPU1_FAULT")
		)
		(pad "2" smd circle
			(at 0.40005 0 180)
			(size 0 0)
			(layers "F.Cu" "F.Mask" "F.Paste")
			(net "GND")
		)
	)
	(footprint ""
		(layer "F.Cu")
		(at 367.44783 -251.375418 90)
		(property "Reference" "C1044"
			(at 0 0 90)
			(layer "F.SilkS")
			(hide yes)
			(effects
				(font
					(size 1.27 1.27)
				)
			)
		)
		(property "Value" ""
			(at 0 0 90)
			(layer "F.Fab")
			(effects
				(font
					(size 1.27 1.27)
				)
			)
		)
		(duplicate_pad_numbers_are_jumpers no)
		(fp_line
			(start 0.7874 -0.4064)
			(end 0.7874 0.4064)
			(stroke
				(width 0.1524)
				(type default)
			)
			(layer "F.SilkS")
		)
		(fp_line
			(start -0.7874 -0.4064)
			(end 0.7874 -0.4064)
			(stroke
				(width 0.1524)
				(type default)
			)
			(layer "F.SilkS")
		)
		(fp_line
			(start 0.7874 0.4064)
			(end -0.7874 0.4064)
			(stroke
				(width 0.1524)
				(type default)
			)
			(layer "F.SilkS")
		)
		(fp_line
			(start -0.7874 0.4064)
			(end -0.7874 -0.4064)
			(stroke
				(width 0.1524)
				(type default)
			)
			(layer "F.SilkS")
		)
		(fp_line
			(start -0.12065 -0.305054)
			(end -0.12065 -0.2794)
			(stroke
				(width 0.1)
				(type default)
			)
			(layer "F.Fab")
		)
		(fp_line
			(start -0.67945 -0.305054)
			(end -0.12065 -0.305054)
			(stroke
				(width 0.1)
				(type default)
			)
			(layer "F.Fab")
		)
		(fp_line
			(start 0.67945 -0.3048)
			(end 0.67945 0.3048)
			(stroke
				(width 0.1)
				(type default)
			)
			(layer "F.Fab")
		)
		(fp_line
			(start 0.12065 -0.3048)
			(end 0.67945 -0.3048)
			(stroke
				(width 0.1)
				(type default)
			)
			(layer "F.Fab")
		)
		(fp_line
			(start 0.12065 -0.2794)
			(end 0.12065 -0.3048)
			(stroke
				(width 0.1)
				(type default)
			)
			(layer "F.Fab")
		)
		(fp_line
			(start -0.12065 -0.2794)
			(end 0.12065 -0.2794)
			(stroke
				(width 0.1)
				(type default)
			)
			(layer "F.Fab")
		)
		(fp_line
			(start 0.120396 0.2794)
			(end -0.12065 0.2794)
			(stroke
				(width 0.1)
				(type default)
			)
			(layer "F.Fab")
		)
		(fp_line
			(start -0.12065 0.2794)
			(end -0.12065 0.3048)
			(stroke
				(width 0.1)
				(type default)
			)
			(layer "F.Fab")
		)
		(fp_line
			(start 0.67945 0.3048)
			(end 0.120396 0.3048)
			(stroke
				(width 0.1)
				(type default)
			)
			(layer "F.Fab")
		)
		(fp_line
			(start 0.120396 0.3048)
			(end 0.120396 0.2794)
			(stroke
				(width 0.1)
				(type default)
			)
			(layer "F.Fab")
		)
		(fp_line
			(start -0.12065 0.3048)
			(end -0.67945 0.3048)
			(stroke
				(width 0.1)
				(type default)
			)
			(layer "F.Fab")
		)
		(fp_line
			(start -0.67945 0.3048)
			(end -0.67945 -0.305054)
			(stroke
				(width 0.1)
				(type default)
			)
			(layer "F.Fab")
		)
		(pad "1" smd circle
			(at -0.40005 0 90)
			(size 0 0)
			(layers "F.Cu" "F.Mask" "F.Paste")
			(net "PVCCIN_CPU0")
		)
		(pad "2" smd circle
			(at 0.40005 0 90)
			(size 0 0)
			(layers "F.Cu" "F.Mask" "F.Paste")
			(net "GND")
		)
	)
	(footprint ""
		(layer "F.Cu")
		(at 425.84878 -362.087668)
		(property "Reference" "PU71_P0_3"
			(at 8.44042 -2.23647 0)
			(unlocked yes)
			(layer "F.SilkS")
			(effects
				(font
					(size 0.7874 0.5842)
					(thickness 0.1524)
				)
				(justify left)
			)
		)
		(property "Value" ""
			(at 0 0 0)
			(layer "F.Fab")
			(effects
				(font
					(size 1.27 1.27)
				)
			)
		)
		(duplicate_pad_numbers_are_jumpers no)
		(fp_line
			(start -2.500122 -2.999994)
			(end -2.24409 -2.999994)
			(stroke
				(width 0.1524)
				(type default)
			)
			(layer "F.SilkS")
		)
		(fp_line
			(start -2.500122 -2.529078)
			(end -2.500122 -2.999994)
			(stroke
				(width 0.1524)
				(type default)
			)
			(layer "F.SilkS")
		)
		(fp_line
			(start -2.500122 0.6604)
			(end -2.500122 0.229108)
			(stroke
				(width 0.1524)
				(type default)
			)
			(layer "F.SilkS")
		)
		(fp_line
			(start -2.500122 2.999994)
			(end -2.500122 2.339594)
			(stroke
				(width 0.1524)
				(type default)
			)
			(layer "F.SilkS")
		)
		(fp_line
			(start -2.2987 2.999994)
			(end -2.500122 2.999994)
			(stroke
				(width 0.1524)
				(type default)
			)
			(layer "F.SilkS")
		)
		(fp_line
			(start 2.31394 -2.999994)
			(end 2.500122 -2.999994)
			(stroke
				(width 0.1524)
				(type default)
			)
			(layer "F.SilkS")
		)
		(fp_line
			(start 2.500122 -2.999994)
			(end 2.500122 -2.44348)
			(stroke
				(width 0.1524)
				(type default)
			)
			(layer "F.SilkS")
		)
		(fp_line
			(start 2.500122 2.339594)
			(end 2.500122 2.999994)
			(stroke
				(width 0.1524)
				(type default)
			)
			(layer "F.SilkS")
		)
		(fp_line
			(start 2.500122 2.999994)
			(end 2.2987 2.999994)
			(stroke
				(width 0.1524)
				(type default)
			)
			(layer "F.SilkS")
		)
		(fp_poly
			(pts
				(xy -2.218182 -3.583432) (xy -2.726182 -2.567432) (xy -3.234182 -3.583432)
			)
			(stroke
				(width 0)
				(type default)
			)
			(fill yes)
			(layer "F.SilkS")
		)
		(fp_line
			(start -2.500122 -2.999994)
			(end 2.500122 -2.999994)
			(stroke
				(width 0.1)
				(type default)
			)
			(layer "F.Fab")
		)
		(fp_line
			(start -2.500122 2.999994)
			(end -2.500122 -2.999994)
			(stroke
				(width 0.1)
				(type default)
			)
			(layer "F.Fab")
		)
		(fp_line
			(start 2.500122 -2.999994)
			(end 2.500122 2.999994)
			(stroke
				(width 0.1)
				(type default)
			)
			(layer "F.Fab")
		)
		(fp_line
			(start 2.500122 2.999994)
			(end -2.500122 2.999994)
			(stroke
				(width 0.1)
				(type default)
			)
			(layer "F.Fab")
		)
		(fp_poly
			(pts
				(xy -4.218432 -2.783078) (xy -4.218432 -1.767078) (xy -3.202432 -2.275078)
			)
			(stroke
				(width 0)
				(type default)
			)
			(fill yes)
			(layer "F.Fab")
		)
		(pad "1" smd rect
			(at -2.400046 -2.275078 90)
			(size 0.2286 0.6096)
			(layers "F.Cu" "F.Mask" "F.Paste")
			(net "PVCCFA_EHV_FIVRA_CPU0_VOS3")
		)
		(pad "2" smd rect
			(at -2.400046 -1.82499 90)
			(size 0.2286 0.6096)
			(layers "F.Cu" "F.Mask" "F.Paste")
			(net "GND")
		)
		(pad "3" smd rect
			(at -2.400046 -1.374902 90)
			(size 0.2286 0.6096)
			(layers "F.Cu" "F.Mask" "F.Paste")
			(net "PVCCFA_EHV_FIVRA_CPU0_VDD3")
		)
		(pad "4" smd rect
			(at -2.400046 -0.925068 90)
			(size 0.2286 0.6096)
			(layers "F.Cu" "F.Mask" "F.Paste")
			(net "PVCCFA_EHV_FIVRA_CPU0_PVCC1")
		)
		(pad "5" smd rect
			(at -2.400046 -0.47498 90)
			(size 0.2286 0.6096)
			(layers "F.Cu" "F.Mask" "F.Paste")
			(net "GND")
		)
		(pad "6" smd rect
			(at -2.400046 -0.024892 90)
			(size 0.2286 0.6096)
			(layers "F.Cu" "F.Mask" "F.Paste")
			(net "Net_8511")
		)
		(pad "7_9-20_24" smd circle
			(at 0 1.150112 90)
			(size 0 0)
			(layers "F.Cu" "F.Mask" "F.Paste")
			(net "GND")
		)
		(pad "10_19" smd rect
			(at 0 2.899918 90)
			(size 0.6096 4.318)
			(layers "F.Cu" "F.Mask" "F.Paste")
			(net "SW_PVCCFA_EHV_FIVRA_CPU0_SW3")
		)
		(pad "25_29" smd rect
			(at 1.549908 -1.279906 270)
			(size 2.0574 2.3114)
			(layers "F.Cu" "F.Mask" "F.Paste")
			(net "SW_P12V_PVCCFA_EHV_FIVRA_CPU0_R")
		)
		(pad "30" smd rect
			(at 2.05994 -2.899918)
			(size 0.2286 0.6096)
			(layers "F.Cu" "F.Mask" "F.Paste")
			(net "SW_P12V_PVCCFA_EHV_FIVRA_CPU0_R")
		)
		(pad "31" smd rect
			(at 1.610106 -2.899918)
			(size 0.2286 0.6096)
			(layers "F.Cu" "F.Mask" "F.Paste")
			(net "Net_8512")
		)
		(pad "32" smd rect
			(at 1.160018 -2.899918)
			(size 0.2286 0.6096)
			(layers "F.Cu" "F.Mask" "F.Paste")
			(net "SW_PVCCFA_EHV_FIVRA_CPU0_BOOTR3")
		)
		(pad "33" smd rect
			(at 0.70993 -2.899918)
			(size 0.2286 0.6096)
			(layers "F.Cu" "F.Mask" "F.Paste")
			(net "SW_PVCCFA_EHV_FIVRA_CPU0_BOOT3")
		)
		(pad "34" smd rect
			(at 0.260096 -2.899918)
			(size 0.2286 0.6096)
			(layers "F.Cu" "F.Mask" "F.Paste")
			(net "PVCCFA_EHV_FIVRA_CPU0_PWM3")
		)
		(pad "35" smd rect
			(at -0.189992 -2.899918)
			(size 0.2286 0.6096)
			(layers "F.Cu" "F.Mask" "F.Paste")
			(net "PVCCFA_EHV_FIVRA_CPU0_VDD3")
		)
		(pad "36" smd rect
			(at -0.64008 -2.899918)
			(size 0.2286 0.6096)
			(layers "F.Cu" "F.Mask" "F.Paste")
			(net "PVCCFA_EHV_FIVRA_CPU0_BTSEN")
		)
		(pad "37" smd rect
			(at -1.089914 -2.899918)
			(size 0.2286 0.6096)
			(layers "F.Cu" "F.Mask" "F.Paste")
			(net "PVCCFA_EHV_FIVRA_CPU0_LSET3")
		)
		(pad "38" smd rect
			(at -1.540002 -2.899918)
			(size 0.2286 0.6096)
			(layers "F.Cu" "F.Mask" "F.Paste")
			(net "PVCCFA_EHV_FIVRA_CPU0_IMON3")
		)
		(pad "39" smd rect
			(at -1.99009 -2.899918)
			(size 0.2286 0.6096)
			(layers "F.Cu" "F.Mask" "F.Paste")
			(net "PVCCIN_CPU0_VREF")
		)
		(pad "40" smd rect
			(at -0.87503 -1.27508)
			(size 1.7526 1.9558)
			(layers "F.Cu" "F.Mask" "F.Paste")
			(net "GND")
		)
		(pad "41" smd rect
			(at -1.525016 0.249936 270)
			(size 0.3048 0.4572)
			(layers "F.Cu" "F.Mask" "F.Paste")
			(net "Net_8510")
		)
		(zone
			(layer "F.Cu")
			(hatch none 0.5)
			(connect_pads
				(clearance 0)
			)
			(min_thickness 0.25)
			(keepout
				(tracks not_allowed)
				(vias allowed)
				(pads allowed)
				(copperpour not_allowed)
				(footprints allowed)
			)
			(placement
				(enabled no)
				(sheetname "")
			)
			(fill
				(thermal_gap 0.5)
				(thermal_bridge_width 0.5)
				(island_removal_mode 0)
			)
			(polygon
				(pts
					(xy 423.348658 -359.087674) (xy 423.348658 -359.836974) (xy 428.348902 -359.836974) (xy 428.348902 -359.087674)
					(xy 428.05858 -359.087674) (xy 428.05858 -359.54335) (xy 423.63898 -359.54335) (xy 423.63898 -359.087674)
				)
			)
		)
		(zone
			(layer "F.Cu")
			(hatch none 0.5)
			(connect_pads
				(clearance 0)
			)
			(min_thickness 0.25)
			(keepout
				(tracks not_allowed)
				(vias allowed)
				(pads allowed)
				(copperpour not_allowed)
				(footprints allowed)
			)
			(placement
				(enabled no)
				(sheetname "")
			)
			(fill
				(thermal_gap 0.5)
				(thermal_bridge_width 0.5)
				(island_removal_mode 0)
			)
			(polygon
				(pts
					(xy 424.07332 -362.334048) (xy 424.82262 -362.334048) (xy 424.82262 -362.016548) (xy 424.898058 -362.016548)
					(xy 424.898058 -361.385866) (xy 424.85056 -361.338368) (xy 423.348658 -361.338368) (xy 423.348658 -361.79506)
					(xy 424.044364 -361.79506) (xy 424.044364 -361.634532) (xy 424.603164 -361.634532) (xy 424.603164 -362.040932)
					(xy 424.044364 -362.040932) (xy 424.044364 -361.82046) (xy 423.348658 -361.82046) (xy 423.348658 -361.94746)
					(xy 423.804334 -361.94746) (xy 423.804334 -362.311188) (xy 424.07332 -362.311188)
				)
			)
		)
	)
	(footprint ""
		(layer "F.Cu")
		(at 164.64788 -121.376948 180)
		(property "Reference" "R1401"
			(at 0 0 180)
			(layer "F.SilkS")
			(hide yes)
			(effects
				(font
					(size 1.27 1.27)
				)
			)
		)
		(property "Value" ""
			(at 0 0 180)
			(layer "F.Fab")
			(effects
				(font
					(size 1.27 1.27)
				)
			)
		)
		(duplicate_pad_numbers_are_jumpers no)
		(fp_line
			(start 0.7874 0.4064)
			(end -0.7874 0.4064)
			(stroke
				(width 0.1524)
				(type default)
			)
			(layer "F.SilkS")
		)
		(fp_line
			(start 0.7874 -0.4064)
			(end 0.7874 0.4064)
			(stroke
				(width 0.1524)
				(type default)
			)
			(layer "F.SilkS")
		)
		(fp_line
			(start -0.7874 0.4064)
			(end -0.7874 -0.4064)
			(stroke
				(width 0.1524)
				(type default)
			)
			(layer "F.SilkS")
		)
		(fp_line
			(start -0.7874 -0.4064)
			(end 0.7874 -0.4064)
			(stroke
				(width 0.1524)
				(type default)
			)
			(layer "F.SilkS")
		)
		(fp_line
			(start 0.67945 0.3048)
			(end 0.120396 0.3048)
			(stroke
				(width 0.1)
				(type default)
			)
			(layer "F.Fab")
		)
		(fp_line
			(start 0.67945 -0.3048)
			(end 0.67945 0.3048)
			(stroke
				(width 0.1)
				(type default)
			)
			(layer "F.Fab")
		)
		(fp_line
			(start 0.12065 -0.2794)
			(end 0.12065 -0.3048)
			(stroke
				(width 0.1)
				(type default)
			)
			(layer "F.Fab")
		)
		(fp_line
			(start 0.12065 -0.3048)
			(end 0.67945 -0.3048)
			(stroke
				(width 0.1)
				(type default)
			)
			(layer "F.Fab")
		)
		(fp_line
			(start 0.120396 0.3048)
			(end 0.120396 0.2794)
			(stroke
				(width 0.1)
				(type default)
			)
			(layer "F.Fab")
		)
		(fp_line
			(start 0.120396 0.2794)
			(end -0.12065 0.2794)
			(stroke
				(width 0.1)
				(type default)
			)
			(layer "F.Fab")
		)
		(fp_line
			(start -0.12065 0.3048)
			(end -0.67945 0.3048)
			(stroke
				(width 0.1)
				(type default)
			)
			(layer "F.Fab")
		)
		(fp_line
			(start -0.12065 0.2794)
			(end -0.12065 0.3048)
			(stroke
				(width 0.1)
				(type default)
			)
			(layer "F.Fab")
		)
		(fp_line
			(start -0.12065 -0.2794)
			(end 0.12065 -0.2794)
			(stroke
				(width 0.1)
				(type default)
			)
			(layer "F.Fab")
		)
		(fp_line
			(start -0.12065 -0.305054)
			(end -0.12065 -0.2794)
			(stroke
				(width 0.1)
				(type default)
			)
			(layer "F.Fab")
		)
		(fp_line
			(start -0.67945 0.3048)
			(end -0.67945 -0.305054)
			(stroke
				(width 0.1)
				(type default)
			)
			(layer "F.Fab")
		)
		(fp_line
			(start -0.67945 -0.305054)
			(end -0.12065 -0.305054)
			(stroke
				(width 0.1)
				(type default)
			)
			(layer "F.Fab")
		)
		(pad "1" smd circle
			(at -0.40005 0 180)
			(size 0 0)
			(layers "F.Cu" "F.Mask" "F.Paste")
			(net "PU_MAIN_FPGA_CONFIG_DONE")
		)
		(pad "2" smd circle
			(at 0.40005 0 180)
			(size 0 0)
			(layers "F.Cu" "F.Mask" "F.Paste")
			(net "P3V3_AUX")
		)
	)
	(footprint ""
		(layer "F.Cu")
		(at 103.1367 -393.685268 180)
		(property "Reference" "C1963"
			(at 0 0 180)
			(layer "F.SilkS")
			(hide yes)
			(effects
				(font
					(size 1.27 1.27)
				)
			)
		)
		(property "Value" ""
			(at 0 0 180)
			(layer "F.Fab")
			(effects
				(font
					(size 1.27 1.27)
				)
			)
		)
		(duplicate_pad_numbers_are_jumpers no)
		(fp_line
			(start 0.7874 0.4064)
			(end -0.7874 0.4064)
			(stroke
				(width 0.1524)
				(type default)
			)
			(layer "F.SilkS")
		)
		(fp_line
			(start 0.7874 -0.4064)
			(end 0.7874 0.4064)
			(stroke
				(width 0.1524)
				(type default)
			)
			(layer "F.SilkS")
		)
		(fp_line
			(start -0.7874 0.4064)
			(end -0.7874 -0.4064)
			(stroke
				(width 0.1524)
				(type default)
			)
			(layer "F.SilkS")
		)
		(fp_line
			(start -0.7874 -0.4064)
			(end 0.7874 -0.4064)
			(stroke
				(width 0.1524)
				(type default)
			)
			(layer "F.SilkS")
		)
		(fp_line
			(start 0.67945 0.3048)
			(end 0.120396 0.3048)
			(stroke
				(width 0.1)
				(type default)
			)
			(layer "F.Fab")
		)
		(fp_line
			(start 0.67945 -0.3048)
			(end 0.67945 0.3048)
			(stroke
				(width 0.1)
				(type default)
			)
			(layer "F.Fab")
		)
		(fp_line
			(start 0.12065 -0.2794)
			(end 0.12065 -0.3048)
			(stroke
				(width 0.1)
				(type default)
			)
			(layer "F.Fab")
		)
		(fp_line
			(start 0.12065 -0.3048)
			(end 0.67945 -0.3048)
			(stroke
				(width 0.1)
				(type default)
			)
			(layer "F.Fab")
		)
		(fp_line
			(start 0.120396 0.3048)
			(end 0.120396 0.2794)
			(stroke
				(width 0.1)
				(type default)
			)
			(layer "F.Fab")
		)
		(fp_line
			(start 0.120396 0.2794)
			(end -0.12065 0.2794)
			(stroke
				(width 0.1)
				(type default)
			)
			(layer "F.Fab")
		)
		(fp_line
			(start -0.12065 0.3048)
			(end -0.67945 0.3048)
			(stroke
				(width 0.1)
				(type default)
			)
			(layer "F.Fab")
		)
		(fp_line
			(start -0.12065 0.2794)
			(end -0.12065 0.3048)
			(stroke
				(width 0.1)
				(type default)
			)
			(layer "F.Fab")
		)
		(fp_line
			(start -0.12065 -0.2794)
			(end 0.12065 -0.2794)
			(stroke
				(width 0.1)
				(type default)
			)
			(layer "F.Fab")
		)
		(fp_line
			(start -0.12065 -0.305054)
			(end -0.12065 -0.2794)
			(stroke
				(width 0.1)
				(type default)
			)
			(layer "F.Fab")
		)
		(fp_line
			(start -0.67945 0.3048)
			(end -0.67945 -0.305054)
			(stroke
				(width 0.1)
				(type default)
			)
			(layer "F.Fab")
		)
		(fp_line
			(start -0.67945 -0.305054)
			(end -0.12065 -0.305054)
			(stroke
				(width 0.1)
				(type default)
			)
			(layer "F.Fab")
		)
		(pad "1" smd circle
			(at -0.40005 0 180)
			(size 0 0)
			(layers "F.Cu" "F.Mask" "F.Paste")
			(net "P3V3_AUX")
		)
		(pad "2" smd circle
			(at 0.40005 0 180)
			(size 0 0)
			(layers "F.Cu" "F.Mask" "F.Paste")
			(net "GND")
		)
	)
	(footprint ""
		(layer "F.Cu")
		(at 432.41468 -176.61382)
		(property "Reference" "PR50"
			(at 0 0 0)
			(layer "F.SilkS")
			(hide yes)
			(effects
				(font
					(size 1.27 1.27)
				)
			)
		)
		(property "Value" ""
			(at 0 0 0)
			(layer "F.Fab")
			(effects
				(font
					(size 1.27 1.27)
				)
			)
		)
		(duplicate_pad_numbers_are_jumpers no)
		(fp_line
			(start -0.7874 -0.4064)
			(end 0.7874 -0.4064)
			(stroke
				(width 0.1524)
				(type default)
			)
			(layer "F.SilkS")
		)
		(fp_line
			(start -0.7874 0.4064)
			(end -0.7874 -0.4064)
			(stroke
				(width 0.1524)
				(type default)
			)
			(layer "F.SilkS")
		)
		(fp_line
			(start 0.7874 -0.4064)
			(end 0.7874 0.4064)
			(stroke
				(width 0.1524)
				(type default)
			)
			(layer "F.SilkS")
		)
		(fp_line
			(start 0.7874 0.4064)
			(end -0.7874 0.4064)
			(stroke
				(width 0.1524)
				(type default)
			)
			(layer "F.SilkS")
		)
		(fp_line
			(start -0.67945 -0.305054)
			(end -0.12065 -0.305054)
			(stroke
				(width 0.1)
				(type default)
			)
			(layer "F.Fab")
		)
		(fp_line
			(start -0.67945 0.3048)
			(end -0.67945 -0.305054)
			(stroke
				(width 0.1)
				(type default)
			)
			(layer "F.Fab")
		)
		(fp_line
			(start -0.12065 -0.305054)
			(end -0.12065 -0.2794)
			(stroke
				(width 0.1)
				(type default)
			)
			(layer "F.Fab")
		)
		(fp_line
			(start -0.12065 -0.2794)
			(end 0.12065 -0.2794)
			(stroke
				(width 0.1)
				(type default)
			)
			(layer "F.Fab")
		)
		(fp_line
			(start -0.12065 0.2794)
			(end -0.12065 0.3048)
			(stroke
				(width 0.1)
				(type default)
			)
			(layer "F.Fab")
		)
		(fp_line
			(start -0.12065 0.3048)
			(end -0.67945 0.3048)
			(stroke
				(width 0.1)
				(type default)
			)
			(layer "F.Fab")
		)
		(fp_line
			(start 0.120396 0.2794)
			(end -0.12065 0.2794)
			(stroke
				(width 0.1)
				(type default)
			)
			(layer "F.Fab")
		)
		(fp_line
			(start 0.120396 0.3048)
			(end 0.120396 0.2794)
			(stroke
				(width 0.1)
				(type default)
			)
			(layer "F.Fab")
		)
		(fp_line
			(start 0.12065 -0.3048)
			(end 0.67945 -0.3048)
			(stroke
				(width 0.1)
				(type default)
			)
			(layer "F.Fab")
		)
		(fp_line
			(start 0.12065 -0.2794)
			(end 0.12065 -0.3048)
			(stroke
				(width 0.1)
				(type default)
			)
			(layer "F.Fab")
		)
		(fp_line
			(start 0.67945 -0.3048)
			(end 0.67945 0.3048)
			(stroke
				(width 0.1)
				(type default)
			)
			(layer "F.Fab")
		)
		(fp_line
			(start 0.67945 0.3048)
			(end 0.120396 0.3048)
			(stroke
				(width 0.1)
				(type default)
			)
			(layer "F.Fab")
		)
		(pad "1" smd circle
			(at -0.40005 0)
			(size 0 0)
			(layers "F.Cu" "F.Mask" "F.Paste")
			(net "PVNN_MAIN_CPU0_FB")
		)
		(pad "2" smd circle
			(at 0.40005 0)
			(size 0 0)
			(layers "F.Cu" "F.Mask" "F.Paste")
			(net "GND")
		)
	)
	(footprint ""
		(layer "F.Cu")
		(at 102.355142 -338.290662 -90)
		(property "Reference" "PC1338"
			(at 0 0 270)
			(layer "F.SilkS")
			(hide yes)
			(effects
				(font
					(size 1.27 1.27)
				)
			)
		)
		(property "Value" ""
			(at 0 0 270)
			(layer "F.Fab")
			(effects
				(font
					(size 1.27 1.27)
				)
			)
		)
		(duplicate_pad_numbers_are_jumpers no)
		(fp_line
			(start -0.7874 0.4064)
			(end -0.7874 -0.4064)
			(stroke
				(width 0.1524)
				(type default)
			)
			(layer "F.SilkS")
		)
		(fp_line
			(start 0.7874 0.4064)
			(end -0.7874 0.4064)
			(stroke
				(width 0.1524)
				(type default)
			)
			(layer "F.SilkS")
		)
		(fp_line
			(start -0.7874 -0.4064)
			(end 0.7874 -0.4064)
			(stroke
				(width 0.1524)
				(type default)
			)
			(layer "F.SilkS")
		)
		(fp_line
			(start 0.7874 -0.4064)
			(end 0.7874 0.4064)
			(stroke
				(width 0.1524)
				(type default)
			)
			(layer "F.SilkS")
		)
		(fp_line
			(start -0.67945 0.3048)
			(end -0.67945 -0.305054)
			(stroke
				(width 0.1)
				(type default)
			)
			(layer "F.Fab")
		)
		(fp_line
			(start -0.12065 0.3048)
			(end -0.67945 0.3048)
			(stroke
				(width 0.1)
				(type default)
			)
			(layer "F.Fab")
		)
		(fp_line
			(start 0.120396 0.3048)
			(end 0.120396 0.2794)
			(stroke
				(width 0.1)
				(type default)
			)
			(layer "F.Fab")
		)
		(fp_line
			(start 0.67945 0.3048)
			(end 0.120396 0.3048)
			(stroke
				(width 0.1)
				(type default)
			)
			(layer "F.Fab")
		)
		(fp_line
			(start -0.12065 0.2794)
			(end -0.12065 0.3048)
			(stroke
				(width 0.1)
				(type default)
			)
			(layer "F.Fab")
		)
		(fp_line
			(start 0.120396 0.2794)
			(end -0.12065 0.2794)
			(stroke
				(width 0.1)
				(type default)
			)
			(layer "F.Fab")
		)
		(fp_line
			(start -0.12065 -0.2794)
			(end 0.12065 -0.2794)
			(stroke
				(width 0.1)
				(type default)
			)
			(layer "F.Fab")
		)
		(fp_line
			(start 0.12065 -0.2794)
			(end 0.12065 -0.3048)
			(stroke
				(width 0.1)
				(type default)
			)
			(layer "F.Fab")
		)
		(fp_line
			(start 0.12065 -0.3048)
			(end 0.67945 -0.3048)
			(stroke
				(width 0.1)
				(type default)
			)
			(layer "F.Fab")
		)
		(fp_line
			(start 0.67945 -0.3048)
			(end 0.67945 0.3048)
			(stroke
				(width 0.1)
				(type default)
			)
			(layer "F.Fab")
		)
		(fp_line
			(start -0.67945 -0.305054)
			(end -0.12065 -0.305054)
			(stroke
				(width 0.1)
				(type default)
			)
			(layer "F.Fab")
		)
		(fp_line
			(start -0.12065 -0.305054)
			(end -0.12065 -0.2794)
			(stroke
				(width 0.1)
				(type default)
			)
			(layer "F.Fab")
		)
		(pad "1" smd circle
			(at -0.40005 0 270)
			(size 0 0)
			(layers "F.Cu" "F.Mask" "F.Paste")
			(net "GND")
		)
		(pad "2" smd circle
			(at 0.40005 0 270)
			(size 0 0)
			(layers "F.Cu" "F.Mask" "F.Paste")
			(net "PVCCIN_CPU1_VREF")
		)
	)
	(footprint ""
		(layer "F.Cu")
		(at 119.508016 -240.277142 90)
		(property "Reference" "C424"
			(at 0 0 90)
			(layer "F.SilkS")
			(hide yes)
			(effects
				(font
					(size 1.27 1.27)
				)
			)
		)
		(property "Value" ""
			(at 0 0 90)
			(layer "F.Fab")
			(effects
				(font
					(size 1.27 1.27)
				)
			)
		)
		(duplicate_pad_numbers_are_jumpers no)
		(fp_line
			(start 0.7874 -0.4064)
			(end 0.7874 0.4064)
			(stroke
				(width 0.1524)
				(type default)
			)
			(layer "F.SilkS")
		)
		(fp_line
			(start -0.7874 -0.4064)
			(end 0.7874 -0.4064)
			(stroke
				(width 0.1524)
				(type default)
			)
			(layer "F.SilkS")
		)
		(fp_line
			(start 0.7874 0.4064)
			(end -0.7874 0.4064)
			(stroke
				(width 0.1524)
				(type default)
			)
			(layer "F.SilkS")
		)
		(fp_line
			(start -0.7874 0.4064)
			(end -0.7874 -0.4064)
			(stroke
				(width 0.1524)
				(type default)
			)
			(layer "F.SilkS")
		)
		(fp_line
			(start -0.12065 -0.305054)
			(end -0.12065 -0.2794)
			(stroke
				(width 0.1)
				(type default)
			)
			(layer "F.Fab")
		)
		(fp_line
			(start -0.67945 -0.305054)
			(end -0.12065 -0.305054)
			(stroke
				(width 0.1)
				(type default)
			)
			(layer "F.Fab")
		)
		(fp_line
			(start 0.67945 -0.3048)
			(end 0.67945 0.3048)
			(stroke
				(width 0.1)
				(type default)
			)
			(layer "F.Fab")
		)
		(fp_line
			(start 0.12065 -0.3048)
			(end 0.67945 -0.3048)
			(stroke
				(width 0.1)
				(type default)
			)
			(layer "F.Fab")
		)
		(fp_line
			(start 0.12065 -0.2794)
			(end 0.12065 -0.3048)
			(stroke
				(width 0.1)
				(type default)
			)
			(layer "F.Fab")
		)
		(fp_line
			(start -0.12065 -0.2794)
			(end 0.12065 -0.2794)
			(stroke
				(width 0.1)
				(type default)
			)
			(layer "F.Fab")
		)
		(fp_line
			(start 0.120396 0.2794)
			(end -0.12065 0.2794)
			(stroke
				(width 0.1)
				(type default)
			)
			(layer "F.Fab")
		)
		(fp_line
			(start -0.12065 0.2794)
			(end -0.12065 0.3048)
			(stroke
				(width 0.1)
				(type default)
			)
			(layer "F.Fab")
		)
		(fp_line
			(start 0.67945 0.3048)
			(end 0.120396 0.3048)
			(stroke
				(width 0.1)
				(type default)
			)
			(layer "F.Fab")
		)
		(fp_line
			(start 0.120396 0.3048)
			(end 0.120396 0.2794)
			(stroke
				(width 0.1)
				(type default)
			)
			(layer "F.Fab")
		)
		(fp_line
			(start -0.12065 0.3048)
			(end -0.67945 0.3048)
			(stroke
				(width 0.1)
				(type default)
			)
			(layer "F.Fab")
		)
		(fp_line
			(start -0.67945 0.3048)
			(end -0.67945 -0.305054)
			(stroke
				(width 0.1)
				(type default)
			)
			(layer "F.Fab")
		)
		(pad "1" smd circle
			(at -0.40005 0 90)
			(size 0 0)
			(layers "F.Cu" "F.Mask" "F.Paste")
			(net "PVCCFA_EHV_FIVRA_CPU1")
		)
		(pad "2" smd circle
			(at 0.40005 0 90)
			(size 0 0)
			(layers "F.Cu" "F.Mask" "F.Paste")
			(net "GND")
		)
	)
	(footprint ""
		(layer "F.Cu")
		(at 111.74222 -296.05478 180)
		(property "Reference" "C225"
			(at 0 0 180)
			(layer "F.SilkS")
			(hide yes)
			(effects
				(font
					(size 1.27 1.27)
				)
			)
		)
		(property "Value" ""
			(at 0 0 180)
			(layer "F.Fab")
			(effects
				(font
					(size 1.27 1.27)
				)
			)
		)
		(duplicate_pad_numbers_are_jumpers no)
		(fp_line
			(start 1.524 0.762)
			(end -1.524 0.762)
			(stroke
				(width 0.1524)
				(type default)
			)
			(layer "F.SilkS")
		)
		(fp_line
			(start 1.524 -0.762)
			(end 1.524 0.762)
			(stroke
				(width 0.1524)
				(type default)
			)
			(layer "F.SilkS")
		)
		(fp_line
			(start -1.524 0.762)
			(end -1.524 -0.762)
			(stroke
				(width 0.1524)
				(type default)
			)
			(layer "F.SilkS")
		)
		(fp_line
			(start -1.524 -0.762)
			(end 1.524 -0.762)
			(stroke
				(width 0.1524)
				(type default)
			)
			(layer "F.SilkS")
		)
		(fp_line
			(start 1.1049 0.724916)
			(end 1.1049 -0.724916)
			(stroke
				(width 0.1)
				(type default)
			)
			(layer "F.Fab")
		)
		(fp_line
			(start 1.1049 -0.724916)
			(end -1.1049 -0.724916)
			(stroke
				(width 0.1)
				(type default)
			)
			(layer "F.Fab")
		)
		(fp_line
			(start -1.1049 0.724916)
			(end 1.1049 0.724916)
			(stroke
				(width 0.1)
				(type default)
			)
			(layer "F.Fab")
		)
		(fp_line
			(start -1.1049 -0.724916)
			(end -1.1049 0.724916)
			(stroke
				(width 0.1)
				(type default)
			)
			(layer "F.Fab")
		)
		(pad "1" smd rect
			(at -0.889 0)
			(size 1.016 1.27)
			(layers "F.Cu" "F.Mask" "F.Paste")
			(net "PVCCIN_CPU1")
		)
		(pad "2" smd rect
			(at 0.889 0)
			(size 1.016 1.27)
			(layers "F.Cu" "F.Mask" "F.Paste")
			(net "GND")
		)
	)
	(footprint ""
		(layer "F.Cu")
		(at 336.406998 -65.015364)
		(property "Reference" "R1316"
			(at 0 0 0)
			(layer "F.SilkS")
			(hide yes)
			(effects
				(font
					(size 1.27 1.27)
				)
			)
		)
		(property "Value" ""
			(at 0 0 0)
			(layer "F.Fab")
			(effects
				(font
					(size 1.27 1.27)
				)
			)
		)
		(duplicate_pad_numbers_are_jumpers no)
		(fp_line
			(start -1.2954 -0.5842)
			(end 1.2954 -0.5842)
			(stroke
				(width 0.1524)
				(type default)
			)
			(layer "F.SilkS")
		)
		(fp_line
			(start -1.2954 0.5842)
			(end -1.2954 -0.5842)
			(stroke
				(width 0.1524)
				(type default)
			)
			(layer "F.SilkS")
		)
		(fp_line
			(start 1.2954 -0.5842)
			(end 1.2954 0.5842)
			(stroke
				(width 0.1524)
				(type default)
			)
			(layer "F.SilkS")
		)
		(fp_line
			(start 1.2954 0.5842)
			(end -1.2954 0.5842)
			(stroke
				(width 0.1524)
				(type default)
			)
			(layer "F.SilkS")
		)
		(fp_line
			(start -1.1938 -0.406654)
			(end -0.8636 -0.406654)
			(stroke
				(width 0.1)
				(type default)
			)
			(layer "F.Fab")
		)
		(fp_line
			(start -1.1938 0.4064)
			(end -1.1938 -0.406654)
			(stroke
				(width 0.1)
				(type default)
			)
			(layer "F.Fab")
		)
		(fp_line
			(start -0.8636 -0.4572)
			(end 0.8636 -0.4572)
			(stroke
				(width 0.1)
				(type default)
			)
			(layer "F.Fab")
		)
		(fp_line
			(start -0.8636 -0.406654)
			(end -0.8636 -0.4572)
			(stroke
				(width 0.1)
				(type default)
			)
			(layer "F.Fab")
		)
		(fp_line
			(start -0.8636 0.4064)
			(end -1.1938 0.4064)
			(stroke
				(width 0.1)
				(type default)
			)
			(layer "F.Fab")
		)
		(fp_line
			(start -0.8636 0.4318)
			(end -0.8636 0.4064)
			(stroke
				(width 0.1)
				(type default)
			)
			(layer "F.Fab")
		)
		(fp_line
			(start -0.8636 0.4572)
			(end -0.8636 0.4318)
			(stroke
				(width 0.1)
				(type default)
			)
			(layer "F.Fab")
		)
		(fp_line
			(start 0.8636 -0.4572)
			(end 0.8636 -0.406654)
			(stroke
				(width 0.1)
				(type default)
			)
			(layer "F.Fab")
		)
		(fp_line
			(start 0.8636 -0.406654)
			(end 1.1938 -0.406654)
			(stroke
				(width 0.1)
				(type default)
			)
			(layer "F.Fab")
		)
		(fp_line
			(start 0.8636 0.4064)
			(end 0.8636 0.4572)
			(stroke
				(width 0.1)
				(type default)
			)
			(layer "F.Fab")
		)
		(fp_line
			(start 0.8636 0.4572)
			(end -0.8636 0.4572)
			(stroke
				(width 0.1)
				(type default)
			)
			(layer "F.Fab")
		)
		(fp_line
			(start 1.1938 -0.406654)
			(end 1.1938 0.4064)
			(stroke
				(width 0.1)
				(type default)
			)
			(layer "F.Fab")
		)
		(fp_line
			(start 1.1938 0.4064)
			(end 0.8636 0.4064)
			(stroke
				(width 0.1)
				(type default)
			)
			(layer "F.Fab")
		)
		(pad "1" smd rect
			(at -0.7366 0 270)
			(size 0.7112 0.8128)
			(layers "F.Cu" "F.Mask" "F.Paste")
			(net "XTAL_PCH_25M_IN_R")
		)
		(pad "2" smd rect
			(at 0.7366 0 270)
			(size 0.7112 0.8128)
			(layers "F.Cu" "F.Mask" "F.Paste")
			(net "XTAL_PCH_25M_OUT")
		)
	)
	(footprint ""
		(layer "F.Cu")
		(at 191.988186 -429.41113 -90)
		(property "Reference" "R2948"
			(at 0 0 270)
			(layer "F.SilkS")
			(hide yes)
			(effects
				(font
					(size 1.27 1.27)
				)
			)
		)
		(property "Value" ""
			(at 0 0 270)
			(layer "F.Fab")
			(effects
				(font
					(size 1.27 1.27)
				)
			)
		)
		(duplicate_pad_numbers_are_jumpers no)
		(fp_line
			(start -0.7874 0.4064)
			(end -0.7874 -0.4064)
			(stroke
				(width 0.1524)
				(type default)
			)
			(layer "F.SilkS")
		)
		(fp_line
			(start 0.7874 0.4064)
			(end -0.7874 0.4064)
			(stroke
				(width 0.1524)
				(type default)
			)
			(layer "F.SilkS")
		)
		(fp_line
			(start -0.7874 -0.4064)
			(end 0.7874 -0.4064)
			(stroke
				(width 0.1524)
				(type default)
			)
			(layer "F.SilkS")
		)
		(fp_line
			(start 0.7874 -0.4064)
			(end 0.7874 0.4064)
			(stroke
				(width 0.1524)
				(type default)
			)
			(layer "F.SilkS")
		)
		(fp_line
			(start -0.67945 0.3048)
			(end -0.67945 -0.305054)
			(stroke
				(width 0.1)
				(type default)
			)
			(layer "F.Fab")
		)
		(fp_line
			(start -0.12065 0.3048)
			(end -0.67945 0.3048)
			(stroke
				(width 0.1)
				(type default)
			)
			(layer "F.Fab")
		)
		(fp_line
			(start 0.120396 0.3048)
			(end 0.120396 0.2794)
			(stroke
				(width 0.1)
				(type default)
			)
			(layer "F.Fab")
		)
		(fp_line
			(start 0.67945 0.3048)
			(end 0.120396 0.3048)
			(stroke
				(width 0.1)
				(type default)
			)
			(layer "F.Fab")
		)
		(fp_line
			(start -0.12065 0.2794)
			(end -0.12065 0.3048)
			(stroke
				(width 0.1)
				(type default)
			)
			(layer "F.Fab")
		)
		(fp_line
			(start 0.120396 0.2794)
			(end -0.12065 0.2794)
			(stroke
				(width 0.1)
				(type default)
			)
			(layer "F.Fab")
		)
		(fp_line
			(start -0.12065 -0.2794)
			(end 0.12065 -0.2794)
			(stroke
				(width 0.1)
				(type default)
			)
			(layer "F.Fab")
		)
		(fp_line
			(start 0.12065 -0.2794)
			(end 0.12065 -0.3048)
			(stroke
				(width 0.1)
				(type default)
			)
			(layer "F.Fab")
		)
		(fp_line
			(start 0.12065 -0.3048)
			(end 0.67945 -0.3048)
			(stroke
				(width 0.1)
				(type default)
			)
			(layer "F.Fab")
		)
		(fp_line
			(start 0.67945 -0.3048)
			(end 0.67945 0.3048)
			(stroke
				(width 0.1)
				(type default)
			)
			(layer "F.Fab")
		)
		(fp_line
			(start -0.67945 -0.305054)
			(end -0.12065 -0.305054)
			(stroke
				(width 0.1)
				(type default)
			)
			(layer "F.Fab")
		)
		(fp_line
			(start -0.12065 -0.305054)
			(end -0.12065 -0.2794)
			(stroke
				(width 0.1)
				(type default)
			)
			(layer "F.Fab")
		)
		(pad "1" smd circle
			(at -0.40005 0 270)
			(size 0 0)
			(layers "F.Cu" "F.Mask" "F.Paste")
			(net "FM_GPU_HSC_EN_BUF_R")
		)
		(pad "2" smd circle
			(at 0.40005 0 270)
			(size 0 0)
			(layers "F.Cu" "F.Mask" "F.Paste")
			(net "GND")
		)
	)
	(footprint ""
		(layer "F.Cu")
		(at 366.3696 -407.0604)
		(property "Reference" "R4740"
			(at 0 0 0)
			(layer "F.SilkS")
			(hide yes)
			(effects
				(font
					(size 1.27 1.27)
				)
			)
		)
		(property "Value" ""
			(at 0 0 0)
			(layer "F.Fab")
			(effects
				(font
					(size 1.27 1.27)
				)
			)
		)
		(duplicate_pad_numbers_are_jumpers no)
		(fp_line
			(start -0.7874 -0.4064)
			(end 0.7874 -0.4064)
			(stroke
				(width 0.1524)
				(type default)
			)
			(layer "F.SilkS")
		)
		(fp_line
			(start -0.7874 0.4064)
			(end -0.7874 -0.4064)
			(stroke
				(width 0.1524)
				(type default)
			)
			(layer "F.SilkS")
		)
		(fp_line
			(start 0.7874 -0.4064)
			(end 0.7874 0.4064)
			(stroke
				(width 0.1524)
				(type default)
			)
			(layer "F.SilkS")
		)
		(fp_line
			(start 0.7874 0.4064)
			(end -0.7874 0.4064)
			(stroke
				(width 0.1524)
				(type default)
			)
			(layer "F.SilkS")
		)
		(fp_line
			(start -0.67945 -0.305054)
			(end -0.12065 -0.305054)
			(stroke
				(width 0.1)
				(type default)
			)
			(layer "F.Fab")
		)
		(fp_line
			(start -0.67945 0.3048)
			(end -0.67945 -0.305054)
			(stroke
				(width 0.1)
				(type default)
			)
			(layer "F.Fab")
		)
		(fp_line
			(start -0.12065 -0.305054)
			(end -0.12065 -0.2794)
			(stroke
				(width 0.1)
				(type default)
			)
			(layer "F.Fab")
		)
		(fp_line
			(start -0.12065 -0.2794)
			(end 0.12065 -0.2794)
			(stroke
				(width 0.1)
				(type default)
			)
			(layer "F.Fab")
		)
		(fp_line
			(start -0.12065 0.2794)
			(end -0.12065 0.3048)
			(stroke
				(width 0.1)
				(type default)
			)
			(layer "F.Fab")
		)
		(fp_line
			(start -0.12065 0.3048)
			(end -0.67945 0.3048)
			(stroke
				(width 0.1)
				(type default)
			)
			(layer "F.Fab")
		)
		(fp_line
			(start 0.120396 0.2794)
			(end -0.12065 0.2794)
			(stroke
				(width 0.1)
				(type default)
			)
			(layer "F.Fab")
		)
		(fp_line
			(start 0.120396 0.3048)
			(end 0.120396 0.2794)
			(stroke
				(width 0.1)
				(type default)
			)
			(layer "F.Fab")
		)
		(fp_line
			(start 0.12065 -0.3048)
			(end 0.67945 -0.3048)
			(stroke
				(width 0.1)
				(type default)
			)
			(layer "F.Fab")
		)
		(fp_line
			(start 0.12065 -0.2794)
			(end 0.12065 -0.3048)
			(stroke
				(width 0.1)
				(type default)
			)
			(layer "F.Fab")
		)
		(fp_line
			(start 0.67945 -0.3048)
			(end 0.67945 0.3048)
			(stroke
				(width 0.1)
				(type default)
			)
			(layer "F.Fab")
		)
		(fp_line
			(start 0.67945 0.3048)
			(end 0.120396 0.3048)
			(stroke
				(width 0.1)
				(type default)
			)
			(layer "F.Fab")
		)
		(pad "1" smd circle
			(at -0.40005 0)
			(size 0 0)
			(layers "F.Cu" "F.Mask" "F.Paste")
			(net "P3V3_AUX")
		)
		(pad "2" smd circle
			(at 0.40005 0)
			(size 0 0)
			(layers "F.Cu" "F.Mask" "F.Paste")
			(net "PRSNT_CABLE_SWB_B1_ISO_N")
		)
	)
	(footprint ""
		(layer "F.Cu")
		(at 378.099574 5.463794 180)
		(property "Reference" "J66"
			(at -4.451096 -1.394206 90)
			(unlocked yes)
			(layer "F.SilkS")
			(effects
				(font
					(size 0.7874 0.5842)
					(thickness 0.1524)
				)
				(justify left)
			)
		)
		(property "Value" ""
			(at 0 0 180)
			(layer "F.Fab")
			(effects
				(font
					(size 1.27 1.27)
				)
			)
		)
		(duplicate_pad_numbers_are_jumpers no)
		(fp_line
			(start 1.2192 2.1082)
			(end -1.2192 2.1082)
			(stroke
				(width 0.1524)
				(type default)
			)
			(layer "F.SilkS")
		)
		(fp_line
			(start 1.2192 -2.1082)
			(end 1.2192 2.1082)
			(stroke
				(width 0.1524)
				(type default)
			)
			(layer "F.SilkS")
		)
		(fp_line
			(start -1.2192 2.1082)
			(end -1.2192 -2.1082)
			(stroke
				(width 0.1524)
				(type default)
			)
			(layer "F.SilkS")
		)
		(fp_line
			(start -1.2192 -2.1082)
			(end 1.2192 -2.1082)
			(stroke
				(width 0.1524)
				(type default)
			)
			(layer "F.SilkS")
		)
		(pad "" np_thru_hole circle
			(at -2.8829 -1.27 90)
			(size 1.0414 1.0414)
			(drill 1.0414)
			(layers "*.Cu" "*.Mask")
			(clearance 0.381)
			(thermal_gap 0.381)
		)
		(pad "" np_thru_hole circle
			(at -2.8829 1.27 90)
			(size 1.0414 1.0414)
			(drill 1.0414)
			(layers "*.Cu" "*.Mask")
			(clearance 0.381)
			(thermal_gap 0.381)
		)
		(pad "" np_thru_hole circle
			(at 3.4671 -1.27 90)
			(size 1.0414 1.0414)
			(drill 1.0414)
			(layers "*.Cu" "*.Mask")
			(clearance 0.381)
			(thermal_gap 0.381)
		)
		(pad "" np_thru_hole circle
			(at 3.4671 1.27 90)
			(size 1.0414 1.0414)
			(drill 1.0414)
			(layers "*.Cu" "*.Mask")
			(clearance 0.381)
			(thermal_gap 0.381)
		)
		(pad "1" smd rect
			(at 0.8255 -0.249936 90)
			(size 0.3048 0.508)
			(layers "F.Cu" "F.Mask" "F.Paste")
			(net "DELTA_L_85_5INCH_IN2_DP")
		)
		(pad "2" smd rect
			(at 0.8255 0.249936 90)
			(size 0.3048 0.508)
			(layers "F.Cu" "F.Mask" "F.Paste")
			(net "DELTA_L_85_5INCH_IN2_DN")
		)
		(pad "3" smd circle
			(at 0 0 180)
			(size 0 0)
			(layers "F.Cu" "F.Mask" "F.Paste")
			(net "DELTA_L_GND_1")
		)
		(zone
			(layer "F.Cu")
			(hatch none 0.5)
			(connect_pads
				(clearance 0)
			)
			(min_thickness 0.25)
			(keepout
				(tracks not_allowed)
				(vias allowed)
				(pads allowed)
				(copperpour not_allowed)
				(footprints allowed)
			)
			(placement
				(enabled no)
				(sheetname "")
			)
			(fill
				(thermal_gap 0.5)
				(thermal_bridge_width 0.5)
				(island_removal_mode 0)
			)
			(polygon
				(pts
					(xy 376.981974 6.012434) (xy 376.981974 5.91693) (xy 377.578874 5.91693) (xy 377.578874 5.51053)
					(xy 376.981974 5.51053) (xy 376.981974 5.417058) (xy 377.578874 5.417058) (xy 377.578874 5.010658)
					(xy 376.981974 5.010658) (xy 376.981974 4.915154) (xy 377.680474 4.915154) (xy 377.680474 6.012434)
				)
			)
		)
		(zone
			(layers "F.Cu" "B.Cu" "In1.Cu" "In2.Cu" "In3.Cu" "In4.Cu" "In5.Cu" "In6.Cu"
				"In7.Cu" "In8.Cu" "In9.Cu" "In10.Cu" "In11.Cu" "In12.Cu" "In13.Cu" "In14.Cu"
				"In15.Cu" "In16.Cu"
			)
			(hatch none 0.5)
			(connect_pads
				(clearance 0)
			)
			(min_thickness 0.25)
			(keepout
				(tracks not_allowed)
				(vias allowed)
				(pads allowed)
				(copperpour not_allowed)
				(footprints allowed)
			)
			(placement
				(enabled no)
				(sheetname "")
			)
			(fill
				(thermal_gap 0.5)
				(thermal_bridge_width 0.5)
				(island_removal_mode 0)
			)
			(polygon
				(pts
					(arc
						(start 375.559574 4.193794)
						(mid 373.705374 4.193794)
						(end 375.559574 4.193794)
					)
				)
			)
		)
		(zone
			(layers "F.Cu" "B.Cu" "In1.Cu" "In2.Cu" "In3.Cu" "In4.Cu" "In5.Cu" "In6.Cu"
				"In7.Cu" "In8.Cu" "In9.Cu" "In10.Cu" "In11.Cu" "In12.Cu" "In13.Cu" "In14.Cu"
				"In15.Cu" "In16.Cu"
			)
			(hatch none 0.5)
			(connect_pads
				(clearance 0)
			)
			(min_thickness 0.25)
			(keepout
				(tracks not_allowed)
				(vias allowed)
				(pads allowed)
				(copperpour not_allowed)
				(footprints allowed)
			)
			(placement
				(enabled no)
				(sheetname "")
			)
			(fill
				(thermal_gap 0.5)
				(thermal_bridge_width 0.5)
				(island_removal_mode 0)
			)
			(polygon
				(pts
					(arc
						(start 375.559574 6.733794)
						(mid 373.705374 6.733794)
						(end 375.559574 6.733794)
					)
				)
			)
		)
		(zone
			(layers "F.Cu" "B.Cu" "In1.Cu" "In2.Cu" "In3.Cu" "In4.Cu" "In5.Cu" "In6.Cu"
				"In7.Cu" "In8.Cu" "In9.Cu" "In10.Cu" "In11.Cu" "In12.Cu" "In13.Cu" "In14.Cu"
				"In15.Cu" "In16.Cu"
			)
			(hatch none 0.5)
			(connect_pads
				(clearance 0)
			)
			(min_thickness 0.25)
			(keepout
				(tracks not_allowed)
				(vias allowed)
				(pads allowed)
				(copperpour not_allowed)
				(footprints allowed)
			)
			(placement
				(enabled no)
				(sheetname "")
			)
			(fill
				(thermal_gap 0.5)
				(thermal_bridge_width 0.5)
				(island_removal_mode 0)
			)
			(polygon
				(pts
					(arc
						(start 381.909574 4.193794)
						(mid 380.055374 4.193794)
						(end 381.909574 4.193794)
					)
				)
			)
		)
		(zone
			(layers "F.Cu" "B.Cu" "In1.Cu" "In2.Cu" "In3.Cu" "In4.Cu" "In5.Cu" "In6.Cu"
				"In7.Cu" "In8.Cu" "In9.Cu" "In10.Cu" "In11.Cu" "In12.Cu" "In13.Cu" "In14.Cu"
				"In15.Cu" "In16.Cu"
			)
			(hatch none 0.5)
			(connect_pads
				(clearance 0)
			)
			(min_thickness 0.25)
			(keepout
				(tracks not_allowed)
				(vias allowed)
				(pads allowed)
				(copperpour not_allowed)
				(footprints allowed)
			)
			(placement
				(enabled no)
				(sheetname "")
			)
			(fill
				(thermal_gap 0.5)
				(thermal_bridge_width 0.5)
				(island_removal_mode 0)
			)
			(polygon
				(pts
					(arc
						(start 381.909574 6.733794)
						(mid 380.055374 6.733794)
						(end 381.909574 6.733794)
					)
				)
			)
		)
	)
	(footprint ""
		(layer "F.Cu")
		(at 411.201108 -363.193584)
		(property "Reference" "PR444"
			(at 0 0 0)
			(layer "F.SilkS")
			(hide yes)
			(effects
				(font
					(size 1.27 1.27)
				)
			)
		)
		(property "Value" ""
			(at 0 0 0)
			(layer "F.Fab")
			(effects
				(font
					(size 1.27 1.27)
				)
			)
		)
		(duplicate_pad_numbers_are_jumpers no)
		(fp_line
			(start -0.7874 -0.4064)
			(end 0.7874 -0.4064)
			(stroke
				(width 0.1524)
				(type default)
			)
			(layer "F.SilkS")
		)
		(fp_line
			(start -0.7874 0.4064)
			(end -0.7874 -0.4064)
			(stroke
				(width 0.1524)
				(type default)
			)
			(layer "F.SilkS")
		)
		(fp_line
			(start 0.7874 -0.4064)
			(end 0.7874 0.4064)
			(stroke
				(width 0.1524)
				(type default)
			)
			(layer "F.SilkS")
		)
		(fp_line
			(start 0.7874 0.4064)
			(end -0.7874 0.4064)
			(stroke
				(width 0.1524)
				(type default)
			)
			(layer "F.SilkS")
		)
		(fp_line
			(start -0.67945 -0.305054)
			(end -0.12065 -0.305054)
			(stroke
				(width 0.1)
				(type default)
			)
			(layer "F.Fab")
		)
		(fp_line
			(start -0.67945 0.3048)
			(end -0.67945 -0.305054)
			(stroke
				(width 0.1)
				(type default)
			)
			(layer "F.Fab")
		)
		(fp_line
			(start -0.12065 -0.305054)
			(end -0.12065 -0.2794)
			(stroke
				(width 0.1)
				(type default)
			)
			(layer "F.Fab")
		)
		(fp_line
			(start -0.12065 -0.2794)
			(end 0.12065 -0.2794)
			(stroke
				(width 0.1)
				(type default)
			)
			(layer "F.Fab")
		)
		(fp_line
			(start -0.12065 0.2794)
			(end -0.12065 0.3048)
			(stroke
				(width 0.1)
				(type default)
			)
			(layer "F.Fab")
		)
		(fp_line
			(start -0.12065 0.3048)
			(end -0.67945 0.3048)
			(stroke
				(width 0.1)
				(type default)
			)
			(layer "F.Fab")
		)
		(fp_line
			(start 0.120396 0.2794)
			(end -0.12065 0.2794)
			(stroke
				(width 0.1)
				(type default)
			)
			(layer "F.Fab")
		)
		(fp_line
			(start 0.120396 0.3048)
			(end 0.120396 0.2794)
			(stroke
				(width 0.1)
				(type default)
			)
			(layer "F.Fab")
		)
		(fp_line
			(start 0.12065 -0.3048)
			(end 0.67945 -0.3048)
			(stroke
				(width 0.1)
				(type default)
			)
			(layer "F.Fab")
		)
		(fp_line
			(start 0.12065 -0.2794)
			(end 0.12065 -0.3048)
			(stroke
				(width 0.1)
				(type default)
			)
			(layer "F.Fab")
		)
		(fp_line
			(start 0.67945 -0.3048)
			(end 0.67945 0.3048)
			(stroke
				(width 0.1)
				(type default)
			)
			(layer "F.Fab")
		)
		(fp_line
			(start 0.67945 0.3048)
			(end 0.120396 0.3048)
			(stroke
				(width 0.1)
				(type default)
			)
			(layer "F.Fab")
		)
		(pad "1" smd circle
			(at -0.40005 0)
			(size 0 0)
			(layers "F.Cu" "F.Mask" "F.Paste")
			(net "P5V")
		)
		(pad "2" smd circle
			(at 0.40005 0)
			(size 0 0)
			(layers "F.Cu" "F.Mask" "F.Paste")
			(net "PVCCFA_EHV_FIVRA_CPU0_PVCC1")
		)
	)
	(footprint ""
		(layer "F.Cu")
		(at 218.08948 -128.819148 180)
		(property "Reference" "R1691"
			(at 0 0 180)
			(layer "F.SilkS")
			(hide yes)
			(effects
				(font
					(size 1.27 1.27)
				)
			)
		)
		(property "Value" ""
			(at 0 0 180)
			(layer "F.Fab")
			(effects
				(font
					(size 1.27 1.27)
				)
			)
		)
		(duplicate_pad_numbers_are_jumpers no)
		(fp_line
			(start 0.7874 0.4064)
			(end -0.7874 0.4064)
			(stroke
				(width 0.1524)
				(type default)
			)
			(layer "F.SilkS")
		)
		(fp_line
			(start 0.7874 -0.4064)
			(end 0.7874 0.4064)
			(stroke
				(width 0.1524)
				(type default)
			)
			(layer "F.SilkS")
		)
		(fp_line
			(start -0.7874 0.4064)
			(end -0.7874 -0.4064)
			(stroke
				(width 0.1524)
				(type default)
			)
			(layer "F.SilkS")
		)
		(fp_line
			(start -0.7874 -0.4064)
			(end 0.7874 -0.4064)
			(stroke
				(width 0.1524)
				(type default)
			)
			(layer "F.SilkS")
		)
		(fp_line
			(start 0.67945 0.3048)
			(end 0.120396 0.3048)
			(stroke
				(width 0.1)
				(type default)
			)
			(layer "F.Fab")
		)
		(fp_line
			(start 0.67945 -0.3048)
			(end 0.67945 0.3048)
			(stroke
				(width 0.1)
				(type default)
			)
			(layer "F.Fab")
		)
		(fp_line
			(start 0.12065 -0.2794)
			(end 0.12065 -0.3048)
			(stroke
				(width 0.1)
				(type default)
			)
			(layer "F.Fab")
		)
		(fp_line
			(start 0.12065 -0.3048)
			(end 0.67945 -0.3048)
			(stroke
				(width 0.1)
				(type default)
			)
			(layer "F.Fab")
		)
		(fp_line
			(start 0.120396 0.3048)
			(end 0.120396 0.2794)
			(stroke
				(width 0.1)
				(type default)
			)
			(layer "F.Fab")
		)
		(fp_line
			(start 0.120396 0.2794)
			(end -0.12065 0.2794)
			(stroke
				(width 0.1)
				(type default)
			)
			(layer "F.Fab")
		)
		(fp_line
			(start -0.12065 0.3048)
			(end -0.67945 0.3048)
			(stroke
				(width 0.1)
				(type default)
			)
			(layer "F.Fab")
		)
		(fp_line
			(start -0.12065 0.2794)
			(end -0.12065 0.3048)
			(stroke
				(width 0.1)
				(type default)
			)
			(layer "F.Fab")
		)
		(fp_line
			(start -0.12065 -0.2794)
			(end 0.12065 -0.2794)
			(stroke
				(width 0.1)
				(type default)
			)
			(layer "F.Fab")
		)
		(fp_line
			(start -0.12065 -0.305054)
			(end -0.12065 -0.2794)
			(stroke
				(width 0.1)
				(type default)
			)
			(layer "F.Fab")
		)
		(fp_line
			(start -0.67945 0.3048)
			(end -0.67945 -0.305054)
			(stroke
				(width 0.1)
				(type default)
			)
			(layer "F.Fab")
		)
		(fp_line
			(start -0.67945 -0.305054)
			(end -0.12065 -0.305054)
			(stroke
				(width 0.1)
				(type default)
			)
			(layer "F.Fab")
		)
		(pad "1" smd circle
			(at -0.40005 0 180)
			(size 0 0)
			(layers "F.Cu" "F.Mask" "F.Paste")
			(net "P3V3_AUX")
		)
		(pad "2" smd circle
			(at 0.40005 0 180)
			(size 0 0)
			(layers "F.Cu" "F.Mask" "F.Paste")
			(net "PWRGD_DSW_PWROK_R1")
		)
	)
	(footprint ""
		(layer "F.Cu")
		(at 329.948794 -21.625052 180)
		(property "Reference" "R1269"
			(at 0 0 180)
			(layer "F.SilkS")
			(hide yes)
			(effects
				(font
					(size 1.27 1.27)
				)
			)
		)
		(property "Value" ""
			(at 0 0 180)
			(layer "F.Fab")
			(effects
				(font
					(size 1.27 1.27)
				)
			)
		)
		(duplicate_pad_numbers_are_jumpers no)
		(fp_line
			(start 0.7874 0.4064)
			(end -0.7874 0.4064)
			(stroke
				(width 0.1524)
				(type default)
			)
			(layer "F.SilkS")
		)
		(fp_line
			(start 0.7874 -0.4064)
			(end 0.7874 0.4064)
			(stroke
				(width 0.1524)
				(type default)
			)
			(layer "F.SilkS")
		)
		(fp_line
			(start -0.7874 0.4064)
			(end -0.7874 -0.4064)
			(stroke
				(width 0.1524)
				(type default)
			)
			(layer "F.SilkS")
		)
		(fp_line
			(start -0.7874 -0.4064)
			(end 0.7874 -0.4064)
			(stroke
				(width 0.1524)
				(type default)
			)
			(layer "F.SilkS")
		)
		(fp_line
			(start 0.67945 0.3048)
			(end 0.120396 0.3048)
			(stroke
				(width 0.1)
				(type default)
			)
			(layer "F.Fab")
		)
		(fp_line
			(start 0.67945 -0.3048)
			(end 0.67945 0.3048)
			(stroke
				(width 0.1)
				(type default)
			)
			(layer "F.Fab")
		)
		(fp_line
			(start 0.12065 -0.2794)
			(end 0.12065 -0.3048)
			(stroke
				(width 0.1)
				(type default)
			)
			(layer "F.Fab")
		)
		(fp_line
			(start 0.12065 -0.3048)
			(end 0.67945 -0.3048)
			(stroke
				(width 0.1)
				(type default)
			)
			(layer "F.Fab")
		)
		(fp_line
			(start 0.120396 0.3048)
			(end 0.120396 0.2794)
			(stroke
				(width 0.1)
				(type default)
			)
			(layer "F.Fab")
		)
		(fp_line
			(start 0.120396 0.2794)
			(end -0.12065 0.2794)
			(stroke
				(width 0.1)
				(type default)
			)
			(layer "F.Fab")
		)
		(fp_line
			(start -0.12065 0.3048)
			(end -0.67945 0.3048)
			(stroke
				(width 0.1)
				(type default)
			)
			(layer "F.Fab")
		)
		(fp_line
			(start -0.12065 0.2794)
			(end -0.12065 0.3048)
			(stroke
				(width 0.1)
				(type default)
			)
			(layer "F.Fab")
		)
		(fp_line
			(start -0.12065 -0.2794)
			(end 0.12065 -0.2794)
			(stroke
				(width 0.1)
				(type default)
			)
			(layer "F.Fab")
		)
		(fp_line
			(start -0.12065 -0.305054)
			(end -0.12065 -0.2794)
			(stroke
				(width 0.1)
				(type default)
			)
			(layer "F.Fab")
		)
		(fp_line
			(start -0.67945 0.3048)
			(end -0.67945 -0.305054)
			(stroke
				(width 0.1)
				(type default)
			)
			(layer "F.Fab")
		)
		(fp_line
			(start -0.67945 -0.305054)
			(end -0.12065 -0.305054)
			(stroke
				(width 0.1)
				(type default)
			)
			(layer "F.Fab")
		)
		(pad "1" smd circle
			(at -0.40005 0 180)
			(size 0 0)
			(layers "F.Cu" "F.Mask" "F.Paste")
			(net "IRQ_BMC_PCH_NMI")
		)
		(pad "2" smd circle
			(at 0.40005 0 180)
			(size 0 0)
			(layers "F.Cu" "F.Mask" "F.Paste")
			(net "GND")
		)
	)
	(footprint ""
		(layer "F.Cu")
		(at 20.190714 -109.859826 180)
		(property "Reference" "C2052"
			(at 0 0 180)
			(layer "F.SilkS")
			(hide yes)
			(effects
				(font
					(size 1.27 1.27)
				)
			)
		)
		(property "Value" ""
			(at 0 0 180)
			(layer "F.Fab")
			(effects
				(font
					(size 1.27 1.27)
				)
			)
		)
		(duplicate_pad_numbers_are_jumpers no)
		(fp_line
			(start 0.7874 0.4064)
			(end -0.7874 0.4064)
			(stroke
				(width 0.1524)
				(type default)
			)
			(layer "F.SilkS")
		)
		(fp_line
			(start 0.7874 -0.4064)
			(end 0.7874 0.4064)
			(stroke
				(width 0.1524)
				(type default)
			)
			(layer "F.SilkS")
		)
		(fp_line
			(start -0.7874 0.4064)
			(end -0.7874 -0.4064)
			(stroke
				(width 0.1524)
				(type default)
			)
			(layer "F.SilkS")
		)
		(fp_line
			(start -0.7874 -0.4064)
			(end 0.7874 -0.4064)
			(stroke
				(width 0.1524)
				(type default)
			)
			(layer "F.SilkS")
		)
		(fp_line
			(start 0.67945 0.3048)
			(end 0.120396 0.3048)
			(stroke
				(width 0.1)
				(type default)
			)
			(layer "F.Fab")
		)
		(fp_line
			(start 0.67945 -0.3048)
			(end 0.67945 0.3048)
			(stroke
				(width 0.1)
				(type default)
			)
			(layer "F.Fab")
		)
		(fp_line
			(start 0.12065 -0.2794)
			(end 0.12065 -0.3048)
			(stroke
				(width 0.1)
				(type default)
			)
			(layer "F.Fab")
		)
		(fp_line
			(start 0.12065 -0.3048)
			(end 0.67945 -0.3048)
			(stroke
				(width 0.1)
				(type default)
			)
			(layer "F.Fab")
		)
		(fp_line
			(start 0.120396 0.3048)
			(end 0.120396 0.2794)
			(stroke
				(width 0.1)
				(type default)
			)
			(layer "F.Fab")
		)
		(fp_line
			(start 0.120396 0.2794)
			(end -0.12065 0.2794)
			(stroke
				(width 0.1)
				(type default)
			)
			(layer "F.Fab")
		)
		(fp_line
			(start -0.12065 0.3048)
			(end -0.67945 0.3048)
			(stroke
				(width 0.1)
				(type default)
			)
			(layer "F.Fab")
		)
		(fp_line
			(start -0.12065 0.2794)
			(end -0.12065 0.3048)
			(stroke
				(width 0.1)
				(type default)
			)
			(layer "F.Fab")
		)
		(fp_line
			(start -0.12065 -0.2794)
			(end 0.12065 -0.2794)
			(stroke
				(width 0.1)
				(type default)
			)
			(layer "F.Fab")
		)
		(fp_line
			(start -0.12065 -0.305054)
			(end -0.12065 -0.2794)
			(stroke
				(width 0.1)
				(type default)
			)
			(layer "F.Fab")
		)
		(fp_line
			(start -0.67945 0.3048)
			(end -0.67945 -0.305054)
			(stroke
				(width 0.1)
				(type default)
			)
			(layer "F.Fab")
		)
		(fp_line
			(start -0.67945 -0.305054)
			(end -0.12065 -0.305054)
			(stroke
				(width 0.1)
				(type default)
			)
			(layer "F.Fab")
		)
		(pad "1" smd circle
			(at -0.40005 0 180)
			(size 0 0)
			(layers "F.Cu" "F.Mask" "F.Paste")
			(net "P3V3_ADC128_VCC")
		)
		(pad "2" smd circle
			(at 0.40005 0 180)
			(size 0 0)
			(layers "F.Cu" "F.Mask" "F.Paste")
			(net "GND")
		)
	)
	(footprint ""
		(layer "F.Cu")
		(at 174.1424 -94.338648 90)
		(property "Reference" "R4598"
			(at 0 0 90)
			(layer "F.SilkS")
			(hide yes)
			(effects
				(font
					(size 1.27 1.27)
				)
			)
		)
		(property "Value" ""
			(at 0 0 90)
			(layer "F.Fab")
			(effects
				(font
					(size 1.27 1.27)
				)
			)
		)
		(duplicate_pad_numbers_are_jumpers no)
		(fp_line
			(start 0.7874 -0.4064)
			(end 0.7874 0.4064)
			(stroke
				(width 0.1524)
				(type default)
			)
			(layer "F.SilkS")
		)
		(fp_line
			(start -0.7874 -0.4064)
			(end 0.7874 -0.4064)
			(stroke
				(width 0.1524)
				(type default)
			)
			(layer "F.SilkS")
		)
		(fp_line
			(start 0.7874 0.4064)
			(end -0.7874 0.4064)
			(stroke
				(width 0.1524)
				(type default)
			)
			(layer "F.SilkS")
		)
		(fp_line
			(start -0.7874 0.4064)
			(end -0.7874 -0.4064)
			(stroke
				(width 0.1524)
				(type default)
			)
			(layer "F.SilkS")
		)
		(fp_line
			(start -0.12065 -0.305054)
			(end -0.12065 -0.2794)
			(stroke
				(width 0.1)
				(type default)
			)
			(layer "F.Fab")
		)
		(fp_line
			(start -0.67945 -0.305054)
			(end -0.12065 -0.305054)
			(stroke
				(width 0.1)
				(type default)
			)
			(layer "F.Fab")
		)
		(fp_line
			(start 0.67945 -0.3048)
			(end 0.67945 0.3048)
			(stroke
				(width 0.1)
				(type default)
			)
			(layer "F.Fab")
		)
		(fp_line
			(start 0.12065 -0.3048)
			(end 0.67945 -0.3048)
			(stroke
				(width 0.1)
				(type default)
			)
			(layer "F.Fab")
		)
		(fp_line
			(start 0.12065 -0.2794)
			(end 0.12065 -0.3048)
			(stroke
				(width 0.1)
				(type default)
			)
			(layer "F.Fab")
		)
		(fp_line
			(start -0.12065 -0.2794)
			(end 0.12065 -0.2794)
			(stroke
				(width 0.1)
				(type default)
			)
			(layer "F.Fab")
		)
		(fp_line
			(start 0.120396 0.2794)
			(end -0.12065 0.2794)
			(stroke
				(width 0.1)
				(type default)
			)
			(layer "F.Fab")
		)
		(fp_line
			(start -0.12065 0.2794)
			(end -0.12065 0.3048)
			(stroke
				(width 0.1)
				(type default)
			)
			(layer "F.Fab")
		)
		(fp_line
			(start 0.67945 0.3048)
			(end 0.120396 0.3048)
			(stroke
				(width 0.1)
				(type default)
			)
			(layer "F.Fab")
		)
		(fp_line
			(start 0.120396 0.3048)
			(end 0.120396 0.2794)
			(stroke
				(width 0.1)
				(type default)
			)
			(layer "F.Fab")
		)
		(fp_line
			(start -0.12065 0.3048)
			(end -0.67945 0.3048)
			(stroke
				(width 0.1)
				(type default)
			)
			(layer "F.Fab")
		)
		(fp_line
			(start -0.67945 0.3048)
			(end -0.67945 -0.305054)
			(stroke
				(width 0.1)
				(type default)
			)
			(layer "F.Fab")
		)
		(pad "1" smd rect
			(at -0.40005 0 270)
			(size 0.4572 0.508)
			(layers "F.Cu" "F.Mask" "F.Paste")
			(net "FM_BOARD_BMC_SKU_ID2")
		)
		(pad "2" smd rect
			(at 0.40005 0 270)
			(size 0.4572 0.508)
			(layers "F.Cu" "F.Mask" "F.Paste")
			(net "GND")
		)
	)
	(footprint ""
		(layer "F.Cu")
		(at 392.809984 -17.612614 90)
		(property "Reference" "C840"
			(at 0 0 90)
			(layer "F.SilkS")
			(hide yes)
			(effects
				(font
					(size 1.27 1.27)
				)
			)
		)
		(property "Value" ""
			(at 0 0 90)
			(layer "F.Fab")
			(effects
				(font
					(size 1.27 1.27)
				)
			)
		)
		(duplicate_pad_numbers_are_jumpers no)
		(fp_line
			(start 0.299974 -0.150114)
			(end 0.299974 0.150114)
			(stroke
				(width 0.1)
				(type default)
			)
			(layer "F.Fab")
		)
		(fp_line
			(start -0.299974 -0.150114)
			(end 0.299974 -0.150114)
			(stroke
				(width 0.1)
				(type default)
			)
			(layer "F.Fab")
		)
		(fp_line
			(start 0.299974 0.150114)
			(end -0.299974 0.150114)
			(stroke
				(width 0.1)
				(type default)
			)
			(layer "F.Fab")
		)
		(fp_line
			(start -0.299974 0.150114)
			(end -0.299974 -0.150114)
			(stroke
				(width 0.1)
				(type default)
			)
			(layer "F.Fab")
		)
		(pad "1" smd rect
			(at -0.2667 0 90)
			(size 0.3048 0.381)
			(layers "F.Cu" "F.Mask" "F.Paste")
			(net "P5E_CPU0_PE1_TX_C_DN<14>")
		)
		(pad "2" smd rect
			(at 0.2667 0 90)
			(size 0.3048 0.381)
			(layers "F.Cu" "F.Mask" "F.Paste")
			(net "P5E_CPU0_PE1_TX_DN<14>")
		)
	)
	(footprint ""
		(layer "F.Cu")
		(at 449.43014 -114.112548 -90)
		(property "Reference" "U208"
			(at -0.582168 4.89458 0)
			(unlocked yes)
			(layer "F.SilkS")
			(effects
				(font
					(size 0.7874 0.5842)
					(thickness 0.1524)
				)
				(justify left)
			)
		)
		(property "Value" ""
			(at 0 0 270)
			(layer "F.Fab")
			(effects
				(font
					(size 1.27 1.27)
				)
			)
		)
		(duplicate_pad_numbers_are_jumpers no)
		(fp_line
			(start -1.733296 1.549908)
			(end 1.733296 1.549908)
			(stroke
				(width 0.1524)
				(type default)
			)
			(layer "F.SilkS")
		)
		(fp_line
			(start 1.733296 1.549908)
			(end 1.733296 -1.549908)
			(stroke
				(width 0.1524)
				(type default)
			)
			(layer "F.SilkS")
		)
		(fp_line
			(start 0 -0.889)
			(end -0.660908 -1.549908)
			(stroke
				(width 0.1524)
				(type default)
			)
			(layer "F.SilkS")
		)
		(fp_line
			(start -1.733296 -1.549908)
			(end -1.733296 1.549908)
			(stroke
				(width 0.1524)
				(type default)
			)
			(layer "F.SilkS")
		)
		(fp_line
			(start -0.660908 -1.549908)
			(end -1.733296 -1.549908)
			(stroke
				(width 0.1524)
				(type default)
			)
			(layer "F.SilkS")
		)
		(fp_line
			(start 0.660908 -1.549908)
			(end 0 -0.889)
			(stroke
				(width 0.1524)
				(type default)
			)
			(layer "F.SilkS")
		)
		(fp_line
			(start 1.733296 -1.549908)
			(end 0.660908 -1.549908)
			(stroke
				(width 0.1524)
				(type default)
			)
			(layer "F.SilkS")
		)
		(fp_poly
			(pts
				(xy -1.9304 -0.94996) (xy -2.4384 -0.69596) (xy -2.4384 -1.20396)
			)
			(stroke
				(width 0)
				(type default)
			)
			(fill yes)
			(layer "F.SilkS")
		)
		(fp_line
			(start -0.849884 1.549908)
			(end 0.849884 1.549908)
			(stroke
				(width 0.1)
				(type default)
			)
			(layer "F.Fab")
		)
		(fp_line
			(start 0.849884 1.549908)
			(end 0.849884 -1.549908)
			(stroke
				(width 0.1)
				(type default)
			)
			(layer "F.Fab")
		)
		(fp_line
			(start -0.849884 -1.549908)
			(end -0.849884 1.549908)
			(stroke
				(width 0.1)
				(type default)
			)
			(layer "F.Fab")
		)
		(fp_line
			(start 0.849884 -1.549908)
			(end -0.849884 -1.549908)
			(stroke
				(width 0.1)
				(type default)
			)
			(layer "F.Fab")
		)
		(fp_poly
			(pts
				(xy -2.4384 -1.20396) (xy -2.4384 -0.69596) (xy -1.9304 -0.94996)
			)
			(stroke
				(width 0)
				(type default)
			)
			(fill yes)
			(layer "F.Fab")
		)
		(pad "1" smd rect
			(at -1.199896 -0.94996 180)
			(size 0.5588 0.8128)
			(layers "F.Cu" "F.Mask" "F.Paste")
			(net "HP_OCP_V3_1_EN")
		)
		(pad "2" smd rect
			(at -1.199896 0 180)
			(size 0.5588 0.8128)
			(layers "F.Cu" "F.Mask" "F.Paste")
			(net "HP_LVC3_OCP_V3_1_PRSNT2")
		)
		(pad "3" smd rect
			(at -1.199896 0.94996 180)
			(size 0.5588 0.8128)
			(layers "F.Cu" "F.Mask" "F.Paste")
			(net "GND")
		)
		(pad "4" smd rect
			(at 1.199896 0.94996 180)
			(size 0.5588 0.8128)
			(layers "F.Cu" "F.Mask" "F.Paste")
			(net "HP_LVC3_OCP_V3_1_EN")
		)
		(pad "5" smd rect
			(at 1.199896 -0.94996 180)
			(size 0.5588 0.8128)
			(layers "F.Cu" "F.Mask" "F.Paste")
			(net "P3V3_AUX")
		)
	)
	(footprint ""
		(layer "F.Cu")
		(at 355.236018 -244.03177 90)
		(property "Reference" "C1007"
			(at 0 0 90)
			(layer "F.SilkS")
			(hide yes)
			(effects
				(font
					(size 1.27 1.27)
				)
			)
		)
		(property "Value" ""
			(at 0 0 90)
			(layer "F.Fab")
			(effects
				(font
					(size 1.27 1.27)
				)
			)
		)
		(duplicate_pad_numbers_are_jumpers no)
		(fp_line
			(start 0.7874 -0.4064)
			(end 0.7874 0.4064)
			(stroke
				(width 0.1524)
				(type default)
			)
			(layer "F.SilkS")
		)
		(fp_line
			(start -0.7874 -0.4064)
			(end 0.7874 -0.4064)
			(stroke
				(width 0.1524)
				(type default)
			)
			(layer "F.SilkS")
		)
		(fp_line
			(start 0.7874 0.4064)
			(end -0.7874 0.4064)
			(stroke
				(width 0.1524)
				(type default)
			)
			(layer "F.SilkS")
		)
		(fp_line
			(start -0.7874 0.4064)
			(end -0.7874 -0.4064)
			(stroke
				(width 0.1524)
				(type default)
			)
			(layer "F.SilkS")
		)
		(fp_line
			(start -0.12065 -0.305054)
			(end -0.12065 -0.2794)
			(stroke
				(width 0.1)
				(type default)
			)
			(layer "F.Fab")
		)
		(fp_line
			(start -0.67945 -0.305054)
			(end -0.12065 -0.305054)
			(stroke
				(width 0.1)
				(type default)
			)
			(layer "F.Fab")
		)
		(fp_line
			(start 0.67945 -0.3048)
			(end 0.67945 0.3048)
			(stroke
				(width 0.1)
				(type default)
			)
			(layer "F.Fab")
		)
		(fp_line
			(start 0.12065 -0.3048)
			(end 0.67945 -0.3048)
			(stroke
				(width 0.1)
				(type default)
			)
			(layer "F.Fab")
		)
		(fp_line
			(start 0.12065 -0.2794)
			(end 0.12065 -0.3048)
			(stroke
				(width 0.1)
				(type default)
			)
			(layer "F.Fab")
		)
		(fp_line
			(start -0.12065 -0.2794)
			(end 0.12065 -0.2794)
			(stroke
				(width 0.1)
				(type default)
			)
			(layer "F.Fab")
		)
		(fp_line
			(start 0.120396 0.2794)
			(end -0.12065 0.2794)
			(stroke
				(width 0.1)
				(type default)
			)
			(layer "F.Fab")
		)
		(fp_line
			(start -0.12065 0.2794)
			(end -0.12065 0.3048)
			(stroke
				(width 0.1)
				(type default)
			)
			(layer "F.Fab")
		)
		(fp_line
			(start 0.67945 0.3048)
			(end 0.120396 0.3048)
			(stroke
				(width 0.1)
				(type default)
			)
			(layer "F.Fab")
		)
		(fp_line
			(start 0.120396 0.3048)
			(end 0.120396 0.2794)
			(stroke
				(width 0.1)
				(type default)
			)
			(layer "F.Fab")
		)
		(fp_line
			(start -0.12065 0.3048)
			(end -0.67945 0.3048)
			(stroke
				(width 0.1)
				(type default)
			)
			(layer "F.Fab")
		)
		(fp_line
			(start -0.67945 0.3048)
			(end -0.67945 -0.305054)
			(stroke
				(width 0.1)
				(type default)
			)
			(layer "F.Fab")
		)
		(pad "1" smd circle
			(at -0.40005 0 90)
			(size 0 0)
			(layers "F.Cu" "F.Mask" "F.Paste")
			(net "PVCCIN_CPU0")
		)
		(pad "2" smd circle
			(at 0.40005 0 90)
			(size 0 0)
			(layers "F.Cu" "F.Mask" "F.Paste")
			(net "GND")
		)
	)
	(footprint ""
		(layer "F.Cu")
		(at 216.1286 -121.1326)
		(property "Reference" "R4716"
			(at 0 0 0)
			(layer "F.SilkS")
			(hide yes)
			(effects
				(font
					(size 1.27 1.27)
				)
			)
		)
		(property "Value" ""
			(at 0 0 0)
			(layer "F.Fab")
			(effects
				(font
					(size 1.27 1.27)
				)
			)
		)
		(duplicate_pad_numbers_are_jumpers no)
		(fp_line
			(start -0.7874 -0.4064)
			(end 0.7874 -0.4064)
			(stroke
				(width 0.1524)
				(type default)
			)
			(layer "F.SilkS")
		)
		(fp_line
			(start -0.7874 0.4064)
			(end -0.7874 -0.4064)
			(stroke
				(width 0.1524)
				(type default)
			)
			(layer "F.SilkS")
		)
		(fp_line
			(start 0.7874 -0.4064)
			(end 0.7874 0.4064)
			(stroke
				(width 0.1524)
				(type default)
			)
			(layer "F.SilkS")
		)
		(fp_line
			(start 0.7874 0.4064)
			(end -0.7874 0.4064)
			(stroke
				(width 0.1524)
				(type default)
			)
			(layer "F.SilkS")
		)
		(fp_line
			(start -0.67945 -0.305054)
			(end -0.12065 -0.305054)
			(stroke
				(width 0.1)
				(type default)
			)
			(layer "F.Fab")
		)
		(fp_line
			(start -0.67945 0.3048)
			(end -0.67945 -0.305054)
			(stroke
				(width 0.1)
				(type default)
			)
			(layer "F.Fab")
		)
		(fp_line
			(start -0.12065 -0.305054)
			(end -0.12065 -0.2794)
			(stroke
				(width 0.1)
				(type default)
			)
			(layer "F.Fab")
		)
		(fp_line
			(start -0.12065 -0.2794)
			(end 0.12065 -0.2794)
			(stroke
				(width 0.1)
				(type default)
			)
			(layer "F.Fab")
		)
		(fp_line
			(start -0.12065 0.2794)
			(end -0.12065 0.3048)
			(stroke
				(width 0.1)
				(type default)
			)
			(layer "F.Fab")
		)
		(fp_line
			(start -0.12065 0.3048)
			(end -0.67945 0.3048)
			(stroke
				(width 0.1)
				(type default)
			)
			(layer "F.Fab")
		)
		(fp_line
			(start 0.120396 0.2794)
			(end -0.12065 0.2794)
			(stroke
				(width 0.1)
				(type default)
			)
			(layer "F.Fab")
		)
		(fp_line
			(start 0.120396 0.3048)
			(end 0.120396 0.2794)
			(stroke
				(width 0.1)
				(type default)
			)
			(layer "F.Fab")
		)
		(fp_line
			(start 0.12065 -0.3048)
			(end 0.67945 -0.3048)
			(stroke
				(width 0.1)
				(type default)
			)
			(layer "F.Fab")
		)
		(fp_line
			(start 0.12065 -0.2794)
			(end 0.12065 -0.3048)
			(stroke
				(width 0.1)
				(type default)
			)
			(layer "F.Fab")
		)
		(fp_line
			(start 0.67945 -0.3048)
			(end 0.67945 0.3048)
			(stroke
				(width 0.1)
				(type default)
			)
			(layer "F.Fab")
		)
		(fp_line
			(start 0.67945 0.3048)
			(end 0.120396 0.3048)
			(stroke
				(width 0.1)
				(type default)
			)
			(layer "F.Fab")
		)
		(pad "1" smd circle
			(at -0.40005 0)
			(size 0 0)
			(layers "F.Cu" "F.Mask" "F.Paste")
			(net "P3V3_AUX")
		)
		(pad "2" smd circle
			(at 0.40005 0)
			(size 0 0)
			(layers "F.Cu" "F.Mask" "F.Paste")
			(net "FM_AC_PWR_BTN_R_N")
		)
	)
	(footprint ""
		(layer "F.Cu")
		(at 457.8477 -385.08432 90)
		(property "Reference" "PU181"
			(at 4.0894 -2.363216 0)
			(unlocked yes)
			(layer "F.SilkS")
			(effects
				(font
					(size 0.7874 0.5842)
					(thickness 0.1524)
				)
				(justify left)
			)
		)
		(property "Value" ""
			(at 0 0 90)
			(layer "F.Fab")
			(effects
				(font
					(size 1.27 1.27)
				)
			)
		)
		(duplicate_pad_numbers_are_jumpers no)
		(fp_line
			(start 1.549908 -2.050034)
			(end 0.5842 -2.050034)
			(stroke
				(width 0.1524)
				(type default)
			)
			(layer "F.SilkS")
		)
		(fp_line
			(start -0.5842 -2.050034)
			(end -1.549908 -2.050034)
			(stroke
				(width 0.1524)
				(type default)
			)
			(layer "F.SilkS")
		)
		(fp_line
			(start -1.549908 -2.050034)
			(end -1.549908 -1.9812)
			(stroke
				(width 0.1524)
				(type default)
			)
			(layer "F.SilkS")
		)
		(fp_line
			(start 1.549908 -1.9812)
			(end 1.549908 -2.050034)
			(stroke
				(width 0.1524)
				(type default)
			)
			(layer "F.SilkS")
		)
		(fp_line
			(start -1.549908 1.9812)
			(end -1.549908 2.050034)
			(stroke
				(width 0.1524)
				(type default)
			)
			(layer "F.SilkS")
		)
		(fp_line
			(start 1.549908 2.050034)
			(end 1.549908 1.9304)
			(stroke
				(width 0.1524)
				(type default)
			)
			(layer "F.SilkS")
		)
		(fp_line
			(start 0 2.050034)
			(end 1.549908 2.050034)
			(stroke
				(width 0.1524)
				(type default)
			)
			(layer "F.SilkS")
		)
		(fp_line
			(start -1.549908 2.050034)
			(end -0.5842 2.050034)
			(stroke
				(width 0.1524)
				(type default)
			)
			(layer "F.SilkS")
		)
		(fp_poly
			(pts
				(xy -2.9464 -2.208022) (xy -2.9464 -1.192022) (xy -1.9304 -1.700022)
			)
			(stroke
				(width 0)
				(type default)
			)
			(fill yes)
			(layer "F.SilkS")
		)
		(fp_line
			(start 1.549908 -2.050034)
			(end -1.549908 -2.050034)
			(stroke
				(width 0.1)
				(type default)
			)
			(layer "F.Fab")
		)
		(fp_line
			(start -1.549908 -2.050034)
			(end -1.549908 2.050034)
			(stroke
				(width 0.1)
				(type default)
			)
			(layer "F.Fab")
		)
		(fp_line
			(start 1.549908 2.050034)
			(end 1.549908 -2.050034)
			(stroke
				(width 0.1)
				(type default)
			)
			(layer "F.Fab")
		)
		(fp_line
			(start -1.549908 2.050034)
			(end 1.549908 2.050034)
			(stroke
				(width 0.1)
				(type default)
			)
			(layer "F.Fab")
		)
		(fp_poly
			(pts
				(xy -2.9464 -2.208022) (xy -2.9464 -1.192022) (xy -1.9304 -1.700022)
			)
			(stroke
				(width 0)
				(type default)
			)
			(fill yes)
			(layer "F.Fab")
		)
		(pad "1" smd circle
			(at -1.35001 -1.700022 90)
			(size 0 0)
			(layers "F.Cu" "F.Mask" "F.Paste")
			(net "SW_P5V_AUX_BST")
		)
		(pad "2" smd rect
			(at -1.400048 -1.199896 180)
			(size 0.1778 0.8128)
			(layers "F.Cu" "F.Mask" "F.Paste")
			(net "GND")
		)
		(pad "3" smd rect
			(at -1.400048 -0.8001 180)
			(size 0.1778 0.8128)
			(layers "F.Cu" "F.Mask" "F.Paste")
			(net "P5V_AUX_CS")
		)
		(pad "4" smd rect
			(at -1.400048 -0.40005 180)
			(size 0.1778 0.8128)
			(layers "F.Cu" "F.Mask" "F.Paste")
			(net "P5V_AUX_MODE")
		)
		(pad "5" smd rect
			(at -1.400048 0 180)
			(size 0.1778 0.8128)
			(layers "F.Cu" "F.Mask" "F.Paste")
			(net "P5V_AUX_REF")
		)
		(pad "6" smd rect
			(at -1.400048 0.40005 180)
			(size 0.1778 0.8128)
			(layers "F.Cu" "F.Mask" "F.Paste")
			(net "GND")
		)
		(pad "7" smd rect
			(at -1.400048 0.8001 180)
			(size 0.1778 0.8128)
			(layers "F.Cu" "F.Mask" "F.Paste")
			(net "P5V_AUX_FB")
		)
		(pad "8" smd rect
			(at -1.400048 1.199896 180)
			(size 0.1778 0.8128)
			(layers "F.Cu" "F.Mask" "F.Paste")
			(net "PWRGD_P3V3_AUX")
		)
		(pad "9" smd rect
			(at -1.400048 1.700022 180)
			(size 0.3048 0.8128)
			(layers "F.Cu" "F.Mask" "F.Paste")
			(net "PWRGD_P5V_AUX_R")
		)
		(pad "10" smd rect
			(at -0.299974 1.299972 90)
			(size 0.3048 2.0066)
			(layers "F.Cu" "F.Mask" "F.Paste")
			(net "SW_P5V_AUX_FLT")
		)
		(pad "11_18" smd circle
			(at 1.175004 0.275082 90)
			(size 0 0)
			(layers "F.Cu" "F.Mask" "F.Paste")
			(net "GND")
		)
		(pad "19" smd rect
			(at 1.400048 -1.700022)
			(size 0.3048 0.8128)
			(layers "F.Cu" "F.Mask" "F.Paste")
			(net "P5V_AUX_VCC")
		)
		(pad "20" smd rect
			(at 0.299974 -1.299972 90)
			(size 0.3048 2.0066)
			(layers "F.Cu" "F.Mask" "F.Paste")
			(net "SW_P5V_AUX_SW")
		)
		(pad "21" smd rect
			(at -0.299974 -1.299972 90)
			(size 0.3048 2.0066)
			(layers "F.Cu" "F.Mask" "F.Paste")
			(net "SW_P5V_AUX_FLT")
		)
	)
	(footprint ""
		(layer "F.Cu")
		(at 356.667308 -333.804514 -90)
		(property "Reference" "PC298_P0_2"
			(at 0 0 270)
			(layer "F.SilkS")
			(hide yes)
			(effects
				(font
					(size 1.27 1.27)
				)
			)
		)
		(property "Value" ""
			(at 0 0 270)
			(layer "F.Fab")
			(effects
				(font
					(size 1.27 1.27)
				)
			)
		)
		(duplicate_pad_numbers_are_jumpers no)
		(fp_line
			(start -0.7874 0.4064)
			(end -0.7874 -0.4064)
			(stroke
				(width 0.1524)
				(type default)
			)
			(layer "F.SilkS")
		)
		(fp_line
			(start 0.7874 0.4064)
			(end -0.7874 0.4064)
			(stroke
				(width 0.1524)
				(type default)
			)
			(layer "F.SilkS")
		)
		(fp_line
			(start -0.7874 -0.4064)
			(end 0.7874 -0.4064)
			(stroke
				(width 0.1524)
				(type default)
			)
			(layer "F.SilkS")
		)
		(fp_line
			(start 0.7874 -0.4064)
			(end 0.7874 0.4064)
			(stroke
				(width 0.1524)
				(type default)
			)
			(layer "F.SilkS")
		)
		(fp_line
			(start -0.67945 0.3048)
			(end -0.67945 -0.305054)
			(stroke
				(width 0.1)
				(type default)
			)
			(layer "F.Fab")
		)
		(fp_line
			(start -0.12065 0.3048)
			(end -0.67945 0.3048)
			(stroke
				(width 0.1)
				(type default)
			)
			(layer "F.Fab")
		)
		(fp_line
			(start 0.120396 0.3048)
			(end 0.120396 0.2794)
			(stroke
				(width 0.1)
				(type default)
			)
			(layer "F.Fab")
		)
		(fp_line
			(start 0.67945 0.3048)
			(end 0.120396 0.3048)
			(stroke
				(width 0.1)
				(type default)
			)
			(layer "F.Fab")
		)
		(fp_line
			(start -0.12065 0.2794)
			(end -0.12065 0.3048)
			(stroke
				(width 0.1)
				(type default)
			)
			(layer "F.Fab")
		)
		(fp_line
			(start 0.120396 0.2794)
			(end -0.12065 0.2794)
			(stroke
				(width 0.1)
				(type default)
			)
			(layer "F.Fab")
		)
		(fp_line
			(start -0.12065 -0.2794)
			(end 0.12065 -0.2794)
			(stroke
				(width 0.1)
				(type default)
			)
			(layer "F.Fab")
		)
		(fp_line
			(start 0.12065 -0.2794)
			(end 0.12065 -0.3048)
			(stroke
				(width 0.1)
				(type default)
			)
			(layer "F.Fab")
		)
		(fp_line
			(start 0.12065 -0.3048)
			(end 0.67945 -0.3048)
			(stroke
				(width 0.1)
				(type default)
			)
			(layer "F.Fab")
		)
		(fp_line
			(start 0.67945 -0.3048)
			(end 0.67945 0.3048)
			(stroke
				(width 0.1)
				(type default)
			)
			(layer "F.Fab")
		)
		(fp_line
			(start -0.67945 -0.305054)
			(end -0.12065 -0.305054)
			(stroke
				(width 0.1)
				(type default)
			)
			(layer "F.Fab")
		)
		(fp_line
			(start -0.12065 -0.305054)
			(end -0.12065 -0.2794)
			(stroke
				(width 0.1)
				(type default)
			)
			(layer "F.Fab")
		)
		(pad "1" smd circle
			(at -0.40005 0 270)
			(size 0 0)
			(layers "F.Cu" "F.Mask" "F.Paste")
			(net "SW_P12V_PVCCIN_CPU0_FLT")
		)
		(pad "2" smd circle
			(at 0.40005 0 270)
			(size 0 0)
			(layers "F.Cu" "F.Mask" "F.Paste")
			(net "GND")
		)
	)
	(footprint ""
		(layer "F.Cu")
		(at 216.1286 -119.1514 180)
		(property "Reference" "R4717"
			(at 0 0 180)
			(layer "F.SilkS")
			(hide yes)
			(effects
				(font
					(size 1.27 1.27)
				)
			)
		)
		(property "Value" ""
			(at 0 0 180)
			(layer "F.Fab")
			(effects
				(font
					(size 1.27 1.27)
				)
			)
		)
		(duplicate_pad_numbers_are_jumpers no)
		(fp_line
			(start 0.7874 0.4064)
			(end -0.7874 0.4064)
			(stroke
				(width 0.1524)
				(type default)
			)
			(layer "F.SilkS")
		)
		(fp_line
			(start 0.7874 -0.4064)
			(end 0.7874 0.4064)
			(stroke
				(width 0.1524)
				(type default)
			)
			(layer "F.SilkS")
		)
		(fp_line
			(start -0.7874 0.4064)
			(end -0.7874 -0.4064)
			(stroke
				(width 0.1524)
				(type default)
			)
			(layer "F.SilkS")
		)
		(fp_line
			(start -0.7874 -0.4064)
			(end 0.7874 -0.4064)
			(stroke
				(width 0.1524)
				(type default)
			)
			(layer "F.SilkS")
		)
		(fp_line
			(start 0.67945 0.3048)
			(end 0.120396 0.3048)
			(stroke
				(width 0.1)
				(type default)
			)
			(layer "F.Fab")
		)
		(fp_line
			(start 0.67945 -0.3048)
			(end 0.67945 0.3048)
			(stroke
				(width 0.1)
				(type default)
			)
			(layer "F.Fab")
		)
		(fp_line
			(start 0.12065 -0.2794)
			(end 0.12065 -0.3048)
			(stroke
				(width 0.1)
				(type default)
			)
			(layer "F.Fab")
		)
		(fp_line
			(start 0.12065 -0.3048)
			(end 0.67945 -0.3048)
			(stroke
				(width 0.1)
				(type default)
			)
			(layer "F.Fab")
		)
		(fp_line
			(start 0.120396 0.3048)
			(end 0.120396 0.2794)
			(stroke
				(width 0.1)
				(type default)
			)
			(layer "F.Fab")
		)
		(fp_line
			(start 0.120396 0.2794)
			(end -0.12065 0.2794)
			(stroke
				(width 0.1)
				(type default)
			)
			(layer "F.Fab")
		)
		(fp_line
			(start -0.12065 0.3048)
			(end -0.67945 0.3048)
			(stroke
				(width 0.1)
				(type default)
			)
			(layer "F.Fab")
		)
		(fp_line
			(start -0.12065 0.2794)
			(end -0.12065 0.3048)
			(stroke
				(width 0.1)
				(type default)
			)
			(layer "F.Fab")
		)
		(fp_line
			(start -0.12065 -0.2794)
			(end 0.12065 -0.2794)
			(stroke
				(width 0.1)
				(type default)
			)
			(layer "F.Fab")
		)
		(fp_line
			(start -0.12065 -0.305054)
			(end -0.12065 -0.2794)
			(stroke
				(width 0.1)
				(type default)
			)
			(layer "F.Fab")
		)
		(fp_line
			(start -0.67945 0.3048)
			(end -0.67945 -0.305054)
			(stroke
				(width 0.1)
				(type default)
			)
			(layer "F.Fab")
		)
		(fp_line
			(start -0.67945 -0.305054)
			(end -0.12065 -0.305054)
			(stroke
				(width 0.1)
				(type default)
			)
			(layer "F.Fab")
		)
		(pad "1" smd circle
			(at -0.40005 0 180)
			(size 0 0)
			(layers "F.Cu" "F.Mask" "F.Paste")
			(net "FM_AC_PWR_BTN_R_N")
		)
		(pad "2" smd circle
			(at 0.40005 0 180)
			(size 0 0)
			(layers "F.Cu" "F.Mask" "F.Paste")
			(net "FM_AC_PWR_BTN_PLD_N")
		)
	)
	(footprint ""
		(layer "F.Cu")
		(at 96.294448 -74.767694 -90)
		(property "Reference" "R3078"
			(at 0 0 270)
			(layer "F.SilkS")
			(hide yes)
			(effects
				(font
					(size 1.27 1.27)
				)
			)
		)
		(property "Value" ""
			(at 0 0 270)
			(layer "F.Fab")
			(effects
				(font
					(size 1.27 1.27)
				)
			)
		)
		(duplicate_pad_numbers_are_jumpers no)
		(fp_line
			(start -0.7874 0.4064)
			(end -0.7874 -0.4064)
			(stroke
				(width 0.1524)
				(type default)
			)
			(layer "F.SilkS")
		)
		(fp_line
			(start 0.7874 0.4064)
			(end -0.7874 0.4064)
			(stroke
				(width 0.1524)
				(type default)
			)
			(layer "F.SilkS")
		)
		(fp_line
			(start -0.7874 -0.4064)
			(end 0.7874 -0.4064)
			(stroke
				(width 0.1524)
				(type default)
			)
			(layer "F.SilkS")
		)
		(fp_line
			(start 0.7874 -0.4064)
			(end 0.7874 0.4064)
			(stroke
				(width 0.1524)
				(type default)
			)
			(layer "F.SilkS")
		)
		(fp_line
			(start -0.67945 0.3048)
			(end -0.67945 -0.305054)
			(stroke
				(width 0.1)
				(type default)
			)
			(layer "F.Fab")
		)
		(fp_line
			(start -0.12065 0.3048)
			(end -0.67945 0.3048)
			(stroke
				(width 0.1)
				(type default)
			)
			(layer "F.Fab")
		)
		(fp_line
			(start 0.120396 0.3048)
			(end 0.120396 0.2794)
			(stroke
				(width 0.1)
				(type default)
			)
			(layer "F.Fab")
		)
		(fp_line
			(start 0.67945 0.3048)
			(end 0.120396 0.3048)
			(stroke
				(width 0.1)
				(type default)
			)
			(layer "F.Fab")
		)
		(fp_line
			(start -0.12065 0.2794)
			(end -0.12065 0.3048)
			(stroke
				(width 0.1)
				(type default)
			)
			(layer "F.Fab")
		)
		(fp_line
			(start 0.120396 0.2794)
			(end -0.12065 0.2794)
			(stroke
				(width 0.1)
				(type default)
			)
			(layer "F.Fab")
		)
		(fp_line
			(start -0.12065 -0.2794)
			(end 0.12065 -0.2794)
			(stroke
				(width 0.1)
				(type default)
			)
			(layer "F.Fab")
		)
		(fp_line
			(start 0.12065 -0.2794)
			(end 0.12065 -0.3048)
			(stroke
				(width 0.1)
				(type default)
			)
			(layer "F.Fab")
		)
		(fp_line
			(start 0.12065 -0.3048)
			(end 0.67945 -0.3048)
			(stroke
				(width 0.1)
				(type default)
			)
			(layer "F.Fab")
		)
		(fp_line
			(start 0.67945 -0.3048)
			(end 0.67945 0.3048)
			(stroke
				(width 0.1)
				(type default)
			)
			(layer "F.Fab")
		)
		(fp_line
			(start -0.67945 -0.305054)
			(end -0.12065 -0.305054)
			(stroke
				(width 0.1)
				(type default)
			)
			(layer "F.Fab")
		)
		(fp_line
			(start -0.12065 -0.305054)
			(end -0.12065 -0.2794)
			(stroke
				(width 0.1)
				(type default)
			)
			(layer "F.Fab")
		)
		(pad "1" smd circle
			(at -0.40005 0 270)
			(size 0 0)
			(layers "F.Cu" "F.Mask" "F.Paste")
			(net "LED_FM_PCH_SLP_S3_N")
		)
		(pad "2" smd circle
			(at 0.40005 0 270)
			(size 0 0)
			(layers "F.Cu" "F.Mask" "F.Paste")
			(net "P3V3_AUX")
		)
	)
	(footprint ""
		(layer "F.Cu")
		(at 155.690824 -52.674012)
		(property "Reference" "C2018"
			(at 0 0 0)
			(layer "F.SilkS")
			(hide yes)
			(effects
				(font
					(size 1.27 1.27)
				)
			)
		)
		(property "Value" ""
			(at 0 0 0)
			(layer "F.Fab")
			(effects
				(font
					(size 1.27 1.27)
				)
			)
		)
		(duplicate_pad_numbers_are_jumpers no)
		(fp_line
			(start -0.7874 -0.4064)
			(end 0.7874 -0.4064)
			(stroke
				(width 0.1524)
				(type default)
			)
			(layer "F.SilkS")
		)
		(fp_line
			(start -0.7874 0.4064)
			(end -0.7874 -0.4064)
			(stroke
				(width 0.1524)
				(type default)
			)
			(layer "F.SilkS")
		)
		(fp_line
			(start 0.7874 -0.4064)
			(end 0.7874 0.4064)
			(stroke
				(width 0.1524)
				(type default)
			)
			(layer "F.SilkS")
		)
		(fp_line
			(start 0.7874 0.4064)
			(end -0.7874 0.4064)
			(stroke
				(width 0.1524)
				(type default)
			)
			(layer "F.SilkS")
		)
		(fp_line
			(start -0.67945 -0.305054)
			(end -0.12065 -0.305054)
			(stroke
				(width 0.1)
				(type default)
			)
			(layer "F.Fab")
		)
		(fp_line
			(start -0.67945 0.3048)
			(end -0.67945 -0.305054)
			(stroke
				(width 0.1)
				(type default)
			)
			(layer "F.Fab")
		)
		(fp_line
			(start -0.12065 -0.305054)
			(end -0.12065 -0.2794)
			(stroke
				(width 0.1)
				(type default)
			)
			(layer "F.Fab")
		)
		(fp_line
			(start -0.12065 -0.2794)
			(end 0.12065 -0.2794)
			(stroke
				(width 0.1)
				(type default)
			)
			(layer "F.Fab")
		)
		(fp_line
			(start -0.12065 0.2794)
			(end -0.12065 0.3048)
			(stroke
				(width 0.1)
				(type default)
			)
			(layer "F.Fab")
		)
		(fp_line
			(start -0.12065 0.3048)
			(end -0.67945 0.3048)
			(stroke
				(width 0.1)
				(type default)
			)
			(layer "F.Fab")
		)
		(fp_line
			(start 0.120396 0.2794)
			(end -0.12065 0.2794)
			(stroke
				(width 0.1)
				(type default)
			)
			(layer "F.Fab")
		)
		(fp_line
			(start 0.120396 0.3048)
			(end 0.120396 0.2794)
			(stroke
				(width 0.1)
				(type default)
			)
			(layer "F.Fab")
		)
		(fp_line
			(start 0.12065 -0.3048)
			(end 0.67945 -0.3048)
			(stroke
				(width 0.1)
				(type default)
			)
			(layer "F.Fab")
		)
		(fp_line
			(start 0.12065 -0.2794)
			(end 0.12065 -0.3048)
			(stroke
				(width 0.1)
				(type default)
			)
			(layer "F.Fab")
		)
		(fp_line
			(start 0.67945 -0.3048)
			(end 0.67945 0.3048)
			(stroke
				(width 0.1)
				(type default)
			)
			(layer "F.Fab")
		)
		(fp_line
			(start 0.67945 0.3048)
			(end 0.120396 0.3048)
			(stroke
				(width 0.1)
				(type default)
			)
			(layer "F.Fab")
		)
		(pad "1" smd circle
			(at -0.40005 0)
			(size 0 0)
			(layers "F.Cu" "F.Mask" "F.Paste")
			(net "P3V3")
		)
		(pad "2" smd circle
			(at 0.40005 0)
			(size 0 0)
			(layers "F.Cu" "F.Mask" "F.Paste")
			(net "GND")
		)
	)
	(footprint ""
		(layer "F.Cu")
		(at 390.587484 -331.449172 90)
		(property "Reference" "PC242_P0_8"
			(at 0 0 90)
			(layer "F.SilkS")
			(hide yes)
			(effects
				(font
					(size 1.27 1.27)
				)
			)
		)
		(property "Value" ""
			(at 0 0 90)
			(layer "F.Fab")
			(effects
				(font
					(size 1.27 1.27)
				)
			)
		)
		(duplicate_pad_numbers_are_jumpers no)
		(fp_line
			(start 0.7874 -0.4064)
			(end 0.7874 0.4064)
			(stroke
				(width 0.1524)
				(type default)
			)
			(layer "F.SilkS")
		)
		(fp_line
			(start -0.7874 -0.4064)
			(end 0.7874 -0.4064)
			(stroke
				(width 0.1524)
				(type default)
			)
			(layer "F.SilkS")
		)
		(fp_line
			(start 0.7874 0.4064)
			(end -0.7874 0.4064)
			(stroke
				(width 0.1524)
				(type default)
			)
			(layer "F.SilkS")
		)
		(fp_line
			(start -0.7874 0.4064)
			(end -0.7874 -0.4064)
			(stroke
				(width 0.1524)
				(type default)
			)
			(layer "F.SilkS")
		)
		(fp_line
			(start -0.12065 -0.305054)
			(end -0.12065 -0.2794)
			(stroke
				(width 0.1)
				(type default)
			)
			(layer "F.Fab")
		)
		(fp_line
			(start -0.67945 -0.305054)
			(end -0.12065 -0.305054)
			(stroke
				(width 0.1)
				(type default)
			)
			(layer "F.Fab")
		)
		(fp_line
			(start 0.67945 -0.3048)
			(end 0.67945 0.3048)
			(stroke
				(width 0.1)
				(type default)
			)
			(layer "F.Fab")
		)
		(fp_line
			(start 0.12065 -0.3048)
			(end 0.67945 -0.3048)
			(stroke
				(width 0.1)
				(type default)
			)
			(layer "F.Fab")
		)
		(fp_line
			(start 0.12065 -0.2794)
			(end 0.12065 -0.3048)
			(stroke
				(width 0.1)
				(type default)
			)
			(layer "F.Fab")
		)
		(fp_line
			(start -0.12065 -0.2794)
			(end 0.12065 -0.2794)
			(stroke
				(width 0.1)
				(type default)
			)
			(layer "F.Fab")
		)
		(fp_line
			(start 0.120396 0.2794)
			(end -0.12065 0.2794)
			(stroke
				(width 0.1)
				(type default)
			)
			(layer "F.Fab")
		)
		(fp_line
			(start -0.12065 0.2794)
			(end -0.12065 0.3048)
			(stroke
				(width 0.1)
				(type default)
			)
			(layer "F.Fab")
		)
		(fp_line
			(start 0.67945 0.3048)
			(end 0.120396 0.3048)
			(stroke
				(width 0.1)
				(type default)
			)
			(layer "F.Fab")
		)
		(fp_line
			(start 0.120396 0.3048)
			(end 0.120396 0.2794)
			(stroke
				(width 0.1)
				(type default)
			)
			(layer "F.Fab")
		)
		(fp_line
			(start -0.12065 0.3048)
			(end -0.67945 0.3048)
			(stroke
				(width 0.1)
				(type default)
			)
			(layer "F.Fab")
		)
		(fp_line
			(start -0.67945 0.3048)
			(end -0.67945 -0.305054)
			(stroke
				(width 0.1)
				(type default)
			)
			(layer "F.Fab")
		)
		(pad "1" smd circle
			(at -0.40005 0 90)
			(size 0 0)
			(layers "F.Cu" "F.Mask" "F.Paste")
			(net "PVCCIN_CPU0")
		)
		(pad "2" smd circle
			(at 0.40005 0 90)
			(size 0 0)
			(layers "F.Cu" "F.Mask" "F.Paste")
			(net "GND")
		)
	)
	(footprint ""
		(layer "F.Cu")
		(at 9.58088 -52.923948)
		(property "Reference" "R3050"
			(at 0 0 0)
			(layer "F.SilkS")
			(hide yes)
			(effects
				(font
					(size 1.27 1.27)
				)
			)
		)
		(property "Value" ""
			(at 0 0 0)
			(layer "F.Fab")
			(effects
				(font
					(size 1.27 1.27)
				)
			)
		)
		(duplicate_pad_numbers_are_jumpers no)
		(fp_line
			(start -0.7874 -0.4064)
			(end 0.7874 -0.4064)
			(stroke
				(width 0.1524)
				(type default)
			)
			(layer "F.SilkS")
		)
		(fp_line
			(start -0.7874 0.4064)
			(end -0.7874 -0.4064)
			(stroke
				(width 0.1524)
				(type default)
			)
			(layer "F.SilkS")
		)
		(fp_line
			(start 0.7874 -0.4064)
			(end 0.7874 0.4064)
			(stroke
				(width 0.1524)
				(type default)
			)
			(layer "F.SilkS")
		)
		(fp_line
			(start 0.7874 0.4064)
			(end -0.7874 0.4064)
			(stroke
				(width 0.1524)
				(type default)
			)
			(layer "F.SilkS")
		)
		(fp_line
			(start -0.67945 -0.305054)
			(end -0.12065 -0.305054)
			(stroke
				(width 0.1)
				(type default)
			)
			(layer "F.Fab")
		)
		(fp_line
			(start -0.67945 0.3048)
			(end -0.67945 -0.305054)
			(stroke
				(width 0.1)
				(type default)
			)
			(layer "F.Fab")
		)
		(fp_line
			(start -0.12065 -0.305054)
			(end -0.12065 -0.2794)
			(stroke
				(width 0.1)
				(type default)
			)
			(layer "F.Fab")
		)
		(fp_line
			(start -0.12065 -0.2794)
			(end 0.12065 -0.2794)
			(stroke
				(width 0.1)
				(type default)
			)
			(layer "F.Fab")
		)
		(fp_line
			(start -0.12065 0.2794)
			(end -0.12065 0.3048)
			(stroke
				(width 0.1)
				(type default)
			)
			(layer "F.Fab")
		)
		(fp_line
			(start -0.12065 0.3048)
			(end -0.67945 0.3048)
			(stroke
				(width 0.1)
				(type default)
			)
			(layer "F.Fab")
		)
		(fp_line
			(start 0.120396 0.2794)
			(end -0.12065 0.2794)
			(stroke
				(width 0.1)
				(type default)
			)
			(layer "F.Fab")
		)
		(fp_line
			(start 0.120396 0.3048)
			(end 0.120396 0.2794)
			(stroke
				(width 0.1)
				(type default)
			)
			(layer "F.Fab")
		)
		(fp_line
			(start 0.12065 -0.3048)
			(end 0.67945 -0.3048)
			(stroke
				(width 0.1)
				(type default)
			)
			(layer "F.Fab")
		)
		(fp_line
			(start 0.12065 -0.2794)
			(end 0.12065 -0.3048)
			(stroke
				(width 0.1)
				(type default)
			)
			(layer "F.Fab")
		)
		(fp_line
			(start 0.67945 -0.3048)
			(end 0.67945 0.3048)
			(stroke
				(width 0.1)
				(type default)
			)
			(layer "F.Fab")
		)
		(fp_line
			(start 0.67945 0.3048)
			(end 0.120396 0.3048)
			(stroke
				(width 0.1)
				(type default)
			)
			(layer "F.Fab")
		)
		(pad "1" smd circle
			(at -0.40005 0)
			(size 0 0)
			(layers "F.Cu" "F.Mask" "F.Paste")
			(net "RST_RSMRST_PLD_R_N")
		)
		(pad "2" smd circle
			(at 0.40005 0)
			(size 0 0)
			(layers "F.Cu" "F.Mask" "F.Paste")
			(net "RST_RSMRST_NM_HDR_N")
		)
	)
	(footprint ""
		(layer "F.Cu")
		(at 463.636106 -110.287308 180)
		(property "Reference" "R1150"
			(at 0 0 180)
			(layer "F.SilkS")
			(hide yes)
			(effects
				(font
					(size 1.27 1.27)
				)
			)
		)
		(property "Value" ""
			(at 0 0 180)
			(layer "F.Fab")
			(effects
				(font
					(size 1.27 1.27)
				)
			)
		)
		(duplicate_pad_numbers_are_jumpers no)
		(fp_line
			(start 0.7874 0.4064)
			(end -0.7874 0.4064)
			(stroke
				(width 0.1524)
				(type default)
			)
			(layer "F.SilkS")
		)
		(fp_line
			(start 0.7874 -0.4064)
			(end 0.7874 0.4064)
			(stroke
				(width 0.1524)
				(type default)
			)
			(layer "F.SilkS")
		)
		(fp_line
			(start -0.7874 0.4064)
			(end -0.7874 -0.4064)
			(stroke
				(width 0.1524)
				(type default)
			)
			(layer "F.SilkS")
		)
		(fp_line
			(start -0.7874 -0.4064)
			(end 0.7874 -0.4064)
			(stroke
				(width 0.1524)
				(type default)
			)
			(layer "F.SilkS")
		)
		(fp_line
			(start 0.67945 0.3048)
			(end 0.120396 0.3048)
			(stroke
				(width 0.1)
				(type default)
			)
			(layer "F.Fab")
		)
		(fp_line
			(start 0.67945 -0.3048)
			(end 0.67945 0.3048)
			(stroke
				(width 0.1)
				(type default)
			)
			(layer "F.Fab")
		)
		(fp_line
			(start 0.12065 -0.2794)
			(end 0.12065 -0.3048)
			(stroke
				(width 0.1)
				(type default)
			)
			(layer "F.Fab")
		)
		(fp_line
			(start 0.12065 -0.3048)
			(end 0.67945 -0.3048)
			(stroke
				(width 0.1)
				(type default)
			)
			(layer "F.Fab")
		)
		(fp_line
			(start 0.120396 0.3048)
			(end 0.120396 0.2794)
			(stroke
				(width 0.1)
				(type default)
			)
			(layer "F.Fab")
		)
		(fp_line
			(start 0.120396 0.2794)
			(end -0.12065 0.2794)
			(stroke
				(width 0.1)
				(type default)
			)
			(layer "F.Fab")
		)
		(fp_line
			(start -0.12065 0.3048)
			(end -0.67945 0.3048)
			(stroke
				(width 0.1)
				(type default)
			)
			(layer "F.Fab")
		)
		(fp_line
			(start -0.12065 0.2794)
			(end -0.12065 0.3048)
			(stroke
				(width 0.1)
				(type default)
			)
			(layer "F.Fab")
		)
		(fp_line
			(start -0.12065 -0.2794)
			(end 0.12065 -0.2794)
			(stroke
				(width 0.1)
				(type default)
			)
			(layer "F.Fab")
		)
		(fp_line
			(start -0.12065 -0.305054)
			(end -0.12065 -0.2794)
			(stroke
				(width 0.1)
				(type default)
			)
			(layer "F.Fab")
		)
		(fp_line
			(start -0.67945 0.3048)
			(end -0.67945 -0.305054)
			(stroke
				(width 0.1)
				(type default)
			)
			(layer "F.Fab")
		)
		(fp_line
			(start -0.67945 -0.305054)
			(end -0.12065 -0.305054)
			(stroke
				(width 0.1)
				(type default)
			)
			(layer "F.Fab")
		)
		(pad "1" smd circle
			(at -0.40005 0 180)
			(size 0 0)
			(layers "F.Cu" "F.Mask" "F.Paste")
			(net "P3V3_AUX")
		)
		(pad "2" smd circle
			(at 0.40005 0 180)
			(size 0 0)
			(layers "F.Cu" "F.Mask" "F.Paste")
			(net "HP_LVC3_OCP_V3_1_PRSNT2_N")
		)
	)
	(footprint ""
		(layer "F.Cu")
		(at 165.47846 -56.820308 90)
		(property "Reference" "C1920"
			(at 0 0 90)
			(layer "F.SilkS")
			(hide yes)
			(effects
				(font
					(size 1.27 1.27)
				)
			)
		)
		(property "Value" ""
			(at 0 0 90)
			(layer "F.Fab")
			(effects
				(font
					(size 1.27 1.27)
				)
			)
		)
		(duplicate_pad_numbers_are_jumpers no)
		(fp_line
			(start 1.2954 -0.5842)
			(end 1.2954 0.5842)
			(stroke
				(width 0.1524)
				(type default)
			)
			(layer "F.SilkS")
		)
		(fp_line
			(start 0 -0.5842)
			(end 0 0.5842)
			(stroke
				(width 0.1524)
				(type default)
			)
			(layer "F.SilkS")
		)
		(fp_line
			(start -1.2954 -0.5842)
			(end 1.2954 -0.5842)
			(stroke
				(width 0.1524)
				(type default)
			)
			(layer "F.SilkS")
		)
		(fp_line
			(start 1.2954 0.5842)
			(end -1.2954 0.5842)
			(stroke
				(width 0.1524)
				(type default)
			)
			(layer "F.SilkS")
		)
		(fp_line
			(start -1.2954 0.5842)
			(end -1.2954 -0.5842)
			(stroke
				(width 0.1524)
				(type default)
			)
			(layer "F.SilkS")
		)
		(fp_line
			(start 0.8636 -0.4572)
			(end 0.8636 -0.4064)
			(stroke
				(width 0.1)
				(type default)
			)
			(layer "F.Fab")
		)
		(fp_line
			(start -0.8636 -0.4572)
			(end 0.8636 -0.4572)
			(stroke
				(width 0.1)
				(type default)
			)
			(layer "F.Fab")
		)
		(fp_line
			(start 1.1938 -0.4064)
			(end 1.1938 0.4064)
			(stroke
				(width 0.1)
				(type default)
			)
			(layer "F.Fab")
		)
		(fp_line
			(start 0.8636 -0.4064)
			(end 1.1938 -0.4064)
			(stroke
				(width 0.1)
				(type default)
			)
			(layer "F.Fab")
		)
		(fp_line
			(start -0.8636 -0.4064)
			(end -0.8636 -0.4572)
			(stroke
				(width 0.1)
				(type default)
			)
			(layer "F.Fab")
		)
		(fp_line
			(start -1.1938 -0.4064)
			(end -0.8636 -0.4064)
			(stroke
				(width 0.1)
				(type default)
			)
			(layer "F.Fab")
		)
		(fp_line
			(start 1.1938 0.4064)
			(end 0.8636 0.4064)
			(stroke
				(width 0.1)
				(type default)
			)
			(layer "F.Fab")
		)
		(fp_line
			(start 0.8636 0.4064)
			(end 0.8636 0.4572)
			(stroke
				(width 0.1)
				(type default)
			)
			(layer "F.Fab")
		)
		(fp_line
			(start -0.8636 0.4064)
			(end -1.1938 0.4064)
			(stroke
				(width 0.1)
				(type default)
			)
			(layer "F.Fab")
		)
		(fp_line
			(start -1.1938 0.4064)
			(end -1.1938 -0.4064)
			(stroke
				(width 0.1)
				(type default)
			)
			(layer "F.Fab")
		)
		(fp_line
			(start 0.8636 0.4572)
			(end -0.8636 0.4572)
			(stroke
				(width 0.1)
				(type default)
			)
			(layer "F.Fab")
		)
		(fp_line
			(start -0.8636 0.4572)
			(end -0.8636 0.4064)
			(stroke
				(width 0.1)
				(type default)
			)
			(layer "F.Fab")
		)
		(pad "1" smd rect
			(at -0.7366 0)
			(size 0.7112 0.8128)
			(layers "F.Cu" "F.Mask" "F.Paste")
			(net "P3V3_M2_0")
		)
		(pad "2" smd rect
			(at 0.7366 0)
			(size 0.7112 0.8128)
			(layers "F.Cu" "F.Mask" "F.Paste")
			(net "GND")
		)
	)
	(footprint ""
		(layer "F.Cu")
		(at 70.743318 -408.517344 -90)
		(property "Reference" "C694"
			(at 0 0 270)
			(layer "F.SilkS")
			(hide yes)
			(effects
				(font
					(size 1.27 1.27)
				)
			)
		)
		(property "Value" ""
			(at 0 0 270)
			(layer "F.Fab")
			(effects
				(font
					(size 1.27 1.27)
				)
			)
		)
		(duplicate_pad_numbers_are_jumpers no)
		(fp_line
			(start -0.299974 0.150114)
			(end -0.299974 -0.150114)
			(stroke
				(width 0.1)
				(type default)
			)
			(layer "F.Fab")
		)
		(fp_line
			(start 0.299974 0.150114)
			(end -0.299974 0.150114)
			(stroke
				(width 0.1)
				(type default)
			)
			(layer "F.Fab")
		)
		(fp_line
			(start -0.299974 -0.150114)
			(end 0.299974 -0.150114)
			(stroke
				(width 0.1)
				(type default)
			)
			(layer "F.Fab")
		)
		(fp_line
			(start 0.299974 -0.150114)
			(end 0.299974 0.150114)
			(stroke
				(width 0.1)
				(type default)
			)
			(layer "F.Fab")
		)
		(pad "1" smd rect
			(at -0.2667 0 270)
			(size 0.3048 0.381)
			(layers "F.Cu" "F.Mask" "F.Paste")
			(net "P5E_CPU1_PE4_TX_C_DN<7>")
		)
		(pad "2" smd rect
			(at 0.2667 0 270)
			(size 0.3048 0.381)
			(layers "F.Cu" "F.Mask" "F.Paste")
			(net "P5E_CPU1_PE4_TX_DN<7>")
		)
	)
	(footprint ""
		(layer "F.Cu")
		(at 126.91872 -22.172168 90)
		(property "Reference" "L18"
			(at 0 0 90)
			(layer "F.SilkS")
			(hide yes)
			(effects
				(font
					(size 1.27 1.27)
				)
			)
		)
		(property "Value" ""
			(at 0 0 90)
			(layer "F.Fab")
			(effects
				(font
					(size 1.27 1.27)
				)
			)
		)
		(duplicate_pad_numbers_are_jumpers no)
		(fp_line
			(start 0.762 -0.381)
			(end 0.762 0.381)
			(stroke
				(width 0.1524)
				(type default)
			)
			(layer "F.SilkS")
		)
		(fp_line
			(start -0.762 -0.381)
			(end 0.762 -0.381)
			(stroke
				(width 0.1524)
				(type default)
			)
			(layer "F.SilkS")
		)
		(fp_line
			(start 0.762 0.381)
			(end -0.762 0.381)
			(stroke
				(width 0.1524)
				(type default)
			)
			(layer "F.SilkS")
		)
		(fp_line
			(start -0.762 0.381)
			(end -0.762 -0.381)
			(stroke
				(width 0.1524)
				(type default)
			)
			(layer "F.SilkS")
		)
		(fp_line
			(start -0.118364 -0.307086)
			(end -0.118364 -0.2794)
			(stroke
				(width 0.1)
				(type default)
			)
			(layer "F.Fab")
		)
		(fp_line
			(start -0.681736 -0.307086)
			(end -0.118364 -0.307086)
			(stroke
				(width 0.1)
				(type default)
			)
			(layer "F.Fab")
		)
		(fp_line
			(start 0.680466 -0.306324)
			(end 0.680466 0.306324)
			(stroke
				(width 0.1)
				(type default)
			)
			(layer "F.Fab")
		)
		(fp_line
			(start 0.118872 -0.306324)
			(end 0.680466 -0.306324)
			(stroke
				(width 0.1)
				(type default)
			)
			(layer "F.Fab")
		)
		(fp_line
			(start 0.118872 -0.2794)
			(end 0.118872 -0.306324)
			(stroke
				(width 0.1)
				(type default)
			)
			(layer "F.Fab")
		)
		(fp_line
			(start -0.118364 -0.2794)
			(end 0.118872 -0.2794)
			(stroke
				(width 0.1)
				(type default)
			)
			(layer "F.Fab")
		)
		(fp_line
			(start 0.118364 0.2794)
			(end -0.119634 0.2794)
			(stroke
				(width 0.1)
				(type default)
			)
			(layer "F.Fab")
		)
		(fp_line
			(start -0.119634 0.2794)
			(end -0.119634 0.30607)
			(stroke
				(width 0.1)
				(type default)
			)
			(layer "F.Fab")
		)
		(fp_line
			(start -0.119634 0.30607)
			(end -0.681736 0.30607)
			(stroke
				(width 0.1)
				(type default)
			)
			(layer "F.Fab")
		)
		(fp_line
			(start -0.681736 0.30607)
			(end -0.681736 -0.307086)
			(stroke
				(width 0.1)
				(type default)
			)
			(layer "F.Fab")
		)
		(fp_line
			(start 0.680466 0.306324)
			(end 0.118364 0.306324)
			(stroke
				(width 0.1)
				(type default)
			)
			(layer "F.Fab")
		)
		(fp_line
			(start 0.118364 0.306324)
			(end 0.118364 0.2794)
			(stroke
				(width 0.1)
				(type default)
			)
			(layer "F.Fab")
		)
		(pad "1" smd rect
			(at -0.40005 0 270)
			(size 0.4572 0.508)
			(layers "F.Cu" "F.Mask" "F.Paste")
			(net "P3V3_AUX")
		)
		(pad "2" smd rect
			(at 0.40005 0 270)
			(size 0.4572 0.508)
			(layers "F.Cu" "F.Mask" "F.Paste")
			(net "P3V3_AUX_USB_BUF")
		)
	)
	(footprint ""
		(layer "F.Cu")
		(at 54.080918 -402.371052 -90)
		(property "Reference" "C714"
			(at 0 0 270)
			(layer "F.SilkS")
			(hide yes)
			(effects
				(font
					(size 1.27 1.27)
				)
			)
		)
		(property "Value" ""
			(at 0 0 270)
			(layer "F.Fab")
			(effects
				(font
					(size 1.27 1.27)
				)
			)
		)
		(duplicate_pad_numbers_are_jumpers no)
		(fp_line
			(start -0.299974 0.150114)
			(end -0.299974 -0.150114)
			(stroke
				(width 0.1)
				(type default)
			)
			(layer "F.Fab")
		)
		(fp_line
			(start 0.299974 0.150114)
			(end -0.299974 0.150114)
			(stroke
				(width 0.1)
				(type default)
			)
			(layer "F.Fab")
		)
		(fp_line
			(start -0.299974 -0.150114)
			(end 0.299974 -0.150114)
			(stroke
				(width 0.1)
				(type default)
			)
			(layer "F.Fab")
		)
		(fp_line
			(start 0.299974 -0.150114)
			(end 0.299974 0.150114)
			(stroke
				(width 0.1)
				(type default)
			)
			(layer "F.Fab")
		)
		(pad "1" smd rect
			(at -0.2667 0 270)
			(size 0.3048 0.381)
			(layers "F.Cu" "F.Mask" "F.Paste")
			(net "P5E_CPU1_PE0_TX_C_DN<13>")
		)
		(pad "2" smd rect
			(at 0.2667 0 270)
			(size 0.3048 0.381)
			(layers "F.Cu" "F.Mask" "F.Paste")
			(net "P5E_CPU1_PE0_TX_DN<13>")
		)
	)
	(footprint ""
		(layer "F.Cu")
		(at 32.780478 -438.704228)
		(property "Reference" "R3522"
			(at 0 0 0)
			(layer "F.SilkS")
			(hide yes)
			(effects
				(font
					(size 1.27 1.27)
				)
			)
		)
		(property "Value" ""
			(at 0 0 0)
			(layer "F.Fab")
			(effects
				(font
					(size 1.27 1.27)
				)
			)
		)
		(duplicate_pad_numbers_are_jumpers no)
		(fp_line
			(start -0.7874 -0.4064)
			(end 0.7874 -0.4064)
			(stroke
				(width 0.1524)
				(type default)
			)
			(layer "F.SilkS")
		)
		(fp_line
			(start -0.7874 0.4064)
			(end -0.7874 -0.4064)
			(stroke
				(width 0.1524)
				(type default)
			)
			(layer "F.SilkS")
		)
		(fp_line
			(start 0.7874 -0.4064)
			(end 0.7874 0.4064)
			(stroke
				(width 0.1524)
				(type default)
			)
			(layer "F.SilkS")
		)
		(fp_line
			(start 0.7874 0.4064)
			(end -0.7874 0.4064)
			(stroke
				(width 0.1524)
				(type default)
			)
			(layer "F.SilkS")
		)
		(fp_line
			(start -0.67945 -0.305054)
			(end -0.12065 -0.305054)
			(stroke
				(width 0.1)
				(type default)
			)
			(layer "F.Fab")
		)
		(fp_line
			(start -0.67945 0.3048)
			(end -0.67945 -0.305054)
			(stroke
				(width 0.1)
				(type default)
			)
			(layer "F.Fab")
		)
		(fp_line
			(start -0.12065 -0.305054)
			(end -0.12065 -0.2794)
			(stroke
				(width 0.1)
				(type default)
			)
			(layer "F.Fab")
		)
		(fp_line
			(start -0.12065 -0.2794)
			(end 0.12065 -0.2794)
			(stroke
				(width 0.1)
				(type default)
			)
			(layer "F.Fab")
		)
		(fp_line
			(start -0.12065 0.2794)
			(end -0.12065 0.3048)
			(stroke
				(width 0.1)
				(type default)
			)
			(layer "F.Fab")
		)
		(fp_line
			(start -0.12065 0.3048)
			(end -0.67945 0.3048)
			(stroke
				(width 0.1)
				(type default)
			)
			(layer "F.Fab")
		)
		(fp_line
			(start 0.120396 0.2794)
			(end -0.12065 0.2794)
			(stroke
				(width 0.1)
				(type default)
			)
			(layer "F.Fab")
		)
		(fp_line
			(start 0.120396 0.3048)
			(end 0.120396 0.2794)
			(stroke
				(width 0.1)
				(type default)
			)
			(layer "F.Fab")
		)
		(fp_line
			(start 0.12065 -0.3048)
			(end 0.67945 -0.3048)
			(stroke
				(width 0.1)
				(type default)
			)
			(layer "F.Fab")
		)
		(fp_line
			(start 0.12065 -0.2794)
			(end 0.12065 -0.3048)
			(stroke
				(width 0.1)
				(type default)
			)
			(layer "F.Fab")
		)
		(fp_line
			(start 0.67945 -0.3048)
			(end 0.67945 0.3048)
			(stroke
				(width 0.1)
				(type default)
			)
			(layer "F.Fab")
		)
		(fp_line
			(start 0.67945 0.3048)
			(end 0.120396 0.3048)
			(stroke
				(width 0.1)
				(type default)
			)
			(layer "F.Fab")
		)
		(pad "1" smd circle
			(at -0.40005 0)
			(size 0 0)
			(layers "F.Cu" "F.Mask" "F.Paste")
			(net "P3V3_AUX")
		)
		(pad "2" smd circle
			(at 0.40005 0)
			(size 0 0)
			(layers "F.Cu" "F.Mask" "F.Paste")
			(net "SMB_2_BMC_GPU_BUF_R_SDA")
		)
	)
	(footprint ""
		(layer "F.Cu")
		(at 353.36988 -296.05478 180)
		(property "Reference" "C214"
			(at 0 0 180)
			(layer "F.SilkS")
			(hide yes)
			(effects
				(font
					(size 1.27 1.27)
				)
			)
		)
		(property "Value" ""
			(at 0 0 180)
			(layer "F.Fab")
			(effects
				(font
					(size 1.27 1.27)
				)
			)
		)
		(duplicate_pad_numbers_are_jumpers no)
		(fp_line
			(start 1.524 0.762)
			(end -1.524 0.762)
			(stroke
				(width 0.1524)
				(type default)
			)
			(layer "F.SilkS")
		)
		(fp_line
			(start 1.524 -0.762)
			(end 1.524 0.762)
			(stroke
				(width 0.1524)
				(type default)
			)
			(layer "F.SilkS")
		)
		(fp_line
			(start -1.524 0.762)
			(end -1.524 -0.762)
			(stroke
				(width 0.1524)
				(type default)
			)
			(layer "F.SilkS")
		)
		(fp_line
			(start -1.524 -0.762)
			(end 1.524 -0.762)
			(stroke
				(width 0.1524)
				(type default)
			)
			(layer "F.SilkS")
		)
		(fp_line
			(start 1.1049 0.724916)
			(end 1.1049 -0.724916)
			(stroke
				(width 0.1)
				(type default)
			)
			(layer "F.Fab")
		)
		(fp_line
			(start 1.1049 -0.724916)
			(end -1.1049 -0.724916)
			(stroke
				(width 0.1)
				(type default)
			)
			(layer "F.Fab")
		)
		(fp_line
			(start -1.1049 0.724916)
			(end 1.1049 0.724916)
			(stroke
				(width 0.1)
				(type default)
			)
			(layer "F.Fab")
		)
		(fp_line
			(start -1.1049 -0.724916)
			(end -1.1049 0.724916)
			(stroke
				(width 0.1)
				(type default)
			)
			(layer "F.Fab")
		)
		(pad "1" smd rect
			(at -0.889 0)
			(size 1.016 1.27)
			(layers "F.Cu" "F.Mask" "F.Paste")
			(net "PVCCIN_CPU0")
		)
		(pad "2" smd rect
			(at 0.889 0)
			(size 1.016 1.27)
			(layers "F.Cu" "F.Mask" "F.Paste")
			(net "GND")
		)
	)
	(footprint ""
		(layer "F.Cu")
		(at 423.8498 -16.088614 90)
		(property "Reference" "C863"
			(at 0 0 90)
			(layer "F.SilkS")
			(hide yes)
			(effects
				(font
					(size 1.27 1.27)
				)
			)
		)
		(property "Value" ""
			(at 0 0 90)
			(layer "F.Fab")
			(effects
				(font
					(size 1.27 1.27)
				)
			)
		)
		(duplicate_pad_numbers_are_jumpers no)
		(fp_line
			(start 0.299974 -0.150114)
			(end 0.299974 0.150114)
			(stroke
				(width 0.1)
				(type default)
			)
			(layer "F.Fab")
		)
		(fp_line
			(start -0.299974 -0.150114)
			(end 0.299974 -0.150114)
			(stroke
				(width 0.1)
				(type default)
			)
			(layer "F.Fab")
		)
		(fp_line
			(start 0.299974 0.150114)
			(end -0.299974 0.150114)
			(stroke
				(width 0.1)
				(type default)
			)
			(layer "F.Fab")
		)
		(fp_line
			(start -0.299974 0.150114)
			(end -0.299974 -0.150114)
			(stroke
				(width 0.1)
				(type default)
			)
			(layer "F.Fab")
		)
		(pad "1" smd rect
			(at -0.2667 0 90)
			(size 0.3048 0.381)
			(layers "F.Cu" "F.Mask" "F.Paste")
			(net "P5E_CPU0_PE1_TX_C_DP<3>")
		)
		(pad "2" smd rect
			(at 0.2667 0 90)
			(size 0.3048 0.381)
			(layers "F.Cu" "F.Mask" "F.Paste")
			(net "P5E_CPU0_PE1_TX_DP<3>")
		)
	)
	(footprint ""
		(layer "F.Cu")
		(at 56.349138 -360.92765)
		(property "Reference" "PC1677"
			(at 0 0 0)
			(layer "F.SilkS")
			(hide yes)
			(effects
				(font
					(size 1.27 1.27)
				)
			)
		)
		(property "Value" ""
			(at 0 0 0)
			(layer "F.Fab")
			(effects
				(font
					(size 1.27 1.27)
				)
			)
		)
		(duplicate_pad_numbers_are_jumpers no)
		(fp_line
			(start -1.524 -0.762)
			(end 1.524 -0.762)
			(stroke
				(width 0.1524)
				(type default)
			)
			(layer "F.SilkS")
		)
		(fp_line
			(start -1.524 0.762)
			(end -1.524 -0.762)
			(stroke
				(width 0.1524)
				(type default)
			)
			(layer "F.SilkS")
		)
		(fp_line
			(start 1.524 -0.762)
			(end 1.524 0.762)
			(stroke
				(width 0.1524)
				(type default)
			)
			(layer "F.SilkS")
		)
		(fp_line
			(start 1.524 0.762)
			(end -1.524 0.762)
			(stroke
				(width 0.1524)
				(type default)
			)
			(layer "F.SilkS")
		)
		(fp_line
			(start -1.1049 -0.724916)
			(end -1.1049 0.724916)
			(stroke
				(width 0.1)
				(type default)
			)
			(layer "F.Fab")
		)
		(fp_line
			(start -1.1049 0.724916)
			(end 1.1049 0.724916)
			(stroke
				(width 0.1)
				(type default)
			)
			(layer "F.Fab")
		)
		(fp_line
			(start 1.1049 -0.724916)
			(end -1.1049 -0.724916)
			(stroke
				(width 0.1)
				(type default)
			)
			(layer "F.Fab")
		)
		(fp_line
			(start 1.1049 0.724916)
			(end 1.1049 -0.724916)
			(stroke
				(width 0.1)
				(type default)
			)
			(layer "F.Fab")
		)
		(pad "1" smd rect
			(at -0.889 0 180)
			(size 1.016 1.27)
			(layers "F.Cu" "F.Mask" "F.Paste")
			(net "SW_P12V_PVCCFA_EHV_FIVRA_CPU1_L")
		)
		(pad "2" smd rect
			(at 0.889 0 180)
			(size 1.016 1.27)
			(layers "F.Cu" "F.Mask" "F.Paste")
			(net "GND")
		)
	)
	(footprint ""
		(layer "F.Cu")
		(at 46.582584 -112.619282 180)
		(property "Reference" "R1799"
			(at 0 0 180)
			(layer "F.SilkS")
			(hide yes)
			(effects
				(font
					(size 1.27 1.27)
				)
			)
		)
		(property "Value" ""
			(at 0 0 180)
			(layer "F.Fab")
			(effects
				(font
					(size 1.27 1.27)
				)
			)
		)
		(duplicate_pad_numbers_are_jumpers no)
		(fp_line
			(start 0.7874 0.4064)
			(end -0.7874 0.4064)
			(stroke
				(width 0.1524)
				(type default)
			)
			(layer "F.SilkS")
		)
		(fp_line
			(start 0.7874 -0.4064)
			(end 0.7874 0.4064)
			(stroke
				(width 0.1524)
				(type default)
			)
			(layer "F.SilkS")
		)
		(fp_line
			(start -0.7874 0.4064)
			(end -0.7874 -0.4064)
			(stroke
				(width 0.1524)
				(type default)
			)
			(layer "F.SilkS")
		)
		(fp_line
			(start -0.7874 -0.4064)
			(end 0.7874 -0.4064)
			(stroke
				(width 0.1524)
				(type default)
			)
			(layer "F.SilkS")
		)
		(fp_line
			(start 0.67945 0.3048)
			(end 0.120396 0.3048)
			(stroke
				(width 0.1)
				(type default)
			)
			(layer "F.Fab")
		)
		(fp_line
			(start 0.67945 -0.3048)
			(end 0.67945 0.3048)
			(stroke
				(width 0.1)
				(type default)
			)
			(layer "F.Fab")
		)
		(fp_line
			(start 0.12065 -0.2794)
			(end 0.12065 -0.3048)
			(stroke
				(width 0.1)
				(type default)
			)
			(layer "F.Fab")
		)
		(fp_line
			(start 0.12065 -0.3048)
			(end 0.67945 -0.3048)
			(stroke
				(width 0.1)
				(type default)
			)
			(layer "F.Fab")
		)
		(fp_line
			(start 0.120396 0.3048)
			(end 0.120396 0.2794)
			(stroke
				(width 0.1)
				(type default)
			)
			(layer "F.Fab")
		)
		(fp_line
			(start 0.120396 0.2794)
			(end -0.12065 0.2794)
			(stroke
				(width 0.1)
				(type default)
			)
			(layer "F.Fab")
		)
		(fp_line
			(start -0.12065 0.3048)
			(end -0.67945 0.3048)
			(stroke
				(width 0.1)
				(type default)
			)
			(layer "F.Fab")
		)
		(fp_line
			(start -0.12065 0.2794)
			(end -0.12065 0.3048)
			(stroke
				(width 0.1)
				(type default)
			)
			(layer "F.Fab")
		)
		(fp_line
			(start -0.12065 -0.2794)
			(end 0.12065 -0.2794)
			(stroke
				(width 0.1)
				(type default)
			)
			(layer "F.Fab")
		)
		(fp_line
			(start -0.12065 -0.305054)
			(end -0.12065 -0.2794)
			(stroke
				(width 0.1)
				(type default)
			)
			(layer "F.Fab")
		)
		(fp_line
			(start -0.67945 0.3048)
			(end -0.67945 -0.305054)
			(stroke
				(width 0.1)
				(type default)
			)
			(layer "F.Fab")
		)
		(fp_line
			(start -0.67945 -0.305054)
			(end -0.12065 -0.305054)
			(stroke
				(width 0.1)
				(type default)
			)
			(layer "F.Fab")
		)
		(pad "1" smd circle
			(at -0.40005 0 180)
			(size 0 0)
			(layers "F.Cu" "F.Mask" "F.Paste")
			(net "P12V_AUX")
		)
		(pad "2" smd circle
			(at 0.40005 0 180)
			(size 0 0)
			(layers "F.Cu" "F.Mask" "F.Paste")
			(net "P12V_AUX_ADC")
		)
	)
	(footprint ""
		(layer "F.Cu")
		(at 325.072248 -342.786208 -90)
		(property "Reference" "PC229_P0_7"
			(at 0 0 270)
			(layer "F.SilkS")
			(hide yes)
			(effects
				(font
					(size 1.27 1.27)
				)
			)
		)
		(property "Value" ""
			(at 0 0 270)
			(layer "F.Fab")
			(effects
				(font
					(size 1.27 1.27)
				)
			)
		)
		(duplicate_pad_numbers_are_jumpers no)
		(fp_line
			(start -0.7874 0.4064)
			(end -0.7874 -0.4064)
			(stroke
				(width 0.1524)
				(type default)
			)
			(layer "F.SilkS")
		)
		(fp_line
			(start 0.7874 0.4064)
			(end -0.7874 0.4064)
			(stroke
				(width 0.1524)
				(type default)
			)
			(layer "F.SilkS")
		)
		(fp_line
			(start -0.7874 -0.4064)
			(end 0.7874 -0.4064)
			(stroke
				(width 0.1524)
				(type default)
			)
			(layer "F.SilkS")
		)
		(fp_line
			(start 0.7874 -0.4064)
			(end 0.7874 0.4064)
			(stroke
				(width 0.1524)
				(type default)
			)
			(layer "F.SilkS")
		)
		(fp_line
			(start -0.67945 0.3048)
			(end -0.67945 -0.305054)
			(stroke
				(width 0.1)
				(type default)
			)
			(layer "F.Fab")
		)
		(fp_line
			(start -0.12065 0.3048)
			(end -0.67945 0.3048)
			(stroke
				(width 0.1)
				(type default)
			)
			(layer "F.Fab")
		)
		(fp_line
			(start 0.120396 0.3048)
			(end 0.120396 0.2794)
			(stroke
				(width 0.1)
				(type default)
			)
			(layer "F.Fab")
		)
		(fp_line
			(start 0.67945 0.3048)
			(end 0.120396 0.3048)
			(stroke
				(width 0.1)
				(type default)
			)
			(layer "F.Fab")
		)
		(fp_line
			(start -0.12065 0.2794)
			(end -0.12065 0.3048)
			(stroke
				(width 0.1)
				(type default)
			)
			(layer "F.Fab")
		)
		(fp_line
			(start 0.120396 0.2794)
			(end -0.12065 0.2794)
			(stroke
				(width 0.1)
				(type default)
			)
			(layer "F.Fab")
		)
		(fp_line
			(start -0.12065 -0.2794)
			(end 0.12065 -0.2794)
			(stroke
				(width 0.1)
				(type default)
			)
			(layer "F.Fab")
		)
		(fp_line
			(start 0.12065 -0.2794)
			(end 0.12065 -0.3048)
			(stroke
				(width 0.1)
				(type default)
			)
			(layer "F.Fab")
		)
		(fp_line
			(start 0.12065 -0.3048)
			(end 0.67945 -0.3048)
			(stroke
				(width 0.1)
				(type default)
			)
			(layer "F.Fab")
		)
		(fp_line
			(start 0.67945 -0.3048)
			(end 0.67945 0.3048)
			(stroke
				(width 0.1)
				(type default)
			)
			(layer "F.Fab")
		)
		(fp_line
			(start -0.67945 -0.305054)
			(end -0.12065 -0.305054)
			(stroke
				(width 0.1)
				(type default)
			)
			(layer "F.Fab")
		)
		(fp_line
			(start -0.12065 -0.305054)
			(end -0.12065 -0.2794)
			(stroke
				(width 0.1)
				(type default)
			)
			(layer "F.Fab")
		)
		(pad "1" smd circle
			(at -0.40005 0 270)
			(size 0 0)
			(layers "F.Cu" "F.Mask" "F.Paste")
			(net "PVCCIN_CPU0_PVCC")
		)
		(pad "2" smd circle
			(at 0.40005 0 270)
			(size 0 0)
			(layers "F.Cu" "F.Mask" "F.Paste")
			(net "GND")
		)
	)
	(footprint ""
		(layer "F.Cu")
		(at 414.28289 -402.371052 -90)
		(property "Reference" "C963"
			(at 0 0 270)
			(layer "F.SilkS")
			(hide yes)
			(effects
				(font
					(size 1.27 1.27)
				)
			)
		)
		(property "Value" ""
			(at 0 0 270)
			(layer "F.Fab")
			(effects
				(font
					(size 1.27 1.27)
				)
			)
		)
		(duplicate_pad_numbers_are_jumpers no)
		(fp_line
			(start -0.299974 0.150114)
			(end -0.299974 -0.150114)
			(stroke
				(width 0.1)
				(type default)
			)
			(layer "F.Fab")
		)
		(fp_line
			(start 0.299974 0.150114)
			(end -0.299974 0.150114)
			(stroke
				(width 0.1)
				(type default)
			)
			(layer "F.Fab")
		)
		(fp_line
			(start -0.299974 -0.150114)
			(end 0.299974 -0.150114)
			(stroke
				(width 0.1)
				(type default)
			)
			(layer "F.Fab")
		)
		(fp_line
			(start 0.299974 -0.150114)
			(end 0.299974 0.150114)
			(stroke
				(width 0.1)
				(type default)
			)
			(layer "F.Fab")
		)
		(pad "1" smd rect
			(at -0.2667 0 270)
			(size 0.3048 0.381)
			(layers "F.Cu" "F.Mask" "F.Paste")
			(net "P5E_CPU0_PE2_TX_C_DP<1>")
		)
		(pad "2" smd rect
			(at 0.2667 0 270)
			(size 0.3048 0.381)
			(layers "F.Cu" "F.Mask" "F.Paste")
			(net "P5E_CPU0_PE2_TX_DP<1>")
		)
	)
	(footprint ""
		(layer "F.Cu")
		(at 196.729604 -77.06614 180)
		(property "Reference" "R1351"
			(at 0 0 180)
			(layer "F.SilkS")
			(hide yes)
			(effects
				(font
					(size 1.27 1.27)
				)
			)
		)
		(property "Value" ""
			(at 0 0 180)
			(layer "F.Fab")
			(effects
				(font
					(size 1.27 1.27)
				)
			)
		)
		(duplicate_pad_numbers_are_jumpers no)
		(fp_line
			(start 0.7874 0.4064)
			(end -0.7874 0.4064)
			(stroke
				(width 0.1524)
				(type default)
			)
			(layer "F.SilkS")
		)
		(fp_line
			(start 0.7874 -0.4064)
			(end 0.7874 0.4064)
			(stroke
				(width 0.1524)
				(type default)
			)
			(layer "F.SilkS")
		)
		(fp_line
			(start -0.7874 0.4064)
			(end -0.7874 -0.4064)
			(stroke
				(width 0.1524)
				(type default)
			)
			(layer "F.SilkS")
		)
		(fp_line
			(start -0.7874 -0.4064)
			(end 0.7874 -0.4064)
			(stroke
				(width 0.1524)
				(type default)
			)
			(layer "F.SilkS")
		)
		(fp_line
			(start 0.67945 0.3048)
			(end 0.120396 0.3048)
			(stroke
				(width 0.1)
				(type default)
			)
			(layer "F.Fab")
		)
		(fp_line
			(start 0.67945 -0.3048)
			(end 0.67945 0.3048)
			(stroke
				(width 0.1)
				(type default)
			)
			(layer "F.Fab")
		)
		(fp_line
			(start 0.12065 -0.2794)
			(end 0.12065 -0.3048)
			(stroke
				(width 0.1)
				(type default)
			)
			(layer "F.Fab")
		)
		(fp_line
			(start 0.12065 -0.3048)
			(end 0.67945 -0.3048)
			(stroke
				(width 0.1)
				(type default)
			)
			(layer "F.Fab")
		)
		(fp_line
			(start 0.120396 0.3048)
			(end 0.120396 0.2794)
			(stroke
				(width 0.1)
				(type default)
			)
			(layer "F.Fab")
		)
		(fp_line
			(start 0.120396 0.2794)
			(end -0.12065 0.2794)
			(stroke
				(width 0.1)
				(type default)
			)
			(layer "F.Fab")
		)
		(fp_line
			(start -0.12065 0.3048)
			(end -0.67945 0.3048)
			(stroke
				(width 0.1)
				(type default)
			)
			(layer "F.Fab")
		)
		(fp_line
			(start -0.12065 0.2794)
			(end -0.12065 0.3048)
			(stroke
				(width 0.1)
				(type default)
			)
			(layer "F.Fab")
		)
		(fp_line
			(start -0.12065 -0.2794)
			(end 0.12065 -0.2794)
			(stroke
				(width 0.1)
				(type default)
			)
			(layer "F.Fab")
		)
		(fp_line
			(start -0.12065 -0.305054)
			(end -0.12065 -0.2794)
			(stroke
				(width 0.1)
				(type default)
			)
			(layer "F.Fab")
		)
		(fp_line
			(start -0.67945 0.3048)
			(end -0.67945 -0.305054)
			(stroke
				(width 0.1)
				(type default)
			)
			(layer "F.Fab")
		)
		(fp_line
			(start -0.67945 -0.305054)
			(end -0.12065 -0.305054)
			(stroke
				(width 0.1)
				(type default)
			)
			(layer "F.Fab")
		)
		(pad "1" smd circle
			(at -0.40005 0 180)
			(size 0 0)
			(layers "F.Cu" "F.Mask" "F.Paste")
			(net "RMII_OCP_BMC_RXD_0")
		)
		(pad "2" smd circle
			(at 0.40005 0 180)
			(size 0 0)
			(layers "F.Cu" "F.Mask" "F.Paste")
			(net "GND")
		)
	)
	(footprint ""
		(layer "F.Cu")
		(at 384.652012 -347.959426)
		(property "Reference" "PR132"
			(at 0 0 0)
			(layer "F.SilkS")
			(hide yes)
			(effects
				(font
					(size 1.27 1.27)
				)
			)
		)
		(property "Value" ""
			(at 0 0 0)
			(layer "F.Fab")
			(effects
				(font
					(size 1.27 1.27)
				)
			)
		)
		(duplicate_pad_numbers_are_jumpers no)
		(fp_line
			(start -0.7874 -0.4064)
			(end 0.7874 -0.4064)
			(stroke
				(width 0.1524)
				(type default)
			)
			(layer "F.SilkS")
		)
		(fp_line
			(start -0.7874 0.4064)
			(end -0.7874 -0.4064)
			(stroke
				(width 0.1524)
				(type default)
			)
			(layer "F.SilkS")
		)
		(fp_line
			(start 0.7874 -0.4064)
			(end 0.7874 0.4064)
			(stroke
				(width 0.1524)
				(type default)
			)
			(layer "F.SilkS")
		)
		(fp_line
			(start 0.7874 0.4064)
			(end -0.7874 0.4064)
			(stroke
				(width 0.1524)
				(type default)
			)
			(layer "F.SilkS")
		)
		(fp_line
			(start -0.67945 -0.305054)
			(end -0.12065 -0.305054)
			(stroke
				(width 0.1)
				(type default)
			)
			(layer "F.Fab")
		)
		(fp_line
			(start -0.67945 0.3048)
			(end -0.67945 -0.305054)
			(stroke
				(width 0.1)
				(type default)
			)
			(layer "F.Fab")
		)
		(fp_line
			(start -0.12065 -0.305054)
			(end -0.12065 -0.2794)
			(stroke
				(width 0.1)
				(type default)
			)
			(layer "F.Fab")
		)
		(fp_line
			(start -0.12065 -0.2794)
			(end 0.12065 -0.2794)
			(stroke
				(width 0.1)
				(type default)
			)
			(layer "F.Fab")
		)
		(fp_line
			(start -0.12065 0.2794)
			(end -0.12065 0.3048)
			(stroke
				(width 0.1)
				(type default)
			)
			(layer "F.Fab")
		)
		(fp_line
			(start -0.12065 0.3048)
			(end -0.67945 0.3048)
			(stroke
				(width 0.1)
				(type default)
			)
			(layer "F.Fab")
		)
		(fp_line
			(start 0.120396 0.2794)
			(end -0.12065 0.2794)
			(stroke
				(width 0.1)
				(type default)
			)
			(layer "F.Fab")
		)
		(fp_line
			(start 0.120396 0.3048)
			(end 0.120396 0.2794)
			(stroke
				(width 0.1)
				(type default)
			)
			(layer "F.Fab")
		)
		(fp_line
			(start 0.12065 -0.3048)
			(end 0.67945 -0.3048)
			(stroke
				(width 0.1)
				(type default)
			)
			(layer "F.Fab")
		)
		(fp_line
			(start 0.12065 -0.2794)
			(end 0.12065 -0.3048)
			(stroke
				(width 0.1)
				(type default)
			)
			(layer "F.Fab")
		)
		(fp_line
			(start 0.67945 -0.3048)
			(end 0.67945 0.3048)
			(stroke
				(width 0.1)
				(type default)
			)
			(layer "F.Fab")
		)
		(fp_line
			(start 0.67945 0.3048)
			(end 0.120396 0.3048)
			(stroke
				(width 0.1)
				(type default)
			)
			(layer "F.Fab")
		)
		(pad "1" smd circle
			(at -0.40005 0)
			(size 0 0)
			(layers "F.Cu" "F.Mask" "F.Paste")
			(net "PVCCIN_CPU0_LSET8")
		)
		(pad "2" smd circle
			(at 0.40005 0)
			(size 0 0)
			(layers "F.Cu" "F.Mask" "F.Paste")
			(net "GND")
		)
	)
	(footprint ""
		(layer "F.Cu")
		(at 155.136088 -76.244958 180)
		(property "Reference" "U143"
			(at -2.853944 -4.426712 0)
			(unlocked yes)
			(layer "F.SilkS")
			(effects
				(font
					(size 0.7874 0.5842)
					(thickness 0.1524)
				)
				(justify left)
			)
		)
		(property "Value" ""
			(at 0 0 180)
			(layer "F.Fab")
			(effects
				(font
					(size 1.27 1.27)
				)
			)
		)
		(duplicate_pad_numbers_are_jumpers no)
		(fp_line
			(start 2.161032 3.299968)
			(end -2.161032 3.299968)
			(stroke
				(width 0.1524)
				(type default)
			)
			(layer "F.SilkS")
		)
		(fp_line
			(start 2.161032 -3.299968)
			(end 2.161032 3.299968)
			(stroke
				(width 0.1524)
				(type default)
			)
			(layer "F.SilkS")
		)
		(fp_line
			(start 1.013968 -3.299968)
			(end 2.161032 -3.299968)
			(stroke
				(width 0.1524)
				(type default)
			)
			(layer "F.SilkS")
		)
		(fp_line
			(start 0 -2.54)
			(end 1.013968 -3.299968)
			(stroke
				(width 0.1524)
				(type default)
			)
			(layer "F.SilkS")
		)
		(fp_line
			(start -1.013968 -3.299968)
			(end 0 -2.54)
			(stroke
				(width 0.1524)
				(type default)
			)
			(layer "F.SilkS")
		)
		(fp_line
			(start -2.161032 3.299968)
			(end -2.161032 -3.299968)
			(stroke
				(width 0.1524)
				(type default)
			)
			(layer "F.SilkS")
		)
		(fp_line
			(start -2.161032 -3.299968)
			(end -1.013968 -3.299968)
			(stroke
				(width 0.1524)
				(type default)
			)
			(layer "F.SilkS")
		)
		(fp_poly
			(pts
				(xy -3.556 -2.925064) (xy -4.572 -2.417064) (xy -4.572 -3.433064)
			)
			(stroke
				(width 0)
				(type default)
			)
			(fill yes)
			(layer "F.SilkS")
		)
		(fp_line
			(start 2.249932 3.299968)
			(end 2.249932 -3.299968)
			(stroke
				(width 0.1)
				(type default)
			)
			(layer "F.Fab")
		)
		(fp_line
			(start 2.249932 -3.299968)
			(end -2.249932 -3.299968)
			(stroke
				(width 0.1)
				(type default)
			)
			(layer "F.Fab")
		)
		(fp_line
			(start -2.249932 3.299968)
			(end 2.249932 3.299968)
			(stroke
				(width 0.1)
				(type default)
			)
			(layer "F.Fab")
		)
		(fp_line
			(start -2.249932 -3.299968)
			(end -2.249932 3.299968)
			(stroke
				(width 0.1)
				(type default)
			)
			(layer "F.Fab")
		)
		(fp_poly
			(pts
				(xy -4.572 -3.433064) (xy -4.572 -2.417064) (xy -3.556 -2.925064)
			)
			(stroke
				(width 0)
				(type default)
			)
			(fill yes)
			(layer "F.Fab")
		)
		(pad "1" smd rect
			(at -2.84988 -2.925064 90)
			(size 0.4064 1.1176)
			(layers "F.Cu" "F.Mask" "F.Paste")
			(net "PCA9543_S3M_ADDR0")
		)
		(pad "2" smd rect
			(at -2.84988 -2.275078 90)
			(size 0.4064 1.1176)
			(layers "F.Cu" "F.Mask" "F.Paste")
			(net "PCA9543_S3M_ADDR1")
		)
		(pad "3" smd rect
			(at -2.84988 -1.625092 90)
			(size 0.4064 1.1176)
			(layers "F.Cu" "F.Mask" "F.Paste")
			(net "RST_SMB_S3M_N")
		)
		(pad "4" smd rect
			(at -2.84988 -0.975106 90)
			(size 0.4064 1.1176)
			(layers "F.Cu" "F.Mask" "F.Paste")
			(net "PCA9543_S3M_INT0_N")
		)
		(pad "5" smd rect
			(at -2.84988 -0.32512 90)
			(size 0.4064 1.1176)
			(layers "F.Cu" "F.Mask" "F.Paste")
			(net "SMB_S3M_CPU0_3V3AUX_SDA_R")
		)
		(pad "6" smd rect
			(at -2.84988 0.32512 90)
			(size 0.4064 1.1176)
			(layers "F.Cu" "F.Mask" "F.Paste")
			(net "SMB_S3M_CPU0_3V3AUX_SCL_R")
		)
		(pad "7" smd rect
			(at -2.84988 0.975106 90)
			(size 0.4064 1.1176)
			(layers "F.Cu" "F.Mask" "F.Paste")
			(net "PCA9543_S3M_INT1_N")
		)
		(pad "8" smd rect
			(at -2.84988 1.625092 90)
			(size 0.4064 1.1176)
			(layers "F.Cu" "F.Mask" "F.Paste")
			(net "SMB_S3M_CPU1_3V3AUX_SDA_R")
		)
		(pad "9" smd rect
			(at -2.84988 2.275078 90)
			(size 0.4064 1.1176)
			(layers "F.Cu" "F.Mask" "F.Paste")
			(net "SMB_S3M_CPU1_3V3AUX_SCL_R")
		)
		(pad "10" smd rect
			(at -2.84988 2.925064 90)
			(size 0.4064 1.1176)
			(layers "F.Cu" "F.Mask" "F.Paste")
			(net "GND")
		)
		(pad "11" smd rect
			(at 2.84988 2.925064 90)
			(size 0.4064 1.1176)
			(layers "F.Cu" "F.Mask" "F.Paste")
			(net "PCA9543_S3M_INT2_N")
		)
		(pad "12" smd rect
			(at 2.84988 2.275078 90)
			(size 0.4064 1.1176)
			(layers "F.Cu" "F.Mask" "F.Paste")
			(net "SMB_S3M_CPU0_PIROM_3V3AUX_SDA_R")
		)
		(pad "13" smd rect
			(at 2.84988 1.625092 90)
			(size 0.4064 1.1176)
			(layers "F.Cu" "F.Mask" "F.Paste")
			(net "SMB_S3M_CPU0_PIROM_3V3AUX_SCL_R")
		)
		(pad "14" smd rect
			(at 2.84988 0.975106 90)
			(size 0.4064 1.1176)
			(layers "F.Cu" "F.Mask" "F.Paste")
			(net "PCA9543_S3M_INT3_N")
		)
		(pad "15" smd rect
			(at 2.84988 0.32512 90)
			(size 0.4064 1.1176)
			(layers "F.Cu" "F.Mask" "F.Paste")
			(net "SMB_S3M_CPU1_PIROM_3V3AUX_SDA_R")
		)
		(pad "16" smd rect
			(at 2.84988 -0.32512 90)
			(size 0.4064 1.1176)
			(layers "F.Cu" "F.Mask" "F.Paste")
			(net "SMB_S3M_CPU1_PIROM_3V3AUX_SCL_R")
		)
		(pad "17" smd rect
			(at 2.84988 -0.975106 90)
			(size 0.4064 1.1176)
			(layers "F.Cu" "F.Mask" "F.Paste")
			(net "PCA9545_S3M_INT_N")
		)
		(pad "18" smd rect
			(at 2.84988 -1.625092 90)
			(size 0.4064 1.1176)
			(layers "F.Cu" "F.Mask" "F.Paste")
			(net "SMB_S3M_CPU_3V3AUX_SCL")
		)
		(pad "19" smd rect
			(at 2.84988 -2.275078 90)
			(size 0.4064 1.1176)
			(layers "F.Cu" "F.Mask" "F.Paste")
			(net "SMB_S3M_CPU_3V3AUX_SDA")
		)
		(pad "20" smd rect
			(at 2.84988 -2.925064 90)
			(size 0.4064 1.1176)
			(layers "F.Cu" "F.Mask" "F.Paste")
			(net "P3V3_AUX")
		)
	)
	(footprint ""
		(layer "F.Cu")
		(at 193.95948 -349.367348 180)
		(property "Reference" "R1229"
			(at 0 0 180)
			(layer "F.SilkS")
			(hide yes)
			(effects
				(font
					(size 1.27 1.27)
				)
			)
		)
		(property "Value" ""
			(at 0 0 180)
			(layer "F.Fab")
			(effects
				(font
					(size 1.27 1.27)
				)
			)
		)
		(duplicate_pad_numbers_are_jumpers no)
		(fp_line
			(start 0.7874 0.4064)
			(end -0.7874 0.4064)
			(stroke
				(width 0.1524)
				(type default)
			)
			(layer "F.SilkS")
		)
		(fp_line
			(start 0.7874 -0.4064)
			(end 0.7874 0.4064)
			(stroke
				(width 0.1524)
				(type default)
			)
			(layer "F.SilkS")
		)
		(fp_line
			(start -0.7874 0.4064)
			(end -0.7874 -0.4064)
			(stroke
				(width 0.1524)
				(type default)
			)
			(layer "F.SilkS")
		)
		(fp_line
			(start -0.7874 -0.4064)
			(end 0.7874 -0.4064)
			(stroke
				(width 0.1524)
				(type default)
			)
			(layer "F.SilkS")
		)
		(fp_line
			(start 0.67945 0.3048)
			(end 0.120396 0.3048)
			(stroke
				(width 0.1)
				(type default)
			)
			(layer "F.Fab")
		)
		(fp_line
			(start 0.67945 -0.3048)
			(end 0.67945 0.3048)
			(stroke
				(width 0.1)
				(type default)
			)
			(layer "F.Fab")
		)
		(fp_line
			(start 0.12065 -0.2794)
			(end 0.12065 -0.3048)
			(stroke
				(width 0.1)
				(type default)
			)
			(layer "F.Fab")
		)
		(fp_line
			(start 0.12065 -0.3048)
			(end 0.67945 -0.3048)
			(stroke
				(width 0.1)
				(type default)
			)
			(layer "F.Fab")
		)
		(fp_line
			(start 0.120396 0.3048)
			(end 0.120396 0.2794)
			(stroke
				(width 0.1)
				(type default)
			)
			(layer "F.Fab")
		)
		(fp_line
			(start 0.120396 0.2794)
			(end -0.12065 0.2794)
			(stroke
				(width 0.1)
				(type default)
			)
			(layer "F.Fab")
		)
		(fp_line
			(start -0.12065 0.3048)
			(end -0.67945 0.3048)
			(stroke
				(width 0.1)
				(type default)
			)
			(layer "F.Fab")
		)
		(fp_line
			(start -0.12065 0.2794)
			(end -0.12065 0.3048)
			(stroke
				(width 0.1)
				(type default)
			)
			(layer "F.Fab")
		)
		(fp_line
			(start -0.12065 -0.2794)
			(end 0.12065 -0.2794)
			(stroke
				(width 0.1)
				(type default)
			)
			(layer "F.Fab")
		)
		(fp_line
			(start -0.12065 -0.305054)
			(end -0.12065 -0.2794)
			(stroke
				(width 0.1)
				(type default)
			)
			(layer "F.Fab")
		)
		(fp_line
			(start -0.67945 0.3048)
			(end -0.67945 -0.305054)
			(stroke
				(width 0.1)
				(type default)
			)
			(layer "F.Fab")
		)
		(fp_line
			(start -0.67945 -0.305054)
			(end -0.12065 -0.305054)
			(stroke
				(width 0.1)
				(type default)
			)
			(layer "F.Fab")
		)
		(pad "1" smd circle
			(at -0.40005 0 180)
			(size 0 0)
			(layers "F.Cu" "F.Mask" "F.Paste")
			(net "PVNN_TERM_CPU1")
		)
		(pad "2" smd circle
			(at 0.40005 0 180)
			(size 0 0)
			(layers "F.Cu" "F.Mask" "F.Paste")
			(net "PUD_XTAL_CPU1_MODE0")
		)
	)
	(footprint ""
		(layer "F.Cu")
		(at 385.716272 -60.735464 180)
		(property "Reference" "R771"
			(at 0 0 180)
			(layer "F.SilkS")
			(hide yes)
			(effects
				(font
					(size 1.27 1.27)
				)
			)
		)
		(property "Value" ""
			(at 0 0 180)
			(layer "F.Fab")
			(effects
				(font
					(size 1.27 1.27)
				)
			)
		)
		(duplicate_pad_numbers_are_jumpers no)
		(fp_line
			(start 0.7874 0.4064)
			(end -0.7874 0.4064)
			(stroke
				(width 0.1524)
				(type default)
			)
			(layer "F.SilkS")
		)
		(fp_line
			(start 0.7874 -0.4064)
			(end 0.7874 0.4064)
			(stroke
				(width 0.1524)
				(type default)
			)
			(layer "F.SilkS")
		)
		(fp_line
			(start -0.7874 0.4064)
			(end -0.7874 -0.4064)
			(stroke
				(width 0.1524)
				(type default)
			)
			(layer "F.SilkS")
		)
		(fp_line
			(start -0.7874 -0.4064)
			(end 0.7874 -0.4064)
			(stroke
				(width 0.1524)
				(type default)
			)
			(layer "F.SilkS")
		)
		(fp_line
			(start 0.67945 0.3048)
			(end 0.120396 0.3048)
			(stroke
				(width 0.1)
				(type default)
			)
			(layer "F.Fab")
		)
		(fp_line
			(start 0.67945 -0.3048)
			(end 0.67945 0.3048)
			(stroke
				(width 0.1)
				(type default)
			)
			(layer "F.Fab")
		)
		(fp_line
			(start 0.12065 -0.2794)
			(end 0.12065 -0.3048)
			(stroke
				(width 0.1)
				(type default)
			)
			(layer "F.Fab")
		)
		(fp_line
			(start 0.12065 -0.3048)
			(end 0.67945 -0.3048)
			(stroke
				(width 0.1)
				(type default)
			)
			(layer "F.Fab")
		)
		(fp_line
			(start 0.120396 0.3048)
			(end 0.120396 0.2794)
			(stroke
				(width 0.1)
				(type default)
			)
			(layer "F.Fab")
		)
		(fp_line
			(start 0.120396 0.2794)
			(end -0.12065 0.2794)
			(stroke
				(width 0.1)
				(type default)
			)
			(layer "F.Fab")
		)
		(fp_line
			(start -0.12065 0.3048)
			(end -0.67945 0.3048)
			(stroke
				(width 0.1)
				(type default)
			)
			(layer "F.Fab")
		)
		(fp_line
			(start -0.12065 0.2794)
			(end -0.12065 0.3048)
			(stroke
				(width 0.1)
				(type default)
			)
			(layer "F.Fab")
		)
		(fp_line
			(start -0.12065 -0.2794)
			(end 0.12065 -0.2794)
			(stroke
				(width 0.1)
				(type default)
			)
			(layer "F.Fab")
		)
		(fp_line
			(start -0.12065 -0.305054)
			(end -0.12065 -0.2794)
			(stroke
				(width 0.1)
				(type default)
			)
			(layer "F.Fab")
		)
		(fp_line
			(start -0.67945 0.3048)
			(end -0.67945 -0.305054)
			(stroke
				(width 0.1)
				(type default)
			)
			(layer "F.Fab")
		)
		(fp_line
			(start -0.67945 -0.305054)
			(end -0.12065 -0.305054)
			(stroke
				(width 0.1)
				(type default)
			)
			(layer "F.Fab")
		)
		(pad "1" smd circle
			(at -0.40005 0 180)
			(size 0 0)
			(layers "F.Cu" "F.Mask" "F.Paste")
			(net "JTAG_DBP_PCH_DEBUG_CONSENT_N")
		)
		(pad "2" smd circle
			(at 0.40005 0 180)
			(size 0 0)
			(layers "F.Cu" "F.Mask" "F.Paste")
			(net "FM_PCH_CONSENT_STRAP_N")
		)
	)
	(footprint ""
		(layer "F.Cu")
		(at 210.560158 -103.95204 180)
		(property "Reference" "C1562"
			(at 0 0 180)
			(layer "F.SilkS")
			(hide yes)
			(effects
				(font
					(size 1.27 1.27)
				)
			)
		)
		(property "Value" ""
			(at 0 0 180)
			(layer "F.Fab")
			(effects
				(font
					(size 1.27 1.27)
				)
			)
		)
		(duplicate_pad_numbers_are_jumpers no)
		(fp_line
			(start 0.7874 0.4064)
			(end -0.7874 0.4064)
			(stroke
				(width 0.1524)
				(type default)
			)
			(layer "F.SilkS")
		)
		(fp_line
			(start 0.7874 -0.4064)
			(end 0.7874 0.4064)
			(stroke
				(width 0.1524)
				(type default)
			)
			(layer "F.SilkS")
		)
		(fp_line
			(start -0.7874 0.4064)
			(end -0.7874 -0.4064)
			(stroke
				(width 0.1524)
				(type default)
			)
			(layer "F.SilkS")
		)
		(fp_line
			(start -0.7874 -0.4064)
			(end 0.7874 -0.4064)
			(stroke
				(width 0.1524)
				(type default)
			)
			(layer "F.SilkS")
		)
		(fp_line
			(start 0.67945 0.3048)
			(end 0.120396 0.3048)
			(stroke
				(width 0.1)
				(type default)
			)
			(layer "F.Fab")
		)
		(fp_line
			(start 0.67945 -0.3048)
			(end 0.67945 0.3048)
			(stroke
				(width 0.1)
				(type default)
			)
			(layer "F.Fab")
		)
		(fp_line
			(start 0.12065 -0.2794)
			(end 0.12065 -0.3048)
			(stroke
				(width 0.1)
				(type default)
			)
			(layer "F.Fab")
		)
		(fp_line
			(start 0.12065 -0.3048)
			(end 0.67945 -0.3048)
			(stroke
				(width 0.1)
				(type default)
			)
			(layer "F.Fab")
		)
		(fp_line
			(start 0.120396 0.3048)
			(end 0.120396 0.2794)
			(stroke
				(width 0.1)
				(type default)
			)
			(layer "F.Fab")
		)
		(fp_line
			(start 0.120396 0.2794)
			(end -0.12065 0.2794)
			(stroke
				(width 0.1)
				(type default)
			)
			(layer "F.Fab")
		)
		(fp_line
			(start -0.12065 0.3048)
			(end -0.67945 0.3048)
			(stroke
				(width 0.1)
				(type default)
			)
			(layer "F.Fab")
		)
		(fp_line
			(start -0.12065 0.2794)
			(end -0.12065 0.3048)
			(stroke
				(width 0.1)
				(type default)
			)
			(layer "F.Fab")
		)
		(fp_line
			(start -0.12065 -0.2794)
			(end 0.12065 -0.2794)
			(stroke
				(width 0.1)
				(type default)
			)
			(layer "F.Fab")
		)
		(fp_line
			(start -0.12065 -0.305054)
			(end -0.12065 -0.2794)
			(stroke
				(width 0.1)
				(type default)
			)
			(layer "F.Fab")
		)
		(fp_line
			(start -0.67945 0.3048)
			(end -0.67945 -0.305054)
			(stroke
				(width 0.1)
				(type default)
			)
			(layer "F.Fab")
		)
		(fp_line
			(start -0.67945 -0.305054)
			(end -0.12065 -0.305054)
			(stroke
				(width 0.1)
				(type default)
			)
			(layer "F.Fab")
		)
		(pad "1" smd circle
			(at -0.40005 0 180)
			(size 0 0)
			(layers "F.Cu" "F.Mask" "F.Paste")
			(net "U205_VDD")
		)
		(pad "2" smd circle
			(at 0.40005 0 180)
			(size 0 0)
			(layers "F.Cu" "F.Mask" "F.Paste")
			(net "GND")
		)
	)
	(footprint ""
		(layer "F.Cu")
		(at 191.284606 -126.968758 -90)
		(property "Reference" "R4599"
			(at 0 0 270)
			(layer "F.SilkS")
			(hide yes)
			(effects
				(font
					(size 1.27 1.27)
				)
			)
		)
		(property "Value" ""
			(at 0 0 270)
			(layer "F.Fab")
			(effects
				(font
					(size 1.27 1.27)
				)
			)
		)
		(duplicate_pad_numbers_are_jumpers no)
		(fp_line
			(start -0.7874 0.4064)
			(end -0.7874 -0.4064)
			(stroke
				(width 0.1524)
				(type default)
			)
			(layer "F.SilkS")
		)
		(fp_line
			(start 0.7874 0.4064)
			(end -0.7874 0.4064)
			(stroke
				(width 0.1524)
				(type default)
			)
			(layer "F.SilkS")
		)
		(fp_line
			(start -0.7874 -0.4064)
			(end 0.7874 -0.4064)
			(stroke
				(width 0.1524)
				(type default)
			)
			(layer "F.SilkS")
		)
		(fp_line
			(start 0.7874 -0.4064)
			(end 0.7874 0.4064)
			(stroke
				(width 0.1524)
				(type default)
			)
			(layer "F.SilkS")
		)
		(fp_line
			(start -0.67945 0.3048)
			(end -0.67945 -0.305054)
			(stroke
				(width 0.1)
				(type default)
			)
			(layer "F.Fab")
		)
		(fp_line
			(start -0.12065 0.3048)
			(end -0.67945 0.3048)
			(stroke
				(width 0.1)
				(type default)
			)
			(layer "F.Fab")
		)
		(fp_line
			(start 0.120396 0.3048)
			(end 0.120396 0.2794)
			(stroke
				(width 0.1)
				(type default)
			)
			(layer "F.Fab")
		)
		(fp_line
			(start 0.67945 0.3048)
			(end 0.120396 0.3048)
			(stroke
				(width 0.1)
				(type default)
			)
			(layer "F.Fab")
		)
		(fp_line
			(start -0.12065 0.2794)
			(end -0.12065 0.3048)
			(stroke
				(width 0.1)
				(type default)
			)
			(layer "F.Fab")
		)
		(fp_line
			(start 0.120396 0.2794)
			(end -0.12065 0.2794)
			(stroke
				(width 0.1)
				(type default)
			)
			(layer "F.Fab")
		)
		(fp_line
			(start -0.12065 -0.2794)
			(end 0.12065 -0.2794)
			(stroke
				(width 0.1)
				(type default)
			)
			(layer "F.Fab")
		)
		(fp_line
			(start 0.12065 -0.2794)
			(end 0.12065 -0.3048)
			(stroke
				(width 0.1)
				(type default)
			)
			(layer "F.Fab")
		)
		(fp_line
			(start 0.12065 -0.3048)
			(end 0.67945 -0.3048)
			(stroke
				(width 0.1)
				(type default)
			)
			(layer "F.Fab")
		)
		(fp_line
			(start 0.67945 -0.3048)
			(end 0.67945 0.3048)
			(stroke
				(width 0.1)
				(type default)
			)
			(layer "F.Fab")
		)
		(fp_line
			(start -0.67945 -0.305054)
			(end -0.12065 -0.305054)
			(stroke
				(width 0.1)
				(type default)
			)
			(layer "F.Fab")
		)
		(fp_line
			(start -0.12065 -0.305054)
			(end -0.12065 -0.2794)
			(stroke
				(width 0.1)
				(type default)
			)
			(layer "F.Fab")
		)
		(pad "1" smd circle
			(at -0.40005 0 270)
			(size 0 0)
			(layers "F.Cu" "F.Mask" "F.Paste")
			(net "HP_LVC3_OCP_V3_2_P12V_PWRGD")
		)
		(pad "2" smd circle
			(at 0.40005 0 270)
			(size 0 0)
			(layers "F.Cu" "F.Mask" "F.Paste")
			(net "HP_LVC3_OCP_V3_2_HSC_PWRGD_PLD_")
		)
	)
	(footprint ""
		(layer "F.Cu")
		(at 67.11188 -54.361588)
		(property "Reference" "PR3856"
			(at 0 0 0)
			(layer "F.SilkS")
			(hide yes)
			(effects
				(font
					(size 1.27 1.27)
				)
			)
		)
		(property "Value" ""
			(at 0 0 0)
			(layer "F.Fab")
			(effects
				(font
					(size 1.27 1.27)
				)
			)
		)
		(duplicate_pad_numbers_are_jumpers no)
		(fp_line
			(start -0.7874 -0.4064)
			(end 0.7874 -0.4064)
			(stroke
				(width 0.1524)
				(type default)
			)
			(layer "F.SilkS")
		)
		(fp_line
			(start -0.7874 0.4064)
			(end -0.7874 -0.4064)
			(stroke
				(width 0.1524)
				(type default)
			)
			(layer "F.SilkS")
		)
		(fp_line
			(start 0.7874 -0.4064)
			(end 0.7874 0.4064)
			(stroke
				(width 0.1524)
				(type default)
			)
			(layer "F.SilkS")
		)
		(fp_line
			(start 0.7874 0.4064)
			(end -0.7874 0.4064)
			(stroke
				(width 0.1524)
				(type default)
			)
			(layer "F.SilkS")
		)
		(fp_line
			(start -0.67945 -0.305054)
			(end -0.12065 -0.305054)
			(stroke
				(width 0.1)
				(type default)
			)
			(layer "F.Fab")
		)
		(fp_line
			(start -0.67945 0.3048)
			(end -0.67945 -0.305054)
			(stroke
				(width 0.1)
				(type default)
			)
			(layer "F.Fab")
		)
		(fp_line
			(start -0.12065 -0.305054)
			(end -0.12065 -0.2794)
			(stroke
				(width 0.1)
				(type default)
			)
			(layer "F.Fab")
		)
		(fp_line
			(start -0.12065 -0.2794)
			(end 0.12065 -0.2794)
			(stroke
				(width 0.1)
				(type default)
			)
			(layer "F.Fab")
		)
		(fp_line
			(start -0.12065 0.2794)
			(end -0.12065 0.3048)
			(stroke
				(width 0.1)
				(type default)
			)
			(layer "F.Fab")
		)
		(fp_line
			(start -0.12065 0.3048)
			(end -0.67945 0.3048)
			(stroke
				(width 0.1)
				(type default)
			)
			(layer "F.Fab")
		)
		(fp_line
			(start 0.120396 0.2794)
			(end -0.12065 0.2794)
			(stroke
				(width 0.1)
				(type default)
			)
			(layer "F.Fab")
		)
		(fp_line
			(start 0.120396 0.3048)
			(end 0.120396 0.2794)
			(stroke
				(width 0.1)
				(type default)
			)
			(layer "F.Fab")
		)
		(fp_line
			(start 0.12065 -0.3048)
			(end 0.67945 -0.3048)
			(stroke
				(width 0.1)
				(type default)
			)
			(layer "F.Fab")
		)
		(fp_line
			(start 0.12065 -0.2794)
			(end 0.12065 -0.3048)
			(stroke
				(width 0.1)
				(type default)
			)
			(layer "F.Fab")
		)
		(fp_line
			(start 0.67945 -0.3048)
			(end 0.67945 0.3048)
			(stroke
				(width 0.1)
				(type default)
			)
			(layer "F.Fab")
		)
		(fp_line
			(start 0.67945 0.3048)
			(end 0.120396 0.3048)
			(stroke
				(width 0.1)
				(type default)
			)
			(layer "F.Fab")
		)
		(pad "1" smd circle
			(at -0.40005 0)
			(size 0 0)
			(layers "F.Cu" "F.Mask" "F.Paste")
			(net "GND")
		)
		(pad "2" smd circle
			(at 0.40005 0)
			(size 0 0)
			(layers "F.Cu" "F.Mask" "F.Paste")
			(net "P3V3_OCP_ILIMIT_2")
		)
	)
	(footprint ""
		(layer "F.Cu")
		(at 163.50488 -438.495948 180)
		(property "Reference" "R3449"
			(at 0 0 180)
			(layer "F.SilkS")
			(hide yes)
			(effects
				(font
					(size 1.27 1.27)
				)
			)
		)
		(property "Value" ""
			(at 0 0 180)
			(layer "F.Fab")
			(effects
				(font
					(size 1.27 1.27)
				)
			)
		)
		(duplicate_pad_numbers_are_jumpers no)
		(fp_line
			(start 0.7874 0.4064)
			(end -0.7874 0.4064)
			(stroke
				(width 0.1524)
				(type default)
			)
			(layer "F.SilkS")
		)
		(fp_line
			(start 0.7874 -0.4064)
			(end 0.7874 0.4064)
			(stroke
				(width 0.1524)
				(type default)
			)
			(layer "F.SilkS")
		)
		(fp_line
			(start -0.7874 0.4064)
			(end -0.7874 -0.4064)
			(stroke
				(width 0.1524)
				(type default)
			)
			(layer "F.SilkS")
		)
		(fp_line
			(start -0.7874 -0.4064)
			(end 0.7874 -0.4064)
			(stroke
				(width 0.1524)
				(type default)
			)
			(layer "F.SilkS")
		)
		(fp_line
			(start 0.67945 0.3048)
			(end 0.120396 0.3048)
			(stroke
				(width 0.1)
				(type default)
			)
			(layer "F.Fab")
		)
		(fp_line
			(start 0.67945 -0.3048)
			(end 0.67945 0.3048)
			(stroke
				(width 0.1)
				(type default)
			)
			(layer "F.Fab")
		)
		(fp_line
			(start 0.12065 -0.2794)
			(end 0.12065 -0.3048)
			(stroke
				(width 0.1)
				(type default)
			)
			(layer "F.Fab")
		)
		(fp_line
			(start 0.12065 -0.3048)
			(end 0.67945 -0.3048)
			(stroke
				(width 0.1)
				(type default)
			)
			(layer "F.Fab")
		)
		(fp_line
			(start 0.120396 0.3048)
			(end 0.120396 0.2794)
			(stroke
				(width 0.1)
				(type default)
			)
			(layer "F.Fab")
		)
		(fp_line
			(start 0.120396 0.2794)
			(end -0.12065 0.2794)
			(stroke
				(width 0.1)
				(type default)
			)
			(layer "F.Fab")
		)
		(fp_line
			(start -0.12065 0.3048)
			(end -0.67945 0.3048)
			(stroke
				(width 0.1)
				(type default)
			)
			(layer "F.Fab")
		)
		(fp_line
			(start -0.12065 0.2794)
			(end -0.12065 0.3048)
			(stroke
				(width 0.1)
				(type default)
			)
			(layer "F.Fab")
		)
		(fp_line
			(start -0.12065 -0.2794)
			(end 0.12065 -0.2794)
			(stroke
				(width 0.1)
				(type default)
			)
			(layer "F.Fab")
		)
		(fp_line
			(start -0.12065 -0.305054)
			(end -0.12065 -0.2794)
			(stroke
				(width 0.1)
				(type default)
			)
			(layer "F.Fab")
		)
		(fp_line
			(start -0.67945 0.3048)
			(end -0.67945 -0.305054)
			(stroke
				(width 0.1)
				(type default)
			)
			(layer "F.Fab")
		)
		(fp_line
			(start -0.67945 -0.305054)
			(end -0.12065 -0.305054)
			(stroke
				(width 0.1)
				(type default)
			)
			(layer "F.Fab")
		)
		(pad "1" smd circle
			(at -0.40005 0 180)
			(size 0 0)
			(layers "F.Cu" "F.Mask" "F.Paste")
			(net "GPU_FPGA_BOOT_EN")
		)
		(pad "2" smd circle
			(at 0.40005 0 180)
			(size 0 0)
			(layers "F.Cu" "F.Mask" "F.Paste")
			(net "GND")
		)
	)
	(footprint ""
		(layer "F.Cu")
		(at 20.190714 -107.777026)
		(property "Reference" "R3669"
			(at 0 0 0)
			(layer "F.SilkS")
			(hide yes)
			(effects
				(font
					(size 1.27 1.27)
				)
			)
		)
		(property "Value" ""
			(at 0 0 0)
			(layer "F.Fab")
			(effects
				(font
					(size 1.27 1.27)
				)
			)
		)
		(duplicate_pad_numbers_are_jumpers no)
		(fp_line
			(start -0.7874 -0.4064)
			(end 0.7874 -0.4064)
			(stroke
				(width 0.1524)
				(type default)
			)
			(layer "F.SilkS")
		)
		(fp_line
			(start -0.7874 0.4064)
			(end -0.7874 -0.4064)
			(stroke
				(width 0.1524)
				(type default)
			)
			(layer "F.SilkS")
		)
		(fp_line
			(start 0.7874 -0.4064)
			(end 0.7874 0.4064)
			(stroke
				(width 0.1524)
				(type default)
			)
			(layer "F.SilkS")
		)
		(fp_line
			(start 0.7874 0.4064)
			(end -0.7874 0.4064)
			(stroke
				(width 0.1524)
				(type default)
			)
			(layer "F.SilkS")
		)
		(fp_line
			(start -0.67945 -0.305054)
			(end -0.12065 -0.305054)
			(stroke
				(width 0.1)
				(type default)
			)
			(layer "F.Fab")
		)
		(fp_line
			(start -0.67945 0.3048)
			(end -0.67945 -0.305054)
			(stroke
				(width 0.1)
				(type default)
			)
			(layer "F.Fab")
		)
		(fp_line
			(start -0.12065 -0.305054)
			(end -0.12065 -0.2794)
			(stroke
				(width 0.1)
				(type default)
			)
			(layer "F.Fab")
		)
		(fp_line
			(start -0.12065 -0.2794)
			(end 0.12065 -0.2794)
			(stroke
				(width 0.1)
				(type default)
			)
			(layer "F.Fab")
		)
		(fp_line
			(start -0.12065 0.2794)
			(end -0.12065 0.3048)
			(stroke
				(width 0.1)
				(type default)
			)
			(layer "F.Fab")
		)
		(fp_line
			(start -0.12065 0.3048)
			(end -0.67945 0.3048)
			(stroke
				(width 0.1)
				(type default)
			)
			(layer "F.Fab")
		)
		(fp_line
			(start 0.120396 0.2794)
			(end -0.12065 0.2794)
			(stroke
				(width 0.1)
				(type default)
			)
			(layer "F.Fab")
		)
		(fp_line
			(start 0.120396 0.3048)
			(end 0.120396 0.2794)
			(stroke
				(width 0.1)
				(type default)
			)
			(layer "F.Fab")
		)
		(fp_line
			(start 0.12065 -0.3048)
			(end 0.67945 -0.3048)
			(stroke
				(width 0.1)
				(type default)
			)
			(layer "F.Fab")
		)
		(fp_line
			(start 0.12065 -0.2794)
			(end 0.12065 -0.3048)
			(stroke
				(width 0.1)
				(type default)
			)
			(layer "F.Fab")
		)
		(fp_line
			(start 0.67945 -0.3048)
			(end 0.67945 0.3048)
			(stroke
				(width 0.1)
				(type default)
			)
			(layer "F.Fab")
		)
		(fp_line
			(start 0.67945 0.3048)
			(end 0.120396 0.3048)
			(stroke
				(width 0.1)
				(type default)
			)
			(layer "F.Fab")
		)
		(pad "1" smd circle
			(at -0.40005 0)
			(size 0 0)
			(layers "F.Cu" "F.Mask" "F.Paste")
			(net "P3V3_AUX")
		)
		(pad "2" smd circle
			(at 0.40005 0)
			(size 0 0)
			(layers "F.Cu" "F.Mask" "F.Paste")
			(net "ADC128_A0")
		)
	)
	(footprint ""
		(layer "F.Cu")
		(at 257.85953 -54.463442)
		(property "Reference" "PR3949"
			(at 0 0 0)
			(layer "F.SilkS")
			(hide yes)
			(effects
				(font
					(size 1.27 1.27)
				)
			)
		)
		(property "Value" ""
			(at 0 0 0)
			(layer "F.Fab")
			(effects
				(font
					(size 1.27 1.27)
				)
			)
		)
		(duplicate_pad_numbers_are_jumpers no)
		(fp_line
			(start -0.7874 -0.4064)
			(end 0.7874 -0.4064)
			(stroke
				(width 0.1524)
				(type default)
			)
			(layer "F.SilkS")
		)
		(fp_line
			(start -0.7874 0.4064)
			(end -0.7874 -0.4064)
			(stroke
				(width 0.1524)
				(type default)
			)
			(layer "F.SilkS")
		)
		(fp_line
			(start 0.7874 -0.4064)
			(end 0.7874 0.4064)
			(stroke
				(width 0.1524)
				(type default)
			)
			(layer "F.SilkS")
		)
		(fp_line
			(start 0.7874 0.4064)
			(end -0.7874 0.4064)
			(stroke
				(width 0.1524)
				(type default)
			)
			(layer "F.SilkS")
		)
		(fp_line
			(start -0.67945 -0.305054)
			(end -0.12065 -0.305054)
			(stroke
				(width 0.1)
				(type default)
			)
			(layer "F.Fab")
		)
		(fp_line
			(start -0.67945 0.3048)
			(end -0.67945 -0.305054)
			(stroke
				(width 0.1)
				(type default)
			)
			(layer "F.Fab")
		)
		(fp_line
			(start -0.12065 -0.305054)
			(end -0.12065 -0.2794)
			(stroke
				(width 0.1)
				(type default)
			)
			(layer "F.Fab")
		)
		(fp_line
			(start -0.12065 -0.2794)
			(end 0.12065 -0.2794)
			(stroke
				(width 0.1)
				(type default)
			)
			(layer "F.Fab")
		)
		(fp_line
			(start -0.12065 0.2794)
			(end -0.12065 0.3048)
			(stroke
				(width 0.1)
				(type default)
			)
			(layer "F.Fab")
		)
		(fp_line
			(start -0.12065 0.3048)
			(end -0.67945 0.3048)
			(stroke
				(width 0.1)
				(type default)
			)
			(layer "F.Fab")
		)
		(fp_line
			(start 0.120396 0.2794)
			(end -0.12065 0.2794)
			(stroke
				(width 0.1)
				(type default)
			)
			(layer "F.Fab")
		)
		(fp_line
			(start 0.120396 0.3048)
			(end 0.120396 0.2794)
			(stroke
				(width 0.1)
				(type default)
			)
			(layer "F.Fab")
		)
		(fp_line
			(start 0.12065 -0.3048)
			(end 0.67945 -0.3048)
			(stroke
				(width 0.1)
				(type default)
			)
			(layer "F.Fab")
		)
		(fp_line
			(start 0.12065 -0.2794)
			(end 0.12065 -0.3048)
			(stroke
				(width 0.1)
				(type default)
			)
			(layer "F.Fab")
		)
		(fp_line
			(start 0.67945 -0.3048)
			(end 0.67945 0.3048)
			(stroke
				(width 0.1)
				(type default)
			)
			(layer "F.Fab")
		)
		(fp_line
			(start 0.67945 0.3048)
			(end 0.120396 0.3048)
			(stroke
				(width 0.1)
				(type default)
			)
			(layer "F.Fab")
		)
		(pad "1" smd circle
			(at -0.40005 0)
			(size 0 0)
			(layers "F.Cu" "F.Mask" "F.Paste")
			(net "P12V_E1S_IMON_0")
		)
		(pad "2" smd circle
			(at 0.40005 0)
			(size 0 0)
			(layers "F.Cu" "F.Mask" "F.Paste")
			(net "GND")
		)
	)
	(footprint ""
		(layer "F.Cu")
		(at 193.93408 -352.694748)
		(property "Reference" "R626"
			(at 0 0 0)
			(layer "F.SilkS")
			(hide yes)
			(effects
				(font
					(size 1.27 1.27)
				)
			)
		)
		(property "Value" ""
			(at 0 0 0)
			(layer "F.Fab")
			(effects
				(font
					(size 1.27 1.27)
				)
			)
		)
		(duplicate_pad_numbers_are_jumpers no)
		(fp_line
			(start -0.7874 -0.4064)
			(end 0.7874 -0.4064)
			(stroke
				(width 0.1524)
				(type default)
			)
			(layer "F.SilkS")
		)
		(fp_line
			(start -0.7874 0.4064)
			(end -0.7874 -0.4064)
			(stroke
				(width 0.1524)
				(type default)
			)
			(layer "F.SilkS")
		)
		(fp_line
			(start 0.7874 -0.4064)
			(end 0.7874 0.4064)
			(stroke
				(width 0.1524)
				(type default)
			)
			(layer "F.SilkS")
		)
		(fp_line
			(start 0.7874 0.4064)
			(end -0.7874 0.4064)
			(stroke
				(width 0.1524)
				(type default)
			)
			(layer "F.SilkS")
		)
		(fp_line
			(start -0.67945 -0.305054)
			(end -0.12065 -0.305054)
			(stroke
				(width 0.1)
				(type default)
			)
			(layer "F.Fab")
		)
		(fp_line
			(start -0.67945 0.3048)
			(end -0.67945 -0.305054)
			(stroke
				(width 0.1)
				(type default)
			)
			(layer "F.Fab")
		)
		(fp_line
			(start -0.12065 -0.305054)
			(end -0.12065 -0.2794)
			(stroke
				(width 0.1)
				(type default)
			)
			(layer "F.Fab")
		)
		(fp_line
			(start -0.12065 -0.2794)
			(end 0.12065 -0.2794)
			(stroke
				(width 0.1)
				(type default)
			)
			(layer "F.Fab")
		)
		(fp_line
			(start -0.12065 0.2794)
			(end -0.12065 0.3048)
			(stroke
				(width 0.1)
				(type default)
			)
			(layer "F.Fab")
		)
		(fp_line
			(start -0.12065 0.3048)
			(end -0.67945 0.3048)
			(stroke
				(width 0.1)
				(type default)
			)
			(layer "F.Fab")
		)
		(fp_line
			(start 0.120396 0.2794)
			(end -0.12065 0.2794)
			(stroke
				(width 0.1)
				(type default)
			)
			(layer "F.Fab")
		)
		(fp_line
			(start 0.120396 0.3048)
			(end 0.120396 0.2794)
			(stroke
				(width 0.1)
				(type default)
			)
			(layer "F.Fab")
		)
		(fp_line
			(start 0.12065 -0.3048)
			(end 0.67945 -0.3048)
			(stroke
				(width 0.1)
				(type default)
			)
			(layer "F.Fab")
		)
		(fp_line
			(start 0.12065 -0.2794)
			(end 0.12065 -0.3048)
			(stroke
				(width 0.1)
				(type default)
			)
			(layer "F.Fab")
		)
		(fp_line
			(start 0.67945 -0.3048)
			(end 0.67945 0.3048)
			(stroke
				(width 0.1)
				(type default)
			)
			(layer "F.Fab")
		)
		(fp_line
			(start 0.67945 0.3048)
			(end 0.120396 0.3048)
			(stroke
				(width 0.1)
				(type default)
			)
			(layer "F.Fab")
		)
		(pad "1" smd circle
			(at -0.40005 0)
			(size 0 0)
			(layers "F.Cu" "F.Mask" "F.Paste")
			(net "PD_PIROM_CPU1_ADDR2")
		)
		(pad "2" smd circle
			(at 0.40005 0)
			(size 0 0)
			(layers "F.Cu" "F.Mask" "F.Paste")
			(net "GND")
		)
	)
	(footprint ""
		(layer "F.Cu")
		(at 240.626392 -250.717558 90)
		(property "Reference" "C2256"
			(at 0 0 90)
			(layer "F.SilkS")
			(hide yes)
			(effects
				(font
					(size 1.27 1.27)
				)
			)
		)
		(property "Value" ""
			(at 0 0 90)
			(layer "F.Fab")
			(effects
				(font
					(size 1.27 1.27)
				)
			)
		)
		(duplicate_pad_numbers_are_jumpers no)
		(fp_line
			(start 0.7874 -0.4064)
			(end 0.7874 0.4064)
			(stroke
				(width 0.1524)
				(type default)
			)
			(layer "F.SilkS")
		)
		(fp_line
			(start -0.7874 -0.4064)
			(end 0.7874 -0.4064)
			(stroke
				(width 0.1524)
				(type default)
			)
			(layer "F.SilkS")
		)
		(fp_line
			(start 0.7874 0.4064)
			(end -0.7874 0.4064)
			(stroke
				(width 0.1524)
				(type default)
			)
			(layer "F.SilkS")
		)
		(fp_line
			(start -0.7874 0.4064)
			(end -0.7874 -0.4064)
			(stroke
				(width 0.1524)
				(type default)
			)
			(layer "F.SilkS")
		)
		(fp_line
			(start -0.12065 -0.305054)
			(end -0.12065 -0.2794)
			(stroke
				(width 0.1)
				(type default)
			)
			(layer "F.Fab")
		)
		(fp_line
			(start -0.67945 -0.305054)
			(end -0.12065 -0.305054)
			(stroke
				(width 0.1)
				(type default)
			)
			(layer "F.Fab")
		)
		(fp_line
			(start 0.67945 -0.3048)
			(end 0.67945 0.3048)
			(stroke
				(width 0.1)
				(type default)
			)
			(layer "F.Fab")
		)
		(fp_line
			(start 0.12065 -0.3048)
			(end 0.67945 -0.3048)
			(stroke
				(width 0.1)
				(type default)
			)
			(layer "F.Fab")
		)
		(fp_line
			(start 0.12065 -0.2794)
			(end 0.12065 -0.3048)
			(stroke
				(width 0.1)
				(type default)
			)
			(layer "F.Fab")
		)
		(fp_line
			(start -0.12065 -0.2794)
			(end 0.12065 -0.2794)
			(stroke
				(width 0.1)
				(type default)
			)
			(layer "F.Fab")
		)
		(fp_line
			(start 0.120396 0.2794)
			(end -0.12065 0.2794)
			(stroke
				(width 0.1)
				(type default)
			)
			(layer "F.Fab")
		)
		(fp_line
			(start -0.12065 0.2794)
			(end -0.12065 0.3048)
			(stroke
				(width 0.1)
				(type default)
			)
			(layer "F.Fab")
		)
		(fp_line
			(start 0.67945 0.3048)
			(end 0.120396 0.3048)
			(stroke
				(width 0.1)
				(type default)
			)
			(layer "F.Fab")
		)
		(fp_line
			(start 0.120396 0.3048)
			(end 0.120396 0.2794)
			(stroke
				(width 0.1)
				(type default)
			)
			(layer "F.Fab")
		)
		(fp_line
			(start -0.12065 0.3048)
			(end -0.67945 0.3048)
			(stroke
				(width 0.1)
				(type default)
			)
			(layer "F.Fab")
		)
		(fp_line
			(start -0.67945 0.3048)
			(end -0.67945 -0.305054)
			(stroke
				(width 0.1)
				(type default)
			)
			(layer "F.Fab")
		)
		(pad "1" smd circle
			(at -0.40005 0 90)
			(size 0 0)
			(layers "F.Cu" "F.Mask" "F.Paste")
			(net "CLK_GEN2_XTAL_OUT")
		)
		(pad "2" smd circle
			(at 0.40005 0 90)
			(size 0 0)
			(layers "F.Cu" "F.Mask" "F.Paste")
			(net "GND")
		)
	)
	(footprint ""
		(layer "F.Cu")
		(at 441.885324 -153.78557)
		(property "Reference" "H120"
			(at -0.79248 -7.30377 0)
			(unlocked yes)
			(layer "F.SilkS")
			(effects
				(font
					(size 0.7874 0.5842)
					(thickness 0.1524)
				)
				(justify left)
			)
		)
		(property "Value" ""
			(at 0 0 0)
			(layer "F.Fab")
			(effects
				(font
					(size 1.27 1.27)
				)
			)
		)
		(duplicate_pad_numbers_are_jumpers no)
		(fp_circle
			(center 0 0)
			(end 5.8166 0)
			(stroke
				(width 0.1524)
				(type default)
			)
			(fill no)
			(layer "F.SilkS")
		)
		(fp_circle
			(center 0 0)
			(end 5.8166 0)
			(stroke
				(width 0.1524)
				(type default)
			)
			(fill no)
			(layer "B.SilkS")
		)
		(fp_circle
			(center 0 0)
			(end 5.8166 0)
			(stroke
				(width 0.1)
				(type default)
			)
			(fill no)
			(layer "B.Fab")
		)
		(fp_circle
			(center 0 0)
			(end 5.8166 0)
			(stroke
				(width 0.1)
				(type default)
			)
			(fill no)
			(layer "F.Fab")
		)
		(pad "" np_thru_hole circle
			(at 0 0)
			(size 10.0076 10.0076)
			(drill 10.0076)
			(layers "*.Cu" "*.Mask")
			(clearance 0.381)
			(thermal_gap 0.381)
		)
	)
	(footprint ""
		(layer "F.Cu")
		(at 54.242716 -111.94669 180)
		(property "Reference" "R3716"
			(at 0 0 180)
			(layer "F.SilkS")
			(hide yes)
			(effects
				(font
					(size 1.27 1.27)
				)
			)
		)
		(property "Value" ""
			(at 0 0 180)
			(layer "F.Fab")
			(effects
				(font
					(size 1.27 1.27)
				)
			)
		)
		(duplicate_pad_numbers_are_jumpers no)
		(fp_line
			(start 0.7874 0.4064)
			(end -0.7874 0.4064)
			(stroke
				(width 0.1524)
				(type default)
			)
			(layer "F.SilkS")
		)
		(fp_line
			(start 0.7874 -0.4064)
			(end 0.7874 0.4064)
			(stroke
				(width 0.1524)
				(type default)
			)
			(layer "F.SilkS")
		)
		(fp_line
			(start -0.7874 0.4064)
			(end -0.7874 -0.4064)
			(stroke
				(width 0.1524)
				(type default)
			)
			(layer "F.SilkS")
		)
		(fp_line
			(start -0.7874 -0.4064)
			(end 0.7874 -0.4064)
			(stroke
				(width 0.1524)
				(type default)
			)
			(layer "F.SilkS")
		)
		(fp_line
			(start 0.67945 0.3048)
			(end 0.120396 0.3048)
			(stroke
				(width 0.1)
				(type default)
			)
			(layer "F.Fab")
		)
		(fp_line
			(start 0.67945 -0.3048)
			(end 0.67945 0.3048)
			(stroke
				(width 0.1)
				(type default)
			)
			(layer "F.Fab")
		)
		(fp_line
			(start 0.12065 -0.2794)
			(end 0.12065 -0.3048)
			(stroke
				(width 0.1)
				(type default)
			)
			(layer "F.Fab")
		)
		(fp_line
			(start 0.12065 -0.3048)
			(end 0.67945 -0.3048)
			(stroke
				(width 0.1)
				(type default)
			)
			(layer "F.Fab")
		)
		(fp_line
			(start 0.120396 0.3048)
			(end 0.120396 0.2794)
			(stroke
				(width 0.1)
				(type default)
			)
			(layer "F.Fab")
		)
		(fp_line
			(start 0.120396 0.2794)
			(end -0.12065 0.2794)
			(stroke
				(width 0.1)
				(type default)
			)
			(layer "F.Fab")
		)
		(fp_line
			(start -0.12065 0.3048)
			(end -0.67945 0.3048)
			(stroke
				(width 0.1)
				(type default)
			)
			(layer "F.Fab")
		)
		(fp_line
			(start -0.12065 0.2794)
			(end -0.12065 0.3048)
			(stroke
				(width 0.1)
				(type default)
			)
			(layer "F.Fab")
		)
		(fp_line
			(start -0.12065 -0.2794)
			(end 0.12065 -0.2794)
			(stroke
				(width 0.1)
				(type default)
			)
			(layer "F.Fab")
		)
		(fp_line
			(start -0.12065 -0.305054)
			(end -0.12065 -0.2794)
			(stroke
				(width 0.1)
				(type default)
			)
			(layer "F.Fab")
		)
		(fp_line
			(start -0.67945 0.3048)
			(end -0.67945 -0.305054)
			(stroke
				(width 0.1)
				(type default)
			)
			(layer "F.Fab")
		)
		(fp_line
			(start -0.67945 -0.305054)
			(end -0.12065 -0.305054)
			(stroke
				(width 0.1)
				(type default)
			)
			(layer "F.Fab")
		)
		(pad "1" smd circle
			(at -0.40005 0 180)
			(size 0 0)
			(layers "F.Cu" "F.Mask" "F.Paste")
			(net "SMB_LM75_0_3V3AUX_SDA_R")
		)
		(pad "2" smd circle
			(at 0.40005 0 180)
			(size 0 0)
			(layers "F.Cu" "F.Mask" "F.Paste")
			(net "SMB_LM75_0_3V3AUX_SDA")
		)
	)
	(footprint ""
		(layer "F.Cu")
		(at 439.272172 -32.173418 90)
		(property "Reference" "PC2156"
			(at 0 0 90)
			(layer "F.SilkS")
			(hide yes)
			(effects
				(font
					(size 1.27 1.27)
				)
			)
		)
		(property "Value" ""
			(at 0 0 90)
			(layer "F.Fab")
			(effects
				(font
					(size 1.27 1.27)
				)
			)
		)
		(duplicate_pad_numbers_are_jumpers no)
		(fp_line
			(start 0.7874 -0.4064)
			(end 0.7874 0.4064)
			(stroke
				(width 0.1524)
				(type default)
			)
			(layer "F.SilkS")
		)
		(fp_line
			(start -0.7874 -0.4064)
			(end 0.7874 -0.4064)
			(stroke
				(width 0.1524)
				(type default)
			)
			(layer "F.SilkS")
		)
		(fp_line
			(start 0.7874 0.4064)
			(end -0.7874 0.4064)
			(stroke
				(width 0.1524)
				(type default)
			)
			(layer "F.SilkS")
		)
		(fp_line
			(start -0.7874 0.4064)
			(end -0.7874 -0.4064)
			(stroke
				(width 0.1524)
				(type default)
			)
			(layer "F.SilkS")
		)
		(fp_line
			(start -0.12065 -0.305054)
			(end -0.12065 -0.2794)
			(stroke
				(width 0.1)
				(type default)
			)
			(layer "F.Fab")
		)
		(fp_line
			(start -0.67945 -0.305054)
			(end -0.12065 -0.305054)
			(stroke
				(width 0.1)
				(type default)
			)
			(layer "F.Fab")
		)
		(fp_line
			(start 0.67945 -0.3048)
			(end 0.67945 0.3048)
			(stroke
				(width 0.1)
				(type default)
			)
			(layer "F.Fab")
		)
		(fp_line
			(start 0.12065 -0.3048)
			(end 0.67945 -0.3048)
			(stroke
				(width 0.1)
				(type default)
			)
			(layer "F.Fab")
		)
		(fp_line
			(start 0.12065 -0.2794)
			(end 0.12065 -0.3048)
			(stroke
				(width 0.1)
				(type default)
			)
			(layer "F.Fab")
		)
		(fp_line
			(start -0.12065 -0.2794)
			(end 0.12065 -0.2794)
			(stroke
				(width 0.1)
				(type default)
			)
			(layer "F.Fab")
		)
		(fp_line
			(start 0.120396 0.2794)
			(end -0.12065 0.2794)
			(stroke
				(width 0.1)
				(type default)
			)
			(layer "F.Fab")
		)
		(fp_line
			(start -0.12065 0.2794)
			(end -0.12065 0.3048)
			(stroke
				(width 0.1)
				(type default)
			)
			(layer "F.Fab")
		)
		(fp_line
			(start 0.67945 0.3048)
			(end 0.120396 0.3048)
			(stroke
				(width 0.1)
				(type default)
			)
			(layer "F.Fab")
		)
		(fp_line
			(start 0.120396 0.3048)
			(end 0.120396 0.2794)
			(stroke
				(width 0.1)
				(type default)
			)
			(layer "F.Fab")
		)
		(fp_line
			(start -0.12065 0.3048)
			(end -0.67945 0.3048)
			(stroke
				(width 0.1)
				(type default)
			)
			(layer "F.Fab")
		)
		(fp_line
			(start -0.67945 0.3048)
			(end -0.67945 -0.305054)
			(stroke
				(width 0.1)
				(type default)
			)
			(layer "F.Fab")
		)
		(pad "1" smd circle
			(at -0.40005 0 90)
			(size 0 0)
			(layers "F.Cu" "F.Mask" "F.Paste")
			(net "P12V_OCP_IMON_1")
		)
		(pad "2" smd circle
			(at 0.40005 0 90)
			(size 0 0)
			(layers "F.Cu" "F.Mask" "F.Paste")
			(net "GND")
		)
	)
	(footprint ""
		(layer "F.Cu")
		(at 338.56295 -341.729822 -90)
		(property "Reference" "PC256"
			(at 0 0 270)
			(layer "F.SilkS")
			(hide yes)
			(effects
				(font
					(size 1.27 1.27)
				)
			)
		)
		(property "Value" ""
			(at 0 0 270)
			(layer "F.Fab")
			(effects
				(font
					(size 1.27 1.27)
				)
			)
		)
		(duplicate_pad_numbers_are_jumpers no)
		(fp_line
			(start -0.7874 0.4064)
			(end -0.7874 -0.4064)
			(stroke
				(width 0.1524)
				(type default)
			)
			(layer "F.SilkS")
		)
		(fp_line
			(start 0.7874 0.4064)
			(end -0.7874 0.4064)
			(stroke
				(width 0.1524)
				(type default)
			)
			(layer "F.SilkS")
		)
		(fp_line
			(start -0.7874 -0.4064)
			(end 0.7874 -0.4064)
			(stroke
				(width 0.1524)
				(type default)
			)
			(layer "F.SilkS")
		)
		(fp_line
			(start 0.7874 -0.4064)
			(end 0.7874 0.4064)
			(stroke
				(width 0.1524)
				(type default)
			)
			(layer "F.SilkS")
		)
		(fp_line
			(start -0.67945 0.3048)
			(end -0.67945 -0.305054)
			(stroke
				(width 0.1)
				(type default)
			)
			(layer "F.Fab")
		)
		(fp_line
			(start -0.12065 0.3048)
			(end -0.67945 0.3048)
			(stroke
				(width 0.1)
				(type default)
			)
			(layer "F.Fab")
		)
		(fp_line
			(start 0.120396 0.3048)
			(end 0.120396 0.2794)
			(stroke
				(width 0.1)
				(type default)
			)
			(layer "F.Fab")
		)
		(fp_line
			(start 0.67945 0.3048)
			(end 0.120396 0.3048)
			(stroke
				(width 0.1)
				(type default)
			)
			(layer "F.Fab")
		)
		(fp_line
			(start -0.12065 0.2794)
			(end -0.12065 0.3048)
			(stroke
				(width 0.1)
				(type default)
			)
			(layer "F.Fab")
		)
		(fp_line
			(start 0.120396 0.2794)
			(end -0.12065 0.2794)
			(stroke
				(width 0.1)
				(type default)
			)
			(layer "F.Fab")
		)
		(fp_line
			(start -0.12065 -0.2794)
			(end 0.12065 -0.2794)
			(stroke
				(width 0.1)
				(type default)
			)
			(layer "F.Fab")
		)
		(fp_line
			(start 0.12065 -0.2794)
			(end 0.12065 -0.3048)
			(stroke
				(width 0.1)
				(type default)
			)
			(layer "F.Fab")
		)
		(fp_line
			(start 0.12065 -0.3048)
			(end 0.67945 -0.3048)
			(stroke
				(width 0.1)
				(type default)
			)
			(layer "F.Fab")
		)
		(fp_line
			(start 0.67945 -0.3048)
			(end 0.67945 0.3048)
			(stroke
				(width 0.1)
				(type default)
			)
			(layer "F.Fab")
		)
		(fp_line
			(start -0.67945 -0.305054)
			(end -0.12065 -0.305054)
			(stroke
				(width 0.1)
				(type default)
			)
			(layer "F.Fab")
		)
		(fp_line
			(start -0.12065 -0.305054)
			(end -0.12065 -0.2794)
			(stroke
				(width 0.1)
				(type default)
			)
			(layer "F.Fab")
		)
		(pad "1" smd circle
			(at -0.40005 0 270)
			(size 0 0)
			(layers "F.Cu" "F.Mask" "F.Paste")
			(net "SW_PVCCIN_CPU0_BOOT6_R")
		)
		(pad "2" smd circle
			(at 0.40005 0 270)
			(size 0 0)
			(layers "F.Cu" "F.Mask" "F.Paste")
			(net "SW_PVCCIN_CPU0_BOOTR6")
		)
	)
	(footprint ""
		(layer "F.Cu")
		(at 458.720444 -70.271386 -90)
		(property "Reference" "PC2261"
			(at 0 0 270)
			(layer "F.SilkS")
			(hide yes)
			(effects
				(font
					(size 1.27 1.27)
				)
			)
		)
		(property "Value" ""
			(at 0 0 270)
			(layer "F.Fab")
			(effects
				(font
					(size 1.27 1.27)
				)
			)
		)
		(duplicate_pad_numbers_are_jumpers no)
		(fp_line
			(start -1.524 0.762)
			(end -1.524 -0.762)
			(stroke
				(width 0.1524)
				(type default)
			)
			(layer "F.SilkS")
		)
		(fp_line
			(start 1.524 0.762)
			(end -1.524 0.762)
			(stroke
				(width 0.1524)
				(type default)
			)
			(layer "F.SilkS")
		)
		(fp_line
			(start -1.524 -0.762)
			(end 1.524 -0.762)
			(stroke
				(width 0.1524)
				(type default)
			)
			(layer "F.SilkS")
		)
		(fp_line
			(start 1.524 -0.762)
			(end 1.524 0.762)
			(stroke
				(width 0.1524)
				(type default)
			)
			(layer "F.SilkS")
		)
		(fp_line
			(start -1.1049 0.724916)
			(end 1.1049 0.724916)
			(stroke
				(width 0.1)
				(type default)
			)
			(layer "F.Fab")
		)
		(fp_line
			(start 1.1049 0.724916)
			(end 1.1049 -0.724916)
			(stroke
				(width 0.1)
				(type default)
			)
			(layer "F.Fab")
		)
		(fp_line
			(start -1.1049 -0.724916)
			(end -1.1049 0.724916)
			(stroke
				(width 0.1)
				(type default)
			)
			(layer "F.Fab")
		)
		(fp_line
			(start 1.1049 -0.724916)
			(end -1.1049 -0.724916)
			(stroke
				(width 0.1)
				(type default)
			)
			(layer "F.Fab")
		)
		(pad "1" smd rect
			(at -0.889 0 90)
			(size 1.016 1.27)
			(layers "F.Cu" "F.Mask" "F.Paste")
			(net "SW_P3V3_AUX_FLT")
		)
		(pad "2" smd rect
			(at 0.889 0 90)
			(size 1.016 1.27)
			(layers "F.Cu" "F.Mask" "F.Paste")
			(net "GND")
		)
	)
	(footprint ""
		(layer "F.Cu")
		(at 30.49524 -122.380502 90)
		(property "Reference" "R2450"
			(at 0 0 90)
			(layer "F.SilkS")
			(hide yes)
			(effects
				(font
					(size 1.27 1.27)
				)
			)
		)
		(property "Value" ""
			(at 0 0 90)
			(layer "F.Fab")
			(effects
				(font
					(size 1.27 1.27)
				)
			)
		)
		(duplicate_pad_numbers_are_jumpers no)
		(fp_line
			(start 0.7874 -0.4064)
			(end 0.7874 0.4064)
			(stroke
				(width 0.1524)
				(type default)
			)
			(layer "F.SilkS")
		)
		(fp_line
			(start -0.7874 -0.4064)
			(end 0.7874 -0.4064)
			(stroke
				(width 0.1524)
				(type default)
			)
			(layer "F.SilkS")
		)
		(fp_line
			(start 0.7874 0.4064)
			(end -0.7874 0.4064)
			(stroke
				(width 0.1524)
				(type default)
			)
			(layer "F.SilkS")
		)
		(fp_line
			(start -0.7874 0.4064)
			(end -0.7874 -0.4064)
			(stroke
				(width 0.1524)
				(type default)
			)
			(layer "F.SilkS")
		)
		(fp_line
			(start -0.12065 -0.305054)
			(end -0.12065 -0.2794)
			(stroke
				(width 0.1)
				(type default)
			)
			(layer "F.Fab")
		)
		(fp_line
			(start -0.67945 -0.305054)
			(end -0.12065 -0.305054)
			(stroke
				(width 0.1)
				(type default)
			)
			(layer "F.Fab")
		)
		(fp_line
			(start 0.67945 -0.3048)
			(end 0.67945 0.3048)
			(stroke
				(width 0.1)
				(type default)
			)
			(layer "F.Fab")
		)
		(fp_line
			(start 0.12065 -0.3048)
			(end 0.67945 -0.3048)
			(stroke
				(width 0.1)
				(type default)
			)
			(layer "F.Fab")
		)
		(fp_line
			(start 0.12065 -0.2794)
			(end 0.12065 -0.3048)
			(stroke
				(width 0.1)
				(type default)
			)
			(layer "F.Fab")
		)
		(fp_line
			(start -0.12065 -0.2794)
			(end 0.12065 -0.2794)
			(stroke
				(width 0.1)
				(type default)
			)
			(layer "F.Fab")
		)
		(fp_line
			(start 0.120396 0.2794)
			(end -0.12065 0.2794)
			(stroke
				(width 0.1)
				(type default)
			)
			(layer "F.Fab")
		)
		(fp_line
			(start -0.12065 0.2794)
			(end -0.12065 0.3048)
			(stroke
				(width 0.1)
				(type default)
			)
			(layer "F.Fab")
		)
		(fp_line
			(start 0.67945 0.3048)
			(end 0.120396 0.3048)
			(stroke
				(width 0.1)
				(type default)
			)
			(layer "F.Fab")
		)
		(fp_line
			(start 0.120396 0.3048)
			(end 0.120396 0.2794)
			(stroke
				(width 0.1)
				(type default)
			)
			(layer "F.Fab")
		)
		(fp_line
			(start -0.12065 0.3048)
			(end -0.67945 0.3048)
			(stroke
				(width 0.1)
				(type default)
			)
			(layer "F.Fab")
		)
		(fp_line
			(start -0.67945 0.3048)
			(end -0.67945 -0.305054)
			(stroke
				(width 0.1)
				(type default)
			)
			(layer "F.Fab")
		)
		(pad "1" smd circle
			(at -0.40005 0 90)
			(size 0 0)
			(layers "F.Cu" "F.Mask" "F.Paste")
			(net "SMB_VR_3V3AUX_SDA")
		)
		(pad "2" smd circle
			(at 0.40005 0 90)
			(size 0 0)
			(layers "F.Cu" "F.Mask" "F.Paste")
			(net "SMB_VR_3V3AUX_SDA_R1")
		)
	)
	(footprint ""
		(layer "F.Cu")
		(at 348.929198 -337.856068)
		(property "Reference" "PC297_P0_1"
			(at 0 0 0)
			(layer "F.SilkS")
			(hide yes)
			(effects
				(font
					(size 1.27 1.27)
				)
			)
		)
		(property "Value" ""
			(at 0 0 0)
			(layer "F.Fab")
			(effects
				(font
					(size 1.27 1.27)
				)
			)
		)
		(duplicate_pad_numbers_are_jumpers no)
		(fp_line
			(start -0.7874 -0.4064)
			(end 0.7874 -0.4064)
			(stroke
				(width 0.1524)
				(type default)
			)
			(layer "F.SilkS")
		)
		(fp_line
			(start -0.7874 0.4064)
			(end -0.7874 -0.4064)
			(stroke
				(width 0.1524)
				(type default)
			)
			(layer "F.SilkS")
		)
		(fp_line
			(start 0.7874 -0.4064)
			(end 0.7874 0.4064)
			(stroke
				(width 0.1524)
				(type default)
			)
			(layer "F.SilkS")
		)
		(fp_line
			(start 0.7874 0.4064)
			(end -0.7874 0.4064)
			(stroke
				(width 0.1524)
				(type default)
			)
			(layer "F.SilkS")
		)
		(fp_line
			(start -0.67945 -0.305054)
			(end -0.12065 -0.305054)
			(stroke
				(width 0.1)
				(type default)
			)
			(layer "F.Fab")
		)
		(fp_line
			(start -0.67945 0.3048)
			(end -0.67945 -0.305054)
			(stroke
				(width 0.1)
				(type default)
			)
			(layer "F.Fab")
		)
		(fp_line
			(start -0.12065 -0.305054)
			(end -0.12065 -0.2794)
			(stroke
				(width 0.1)
				(type default)
			)
			(layer "F.Fab")
		)
		(fp_line
			(start -0.12065 -0.2794)
			(end 0.12065 -0.2794)
			(stroke
				(width 0.1)
				(type default)
			)
			(layer "F.Fab")
		)
		(fp_line
			(start -0.12065 0.2794)
			(end -0.12065 0.3048)
			(stroke
				(width 0.1)
				(type default)
			)
			(layer "F.Fab")
		)
		(fp_line
			(start -0.12065 0.3048)
			(end -0.67945 0.3048)
			(stroke
				(width 0.1)
				(type default)
			)
			(layer "F.Fab")
		)
		(fp_line
			(start 0.120396 0.2794)
			(end -0.12065 0.2794)
			(stroke
				(width 0.1)
				(type default)
			)
			(layer "F.Fab")
		)
		(fp_line
			(start 0.120396 0.3048)
			(end 0.120396 0.2794)
			(stroke
				(width 0.1)
				(type default)
			)
			(layer "F.Fab")
		)
		(fp_line
			(start 0.12065 -0.3048)
			(end 0.67945 -0.3048)
			(stroke
				(width 0.1)
				(type default)
			)
			(layer "F.Fab")
		)
		(fp_line
			(start 0.12065 -0.2794)
			(end 0.12065 -0.3048)
			(stroke
				(width 0.1)
				(type default)
			)
			(layer "F.Fab")
		)
		(fp_line
			(start 0.67945 -0.3048)
			(end 0.67945 0.3048)
			(stroke
				(width 0.1)
				(type default)
			)
			(layer "F.Fab")
		)
		(fp_line
			(start 0.67945 0.3048)
			(end 0.120396 0.3048)
			(stroke
				(width 0.1)
				(type default)
			)
			(layer "F.Fab")
		)
		(pad "1" smd circle
			(at -0.40005 0)
			(size 0 0)
			(layers "F.Cu" "F.Mask" "F.Paste")
			(net "SW_P12V_PVCCIN_CPU0_FLT")
		)
		(pad "2" smd circle
			(at 0.40005 0)
			(size 0 0)
			(layers "F.Cu" "F.Mask" "F.Paste")
			(net "GND")
		)
	)
	(footprint ""
		(layer "F.Cu")
		(at 224.20961 -46.524926)
		(property "Reference" "R1673"
			(at 0 0 0)
			(layer "F.SilkS")
			(hide yes)
			(effects
				(font
					(size 1.27 1.27)
				)
			)
		)
		(property "Value" ""
			(at 0 0 0)
			(layer "F.Fab")
			(effects
				(font
					(size 1.27 1.27)
				)
			)
		)
		(duplicate_pad_numbers_are_jumpers no)
		(fp_line
			(start -0.7874 -0.4064)
			(end 0.7874 -0.4064)
			(stroke
				(width 0.1524)
				(type default)
			)
			(layer "F.SilkS")
		)
		(fp_line
			(start -0.7874 0.4064)
			(end -0.7874 -0.4064)
			(stroke
				(width 0.1524)
				(type default)
			)
			(layer "F.SilkS")
		)
		(fp_line
			(start 0.7874 -0.4064)
			(end 0.7874 0.4064)
			(stroke
				(width 0.1524)
				(type default)
			)
			(layer "F.SilkS")
		)
		(fp_line
			(start 0.7874 0.4064)
			(end -0.7874 0.4064)
			(stroke
				(width 0.1524)
				(type default)
			)
			(layer "F.SilkS")
		)
		(fp_line
			(start -0.67945 -0.305054)
			(end -0.12065 -0.305054)
			(stroke
				(width 0.1)
				(type default)
			)
			(layer "F.Fab")
		)
		(fp_line
			(start -0.67945 0.3048)
			(end -0.67945 -0.305054)
			(stroke
				(width 0.1)
				(type default)
			)
			(layer "F.Fab")
		)
		(fp_line
			(start -0.12065 -0.305054)
			(end -0.12065 -0.2794)
			(stroke
				(width 0.1)
				(type default)
			)
			(layer "F.Fab")
		)
		(fp_line
			(start -0.12065 -0.2794)
			(end 0.12065 -0.2794)
			(stroke
				(width 0.1)
				(type default)
			)
			(layer "F.Fab")
		)
		(fp_line
			(start -0.12065 0.2794)
			(end -0.12065 0.3048)
			(stroke
				(width 0.1)
				(type default)
			)
			(layer "F.Fab")
		)
		(fp_line
			(start -0.12065 0.3048)
			(end -0.67945 0.3048)
			(stroke
				(width 0.1)
				(type default)
			)
			(layer "F.Fab")
		)
		(fp_line
			(start 0.120396 0.2794)
			(end -0.12065 0.2794)
			(stroke
				(width 0.1)
				(type default)
			)
			(layer "F.Fab")
		)
		(fp_line
			(start 0.120396 0.3048)
			(end 0.120396 0.2794)
			(stroke
				(width 0.1)
				(type default)
			)
			(layer "F.Fab")
		)
		(fp_line
			(start 0.12065 -0.3048)
			(end 0.67945 -0.3048)
			(stroke
				(width 0.1)
				(type default)
			)
			(layer "F.Fab")
		)
		(fp_line
			(start 0.12065 -0.2794)
			(end 0.12065 -0.3048)
			(stroke
				(width 0.1)
				(type default)
			)
			(layer "F.Fab")
		)
		(fp_line
			(start 0.67945 -0.3048)
			(end 0.67945 0.3048)
			(stroke
				(width 0.1)
				(type default)
			)
			(layer "F.Fab")
		)
		(fp_line
			(start 0.67945 0.3048)
			(end 0.120396 0.3048)
			(stroke
				(width 0.1)
				(type default)
			)
			(layer "F.Fab")
		)
		(pad "1" smd circle
			(at -0.40005 0)
			(size 0 0)
			(layers "F.Cu" "F.Mask" "F.Paste")
			(net "P3V3_E1S_0")
		)
		(pad "2" smd circle
			(at 0.40005 0)
			(size 0 0)
			(layers "F.Cu" "F.Mask" "F.Paste")
			(net "RST_SMB_E1S_0_N")
		)
	)
	(footprint ""
		(layer "F.Cu")
		(at 22.91842 -428.401988)
		(property "Reference" "R4622"
			(at 0 0 0)
			(layer "F.SilkS")
			(hide yes)
			(effects
				(font
					(size 1.27 1.27)
				)
			)
		)
		(property "Value" ""
			(at 0 0 0)
			(layer "F.Fab")
			(effects
				(font
					(size 1.27 1.27)
				)
			)
		)
		(duplicate_pad_numbers_are_jumpers no)
		(fp_line
			(start -0.7874 -0.4064)
			(end 0.7874 -0.4064)
			(stroke
				(width 0.1524)
				(type default)
			)
			(layer "F.SilkS")
		)
		(fp_line
			(start -0.7874 0.4064)
			(end -0.7874 -0.4064)
			(stroke
				(width 0.1524)
				(type default)
			)
			(layer "F.SilkS")
		)
		(fp_line
			(start 0.7874 -0.4064)
			(end 0.7874 0.4064)
			(stroke
				(width 0.1524)
				(type default)
			)
			(layer "F.SilkS")
		)
		(fp_line
			(start 0.7874 0.4064)
			(end -0.7874 0.4064)
			(stroke
				(width 0.1524)
				(type default)
			)
			(layer "F.SilkS")
		)
		(fp_line
			(start -0.67945 -0.305054)
			(end -0.12065 -0.305054)
			(stroke
				(width 0.1)
				(type default)
			)
			(layer "F.Fab")
		)
		(fp_line
			(start -0.67945 0.3048)
			(end -0.67945 -0.305054)
			(stroke
				(width 0.1)
				(type default)
			)
			(layer "F.Fab")
		)
		(fp_line
			(start -0.12065 -0.305054)
			(end -0.12065 -0.2794)
			(stroke
				(width 0.1)
				(type default)
			)
			(layer "F.Fab")
		)
		(fp_line
			(start -0.12065 -0.2794)
			(end 0.12065 -0.2794)
			(stroke
				(width 0.1)
				(type default)
			)
			(layer "F.Fab")
		)
		(fp_line
			(start -0.12065 0.2794)
			(end -0.12065 0.3048)
			(stroke
				(width 0.1)
				(type default)
			)
			(layer "F.Fab")
		)
		(fp_line
			(start -0.12065 0.3048)
			(end -0.67945 0.3048)
			(stroke
				(width 0.1)
				(type default)
			)
			(layer "F.Fab")
		)
		(fp_line
			(start 0.120396 0.2794)
			(end -0.12065 0.2794)
			(stroke
				(width 0.1)
				(type default)
			)
			(layer "F.Fab")
		)
		(fp_line
			(start 0.120396 0.3048)
			(end 0.120396 0.2794)
			(stroke
				(width 0.1)
				(type default)
			)
			(layer "F.Fab")
		)
		(fp_line
			(start 0.12065 -0.3048)
			(end 0.67945 -0.3048)
			(stroke
				(width 0.1)
				(type default)
			)
			(layer "F.Fab")
		)
		(fp_line
			(start 0.12065 -0.2794)
			(end 0.12065 -0.3048)
			(stroke
				(width 0.1)
				(type default)
			)
			(layer "F.Fab")
		)
		(fp_line
			(start 0.67945 -0.3048)
			(end 0.67945 0.3048)
			(stroke
				(width 0.1)
				(type default)
			)
			(layer "F.Fab")
		)
		(fp_line
			(start 0.67945 0.3048)
			(end 0.120396 0.3048)
			(stroke
				(width 0.1)
				(type default)
			)
			(layer "F.Fab")
		)
		(pad "1" smd circle
			(at -0.40005 0)
			(size 0 0)
			(layers "F.Cu" "F.Mask" "F.Paste")
			(net "RST_PERST_SWB_N")
		)
		(pad "2" smd circle
			(at 0.40005 0)
			(size 0 0)
			(layers "F.Cu" "F.Mask" "F.Paste")
			(net "GND")
		)
	)
	(footprint ""
		(layer "F.Cu")
		(at 303.9872 -23.6728)
		(property "Reference" "R4790"
			(at 0 0 0)
			(layer "F.SilkS")
			(hide yes)
			(effects
				(font
					(size 1.27 1.27)
				)
			)
		)
		(property "Value" ""
			(at 0 0 0)
			(layer "F.Fab")
			(effects
				(font
					(size 1.27 1.27)
				)
			)
		)
		(duplicate_pad_numbers_are_jumpers no)
		(fp_line
			(start -0.7874 -0.4064)
			(end 0.7874 -0.4064)
			(stroke
				(width 0.1524)
				(type default)
			)
			(layer "F.SilkS")
		)
		(fp_line
			(start -0.7874 0.4064)
			(end -0.7874 -0.4064)
			(stroke
				(width 0.1524)
				(type default)
			)
			(layer "F.SilkS")
		)
		(fp_line
			(start 0.7874 -0.4064)
			(end 0.7874 0.4064)
			(stroke
				(width 0.1524)
				(type default)
			)
			(layer "F.SilkS")
		)
		(fp_line
			(start 0.7874 0.4064)
			(end -0.7874 0.4064)
			(stroke
				(width 0.1524)
				(type default)
			)
			(layer "F.SilkS")
		)
		(fp_line
			(start -0.67945 -0.305054)
			(end -0.12065 -0.305054)
			(stroke
				(width 0.1)
				(type default)
			)
			(layer "F.Fab")
		)
		(fp_line
			(start -0.67945 0.3048)
			(end -0.67945 -0.305054)
			(stroke
				(width 0.1)
				(type default)
			)
			(layer "F.Fab")
		)
		(fp_line
			(start -0.12065 -0.305054)
			(end -0.12065 -0.2794)
			(stroke
				(width 0.1)
				(type default)
			)
			(layer "F.Fab")
		)
		(fp_line
			(start -0.12065 -0.2794)
			(end 0.12065 -0.2794)
			(stroke
				(width 0.1)
				(type default)
			)
			(layer "F.Fab")
		)
		(fp_line
			(start -0.12065 0.2794)
			(end -0.12065 0.3048)
			(stroke
				(width 0.1)
				(type default)
			)
			(layer "F.Fab")
		)
		(fp_line
			(start -0.12065 0.3048)
			(end -0.67945 0.3048)
			(stroke
				(width 0.1)
				(type default)
			)
			(layer "F.Fab")
		)
		(fp_line
			(start 0.120396 0.2794)
			(end -0.12065 0.2794)
			(stroke
				(width 0.1)
				(type default)
			)
			(layer "F.Fab")
		)
		(fp_line
			(start 0.120396 0.3048)
			(end 0.120396 0.2794)
			(stroke
				(width 0.1)
				(type default)
			)
			(layer "F.Fab")
		)
		(fp_line
			(start 0.12065 -0.3048)
			(end 0.67945 -0.3048)
			(stroke
				(width 0.1)
				(type default)
			)
			(layer "F.Fab")
		)
		(fp_line
			(start 0.12065 -0.2794)
			(end 0.12065 -0.3048)
			(stroke
				(width 0.1)
				(type default)
			)
			(layer "F.Fab")
		)
		(fp_line
			(start 0.67945 -0.3048)
			(end 0.67945 0.3048)
			(stroke
				(width 0.1)
				(type default)
			)
			(layer "F.Fab")
		)
		(fp_line
			(start 0.67945 0.3048)
			(end 0.120396 0.3048)
			(stroke
				(width 0.1)
				(type default)
			)
			(layer "F.Fab")
		)
		(pad "1" smd circle
			(at -0.40005 0)
			(size 0 0)
			(layers "F.Cu" "F.Mask" "F.Paste")
			(net "P12V_AUX")
		)
		(pad "2" smd circle
			(at 0.40005 0)
			(size 0 0)
			(layers "F.Cu" "F.Mask" "F.Paste")
			(net "PWRGD_DSW_PWROK_TRIGGER")
		)
	)
	(footprint ""
		(layer "F.Cu")
		(at 341.362792 -336.192368 90)
		(property "Reference" "PC293"
			(at 0 0 90)
			(layer "F.SilkS")
			(hide yes)
			(effects
				(font
					(size 1.27 1.27)
				)
			)
		)
		(property "Value" ""
			(at 0 0 90)
			(layer "F.Fab")
			(effects
				(font
					(size 1.27 1.27)
				)
			)
		)
		(duplicate_pad_numbers_are_jumpers no)
		(fp_line
			(start 0.7874 -0.4064)
			(end 0.7874 0.4064)
			(stroke
				(width 0.1524)
				(type default)
			)
			(layer "F.SilkS")
		)
		(fp_line
			(start -0.7874 -0.4064)
			(end 0.7874 -0.4064)
			(stroke
				(width 0.1524)
				(type default)
			)
			(layer "F.SilkS")
		)
		(fp_line
			(start 0.7874 0.4064)
			(end -0.7874 0.4064)
			(stroke
				(width 0.1524)
				(type default)
			)
			(layer "F.SilkS")
		)
		(fp_line
			(start -0.7874 0.4064)
			(end -0.7874 -0.4064)
			(stroke
				(width 0.1524)
				(type default)
			)
			(layer "F.SilkS")
		)
		(fp_line
			(start -0.12065 -0.305054)
			(end -0.12065 -0.2794)
			(stroke
				(width 0.1)
				(type default)
			)
			(layer "F.Fab")
		)
		(fp_line
			(start -0.67945 -0.305054)
			(end -0.12065 -0.305054)
			(stroke
				(width 0.1)
				(type default)
			)
			(layer "F.Fab")
		)
		(fp_line
			(start 0.67945 -0.3048)
			(end 0.67945 0.3048)
			(stroke
				(width 0.1)
				(type default)
			)
			(layer "F.Fab")
		)
		(fp_line
			(start 0.12065 -0.3048)
			(end 0.67945 -0.3048)
			(stroke
				(width 0.1)
				(type default)
			)
			(layer "F.Fab")
		)
		(fp_line
			(start 0.12065 -0.2794)
			(end 0.12065 -0.3048)
			(stroke
				(width 0.1)
				(type default)
			)
			(layer "F.Fab")
		)
		(fp_line
			(start -0.12065 -0.2794)
			(end 0.12065 -0.2794)
			(stroke
				(width 0.1)
				(type default)
			)
			(layer "F.Fab")
		)
		(fp_line
			(start 0.120396 0.2794)
			(end -0.12065 0.2794)
			(stroke
				(width 0.1)
				(type default)
			)
			(layer "F.Fab")
		)
		(fp_line
			(start -0.12065 0.2794)
			(end -0.12065 0.3048)
			(stroke
				(width 0.1)
				(type default)
			)
			(layer "F.Fab")
		)
		(fp_line
			(start 0.67945 0.3048)
			(end 0.120396 0.3048)
			(stroke
				(width 0.1)
				(type default)
			)
			(layer "F.Fab")
		)
		(fp_line
			(start 0.120396 0.3048)
			(end 0.120396 0.2794)
			(stroke
				(width 0.1)
				(type default)
			)
			(layer "F.Fab")
		)
		(fp_line
			(start -0.12065 0.3048)
			(end -0.67945 0.3048)
			(stroke
				(width 0.1)
				(type default)
			)
			(layer "F.Fab")
		)
		(fp_line
			(start -0.67945 0.3048)
			(end -0.67945 -0.305054)
			(stroke
				(width 0.1)
				(type default)
			)
			(layer "F.Fab")
		)
		(pad "1" smd circle
			(at -0.40005 0 90)
			(size 0 0)
			(layers "F.Cu" "F.Mask" "F.Paste")
			(net "PVCCIN_CPU0_VDD1")
		)
		(pad "2" smd circle
			(at 0.40005 0 90)
			(size 0 0)
			(layers "F.Cu" "F.Mask" "F.Paste")
			(net "GND")
		)
	)
	(footprint ""
		(layer "F.Cu")
		(at 309.55488 -49.494948 180)
		(property "Reference" "R1257"
			(at 0 0 180)
			(layer "F.SilkS")
			(hide yes)
			(effects
				(font
					(size 1.27 1.27)
				)
			)
		)
		(property "Value" ""
			(at 0 0 180)
			(layer "F.Fab")
			(effects
				(font
					(size 1.27 1.27)
				)
			)
		)
		(duplicate_pad_numbers_are_jumpers no)
		(fp_line
			(start 0.7874 0.4064)
			(end -0.7874 0.4064)
			(stroke
				(width 0.1524)
				(type default)
			)
			(layer "F.SilkS")
		)
		(fp_line
			(start 0.7874 -0.4064)
			(end 0.7874 0.4064)
			(stroke
				(width 0.1524)
				(type default)
			)
			(layer "F.SilkS")
		)
		(fp_line
			(start -0.7874 0.4064)
			(end -0.7874 -0.4064)
			(stroke
				(width 0.1524)
				(type default)
			)
			(layer "F.SilkS")
		)
		(fp_line
			(start -0.7874 -0.4064)
			(end 0.7874 -0.4064)
			(stroke
				(width 0.1524)
				(type default)
			)
			(layer "F.SilkS")
		)
		(fp_line
			(start 0.67945 0.3048)
			(end 0.120396 0.3048)
			(stroke
				(width 0.1)
				(type default)
			)
			(layer "F.Fab")
		)
		(fp_line
			(start 0.67945 -0.3048)
			(end 0.67945 0.3048)
			(stroke
				(width 0.1)
				(type default)
			)
			(layer "F.Fab")
		)
		(fp_line
			(start 0.12065 -0.2794)
			(end 0.12065 -0.3048)
			(stroke
				(width 0.1)
				(type default)
			)
			(layer "F.Fab")
		)
		(fp_line
			(start 0.12065 -0.3048)
			(end 0.67945 -0.3048)
			(stroke
				(width 0.1)
				(type default)
			)
			(layer "F.Fab")
		)
		(fp_line
			(start 0.120396 0.3048)
			(end 0.120396 0.2794)
			(stroke
				(width 0.1)
				(type default)
			)
			(layer "F.Fab")
		)
		(fp_line
			(start 0.120396 0.2794)
			(end -0.12065 0.2794)
			(stroke
				(width 0.1)
				(type default)
			)
			(layer "F.Fab")
		)
		(fp_line
			(start -0.12065 0.3048)
			(end -0.67945 0.3048)
			(stroke
				(width 0.1)
				(type default)
			)
			(layer "F.Fab")
		)
		(fp_line
			(start -0.12065 0.2794)
			(end -0.12065 0.3048)
			(stroke
				(width 0.1)
				(type default)
			)
			(layer "F.Fab")
		)
		(fp_line
			(start -0.12065 -0.2794)
			(end 0.12065 -0.2794)
			(stroke
				(width 0.1)
				(type default)
			)
			(layer "F.Fab")
		)
		(fp_line
			(start -0.12065 -0.305054)
			(end -0.12065 -0.2794)
			(stroke
				(width 0.1)
				(type default)
			)
			(layer "F.Fab")
		)
		(fp_line
			(start -0.67945 0.3048)
			(end -0.67945 -0.305054)
			(stroke
				(width 0.1)
				(type default)
			)
			(layer "F.Fab")
		)
		(fp_line
			(start -0.67945 -0.305054)
			(end -0.12065 -0.305054)
			(stroke
				(width 0.1)
				(type default)
			)
			(layer "F.Fab")
		)
		(pad "1" smd circle
			(at -0.40005 0 180)
			(size 0 0)
			(layers "F.Cu" "F.Mask" "F.Paste")
			(net "P3V3_AUX")
		)
		(pad "2" smd circle
			(at 0.40005 0 180)
			(size 0 0)
			(layers "F.Cu" "F.Mask" "F.Paste")
			(net "PU_PCH_VRALERT_N")
		)
	)
	(footprint ""
		(layer "F.Cu")
		(at 34.370518 -122.380502 -90)
		(property "Reference" "R2453"
			(at 0 0 270)
			(layer "F.SilkS")
			(hide yes)
			(effects
				(font
					(size 1.27 1.27)
				)
			)
		)
		(property "Value" ""
			(at 0 0 270)
			(layer "F.Fab")
			(effects
				(font
					(size 1.27 1.27)
				)
			)
		)
		(duplicate_pad_numbers_are_jumpers no)
		(fp_line
			(start -0.7874 0.4064)
			(end -0.7874 -0.4064)
			(stroke
				(width 0.1524)
				(type default)
			)
			(layer "F.SilkS")
		)
		(fp_line
			(start 0.7874 0.4064)
			(end -0.7874 0.4064)
			(stroke
				(width 0.1524)
				(type default)
			)
			(layer "F.SilkS")
		)
		(fp_line
			(start -0.7874 -0.4064)
			(end 0.7874 -0.4064)
			(stroke
				(width 0.1524)
				(type default)
			)
			(layer "F.SilkS")
		)
		(fp_line
			(start 0.7874 -0.4064)
			(end 0.7874 0.4064)
			(stroke
				(width 0.1524)
				(type default)
			)
			(layer "F.SilkS")
		)
		(fp_line
			(start -0.67945 0.3048)
			(end -0.67945 -0.305054)
			(stroke
				(width 0.1)
				(type default)
			)
			(layer "F.Fab")
		)
		(fp_line
			(start -0.12065 0.3048)
			(end -0.67945 0.3048)
			(stroke
				(width 0.1)
				(type default)
			)
			(layer "F.Fab")
		)
		(fp_line
			(start 0.120396 0.3048)
			(end 0.120396 0.2794)
			(stroke
				(width 0.1)
				(type default)
			)
			(layer "F.Fab")
		)
		(fp_line
			(start 0.67945 0.3048)
			(end 0.120396 0.3048)
			(stroke
				(width 0.1)
				(type default)
			)
			(layer "F.Fab")
		)
		(fp_line
			(start -0.12065 0.2794)
			(end -0.12065 0.3048)
			(stroke
				(width 0.1)
				(type default)
			)
			(layer "F.Fab")
		)
		(fp_line
			(start 0.120396 0.2794)
			(end -0.12065 0.2794)
			(stroke
				(width 0.1)
				(type default)
			)
			(layer "F.Fab")
		)
		(fp_line
			(start -0.12065 -0.2794)
			(end 0.12065 -0.2794)
			(stroke
				(width 0.1)
				(type default)
			)
			(layer "F.Fab")
		)
		(fp_line
			(start 0.12065 -0.2794)
			(end 0.12065 -0.3048)
			(stroke
				(width 0.1)
				(type default)
			)
			(layer "F.Fab")
		)
		(fp_line
			(start 0.12065 -0.3048)
			(end 0.67945 -0.3048)
			(stroke
				(width 0.1)
				(type default)
			)
			(layer "F.Fab")
		)
		(fp_line
			(start 0.67945 -0.3048)
			(end 0.67945 0.3048)
			(stroke
				(width 0.1)
				(type default)
			)
			(layer "F.Fab")
		)
		(fp_line
			(start -0.67945 -0.305054)
			(end -0.12065 -0.305054)
			(stroke
				(width 0.1)
				(type default)
			)
			(layer "F.Fab")
		)
		(fp_line
			(start -0.12065 -0.305054)
			(end -0.12065 -0.2794)
			(stroke
				(width 0.1)
				(type default)
			)
			(layer "F.Fab")
		)
		(pad "1" smd circle
			(at -0.40005 0 270)
			(size 0 0)
			(layers "F.Cu" "F.Mask" "F.Paste")
			(net "SMB_VR_3V3AUX_SCL_R")
		)
		(pad "2" smd circle
			(at 0.40005 0 270)
			(size 0 0)
			(layers "F.Cu" "F.Mask" "F.Paste")
			(net "SMB_VR_3V3AUX_SCL_R2")
		)
	)
	(footprint ""
		(layer "F.Cu")
		(at 21.44522 -335.905094 -90)
		(property "Reference" "R1837"
			(at 0 0 270)
			(layer "F.SilkS")
			(hide yes)
			(effects
				(font
					(size 1.27 1.27)
				)
			)
		)
		(property "Value" ""
			(at 0 0 270)
			(layer "F.Fab")
			(effects
				(font
					(size 1.27 1.27)
				)
			)
		)
		(duplicate_pad_numbers_are_jumpers no)
		(fp_line
			(start -4.0386 1.7526)
			(end -4.0386 -1.7526)
			(stroke
				(width 0.1524)
				(type default)
			)
			(layer "F.SilkS")
		)
		(fp_line
			(start 4.0386 1.7526)
			(end -4.0386 1.7526)
			(stroke
				(width 0.1524)
				(type default)
			)
			(layer "F.SilkS")
		)
		(fp_line
			(start -4.0386 -1.7526)
			(end 4.0386 -1.7526)
			(stroke
				(width 0.1524)
				(type default)
			)
			(layer "F.SilkS")
		)
		(fp_line
			(start 4.0386 -1.7526)
			(end 4.0386 1.7526)
			(stroke
				(width 0.1524)
				(type default)
			)
			(layer "F.SilkS")
		)
		(fp_line
			(start -4.0386 1.7526)
			(end -4.0386 -1.7526)
			(stroke
				(width 0.1)
				(type default)
			)
			(layer "F.Fab")
		)
		(fp_line
			(start 4.0386 1.7526)
			(end -4.0386 1.7526)
			(stroke
				(width 0.1)
				(type default)
			)
			(layer "F.Fab")
		)
		(fp_line
			(start -4.0386 -1.7526)
			(end 4.0386 -1.7526)
			(stroke
				(width 0.1)
				(type default)
			)
			(layer "F.Fab")
		)
		(fp_line
			(start 4.0386 -1.7526)
			(end 4.0386 1.7526)
			(stroke
				(width 0.1)
				(type default)
			)
			(layer "F.Fab")
		)
		(pad "1" smd circle
			(at -3.700018 0 180)
			(size 0 0)
			(layers "F.Cu" "F.Mask" "F.Paste")
			(net "P12V_AUX")
		)
		(pad "2" smd circle
			(at 3.700018 0)
			(size 0 0)
			(layers "F.Cu" "F.Mask" "F.Paste")
			(net "P12V_S3_AUX_CPU1_NVDIMM")
		)
		(pad "3" smd rect
			(at -2.70002 0)
			(size 0.4064 1.1176)
			(layers "F.Cu" "F.Mask" "F.Paste")
			(net "P12V_AUX_CPU1_DIMM_ISEN_P")
		)
		(pad "4" smd rect
			(at 2.70002 0)
			(size 0.4064 1.1176)
			(layers "F.Cu" "F.Mask" "F.Paste")
			(net "P12V_AUX_CPU1_DIMM_ISEN_N")
		)
	)
	(footprint ""
		(layer "F.Cu")
		(at 420.591488 -182.290974 180)
		(property "Reference" "PC1346"
			(at 0 0 180)
			(layer "F.SilkS")
			(hide yes)
			(effects
				(font
					(size 1.27 1.27)
				)
			)
		)
		(property "Value" ""
			(at 0 0 180)
			(layer "F.Fab")
			(effects
				(font
					(size 1.27 1.27)
				)
			)
		)
		(duplicate_pad_numbers_are_jumpers no)
		(fp_line
			(start 0.7874 0.4064)
			(end -0.7874 0.4064)
			(stroke
				(width 0.1524)
				(type default)
			)
			(layer "F.SilkS")
		)
		(fp_line
			(start 0.7874 -0.4064)
			(end 0.7874 0.4064)
			(stroke
				(width 0.1524)
				(type default)
			)
			(layer "F.SilkS")
		)
		(fp_line
			(start -0.7874 0.4064)
			(end -0.7874 -0.4064)
			(stroke
				(width 0.1524)
				(type default)
			)
			(layer "F.SilkS")
		)
		(fp_line
			(start -0.7874 -0.4064)
			(end 0.7874 -0.4064)
			(stroke
				(width 0.1524)
				(type default)
			)
			(layer "F.SilkS")
		)
		(fp_line
			(start 0.67945 0.3048)
			(end 0.120396 0.3048)
			(stroke
				(width 0.1)
				(type default)
			)
			(layer "F.Fab")
		)
		(fp_line
			(start 0.67945 -0.3048)
			(end 0.67945 0.3048)
			(stroke
				(width 0.1)
				(type default)
			)
			(layer "F.Fab")
		)
		(fp_line
			(start 0.12065 -0.2794)
			(end 0.12065 -0.3048)
			(stroke
				(width 0.1)
				(type default)
			)
			(layer "F.Fab")
		)
		(fp_line
			(start 0.12065 -0.3048)
			(end 0.67945 -0.3048)
			(stroke
				(width 0.1)
				(type default)
			)
			(layer "F.Fab")
		)
		(fp_line
			(start 0.120396 0.3048)
			(end 0.120396 0.2794)
			(stroke
				(width 0.1)
				(type default)
			)
			(layer "F.Fab")
		)
		(fp_line
			(start 0.120396 0.2794)
			(end -0.12065 0.2794)
			(stroke
				(width 0.1)
				(type default)
			)
			(layer "F.Fab")
		)
		(fp_line
			(start -0.12065 0.3048)
			(end -0.67945 0.3048)
			(stroke
				(width 0.1)
				(type default)
			)
			(layer "F.Fab")
		)
		(fp_line
			(start -0.12065 0.2794)
			(end -0.12065 0.3048)
			(stroke
				(width 0.1)
				(type default)
			)
			(layer "F.Fab")
		)
		(fp_line
			(start -0.12065 -0.2794)
			(end 0.12065 -0.2794)
			(stroke
				(width 0.1)
				(type default)
			)
			(layer "F.Fab")
		)
		(fp_line
			(start -0.12065 -0.305054)
			(end -0.12065 -0.2794)
			(stroke
				(width 0.1)
				(type default)
			)
			(layer "F.Fab")
		)
		(fp_line
			(start -0.67945 0.3048)
			(end -0.67945 -0.305054)
			(stroke
				(width 0.1)
				(type default)
			)
			(layer "F.Fab")
		)
		(fp_line
			(start -0.67945 -0.305054)
			(end -0.12065 -0.305054)
			(stroke
				(width 0.1)
				(type default)
			)
			(layer "F.Fab")
		)
		(pad "1" smd circle
			(at -0.40005 0 180)
			(size 0 0)
			(layers "F.Cu" "F.Mask" "F.Paste")
			(net "GND")
		)
		(pad "2" smd circle
			(at 0.40005 0 180)
			(size 0 0)
			(layers "F.Cu" "F.Mask" "F.Paste")
			(net "PVCCINFAON_CPU0_VREF")
		)
	)
	(footprint ""
		(layer "F.Cu")
		(at 36.930584 -108.555282)
		(property "Reference" "C2048"
			(at 0 0 0)
			(layer "F.SilkS")
			(hide yes)
			(effects
				(font
					(size 1.27 1.27)
				)
			)
		)
		(property "Value" ""
			(at 0 0 0)
			(layer "F.Fab")
			(effects
				(font
					(size 1.27 1.27)
				)
			)
		)
		(duplicate_pad_numbers_are_jumpers no)
		(fp_line
			(start -0.7874 -0.4064)
			(end 0.7874 -0.4064)
			(stroke
				(width 0.1524)
				(type default)
			)
			(layer "F.SilkS")
		)
		(fp_line
			(start -0.7874 0.4064)
			(end -0.7874 -0.4064)
			(stroke
				(width 0.1524)
				(type default)
			)
			(layer "F.SilkS")
		)
		(fp_line
			(start 0.7874 -0.4064)
			(end 0.7874 0.4064)
			(stroke
				(width 0.1524)
				(type default)
			)
			(layer "F.SilkS")
		)
		(fp_line
			(start 0.7874 0.4064)
			(end -0.7874 0.4064)
			(stroke
				(width 0.1524)
				(type default)
			)
			(layer "F.SilkS")
		)
		(fp_line
			(start -0.67945 -0.305054)
			(end -0.12065 -0.305054)
			(stroke
				(width 0.1)
				(type default)
			)
			(layer "F.Fab")
		)
		(fp_line
			(start -0.67945 0.3048)
			(end -0.67945 -0.305054)
			(stroke
				(width 0.1)
				(type default)
			)
			(layer "F.Fab")
		)
		(fp_line
			(start -0.12065 -0.305054)
			(end -0.12065 -0.2794)
			(stroke
				(width 0.1)
				(type default)
			)
			(layer "F.Fab")
		)
		(fp_line
			(start -0.12065 -0.2794)
			(end 0.12065 -0.2794)
			(stroke
				(width 0.1)
				(type default)
			)
			(layer "F.Fab")
		)
		(fp_line
			(start -0.12065 0.2794)
			(end -0.12065 0.3048)
			(stroke
				(width 0.1)
				(type default)
			)
			(layer "F.Fab")
		)
		(fp_line
			(start -0.12065 0.3048)
			(end -0.67945 0.3048)
			(stroke
				(width 0.1)
				(type default)
			)
			(layer "F.Fab")
		)
		(fp_line
			(start 0.120396 0.2794)
			(end -0.12065 0.2794)
			(stroke
				(width 0.1)
				(type default)
			)
			(layer "F.Fab")
		)
		(fp_line
			(start 0.120396 0.3048)
			(end 0.120396 0.2794)
			(stroke
				(width 0.1)
				(type default)
			)
			(layer "F.Fab")
		)
		(fp_line
			(start 0.12065 -0.3048)
			(end 0.67945 -0.3048)
			(stroke
				(width 0.1)
				(type default)
			)
			(layer "F.Fab")
		)
		(fp_line
			(start 0.12065 -0.2794)
			(end 0.12065 -0.3048)
			(stroke
				(width 0.1)
				(type default)
			)
			(layer "F.Fab")
		)
		(fp_line
			(start 0.67945 -0.3048)
			(end 0.67945 0.3048)
			(stroke
				(width 0.1)
				(type default)
			)
			(layer "F.Fab")
		)
		(fp_line
			(start 0.67945 0.3048)
			(end 0.120396 0.3048)
			(stroke
				(width 0.1)
				(type default)
			)
			(layer "F.Fab")
		)
		(pad "1" smd circle
			(at -0.40005 0)
			(size 0 0)
			(layers "F.Cu" "F.Mask" "F.Paste")
			(net "P3V3_ADC_TIC")
		)
		(pad "2" smd circle
			(at 0.40005 0)
			(size 0 0)
			(layers "F.Cu" "F.Mask" "F.Paste")
			(net "GND")
		)
	)
	(footprint ""
		(layer "F.Cu")
		(at 374.802146 -341.716106 -90)
		(property "Reference" "PC1343"
			(at 0 0 270)
			(layer "F.SilkS")
			(hide yes)
			(effects
				(font
					(size 1.27 1.27)
				)
			)
		)
		(property "Value" ""
			(at 0 0 270)
			(layer "F.Fab")
			(effects
				(font
					(size 1.27 1.27)
				)
			)
		)
		(duplicate_pad_numbers_are_jumpers no)
		(fp_line
			(start -0.7874 0.4064)
			(end -0.7874 -0.4064)
			(stroke
				(width 0.1524)
				(type default)
			)
			(layer "F.SilkS")
		)
		(fp_line
			(start 0.7874 0.4064)
			(end -0.7874 0.4064)
			(stroke
				(width 0.1524)
				(type default)
			)
			(layer "F.SilkS")
		)
		(fp_line
			(start -0.7874 -0.4064)
			(end 0.7874 -0.4064)
			(stroke
				(width 0.1524)
				(type default)
			)
			(layer "F.SilkS")
		)
		(fp_line
			(start 0.7874 -0.4064)
			(end 0.7874 0.4064)
			(stroke
				(width 0.1524)
				(type default)
			)
			(layer "F.SilkS")
		)
		(fp_line
			(start -0.67945 0.3048)
			(end -0.67945 -0.305054)
			(stroke
				(width 0.1)
				(type default)
			)
			(layer "F.Fab")
		)
		(fp_line
			(start -0.12065 0.3048)
			(end -0.67945 0.3048)
			(stroke
				(width 0.1)
				(type default)
			)
			(layer "F.Fab")
		)
		(fp_line
			(start 0.120396 0.3048)
			(end 0.120396 0.2794)
			(stroke
				(width 0.1)
				(type default)
			)
			(layer "F.Fab")
		)
		(fp_line
			(start 0.67945 0.3048)
			(end 0.120396 0.3048)
			(stroke
				(width 0.1)
				(type default)
			)
			(layer "F.Fab")
		)
		(fp_line
			(start -0.12065 0.2794)
			(end -0.12065 0.3048)
			(stroke
				(width 0.1)
				(type default)
			)
			(layer "F.Fab")
		)
		(fp_line
			(start 0.120396 0.2794)
			(end -0.12065 0.2794)
			(stroke
				(width 0.1)
				(type default)
			)
			(layer "F.Fab")
		)
		(fp_line
			(start -0.12065 -0.2794)
			(end 0.12065 -0.2794)
			(stroke
				(width 0.1)
				(type default)
			)
			(layer "F.Fab")
		)
		(fp_line
			(start 0.12065 -0.2794)
			(end 0.12065 -0.3048)
			(stroke
				(width 0.1)
				(type default)
			)
			(layer "F.Fab")
		)
		(fp_line
			(start 0.12065 -0.3048)
			(end 0.67945 -0.3048)
			(stroke
				(width 0.1)
				(type default)
			)
			(layer "F.Fab")
		)
		(fp_line
			(start 0.67945 -0.3048)
			(end 0.67945 0.3048)
			(stroke
				(width 0.1)
				(type default)
			)
			(layer "F.Fab")
		)
		(fp_line
			(start -0.67945 -0.305054)
			(end -0.12065 -0.305054)
			(stroke
				(width 0.1)
				(type default)
			)
			(layer "F.Fab")
		)
		(fp_line
			(start -0.12065 -0.305054)
			(end -0.12065 -0.2794)
			(stroke
				(width 0.1)
				(type default)
			)
			(layer "F.Fab")
		)
		(pad "1" smd circle
			(at -0.40005 0 270)
			(size 0 0)
			(layers "F.Cu" "F.Mask" "F.Paste")
			(net "GND")
		)
		(pad "2" smd circle
			(at 0.40005 0 270)
			(size 0 0)
			(layers "F.Cu" "F.Mask" "F.Paste")
			(net "PVCCIN_CPU0_VREF")
		)
	)
	(footprint ""
		(layer "F.Cu")
		(at 140.7922 -104.116378 -90)
		(property "Reference" "R342"
			(at 0 0 270)
			(layer "F.SilkS")
			(hide yes)
			(effects
				(font
					(size 1.27 1.27)
				)
			)
		)
		(property "Value" ""
			(at 0 0 270)
			(layer "F.Fab")
			(effects
				(font
					(size 1.27 1.27)
				)
			)
		)
		(duplicate_pad_numbers_are_jumpers no)
		(fp_line
			(start -0.7874 0.4064)
			(end -0.7874 -0.4064)
			(stroke
				(width 0.1524)
				(type default)
			)
			(layer "F.SilkS")
		)
		(fp_line
			(start 0.7874 0.4064)
			(end -0.7874 0.4064)
			(stroke
				(width 0.1524)
				(type default)
			)
			(layer "F.SilkS")
		)
		(fp_line
			(start -0.7874 -0.4064)
			(end 0.7874 -0.4064)
			(stroke
				(width 0.1524)
				(type default)
			)
			(layer "F.SilkS")
		)
		(fp_line
			(start 0.7874 -0.4064)
			(end 0.7874 0.4064)
			(stroke
				(width 0.1524)
				(type default)
			)
			(layer "F.SilkS")
		)
		(fp_line
			(start -0.67945 0.3048)
			(end -0.67945 -0.305054)
			(stroke
				(width 0.1)
				(type default)
			)
			(layer "F.Fab")
		)
		(fp_line
			(start -0.12065 0.3048)
			(end -0.67945 0.3048)
			(stroke
				(width 0.1)
				(type default)
			)
			(layer "F.Fab")
		)
		(fp_line
			(start 0.120396 0.3048)
			(end 0.120396 0.2794)
			(stroke
				(width 0.1)
				(type default)
			)
			(layer "F.Fab")
		)
		(fp_line
			(start 0.67945 0.3048)
			(end 0.120396 0.3048)
			(stroke
				(width 0.1)
				(type default)
			)
			(layer "F.Fab")
		)
		(fp_line
			(start -0.12065 0.2794)
			(end -0.12065 0.3048)
			(stroke
				(width 0.1)
				(type default)
			)
			(layer "F.Fab")
		)
		(fp_line
			(start 0.120396 0.2794)
			(end -0.12065 0.2794)
			(stroke
				(width 0.1)
				(type default)
			)
			(layer "F.Fab")
		)
		(fp_line
			(start -0.12065 -0.2794)
			(end 0.12065 -0.2794)
			(stroke
				(width 0.1)
				(type default)
			)
			(layer "F.Fab")
		)
		(fp_line
			(start 0.12065 -0.2794)
			(end 0.12065 -0.3048)
			(stroke
				(width 0.1)
				(type default)
			)
			(layer "F.Fab")
		)
		(fp_line
			(start 0.12065 -0.3048)
			(end 0.67945 -0.3048)
			(stroke
				(width 0.1)
				(type default)
			)
			(layer "F.Fab")
		)
		(fp_line
			(start 0.67945 -0.3048)
			(end 0.67945 0.3048)
			(stroke
				(width 0.1)
				(type default)
			)
			(layer "F.Fab")
		)
		(fp_line
			(start -0.67945 -0.305054)
			(end -0.12065 -0.305054)
			(stroke
				(width 0.1)
				(type default)
			)
			(layer "F.Fab")
		)
		(fp_line
			(start -0.12065 -0.305054)
			(end -0.12065 -0.2794)
			(stroke
				(width 0.1)
				(type default)
			)
			(layer "F.Fab")
		)
		(pad "1" smd circle
			(at -0.40005 0 270)
			(size 0 0)
			(layers "F.Cu" "F.Mask" "F.Paste")
			(net "H_CPU_ERR1_LVC1_R_N")
		)
		(pad "2" smd circle
			(at 0.40005 0 270)
			(size 0 0)
			(layers "F.Cu" "F.Mask" "F.Paste")
			(net "H_CPU_ERR1_LVC1_N")
		)
	)
	(footprint ""
		(layer "F.Cu")
		(at 285.242762 -14.36243)
		(property "Reference" "R4214"
			(at 0 0 0)
			(layer "F.SilkS")
			(hide yes)
			(effects
				(font
					(size 1.27 1.27)
				)
			)
		)
		(property "Value" ""
			(at 0 0 0)
			(layer "F.Fab")
			(effects
				(font
					(size 1.27 1.27)
				)
			)
		)
		(duplicate_pad_numbers_are_jumpers no)
		(fp_line
			(start -0.7874 -0.4064)
			(end 0.7874 -0.4064)
			(stroke
				(width 0.1524)
				(type default)
			)
			(layer "F.SilkS")
		)
		(fp_line
			(start -0.7874 0.4064)
			(end -0.7874 -0.4064)
			(stroke
				(width 0.1524)
				(type default)
			)
			(layer "F.SilkS")
		)
		(fp_line
			(start 0.7874 -0.4064)
			(end 0.7874 0.4064)
			(stroke
				(width 0.1524)
				(type default)
			)
			(layer "F.SilkS")
		)
		(fp_line
			(start 0.7874 0.4064)
			(end -0.7874 0.4064)
			(stroke
				(width 0.1524)
				(type default)
			)
			(layer "F.SilkS")
		)
		(fp_line
			(start -0.67945 -0.305054)
			(end -0.12065 -0.305054)
			(stroke
				(width 0.1)
				(type default)
			)
			(layer "F.Fab")
		)
		(fp_line
			(start -0.67945 0.3048)
			(end -0.67945 -0.305054)
			(stroke
				(width 0.1)
				(type default)
			)
			(layer "F.Fab")
		)
		(fp_line
			(start -0.12065 -0.305054)
			(end -0.12065 -0.2794)
			(stroke
				(width 0.1)
				(type default)
			)
			(layer "F.Fab")
		)
		(fp_line
			(start -0.12065 -0.2794)
			(end 0.12065 -0.2794)
			(stroke
				(width 0.1)
				(type default)
			)
			(layer "F.Fab")
		)
		(fp_line
			(start -0.12065 0.2794)
			(end -0.12065 0.3048)
			(stroke
				(width 0.1)
				(type default)
			)
			(layer "F.Fab")
		)
		(fp_line
			(start -0.12065 0.3048)
			(end -0.67945 0.3048)
			(stroke
				(width 0.1)
				(type default)
			)
			(layer "F.Fab")
		)
		(fp_line
			(start 0.120396 0.2794)
			(end -0.12065 0.2794)
			(stroke
				(width 0.1)
				(type default)
			)
			(layer "F.Fab")
		)
		(fp_line
			(start 0.120396 0.3048)
			(end 0.120396 0.2794)
			(stroke
				(width 0.1)
				(type default)
			)
			(layer "F.Fab")
		)
		(fp_line
			(start 0.12065 -0.3048)
			(end 0.67945 -0.3048)
			(stroke
				(width 0.1)
				(type default)
			)
			(layer "F.Fab")
		)
		(fp_line
			(start 0.12065 -0.2794)
			(end 0.12065 -0.3048)
			(stroke
				(width 0.1)
				(type default)
			)
			(layer "F.Fab")
		)
		(fp_line
			(start 0.67945 -0.3048)
			(end 0.67945 0.3048)
			(stroke
				(width 0.1)
				(type default)
			)
			(layer "F.Fab")
		)
		(fp_line
			(start 0.67945 0.3048)
			(end 0.120396 0.3048)
			(stroke
				(width 0.1)
				(type default)
			)
			(layer "F.Fab")
		)
		(pad "1" smd circle
			(at -0.40005 0)
			(size 0 0)
			(layers "F.Cu" "F.Mask" "F.Paste")
			(net "FM_THERMAL_ALERT_N")
		)
		(pad "2" smd circle
			(at 0.40005 0)
			(size 0 0)
			(layers "F.Cu" "F.Mask" "F.Paste")
			(net "FM_G751_1_ALERT_N")
		)
	)
	(footprint ""
		(layer "F.Cu")
		(at 153.825194 -402.371052 -90)
		(property "Reference" "C765"
			(at 0 0 270)
			(layer "F.SilkS")
			(hide yes)
			(effects
				(font
					(size 1.27 1.27)
				)
			)
		)
		(property "Value" ""
			(at 0 0 270)
			(layer "F.Fab")
			(effects
				(font
					(size 1.27 1.27)
				)
			)
		)
		(duplicate_pad_numbers_are_jumpers no)
		(fp_line
			(start -0.299974 0.150114)
			(end -0.299974 -0.150114)
			(stroke
				(width 0.1)
				(type default)
			)
			(layer "F.Fab")
		)
		(fp_line
			(start 0.299974 0.150114)
			(end -0.299974 0.150114)
			(stroke
				(width 0.1)
				(type default)
			)
			(layer "F.Fab")
		)
		(fp_line
			(start -0.299974 -0.150114)
			(end 0.299974 -0.150114)
			(stroke
				(width 0.1)
				(type default)
			)
			(layer "F.Fab")
		)
		(fp_line
			(start 0.299974 -0.150114)
			(end 0.299974 0.150114)
			(stroke
				(width 0.1)
				(type default)
			)
			(layer "F.Fab")
		)
		(pad "1" smd rect
			(at -0.2667 0 270)
			(size 0.3048 0.381)
			(layers "F.Cu" "F.Mask" "F.Paste")
			(net "P5E_CPU1_PE2_TX_C_DP<4>")
		)
		(pad "2" smd rect
			(at 0.2667 0 270)
			(size 0.3048 0.381)
			(layers "F.Cu" "F.Mask" "F.Paste")
			(net "P5E_CPU1_PE2_TX_DP<4>")
		)
	)
	(footprint ""
		(layer "F.Cu")
		(at 205.397608 -406.855422)
		(property "Reference" "PR3920"
			(at 0 0 0)
			(layer "F.SilkS")
			(hide yes)
			(effects
				(font
					(size 1.27 1.27)
				)
			)
		)
		(property "Value" ""
			(at 0 0 0)
			(layer "F.Fab")
			(effects
				(font
					(size 1.27 1.27)
				)
			)
		)
		(duplicate_pad_numbers_are_jumpers no)
		(fp_line
			(start -0.7874 -0.4064)
			(end 0.7874 -0.4064)
			(stroke
				(width 0.1524)
				(type default)
			)
			(layer "F.SilkS")
		)
		(fp_line
			(start -0.7874 0.4064)
			(end -0.7874 -0.4064)
			(stroke
				(width 0.1524)
				(type default)
			)
			(layer "F.SilkS")
		)
		(fp_line
			(start 0.7874 -0.4064)
			(end 0.7874 0.4064)
			(stroke
				(width 0.1524)
				(type default)
			)
			(layer "F.SilkS")
		)
		(fp_line
			(start 0.7874 0.4064)
			(end -0.7874 0.4064)
			(stroke
				(width 0.1524)
				(type default)
			)
			(layer "F.SilkS")
		)
		(fp_line
			(start -0.67945 -0.305054)
			(end -0.12065 -0.305054)
			(stroke
				(width 0.1)
				(type default)
			)
			(layer "F.Fab")
		)
		(fp_line
			(start -0.67945 0.3048)
			(end -0.67945 -0.305054)
			(stroke
				(width 0.1)
				(type default)
			)
			(layer "F.Fab")
		)
		(fp_line
			(start -0.12065 -0.305054)
			(end -0.12065 -0.2794)
			(stroke
				(width 0.1)
				(type default)
			)
			(layer "F.Fab")
		)
		(fp_line
			(start -0.12065 -0.2794)
			(end 0.12065 -0.2794)
			(stroke
				(width 0.1)
				(type default)
			)
			(layer "F.Fab")
		)
		(fp_line
			(start -0.12065 0.2794)
			(end -0.12065 0.3048)
			(stroke
				(width 0.1)
				(type default)
			)
			(layer "F.Fab")
		)
		(fp_line
			(start -0.12065 0.3048)
			(end -0.67945 0.3048)
			(stroke
				(width 0.1)
				(type default)
			)
			(layer "F.Fab")
		)
		(fp_line
			(start 0.120396 0.2794)
			(end -0.12065 0.2794)
			(stroke
				(width 0.1)
				(type default)
			)
			(layer "F.Fab")
		)
		(fp_line
			(start 0.120396 0.3048)
			(end 0.120396 0.2794)
			(stroke
				(width 0.1)
				(type default)
			)
			(layer "F.Fab")
		)
		(fp_line
			(start 0.12065 -0.3048)
			(end 0.67945 -0.3048)
			(stroke
				(width 0.1)
				(type default)
			)
			(layer "F.Fab")
		)
		(fp_line
			(start 0.12065 -0.2794)
			(end 0.12065 -0.3048)
			(stroke
				(width 0.1)
				(type default)
			)
			(layer "F.Fab")
		)
		(fp_line
			(start 0.67945 -0.3048)
			(end 0.67945 0.3048)
			(stroke
				(width 0.1)
				(type default)
			)
			(layer "F.Fab")
		)
		(fp_line
			(start 0.67945 0.3048)
			(end 0.120396 0.3048)
			(stroke
				(width 0.1)
				(type default)
			)
			(layer "F.Fab")
		)
		(pad "1" smd circle
			(at -0.40005 0)
			(size 0 0)
			(layers "F.Cu" "F.Mask" "F.Paste")
			(net "HSC_FLT_TYPE_1")
		)
		(pad "2" smd circle
			(at 0.40005 0)
			(size 0 0)
			(layers "F.Cu" "F.Mask" "F.Paste")
			(net "HSC_FLT_TYPE")
		)
	)
	(footprint ""
		(layer "F.Cu")
		(at 374.00484 -339.602572 90)
		(property "Reference" "PC249"
			(at 0 0 90)
			(layer "F.SilkS")
			(hide yes)
			(effects
				(font
					(size 1.27 1.27)
				)
			)
		)
		(property "Value" ""
			(at 0 0 90)
			(layer "F.Fab")
			(effects
				(font
					(size 1.27 1.27)
				)
			)
		)
		(duplicate_pad_numbers_are_jumpers no)
		(fp_line
			(start 0.7874 -0.4064)
			(end 0.7874 0.4064)
			(stroke
				(width 0.1524)
				(type default)
			)
			(layer "F.SilkS")
		)
		(fp_line
			(start -0.7874 -0.4064)
			(end 0.7874 -0.4064)
			(stroke
				(width 0.1524)
				(type default)
			)
			(layer "F.SilkS")
		)
		(fp_line
			(start 0.7874 0.4064)
			(end -0.7874 0.4064)
			(stroke
				(width 0.1524)
				(type default)
			)
			(layer "F.SilkS")
		)
		(fp_line
			(start -0.7874 0.4064)
			(end -0.7874 -0.4064)
			(stroke
				(width 0.1524)
				(type default)
			)
			(layer "F.SilkS")
		)
		(fp_line
			(start -0.12065 -0.305054)
			(end -0.12065 -0.2794)
			(stroke
				(width 0.1)
				(type default)
			)
			(layer "F.Fab")
		)
		(fp_line
			(start -0.67945 -0.305054)
			(end -0.12065 -0.305054)
			(stroke
				(width 0.1)
				(type default)
			)
			(layer "F.Fab")
		)
		(fp_line
			(start 0.67945 -0.3048)
			(end 0.67945 0.3048)
			(stroke
				(width 0.1)
				(type default)
			)
			(layer "F.Fab")
		)
		(fp_line
			(start 0.12065 -0.3048)
			(end 0.67945 -0.3048)
			(stroke
				(width 0.1)
				(type default)
			)
			(layer "F.Fab")
		)
		(fp_line
			(start 0.12065 -0.2794)
			(end 0.12065 -0.3048)
			(stroke
				(width 0.1)
				(type default)
			)
			(layer "F.Fab")
		)
		(fp_line
			(start -0.12065 -0.2794)
			(end 0.12065 -0.2794)
			(stroke
				(width 0.1)
				(type default)
			)
			(layer "F.Fab")
		)
		(fp_line
			(start 0.120396 0.2794)
			(end -0.12065 0.2794)
			(stroke
				(width 0.1)
				(type default)
			)
			(layer "F.Fab")
		)
		(fp_line
			(start -0.12065 0.2794)
			(end -0.12065 0.3048)
			(stroke
				(width 0.1)
				(type default)
			)
			(layer "F.Fab")
		)
		(fp_line
			(start 0.67945 0.3048)
			(end 0.120396 0.3048)
			(stroke
				(width 0.1)
				(type default)
			)
			(layer "F.Fab")
		)
		(fp_line
			(start 0.120396 0.3048)
			(end 0.120396 0.2794)
			(stroke
				(width 0.1)
				(type default)
			)
			(layer "F.Fab")
		)
		(fp_line
			(start -0.12065 0.3048)
			(end -0.67945 0.3048)
			(stroke
				(width 0.1)
				(type default)
			)
			(layer "F.Fab")
		)
		(fp_line
			(start -0.67945 0.3048)
			(end -0.67945 -0.305054)
			(stroke
				(width 0.1)
				(type default)
			)
			(layer "F.Fab")
		)
		(pad "1" smd circle
			(at -0.40005 0 90)
			(size 0 0)
			(layers "F.Cu" "F.Mask" "F.Paste")
			(net "PVCCIN_CPU0_VDD5")
		)
		(pad "2" smd circle
			(at 0.40005 0 90)
			(size 0 0)
			(layers "F.Cu" "F.Mask" "F.Paste")
			(net "GND")
		)
	)
	(footprint ""
		(layer "F.Cu")
		(at 66.162174 -16.37157 180)
		(property "Reference" "C1831"
			(at 0 0 180)
			(layer "F.SilkS")
			(hide yes)
			(effects
				(font
					(size 1.27 1.27)
				)
			)
		)
		(property "Value" ""
			(at 0 0 180)
			(layer "F.Fab")
			(effects
				(font
					(size 1.27 1.27)
				)
			)
		)
		(duplicate_pad_numbers_are_jumpers no)
		(fp_line
			(start 0.7874 0.4064)
			(end -0.7874 0.4064)
			(stroke
				(width 0.1524)
				(type default)
			)
			(layer "F.SilkS")
		)
		(fp_line
			(start 0.7874 -0.4064)
			(end 0.7874 0.4064)
			(stroke
				(width 0.1524)
				(type default)
			)
			(layer "F.SilkS")
		)
		(fp_line
			(start -0.7874 0.4064)
			(end -0.7874 -0.4064)
			(stroke
				(width 0.1524)
				(type default)
			)
			(layer "F.SilkS")
		)
		(fp_line
			(start -0.7874 -0.4064)
			(end 0.7874 -0.4064)
			(stroke
				(width 0.1524)
				(type default)
			)
			(layer "F.SilkS")
		)
		(fp_line
			(start 0.67945 0.3048)
			(end 0.120396 0.3048)
			(stroke
				(width 0.1)
				(type default)
			)
			(layer "F.Fab")
		)
		(fp_line
			(start 0.67945 -0.3048)
			(end 0.67945 0.3048)
			(stroke
				(width 0.1)
				(type default)
			)
			(layer "F.Fab")
		)
		(fp_line
			(start 0.12065 -0.2794)
			(end 0.12065 -0.3048)
			(stroke
				(width 0.1)
				(type default)
			)
			(layer "F.Fab")
		)
		(fp_line
			(start 0.12065 -0.3048)
			(end 0.67945 -0.3048)
			(stroke
				(width 0.1)
				(type default)
			)
			(layer "F.Fab")
		)
		(fp_line
			(start 0.120396 0.3048)
			(end 0.120396 0.2794)
			(stroke
				(width 0.1)
				(type default)
			)
			(layer "F.Fab")
		)
		(fp_line
			(start 0.120396 0.2794)
			(end -0.12065 0.2794)
			(stroke
				(width 0.1)
				(type default)
			)
			(layer "F.Fab")
		)
		(fp_line
			(start -0.12065 0.3048)
			(end -0.67945 0.3048)
			(stroke
				(width 0.1)
				(type default)
			)
			(layer "F.Fab")
		)
		(fp_line
			(start -0.12065 0.2794)
			(end -0.12065 0.3048)
			(stroke
				(width 0.1)
				(type default)
			)
			(layer "F.Fab")
		)
		(fp_line
			(start -0.12065 -0.2794)
			(end 0.12065 -0.2794)
			(stroke
				(width 0.1)
				(type default)
			)
			(layer "F.Fab")
		)
		(fp_line
			(start -0.12065 -0.305054)
			(end -0.12065 -0.2794)
			(stroke
				(width 0.1)
				(type default)
			)
			(layer "F.Fab")
		)
		(fp_line
			(start -0.67945 0.3048)
			(end -0.67945 -0.305054)
			(stroke
				(width 0.1)
				(type default)
			)
			(layer "F.Fab")
		)
		(fp_line
			(start -0.67945 -0.305054)
			(end -0.12065 -0.305054)
			(stroke
				(width 0.1)
				(type default)
			)
			(layer "F.Fab")
		)
		(pad "1" smd circle
			(at -0.40005 0 180)
			(size 0 0)
			(layers "F.Cu" "F.Mask" "F.Paste")
			(net "P12V_OCP_V3_2")
		)
		(pad "2" smd circle
			(at 0.40005 0 180)
			(size 0 0)
			(layers "F.Cu" "F.Mask" "F.Paste")
			(net "GND")
		)
	)
	(footprint ""
		(layer "F.Cu")
		(at 66.86296 -61.158628 90)
		(property "Reference" "PC1321"
			(at 0 0 90)
			(layer "F.SilkS")
			(hide yes)
			(effects
				(font
					(size 1.27 1.27)
				)
			)
		)
		(property "Value" ""
			(at 0 0 90)
			(layer "F.Fab")
			(effects
				(font
					(size 1.27 1.27)
				)
			)
		)
		(duplicate_pad_numbers_are_jumpers no)
		(fp_line
			(start 0.7874 -0.4064)
			(end 0.7874 0.4064)
			(stroke
				(width 0.1524)
				(type default)
			)
			(layer "F.SilkS")
		)
		(fp_line
			(start -0.7874 -0.4064)
			(end 0.7874 -0.4064)
			(stroke
				(width 0.1524)
				(type default)
			)
			(layer "F.SilkS")
		)
		(fp_line
			(start 0.7874 0.4064)
			(end -0.7874 0.4064)
			(stroke
				(width 0.1524)
				(type default)
			)
			(layer "F.SilkS")
		)
		(fp_line
			(start -0.7874 0.4064)
			(end -0.7874 -0.4064)
			(stroke
				(width 0.1524)
				(type default)
			)
			(layer "F.SilkS")
		)
		(fp_line
			(start -0.12065 -0.305054)
			(end -0.12065 -0.2794)
			(stroke
				(width 0.1)
				(type default)
			)
			(layer "F.Fab")
		)
		(fp_line
			(start -0.67945 -0.305054)
			(end -0.12065 -0.305054)
			(stroke
				(width 0.1)
				(type default)
			)
			(layer "F.Fab")
		)
		(fp_line
			(start 0.67945 -0.3048)
			(end 0.67945 0.3048)
			(stroke
				(width 0.1)
				(type default)
			)
			(layer "F.Fab")
		)
		(fp_line
			(start 0.12065 -0.3048)
			(end 0.67945 -0.3048)
			(stroke
				(width 0.1)
				(type default)
			)
			(layer "F.Fab")
		)
		(fp_line
			(start 0.12065 -0.2794)
			(end 0.12065 -0.3048)
			(stroke
				(width 0.1)
				(type default)
			)
			(layer "F.Fab")
		)
		(fp_line
			(start -0.12065 -0.2794)
			(end 0.12065 -0.2794)
			(stroke
				(width 0.1)
				(type default)
			)
			(layer "F.Fab")
		)
		(fp_line
			(start 0.120396 0.2794)
			(end -0.12065 0.2794)
			(stroke
				(width 0.1)
				(type default)
			)
			(layer "F.Fab")
		)
		(fp_line
			(start -0.12065 0.2794)
			(end -0.12065 0.3048)
			(stroke
				(width 0.1)
				(type default)
			)
			(layer "F.Fab")
		)
		(fp_line
			(start 0.67945 0.3048)
			(end 0.120396 0.3048)
			(stroke
				(width 0.1)
				(type default)
			)
			(layer "F.Fab")
		)
		(fp_line
			(start 0.120396 0.3048)
			(end 0.120396 0.2794)
			(stroke
				(width 0.1)
				(type default)
			)
			(layer "F.Fab")
		)
		(fp_line
			(start -0.12065 0.3048)
			(end -0.67945 0.3048)
			(stroke
				(width 0.1)
				(type default)
			)
			(layer "F.Fab")
		)
		(fp_line
			(start -0.67945 0.3048)
			(end -0.67945 -0.305054)
			(stroke
				(width 0.1)
				(type default)
			)
			(layer "F.Fab")
		)
		(pad "1" smd circle
			(at -0.40005 0 90)
			(size 0 0)
			(layers "F.Cu" "F.Mask" "F.Paste")
			(net "P3V3_OCP_DVDT_2")
		)
		(pad "2" smd circle
			(at 0.40005 0 90)
			(size 0 0)
			(layers "F.Cu" "F.Mask" "F.Paste")
			(net "GND")
		)
	)
	(footprint ""
		(layer "F.Cu")
		(at 166.196772 -129.036318 -90)
		(property "Reference" "Q37"
			(at 2.027428 -1.224788 0)
			(unlocked yes)
			(layer "F.SilkS")
			(effects
				(font
					(size 0.7874 0.5842)
					(thickness 0.1524)
				)
				(justify left)
			)
		)
		(property "Value" ""
			(at 0 0 270)
			(layer "F.Fab")
			(effects
				(font
					(size 1.27 1.27)
				)
			)
		)
		(duplicate_pad_numbers_are_jumpers no)
		(fp_line
			(start -1.332738 1.100074)
			(end -1.332738 -1.100074)
			(stroke
				(width 0.1524)
				(type default)
			)
			(layer "F.SilkS")
		)
		(fp_line
			(start 1.332738 1.100074)
			(end -1.332738 1.100074)
			(stroke
				(width 0.1524)
				(type default)
			)
			(layer "F.SilkS")
		)
		(fp_line
			(start 0 -0.541274)
			(end 0.4826 -1.100074)
			(stroke
				(width 0.1524)
				(type default)
			)
			(layer "F.SilkS")
		)
		(fp_line
			(start -1.332738 -1.100074)
			(end -0.4826 -1.100074)
			(stroke
				(width 0.1524)
				(type default)
			)
			(layer "F.SilkS")
		)
		(fp_line
			(start -0.4826 -1.100074)
			(end 0 -0.541274)
			(stroke
				(width 0.1524)
				(type default)
			)
			(layer "F.SilkS")
		)
		(fp_line
			(start 0.4826 -1.100074)
			(end 1.332738 -1.100074)
			(stroke
				(width 0.1524)
				(type default)
			)
			(layer "F.SilkS")
		)
		(fp_line
			(start 1.332738 -1.100074)
			(end 1.332738 1.100074)
			(stroke
				(width 0.1524)
				(type default)
			)
			(layer "F.SilkS")
		)
		(fp_poly
			(pts
				(xy -1.53416 -1.988312) (xy -1.323086 -1.232408) (xy -2.054606 -1.517142)
			)
			(stroke
				(width 0)
				(type default)
			)
			(fill yes)
			(layer "F.SilkS")
		)
		(fp_line
			(start -0.674878 1.100074)
			(end -0.674878 -1.100074)
			(stroke
				(width 0.1)
				(type default)
			)
			(layer "F.Fab")
		)
		(fp_line
			(start 0.674878 1.100074)
			(end -0.674878 1.100074)
			(stroke
				(width 0.1)
				(type default)
			)
			(layer "F.Fab")
		)
		(fp_line
			(start -0.674878 -1.100074)
			(end 0.674878 -1.100074)
			(stroke
				(width 0.1)
				(type default)
			)
			(layer "F.Fab")
		)
		(fp_line
			(start 0.674878 -1.100074)
			(end 0.674878 1.100074)
			(stroke
				(width 0.1)
				(type default)
			)
			(layer "F.Fab")
		)
		(fp_poly
			(pts
				(xy -2.2352 -0.298958) (xy -2.2352 -1.001014) (xy -1.533144 -0.649986)
			)
			(stroke
				(width 0)
				(type default)
			)
			(fill yes)
			(layer "F.Fab")
		)
		(pad "1" smd rect
			(at -0.94996 -0.649986)
			(size 0.4318 0.508)
			(layers "F.Cu" "F.Mask" "F.Paste")
			(net "GND")
		)
		(pad "2" smd rect
			(at -0.94996 0)
			(size 0.4318 0.508)
			(layers "F.Cu" "F.Mask" "F.Paste")
			(net "VR_P5V_EN")
		)
		(pad "3" smd rect
			(at -0.94996 0.649986)
			(size 0.4318 0.508)
			(layers "F.Cu" "F.Mask" "F.Paste")
			(net "VR_P5V_EN_D_R1")
		)
		(pad "4" smd rect
			(at 0.94996 0.649986)
			(size 0.4318 0.508)
			(layers "F.Cu" "F.Mask" "F.Paste")
			(net "GND")
		)
		(pad "5" smd rect
			(at 0.94996 0)
			(size 0.4318 0.508)
			(layers "F.Cu" "F.Mask" "F.Paste")
			(net "VR_P5V_EN_N")
		)
		(pad "6" smd rect
			(at 0.94996 -0.649986)
			(size 0.4318 0.508)
			(layers "F.Cu" "F.Mask" "F.Paste")
			(net "VR_P5V_EN_N")
		)
	)
	(footprint ""
		(layer "F.Cu")
		(at 157.02788 -116.296948)
		(property "Reference" "R3482"
			(at 0 0 0)
			(layer "F.SilkS")
			(hide yes)
			(effects
				(font
					(size 1.27 1.27)
				)
			)
		)
		(property "Value" ""
			(at 0 0 0)
			(layer "F.Fab")
			(effects
				(font
					(size 1.27 1.27)
				)
			)
		)
		(duplicate_pad_numbers_are_jumpers no)
		(fp_line
			(start -0.7874 -0.4064)
			(end 0.7874 -0.4064)
			(stroke
				(width 0.1524)
				(type default)
			)
			(layer "F.SilkS")
		)
		(fp_line
			(start -0.7874 0.4064)
			(end -0.7874 -0.4064)
			(stroke
				(width 0.1524)
				(type default)
			)
			(layer "F.SilkS")
		)
		(fp_line
			(start 0.7874 -0.4064)
			(end 0.7874 0.4064)
			(stroke
				(width 0.1524)
				(type default)
			)
			(layer "F.SilkS")
		)
		(fp_line
			(start 0.7874 0.4064)
			(end -0.7874 0.4064)
			(stroke
				(width 0.1524)
				(type default)
			)
			(layer "F.SilkS")
		)
		(fp_line
			(start -0.67945 -0.305054)
			(end -0.12065 -0.305054)
			(stroke
				(width 0.1)
				(type default)
			)
			(layer "F.Fab")
		)
		(fp_line
			(start -0.67945 0.3048)
			(end -0.67945 -0.305054)
			(stroke
				(width 0.1)
				(type default)
			)
			(layer "F.Fab")
		)
		(fp_line
			(start -0.12065 -0.305054)
			(end -0.12065 -0.2794)
			(stroke
				(width 0.1)
				(type default)
			)
			(layer "F.Fab")
		)
		(fp_line
			(start -0.12065 -0.2794)
			(end 0.12065 -0.2794)
			(stroke
				(width 0.1)
				(type default)
			)
			(layer "F.Fab")
		)
		(fp_line
			(start -0.12065 0.2794)
			(end -0.12065 0.3048)
			(stroke
				(width 0.1)
				(type default)
			)
			(layer "F.Fab")
		)
		(fp_line
			(start -0.12065 0.3048)
			(end -0.67945 0.3048)
			(stroke
				(width 0.1)
				(type default)
			)
			(layer "F.Fab")
		)
		(fp_line
			(start 0.120396 0.2794)
			(end -0.12065 0.2794)
			(stroke
				(width 0.1)
				(type default)
			)
			(layer "F.Fab")
		)
		(fp_line
			(start 0.120396 0.3048)
			(end 0.120396 0.2794)
			(stroke
				(width 0.1)
				(type default)
			)
			(layer "F.Fab")
		)
		(fp_line
			(start 0.12065 -0.3048)
			(end 0.67945 -0.3048)
			(stroke
				(width 0.1)
				(type default)
			)
			(layer "F.Fab")
		)
		(fp_line
			(start 0.12065 -0.2794)
			(end 0.12065 -0.3048)
			(stroke
				(width 0.1)
				(type default)
			)
			(layer "F.Fab")
		)
		(fp_line
			(start 0.67945 -0.3048)
			(end 0.67945 0.3048)
			(stroke
				(width 0.1)
				(type default)
			)
			(layer "F.Fab")
		)
		(fp_line
			(start 0.67945 0.3048)
			(end 0.120396 0.3048)
			(stroke
				(width 0.1)
				(type default)
			)
			(layer "F.Fab")
		)
		(pad "1" smd circle
			(at -0.40005 0)
			(size 0 0)
			(layers "F.Cu" "F.Mask" "F.Paste")
			(net "GPU_FPGA_BOOT_EN")
		)
		(pad "2" smd circle
			(at 0.40005 0)
			(size 0 0)
			(layers "F.Cu" "F.Mask" "F.Paste")
			(net "GPU_FPGA_BOOT_EN_R")
		)
	)
	(footprint ""
		(layer "F.Cu")
		(at 436.292244 -127.248158 -90)
		(property "Reference" "PR371"
			(at 0 0 270)
			(layer "F.SilkS")
			(hide yes)
			(effects
				(font
					(size 1.27 1.27)
				)
			)
		)
		(property "Value" ""
			(at 0 0 270)
			(layer "F.Fab")
			(effects
				(font
					(size 1.27 1.27)
				)
			)
		)
		(duplicate_pad_numbers_are_jumpers no)
		(fp_line
			(start -0.7874 0.4064)
			(end -0.7874 -0.4064)
			(stroke
				(width 0.1524)
				(type default)
			)
			(layer "F.SilkS")
		)
		(fp_line
			(start 0.7874 0.4064)
			(end -0.7874 0.4064)
			(stroke
				(width 0.1524)
				(type default)
			)
			(layer "F.SilkS")
		)
		(fp_line
			(start -0.7874 -0.4064)
			(end 0.7874 -0.4064)
			(stroke
				(width 0.1524)
				(type default)
			)
			(layer "F.SilkS")
		)
		(fp_line
			(start 0.7874 -0.4064)
			(end 0.7874 0.4064)
			(stroke
				(width 0.1524)
				(type default)
			)
			(layer "F.SilkS")
		)
		(fp_line
			(start -0.67945 0.3048)
			(end -0.67945 -0.305054)
			(stroke
				(width 0.1)
				(type default)
			)
			(layer "F.Fab")
		)
		(fp_line
			(start -0.12065 0.3048)
			(end -0.67945 0.3048)
			(stroke
				(width 0.1)
				(type default)
			)
			(layer "F.Fab")
		)
		(fp_line
			(start 0.120396 0.3048)
			(end 0.120396 0.2794)
			(stroke
				(width 0.1)
				(type default)
			)
			(layer "F.Fab")
		)
		(fp_line
			(start 0.67945 0.3048)
			(end 0.120396 0.3048)
			(stroke
				(width 0.1)
				(type default)
			)
			(layer "F.Fab")
		)
		(fp_line
			(start -0.12065 0.2794)
			(end -0.12065 0.3048)
			(stroke
				(width 0.1)
				(type default)
			)
			(layer "F.Fab")
		)
		(fp_line
			(start 0.120396 0.2794)
			(end -0.12065 0.2794)
			(stroke
				(width 0.1)
				(type default)
			)
			(layer "F.Fab")
		)
		(fp_line
			(start -0.12065 -0.2794)
			(end 0.12065 -0.2794)
			(stroke
				(width 0.1)
				(type default)
			)
			(layer "F.Fab")
		)
		(fp_line
			(start 0.12065 -0.2794)
			(end 0.12065 -0.3048)
			(stroke
				(width 0.1)
				(type default)
			)
			(layer "F.Fab")
		)
		(fp_line
			(start 0.12065 -0.3048)
			(end 0.67945 -0.3048)
			(stroke
				(width 0.1)
				(type default)
			)
			(layer "F.Fab")
		)
		(fp_line
			(start 0.67945 -0.3048)
			(end 0.67945 0.3048)
			(stroke
				(width 0.1)
				(type default)
			)
			(layer "F.Fab")
		)
		(fp_line
			(start -0.67945 -0.305054)
			(end -0.12065 -0.305054)
			(stroke
				(width 0.1)
				(type default)
			)
			(layer "F.Fab")
		)
		(fp_line
			(start -0.12065 -0.305054)
			(end -0.12065 -0.2794)
			(stroke
				(width 0.1)
				(type default)
			)
			(layer "F.Fab")
		)
		(pad "1" smd circle
			(at -0.40005 0 270)
			(size 0 0)
			(layers "F.Cu" "F.Mask" "F.Paste")
			(net "SH_PVCCD_HV_CPU0")
		)
		(pad "2" smd circle
			(at 0.40005 0 270)
			(size 0 0)
			(layers "F.Cu" "F.Mask" "F.Paste")
			(net "SH_PVCCD_HV_CPU0_R")
		)
	)
	(footprint ""
		(layer "F.Cu")
		(at 407.40584 -183.535828)
		(property "Reference" "PC199_P0_1"
			(at 0 0 0)
			(layer "F.SilkS")
			(hide yes)
			(effects
				(font
					(size 1.27 1.27)
				)
			)
		)
		(property "Value" ""
			(at 0 0 0)
			(layer "F.Fab")
			(effects
				(font
					(size 1.27 1.27)
				)
			)
		)
		(duplicate_pad_numbers_are_jumpers no)
		(fp_line
			(start -0.7874 -0.4064)
			(end 0.7874 -0.4064)
			(stroke
				(width 0.1524)
				(type default)
			)
			(layer "F.SilkS")
		)
		(fp_line
			(start -0.7874 0.4064)
			(end -0.7874 -0.4064)
			(stroke
				(width 0.1524)
				(type default)
			)
			(layer "F.SilkS")
		)
		(fp_line
			(start 0.7874 -0.4064)
			(end 0.7874 0.4064)
			(stroke
				(width 0.1524)
				(type default)
			)
			(layer "F.SilkS")
		)
		(fp_line
			(start 0.7874 0.4064)
			(end -0.7874 0.4064)
			(stroke
				(width 0.1524)
				(type default)
			)
			(layer "F.SilkS")
		)
		(fp_line
			(start -0.67945 -0.305054)
			(end -0.12065 -0.305054)
			(stroke
				(width 0.1)
				(type default)
			)
			(layer "F.Fab")
		)
		(fp_line
			(start -0.67945 0.3048)
			(end -0.67945 -0.305054)
			(stroke
				(width 0.1)
				(type default)
			)
			(layer "F.Fab")
		)
		(fp_line
			(start -0.12065 -0.305054)
			(end -0.12065 -0.2794)
			(stroke
				(width 0.1)
				(type default)
			)
			(layer "F.Fab")
		)
		(fp_line
			(start -0.12065 -0.2794)
			(end 0.12065 -0.2794)
			(stroke
				(width 0.1)
				(type default)
			)
			(layer "F.Fab")
		)
		(fp_line
			(start -0.12065 0.2794)
			(end -0.12065 0.3048)
			(stroke
				(width 0.1)
				(type default)
			)
			(layer "F.Fab")
		)
		(fp_line
			(start -0.12065 0.3048)
			(end -0.67945 0.3048)
			(stroke
				(width 0.1)
				(type default)
			)
			(layer "F.Fab")
		)
		(fp_line
			(start 0.120396 0.2794)
			(end -0.12065 0.2794)
			(stroke
				(width 0.1)
				(type default)
			)
			(layer "F.Fab")
		)
		(fp_line
			(start 0.120396 0.3048)
			(end 0.120396 0.2794)
			(stroke
				(width 0.1)
				(type default)
			)
			(layer "F.Fab")
		)
		(fp_line
			(start 0.12065 -0.3048)
			(end 0.67945 -0.3048)
			(stroke
				(width 0.1)
				(type default)
			)
			(layer "F.Fab")
		)
		(fp_line
			(start 0.12065 -0.2794)
			(end 0.12065 -0.3048)
			(stroke
				(width 0.1)
				(type default)
			)
			(layer "F.Fab")
		)
		(fp_line
			(start 0.67945 -0.3048)
			(end 0.67945 0.3048)
			(stroke
				(width 0.1)
				(type default)
			)
			(layer "F.Fab")
		)
		(fp_line
			(start 0.67945 0.3048)
			(end 0.120396 0.3048)
			(stroke
				(width 0.1)
				(type default)
			)
			(layer "F.Fab")
		)
		(pad "1" smd circle
			(at -0.40005 0)
			(size 0 0)
			(layers "F.Cu" "F.Mask" "F.Paste")
			(net "PVCCINFAON_CPU0")
		)
		(pad "2" smd circle
			(at 0.40005 0)
			(size 0 0)
			(layers "F.Cu" "F.Mask" "F.Paste")
			(net "GND")
		)
	)
	(footprint ""
		(layer "F.Cu")
		(at 217.47226 -47.90694 90)
		(property "Reference" "R4767"
			(at 0 0 90)
			(layer "F.SilkS")
			(hide yes)
			(effects
				(font
					(size 1.27 1.27)
				)
			)
		)
		(property "Value" ""
			(at 0 0 90)
			(layer "F.Fab")
			(effects
				(font
					(size 1.27 1.27)
				)
			)
		)
		(duplicate_pad_numbers_are_jumpers no)
		(fp_line
			(start 0.7874 -0.4064)
			(end 0.7874 0.4064)
			(stroke
				(width 0.1524)
				(type default)
			)
			(layer "F.SilkS")
		)
		(fp_line
			(start -0.7874 -0.4064)
			(end 0.7874 -0.4064)
			(stroke
				(width 0.1524)
				(type default)
			)
			(layer "F.SilkS")
		)
		(fp_line
			(start 0.7874 0.4064)
			(end -0.7874 0.4064)
			(stroke
				(width 0.1524)
				(type default)
			)
			(layer "F.SilkS")
		)
		(fp_line
			(start -0.7874 0.4064)
			(end -0.7874 -0.4064)
			(stroke
				(width 0.1524)
				(type default)
			)
			(layer "F.SilkS")
		)
		(fp_line
			(start -0.12065 -0.305054)
			(end -0.12065 -0.2794)
			(stroke
				(width 0.1)
				(type default)
			)
			(layer "F.Fab")
		)
		(fp_line
			(start -0.67945 -0.305054)
			(end -0.12065 -0.305054)
			(stroke
				(width 0.1)
				(type default)
			)
			(layer "F.Fab")
		)
		(fp_line
			(start 0.67945 -0.3048)
			(end 0.67945 0.3048)
			(stroke
				(width 0.1)
				(type default)
			)
			(layer "F.Fab")
		)
		(fp_line
			(start 0.12065 -0.3048)
			(end 0.67945 -0.3048)
			(stroke
				(width 0.1)
				(type default)
			)
			(layer "F.Fab")
		)
		(fp_line
			(start 0.12065 -0.2794)
			(end 0.12065 -0.3048)
			(stroke
				(width 0.1)
				(type default)
			)
			(layer "F.Fab")
		)
		(fp_line
			(start -0.12065 -0.2794)
			(end 0.12065 -0.2794)
			(stroke
				(width 0.1)
				(type default)
			)
			(layer "F.Fab")
		)
		(fp_line
			(start 0.120396 0.2794)
			(end -0.12065 0.2794)
			(stroke
				(width 0.1)
				(type default)
			)
			(layer "F.Fab")
		)
		(fp_line
			(start -0.12065 0.2794)
			(end -0.12065 0.3048)
			(stroke
				(width 0.1)
				(type default)
			)
			(layer "F.Fab")
		)
		(fp_line
			(start 0.67945 0.3048)
			(end 0.120396 0.3048)
			(stroke
				(width 0.1)
				(type default)
			)
			(layer "F.Fab")
		)
		(fp_line
			(start 0.120396 0.3048)
			(end 0.120396 0.2794)
			(stroke
				(width 0.1)
				(type default)
			)
			(layer "F.Fab")
		)
		(fp_line
			(start -0.12065 0.3048)
			(end -0.67945 0.3048)
			(stroke
				(width 0.1)
				(type default)
			)
			(layer "F.Fab")
		)
		(fp_line
			(start -0.67945 0.3048)
			(end -0.67945 -0.305054)
			(stroke
				(width 0.1)
				(type default)
			)
			(layer "F.Fab")
		)
		(pad "1" smd circle
			(at -0.40005 0 90)
			(size 0 0)
			(layers "F.Cu" "F.Mask" "F.Paste")
			(net "HP_E1S_0_P3V3_PWRGD")
		)
		(pad "2" smd circle
			(at 0.40005 0 90)
			(size 0 0)
			(layers "F.Cu" "F.Mask" "F.Paste")
			(net "HP_E1S_0_P3V3_PWRGD_PLD")
		)
	)
	(footprint ""
		(layer "F.Cu")
		(at 369.554252 -366.764062 -90)
		(property "Reference" "PC1254"
			(at 0 0 270)
			(layer "F.SilkS")
			(hide yes)
			(effects
				(font
					(size 1.27 1.27)
				)
			)
		)
		(property "Value" ""
			(at 0 0 270)
			(layer "F.Fab")
			(effects
				(font
					(size 1.27 1.27)
				)
			)
		)
		(duplicate_pad_numbers_are_jumpers no)
		(fp_line
			(start -0.7874 0.4064)
			(end -0.7874 -0.4064)
			(stroke
				(width 0.1524)
				(type default)
			)
			(layer "F.SilkS")
		)
		(fp_line
			(start 0.7874 0.4064)
			(end -0.7874 0.4064)
			(stroke
				(width 0.1524)
				(type default)
			)
			(layer "F.SilkS")
		)
		(fp_line
			(start -0.7874 -0.4064)
			(end 0.7874 -0.4064)
			(stroke
				(width 0.1524)
				(type default)
			)
			(layer "F.SilkS")
		)
		(fp_line
			(start 0.7874 -0.4064)
			(end 0.7874 0.4064)
			(stroke
				(width 0.1524)
				(type default)
			)
			(layer "F.SilkS")
		)
		(fp_line
			(start -0.67945 0.3048)
			(end -0.67945 -0.305054)
			(stroke
				(width 0.1)
				(type default)
			)
			(layer "F.Fab")
		)
		(fp_line
			(start -0.12065 0.3048)
			(end -0.67945 0.3048)
			(stroke
				(width 0.1)
				(type default)
			)
			(layer "F.Fab")
		)
		(fp_line
			(start 0.120396 0.3048)
			(end 0.120396 0.2794)
			(stroke
				(width 0.1)
				(type default)
			)
			(layer "F.Fab")
		)
		(fp_line
			(start 0.67945 0.3048)
			(end 0.120396 0.3048)
			(stroke
				(width 0.1)
				(type default)
			)
			(layer "F.Fab")
		)
		(fp_line
			(start -0.12065 0.2794)
			(end -0.12065 0.3048)
			(stroke
				(width 0.1)
				(type default)
			)
			(layer "F.Fab")
		)
		(fp_line
			(start 0.120396 0.2794)
			(end -0.12065 0.2794)
			(stroke
				(width 0.1)
				(type default)
			)
			(layer "F.Fab")
		)
		(fp_line
			(start -0.12065 -0.2794)
			(end 0.12065 -0.2794)
			(stroke
				(width 0.1)
				(type default)
			)
			(layer "F.Fab")
		)
		(fp_line
			(start 0.12065 -0.2794)
			(end 0.12065 -0.3048)
			(stroke
				(width 0.1)
				(type default)
			)
			(layer "F.Fab")
		)
		(fp_line
			(start 0.12065 -0.3048)
			(end 0.67945 -0.3048)
			(stroke
				(width 0.1)
				(type default)
			)
			(layer "F.Fab")
		)
		(fp_line
			(start 0.67945 -0.3048)
			(end 0.67945 0.3048)
			(stroke
				(width 0.1)
				(type default)
			)
			(layer "F.Fab")
		)
		(fp_line
			(start -0.67945 -0.305054)
			(end -0.12065 -0.305054)
			(stroke
				(width 0.1)
				(type default)
			)
			(layer "F.Fab")
		)
		(fp_line
			(start -0.12065 -0.305054)
			(end -0.12065 -0.2794)
			(stroke
				(width 0.1)
				(type default)
			)
			(layer "F.Fab")
		)
		(pad "1" smd circle
			(at -0.40005 0 270)
			(size 0 0)
			(layers "F.Cu" "F.Mask" "F.Paste")
			(net "PVPP_HBM_CPU0")
		)
		(pad "2" smd circle
			(at 0.40005 0 270)
			(size 0 0)
			(layers "F.Cu" "F.Mask" "F.Paste")
			(net "GND")
		)
	)
	(footprint ""
		(layer "F.Cu")
		(at 395.10081 -408.517344 -90)
		(property "Reference" "C885"
			(at 0 0 270)
			(layer "F.SilkS")
			(hide yes)
			(effects
				(font
					(size 1.27 1.27)
				)
			)
		)
		(property "Value" ""
			(at 0 0 270)
			(layer "F.Fab")
			(effects
				(font
					(size 1.27 1.27)
				)
			)
		)
		(duplicate_pad_numbers_are_jumpers no)
		(fp_line
			(start -0.299974 0.150114)
			(end -0.299974 -0.150114)
			(stroke
				(width 0.1)
				(type default)
			)
			(layer "F.Fab")
		)
		(fp_line
			(start 0.299974 0.150114)
			(end -0.299974 0.150114)
			(stroke
				(width 0.1)
				(type default)
			)
			(layer "F.Fab")
		)
		(fp_line
			(start -0.299974 -0.150114)
			(end 0.299974 -0.150114)
			(stroke
				(width 0.1)
				(type default)
			)
			(layer "F.Fab")
		)
		(fp_line
			(start 0.299974 -0.150114)
			(end 0.299974 0.150114)
			(stroke
				(width 0.1)
				(type default)
			)
			(layer "F.Fab")
		)
		(pad "1" smd rect
			(at -0.2667 0 270)
			(size 0.3048 0.381)
			(layers "F.Cu" "F.Mask" "F.Paste")
			(net "P5E_CPU0_PE3_TX_C_DP<8>")
		)
		(pad "2" smd rect
			(at 0.2667 0 270)
			(size 0.3048 0.381)
			(layers "F.Cu" "F.Mask" "F.Paste")
			(net "P5E_CPU0_PE3_TX_DP<8>")
		)
	)
	(footprint ""
		(layer "F.Cu")
		(at 243.084858 -50.138838 90)
		(property "Reference" "C1279"
			(at 0 0 90)
			(layer "F.SilkS")
			(hide yes)
			(effects
				(font
					(size 1.27 1.27)
				)
			)
		)
		(property "Value" ""
			(at 0 0 90)
			(layer "F.Fab")
			(effects
				(font
					(size 1.27 1.27)
				)
			)
		)
		(duplicate_pad_numbers_are_jumpers no)
		(fp_line
			(start 0.7874 -0.4064)
			(end 0.7874 0.4064)
			(stroke
				(width 0.1524)
				(type default)
			)
			(layer "F.SilkS")
		)
		(fp_line
			(start -0.7874 -0.4064)
			(end 0.7874 -0.4064)
			(stroke
				(width 0.1524)
				(type default)
			)
			(layer "F.SilkS")
		)
		(fp_line
			(start 0.7874 0.4064)
			(end -0.7874 0.4064)
			(stroke
				(width 0.1524)
				(type default)
			)
			(layer "F.SilkS")
		)
		(fp_line
			(start -0.7874 0.4064)
			(end -0.7874 -0.4064)
			(stroke
				(width 0.1524)
				(type default)
			)
			(layer "F.SilkS")
		)
		(fp_line
			(start -0.12065 -0.305054)
			(end -0.12065 -0.2794)
			(stroke
				(width 0.1)
				(type default)
			)
			(layer "F.Fab")
		)
		(fp_line
			(start -0.67945 -0.305054)
			(end -0.12065 -0.305054)
			(stroke
				(width 0.1)
				(type default)
			)
			(layer "F.Fab")
		)
		(fp_line
			(start 0.67945 -0.3048)
			(end 0.67945 0.3048)
			(stroke
				(width 0.1)
				(type default)
			)
			(layer "F.Fab")
		)
		(fp_line
			(start 0.12065 -0.3048)
			(end 0.67945 -0.3048)
			(stroke
				(width 0.1)
				(type default)
			)
			(layer "F.Fab")
		)
		(fp_line
			(start 0.12065 -0.2794)
			(end 0.12065 -0.3048)
			(stroke
				(width 0.1)
				(type default)
			)
			(layer "F.Fab")
		)
		(fp_line
			(start -0.12065 -0.2794)
			(end 0.12065 -0.2794)
			(stroke
				(width 0.1)
				(type default)
			)
			(layer "F.Fab")
		)
		(fp_line
			(start 0.120396 0.2794)
			(end -0.12065 0.2794)
			(stroke
				(width 0.1)
				(type default)
			)
			(layer "F.Fab")
		)
		(fp_line
			(start -0.12065 0.2794)
			(end -0.12065 0.3048)
			(stroke
				(width 0.1)
				(type default)
			)
			(layer "F.Fab")
		)
		(fp_line
			(start 0.67945 0.3048)
			(end 0.120396 0.3048)
			(stroke
				(width 0.1)
				(type default)
			)
			(layer "F.Fab")
		)
		(fp_line
			(start 0.120396 0.3048)
			(end 0.120396 0.2794)
			(stroke
				(width 0.1)
				(type default)
			)
			(layer "F.Fab")
		)
		(fp_line
			(start -0.12065 0.3048)
			(end -0.67945 0.3048)
			(stroke
				(width 0.1)
				(type default)
			)
			(layer "F.Fab")
		)
		(fp_line
			(start -0.67945 0.3048)
			(end -0.67945 -0.305054)
			(stroke
				(width 0.1)
				(type default)
			)
			(layer "F.Fab")
		)
		(pad "1" smd circle
			(at -0.40005 0 90)
			(size 0 0)
			(layers "F.Cu" "F.Mask" "F.Paste")
			(net "P12V_E1S_0")
		)
		(pad "2" smd circle
			(at 0.40005 0 90)
			(size 0 0)
			(layers "F.Cu" "F.Mask" "F.Paste")
			(net "GND")
		)
	)
	(footprint ""
		(layer "F.Cu")
		(at 32.761428 -100.602034 180)
		(property "Reference" "C1344"
			(at 0 0 180)
			(layer "F.SilkS")
			(hide yes)
			(effects
				(font
					(size 1.27 1.27)
				)
			)
		)
		(property "Value" ""
			(at 0 0 180)
			(layer "F.Fab")
			(effects
				(font
					(size 1.27 1.27)
				)
			)
		)
		(duplicate_pad_numbers_are_jumpers no)
		(fp_line
			(start 0.7874 0.4064)
			(end -0.7874 0.4064)
			(stroke
				(width 0.1524)
				(type default)
			)
			(layer "F.SilkS")
		)
		(fp_line
			(start 0.7874 -0.4064)
			(end 0.7874 0.4064)
			(stroke
				(width 0.1524)
				(type default)
			)
			(layer "F.SilkS")
		)
		(fp_line
			(start -0.7874 0.4064)
			(end -0.7874 -0.4064)
			(stroke
				(width 0.1524)
				(type default)
			)
			(layer "F.SilkS")
		)
		(fp_line
			(start -0.7874 -0.4064)
			(end 0.7874 -0.4064)
			(stroke
				(width 0.1524)
				(type default)
			)
			(layer "F.SilkS")
		)
		(fp_line
			(start 0.67945 0.3048)
			(end 0.120396 0.3048)
			(stroke
				(width 0.1)
				(type default)
			)
			(layer "F.Fab")
		)
		(fp_line
			(start 0.67945 -0.3048)
			(end 0.67945 0.3048)
			(stroke
				(width 0.1)
				(type default)
			)
			(layer "F.Fab")
		)
		(fp_line
			(start 0.12065 -0.2794)
			(end 0.12065 -0.3048)
			(stroke
				(width 0.1)
				(type default)
			)
			(layer "F.Fab")
		)
		(fp_line
			(start 0.12065 -0.3048)
			(end 0.67945 -0.3048)
			(stroke
				(width 0.1)
				(type default)
			)
			(layer "F.Fab")
		)
		(fp_line
			(start 0.120396 0.3048)
			(end 0.120396 0.2794)
			(stroke
				(width 0.1)
				(type default)
			)
			(layer "F.Fab")
		)
		(fp_line
			(start 0.120396 0.2794)
			(end -0.12065 0.2794)
			(stroke
				(width 0.1)
				(type default)
			)
			(layer "F.Fab")
		)
		(fp_line
			(start -0.12065 0.3048)
			(end -0.67945 0.3048)
			(stroke
				(width 0.1)
				(type default)
			)
			(layer "F.Fab")
		)
		(fp_line
			(start -0.12065 0.2794)
			(end -0.12065 0.3048)
			(stroke
				(width 0.1)
				(type default)
			)
			(layer "F.Fab")
		)
		(fp_line
			(start -0.12065 -0.2794)
			(end 0.12065 -0.2794)
			(stroke
				(width 0.1)
				(type default)
			)
			(layer "F.Fab")
		)
		(fp_line
			(start -0.12065 -0.305054)
			(end -0.12065 -0.2794)
			(stroke
				(width 0.1)
				(type default)
			)
			(layer "F.Fab")
		)
		(fp_line
			(start -0.67945 0.3048)
			(end -0.67945 -0.305054)
			(stroke
				(width 0.1)
				(type default)
			)
			(layer "F.Fab")
		)
		(fp_line
			(start -0.67945 -0.305054)
			(end -0.12065 -0.305054)
			(stroke
				(width 0.1)
				(type default)
			)
			(layer "F.Fab")
		)
		(pad "1" smd circle
			(at -0.40005 0 180)
			(size 0 0)
			(layers "F.Cu" "F.Mask" "F.Paste")
			(net "P12V_AUX_ADC_MAM")
		)
		(pad "2" smd circle
			(at 0.40005 0 180)
			(size 0 0)
			(layers "F.Cu" "F.Mask" "F.Paste")
			(net "GND")
		)
	)
	(footprint ""
		(layer "F.Cu")
		(at 107.28833 -238.162592 -90)
		(property "Reference" "C304"
			(at 0 0 270)
			(layer "F.SilkS")
			(hide yes)
			(effects
				(font
					(size 1.27 1.27)
				)
			)
		)
		(property "Value" ""
			(at 0 0 270)
			(layer "F.Fab")
			(effects
				(font
					(size 1.27 1.27)
				)
			)
		)
		(duplicate_pad_numbers_are_jumpers no)
		(fp_line
			(start -0.7874 0.4064)
			(end -0.7874 -0.4064)
			(stroke
				(width 0.1524)
				(type default)
			)
			(layer "F.SilkS")
		)
		(fp_line
			(start 0.7874 0.4064)
			(end -0.7874 0.4064)
			(stroke
				(width 0.1524)
				(type default)
			)
			(layer "F.SilkS")
		)
		(fp_line
			(start -0.7874 -0.4064)
			(end 0.7874 -0.4064)
			(stroke
				(width 0.1524)
				(type default)
			)
			(layer "F.SilkS")
		)
		(fp_line
			(start 0.7874 -0.4064)
			(end 0.7874 0.4064)
			(stroke
				(width 0.1524)
				(type default)
			)
			(layer "F.SilkS")
		)
		(fp_line
			(start -0.67945 0.3048)
			(end -0.67945 -0.305054)
			(stroke
				(width 0.1)
				(type default)
			)
			(layer "F.Fab")
		)
		(fp_line
			(start -0.12065 0.3048)
			(end -0.67945 0.3048)
			(stroke
				(width 0.1)
				(type default)
			)
			(layer "F.Fab")
		)
		(fp_line
			(start 0.120396 0.3048)
			(end 0.120396 0.2794)
			(stroke
				(width 0.1)
				(type default)
			)
			(layer "F.Fab")
		)
		(fp_line
			(start 0.67945 0.3048)
			(end 0.120396 0.3048)
			(stroke
				(width 0.1)
				(type default)
			)
			(layer "F.Fab")
		)
		(fp_line
			(start -0.12065 0.2794)
			(end -0.12065 0.3048)
			(stroke
				(width 0.1)
				(type default)
			)
			(layer "F.Fab")
		)
		(fp_line
			(start 0.120396 0.2794)
			(end -0.12065 0.2794)
			(stroke
				(width 0.1)
				(type default)
			)
			(layer "F.Fab")
		)
		(fp_line
			(start -0.12065 -0.2794)
			(end 0.12065 -0.2794)
			(stroke
				(width 0.1)
				(type default)
			)
			(layer "F.Fab")
		)
		(fp_line
			(start 0.12065 -0.2794)
			(end 0.12065 -0.3048)
			(stroke
				(width 0.1)
				(type default)
			)
			(layer "F.Fab")
		)
		(fp_line
			(start 0.12065 -0.3048)
			(end 0.67945 -0.3048)
			(stroke
				(width 0.1)
				(type default)
			)
			(layer "F.Fab")
		)
		(fp_line
			(start 0.67945 -0.3048)
			(end 0.67945 0.3048)
			(stroke
				(width 0.1)
				(type default)
			)
			(layer "F.Fab")
		)
		(fp_line
			(start -0.67945 -0.305054)
			(end -0.12065 -0.305054)
			(stroke
				(width 0.1)
				(type default)
			)
			(layer "F.Fab")
		)
		(fp_line
			(start -0.12065 -0.305054)
			(end -0.12065 -0.2794)
			(stroke
				(width 0.1)
				(type default)
			)
			(layer "F.Fab")
		)
		(pad "1" smd circle
			(at -0.40005 0 270)
			(size 0 0)
			(layers "F.Cu" "F.Mask" "F.Paste")
			(net "PVCCIN_CPU1")
		)
		(pad "2" smd circle
			(at 0.40005 0 270)
			(size 0 0)
			(layers "F.Cu" "F.Mask" "F.Paste")
			(net "GND")
		)
	)
	(footprint ""
		(layer "F.Cu")
		(at 20.785582 -428.024036 90)
		(property "Reference" "R3440"
			(at 0 0 90)
			(layer "F.SilkS")
			(hide yes)
			(effects
				(font
					(size 1.27 1.27)
				)
			)
		)
		(property "Value" ""
			(at 0 0 90)
			(layer "F.Fab")
			(effects
				(font
					(size 1.27 1.27)
				)
			)
		)
		(duplicate_pad_numbers_are_jumpers no)
		(fp_line
			(start 0.7874 -0.4064)
			(end 0.7874 0.4064)
			(stroke
				(width 0.1524)
				(type default)
			)
			(layer "F.SilkS")
		)
		(fp_line
			(start -0.7874 -0.4064)
			(end 0.7874 -0.4064)
			(stroke
				(width 0.1524)
				(type default)
			)
			(layer "F.SilkS")
		)
		(fp_line
			(start 0.7874 0.4064)
			(end -0.7874 0.4064)
			(stroke
				(width 0.1524)
				(type default)
			)
			(layer "F.SilkS")
		)
		(fp_line
			(start -0.7874 0.4064)
			(end -0.7874 -0.4064)
			(stroke
				(width 0.1524)
				(type default)
			)
			(layer "F.SilkS")
		)
		(fp_line
			(start -0.12065 -0.305054)
			(end -0.12065 -0.2794)
			(stroke
				(width 0.1)
				(type default)
			)
			(layer "F.Fab")
		)
		(fp_line
			(start -0.67945 -0.305054)
			(end -0.12065 -0.305054)
			(stroke
				(width 0.1)
				(type default)
			)
			(layer "F.Fab")
		)
		(fp_line
			(start 0.67945 -0.3048)
			(end 0.67945 0.3048)
			(stroke
				(width 0.1)
				(type default)
			)
			(layer "F.Fab")
		)
		(fp_line
			(start 0.12065 -0.3048)
			(end 0.67945 -0.3048)
			(stroke
				(width 0.1)
				(type default)
			)
			(layer "F.Fab")
		)
		(fp_line
			(start 0.12065 -0.2794)
			(end 0.12065 -0.3048)
			(stroke
				(width 0.1)
				(type default)
			)
			(layer "F.Fab")
		)
		(fp_line
			(start -0.12065 -0.2794)
			(end 0.12065 -0.2794)
			(stroke
				(width 0.1)
				(type default)
			)
			(layer "F.Fab")
		)
		(fp_line
			(start 0.120396 0.2794)
			(end -0.12065 0.2794)
			(stroke
				(width 0.1)
				(type default)
			)
			(layer "F.Fab")
		)
		(fp_line
			(start -0.12065 0.2794)
			(end -0.12065 0.3048)
			(stroke
				(width 0.1)
				(type default)
			)
			(layer "F.Fab")
		)
		(fp_line
			(start 0.67945 0.3048)
			(end 0.120396 0.3048)
			(stroke
				(width 0.1)
				(type default)
			)
			(layer "F.Fab")
		)
		(fp_line
			(start 0.120396 0.3048)
			(end 0.120396 0.2794)
			(stroke
				(width 0.1)
				(type default)
			)
			(layer "F.Fab")
		)
		(fp_line
			(start -0.12065 0.3048)
			(end -0.67945 0.3048)
			(stroke
				(width 0.1)
				(type default)
			)
			(layer "F.Fab")
		)
		(fp_line
			(start -0.67945 0.3048)
			(end -0.67945 -0.305054)
			(stroke
				(width 0.1)
				(type default)
			)
			(layer "F.Fab")
		)
		(pad "1" smd circle
			(at -0.40005 0 90)
			(size 0 0)
			(layers "F.Cu" "F.Mask" "F.Paste")
			(net "GPU_BASE_ID0")
		)
		(pad "2" smd circle
			(at 0.40005 0 90)
			(size 0 0)
			(layers "F.Cu" "F.Mask" "F.Paste")
			(net "GND")
		)
	)
	(footprint ""
		(layer "F.Cu")
		(at 347.00718 -338.180172 -90)
		(property "Reference" "PC301"
			(at 0 0 270)
			(layer "F.SilkS")
			(hide yes)
			(effects
				(font
					(size 1.27 1.27)
				)
			)
		)
		(property "Value" ""
			(at 0 0 270)
			(layer "F.Fab")
			(effects
				(font
					(size 1.27 1.27)
				)
			)
		)
		(duplicate_pad_numbers_are_jumpers no)
		(fp_line
			(start -0.7874 0.4064)
			(end -0.7874 -0.4064)
			(stroke
				(width 0.1524)
				(type default)
			)
			(layer "F.SilkS")
		)
		(fp_line
			(start 0.7874 0.4064)
			(end -0.7874 0.4064)
			(stroke
				(width 0.1524)
				(type default)
			)
			(layer "F.SilkS")
		)
		(fp_line
			(start -0.7874 -0.4064)
			(end 0.7874 -0.4064)
			(stroke
				(width 0.1524)
				(type default)
			)
			(layer "F.SilkS")
		)
		(fp_line
			(start 0.7874 -0.4064)
			(end 0.7874 0.4064)
			(stroke
				(width 0.1524)
				(type default)
			)
			(layer "F.SilkS")
		)
		(fp_line
			(start -0.67945 0.3048)
			(end -0.67945 -0.305054)
			(stroke
				(width 0.1)
				(type default)
			)
			(layer "F.Fab")
		)
		(fp_line
			(start -0.12065 0.3048)
			(end -0.67945 0.3048)
			(stroke
				(width 0.1)
				(type default)
			)
			(layer "F.Fab")
		)
		(fp_line
			(start 0.120396 0.3048)
			(end 0.120396 0.2794)
			(stroke
				(width 0.1)
				(type default)
			)
			(layer "F.Fab")
		)
		(fp_line
			(start 0.67945 0.3048)
			(end 0.120396 0.3048)
			(stroke
				(width 0.1)
				(type default)
			)
			(layer "F.Fab")
		)
		(fp_line
			(start -0.12065 0.2794)
			(end -0.12065 0.3048)
			(stroke
				(width 0.1)
				(type default)
			)
			(layer "F.Fab")
		)
		(fp_line
			(start 0.120396 0.2794)
			(end -0.12065 0.2794)
			(stroke
				(width 0.1)
				(type default)
			)
			(layer "F.Fab")
		)
		(fp_line
			(start -0.12065 -0.2794)
			(end 0.12065 -0.2794)
			(stroke
				(width 0.1)
				(type default)
			)
			(layer "F.Fab")
		)
		(fp_line
			(start 0.12065 -0.2794)
			(end 0.12065 -0.3048)
			(stroke
				(width 0.1)
				(type default)
			)
			(layer "F.Fab")
		)
		(fp_line
			(start 0.12065 -0.3048)
			(end 0.67945 -0.3048)
			(stroke
				(width 0.1)
				(type default)
			)
			(layer "F.Fab")
		)
		(fp_line
			(start 0.67945 -0.3048)
			(end 0.67945 0.3048)
			(stroke
				(width 0.1)
				(type default)
			)
			(layer "F.Fab")
		)
		(fp_line
			(start -0.67945 -0.305054)
			(end -0.12065 -0.305054)
			(stroke
				(width 0.1)
				(type default)
			)
			(layer "F.Fab")
		)
		(fp_line
			(start -0.12065 -0.305054)
			(end -0.12065 -0.2794)
			(stroke
				(width 0.1)
				(type default)
			)
			(layer "F.Fab")
		)
		(pad "1" smd circle
			(at -0.40005 0 270)
			(size 0 0)
			(layers "F.Cu" "F.Mask" "F.Paste")
			(net "SW_PVCCIN_CPU0_BOOT1_R")
		)
		(pad "2" smd circle
			(at 0.40005 0 270)
			(size 0 0)
			(layers "F.Cu" "F.Mask" "F.Paste")
			(net "SW_PVCCIN_CPU0_BOOTR1")
		)
	)
	(footprint ""
		(layer "F.Cu")
		(at 189.80023 -35.017456 180)
		(property "Reference" "R1854"
			(at 0 0 180)
			(layer "F.SilkS")
			(hide yes)
			(effects
				(font
					(size 1.27 1.27)
				)
			)
		)
		(property "Value" ""
			(at 0 0 180)
			(layer "F.Fab")
			(effects
				(font
					(size 1.27 1.27)
				)
			)
		)
		(duplicate_pad_numbers_are_jumpers no)
		(fp_line
			(start 0.7874 0.4064)
			(end -0.7874 0.4064)
			(stroke
				(width 0.1524)
				(type default)
			)
			(layer "F.SilkS")
		)
		(fp_line
			(start 0.7874 -0.4064)
			(end 0.7874 0.4064)
			(stroke
				(width 0.1524)
				(type default)
			)
			(layer "F.SilkS")
		)
		(fp_line
			(start -0.7874 0.4064)
			(end -0.7874 -0.4064)
			(stroke
				(width 0.1524)
				(type default)
			)
			(layer "F.SilkS")
		)
		(fp_line
			(start -0.7874 -0.4064)
			(end 0.7874 -0.4064)
			(stroke
				(width 0.1524)
				(type default)
			)
			(layer "F.SilkS")
		)
		(fp_line
			(start 0.67945 0.3048)
			(end 0.120396 0.3048)
			(stroke
				(width 0.1)
				(type default)
			)
			(layer "F.Fab")
		)
		(fp_line
			(start 0.67945 -0.3048)
			(end 0.67945 0.3048)
			(stroke
				(width 0.1)
				(type default)
			)
			(layer "F.Fab")
		)
		(fp_line
			(start 0.12065 -0.2794)
			(end 0.12065 -0.3048)
			(stroke
				(width 0.1)
				(type default)
			)
			(layer "F.Fab")
		)
		(fp_line
			(start 0.12065 -0.3048)
			(end 0.67945 -0.3048)
			(stroke
				(width 0.1)
				(type default)
			)
			(layer "F.Fab")
		)
		(fp_line
			(start 0.120396 0.3048)
			(end 0.120396 0.2794)
			(stroke
				(width 0.1)
				(type default)
			)
			(layer "F.Fab")
		)
		(fp_line
			(start 0.120396 0.2794)
			(end -0.12065 0.2794)
			(stroke
				(width 0.1)
				(type default)
			)
			(layer "F.Fab")
		)
		(fp_line
			(start -0.12065 0.3048)
			(end -0.67945 0.3048)
			(stroke
				(width 0.1)
				(type default)
			)
			(layer "F.Fab")
		)
		(fp_line
			(start -0.12065 0.2794)
			(end -0.12065 0.3048)
			(stroke
				(width 0.1)
				(type default)
			)
			(layer "F.Fab")
		)
		(fp_line
			(start -0.12065 -0.2794)
			(end 0.12065 -0.2794)
			(stroke
				(width 0.1)
				(type default)
			)
			(layer "F.Fab")
		)
		(fp_line
			(start -0.12065 -0.305054)
			(end -0.12065 -0.2794)
			(stroke
				(width 0.1)
				(type default)
			)
			(layer "F.Fab")
		)
		(fp_line
			(start -0.67945 0.3048)
			(end -0.67945 -0.305054)
			(stroke
				(width 0.1)
				(type default)
			)
			(layer "F.Fab")
		)
		(fp_line
			(start -0.67945 -0.305054)
			(end -0.12065 -0.305054)
			(stroke
				(width 0.1)
				(type default)
			)
			(layer "F.Fab")
		)
		(pad "1" smd circle
			(at -0.40005 0 180)
			(size 0 0)
			(layers "F.Cu" "F.Mask" "F.Paste")
			(net "P3V3_AUX")
		)
		(pad "2" smd circle
			(at 0.40005 0 180)
			(size 0 0)
			(layers "F.Cu" "F.Mask" "F.Paste")
			(net "FM_SCM_PRSNT1_N")
		)
	)
	(footprint ""
		(layer "F.Cu")
		(at 194.853306 -399.743422 180)
		(property "Reference" "PC2347"
			(at 0 0 180)
			(layer "F.SilkS")
			(hide yes)
			(effects
				(font
					(size 1.27 1.27)
				)
			)
		)
		(property "Value" ""
			(at 0 0 180)
			(layer "F.Fab")
			(effects
				(font
					(size 1.27 1.27)
				)
			)
		)
		(duplicate_pad_numbers_are_jumpers no)
		(fp_line
			(start 0.7874 0.4064)
			(end -0.7874 0.4064)
			(stroke
				(width 0.1524)
				(type default)
			)
			(layer "F.SilkS")
		)
		(fp_line
			(start 0.7874 -0.4064)
			(end 0.7874 0.4064)
			(stroke
				(width 0.1524)
				(type default)
			)
			(layer "F.SilkS")
		)
		(fp_line
			(start -0.7874 0.4064)
			(end -0.7874 -0.4064)
			(stroke
				(width 0.1524)
				(type default)
			)
			(layer "F.SilkS")
		)
		(fp_line
			(start -0.7874 -0.4064)
			(end 0.7874 -0.4064)
			(stroke
				(width 0.1524)
				(type default)
			)
			(layer "F.SilkS")
		)
		(fp_line
			(start 0.67945 0.3048)
			(end 0.120396 0.3048)
			(stroke
				(width 0.1)
				(type default)
			)
			(layer "F.Fab")
		)
		(fp_line
			(start 0.67945 -0.3048)
			(end 0.67945 0.3048)
			(stroke
				(width 0.1)
				(type default)
			)
			(layer "F.Fab")
		)
		(fp_line
			(start 0.12065 -0.2794)
			(end 0.12065 -0.3048)
			(stroke
				(width 0.1)
				(type default)
			)
			(layer "F.Fab")
		)
		(fp_line
			(start 0.12065 -0.3048)
			(end 0.67945 -0.3048)
			(stroke
				(width 0.1)
				(type default)
			)
			(layer "F.Fab")
		)
		(fp_line
			(start 0.120396 0.3048)
			(end 0.120396 0.2794)
			(stroke
				(width 0.1)
				(type default)
			)
			(layer "F.Fab")
		)
		(fp_line
			(start 0.120396 0.2794)
			(end -0.12065 0.2794)
			(stroke
				(width 0.1)
				(type default)
			)
			(layer "F.Fab")
		)
		(fp_line
			(start -0.12065 0.3048)
			(end -0.67945 0.3048)
			(stroke
				(width 0.1)
				(type default)
			)
			(layer "F.Fab")
		)
		(fp_line
			(start -0.12065 0.2794)
			(end -0.12065 0.3048)
			(stroke
				(width 0.1)
				(type default)
			)
			(layer "F.Fab")
		)
		(fp_line
			(start -0.12065 -0.2794)
			(end 0.12065 -0.2794)
			(stroke
				(width 0.1)
				(type default)
			)
			(layer "F.Fab")
		)
		(fp_line
			(start -0.12065 -0.305054)
			(end -0.12065 -0.2794)
			(stroke
				(width 0.1)
				(type default)
			)
			(layer "F.Fab")
		)
		(fp_line
			(start -0.67945 0.3048)
			(end -0.67945 -0.305054)
			(stroke
				(width 0.1)
				(type default)
			)
			(layer "F.Fab")
		)
		(fp_line
			(start -0.67945 -0.305054)
			(end -0.12065 -0.305054)
			(stroke
				(width 0.1)
				(type default)
			)
			(layer "F.Fab")
		)
		(pad "1" smd circle
			(at -0.40005 0 180)
			(size 0 0)
			(layers "F.Cu" "F.Mask" "F.Paste")
			(net "HSC_OCREF")
		)
		(pad "2" smd circle
			(at 0.40005 0 180)
			(size 0 0)
			(layers "F.Cu" "F.Mask" "F.Paste")
			(net "AGND_HSC")
		)
	)
	(footprint ""
		(layer "F.Cu")
		(at 129.46888 -100.167948 90)
		(property "Reference" "R205"
			(at 0 0 90)
			(layer "F.SilkS")
			(hide yes)
			(effects
				(font
					(size 1.27 1.27)
				)
			)
		)
		(property "Value" ""
			(at 0 0 90)
			(layer "F.Fab")
			(effects
				(font
					(size 1.27 1.27)
				)
			)
		)
		(duplicate_pad_numbers_are_jumpers no)
		(fp_line
			(start 0.7874 -0.4064)
			(end 0.7874 0.4064)
			(stroke
				(width 0.1524)
				(type default)
			)
			(layer "F.SilkS")
		)
		(fp_line
			(start -0.7874 -0.4064)
			(end 0.7874 -0.4064)
			(stroke
				(width 0.1524)
				(type default)
			)
			(layer "F.SilkS")
		)
		(fp_line
			(start 0.7874 0.4064)
			(end -0.7874 0.4064)
			(stroke
				(width 0.1524)
				(type default)
			)
			(layer "F.SilkS")
		)
		(fp_line
			(start -0.7874 0.4064)
			(end -0.7874 -0.4064)
			(stroke
				(width 0.1524)
				(type default)
			)
			(layer "F.SilkS")
		)
		(fp_line
			(start -0.12065 -0.305054)
			(end -0.12065 -0.2794)
			(stroke
				(width 0.1)
				(type default)
			)
			(layer "F.Fab")
		)
		(fp_line
			(start -0.67945 -0.305054)
			(end -0.12065 -0.305054)
			(stroke
				(width 0.1)
				(type default)
			)
			(layer "F.Fab")
		)
		(fp_line
			(start 0.67945 -0.3048)
			(end 0.67945 0.3048)
			(stroke
				(width 0.1)
				(type default)
			)
			(layer "F.Fab")
		)
		(fp_line
			(start 0.12065 -0.3048)
			(end 0.67945 -0.3048)
			(stroke
				(width 0.1)
				(type default)
			)
			(layer "F.Fab")
		)
		(fp_line
			(start 0.12065 -0.2794)
			(end 0.12065 -0.3048)
			(stroke
				(width 0.1)
				(type default)
			)
			(layer "F.Fab")
		)
		(fp_line
			(start -0.12065 -0.2794)
			(end 0.12065 -0.2794)
			(stroke
				(width 0.1)
				(type default)
			)
			(layer "F.Fab")
		)
		(fp_line
			(start 0.120396 0.2794)
			(end -0.12065 0.2794)
			(stroke
				(width 0.1)
				(type default)
			)
			(layer "F.Fab")
		)
		(fp_line
			(start -0.12065 0.2794)
			(end -0.12065 0.3048)
			(stroke
				(width 0.1)
				(type default)
			)
			(layer "F.Fab")
		)
		(fp_line
			(start 0.67945 0.3048)
			(end 0.120396 0.3048)
			(stroke
				(width 0.1)
				(type default)
			)
			(layer "F.Fab")
		)
		(fp_line
			(start 0.120396 0.3048)
			(end 0.120396 0.2794)
			(stroke
				(width 0.1)
				(type default)
			)
			(layer "F.Fab")
		)
		(fp_line
			(start -0.12065 0.3048)
			(end -0.67945 0.3048)
			(stroke
				(width 0.1)
				(type default)
			)
			(layer "F.Fab")
		)
		(fp_line
			(start -0.67945 0.3048)
			(end -0.67945 -0.305054)
			(stroke
				(width 0.1)
				(type default)
			)
			(layer "F.Fab")
		)
		(pad "1" smd circle
			(at -0.40005 0 90)
			(size 0 0)
			(layers "F.Cu" "F.Mask" "F.Paste")
			(net "H_CPU0_MEMTRIP_LVC1_R_N")
		)
		(pad "2" smd circle
			(at 0.40005 0 90)
			(size 0 0)
			(layers "F.Cu" "F.Mask" "F.Paste")
			(net "H_CPU0_MEMTRIP_OUT_VT_R_N")
		)
	)
	(footprint ""
		(layer "F.Cu")
		(at 274.72894 -96.329754 180)
		(property "Reference" "R722"
			(at 0 0 180)
			(layer "F.SilkS")
			(hide yes)
			(effects
				(font
					(size 1.27 1.27)
				)
			)
		)
		(property "Value" ""
			(at 0 0 180)
			(layer "F.Fab")
			(effects
				(font
					(size 1.27 1.27)
				)
			)
		)
		(duplicate_pad_numbers_are_jumpers no)
		(fp_line
			(start 0.7874 0.4064)
			(end -0.7874 0.4064)
			(stroke
				(width 0.1524)
				(type default)
			)
			(layer "F.SilkS")
		)
		(fp_line
			(start 0.7874 -0.4064)
			(end 0.7874 0.4064)
			(stroke
				(width 0.1524)
				(type default)
			)
			(layer "F.SilkS")
		)
		(fp_line
			(start -0.7874 0.4064)
			(end -0.7874 -0.4064)
			(stroke
				(width 0.1524)
				(type default)
			)
			(layer "F.SilkS")
		)
		(fp_line
			(start -0.7874 -0.4064)
			(end 0.7874 -0.4064)
			(stroke
				(width 0.1524)
				(type default)
			)
			(layer "F.SilkS")
		)
		(fp_line
			(start 0.67945 0.3048)
			(end 0.120396 0.3048)
			(stroke
				(width 0.1)
				(type default)
			)
			(layer "F.Fab")
		)
		(fp_line
			(start 0.67945 -0.3048)
			(end 0.67945 0.3048)
			(stroke
				(width 0.1)
				(type default)
			)
			(layer "F.Fab")
		)
		(fp_line
			(start 0.12065 -0.2794)
			(end 0.12065 -0.3048)
			(stroke
				(width 0.1)
				(type default)
			)
			(layer "F.Fab")
		)
		(fp_line
			(start 0.12065 -0.3048)
			(end 0.67945 -0.3048)
			(stroke
				(width 0.1)
				(type default)
			)
			(layer "F.Fab")
		)
		(fp_line
			(start 0.120396 0.3048)
			(end 0.120396 0.2794)
			(stroke
				(width 0.1)
				(type default)
			)
			(layer "F.Fab")
		)
		(fp_line
			(start 0.120396 0.2794)
			(end -0.12065 0.2794)
			(stroke
				(width 0.1)
				(type default)
			)
			(layer "F.Fab")
		)
		(fp_line
			(start -0.12065 0.3048)
			(end -0.67945 0.3048)
			(stroke
				(width 0.1)
				(type default)
			)
			(layer "F.Fab")
		)
		(fp_line
			(start -0.12065 0.2794)
			(end -0.12065 0.3048)
			(stroke
				(width 0.1)
				(type default)
			)
			(layer "F.Fab")
		)
		(fp_line
			(start -0.12065 -0.2794)
			(end 0.12065 -0.2794)
			(stroke
				(width 0.1)
				(type default)
			)
			(layer "F.Fab")
		)
		(fp_line
			(start -0.12065 -0.305054)
			(end -0.12065 -0.2794)
			(stroke
				(width 0.1)
				(type default)
			)
			(layer "F.Fab")
		)
		(fp_line
			(start -0.67945 0.3048)
			(end -0.67945 -0.305054)
			(stroke
				(width 0.1)
				(type default)
			)
			(layer "F.Fab")
		)
		(fp_line
			(start -0.67945 -0.305054)
			(end -0.12065 -0.305054)
			(stroke
				(width 0.1)
				(type default)
			)
			(layer "F.Fab")
		)
		(pad "1" smd circle
			(at -0.40005 0 180)
			(size 0 0)
			(layers "F.Cu" "F.Mask" "F.Paste")
			(net "MB_FRU_ADDR0")
		)
		(pad "2" smd circle
			(at 0.40005 0 180)
			(size 0 0)
			(layers "F.Cu" "F.Mask" "F.Paste")
			(net "GND")
		)
	)
	(footprint ""
		(layer "F.Cu")
		(at 362.89488 -296.05478)
		(property "Reference" "C213"
			(at 0 0 0)
			(layer "F.SilkS")
			(hide yes)
			(effects
				(font
					(size 1.27 1.27)
				)
			)
		)
		(property "Value" ""
			(at 0 0 0)
			(layer "F.Fab")
			(effects
				(font
					(size 1.27 1.27)
				)
			)
		)
		(duplicate_pad_numbers_are_jumpers no)
		(fp_line
			(start -1.524 -0.762)
			(end 1.524 -0.762)
			(stroke
				(width 0.1524)
				(type default)
			)
			(layer "F.SilkS")
		)
		(fp_line
			(start -1.524 0.762)
			(end -1.524 -0.762)
			(stroke
				(width 0.1524)
				(type default)
			)
			(layer "F.SilkS")
		)
		(fp_line
			(start 1.524 -0.762)
			(end 1.524 0.762)
			(stroke
				(width 0.1524)
				(type default)
			)
			(layer "F.SilkS")
		)
		(fp_line
			(start 1.524 0.762)
			(end -1.524 0.762)
			(stroke
				(width 0.1524)
				(type default)
			)
			(layer "F.SilkS")
		)
		(fp_line
			(start -1.1049 -0.724916)
			(end -1.1049 0.724916)
			(stroke
				(width 0.1)
				(type default)
			)
			(layer "F.Fab")
		)
		(fp_line
			(start -1.1049 0.724916)
			(end 1.1049 0.724916)
			(stroke
				(width 0.1)
				(type default)
			)
			(layer "F.Fab")
		)
		(fp_line
			(start 1.1049 -0.724916)
			(end -1.1049 -0.724916)
			(stroke
				(width 0.1)
				(type default)
			)
			(layer "F.Fab")
		)
		(fp_line
			(start 1.1049 0.724916)
			(end 1.1049 -0.724916)
			(stroke
				(width 0.1)
				(type default)
			)
			(layer "F.Fab")
		)
		(pad "1" smd rect
			(at -0.889 0 180)
			(size 1.016 1.27)
			(layers "F.Cu" "F.Mask" "F.Paste")
			(net "PVCCIN_CPU0")
		)
		(pad "2" smd rect
			(at 0.889 0 180)
			(size 1.016 1.27)
			(layers "F.Cu" "F.Mask" "F.Paste")
			(net "GND")
		)
	)
	(footprint ""
		(layer "F.Cu")
		(at 356.899972 -28.450032)
		(property "Reference" "H36"
			(at 3.200908 -2.585466 0)
			(unlocked yes)
			(layer "F.SilkS")
			(effects
				(font
					(size 0.7874 0.5842)
					(thickness 0.1524)
				)
				(justify left)
			)
		)
		(property "Value" ""
			(at 0 0 0)
			(layer "F.Fab")
			(effects
				(font
					(size 1.27 1.27)
				)
			)
		)
		(duplicate_pad_numbers_are_jumpers no)
		(fp_circle
			(center 0 0)
			(end 2.3622 0)
			(stroke
				(width 0.1524)
				(type default)
			)
			(fill no)
			(layer "F.SilkS")
		)
		(fp_circle
			(center 0 0)
			(end 2.3622 0)
			(stroke
				(width 0.1524)
				(type default)
			)
			(fill no)
			(layer "B.SilkS")
		)
		(fp_circle
			(center 0 0)
			(end 2.3622 0)
			(stroke
				(width 0.1)
				(type default)
			)
			(fill no)
			(layer "B.Fab")
		)
		(fp_circle
			(center 0 0)
			(end 2.3622 0)
			(stroke
				(width 0.1)
				(type default)
			)
			(fill no)
			(layer "F.Fab")
		)
		(pad "" np_thru_hole circle
			(at 0 0)
			(size 3.0988 3.0988)
			(drill 3.0988)
			(layers "*.Cu" "*.Mask")
			(clearance 0.254)
			(thermal_gap 0.254)
		)
	)
	(footprint ""
		(layer "F.Cu")
		(at 398.750028 -440.489848)
		(property "Reference" "J105"
			(at -2.99466 23.400512 0)
			(unlocked yes)
			(layer "F.SilkS")
			(effects
				(font
					(size 0.7874 0.5842)
					(thickness 0.1524)
				)
				(justify left)
			)
		)
		(property "Value" ""
			(at 0 0 0)
			(layer "F.Fab")
			(effects
				(font
					(size 1.27 1.27)
				)
			)
		)
		(duplicate_pad_numbers_are_jumpers no)
		(fp_line
			(start -4.249928 -11.999976)
			(end 18.64995 -11.999976)
			(stroke
				(width 0.1524)
				(type default)
			)
			(layer "F.SilkS")
		)
		(fp_line
			(start -4.249928 22.400006)
			(end -4.249928 -11.999976)
			(stroke
				(width 0.1524)
				(type default)
			)
			(layer "F.SilkS")
		)
		(fp_line
			(start -1.249934 -8.999982)
			(end -1.249934 19.400012)
			(stroke
				(width 0.1524)
				(type default)
			)
			(layer "F.SilkS")
		)
		(fp_line
			(start -1.249934 -1.500124)
			(end 15.649956 -1.500124)
			(stroke
				(width 0.1524)
				(type default)
			)
			(layer "F.SilkS")
		)
		(fp_line
			(start -1.249934 19.400012)
			(end 15.649956 19.400012)
			(stroke
				(width 0.1524)
				(type default)
			)
			(layer "F.SilkS")
		)
		(fp_line
			(start 0.0254 -0.9144)
			(end 1.0414 -0.9144)
			(stroke
				(width 0.1524)
				(type default)
			)
			(layer "F.SilkS")
		)
		(fp_line
			(start 0.5334 -1.4224)
			(end 0.0254 -0.9144)
			(stroke
				(width 0.1524)
				(type default)
			)
			(layer "F.SilkS")
		)
		(fp_line
			(start 0.5334 -1.4224)
			(end 0.5334 -0.5588)
			(stroke
				(width 0.1524)
				(type default)
			)
			(layer "F.SilkS")
		)
		(fp_line
			(start 0.5334 -0.5588)
			(end 1.8034 -0.5588)
			(stroke
				(width 0.1524)
				(type default)
			)
			(layer "F.SilkS")
		)
		(fp_line
			(start 1.0414 -0.9144)
			(end 0.5334 -1.4224)
			(stroke
				(width 0.1524)
				(type default)
			)
			(layer "F.SilkS")
		)
		(fp_line
			(start 1.8034 -0.5588)
			(end 2.032 -0.7874)
			(stroke
				(width 0.1524)
				(type default)
			)
			(layer "F.SilkS")
		)
		(fp_line
			(start 15.649956 -8.999982)
			(end -1.249934 -8.999982)
			(stroke
				(width 0.1524)
				(type default)
			)
			(layer "F.SilkS")
		)
		(fp_line
			(start 15.649956 19.400012)
			(end 15.649956 -8.999982)
			(stroke
				(width 0.1524)
				(type default)
			)
			(layer "F.SilkS")
		)
		(fp_line
			(start 18.64995 -11.999976)
			(end 18.64995 22.400006)
			(stroke
				(width 0.1524)
				(type default)
			)
			(layer "F.SilkS")
		)
		(fp_line
			(start 18.64995 22.400006)
			(end -4.249928 22.400006)
			(stroke
				(width 0.1524)
				(type default)
			)
			(layer "F.SilkS")
		)
		(fp_poly
			(pts
				(xy -1.567688 0.07874) (xy -2.334768 0.46228) (xy -2.334768 -0.3048)
			)
			(stroke
				(width 0)
				(type default)
			)
			(fill yes)
			(layer "F.SilkS")
		)
		(fp_line
			(start -4.249928 -11.999976)
			(end 18.64995 -11.999976)
			(stroke
				(width 0.1524)
				(type default)
			)
			(layer "B.SilkS")
		)
		(fp_line
			(start -4.249928 22.400006)
			(end -4.249928 -11.999976)
			(stroke
				(width 0.1524)
				(type default)
			)
			(layer "B.SilkS")
		)
		(fp_line
			(start 18.64995 -11.999976)
			(end 18.64995 22.400006)
			(stroke
				(width 0.1524)
				(type default)
			)
			(layer "B.SilkS")
		)
		(fp_line
			(start 18.64995 22.400006)
			(end -4.249928 22.400006)
			(stroke
				(width 0.1524)
				(type default)
			)
			(layer "B.SilkS")
		)
		(fp_line
			(start -4.249928 -11.999976)
			(end 18.64995 -11.999976)
			(stroke
				(width 0.1)
				(type default)
			)
			(layer "B.Fab")
		)
		(fp_line
			(start -4.249928 22.400006)
			(end -4.249928 -11.999976)
			(stroke
				(width 0.1)
				(type default)
			)
			(layer "B.Fab")
		)
		(fp_line
			(start 18.64995 -11.999976)
			(end 18.64995 22.400006)
			(stroke
				(width 0.1)
				(type default)
			)
			(layer "B.Fab")
		)
		(fp_line
			(start 18.64995 22.400006)
			(end -4.249928 22.400006)
			(stroke
				(width 0.1)
				(type default)
			)
			(layer "B.Fab")
		)
		(fp_line
			(start -1.249934 -8.999982)
			(end -1.249934 19.400012)
			(stroke
				(width 0.1)
				(type default)
			)
			(layer "F.Fab")
		)
		(fp_line
			(start -1.249934 19.400012)
			(end 15.649956 19.400012)
			(stroke
				(width 0.1)
				(type default)
			)
			(layer "F.Fab")
		)
		(fp_line
			(start 15.649956 -8.999982)
			(end -1.249934 -8.999982)
			(stroke
				(width 0.1)
				(type default)
			)
			(layer "F.Fab")
		)
		(fp_line
			(start 15.649956 19.400012)
			(end 15.649956 -8.999982)
			(stroke
				(width 0.1)
				(type default)
			)
			(layer "F.Fab")
		)
		(fp_poly
			(pts
				(xy -2.670048 -0.508) (xy -2.670048 0.508) (xy -1.654048 0)
			)
			(stroke
				(width 0)
				(type default)
			)
			(fill yes)
			(layer "F.Fab")
		)
		(fp_text user "B"
			(at -1.932432 1.183386 0)
			(unlocked yes)
			(layer "F.SilkS")
			(effects
				(font
					(size 0.7874 0.5842)
					(thickness 0.1524)
				)
			)
		)
		(fp_text user "C"
			(at -1.932432 2.383536 0)
			(unlocked yes)
			(layer "F.SilkS")
			(effects
				(font
					(size 0.7874 0.5842)
					(thickness 0.1524)
				)
			)
		)
		(fp_text user "D"
			(at -1.932432 3.583432 0)
			(unlocked yes)
			(layer "F.SilkS")
			(effects
				(font
					(size 0.7874 0.5842)
					(thickness 0.1524)
				)
			)
		)
		(fp_text user "E"
			(at -1.932432 4.783582 0)
			(unlocked yes)
			(layer "F.SilkS")
			(effects
				(font
					(size 0.7874 0.5842)
					(thickness 0.1524)
				)
			)
		)
		(fp_text user "F"
			(at -1.932432 5.983478 0)
			(unlocked yes)
			(layer "F.SilkS")
			(effects
				(font
					(size 0.7874 0.5842)
					(thickness 0.1524)
				)
			)
		)
		(fp_text user "G"
			(at -1.932432 7.183374 0)
			(unlocked yes)
			(layer "F.SilkS")
			(effects
				(font
					(size 0.7874 0.5842)
					(thickness 0.1524)
				)
			)
		)
		(fp_text user "H"
			(at -1.932432 8.383524 0)
			(unlocked yes)
			(layer "F.SilkS")
			(effects
				(font
					(size 0.7874 0.5842)
					(thickness 0.1524)
				)
			)
		)
		(fp_text user "I"
			(at -1.932432 9.58342 0)
			(unlocked yes)
			(layer "F.SilkS")
			(effects
				(font
					(size 0.7874 0.5842)
					(thickness 0.1524)
				)
			)
		)
		(fp_text user "J"
			(at -1.932432 10.78357 0)
			(unlocked yes)
			(layer "F.SilkS")
			(effects
				(font
					(size 0.7874 0.5842)
					(thickness 0.1524)
				)
			)
		)
		(fp_text user "K"
			(at -1.932432 11.983466 0)
			(unlocked yes)
			(layer "F.SilkS")
			(effects
				(font
					(size 0.7874 0.5842)
					(thickness 0.1524)
				)
			)
		)
		(fp_text user "L"
			(at -1.932432 13.183616 0)
			(unlocked yes)
			(layer "F.SilkS")
			(effects
				(font
					(size 0.7874 0.5842)
					(thickness 0.1524)
				)
			)
		)
		(fp_text user "M"
			(at -1.932432 14.383512 0)
			(unlocked yes)
			(layer "F.SilkS")
			(effects
				(font
					(size 0.7874 0.5842)
					(thickness 0.1524)
				)
			)
		)
		(fp_text user "N"
			(at -1.932432 15.583408 0)
			(unlocked yes)
			(layer "F.SilkS")
			(effects
				(font
					(size 0.7874 0.5842)
					(thickness 0.1524)
				)
			)
		)
		(fp_text user "1"
			(at 0.427482 20.23491 0)
			(unlocked yes)
			(layer "F.SilkS")
			(effects
				(font
					(size 0.7874 0.5842)
					(thickness 0.1524)
				)
			)
		)
		(fp_text user "EDGE OF DAUGHTER CARD"
			(at 2.2479 -0.899668 0)
			(unlocked yes)
			(layer "F.SilkS")
			(effects
				(font
					(size 0.635 0.4064)
					(thickness 0.1524)
				)
				(justify left)
			)
		)
		(fp_text user "2"
			(at 2.427478 20.23491 0)
			(unlocked yes)
			(layer "F.SilkS")
			(effects
				(font
					(size 0.7874 0.5842)
					(thickness 0.1524)
				)
			)
		)
		(fp_text user "3"
			(at 4.427474 20.23491 0)
			(unlocked yes)
			(layer "F.SilkS")
			(effects
				(font
					(size 0.7874 0.5842)
					(thickness 0.1524)
				)
			)
		)
		(fp_text user "4"
			(at 6.42747 20.23491 0)
			(unlocked yes)
			(layer "F.SilkS")
			(effects
				(font
					(size 0.7874 0.5842)
					(thickness 0.1524)
				)
			)
		)
		(fp_text user "5"
			(at 8.427466 20.23491 0)
			(unlocked yes)
			(layer "F.SilkS")
			(effects
				(font
					(size 0.7874 0.5842)
					(thickness 0.1524)
				)
			)
		)
		(fp_text user "6"
			(at 10.427462 20.23491 0)
			(unlocked yes)
			(layer "F.SilkS")
			(effects
				(font
					(size 0.7874 0.5842)
					(thickness 0.1524)
				)
			)
		)
		(fp_text user "7"
			(at 12.427458 20.23491 0)
			(unlocked yes)
			(layer "F.SilkS")
			(effects
				(font
					(size 0.7874 0.5842)
					(thickness 0.1524)
				)
			)
		)
		(fp_text user "8"
			(at 14.427454 20.23491 0)
			(unlocked yes)
			(layer "F.SilkS")
			(effects
				(font
					(size 0.7874 0.5842)
					(thickness 0.1524)
				)
			)
		)
		(fp_text user "PRESS-FIT"
			(at 17.240758 16.521684 90)
			(unlocked yes)
			(layer "F.SilkS")
			(effects
				(font
					(size 1.905 1.4224)
					(thickness 0.1524)
				)
				(justify left)
			)
		)
		(fp_text user "A"
			(at -1.342644 0.18161 0)
			(unlocked yes)
			(layer "B.SilkS")
			(effects
				(font
					(size 0.7874 0.5842)
					(thickness 0.1524)
				)
				(justify mirror)
			)
		)
		(fp_text user "G"
			(at -1.317244 7.59841 0)
			(unlocked yes)
			(layer "B.SilkS")
			(effects
				(font
					(size 0.7874 0.5842)
					(thickness 0.1524)
				)
				(justify mirror)
			)
		)
		(fp_text user "H"
			(at -1.291844 8.81761 0)
			(unlocked yes)
			(layer "B.SilkS")
			(effects
				(font
					(size 0.7874 0.5842)
					(thickness 0.1524)
				)
				(justify mirror)
			)
		)
		(fp_text user "B"
			(at -1.29032 1.508506 0)
			(unlocked yes)
			(layer "B.SilkS")
			(effects
				(font
					(size 0.7874 0.5842)
					(thickness 0.1524)
				)
				(justify mirror)
			)
		)
		(fp_text user "C"
			(at -1.29032 2.708656 0)
			(unlocked yes)
			(layer "B.SilkS")
			(effects
				(font
					(size 0.7874 0.5842)
					(thickness 0.1524)
				)
				(justify mirror)
			)
		)
		(fp_text user "D"
			(at -1.29032 3.908552 0)
			(unlocked yes)
			(layer "B.SilkS")
			(effects
				(font
					(size 0.7874 0.5842)
					(thickness 0.1524)
				)
				(justify mirror)
			)
		)
		(fp_text user "E"
			(at -1.29032 5.108702 0)
			(unlocked yes)
			(layer "B.SilkS")
			(effects
				(font
					(size 0.7874 0.5842)
					(thickness 0.1524)
				)
				(justify mirror)
			)
		)
		(fp_text user "F"
			(at -1.29032 6.308598 0)
			(unlocked yes)
			(layer "B.SilkS")
			(effects
				(font
					(size 0.7874 0.5842)
					(thickness 0.1524)
				)
				(justify mirror)
			)
		)
		(fp_text user "I"
			(at -1.29032 9.90854 0)
			(unlocked yes)
			(layer "B.SilkS")
			(effects
				(font
					(size 0.7874 0.5842)
					(thickness 0.1524)
				)
				(justify mirror)
			)
		)
		(fp_text user "J"
			(at -1.29032 11.10869 0)
			(unlocked yes)
			(layer "B.SilkS")
			(effects
				(font
					(size 0.7874 0.5842)
					(thickness 0.1524)
				)
				(justify mirror)
			)
		)
		(fp_text user "K"
			(at -1.29032 12.308586 0)
			(unlocked yes)
			(layer "B.SilkS")
			(effects
				(font
					(size 0.7874 0.5842)
					(thickness 0.1524)
				)
				(justify mirror)
			)
		)
		(fp_text user "L"
			(at -1.29032 13.508736 0)
			(unlocked yes)
			(layer "B.SilkS")
			(effects
				(font
					(size 0.7874 0.5842)
					(thickness 0.1524)
				)
				(justify mirror)
			)
		)
		(fp_text user "M"
			(at -1.29032 14.708632 0)
			(unlocked yes)
			(layer "B.SilkS")
			(effects
				(font
					(size 0.7874 0.5842)
					(thickness 0.1524)
				)
				(justify mirror)
			)
		)
		(fp_text user "N"
			(at -1.29032 15.908528 0)
			(unlocked yes)
			(layer "B.SilkS")
			(effects
				(font
					(size 0.7874 0.5842)
					(thickness 0.1524)
				)
				(justify mirror)
			)
		)
		(fp_text user "1"
			(at 0.529082 16.79321 0)
			(unlocked yes)
			(layer "B.SilkS")
			(effects
				(font
					(size 0.7874 0.5842)
					(thickness 0.1524)
				)
				(justify mirror)
			)
		)
		(fp_text user "2"
			(at 2.529078 16.79321 0)
			(unlocked yes)
			(layer "B.SilkS")
			(effects
				(font
					(size 0.7874 0.5842)
					(thickness 0.1524)
				)
				(justify mirror)
			)
		)
		(fp_text user "3"
			(at 4.529074 16.79321 0)
			(unlocked yes)
			(layer "B.SilkS")
			(effects
				(font
					(size 0.7874 0.5842)
					(thickness 0.1524)
				)
				(justify mirror)
			)
		)
		(fp_text user "4"
			(at 6.52907 16.79321 0)
			(unlocked yes)
			(layer "B.SilkS")
			(effects
				(font
					(size 0.7874 0.5842)
					(thickness 0.1524)
				)
				(justify mirror)
			)
		)
		(fp_text user "5"
			(at 8.529066 16.79321 0)
			(unlocked yes)
			(layer "B.SilkS")
			(effects
				(font
					(size 0.7874 0.5842)
					(thickness 0.1524)
				)
				(justify mirror)
			)
		)
		(fp_text user "6"
			(at 10.529062 16.79321 0)
			(unlocked yes)
			(layer "B.SilkS")
			(effects
				(font
					(size 0.7874 0.5842)
					(thickness 0.1524)
				)
				(justify mirror)
			)
		)
		(fp_text user "7"
			(at 12.529058 16.79321 0)
			(unlocked yes)
			(layer "B.SilkS")
			(effects
				(font
					(size 0.7874 0.5842)
					(thickness 0.1524)
				)
				(justify mirror)
			)
		)
		(fp_text user "8"
			(at 14.529054 16.79321 0)
			(unlocked yes)
			(layer "B.SilkS")
			(effects
				(font
					(size 0.7874 0.5842)
					(thickness 0.1524)
				)
				(justify mirror)
			)
		)
		(fp_text user "PRESS-FIT"
			(at 18.343372 19.50847 0)
			(unlocked yes)
			(layer "B.SilkS")
			(effects
				(font
					(size 1.905 1.4224)
					(thickness 0.1524)
				)
				(justify left mirror)
			)
		)
		(fp_text user "A"
			(at -1.199134 0 90)
			(unlocked yes)
			(layer "B.Fab")
			(effects
				(font
					(size 0.7874 0.5842)
					(thickness 0.1524)
				)
				(justify mirror)
			)
		)
		(fp_text user "G"
			(at -1.173734 7.4168 90)
			(unlocked yes)
			(layer "B.Fab")
			(effects
				(font
					(size 0.7874 0.5842)
					(thickness 0.1524)
				)
				(justify mirror)
			)
		)
		(fp_text user "H"
			(at -1.148334 8.636 90)
			(unlocked yes)
			(layer "B.Fab")
			(effects
				(font
					(size 0.7874 0.5842)
					(thickness 0.1524)
				)
				(justify mirror)
			)
		)
		(fp_text user "B"
			(at -1.14681 1.326896 90)
			(unlocked yes)
			(layer "B.Fab")
			(effects
				(font
					(size 0.7874 0.5842)
					(thickness 0.1524)
				)
				(justify mirror)
			)
		)
		(fp_text user "C"
			(at -1.14681 2.527046 90)
			(unlocked yes)
			(layer "B.Fab")
			(effects
				(font
					(size 0.7874 0.5842)
					(thickness 0.1524)
				)
				(justify mirror)
			)
		)
		(fp_text user "D"
			(at -1.14681 3.726942 90)
			(unlocked yes)
			(layer "B.Fab")
			(effects
				(font
					(size 0.7874 0.5842)
					(thickness 0.1524)
				)
				(justify mirror)
			)
		)
		(fp_text user "E"
			(at -1.14681 4.927092 90)
			(unlocked yes)
			(layer "B.Fab")
			(effects
				(font
					(size 0.7874 0.5842)
					(thickness 0.1524)
				)
				(justify mirror)
			)
		)
		(fp_text user "F"
			(at -1.14681 6.126988 90)
			(unlocked yes)
			(layer "B.Fab")
			(effects
				(font
					(size 0.7874 0.5842)
					(thickness 0.1524)
				)
				(justify mirror)
			)
		)
		(fp_text user "I"
			(at -1.14681 9.72693 90)
			(unlocked yes)
			(layer "B.Fab")
			(effects
				(font
					(size 0.7874 0.5842)
					(thickness 0.1524)
				)
				(justify mirror)
			)
		)
		(fp_text user "J"
			(at -1.14681 10.92708 90)
			(unlocked yes)
			(layer "B.Fab")
			(effects
				(font
					(size 0.7874 0.5842)
					(thickness 0.1524)
				)
				(justify mirror)
			)
		)
		(fp_text user "K"
			(at -1.14681 12.126976 90)
			(unlocked yes)
			(layer "B.Fab")
			(effects
				(font
					(size 0.7874 0.5842)
					(thickness 0.1524)
				)
				(justify mirror)
			)
		)
		(fp_text user "L"
			(at -1.14681 13.327126 90)
			(unlocked yes)
			(layer "B.Fab")
			(effects
				(font
					(size 0.7874 0.5842)
					(thickness 0.1524)
				)
				(justify mirror)
			)
		)
		(fp_text user "M"
			(at -1.14681 14.527022 90)
			(unlocked yes)
			(layer "B.Fab")
			(effects
				(font
					(size 0.7874 0.5842)
					(thickness 0.1524)
				)
				(justify mirror)
			)
		)
		(fp_text user "N"
			(at -1.14681 15.726918 90)
			(unlocked yes)
			(layer "B.Fab")
			(effects
				(font
					(size 0.7874 0.5842)
					(thickness 0.1524)
				)
				(justify mirror)
			)
		)
		(fp_text user "1"
			(at 0.060452 16.764 90)
			(unlocked yes)
			(layer "B.Fab")
			(effects
				(font
					(size 0.7874 0.5842)
					(thickness 0.1524)
				)
				(justify mirror)
			)
		)
		(fp_text user "2"
			(at 2.060448 16.764 90)
			(unlocked yes)
			(layer "B.Fab")
			(effects
				(font
					(size 0.7874 0.5842)
					(thickness 0.1524)
				)
				(justify mirror)
			)
		)
		(fp_text user "3"
			(at 4.060444 16.764 90)
			(unlocked yes)
			(layer "B.Fab")
			(effects
				(font
					(size 0.7874 0.5842)
					(thickness 0.1524)
				)
				(justify mirror)
			)
		)
		(fp_text user "4"
			(at 6.06044 16.764 90)
			(unlocked yes)
			(layer "B.Fab")
			(effects
				(font
					(size 0.7874 0.5842)
					(thickness 0.1524)
				)
				(justify mirror)
			)
		)
		(fp_text user "5"
			(at 8.060436 16.764 90)
			(unlocked yes)
			(layer "B.Fab")
			(effects
				(font
					(size 0.7874 0.5842)
					(thickness 0.1524)
				)
				(justify mirror)
			)
		)
		(fp_text user "6"
			(at 10.060432 16.764 90)
			(unlocked yes)
			(layer "B.Fab")
			(effects
				(font
					(size 0.7874 0.5842)
					(thickness 0.1524)
				)
				(justify mirror)
			)
		)
		(fp_text user "7"
			(at 12.060428 16.764 90)
			(unlocked yes)
			(layer "B.Fab")
			(effects
				(font
					(size 0.7874 0.5842)
					(thickness 0.1524)
				)
				(justify mirror)
			)
		)
		(fp_text user "8"
			(at 14.060424 16.764 90)
			(unlocked yes)
			(layer "B.Fab")
			(effects
				(font
					(size 0.7874 0.5842)
					(thickness 0.1524)
				)
				(justify mirror)
			)
		)
		(fp_text user "PRESS-FIT"
			(at 17.23771 -0.0762 90)
			(unlocked yes)
			(layer "B.Fab")
			(effects
				(font
					(size 1.905 1.4224)
					(thickness 0.1524)
				)
				(justify left mirror)
			)
		)
		(fp_text user "B"
			(at -2.253742 1.199896 90)
			(unlocked yes)
			(layer "F.Fab")
			(effects
				(font
					(size 0.7874 0.5842)
					(thickness 0.1524)
				)
			)
		)
		(fp_text user "C"
			(at -2.253742 2.400046 90)
			(unlocked yes)
			(layer "F.Fab")
			(effects
				(font
					(size 0.7874 0.5842)
					(thickness 0.1524)
				)
			)
		)
		(fp_text user "D"
			(at -2.253742 3.599942 90)
			(unlocked yes)
			(layer "F.Fab")
			(effects
				(font
					(size 0.7874 0.5842)
					(thickness 0.1524)
				)
			)
		)
		(fp_text user "E"
			(at -2.253742 4.800092 90)
			(unlocked yes)
			(layer "F.Fab")
			(effects
				(font
					(size 0.7874 0.5842)
					(thickness 0.1524)
				)
			)
		)
		(fp_text user "F"
			(at -2.253742 5.999988 90)
			(unlocked yes)
			(layer "F.Fab")
			(effects
				(font
					(size 0.7874 0.5842)
					(thickness 0.1524)
				)
			)
		)
		(fp_text user "G"
			(at -2.253742 7.199884 90)
			(unlocked yes)
			(layer "F.Fab")
			(effects
				(font
					(size 0.7874 0.5842)
					(thickness 0.1524)
				)
			)
		)
		(fp_text user "H"
			(at -2.253742 8.400034 90)
			(unlocked yes)
			(layer "F.Fab")
			(effects
				(font
					(size 0.7874 0.5842)
					(thickness 0.1524)
				)
			)
		)
		(fp_text user "I"
			(at -2.253742 9.59993 90)
			(unlocked yes)
			(layer "F.Fab")
			(effects
				(font
					(size 0.7874 0.5842)
					(thickness 0.1524)
				)
			)
		)
		(fp_text user "J"
			(at -2.253742 10.80008 90)
			(unlocked yes)
			(layer "F.Fab")
			(effects
				(font
					(size 0.7874 0.5842)
					(thickness 0.1524)
				)
			)
		)
		(fp_text user "K"
			(at -2.253742 11.999976 90)
			(unlocked yes)
			(layer "F.Fab")
			(effects
				(font
					(size 0.7874 0.5842)
					(thickness 0.1524)
				)
			)
		)
		(fp_text user "L"
			(at -2.253742 13.200126 90)
			(unlocked yes)
			(layer "F.Fab")
			(effects
				(font
					(size 0.7874 0.5842)
					(thickness 0.1524)
				)
			)
		)
		(fp_text user "M"
			(at -2.253742 14.400022 90)
			(unlocked yes)
			(layer "F.Fab")
			(effects
				(font
					(size 0.7874 0.5842)
					(thickness 0.1524)
				)
			)
		)
		(fp_text user "N"
			(at -2.253742 15.599918 90)
			(unlocked yes)
			(layer "F.Fab")
			(effects
				(font
					(size 0.7874 0.5842)
					(thickness 0.1524)
				)
			)
		)
		(fp_text user "1"
			(at 0.111252 19.8628 90)
			(unlocked yes)
			(layer "F.Fab")
			(effects
				(font
					(size 0.7874 0.5842)
					(thickness 0.1524)
				)
			)
		)
		(fp_text user "2"
			(at 2.111248 19.8628 90)
			(unlocked yes)
			(layer "F.Fab")
			(effects
				(font
					(size 0.7874 0.5842)
					(thickness 0.1524)
				)
			)
		)
		(fp_text user "3"
			(at 4.111244 19.8628 90)
			(unlocked yes)
			(layer "F.Fab")
			(effects
				(font
					(size 0.7874 0.5842)
					(thickness 0.1524)
				)
			)
		)
		(fp_text user "4"
			(at 6.11124 19.8628 90)
			(unlocked yes)
			(layer "F.Fab")
			(effects
				(font
					(size 0.7874 0.5842)
					(thickness 0.1524)
				)
			)
		)
		(fp_text user "5"
			(at 8.111236 19.8628 90)
			(unlocked yes)
			(layer "F.Fab")
			(effects
				(font
					(size 0.7874 0.5842)
					(thickness 0.1524)
				)
			)
		)
		(fp_text user "6"
			(at 10.111232 19.8628 90)
			(unlocked yes)
			(layer "F.Fab")
			(effects
				(font
					(size 0.7874 0.5842)
					(thickness 0.1524)
				)
			)
		)
		(fp_text user "7"
			(at 12.111228 19.8628 90)
			(unlocked yes)
			(layer "F.Fab")
			(effects
				(font
					(size 0.7874 0.5842)
					(thickness 0.1524)
				)
			)
		)
		(fp_text user "8"
			(at 14.111224 19.8628 90)
			(unlocked yes)
			(layer "F.Fab")
			(effects
				(font
					(size 0.7874 0.5842)
					(thickness 0.1524)
				)
			)
		)
		(fp_text user "PRESS-FIT"
			(at 17.240758 16.521684 90)
			(unlocked yes)
			(layer "F.Fab")
			(effects
				(font
					(size 1.905 1.4224)
					(thickness 0.1524)
				)
				(justify left)
			)
		)
		(pad "A1" thru_hole rect
			(at 0 0 180)
			(size 0.766318 0.766318)
			(drill 0.359918)
			(layers "*.Cu" "*.Mask")
			(remove_unused_layers no)
			(net "GPU_3V3IO_RSVD4")
			(clearance 0.0508)
			(thermal_gap 0.0508)
			(padstack
				(mode front_inner_back)
				(layer "Inner"
					(shape circle)
					(size 0.766318 0.766318)
					(clearance 0.0508)
				)
				(layer "B.Cu"
					(shape rect)
					(size 0.766318 0.766318)
					(clearance 0.0508)
				)
			)
		)
		(pad "A2" thru_hole circle
			(at 1.999996 0.199898 180)
			(size 0.906272 0.906272)
			(drill 0.499872)
			(layers "*.Cu" "*.Mask")
			(remove_unused_layers no)
			(net "GND")
			(clearance 0.0508)
			(thermal_gap 0.0508)
		)
		(pad "A3" thru_hole circle
			(at 3.999992 0 180)
			(size 0.766318 0.766318)
			(drill 0.359918)
			(layers "*.Cu" "*.Mask")
			(remove_unused_layers no)
			(net "GPU_WP_HW_CTRL_ISO")
			(clearance 0.0508)
			(thermal_gap 0.0508)
		)
		(pad "A4" thru_hole circle
			(at 5.999988 0.199898 180)
			(size 0.906272 0.906272)
			(drill 0.499872)
			(layers "*.Cu" "*.Mask")
			(remove_unused_layers no)
			(net "GND")
			(clearance 0.0508)
			(thermal_gap 0.0508)
		)
		(pad "A5" thru_hole circle
			(at 7.999984 0 180)
			(size 0.766318 0.766318)
			(drill 0.359918)
			(layers "*.Cu" "*.Mask")
			(remove_unused_layers no)
			(net "GPU_3V3IO_RSVD3")
			(clearance 0.0508)
			(thermal_gap 0.0508)
		)
		(pad "A6" thru_hole circle
			(at 9.99998 0.199898 180)
			(size 0.906272 0.906272)
			(drill 0.499872)
			(layers "*.Cu" "*.Mask")
			(remove_unused_layers no)
			(net "GND")
			(clearance 0.0508)
			(thermal_gap 0.0508)
		)
		(pad "A7" thru_hole circle
			(at 11.999976 0 180)
			(size 0.766318 0.766318)
			(drill 0.359918)
			(layers "*.Cu" "*.Mask")
			(remove_unused_layers no)
			(net "GPU_3V3IO_RSVD1")
			(clearance 0.0508)
			(thermal_gap 0.0508)
		)
		(pad "A8" thru_hole circle
			(at 13.999972 0.199898 180)
			(size 0.906272 0.906272)
			(drill 0.499872)
			(layers "*.Cu" "*.Mask")
			(remove_unused_layers no)
			(net "GND")
			(clearance 0.0508)
			(thermal_gap 0.0508)
		)
		(pad "B1" thru_hole circle
			(at 0 1.199896 180)
			(size 0.906272 0.906272)
			(drill 0.499872)
			(layers "*.Cu" "*.Mask")
			(remove_unused_layers no)
			(net "GND")
			(clearance 0.0508)
			(thermal_gap 0.0508)
		)
		(pad "B3" thru_hole circle
			(at 3.999992 1.199896 180)
			(size 0.906272 0.906272)
			(drill 0.499872)
			(layers "*.Cu" "*.Mask")
			(remove_unused_layers no)
			(net "GND")
			(clearance 0.0508)
			(thermal_gap 0.0508)
		)
		(pad "B5" thru_hole circle
			(at 7.999984 1.199896 180)
			(size 0.906272 0.906272)
			(drill 0.499872)
			(layers "*.Cu" "*.Mask")
			(remove_unused_layers no)
			(net "GND")
			(clearance 0.0508)
			(thermal_gap 0.0508)
		)
		(pad "B7" thru_hole circle
			(at 11.999976 1.199896 180)
			(size 0.906272 0.906272)
			(drill 0.499872)
			(layers "*.Cu" "*.Mask")
			(remove_unused_layers no)
			(net "GND")
			(clearance 0.0508)
			(thermal_gap 0.0508)
		)
		(pad "D2" thru_hole circle
			(at 1.999996 3.800094 180)
			(size 0.906272 0.906272)
			(drill 0.499872)
			(layers "*.Cu" "*.Mask")
			(remove_unused_layers no)
			(net "GND")
			(clearance 0.0508)
			(thermal_gap 0.0508)
		)
		(pad "D4" thru_hole circle
			(at 5.999988 3.800094 180)
			(size 0.906272 0.906272)
			(drill 0.499872)
			(layers "*.Cu" "*.Mask")
			(remove_unused_layers no)
			(net "GND")
			(clearance 0.0508)
			(thermal_gap 0.0508)
		)
		(pad "D6" thru_hole circle
			(at 9.99998 3.800094 180)
			(size 0.906272 0.906272)
			(drill 0.499872)
			(layers "*.Cu" "*.Mask")
			(remove_unused_layers no)
			(net "GND")
			(clearance 0.0508)
			(thermal_gap 0.0508)
		)
		(pad "D8" thru_hole circle
			(at 13.999972 3.800094 180)
			(size 0.906272 0.906272)
			(drill 0.499872)
			(layers "*.Cu" "*.Mask")
			(remove_unused_layers no)
			(net "GND")
			(clearance 0.0508)
			(thermal_gap 0.0508)
		)
		(pad "E1" thru_hole circle
			(at 0 4.800092 180)
			(size 0.906272 0.906272)
			(drill 0.499872)
			(layers "*.Cu" "*.Mask")
			(remove_unused_layers no)
			(net "GND")
			(clearance 0.0508)
			(thermal_gap 0.0508)
		)
		(pad "E3" thru_hole circle
			(at 3.999992 4.800092 180)
			(size 0.906272 0.906272)
			(drill 0.499872)
			(layers "*.Cu" "*.Mask")
			(remove_unused_layers no)
			(net "GND")
			(clearance 0.0508)
			(thermal_gap 0.0508)
		)
		(pad "E5" thru_hole circle
			(at 7.999984 4.800092 180)
			(size 0.906272 0.906272)
			(drill 0.499872)
			(layers "*.Cu" "*.Mask")
			(remove_unused_layers no)
			(net "GND")
			(clearance 0.0508)
			(thermal_gap 0.0508)
		)
		(pad "E7" thru_hole circle
			(at 11.999976 4.800092 180)
			(size 0.906272 0.906272)
			(drill 0.499872)
			(layers "*.Cu" "*.Mask")
			(remove_unused_layers no)
			(net "GND")
			(clearance 0.0508)
			(thermal_gap 0.0508)
		)
		(pad "G2" thru_hole circle
			(at 1.999996 7.400036 180)
			(size 0.906272 0.906272)
			(drill 0.499872)
			(layers "*.Cu" "*.Mask")
			(remove_unused_layers no)
			(net "GND")
			(clearance 0.0508)
			(thermal_gap 0.0508)
		)
		(pad "G4" thru_hole circle
			(at 5.999988 7.400036 180)
			(size 0.906272 0.906272)
			(drill 0.499872)
			(layers "*.Cu" "*.Mask")
			(remove_unused_layers no)
			(net "GND")
			(clearance 0.0508)
			(thermal_gap 0.0508)
		)
		(pad "G6" thru_hole circle
			(at 9.99998 7.400036 180)
			(size 0.906272 0.906272)
			(drill 0.499872)
			(layers "*.Cu" "*.Mask")
			(remove_unused_layers no)
			(net "GND")
			(clearance 0.0508)
			(thermal_gap 0.0508)
		)
		(pad "G8" thru_hole circle
			(at 13.999972 7.400036 180)
			(size 0.906272 0.906272)
			(drill 0.499872)
			(layers "*.Cu" "*.Mask")
			(remove_unused_layers no)
			(net "GND")
			(clearance 0.0508)
			(thermal_gap 0.0508)
		)
		(pad "H1" thru_hole circle
			(at 0 8.400034 180)
			(size 0.906272 0.906272)
			(drill 0.499872)
			(layers "*.Cu" "*.Mask")
			(remove_unused_layers no)
			(net "GND")
			(clearance 0.0508)
			(thermal_gap 0.0508)
		)
		(pad "H3" thru_hole circle
			(at 3.999992 8.400034 180)
			(size 0.906272 0.906272)
			(drill 0.499872)
			(layers "*.Cu" "*.Mask")
			(remove_unused_layers no)
			(net "GND")
			(clearance 0.0508)
			(thermal_gap 0.0508)
		)
		(pad "H5" thru_hole circle
			(at 7.999984 8.400034 180)
			(size 0.906272 0.906272)
			(drill 0.499872)
			(layers "*.Cu" "*.Mask")
			(remove_unused_layers no)
			(net "GND")
			(clearance 0.0508)
			(thermal_gap 0.0508)
		)
		(pad "H7" thru_hole circle
			(at 11.999976 8.400034 180)
			(size 0.906272 0.906272)
			(drill 0.499872)
			(layers "*.Cu" "*.Mask")
			(remove_unused_layers no)
			(net "GND")
			(clearance 0.0508)
			(thermal_gap 0.0508)
		)
		(pad "J2" thru_hole circle
			(at 1.999996 10.999978 180)
			(size 0.906272 0.906272)
			(drill 0.499872)
			(layers "*.Cu" "*.Mask")
			(remove_unused_layers no)
			(net "GND")
			(clearance 0.0508)
			(thermal_gap 0.0508)
		)
		(pad "J4" thru_hole circle
			(at 5.999988 10.999978 180)
			(size 0.906272 0.906272)
			(drill 0.499872)
			(layers "*.Cu" "*.Mask")
			(remove_unused_layers no)
			(net "GND")
			(clearance 0.0508)
			(thermal_gap 0.0508)
		)
		(pad "J6" thru_hole circle
			(at 9.99998 10.999978 180)
			(size 0.906272 0.906272)
			(drill 0.499872)
			(layers "*.Cu" "*.Mask")
			(remove_unused_layers no)
			(net "GND")
			(clearance 0.0508)
			(thermal_gap 0.0508)
		)
		(pad "J8" thru_hole circle
			(at 13.999972 10.999978 180)
			(size 0.906272 0.906272)
			(drill 0.499872)
			(layers "*.Cu" "*.Mask")
			(remove_unused_layers no)
			(net "GND")
			(clearance 0.0508)
			(thermal_gap 0.0508)
		)
		(pad "K1" thru_hole circle
			(at 0 11.999976 180)
			(size 0.906272 0.906272)
			(drill 0.499872)
			(layers "*.Cu" "*.Mask")
			(remove_unused_layers no)
			(net "GND")
			(clearance 0.0508)
			(thermal_gap 0.0508)
		)
		(pad "K3" thru_hole circle
			(at 3.999992 11.999976 180)
			(size 0.906272 0.906272)
			(drill 0.499872)
			(layers "*.Cu" "*.Mask")
			(remove_unused_layers no)
			(net "GND")
			(clearance 0.0508)
			(thermal_gap 0.0508)
		)
		(pad "K5" thru_hole circle
			(at 7.999984 11.999976 180)
			(size 0.906272 0.906272)
			(drill 0.499872)
			(layers "*.Cu" "*.Mask")
			(remove_unused_layers no)
			(net "GND")
			(clearance 0.0508)
			(thermal_gap 0.0508)
		)
		(pad "K7" thru_hole circle
			(at 11.999976 11.999976 180)
			(size 0.906272 0.906272)
			(drill 0.499872)
			(layers "*.Cu" "*.Mask")
			(remove_unused_layers no)
			(net "GND")
			(clearance 0.0508)
			(thermal_gap 0.0508)
		)
		(pad "M2" thru_hole circle
			(at 1.999996 14.59992 180)
			(size 0.906272 0.906272)
			(drill 0.499872)
			(layers "*.Cu" "*.Mask")
			(remove_unused_layers no)
			(net "GND")
			(clearance 0.0508)
			(thermal_gap 0.0508)
		)
		(pad "M4" thru_hole circle
			(at 5.999988 14.59992 180)
			(size 0.906272 0.906272)
			(drill 0.499872)
			(layers "*.Cu" "*.Mask")
			(remove_unused_layers no)
			(net "GND")
			(clearance 0.0508)
			(thermal_gap 0.0508)
		)
		(pad "M6" thru_hole circle
			(at 9.99998 14.59992 180)
			(size 0.906272 0.906272)
			(drill 0.499872)
			(layers "*.Cu" "*.Mask")
			(remove_unused_layers no)
			(net "GND")
			(clearance 0.0508)
			(thermal_gap 0.0508)
		)
		(pad "M8" thru_hole circle
			(at 13.999972 14.59992 180)
			(size 0.906272 0.906272)
			(drill 0.499872)
			(layers "*.Cu" "*.Mask")
			(remove_unused_layers no)
			(net "GND")
			(clearance 0.0508)
			(thermal_gap 0.0508)
		)
		(pad "N1" thru_hole circle
			(at 0 15.599918 180)
			(size 0.906272 0.906272)
			(drill 0.499872)
			(layers "*.Cu" "*.Mask")
			(remove_unused_layers no)
			(net "GND")
			(clearance 0.0508)
			(thermal_gap 0.0508)
		)
		(pad "N2" thru_hole circle
			(at 1.999996 15.80007 180)
			(size 0.766318 0.766318)
			(drill 0.359918)
			(layers "*.Cu" "*.Mask")
			(remove_unused_layers no)
			(net "FM_SWB_PWR_EN_R_BUF")
			(clearance 0.0508)
			(thermal_gap 0.0508)
		)
		(pad "N3" thru_hole circle
			(at 3.999992 15.599918 180)
			(size 0.906272 0.906272)
			(drill 0.499872)
			(layers "*.Cu" "*.Mask")
			(remove_unused_layers no)
			(net "GND")
			(clearance 0.0508)
			(thermal_gap 0.0508)
		)
		(pad "N4" thru_hole circle
			(at 5.999988 15.80007 180)
			(size 0.766318 0.766318)
			(drill 0.359918)
			(layers "*.Cu" "*.Mask")
			(remove_unused_layers no)
			(net "FM_SWB_BIC_READY_N")
			(clearance 0.0508)
			(thermal_gap 0.0508)
		)
		(pad "N5" thru_hole circle
			(at 7.999984 15.599918 180)
			(size 0.906272 0.906272)
			(drill 0.499872)
			(layers "*.Cu" "*.Mask")
			(remove_unused_layers no)
			(net "GND")
			(clearance 0.0508)
			(thermal_gap 0.0508)
		)
		(pad "N6" thru_hole circle
			(at 9.99998 15.80007 180)
			(size 0.766318 0.766318)
			(drill 0.359918)
			(layers "*.Cu" "*.Mask")
			(remove_unused_layers no)
			(net "RST_SWB_BIC_BUF_N")
			(clearance 0.0508)
			(thermal_gap 0.0508)
		)
		(pad "N7" thru_hole circle
			(at 11.999976 15.599918 180)
			(size 0.906272 0.906272)
			(drill 0.499872)
			(layers "*.Cu" "*.Mask")
			(remove_unused_layers no)
			(net "GND")
			(clearance 0.0508)
			(thermal_gap 0.0508)
		)
		(pad "N8" thru_hole circle
			(at 13.999972 15.80007 180)
			(size 0.766318 0.766318)
			(drill 0.359918)
			(layers "*.Cu" "*.Mask")
			(remove_unused_layers no)
			(net "RST_BMC_FROM_SWB_N")
			(clearance 0.0508)
			(thermal_gap 0.0508)
		)
	)
	(footprint ""
		(layer "F.Cu")
		(at 255.68275 -99.563174)
		(property "Reference" "U13"
			(at 3.232404 -8.016748 0)
			(unlocked yes)
			(layer "F.SilkS")
			(effects
				(font
					(size 0.7874 0.5842)
					(thickness 0.1524)
				)
				(justify left)
			)
		)
		(property "Value" ""
			(at 0 0 0)
			(layer "F.Fab")
			(effects
				(font
					(size 1.27 1.27)
				)
			)
		)
		(duplicate_pad_numbers_are_jumpers no)
		(fp_line
			(start -3.999992 -3.999992)
			(end -3.999992 -3.4798)
			(stroke
				(width 0.1524)
				(type default)
			)
			(layer "F.SilkS")
		)
		(fp_line
			(start -3.999992 3.4798)
			(end -3.999992 3.999992)
			(stroke
				(width 0.1524)
				(type default)
			)
			(layer "F.SilkS")
		)
		(fp_line
			(start -3.999992 3.999992)
			(end -3.4798 3.999992)
			(stroke
				(width 0.1524)
				(type default)
			)
			(layer "F.SilkS")
		)
		(fp_line
			(start -3.4798 -3.999992)
			(end -3.999992 -3.999992)
			(stroke
				(width 0.1524)
				(type default)
			)
			(layer "F.SilkS")
		)
		(fp_line
			(start 3.4798 3.999992)
			(end 3.999992 3.999992)
			(stroke
				(width 0.1524)
				(type default)
			)
			(layer "F.SilkS")
		)
		(fp_line
			(start 3.999992 -3.999992)
			(end 3.4798 -3.999992)
			(stroke
				(width 0.1524)
				(type default)
			)
			(layer "F.SilkS")
		)
		(fp_line
			(start 3.999992 -3.4798)
			(end 3.999992 -3.999992)
			(stroke
				(width 0.1524)
				(type default)
			)
			(layer "F.SilkS")
		)
		(fp_line
			(start 3.999992 3.999992)
			(end 3.999992 3.4798)
			(stroke
				(width 0.1524)
				(type default)
			)
			(layer "F.SilkS")
		)
		(fp_poly
			(pts
				(xy -5.4102 -3.75793) (xy -5.4102 -2.74193) (xy -4.3942 -3.24993)
			)
			(stroke
				(width 0)
				(type default)
			)
			(fill yes)
			(layer "F.SilkS")
		)
		(fp_line
			(start -3.999992 -3.999992)
			(end -3.999992 3.999992)
			(stroke
				(width 0.1)
				(type default)
			)
			(layer "F.Fab")
		)
		(fp_line
			(start -3.999992 3.999992)
			(end 3.999992 3.999992)
			(stroke
				(width 0.1)
				(type default)
			)
			(layer "F.Fab")
		)
		(fp_line
			(start 3.999992 -3.999992)
			(end -3.999992 -3.999992)
			(stroke
				(width 0.1)
				(type default)
			)
			(layer "F.Fab")
		)
		(fp_line
			(start 3.999992 3.999992)
			(end 3.999992 -3.999992)
			(stroke
				(width 0.1)
				(type default)
			)
			(layer "F.Fab")
		)
		(fp_poly
			(pts
				(xy -5.4102 -3.75793) (xy -5.4102 -2.74193) (xy -4.3942 -3.24993)
			)
			(stroke
				(width 0)
				(type default)
			)
			(fill yes)
			(layer "F.Fab")
		)
		(pad "A1" smd rect
			(at -3.875024 -3.24993 90)
			(size 0.1778 0.5588)
			(layers "F.Cu" "F.Mask" "F.Paste")
			(net "FM_CK440Q_DEV_25M_EN")
		)
		(pad "A2" smd rect
			(at -3.875024 -2.750058 90)
			(size 0.1778 0.5588)
			(layers "F.Cu" "F.Mask" "F.Paste")
			(net "CLK_25M_CK440_CPU1_DN")
		)
		(pad "A3" smd rect
			(at -3.875024 -2.249932 90)
			(size 0.1778 0.5588)
			(layers "F.Cu" "F.Mask" "F.Paste")
			(net "CLK_25M_CK440_CPU1_DP")
		)
		(pad "A4" smd rect
			(at -3.875024 -1.75006 90)
			(size 0.1778 0.5588)
			(layers "F.Cu" "F.Mask" "F.Paste")
			(net "CLK_25M_CK440_CPU0_DN")
		)
		(pad "A5" smd rect
			(at -3.875024 -1.249934 90)
			(size 0.1778 0.5588)
			(layers "F.Cu" "F.Mask" "F.Paste")
			(net "CLK_25M_CK440_CPU0_DP")
		)
		(pad "A6" smd rect
			(at -3.875024 -0.750062 90)
			(size 0.1778 0.5588)
			(layers "F.Cu" "F.Mask" "F.Paste")
			(net "TP_CLK_CK440_PFT_OUT_DP")
		)
		(pad "A7" smd rect
			(at -3.875024 -0.249936 90)
			(size 0.1778 0.5588)
			(layers "F.Cu" "F.Mask" "F.Paste")
			(net "TP_CLK_CK440_PFT_OUT_DN")
		)
		(pad "A8" smd rect
			(at -3.875024 0.249936 90)
			(size 0.1778 0.5588)
			(layers "F.Cu" "F.Mask" "F.Paste")
			(net "TP_CLK_PFT_IN_DP")
		)
		(pad "A9" smd rect
			(at -3.875024 0.750062 90)
			(size 0.1778 0.5588)
			(layers "F.Cu" "F.Mask" "F.Paste")
			(net "TP_CLK_PFT_IN_DN")
		)
		(pad "A10" smd rect
			(at -3.875024 1.249934 90)
			(size 0.1778 0.5588)
			(layers "F.Cu" "F.Mask" "F.Paste")
			(net "SMB_HOST_CLK_3V3AUX_SCL")
		)
		(pad "A11" smd rect
			(at -3.875024 1.75006 90)
			(size 0.1778 0.5588)
			(layers "F.Cu" "F.Mask" "F.Paste")
			(net "CLK_CK440_SMB_ADDR0")
		)
		(pad "A12" smd rect
			(at -3.875024 2.249932 90)
			(size 0.1778 0.5588)
			(layers "F.Cu" "F.Mask" "F.Paste")
			(net "P3V3_AUX_CLK_GEN_VDDXTAL_CK440")
		)
		(pad "A13" smd rect
			(at -3.875024 2.750058 90)
			(size 0.1778 0.5588)
			(layers "F.Cu" "F.Mask" "F.Paste")
			(net "XTAL_CLK_GEN1_25M_X1")
		)
		(pad "A14" smd rect
			(at -3.875024 3.24993 90)
			(size 0.1778 0.5588)
			(layers "F.Cu" "F.Mask" "F.Paste")
			(net "GND")
		)
		(pad "A15" smd rect
			(at -3.24993 3.875024)
			(size 0.1778 0.5588)
			(layers "F.Cu" "F.Mask" "F.Paste")
			(net "NC_CK440_A15")
		)
		(pad "A16" smd rect
			(at -2.750058 3.875024)
			(size 0.1778 0.5588)
			(layers "F.Cu" "F.Mask" "F.Paste")
			(net "FM_CLK_CK440_SS_EN")
		)
		(pad "A17" smd rect
			(at -2.249932 3.875024)
			(size 0.1778 0.5588)
			(layers "F.Cu" "F.Mask" "F.Paste")
			(net "FM_PLD_CLKS_DEV_EN")
		)
		(pad "A18" smd rect
			(at -1.75006 3.875024)
			(size 0.1778 0.5588)
			(layers "F.Cu" "F.Mask" "F.Paste")
			(net "NC_CLK_CK440_100M6_DN")
		)
		(pad "A19" smd rect
			(at -1.249934 3.875024)
			(size 0.1778 0.5588)
			(layers "F.Cu" "F.Mask" "F.Paste")
			(net "NC_CLK_CK440_100M6_DP")
		)
		(pad "A20" smd rect
			(at -0.750062 3.875024)
			(size 0.1778 0.5588)
			(layers "F.Cu" "F.Mask" "F.Paste")
			(net "NC_CLK_CK440_100M5_DN")
		)
		(pad "A21" smd rect
			(at -0.249936 3.875024)
			(size 0.1778 0.5588)
			(layers "F.Cu" "F.Mask" "F.Paste")
			(net "NC_CLK_CK440_100M5_DP")
		)
		(pad "A22" smd rect
			(at 0.249936 3.875024)
			(size 0.1778 0.5588)
			(layers "F.Cu" "F.Mask" "F.Paste")
			(net "NC_CLK_CK440_100M4_DN")
		)
		(pad "A23" smd rect
			(at 0.750062 3.875024)
			(size 0.1778 0.5588)
			(layers "F.Cu" "F.Mask" "F.Paste")
			(net "NC_CLK_CK440_100M4_DP")
		)
		(pad "A24" smd rect
			(at 1.249934 3.875024)
			(size 0.1778 0.5588)
			(layers "F.Cu" "F.Mask" "F.Paste")
			(net "NC_CLK_CK440_100M3_DN")
		)
		(pad "A25" smd rect
			(at 1.75006 3.875024)
			(size 0.1778 0.5588)
			(layers "F.Cu" "F.Mask" "F.Paste")
			(net "NC_CLK_CK440_100M3_DP")
		)
		(pad "A26" smd rect
			(at 2.249932 3.875024)
			(size 0.1778 0.5588)
			(layers "F.Cu" "F.Mask" "F.Paste")
			(net "CK440Q_OE_3")
		)
		(pad "A27" smd rect
			(at 2.750058 3.875024)
			(size 0.1778 0.5588)
			(layers "F.Cu" "F.Mask" "F.Paste")
			(net "NC_CLK_CK440_100M2_DN")
		)
		(pad "A28" smd rect
			(at 3.24993 3.875024)
			(size 0.1778 0.5588)
			(layers "F.Cu" "F.Mask" "F.Paste")
			(net "NC_CLK_CK440_100M2_DP")
		)
		(pad "A29" smd rect
			(at 3.875024 3.24993 270)
			(size 0.1778 0.5588)
			(layers "F.Cu" "F.Mask" "F.Paste")
			(net "CK440Q_OE_2")
		)
		(pad "A30" smd rect
			(at 3.875024 2.750058 270)
			(size 0.1778 0.5588)
			(layers "F.Cu" "F.Mask" "F.Paste")
			(net "CK440Q_OE_1")
		)
		(pad "A31" smd rect
			(at 3.875024 2.249932 270)
			(size 0.1778 0.5588)
			(layers "F.Cu" "F.Mask" "F.Paste")
			(net "NC_CLK_CK440_100M1_DN")
		)
		(pad "A32" smd rect
			(at 3.875024 1.75006 270)
			(size 0.1778 0.5588)
			(layers "F.Cu" "F.Mask" "F.Paste")
			(net "NC_CLK_CK440_100M1_DP")
		)
		(pad "A33" smd rect
			(at 3.875024 1.249934 270)
			(size 0.1778 0.5588)
			(layers "F.Cu" "F.Mask" "F.Paste")
			(net "CLK_100M_DB2000_DN")
		)
		(pad "A34" smd rect
			(at 3.875024 0.750062 270)
			(size 0.1778 0.5588)
			(layers "F.Cu" "F.Mask" "F.Paste")
			(net "CLK_100M_DB2000_DP")
		)
		(pad "A35" smd rect
			(at 3.875024 0.249936 270)
			(size 0.1778 0.5588)
			(layers "F.Cu" "F.Mask" "F.Paste")
			(net "NC_CLK_CK440_MXCK8_DN")
		)
		(pad "A36" smd rect
			(at 3.875024 -0.249936 270)
			(size 0.1778 0.5588)
			(layers "F.Cu" "F.Mask" "F.Paste")
			(net "NC_CLK_CK440_MXCK8_DP")
		)
		(pad "A37" smd rect
			(at 3.875024 -0.750062 270)
			(size 0.1778 0.5588)
			(layers "F.Cu" "F.Mask" "F.Paste")
			(net "NC_CLK_CK440_MXCK7_DN")
		)
		(pad "A38" smd rect
			(at 3.875024 -1.249934 270)
			(size 0.1778 0.5588)
			(layers "F.Cu" "F.Mask" "F.Paste")
			(net "NC_CLK_CK440_MXCK7_DP")
		)
		(pad "A39" smd rect
			(at 3.875024 -1.75006 270)
			(size 0.1778 0.5588)
			(layers "F.Cu" "F.Mask" "F.Paste")
			(net "NC_CLK_CK440_MXCK6_DN")
		)
		(pad "A40" smd rect
			(at 3.875024 -2.249932 270)
			(size 0.1778 0.5588)
			(layers "F.Cu" "F.Mask" "F.Paste")
			(net "NC_CLK_CK440_MXCK6_DP")
		)
		(pad "A41" smd rect
			(at 3.875024 -2.750058 270)
			(size 0.1778 0.5588)
			(layers "F.Cu" "F.Mask" "F.Paste")
			(net "NC_CLK_CK440_MXCK5_DN")
		)
		(pad "A42" smd rect
			(at 3.875024 -3.24993 270)
			(size 0.1778 0.5588)
			(layers "F.Cu" "F.Mask" "F.Paste")
			(net "NC_CLK_CK440_MXCK5_DP")
		)
		(pad "A43" smd rect
			(at 3.24993 -3.875024)
			(size 0.1778 0.5588)
			(layers "F.Cu" "F.Mask" "F.Paste")
			(net "NC_CLK_CK440_MXCK4_DN")
		)
		(pad "A44" smd rect
			(at 2.750058 -3.875024)
			(size 0.1778 0.5588)
			(layers "F.Cu" "F.Mask" "F.Paste")
			(net "NC_CLK_CK440_MXCK4_DP")
		)
		(pad "A45" smd rect
			(at 2.249932 -3.875024)
			(size 0.1778 0.5588)
			(layers "F.Cu" "F.Mask" "F.Paste")
			(net "NC_CLK_CK440_MXCK3_DN")
		)
		(pad "A46" smd rect
			(at 1.75006 -3.875024)
			(size 0.1778 0.5588)
			(layers "F.Cu" "F.Mask" "F.Paste")
			(net "NC_CLK_CK440_MXCK3_DP")
		)
		(pad "A47" smd rect
			(at 1.249934 -3.875024)
			(size 0.1778 0.5588)
			(layers "F.Cu" "F.Mask" "F.Paste")
			(net "CLK_100M_CK440_PCH_EXTCLK_R_DN")
		)
		(pad "A48" smd rect
			(at 0.750062 -3.875024)
			(size 0.1778 0.5588)
			(layers "F.Cu" "F.Mask" "F.Paste")
			(net "CLK_100M_CK440_PCH_EXTCLK_R_DP")
		)
		(pad "A49" smd rect
			(at 0.249936 -3.875024)
			(size 0.1778 0.5588)
			(layers "F.Cu" "F.Mask" "F.Paste")
			(net "NC_CLK_CK440_MXCK1_DN")
		)
		(pad "A50" smd rect
			(at -0.249936 -3.875024)
			(size 0.1778 0.5588)
			(layers "F.Cu" "F.Mask" "F.Paste")
			(net "NC_CLK_CK440_MXCK1_DP")
		)
		(pad "A51" smd rect
			(at -0.750062 -3.875024)
			(size 0.1778 0.5588)
			(layers "F.Cu" "F.Mask" "F.Paste")
			(net "NC_CLK_CK440_MXCK0_DN")
		)
		(pad "A52" smd rect
			(at -1.249934 -3.875024)
			(size 0.1778 0.5588)
			(layers "F.Cu" "F.Mask" "F.Paste")
			(net "NC_CLK_CK440_MXCK0_DP")
		)
		(pad "A53" smd rect
			(at -1.75006 -3.875024)
			(size 0.1778 0.5588)
			(layers "F.Cu" "F.Mask" "F.Paste")
			(net "TP_CK440_SBI_DATA_OUT")
		)
		(pad "A54" smd rect
			(at -2.249932 -3.875024)
			(size 0.1778 0.5588)
			(layers "F.Cu" "F.Mask" "F.Paste")
			(net "PD_CK440_SBI_CLK")
		)
		(pad "A55" smd rect
			(at -2.750058 -3.875024)
			(size 0.1778 0.5588)
			(layers "F.Cu" "F.Mask" "F.Paste")
			(net "CLK_25M_CK440_ISCLK_REF_DN")
		)
		(pad "A56" smd rect
			(at -3.24993 -3.875024)
			(size 0.1778 0.5588)
			(layers "F.Cu" "F.Mask" "F.Paste")
			(net "CLK_25M_CK440_ISCLK_REF_DP")
		)
		(pad "B1" smd rect
			(at -3.124962 -2.500122 90)
			(size 0.2794 0.4572)
			(layers "F.Cu" "F.Mask" "F.Paste")
			(net "P3V3_AUX_CLK_GEN_VDDA25M_CK440")
		)
		(pad "B2" smd rect
			(at -3.124962 -1.999996 90)
			(size 0.2794 0.4572)
			(layers "F.Cu" "F.Mask" "F.Paste")
			(net "NC_CK440_B2")
		)
		(pad "B3" smd rect
			(at -3.124962 -1.500124 90)
			(size 0.2794 0.4572)
			(layers "F.Cu" "F.Mask" "F.Paste")
			(net "NC_CK440_B3")
		)
		(pad "B4" smd rect
			(at -3.124962 -0.999998 90)
			(size 0.2794 0.4572)
			(layers "F.Cu" "F.Mask" "F.Paste")
			(net "PU_CLK_PFT_LOST_N")
		)
		(pad "B5" smd rect
			(at -3.124962 -0.499872 90)
			(size 0.2794 0.4572)
			(layers "F.Cu" "F.Mask" "F.Paste")
			(net "NC_CK440_B5")
		)
		(pad "B6" smd rect
			(at -3.124962 0 90)
			(size 0.2794 0.4572)
			(layers "F.Cu" "F.Mask" "F.Paste")
			(net "P3V3_AUX_CLK_GEN_VDDPT_CK440")
		)
		(pad "B7" smd rect
			(at -3.124962 0.499872 90)
			(size 0.2794 0.4572)
			(layers "F.Cu" "F.Mask" "F.Paste")
			(net "NC_CK440_B7")
		)
		(pad "B8" smd rect
			(at -3.124962 0.999998 90)
			(size 0.2794 0.4572)
			(layers "F.Cu" "F.Mask" "F.Paste")
			(net "SMB_HOST_CLK_3V3AUX_SDA")
		)
		(pad "B9" smd rect
			(at -3.124962 1.500124 90)
			(size 0.2794 0.4572)
			(layers "F.Cu" "F.Mask" "F.Paste")
			(net "CLK_CK440_SMB_ADDR1")
		)
		(pad "B10" smd rect
			(at -3.124962 1.999996 90)
			(size 0.2794 0.4572)
			(layers "F.Cu" "F.Mask" "F.Paste")
			(net "GND")
		)
		(pad "B11" smd rect
			(at -3.124962 2.500122 90)
			(size 0.2794 0.4572)
			(layers "F.Cu" "F.Mask" "F.Paste")
			(net "XTAL_CLK_GEN1_25M_X2")
		)
		(pad "B12" smd rect
			(at -2.500122 3.124962)
			(size 0.2794 0.4572)
			(layers "F.Cu" "F.Mask" "F.Paste")
			(net "GND")
		)
		(pad "B13" smd rect
			(at -1.999996 3.124962)
			(size 0.2794 0.4572)
			(layers "F.Cu" "F.Mask" "F.Paste")
			(net "NC_CK440_B13")
		)
		(pad "B14" smd rect
			(at -1.500124 3.124962)
			(size 0.2794 0.4572)
			(layers "F.Cu" "F.Mask" "F.Paste")
			(net "CK440Q_OE_6")
		)
		(pad "B15" smd rect
			(at -0.999998 3.124962)
			(size 0.2794 0.4572)
			(layers "F.Cu" "F.Mask" "F.Paste")
			(net "CK440Q_OE_5")
		)
		(pad "B16" smd rect
			(at -0.499872 3.124962)
			(size 0.2794 0.4572)
			(layers "F.Cu" "F.Mask" "F.Paste")
			(net "NC_CK440_B16")
		)
		(pad "B17" smd rect
			(at 0 3.124962)
			(size 0.2794 0.4572)
			(layers "F.Cu" "F.Mask" "F.Paste")
			(net "P3V3_AUX_CLK_GEN_VDDA100M_CK440")
		)
		(pad "B18" smd rect
			(at 0.499872 3.124962)
			(size 0.2794 0.4572)
			(layers "F.Cu" "F.Mask" "F.Paste")
			(net "NC_CK440_B18")
		)
		(pad "B19" smd rect
			(at 0.999998 3.124962)
			(size 0.2794 0.4572)
			(layers "F.Cu" "F.Mask" "F.Paste")
			(net "CK440Q_OE_4")
		)
		(pad "B20" smd rect
			(at 1.500124 3.124962)
			(size 0.2794 0.4572)
			(layers "F.Cu" "F.Mask" "F.Paste")
			(net "NC_CK440_B20")
		)
		(pad "B21" smd rect
			(at 1.999996 3.124962)
			(size 0.2794 0.4572)
			(layers "F.Cu" "F.Mask" "F.Paste")
			(net "P3V3_AUX_CLK_GEN_VDD_CK440")
		)
		(pad "B22" smd rect
			(at 2.500122 3.124962)
			(size 0.2794 0.4572)
			(layers "F.Cu" "F.Mask" "F.Paste")
			(net "NC_CK440_B22")
		)
		(pad "B23" smd rect
			(at 3.124962 2.500122 270)
			(size 0.2794 0.4572)
			(layers "F.Cu" "F.Mask" "F.Paste")
			(net "P3V3_AUX_CLK_GEN_VDD_CK440")
		)
		(pad "B24" smd rect
			(at 3.124962 1.999996 270)
			(size 0.2794 0.4572)
			(layers "F.Cu" "F.Mask" "F.Paste")
			(net "NC_CK440_B24")
		)
		(pad "B25" smd rect
			(at 3.124962 1.500124 270)
			(size 0.2794 0.4572)
			(layers "F.Cu" "F.Mask" "F.Paste")
			(net "NC_CK440_B25")
		)
		(pad "B26" smd rect
			(at 3.124962 0.999998 270)
			(size 0.2794 0.4572)
			(layers "F.Cu" "F.Mask" "F.Paste")
			(net "NC_CK440_B26")
		)
		(pad "B27" smd rect
			(at 3.124962 0.499872 270)
			(size 0.2794 0.4572)
			(layers "F.Cu" "F.Mask" "F.Paste")
			(net "FM_CLK_GEN1_OE0_N")
		)
		(pad "B28" smd rect
			(at 3.124962 0 270)
			(size 0.2794 0.4572)
			(layers "F.Cu" "F.Mask" "F.Paste")
			(net "NC_CK440_B28")
		)
		(pad "B29" smd rect
			(at 3.124962 -0.499872 270)
			(size 0.2794 0.4572)
			(layers "F.Cu" "F.Mask" "F.Paste")
			(net "P3V3_AUX_CLK_GEN_VDDMXCK_CK440")
		)
		(pad "B30" smd rect
			(at 3.124962 -0.999998 270)
			(size 0.2794 0.4572)
			(layers "F.Cu" "F.Mask" "F.Paste")
			(net "NC_CK440_B30")
		)
		(pad "B31" smd rect
			(at 3.124962 -1.500124 270)
			(size 0.2794 0.4572)
			(layers "F.Cu" "F.Mask" "F.Paste")
			(net "NC_CK440_B31")
		)
		(pad "B32" smd rect
			(at 3.124962 -1.999996 270)
			(size 0.2794 0.4572)
			(layers "F.Cu" "F.Mask" "F.Paste")
			(net "P3V3_AUX_CLK_GEN_VDDMXCK_CK440")
		)
		(pad "B33" smd rect
			(at 3.124962 -2.500122 270)
			(size 0.2794 0.4572)
			(layers "F.Cu" "F.Mask" "F.Paste")
			(net "NC_CK440_B33")
		)
		(pad "B34" smd rect
			(at 2.500122 -3.124962)
			(size 0.2794 0.4572)
			(layers "F.Cu" "F.Mask" "F.Paste")
			(net "NC_CK440_B34")
		)
		(pad "B35" smd rect
			(at 1.999996 -3.124962)
			(size 0.2794 0.4572)
			(layers "F.Cu" "F.Mask" "F.Paste")
			(net "P3V3_AUX_CLK_GEN_VDDMXCK_CK440")
		)
		(pad "B36" smd rect
			(at 1.500124 -3.124962)
			(size 0.2794 0.4572)
			(layers "F.Cu" "F.Mask" "F.Paste")
			(net "NC_CK440_B36")
		)
		(pad "B37" smd rect
			(at 0.999998 -3.124962)
			(size 0.2794 0.4572)
			(layers "F.Cu" "F.Mask" "F.Paste")
			(net "NC_CK440_B37")
		)
		(pad "B38" smd rect
			(at 0.499872 -3.124962)
			(size 0.2794 0.4572)
			(layers "F.Cu" "F.Mask" "F.Paste")
			(net "FM_CK440_MXCK_25M_100M")
		)
		(pad "B39" smd rect
			(at 0 -3.124962)
			(size 0.2794 0.4572)
			(layers "F.Cu" "F.Mask" "F.Paste")
			(net "NC_CK440_B39")
		)
		(pad "B40" smd rect
			(at -0.499872 -3.124962)
			(size 0.2794 0.4572)
			(layers "F.Cu" "F.Mask" "F.Paste")
			(net "P3V3_AUX_CLK_GEN_VDDMXCK_CK440")
		)
		(pad "B41" smd rect
			(at -0.999998 -3.124962)
			(size 0.2794 0.4572)
			(layers "F.Cu" "F.Mask" "F.Paste")
			(net "NC_CK440_B41")
		)
		(pad "B42" smd rect
			(at -1.500124 -3.124962)
			(size 0.2794 0.4572)
			(layers "F.Cu" "F.Mask" "F.Paste")
			(net "PU_CK440_SHFT_LD_N")
		)
		(pad "B43" smd rect
			(at -1.999996 -3.124962)
			(size 0.2794 0.4572)
			(layers "F.Cu" "F.Mask" "F.Paste")
			(net "PD_CK440_SBI_DATA_IN")
		)
		(pad "B44" smd rect
			(at -2.500122 -3.124962)
			(size 0.2794 0.4572)
			(layers "F.Cu" "F.Mask" "F.Paste")
			(net "NC_CK440_B44")
		)
		(pad "C1" smd circle
			(at 0 0)
			(size 0 0)
			(layers "F.Cu" "F.Mask" "F.Paste")
			(net "GND")
		)
	)
	(footprint ""
		(layer "F.Cu")
		(at 364.82782 -333.804514 -90)
		(property "Reference" "PC277_P0_3"
			(at 0 0 270)
			(layer "F.SilkS")
			(hide yes)
			(effects
				(font
					(size 1.27 1.27)
				)
			)
		)
		(property "Value" ""
			(at 0 0 270)
			(layer "F.Fab")
			(effects
				(font
					(size 1.27 1.27)
				)
			)
		)
		(duplicate_pad_numbers_are_jumpers no)
		(fp_line
			(start -0.7874 0.4064)
			(end -0.7874 -0.4064)
			(stroke
				(width 0.1524)
				(type default)
			)
			(layer "F.SilkS")
		)
		(fp_line
			(start 0.7874 0.4064)
			(end -0.7874 0.4064)
			(stroke
				(width 0.1524)
				(type default)
			)
			(layer "F.SilkS")
		)
		(fp_line
			(start -0.7874 -0.4064)
			(end 0.7874 -0.4064)
			(stroke
				(width 0.1524)
				(type default)
			)
			(layer "F.SilkS")
		)
		(fp_line
			(start 0.7874 -0.4064)
			(end 0.7874 0.4064)
			(stroke
				(width 0.1524)
				(type default)
			)
			(layer "F.SilkS")
		)
		(fp_line
			(start -0.67945 0.3048)
			(end -0.67945 -0.305054)
			(stroke
				(width 0.1)
				(type default)
			)
			(layer "F.Fab")
		)
		(fp_line
			(start -0.12065 0.3048)
			(end -0.67945 0.3048)
			(stroke
				(width 0.1)
				(type default)
			)
			(layer "F.Fab")
		)
		(fp_line
			(start 0.120396 0.3048)
			(end 0.120396 0.2794)
			(stroke
				(width 0.1)
				(type default)
			)
			(layer "F.Fab")
		)
		(fp_line
			(start 0.67945 0.3048)
			(end 0.120396 0.3048)
			(stroke
				(width 0.1)
				(type default)
			)
			(layer "F.Fab")
		)
		(fp_line
			(start -0.12065 0.2794)
			(end -0.12065 0.3048)
			(stroke
				(width 0.1)
				(type default)
			)
			(layer "F.Fab")
		)
		(fp_line
			(start 0.120396 0.2794)
			(end -0.12065 0.2794)
			(stroke
				(width 0.1)
				(type default)
			)
			(layer "F.Fab")
		)
		(fp_line
			(start -0.12065 -0.2794)
			(end 0.12065 -0.2794)
			(stroke
				(width 0.1)
				(type default)
			)
			(layer "F.Fab")
		)
		(fp_line
			(start 0.12065 -0.2794)
			(end 0.12065 -0.3048)
			(stroke
				(width 0.1)
				(type default)
			)
			(layer "F.Fab")
		)
		(fp_line
			(start 0.12065 -0.3048)
			(end 0.67945 -0.3048)
			(stroke
				(width 0.1)
				(type default)
			)
			(layer "F.Fab")
		)
		(fp_line
			(start 0.67945 -0.3048)
			(end 0.67945 0.3048)
			(stroke
				(width 0.1)
				(type default)
			)
			(layer "F.Fab")
		)
		(fp_line
			(start -0.67945 -0.305054)
			(end -0.12065 -0.305054)
			(stroke
				(width 0.1)
				(type default)
			)
			(layer "F.Fab")
		)
		(fp_line
			(start -0.12065 -0.305054)
			(end -0.12065 -0.2794)
			(stroke
				(width 0.1)
				(type default)
			)
			(layer "F.Fab")
		)
		(pad "1" smd circle
			(at -0.40005 0 270)
			(size 0 0)
			(layers "F.Cu" "F.Mask" "F.Paste")
			(net "SW_P12V_PVCCIN_CPU0_FLT")
		)
		(pad "2" smd circle
			(at 0.40005 0 270)
			(size 0 0)
			(layers "F.Cu" "F.Mask" "F.Paste")
			(net "GND")
		)
	)
	(footprint ""
		(layer "F.Cu")
		(at 294.62222 -421.41521 90)
		(property "Reference" "R4153"
			(at 0 0 90)
			(layer "F.SilkS")
			(hide yes)
			(effects
				(font
					(size 1.27 1.27)
				)
			)
		)
		(property "Value" ""
			(at 0 0 90)
			(layer "F.Fab")
			(effects
				(font
					(size 1.27 1.27)
				)
			)
		)
		(duplicate_pad_numbers_are_jumpers no)
		(fp_line
			(start 0.7874 -0.4064)
			(end 0.7874 0.4064)
			(stroke
				(width 0.1524)
				(type default)
			)
			(layer "F.SilkS")
		)
		(fp_line
			(start -0.7874 -0.4064)
			(end 0.7874 -0.4064)
			(stroke
				(width 0.1524)
				(type default)
			)
			(layer "F.SilkS")
		)
		(fp_line
			(start 0.7874 0.4064)
			(end -0.7874 0.4064)
			(stroke
				(width 0.1524)
				(type default)
			)
			(layer "F.SilkS")
		)
		(fp_line
			(start -0.7874 0.4064)
			(end -0.7874 -0.4064)
			(stroke
				(width 0.1524)
				(type default)
			)
			(layer "F.SilkS")
		)
		(fp_line
			(start -0.12065 -0.305054)
			(end -0.12065 -0.2794)
			(stroke
				(width 0.1)
				(type default)
			)
			(layer "F.Fab")
		)
		(fp_line
			(start -0.67945 -0.305054)
			(end -0.12065 -0.305054)
			(stroke
				(width 0.1)
				(type default)
			)
			(layer "F.Fab")
		)
		(fp_line
			(start 0.67945 -0.3048)
			(end 0.67945 0.3048)
			(stroke
				(width 0.1)
				(type default)
			)
			(layer "F.Fab")
		)
		(fp_line
			(start 0.12065 -0.3048)
			(end 0.67945 -0.3048)
			(stroke
				(width 0.1)
				(type default)
			)
			(layer "F.Fab")
		)
		(fp_line
			(start 0.12065 -0.2794)
			(end 0.12065 -0.3048)
			(stroke
				(width 0.1)
				(type default)
			)
			(layer "F.Fab")
		)
		(fp_line
			(start -0.12065 -0.2794)
			(end 0.12065 -0.2794)
			(stroke
				(width 0.1)
				(type default)
			)
			(layer "F.Fab")
		)
		(fp_line
			(start 0.120396 0.2794)
			(end -0.12065 0.2794)
			(stroke
				(width 0.1)
				(type default)
			)
			(layer "F.Fab")
		)
		(fp_line
			(start -0.12065 0.2794)
			(end -0.12065 0.3048)
			(stroke
				(width 0.1)
				(type default)
			)
			(layer "F.Fab")
		)
		(fp_line
			(start 0.67945 0.3048)
			(end 0.120396 0.3048)
			(stroke
				(width 0.1)
				(type default)
			)
			(layer "F.Fab")
		)
		(fp_line
			(start 0.120396 0.3048)
			(end 0.120396 0.2794)
			(stroke
				(width 0.1)
				(type default)
			)
			(layer "F.Fab")
		)
		(fp_line
			(start -0.12065 0.3048)
			(end -0.67945 0.3048)
			(stroke
				(width 0.1)
				(type default)
			)
			(layer "F.Fab")
		)
		(fp_line
			(start -0.67945 0.3048)
			(end -0.67945 -0.305054)
			(stroke
				(width 0.1)
				(type default)
			)
			(layer "F.Fab")
		)
		(pad "1" smd circle
			(at -0.40005 0 90)
			(size 0 0)
			(layers "F.Cu" "F.Mask" "F.Paste")
			(net "P3V3_AUX")
		)
		(pad "2" smd circle
			(at 0.40005 0 90)
			(size 0 0)
			(layers "F.Cu" "F.Mask" "F.Paste")
			(net "PRSNT_CABLE_GPU_A1_N")
		)
	)
	(footprint ""
		(layer "F.Cu")
		(at 158.901384 -43.832526 90)
		(property "Reference" "R4471"
			(at 0 0 90)
			(layer "F.SilkS")
			(hide yes)
			(effects
				(font
					(size 1.27 1.27)
				)
			)
		)
		(property "Value" ""
			(at 0 0 90)
			(layer "F.Fab")
			(effects
				(font
					(size 1.27 1.27)
				)
			)
		)
		(duplicate_pad_numbers_are_jumpers no)
		(fp_line
			(start 0.7874 -0.4064)
			(end 0.7874 0.4064)
			(stroke
				(width 0.1524)
				(type default)
			)
			(layer "F.SilkS")
		)
		(fp_line
			(start -0.7874 -0.4064)
			(end 0.7874 -0.4064)
			(stroke
				(width 0.1524)
				(type default)
			)
			(layer "F.SilkS")
		)
		(fp_line
			(start -0.12065 -0.305054)
			(end -0.12065 -0.2794)
			(stroke
				(width 0.1)
				(type default)
			)
			(layer "F.Fab")
		)
		(fp_line
			(start -0.67945 -0.305054)
			(end -0.12065 -0.305054)
			(stroke
				(width 0.1)
				(type default)
			)
			(layer "F.Fab")
		)
		(fp_line
			(start 0.67945 -0.3048)
			(end 0.67945 0.3048)
			(stroke
				(width 0.1)
				(type default)
			)
			(layer "F.Fab")
		)
		(fp_line
			(start 0.12065 -0.3048)
			(end 0.67945 -0.3048)
			(stroke
				(width 0.1)
				(type default)
			)
			(layer "F.Fab")
		)
		(fp_line
			(start 0.12065 -0.2794)
			(end 0.12065 -0.3048)
			(stroke
				(width 0.1)
				(type default)
			)
			(layer "F.Fab")
		)
		(fp_line
			(start -0.12065 -0.2794)
			(end 0.12065 -0.2794)
			(stroke
				(width 0.1)
				(type default)
			)
			(layer "F.Fab")
		)
		(fp_line
			(start 0.120396 0.2794)
			(end -0.12065 0.2794)
			(stroke
				(width 0.1)
				(type default)
			)
			(layer "F.Fab")
		)
		(fp_line
			(start -0.12065 0.2794)
			(end -0.12065 0.3048)
			(stroke
				(width 0.1)
				(type default)
			)
			(layer "F.Fab")
		)
		(fp_line
			(start 0.67945 0.3048)
			(end 0.120396 0.3048)
			(stroke
				(width 0.1)
				(type default)
			)
			(layer "F.Fab")
		)
		(fp_line
			(start 0.120396 0.3048)
			(end 0.120396 0.2794)
			(stroke
				(width 0.1)
				(type default)
			)
			(layer "F.Fab")
		)
		(fp_line
			(start -0.12065 0.3048)
			(end -0.67945 0.3048)
			(stroke
				(width 0.1)
				(type default)
			)
			(layer "F.Fab")
		)
		(fp_line
			(start -0.67945 0.3048)
			(end -0.67945 -0.305054)
			(stroke
				(width 0.1)
				(type default)
			)
			(layer "F.Fab")
		)
		(pad "1" smd rect
			(at -0.40005 0 270)
			(size 0.4572 0.508)
			(layers "F.Cu" "F.Mask" "F.Paste")
			(net "USB2_PCH_0_R_DP")
		)
		(pad "2" smd rect
			(at 0.40005 0 270)
			(size 0.4572 0.508)
			(layers "F.Cu" "F.Mask" "F.Paste")
			(net "USB2_0_DP")
		)
	)
	(footprint ""
		(layer "F.Cu")
		(at 81.424018 -15.177262 180)
		(property "Reference" "PD108"
			(at -4.814824 -0.9271 0)
			(unlocked yes)
			(layer "F.SilkS")
			(effects
				(font
					(size 0.7874 0.5842)
					(thickness 0.1524)
				)
				(justify left)
			)
		)
		(property "Value" ""
			(at 0 0 180)
			(layer "F.Fab")
			(effects
				(font
					(size 1.27 1.27)
				)
			)
		)
		(duplicate_pad_numbers_are_jumpers no)
		(fp_line
			(start 4.107942 1.459992)
			(end -3.400044 1.459992)
			(stroke
				(width 0.1524)
				(type default)
			)
			(layer "F.SilkS")
		)
		(fp_line
			(start 4.107942 -1.459992)
			(end 4.107942 1.459992)
			(stroke
				(width 0.1524)
				(type default)
			)
			(layer "F.SilkS")
		)
		(fp_line
			(start -3.400044 1.459992)
			(end -3.400044 -1.459992)
			(stroke
				(width 0.1524)
				(type default)
			)
			(layer "F.SilkS")
		)
		(fp_line
			(start -3.400044 -1.459992)
			(end 4.107942 -1.459992)
			(stroke
				(width 0.1524)
				(type default)
			)
			(layer "F.SilkS")
		)
		(fp_rect
			(start 4.107942 -1.459992)
			(end 3.308096 1.459992)
			(stroke
				(width 0)
				(type default)
			)
			(fill yes)
			(layer "F.SilkS")
		)
		(fp_line
			(start 2.29997 1.459992)
			(end -2.29997 1.459992)
			(stroke
				(width 0.1)
				(type default)
			)
			(layer "F.Fab")
		)
		(fp_line
			(start 2.29997 -1.459992)
			(end 2.29997 1.459992)
			(stroke
				(width 0.1)
				(type default)
			)
			(layer "F.Fab")
		)
		(fp_line
			(start -2.29997 1.459992)
			(end -2.29997 -1.459992)
			(stroke
				(width 0.1)
				(type default)
			)
			(layer "F.Fab")
		)
		(fp_line
			(start -2.29997 -1.459992)
			(end 2.29997 -1.459992)
			(stroke
				(width 0.1)
				(type default)
			)
			(layer "F.Fab")
		)
		(fp_text user "-"
			(at 5.4102 0.29845 0)
			(unlocked yes)
			(layer "F.SilkS")
			(effects
				(font
					(size 1.905 1.4224)
					(thickness 0.1524)
				)
				(justify left)
			)
		)
		(fp_text user "+"
			(at -4.7752 -0.12065 180)
			(unlocked yes)
			(layer "F.SilkS")
			(effects
				(font
					(size 1.905 1.4224)
					(thickness 0.1524)
				)
				(justify left)
			)
		)
		(fp_text user "-"
			(at 5.4102 0.29845 0)
			(unlocked yes)
			(layer "F.Fab")
			(effects
				(font
					(size 1.905 1.4224)
					(thickness 0.1524)
				)
				(justify left)
			)
		)
		(fp_text user "+"
			(at -4.7752 -0.12065 180)
			(unlocked yes)
			(layer "F.Fab")
			(effects
				(font
					(size 1.905 1.4224)
					(thickness 0.1524)
				)
				(justify left)
			)
		)
		(pad "A" smd rect
			(at -1.999996 0 270)
			(size 1.7018 2.5146)
			(layers "F.Cu" "F.Mask" "F.Paste")
			(net "GND")
		)
		(pad "C" smd rect
			(at 1.999996 0 270)
			(size 1.7018 2.5146)
			(layers "F.Cu" "F.Mask" "F.Paste")
			(net "P12V_OCP_V3_2")
		)
	)
	(footprint ""
		(layer "F.Cu")
		(at 153.21788 -114.137948 180)
		(property "Reference" "R3236"
			(at 0 0 180)
			(layer "F.SilkS")
			(hide yes)
			(effects
				(font
					(size 1.27 1.27)
				)
			)
		)
		(property "Value" ""
			(at 0 0 180)
			(layer "F.Fab")
			(effects
				(font
					(size 1.27 1.27)
				)
			)
		)
		(duplicate_pad_numbers_are_jumpers no)
		(fp_line
			(start 0.7874 0.4064)
			(end -0.7874 0.4064)
			(stroke
				(width 0.1524)
				(type default)
			)
			(layer "F.SilkS")
		)
		(fp_line
			(start 0.7874 -0.4064)
			(end 0.7874 0.4064)
			(stroke
				(width 0.1524)
				(type default)
			)
			(layer "F.SilkS")
		)
		(fp_line
			(start -0.7874 0.4064)
			(end -0.7874 -0.4064)
			(stroke
				(width 0.1524)
				(type default)
			)
			(layer "F.SilkS")
		)
		(fp_line
			(start -0.7874 -0.4064)
			(end 0.7874 -0.4064)
			(stroke
				(width 0.1524)
				(type default)
			)
			(layer "F.SilkS")
		)
		(fp_line
			(start 0.67945 0.3048)
			(end 0.120396 0.3048)
			(stroke
				(width 0.1)
				(type default)
			)
			(layer "F.Fab")
		)
		(fp_line
			(start 0.67945 -0.3048)
			(end 0.67945 0.3048)
			(stroke
				(width 0.1)
				(type default)
			)
			(layer "F.Fab")
		)
		(fp_line
			(start 0.12065 -0.2794)
			(end 0.12065 -0.3048)
			(stroke
				(width 0.1)
				(type default)
			)
			(layer "F.Fab")
		)
		(fp_line
			(start 0.12065 -0.3048)
			(end 0.67945 -0.3048)
			(stroke
				(width 0.1)
				(type default)
			)
			(layer "F.Fab")
		)
		(fp_line
			(start 0.120396 0.3048)
			(end 0.120396 0.2794)
			(stroke
				(width 0.1)
				(type default)
			)
			(layer "F.Fab")
		)
		(fp_line
			(start 0.120396 0.2794)
			(end -0.12065 0.2794)
			(stroke
				(width 0.1)
				(type default)
			)
			(layer "F.Fab")
		)
		(fp_line
			(start -0.12065 0.3048)
			(end -0.67945 0.3048)
			(stroke
				(width 0.1)
				(type default)
			)
			(layer "F.Fab")
		)
		(fp_line
			(start -0.12065 0.2794)
			(end -0.12065 0.3048)
			(stroke
				(width 0.1)
				(type default)
			)
			(layer "F.Fab")
		)
		(fp_line
			(start -0.12065 -0.2794)
			(end 0.12065 -0.2794)
			(stroke
				(width 0.1)
				(type default)
			)
			(layer "F.Fab")
		)
		(fp_line
			(start -0.12065 -0.305054)
			(end -0.12065 -0.2794)
			(stroke
				(width 0.1)
				(type default)
			)
			(layer "F.Fab")
		)
		(fp_line
			(start -0.67945 0.3048)
			(end -0.67945 -0.305054)
			(stroke
				(width 0.1)
				(type default)
			)
			(layer "F.Fab")
		)
		(fp_line
			(start -0.67945 -0.305054)
			(end -0.12065 -0.305054)
			(stroke
				(width 0.1)
				(type default)
			)
			(layer "F.Fab")
		)
		(pad "1" smd circle
			(at -0.40005 0 180)
			(size 0 0)
			(layers "F.Cu" "F.Mask" "F.Paste")
			(net "RST_HP_OCP_V3_2_R_N")
		)
		(pad "2" smd circle
			(at 0.40005 0 180)
			(size 0 0)
			(layers "F.Cu" "F.Mask" "F.Paste")
			(net "RST_SMB_OCP_V3_2_N")
		)
	)
	(footprint ""
		(layer "F.Cu")
		(at 334.385412 -21.60778 -90)
		(property "Reference" "U61"
			(at -1.967738 -5.486908 0)
			(unlocked yes)
			(layer "F.SilkS")
			(effects
				(font
					(size 0.7874 0.5842)
					(thickness 0.1524)
				)
			)
		)
		(property "Value" ""
			(at 0 0 270)
			(layer "F.Fab")
			(effects
				(font
					(size 1.27 1.27)
				)
			)
		)
		(duplicate_pad_numbers_are_jumpers no)
		(fp_line
			(start -1.7272 1.1176)
			(end -1.7272 -1.1176)
			(stroke
				(width 0.1524)
				(type default)
			)
			(layer "F.SilkS")
		)
		(fp_line
			(start 1.7272 1.1176)
			(end -1.7272 1.1176)
			(stroke
				(width 0.1524)
				(type default)
			)
			(layer "F.SilkS")
		)
		(fp_line
			(start 0 -0.7366)
			(end -0.254 -1.1176)
			(stroke
				(width 0.1524)
				(type default)
			)
			(layer "F.SilkS")
		)
		(fp_line
			(start -0.254 -1.1176)
			(end -1.7272 -1.1176)
			(stroke
				(width 0.1524)
				(type default)
			)
			(layer "F.SilkS")
		)
		(fp_line
			(start 0.254 -1.1176)
			(end 0 -0.7366)
			(stroke
				(width 0.1524)
				(type default)
			)
			(layer "F.SilkS")
		)
		(fp_line
			(start 1.7272 -1.1176)
			(end 1.7272 1.1176)
			(stroke
				(width 0.1524)
				(type default)
			)
			(layer "F.SilkS")
		)
		(fp_line
			(start 1.7272 -1.1176)
			(end 0.254 -1.1176)
			(stroke
				(width 0.1524)
				(type default)
			)
			(layer "F.SilkS")
		)
		(fp_poly
			(pts
				(xy -2.699766 -0.808736) (xy -2.440686 -1.525524) (xy -1.853692 -0.90805)
			)
			(stroke
				(width 0)
				(type default)
			)
			(fill yes)
			(layer "F.SilkS")
		)
		(fp_line
			(start -1.5748 1.1176)
			(end 1.5748 1.1176)
			(stroke
				(width 0.1)
				(type default)
			)
			(layer "F.Fab")
		)
		(fp_line
			(start 1.5748 1.1176)
			(end 1.5748 -1.1176)
			(stroke
				(width 0.1)
				(type default)
			)
			(layer "F.Fab")
		)
		(fp_line
			(start -1.5748 -1.1176)
			(end -1.5748 1.1176)
			(stroke
				(width 0.1)
				(type default)
			)
			(layer "F.Fab")
		)
		(fp_line
			(start 1.5748 -1.1176)
			(end -1.5748 -1.1176)
			(stroke
				(width 0.1)
				(type default)
			)
			(layer "F.Fab")
		)
		(fp_poly
			(pts
				(xy -1.9558 -0.649986) (xy -2.7178 -0.268986) (xy -2.7178 -1.030986)
			)
			(stroke
				(width 0)
				(type default)
			)
			(fill yes)
			(layer "F.Fab")
		)
		(pad "1" smd rect
			(at -0.999998 -0.649986 180)
			(size 0.3556 1.1176)
			(layers "F.Cu" "F.Mask" "F.Paste")
			(net "RST_ESPI_RESET_N_R")
		)
		(pad "2" smd rect
			(at -0.999998 0 180)
			(size 0.3556 1.1176)
			(layers "F.Cu" "F.Mask" "F.Paste")
			(net "GND")
		)
		(pad "3" smd rect
			(at -0.999998 0.649986 180)
			(size 0.3556 1.1176)
			(layers "F.Cu" "F.Mask" "F.Paste")
			(net "RST_PLTRST_B_MUX_N")
		)
		(pad "4" smd rect
			(at 0.999998 0.649986 180)
			(size 0.3556 1.1176)
			(layers "F.Cu" "F.Mask" "F.Paste")
			(net "ESPI_BMC_LPC_RST_N")
		)
		(pad "5" smd rect
			(at 0.999998 0 180)
			(size 0.3556 1.1176)
			(layers "F.Cu" "F.Mask" "F.Paste")
			(net "PGPPA_AUX")
		)
		(pad "6" smd rect
			(at 0.999998 -0.649986 180)
			(size 0.3556 1.1176)
			(layers "F.Cu" "F.Mask" "F.Paste")
			(net "FM_ESPI_PLD_EN")
		)
	)
	(footprint ""
		(layer "F.Cu")
		(at 268.28115 -41.435274)
		(property "Reference" "JP9"
			(at -1.4097 -2.009648 0)
			(unlocked yes)
			(layer "F.SilkS")
			(effects
				(font
					(size 0.7874 0.5842)
					(thickness 0.1524)
				)
				(justify left)
			)
		)
		(property "Value" ""
			(at 0 0 0)
			(layer "F.Fab")
			(effects
				(font
					(size 1.27 1.27)
				)
			)
		)
		(duplicate_pad_numbers_are_jumpers no)
		(fp_line
			(start -1.249934 -1.320038)
			(end 1.249934 -1.320038)
			(stroke
				(width 0.1524)
				(type default)
			)
			(layer "F.SilkS")
		)
		(fp_line
			(start -1.249934 6.400038)
			(end -1.249934 -1.320038)
			(stroke
				(width 0.1524)
				(type default)
			)
			(layer "F.SilkS")
		)
		(fp_line
			(start 1.249934 -1.320038)
			(end 1.249934 6.400038)
			(stroke
				(width 0.1524)
				(type default)
			)
			(layer "F.SilkS")
		)
		(fp_line
			(start 1.249934 6.400038)
			(end -1.249934 6.400038)
			(stroke
				(width 0.1524)
				(type default)
			)
			(layer "F.SilkS")
		)
		(fp_poly
			(pts
				(xy -1.406652 0) (xy -2.13741 0.365506) (xy -2.13741 -0.365506)
			)
			(stroke
				(width 0)
				(type default)
			)
			(fill yes)
			(layer "F.SilkS")
		)
		(fp_line
			(start -1.249934 -1.320038)
			(end 1.249934 -1.320038)
			(stroke
				(width 0.1)
				(type default)
			)
			(layer "F.Fab")
		)
		(fp_line
			(start -1.249934 6.400038)
			(end -1.249934 -1.320038)
			(stroke
				(width 0.1)
				(type default)
			)
			(layer "F.Fab")
		)
		(fp_line
			(start 1.249934 -1.320038)
			(end 1.249934 6.400038)
			(stroke
				(width 0.1)
				(type default)
			)
			(layer "F.Fab")
		)
		(fp_line
			(start 1.249934 6.400038)
			(end -1.249934 6.400038)
			(stroke
				(width 0.1)
				(type default)
			)
			(layer "F.Fab")
		)
		(fp_poly
			(pts
				(xy -2.5654 -0.556514) (xy -1.452372 0) (xy -2.5654 0.556514)
			)
			(stroke
				(width 0)
				(type default)
			)
			(fill yes)
			(layer "F.Fab")
		)
		(fp_text user "3"
			(at -1.778 5.13207 0)
			(unlocked yes)
			(layer "F.SilkS")
			(effects
				(font
					(size 0.7874 0.5842)
					(thickness 0.1524)
				)
			)
		)
		(fp_text user "3"
			(at -1.1557 5.18287 0)
			(unlocked yes)
			(layer "B.SilkS")
			(effects
				(font
					(size 0.7874 0.5842)
					(thickness 0.1524)
				)
				(justify mirror)
			)
		)
		(fp_text user "1"
			(at -1.143 0.02667 0)
			(unlocked yes)
			(layer "B.SilkS")
			(effects
				(font
					(size 0.7874 0.5842)
					(thickness 0.1524)
				)
				(justify mirror)
			)
		)
		(fp_text user "3"
			(at -1.1557 5.18287 0)
			(unlocked yes)
			(layer "B.Fab")
			(effects
				(font
					(size 0.7874 0.5842)
					(thickness 0.1524)
				)
				(justify mirror)
			)
		)
		(fp_text user "1"
			(at -1.143 0.02667 0)
			(unlocked yes)
			(layer "B.Fab")
			(effects
				(font
					(size 0.7874 0.5842)
					(thickness 0.1524)
				)
				(justify mirror)
			)
		)
		(fp_text user "3"
			(at -1.778 5.13207 0)
			(unlocked yes)
			(layer "F.Fab")
			(effects
				(font
					(size 0.7874 0.5842)
					(thickness 0.1524)
				)
			)
		)
		(pad "1" thru_hole rect
			(at 0 0)
			(size 1.5494 1.5494)
			(drill 1.0414)
			(layers "*.Cu" "*.Mask")
			(remove_unused_layers no)
			(net "SMB_SML1_PMBUS_3V3AUX_PCH_SCL_1")
			(clearance 0)
			(padstack
				(mode front_inner_back)
				(layer "Inner"
					(shape circle)
					(size 1.5494 1.5494)
					(clearance 0)
				)
				(layer "B.Cu"
					(shape rect)
					(size 1.5494 1.5494)
					(clearance 0)
				)
			)
		)
		(pad "2" thru_hole circle
			(at 0 2.54)
			(size 1.5494 1.5494)
			(drill 1.0414)
			(layers "*.Cu" "*.Mask")
			(remove_unused_layers no)
			(net "GND")
			(clearance 0)
		)
		(pad "3" thru_hole circle
			(at 0 5.08)
			(size 1.5494 1.5494)
			(drill 1.0414)
			(layers "*.Cu" "*.Mask")
			(remove_unused_layers no)
			(net "SMB_SML1_PMBUS_3V3AUX_PCH_SDA_1")
			(clearance 0)
		)
	)
	(footprint ""
		(layer "F.Cu")
		(at 300.6852 -28.3464 180)
		(property "Reference" "R1203"
			(at 0 0 180)
			(layer "F.SilkS")
			(hide yes)
			(effects
				(font
					(size 1.27 1.27)
				)
			)
		)
		(property "Value" ""
			(at 0 0 180)
			(layer "F.Fab")
			(effects
				(font
					(size 1.27 1.27)
				)
			)
		)
		(duplicate_pad_numbers_are_jumpers no)
		(fp_line
			(start 0.7874 0.4064)
			(end -0.7874 0.4064)
			(stroke
				(width 0.1524)
				(type default)
			)
			(layer "F.SilkS")
		)
		(fp_line
			(start 0.7874 -0.4064)
			(end 0.7874 0.4064)
			(stroke
				(width 0.1524)
				(type default)
			)
			(layer "F.SilkS")
		)
		(fp_line
			(start -0.7874 0.4064)
			(end -0.7874 -0.4064)
			(stroke
				(width 0.1524)
				(type default)
			)
			(layer "F.SilkS")
		)
		(fp_line
			(start -0.7874 -0.4064)
			(end 0.7874 -0.4064)
			(stroke
				(width 0.1524)
				(type default)
			)
			(layer "F.SilkS")
		)
		(fp_line
			(start 0.67945 0.3048)
			(end 0.120396 0.3048)
			(stroke
				(width 0.1)
				(type default)
			)
			(layer "F.Fab")
		)
		(fp_line
			(start 0.67945 -0.3048)
			(end 0.67945 0.3048)
			(stroke
				(width 0.1)
				(type default)
			)
			(layer "F.Fab")
		)
		(fp_line
			(start 0.12065 -0.2794)
			(end 0.12065 -0.3048)
			(stroke
				(width 0.1)
				(type default)
			)
			(layer "F.Fab")
		)
		(fp_line
			(start 0.12065 -0.3048)
			(end 0.67945 -0.3048)
			(stroke
				(width 0.1)
				(type default)
			)
			(layer "F.Fab")
		)
		(fp_line
			(start 0.120396 0.3048)
			(end 0.120396 0.2794)
			(stroke
				(width 0.1)
				(type default)
			)
			(layer "F.Fab")
		)
		(fp_line
			(start 0.120396 0.2794)
			(end -0.12065 0.2794)
			(stroke
				(width 0.1)
				(type default)
			)
			(layer "F.Fab")
		)
		(fp_line
			(start -0.12065 0.3048)
			(end -0.67945 0.3048)
			(stroke
				(width 0.1)
				(type default)
			)
			(layer "F.Fab")
		)
		(fp_line
			(start -0.12065 0.2794)
			(end -0.12065 0.3048)
			(stroke
				(width 0.1)
				(type default)
			)
			(layer "F.Fab")
		)
		(fp_line
			(start -0.12065 -0.2794)
			(end 0.12065 -0.2794)
			(stroke
				(width 0.1)
				(type default)
			)
			(layer "F.Fab")
		)
		(fp_line
			(start -0.12065 -0.305054)
			(end -0.12065 -0.2794)
			(stroke
				(width 0.1)
				(type default)
			)
			(layer "F.Fab")
		)
		(fp_line
			(start -0.67945 0.3048)
			(end -0.67945 -0.305054)
			(stroke
				(width 0.1)
				(type default)
			)
			(layer "F.Fab")
		)
		(fp_line
			(start -0.67945 -0.305054)
			(end -0.12065 -0.305054)
			(stroke
				(width 0.1)
				(type default)
			)
			(layer "F.Fab")
		)
		(pad "1" smd circle
			(at -0.40005 0 180)
			(size 0 0)
			(layers "F.Cu" "F.Mask" "F.Paste")
			(net "P3V_BAT")
		)
		(pad "2" smd circle
			(at 0.40005 0 180)
			(size 0 0)
			(layers "F.Cu" "F.Mask" "F.Paste")
			(net "P3V_BAT_R")
		)
	)
	(footprint ""
		(layer "F.Cu")
		(at 223.378522 -74.510138 180)
		(property "Reference" "PC2213"
			(at 0 0 180)
			(layer "F.SilkS")
			(hide yes)
			(effects
				(font
					(size 1.27 1.27)
				)
			)
		)
		(property "Value" ""
			(at 0 0 180)
			(layer "F.Fab")
			(effects
				(font
					(size 1.27 1.27)
				)
			)
		)
		(duplicate_pad_numbers_are_jumpers no)
		(fp_line
			(start 0.7874 0.4064)
			(end -0.7874 0.4064)
			(stroke
				(width 0.1524)
				(type default)
			)
			(layer "F.SilkS")
		)
		(fp_line
			(start 0.7874 -0.4064)
			(end 0.7874 0.4064)
			(stroke
				(width 0.1524)
				(type default)
			)
			(layer "F.SilkS")
		)
		(fp_line
			(start -0.7874 0.4064)
			(end -0.7874 -0.4064)
			(stroke
				(width 0.1524)
				(type default)
			)
			(layer "F.SilkS")
		)
		(fp_line
			(start -0.7874 -0.4064)
			(end 0.7874 -0.4064)
			(stroke
				(width 0.1524)
				(type default)
			)
			(layer "F.SilkS")
		)
		(fp_line
			(start 0.67945 0.3048)
			(end 0.120396 0.3048)
			(stroke
				(width 0.1)
				(type default)
			)
			(layer "F.Fab")
		)
		(fp_line
			(start 0.67945 -0.3048)
			(end 0.67945 0.3048)
			(stroke
				(width 0.1)
				(type default)
			)
			(layer "F.Fab")
		)
		(fp_line
			(start 0.12065 -0.2794)
			(end 0.12065 -0.3048)
			(stroke
				(width 0.1)
				(type default)
			)
			(layer "F.Fab")
		)
		(fp_line
			(start 0.12065 -0.3048)
			(end 0.67945 -0.3048)
			(stroke
				(width 0.1)
				(type default)
			)
			(layer "F.Fab")
		)
		(fp_line
			(start 0.120396 0.3048)
			(end 0.120396 0.2794)
			(stroke
				(width 0.1)
				(type default)
			)
			(layer "F.Fab")
		)
		(fp_line
			(start 0.120396 0.2794)
			(end -0.12065 0.2794)
			(stroke
				(width 0.1)
				(type default)
			)
			(layer "F.Fab")
		)
		(fp_line
			(start -0.12065 0.3048)
			(end -0.67945 0.3048)
			(stroke
				(width 0.1)
				(type default)
			)
			(layer "F.Fab")
		)
		(fp_line
			(start -0.12065 0.2794)
			(end -0.12065 0.3048)
			(stroke
				(width 0.1)
				(type default)
			)
			(layer "F.Fab")
		)
		(fp_line
			(start -0.12065 -0.2794)
			(end 0.12065 -0.2794)
			(stroke
				(width 0.1)
				(type default)
			)
			(layer "F.Fab")
		)
		(fp_line
			(start -0.12065 -0.305054)
			(end -0.12065 -0.2794)
			(stroke
				(width 0.1)
				(type default)
			)
			(layer "F.Fab")
		)
		(fp_line
			(start -0.67945 0.3048)
			(end -0.67945 -0.305054)
			(stroke
				(width 0.1)
				(type default)
			)
			(layer "F.Fab")
		)
		(fp_line
			(start -0.67945 -0.305054)
			(end -0.12065 -0.305054)
			(stroke
				(width 0.1)
				(type default)
			)
			(layer "F.Fab")
		)
		(pad "1" smd circle
			(at -0.40005 0 180)
			(size 0 0)
			(layers "F.Cu" "F.Mask" "F.Paste")
			(net "P3V3_E1S_0_R")
		)
		(pad "2" smd circle
			(at 0.40005 0 180)
			(size 0 0)
			(layers "F.Cu" "F.Mask" "F.Paste")
			(net "P3V3_E1S_GATE_0")
		)
	)
	(footprint ""
		(layer "F.Cu")
		(at 175.06188 -21.173948 180)
		(property "Reference" "PC2242"
			(at 0 0 180)
			(layer "F.SilkS")
			(hide yes)
			(effects
				(font
					(size 1.27 1.27)
				)
			)
		)
		(property "Value" ""
			(at 0 0 180)
			(layer "F.Fab")
			(effects
				(font
					(size 1.27 1.27)
				)
			)
		)
		(duplicate_pad_numbers_are_jumpers no)
		(fp_line
			(start 1.524 0.762)
			(end -1.524 0.762)
			(stroke
				(width 0.1524)
				(type default)
			)
			(layer "F.SilkS")
		)
		(fp_line
			(start 1.524 -0.762)
			(end 1.524 0.762)
			(stroke
				(width 0.1524)
				(type default)
			)
			(layer "F.SilkS")
		)
		(fp_line
			(start -1.524 0.762)
			(end -1.524 -0.762)
			(stroke
				(width 0.1524)
				(type default)
			)
			(layer "F.SilkS")
		)
		(fp_line
			(start -1.524 -0.762)
			(end 1.524 -0.762)
			(stroke
				(width 0.1524)
				(type default)
			)
			(layer "F.SilkS")
		)
		(fp_line
			(start 1.1049 0.724916)
			(end 1.1049 -0.724916)
			(stroke
				(width 0.1)
				(type default)
			)
			(layer "F.Fab")
		)
		(fp_line
			(start 1.1049 -0.724916)
			(end -1.1049 -0.724916)
			(stroke
				(width 0.1)
				(type default)
			)
			(layer "F.Fab")
		)
		(fp_line
			(start -1.1049 0.724916)
			(end 1.1049 0.724916)
			(stroke
				(width 0.1)
				(type default)
			)
			(layer "F.Fab")
		)
		(fp_line
			(start -1.1049 -0.724916)
			(end -1.1049 0.724916)
			(stroke
				(width 0.1)
				(type default)
			)
			(layer "F.Fab")
		)
		(pad "1" smd rect
			(at -0.889 0)
			(size 1.016 1.27)
			(layers "F.Cu" "F.Mask" "F.Paste")
			(net "P12V_SCM_R")
		)
		(pad "2" smd rect
			(at 0.889 0)
			(size 1.016 1.27)
			(layers "F.Cu" "F.Mask" "F.Paste")
			(net "GND")
		)
	)
	(footprint ""
		(layer "F.Cu")
		(at 15.436596 -388.161276 180)
		(property "Reference" "R3288"
			(at 0 0 180)
			(layer "F.SilkS")
			(hide yes)
			(effects
				(font
					(size 1.27 1.27)
				)
			)
		)
		(property "Value" ""
			(at 0 0 180)
			(layer "F.Fab")
			(effects
				(font
					(size 1.27 1.27)
				)
			)
		)
		(duplicate_pad_numbers_are_jumpers no)
		(fp_line
			(start 0.7874 0.4064)
			(end -0.7874 0.4064)
			(stroke
				(width 0.1524)
				(type default)
			)
			(layer "F.SilkS")
		)
		(fp_line
			(start 0.7874 -0.4064)
			(end 0.7874 0.4064)
			(stroke
				(width 0.1524)
				(type default)
			)
			(layer "F.SilkS")
		)
		(fp_line
			(start -0.7874 0.4064)
			(end -0.7874 -0.4064)
			(stroke
				(width 0.1524)
				(type default)
			)
			(layer "F.SilkS")
		)
		(fp_line
			(start -0.7874 -0.4064)
			(end 0.7874 -0.4064)
			(stroke
				(width 0.1524)
				(type default)
			)
			(layer "F.SilkS")
		)
		(fp_line
			(start 0.67945 0.3048)
			(end 0.120396 0.3048)
			(stroke
				(width 0.1)
				(type default)
			)
			(layer "F.Fab")
		)
		(fp_line
			(start 0.67945 -0.3048)
			(end 0.67945 0.3048)
			(stroke
				(width 0.1)
				(type default)
			)
			(layer "F.Fab")
		)
		(fp_line
			(start 0.12065 -0.2794)
			(end 0.12065 -0.3048)
			(stroke
				(width 0.1)
				(type default)
			)
			(layer "F.Fab")
		)
		(fp_line
			(start 0.12065 -0.3048)
			(end 0.67945 -0.3048)
			(stroke
				(width 0.1)
				(type default)
			)
			(layer "F.Fab")
		)
		(fp_line
			(start 0.120396 0.3048)
			(end 0.120396 0.2794)
			(stroke
				(width 0.1)
				(type default)
			)
			(layer "F.Fab")
		)
		(fp_line
			(start 0.120396 0.2794)
			(end -0.12065 0.2794)
			(stroke
				(width 0.1)
				(type default)
			)
			(layer "F.Fab")
		)
		(fp_line
			(start -0.12065 0.3048)
			(end -0.67945 0.3048)
			(stroke
				(width 0.1)
				(type default)
			)
			(layer "F.Fab")
		)
		(fp_line
			(start -0.12065 0.2794)
			(end -0.12065 0.3048)
			(stroke
				(width 0.1)
				(type default)
			)
			(layer "F.Fab")
		)
		(fp_line
			(start -0.12065 -0.2794)
			(end 0.12065 -0.2794)
			(stroke
				(width 0.1)
				(type default)
			)
			(layer "F.Fab")
		)
		(fp_line
			(start -0.12065 -0.305054)
			(end -0.12065 -0.2794)
			(stroke
				(width 0.1)
				(type default)
			)
			(layer "F.Fab")
		)
		(fp_line
			(start -0.67945 0.3048)
			(end -0.67945 -0.305054)
			(stroke
				(width 0.1)
				(type default)
			)
			(layer "F.Fab")
		)
		(fp_line
			(start -0.67945 -0.305054)
			(end -0.12065 -0.305054)
			(stroke
				(width 0.1)
				(type default)
			)
			(layer "F.Fab")
		)
		(pad "1" smd circle
			(at -0.40005 0 180)
			(size 0 0)
			(layers "F.Cu" "F.Mask" "F.Paste")
			(net "FM_P2E_SWA")
		)
		(pad "2" smd circle
			(at 0.40005 0 180)
			(size 0 0)
			(layers "F.Cu" "F.Mask" "F.Paste")
			(net "GND")
		)
	)
	(footprint ""
		(layer "F.Cu")
		(at 59.404758 -408.517344 -90)
		(property "Reference" "C703"
			(at 0 0 270)
			(layer "F.SilkS")
			(hide yes)
			(effects
				(font
					(size 1.27 1.27)
				)
			)
		)
		(property "Value" ""
			(at 0 0 270)
			(layer "F.Fab")
			(effects
				(font
					(size 1.27 1.27)
				)
			)
		)
		(duplicate_pad_numbers_are_jumpers no)
		(fp_line
			(start -0.299974 0.150114)
			(end -0.299974 -0.150114)
			(stroke
				(width 0.1)
				(type default)
			)
			(layer "F.Fab")
		)
		(fp_line
			(start 0.299974 0.150114)
			(end -0.299974 0.150114)
			(stroke
				(width 0.1)
				(type default)
			)
			(layer "F.Fab")
		)
		(fp_line
			(start -0.299974 -0.150114)
			(end 0.299974 -0.150114)
			(stroke
				(width 0.1)
				(type default)
			)
			(layer "F.Fab")
		)
		(fp_line
			(start 0.299974 -0.150114)
			(end 0.299974 0.150114)
			(stroke
				(width 0.1)
				(type default)
			)
			(layer "F.Fab")
		)
		(pad "1" smd rect
			(at -0.2667 0 270)
			(size 0.3048 0.381)
			(layers "F.Cu" "F.Mask" "F.Paste")
			(net "P5E_CPU1_PE4_TX_C_DP<3>")
		)
		(pad "2" smd rect
			(at 0.2667 0 270)
			(size 0.3048 0.381)
			(layers "F.Cu" "F.Mask" "F.Paste")
			(net "P5E_CPU1_PE4_TX_DP<3>")
		)
	)
	(footprint ""
		(layer "F.Cu")
		(at 52.17033 -17.623536 90)
		(property "Reference" "C832"
			(at 0 0 90)
			(layer "F.SilkS")
			(hide yes)
			(effects
				(font
					(size 1.27 1.27)
				)
			)
		)
		(property "Value" ""
			(at 0 0 90)
			(layer "F.Fab")
			(effects
				(font
					(size 1.27 1.27)
				)
			)
		)
		(duplicate_pad_numbers_are_jumpers no)
		(fp_line
			(start 0.299974 -0.150114)
			(end 0.299974 0.150114)
			(stroke
				(width 0.1)
				(type default)
			)
			(layer "F.Fab")
		)
		(fp_line
			(start -0.299974 -0.150114)
			(end 0.299974 -0.150114)
			(stroke
				(width 0.1)
				(type default)
			)
			(layer "F.Fab")
		)
		(fp_line
			(start 0.299974 0.150114)
			(end -0.299974 0.150114)
			(stroke
				(width 0.1)
				(type default)
			)
			(layer "F.Fab")
		)
		(fp_line
			(start -0.299974 0.150114)
			(end -0.299974 -0.150114)
			(stroke
				(width 0.1)
				(type default)
			)
			(layer "F.Fab")
		)
		(pad "1" smd rect
			(at -0.2667 0 90)
			(size 0.3048 0.381)
			(layers "F.Cu" "F.Mask" "F.Paste")
			(net "P5E_CPU1_PE1_TX_C_DN<2>")
		)
		(pad "2" smd rect
			(at 0.2667 0 90)
			(size 0.3048 0.381)
			(layers "F.Cu" "F.Mask" "F.Paste")
			(net "P5E_CPU1_PE1_TX_DN<2>")
		)
	)
	(footprint ""
		(layer "F.Cu")
		(at 148.13788 -57.241948)
		(property "Reference" "R1703"
			(at 0 0 0)
			(layer "F.SilkS")
			(hide yes)
			(effects
				(font
					(size 1.27 1.27)
				)
			)
		)
		(property "Value" ""
			(at 0 0 0)
			(layer "F.Fab")
			(effects
				(font
					(size 1.27 1.27)
				)
			)
		)
		(duplicate_pad_numbers_are_jumpers no)
		(fp_line
			(start -0.7874 -0.4064)
			(end 0.7874 -0.4064)
			(stroke
				(width 0.1524)
				(type default)
			)
			(layer "F.SilkS")
		)
		(fp_line
			(start -0.7874 0.4064)
			(end -0.7874 -0.4064)
			(stroke
				(width 0.1524)
				(type default)
			)
			(layer "F.SilkS")
		)
		(fp_line
			(start 0.7874 -0.4064)
			(end 0.7874 0.4064)
			(stroke
				(width 0.1524)
				(type default)
			)
			(layer "F.SilkS")
		)
		(fp_line
			(start 0.7874 0.4064)
			(end -0.7874 0.4064)
			(stroke
				(width 0.1524)
				(type default)
			)
			(layer "F.SilkS")
		)
		(fp_line
			(start -0.67945 -0.305054)
			(end -0.12065 -0.305054)
			(stroke
				(width 0.1)
				(type default)
			)
			(layer "F.Fab")
		)
		(fp_line
			(start -0.67945 0.3048)
			(end -0.67945 -0.305054)
			(stroke
				(width 0.1)
				(type default)
			)
			(layer "F.Fab")
		)
		(fp_line
			(start -0.12065 -0.305054)
			(end -0.12065 -0.2794)
			(stroke
				(width 0.1)
				(type default)
			)
			(layer "F.Fab")
		)
		(fp_line
			(start -0.12065 -0.2794)
			(end 0.12065 -0.2794)
			(stroke
				(width 0.1)
				(type default)
			)
			(layer "F.Fab")
		)
		(fp_line
			(start -0.12065 0.2794)
			(end -0.12065 0.3048)
			(stroke
				(width 0.1)
				(type default)
			)
			(layer "F.Fab")
		)
		(fp_line
			(start -0.12065 0.3048)
			(end -0.67945 0.3048)
			(stroke
				(width 0.1)
				(type default)
			)
			(layer "F.Fab")
		)
		(fp_line
			(start 0.120396 0.2794)
			(end -0.12065 0.2794)
			(stroke
				(width 0.1)
				(type default)
			)
			(layer "F.Fab")
		)
		(fp_line
			(start 0.120396 0.3048)
			(end 0.120396 0.2794)
			(stroke
				(width 0.1)
				(type default)
			)
			(layer "F.Fab")
		)
		(fp_line
			(start 0.12065 -0.3048)
			(end 0.67945 -0.3048)
			(stroke
				(width 0.1)
				(type default)
			)
			(layer "F.Fab")
		)
		(fp_line
			(start 0.12065 -0.2794)
			(end 0.12065 -0.3048)
			(stroke
				(width 0.1)
				(type default)
			)
			(layer "F.Fab")
		)
		(fp_line
			(start 0.67945 -0.3048)
			(end 0.67945 0.3048)
			(stroke
				(width 0.1)
				(type default)
			)
			(layer "F.Fab")
		)
		(fp_line
			(start 0.67945 0.3048)
			(end 0.120396 0.3048)
			(stroke
				(width 0.1)
				(type default)
			)
			(layer "F.Fab")
		)
		(pad "1" smd circle
			(at -0.40005 0)
			(size 0 0)
			(layers "F.Cu" "F.Mask" "F.Paste")
			(net "P1V8_PCH_AUX")
		)
		(pad "2" smd circle
			(at 0.40005 0)
			(size 0 0)
			(layers "F.Cu" "F.Mask" "F.Paste")
			(net "SMB_M2_P0_1V8AUX_SCL_R")
		)
	)
	(footprint ""
		(layer "F.Cu")
		(at 32.761428 -102.761034)
		(property "Reference" "R2900"
			(at 0 0 0)
			(layer "F.SilkS")
			(hide yes)
			(effects
				(font
					(size 1.27 1.27)
				)
			)
		)
		(property "Value" ""
			(at 0 0 0)
			(layer "F.Fab")
			(effects
				(font
					(size 1.27 1.27)
				)
			)
		)
		(duplicate_pad_numbers_are_jumpers no)
		(fp_line
			(start -0.7874 -0.4064)
			(end 0.7874 -0.4064)
			(stroke
				(width 0.1524)
				(type default)
			)
			(layer "F.SilkS")
		)
		(fp_line
			(start -0.7874 0.4064)
			(end -0.7874 -0.4064)
			(stroke
				(width 0.1524)
				(type default)
			)
			(layer "F.SilkS")
		)
		(fp_line
			(start 0.7874 -0.4064)
			(end 0.7874 0.4064)
			(stroke
				(width 0.1524)
				(type default)
			)
			(layer "F.SilkS")
		)
		(fp_line
			(start 0.7874 0.4064)
			(end -0.7874 0.4064)
			(stroke
				(width 0.1524)
				(type default)
			)
			(layer "F.SilkS")
		)
		(fp_line
			(start -0.67945 -0.305054)
			(end -0.12065 -0.305054)
			(stroke
				(width 0.1)
				(type default)
			)
			(layer "F.Fab")
		)
		(fp_line
			(start -0.67945 0.3048)
			(end -0.67945 -0.305054)
			(stroke
				(width 0.1)
				(type default)
			)
			(layer "F.Fab")
		)
		(fp_line
			(start -0.12065 -0.305054)
			(end -0.12065 -0.2794)
			(stroke
				(width 0.1)
				(type default)
			)
			(layer "F.Fab")
		)
		(fp_line
			(start -0.12065 -0.2794)
			(end 0.12065 -0.2794)
			(stroke
				(width 0.1)
				(type default)
			)
			(layer "F.Fab")
		)
		(fp_line
			(start -0.12065 0.2794)
			(end -0.12065 0.3048)
			(stroke
				(width 0.1)
				(type default)
			)
			(layer "F.Fab")
		)
		(fp_line
			(start -0.12065 0.3048)
			(end -0.67945 0.3048)
			(stroke
				(width 0.1)
				(type default)
			)
			(layer "F.Fab")
		)
		(fp_line
			(start 0.120396 0.2794)
			(end -0.12065 0.2794)
			(stroke
				(width 0.1)
				(type default)
			)
			(layer "F.Fab")
		)
		(fp_line
			(start 0.120396 0.3048)
			(end 0.120396 0.2794)
			(stroke
				(width 0.1)
				(type default)
			)
			(layer "F.Fab")
		)
		(fp_line
			(start 0.12065 -0.3048)
			(end 0.67945 -0.3048)
			(stroke
				(width 0.1)
				(type default)
			)
			(layer "F.Fab")
		)
		(fp_line
			(start 0.12065 -0.2794)
			(end 0.12065 -0.3048)
			(stroke
				(width 0.1)
				(type default)
			)
			(layer "F.Fab")
		)
		(fp_line
			(start 0.67945 -0.3048)
			(end 0.67945 0.3048)
			(stroke
				(width 0.1)
				(type default)
			)
			(layer "F.Fab")
		)
		(fp_line
			(start 0.67945 0.3048)
			(end 0.120396 0.3048)
			(stroke
				(width 0.1)
				(type default)
			)
			(layer "F.Fab")
		)
		(pad "1" smd circle
			(at -0.40005 0)
			(size 0 0)
			(layers "F.Cu" "F.Mask" "F.Paste")
			(net "MAX11617_VREF")
		)
		(pad "2" smd circle
			(at 0.40005 0)
			(size 0 0)
			(layers "F.Cu" "F.Mask" "F.Paste")
			(net "MAX11617_VREF_R")
		)
	)
	(footprint ""
		(layer "F.Cu")
		(at 407.35377 -408.517344 -90)
		(property "Reference" "C893"
			(at 0 0 270)
			(layer "F.SilkS")
			(hide yes)
			(effects
				(font
					(size 1.27 1.27)
				)
			)
		)
		(property "Value" ""
			(at 0 0 270)
			(layer "F.Fab")
			(effects
				(font
					(size 1.27 1.27)
				)
			)
		)
		(duplicate_pad_numbers_are_jumpers no)
		(fp_line
			(start -0.299974 0.150114)
			(end -0.299974 -0.150114)
			(stroke
				(width 0.1)
				(type default)
			)
			(layer "F.Fab")
		)
		(fp_line
			(start 0.299974 0.150114)
			(end -0.299974 0.150114)
			(stroke
				(width 0.1)
				(type default)
			)
			(layer "F.Fab")
		)
		(fp_line
			(start -0.299974 -0.150114)
			(end 0.299974 -0.150114)
			(stroke
				(width 0.1)
				(type default)
			)
			(layer "F.Fab")
		)
		(fp_line
			(start 0.299974 -0.150114)
			(end 0.299974 0.150114)
			(stroke
				(width 0.1)
				(type default)
			)
			(layer "F.Fab")
		)
		(pad "1" smd rect
			(at -0.2667 0 270)
			(size 0.3048 0.381)
			(layers "F.Cu" "F.Mask" "F.Paste")
			(net "P5E_CPU0_PE3_TX_C_DP<4>")
		)
		(pad "2" smd rect
			(at 0.2667 0 270)
			(size 0.3048 0.381)
			(layers "F.Cu" "F.Mask" "F.Paste")
			(net "P5E_CPU0_PE3_TX_DP<4>")
		)
	)
	(footprint ""
		(layer "F.Cu")
		(at 170.59402 -99.466908)
		(property "Reference" "R2661"
			(at 0 0 0)
			(layer "F.SilkS")
			(hide yes)
			(effects
				(font
					(size 1.27 1.27)
				)
			)
		)
		(property "Value" ""
			(at 0 0 0)
			(layer "F.Fab")
			(effects
				(font
					(size 1.27 1.27)
				)
			)
		)
		(duplicate_pad_numbers_are_jumpers no)
		(fp_line
			(start -0.7874 -0.4064)
			(end 0.7874 -0.4064)
			(stroke
				(width 0.1524)
				(type default)
			)
			(layer "F.SilkS")
		)
		(fp_line
			(start -0.7874 0.4064)
			(end -0.7874 -0.4064)
			(stroke
				(width 0.1524)
				(type default)
			)
			(layer "F.SilkS")
		)
		(fp_line
			(start 0.7874 -0.4064)
			(end 0.7874 0.4064)
			(stroke
				(width 0.1524)
				(type default)
			)
			(layer "F.SilkS")
		)
		(fp_line
			(start 0.7874 0.4064)
			(end -0.7874 0.4064)
			(stroke
				(width 0.1524)
				(type default)
			)
			(layer "F.SilkS")
		)
		(fp_line
			(start -0.67945 -0.305054)
			(end -0.12065 -0.305054)
			(stroke
				(width 0.1)
				(type default)
			)
			(layer "F.Fab")
		)
		(fp_line
			(start -0.67945 0.3048)
			(end -0.67945 -0.305054)
			(stroke
				(width 0.1)
				(type default)
			)
			(layer "F.Fab")
		)
		(fp_line
			(start -0.12065 -0.305054)
			(end -0.12065 -0.2794)
			(stroke
				(width 0.1)
				(type default)
			)
			(layer "F.Fab")
		)
		(fp_line
			(start -0.12065 -0.2794)
			(end 0.12065 -0.2794)
			(stroke
				(width 0.1)
				(type default)
			)
			(layer "F.Fab")
		)
		(fp_line
			(start -0.12065 0.2794)
			(end -0.12065 0.3048)
			(stroke
				(width 0.1)
				(type default)
			)
			(layer "F.Fab")
		)
		(fp_line
			(start -0.12065 0.3048)
			(end -0.67945 0.3048)
			(stroke
				(width 0.1)
				(type default)
			)
			(layer "F.Fab")
		)
		(fp_line
			(start 0.120396 0.2794)
			(end -0.12065 0.2794)
			(stroke
				(width 0.1)
				(type default)
			)
			(layer "F.Fab")
		)
		(fp_line
			(start 0.120396 0.3048)
			(end 0.120396 0.2794)
			(stroke
				(width 0.1)
				(type default)
			)
			(layer "F.Fab")
		)
		(fp_line
			(start 0.12065 -0.3048)
			(end 0.67945 -0.3048)
			(stroke
				(width 0.1)
				(type default)
			)
			(layer "F.Fab")
		)
		(fp_line
			(start 0.12065 -0.2794)
			(end 0.12065 -0.3048)
			(stroke
				(width 0.1)
				(type default)
			)
			(layer "F.Fab")
		)
		(fp_line
			(start 0.67945 -0.3048)
			(end 0.67945 0.3048)
			(stroke
				(width 0.1)
				(type default)
			)
			(layer "F.Fab")
		)
		(fp_line
			(start 0.67945 0.3048)
			(end 0.120396 0.3048)
			(stroke
				(width 0.1)
				(type default)
			)
			(layer "F.Fab")
		)
		(pad "1" smd circle
			(at -0.40005 0)
			(size 0 0)
			(layers "F.Cu" "F.Mask" "F.Paste")
			(net "FM_SWB_PWR_EN")
		)
		(pad "2" smd circle
			(at 0.40005 0)
			(size 0 0)
			(layers "F.Cu" "F.Mask" "F.Paste")
			(net "FM_SWB_PWR_EN_R")
		)
	)
	(footprint ""
		(layer "F.Cu")
		(at 47.678594 -356.02418 90)
		(property "Reference" "PC396"
			(at 0 0 90)
			(layer "F.SilkS")
			(hide yes)
			(effects
				(font
					(size 1.27 1.27)
				)
			)
		)
		(property "Value" ""
			(at 0 0 90)
			(layer "F.Fab")
			(effects
				(font
					(size 1.27 1.27)
				)
			)
		)
		(duplicate_pad_numbers_are_jumpers no)
		(fp_line
			(start 0.7874 -0.4064)
			(end 0.7874 0.4064)
			(stroke
				(width 0.1524)
				(type default)
			)
			(layer "F.SilkS")
		)
		(fp_line
			(start -0.7874 -0.4064)
			(end 0.7874 -0.4064)
			(stroke
				(width 0.1524)
				(type default)
			)
			(layer "F.SilkS")
		)
		(fp_line
			(start 0.7874 0.4064)
			(end -0.7874 0.4064)
			(stroke
				(width 0.1524)
				(type default)
			)
			(layer "F.SilkS")
		)
		(fp_line
			(start -0.7874 0.4064)
			(end -0.7874 -0.4064)
			(stroke
				(width 0.1524)
				(type default)
			)
			(layer "F.SilkS")
		)
		(fp_line
			(start -0.12065 -0.305054)
			(end -0.12065 -0.2794)
			(stroke
				(width 0.1)
				(type default)
			)
			(layer "F.Fab")
		)
		(fp_line
			(start -0.67945 -0.305054)
			(end -0.12065 -0.305054)
			(stroke
				(width 0.1)
				(type default)
			)
			(layer "F.Fab")
		)
		(fp_line
			(start 0.67945 -0.3048)
			(end 0.67945 0.3048)
			(stroke
				(width 0.1)
				(type default)
			)
			(layer "F.Fab")
		)
		(fp_line
			(start 0.12065 -0.3048)
			(end 0.67945 -0.3048)
			(stroke
				(width 0.1)
				(type default)
			)
			(layer "F.Fab")
		)
		(fp_line
			(start 0.12065 -0.2794)
			(end 0.12065 -0.3048)
			(stroke
				(width 0.1)
				(type default)
			)
			(layer "F.Fab")
		)
		(fp_line
			(start -0.12065 -0.2794)
			(end 0.12065 -0.2794)
			(stroke
				(width 0.1)
				(type default)
			)
			(layer "F.Fab")
		)
		(fp_line
			(start 0.120396 0.2794)
			(end -0.12065 0.2794)
			(stroke
				(width 0.1)
				(type default)
			)
			(layer "F.Fab")
		)
		(fp_line
			(start -0.12065 0.2794)
			(end -0.12065 0.3048)
			(stroke
				(width 0.1)
				(type default)
			)
			(layer "F.Fab")
		)
		(fp_line
			(start 0.67945 0.3048)
			(end 0.120396 0.3048)
			(stroke
				(width 0.1)
				(type default)
			)
			(layer "F.Fab")
		)
		(fp_line
			(start 0.120396 0.3048)
			(end 0.120396 0.2794)
			(stroke
				(width 0.1)
				(type default)
			)
			(layer "F.Fab")
		)
		(fp_line
			(start -0.12065 0.3048)
			(end -0.67945 0.3048)
			(stroke
				(width 0.1)
				(type default)
			)
			(layer "F.Fab")
		)
		(fp_line
			(start -0.67945 0.3048)
			(end -0.67945 -0.305054)
			(stroke
				(width 0.1)
				(type default)
			)
			(layer "F.Fab")
		)
		(pad "1" smd circle
			(at -0.40005 0 90)
			(size 0 0)
			(layers "F.Cu" "F.Mask" "F.Paste")
			(net "PVCCFA_EHV_FIVRA_CPU1_VDD2")
		)
		(pad "2" smd circle
			(at 0.40005 0 90)
			(size 0 0)
			(layers "F.Cu" "F.Mask" "F.Paste")
			(net "GND")
		)
	)
	(footprint ""
		(layer "F.Cu")
		(at 70.7136 -34.788348)
		(property "Reference" "R3569"
			(at 0 0 0)
			(layer "F.SilkS")
			(hide yes)
			(effects
				(font
					(size 1.27 1.27)
				)
			)
		)
		(property "Value" ""
			(at 0 0 0)
			(layer "F.Fab")
			(effects
				(font
					(size 1.27 1.27)
				)
			)
		)
		(duplicate_pad_numbers_are_jumpers no)
		(fp_line
			(start -0.7874 -0.4064)
			(end 0.7874 -0.4064)
			(stroke
				(width 0.1524)
				(type default)
			)
			(layer "F.SilkS")
		)
		(fp_line
			(start -0.7874 0.4064)
			(end -0.7874 -0.4064)
			(stroke
				(width 0.1524)
				(type default)
			)
			(layer "F.SilkS")
		)
		(fp_line
			(start 0.7874 -0.4064)
			(end 0.7874 0.4064)
			(stroke
				(width 0.1524)
				(type default)
			)
			(layer "F.SilkS")
		)
		(fp_line
			(start 0.7874 0.4064)
			(end -0.7874 0.4064)
			(stroke
				(width 0.1524)
				(type default)
			)
			(layer "F.SilkS")
		)
		(fp_line
			(start -0.67945 -0.305054)
			(end -0.12065 -0.305054)
			(stroke
				(width 0.1)
				(type default)
			)
			(layer "F.Fab")
		)
		(fp_line
			(start -0.67945 0.3048)
			(end -0.67945 -0.305054)
			(stroke
				(width 0.1)
				(type default)
			)
			(layer "F.Fab")
		)
		(fp_line
			(start -0.12065 -0.305054)
			(end -0.12065 -0.2794)
			(stroke
				(width 0.1)
				(type default)
			)
			(layer "F.Fab")
		)
		(fp_line
			(start -0.12065 -0.2794)
			(end 0.12065 -0.2794)
			(stroke
				(width 0.1)
				(type default)
			)
			(layer "F.Fab")
		)
		(fp_line
			(start -0.12065 0.2794)
			(end -0.12065 0.3048)
			(stroke
				(width 0.1)
				(type default)
			)
			(layer "F.Fab")
		)
		(fp_line
			(start -0.12065 0.3048)
			(end -0.67945 0.3048)
			(stroke
				(width 0.1)
				(type default)
			)
			(layer "F.Fab")
		)
		(fp_line
			(start 0.120396 0.2794)
			(end -0.12065 0.2794)
			(stroke
				(width 0.1)
				(type default)
			)
			(layer "F.Fab")
		)
		(fp_line
			(start 0.120396 0.3048)
			(end 0.120396 0.2794)
			(stroke
				(width 0.1)
				(type default)
			)
			(layer "F.Fab")
		)
		(fp_line
			(start 0.12065 -0.3048)
			(end 0.67945 -0.3048)
			(stroke
				(width 0.1)
				(type default)
			)
			(layer "F.Fab")
		)
		(fp_line
			(start 0.12065 -0.2794)
			(end 0.12065 -0.3048)
			(stroke
				(width 0.1)
				(type default)
			)
			(layer "F.Fab")
		)
		(fp_line
			(start 0.67945 -0.3048)
			(end 0.67945 0.3048)
			(stroke
				(width 0.1)
				(type default)
			)
			(layer "F.Fab")
		)
		(fp_line
			(start 0.67945 0.3048)
			(end 0.120396 0.3048)
			(stroke
				(width 0.1)
				(type default)
			)
			(layer "F.Fab")
		)
		(pad "1" smd circle
			(at -0.40005 0)
			(size 0 0)
			(layers "F.Cu" "F.Mask" "F.Paste")
			(net "SMB_INA230_3_3V3AUX_SDA_R")
		)
		(pad "2" smd circle
			(at 0.40005 0)
			(size 0 0)
			(layers "F.Cu" "F.Mask" "F.Paste")
			(net "SMB_INA230_3_3V3AUX_SDA_R1")
		)
	)
	(footprint ""
		(layer "F.Cu")
		(at 86.973918 -408.517344 -90)
		(property "Reference" "C685"
			(at 0 0 270)
			(layer "F.SilkS")
			(hide yes)
			(effects
				(font
					(size 1.27 1.27)
				)
			)
		)
		(property "Value" ""
			(at 0 0 270)
			(layer "F.Fab")
			(effects
				(font
					(size 1.27 1.27)
				)
			)
		)
		(duplicate_pad_numbers_are_jumpers no)
		(fp_line
			(start -0.299974 0.150114)
			(end -0.299974 -0.150114)
			(stroke
				(width 0.1)
				(type default)
			)
			(layer "F.Fab")
		)
		(fp_line
			(start 0.299974 0.150114)
			(end -0.299974 0.150114)
			(stroke
				(width 0.1)
				(type default)
			)
			(layer "F.Fab")
		)
		(fp_line
			(start -0.299974 -0.150114)
			(end 0.299974 -0.150114)
			(stroke
				(width 0.1)
				(type default)
			)
			(layer "F.Fab")
		)
		(fp_line
			(start 0.299974 -0.150114)
			(end 0.299974 0.150114)
			(stroke
				(width 0.1)
				(type default)
			)
			(layer "F.Fab")
		)
		(pad "1" smd rect
			(at -0.2667 0 270)
			(size 0.3048 0.381)
			(layers "F.Cu" "F.Mask" "F.Paste")
			(net "P5E_CPU1_PE4_TX_C_DP<12>")
		)
		(pad "2" smd rect
			(at 0.2667 0 270)
			(size 0.3048 0.381)
			(layers "F.Cu" "F.Mask" "F.Paste")
			(net "P5E_CPU1_PE4_TX_DP<12>")
		)
	)
	(footprint ""
		(layer "F.Cu")
		(at 377.637294 -327.79335)
		(property "Reference" "PL10"
			(at 4.840986 4.553712 0)
			(unlocked yes)
			(layer "F.SilkS")
			(effects
				(font
					(size 0.7874 0.5842)
					(thickness 0.1524)
				)
				(justify left)
			)
		)
		(property "Value" ""
			(at 0 0 0)
			(layer "F.Fab")
			(effects
				(font
					(size 1.27 1.27)
				)
			)
		)
		(duplicate_pad_numbers_are_jumpers no)
		(fp_line
			(start -3.750056 -5.500116)
			(end -2.393442 -5.500116)
			(stroke
				(width 0.1524)
				(type default)
			)
			(layer "F.SilkS")
		)
		(fp_line
			(start -3.750056 5.500116)
			(end -3.750056 -5.500116)
			(stroke
				(width 0.1524)
				(type default)
			)
			(layer "F.SilkS")
		)
		(fp_line
			(start -2.393442 5.500116)
			(end -3.750056 5.500116)
			(stroke
				(width 0.1524)
				(type default)
			)
			(layer "F.SilkS")
		)
		(fp_line
			(start 2.393442 5.500116)
			(end 3.750056 5.500116)
			(stroke
				(width 0.1524)
				(type default)
			)
			(layer "F.SilkS")
		)
		(fp_line
			(start 3.750056 -5.500116)
			(end 2.393442 -5.500116)
			(stroke
				(width 0.1524)
				(type default)
			)
			(layer "F.SilkS")
		)
		(fp_line
			(start 3.750056 5.500116)
			(end 3.750056 -5.500116)
			(stroke
				(width 0.1524)
				(type default)
			)
			(layer "F.SilkS")
		)
		(fp_poly
			(pts
				(xy -4.9276 -4.757928) (xy -3.9116 -4.249928) (xy -4.9276 -3.741928)
			)
			(stroke
				(width 0)
				(type default)
			)
			(fill yes)
			(layer "F.SilkS")
		)
		(fp_line
			(start -3.750056 -5.500116)
			(end -3.750056 5.500116)
			(stroke
				(width 0.1)
				(type default)
			)
			(layer "F.Fab")
		)
		(fp_line
			(start -3.750056 5.500116)
			(end 3.750056 5.500116)
			(stroke
				(width 0.1)
				(type default)
			)
			(layer "F.Fab")
		)
		(fp_line
			(start 3.750056 -5.500116)
			(end -3.750056 -5.500116)
			(stroke
				(width 0.1)
				(type default)
			)
			(layer "F.Fab")
		)
		(fp_line
			(start 3.750056 5.500116)
			(end 3.750056 -5.500116)
			(stroke
				(width 0.1)
				(type default)
			)
			(layer "F.Fab")
		)
		(fp_poly
			(pts
				(xy -4.9276 -4.757928) (xy -4.9276 -3.741928) (xy -3.9116 -4.249928)
			)
			(stroke
				(width 0)
				(type default)
			)
			(fill yes)
			(layer "F.Fab")
		)
		(pad "1" smd rect
			(at 0 -4.249928 270)
			(size 2.413 4.5212)
			(layers "F.Cu" "F.Mask" "F.Paste")
			(net "SW_PVCCIN_CPU0_SW5")
		)
		(pad "2" smd rect
			(at 0 -1.175004 270)
			(size 1.3716 4.5212)
			(layers "F.Cu" "F.Mask" "F.Paste")
			(net "IND_P0_CPL5")
		)
		(pad "3" smd rect
			(at 0 1.175004 270)
			(size 1.3716 4.5212)
			(layers "F.Cu" "F.Mask" "F.Paste")
			(net "IND_P0_CPL8")
		)
		(pad "4" smd rect
			(at 0 4.249928 270)
			(size 2.413 4.5212)
			(layers "F.Cu" "F.Mask" "F.Paste")
			(net "PVCCIN_CPU0")
		)
	)
	(footprint ""
		(layer "F.Cu")
		(at 65.60058 -116.488718)
		(property "Reference" "C2056"
			(at 0 0 0)
			(layer "F.SilkS")
			(hide yes)
			(effects
				(font
					(size 1.27 1.27)
				)
			)
		)
		(property "Value" ""
			(at 0 0 0)
			(layer "F.Fab")
			(effects
				(font
					(size 1.27 1.27)
				)
			)
		)
		(duplicate_pad_numbers_are_jumpers no)
		(fp_line
			(start -0.7874 -0.4064)
			(end 0.7874 -0.4064)
			(stroke
				(width 0.1524)
				(type default)
			)
			(layer "F.SilkS")
		)
		(fp_line
			(start -0.7874 0.4064)
			(end -0.7874 -0.4064)
			(stroke
				(width 0.1524)
				(type default)
			)
			(layer "F.SilkS")
		)
		(fp_line
			(start 0.7874 -0.4064)
			(end 0.7874 0.4064)
			(stroke
				(width 0.1524)
				(type default)
			)
			(layer "F.SilkS")
		)
		(fp_line
			(start 0.7874 0.4064)
			(end -0.7874 0.4064)
			(stroke
				(width 0.1524)
				(type default)
			)
			(layer "F.SilkS")
		)
		(fp_line
			(start -0.67945 -0.305054)
			(end -0.12065 -0.305054)
			(stroke
				(width 0.1)
				(type default)
			)
			(layer "F.Fab")
		)
		(fp_line
			(start -0.67945 0.3048)
			(end -0.67945 -0.305054)
			(stroke
				(width 0.1)
				(type default)
			)
			(layer "F.Fab")
		)
		(fp_line
			(start -0.12065 -0.305054)
			(end -0.12065 -0.2794)
			(stroke
				(width 0.1)
				(type default)
			)
			(layer "F.Fab")
		)
		(fp_line
			(start -0.12065 -0.2794)
			(end 0.12065 -0.2794)
			(stroke
				(width 0.1)
				(type default)
			)
			(layer "F.Fab")
		)
		(fp_line
			(start -0.12065 0.2794)
			(end -0.12065 0.3048)
			(stroke
				(width 0.1)
				(type default)
			)
			(layer "F.Fab")
		)
		(fp_line
			(start -0.12065 0.3048)
			(end -0.67945 0.3048)
			(stroke
				(width 0.1)
				(type default)
			)
			(layer "F.Fab")
		)
		(fp_line
			(start 0.120396 0.2794)
			(end -0.12065 0.2794)
			(stroke
				(width 0.1)
				(type default)
			)
			(layer "F.Fab")
		)
		(fp_line
			(start 0.120396 0.3048)
			(end 0.120396 0.2794)
			(stroke
				(width 0.1)
				(type default)
			)
			(layer "F.Fab")
		)
		(fp_line
			(start 0.12065 -0.3048)
			(end 0.67945 -0.3048)
			(stroke
				(width 0.1)
				(type default)
			)
			(layer "F.Fab")
		)
		(fp_line
			(start 0.12065 -0.2794)
			(end 0.12065 -0.3048)
			(stroke
				(width 0.1)
				(type default)
			)
			(layer "F.Fab")
		)
		(fp_line
			(start 0.67945 -0.3048)
			(end 0.67945 0.3048)
			(stroke
				(width 0.1)
				(type default)
			)
			(layer "F.Fab")
		)
		(fp_line
			(start 0.67945 0.3048)
			(end 0.120396 0.3048)
			(stroke
				(width 0.1)
				(type default)
			)
			(layer "F.Fab")
		)
		(pad "1" smd circle
			(at -0.40005 0)
			(size 0 0)
			(layers "F.Cu" "F.Mask" "F.Paste")
			(net "P3V3_AUX")
		)
		(pad "2" smd circle
			(at 0.40005 0)
			(size 0 0)
			(layers "F.Cu" "F.Mask" "F.Paste")
			(net "GND")
		)
	)
	(footprint ""
		(layer "F.Cu")
		(at 308.4576 -21.1836)
		(property "Reference" "U341"
			(at 2.159 -0.11811 0)
			(unlocked yes)
			(layer "F.SilkS")
			(effects
				(font
					(size 0.7874 0.5842)
					(thickness 0.1524)
				)
				(justify left)
			)
		)
		(property "Value" ""
			(at 0 0 0)
			(layer "F.Fab")
			(effects
				(font
					(size 1.27 1.27)
				)
			)
		)
		(duplicate_pad_numbers_are_jumpers no)
		(fp_line
			(start -1.868424 -1.519936)
			(end -1.868424 1.519936)
			(stroke
				(width 0.1524)
				(type default)
			)
			(layer "F.SilkS")
		)
		(fp_line
			(start -1.868424 1.519936)
			(end 1.868424 1.519936)
			(stroke
				(width 0.1524)
				(type default)
			)
			(layer "F.SilkS")
		)
		(fp_line
			(start 1.868424 -1.519936)
			(end -1.868424 -1.519936)
			(stroke
				(width 0.1524)
				(type default)
			)
			(layer "F.SilkS")
		)
		(fp_line
			(start 1.868424 1.519936)
			(end 1.868424 -1.519936)
			(stroke
				(width 0.1524)
				(type default)
			)
			(layer "F.SilkS")
		)
		(fp_line
			(start -0.700024 -1.519936)
			(end -0.700024 1.519936)
			(stroke
				(width 0.1)
				(type default)
			)
			(layer "F.Fab")
		)
		(fp_line
			(start -0.700024 1.519936)
			(end 0.700024 1.519936)
			(stroke
				(width 0.1)
				(type default)
			)
			(layer "F.Fab")
		)
		(fp_line
			(start 0.700024 -1.519936)
			(end -0.700024 -1.519936)
			(stroke
				(width 0.1)
				(type default)
			)
			(layer "F.Fab")
		)
		(fp_line
			(start 0.700024 1.519936)
			(end 0.700024 -1.519936)
			(stroke
				(width 0.1)
				(type default)
			)
			(layer "F.Fab")
		)
		(pad "1" smd rect
			(at -1.18491 -0.94996 270)
			(size 0.6096 1.0668)
			(layers "F.Cu" "F.Mask" "F.Paste")
			(net "DSW_PWROK_P2V5_COMP")
		)
		(pad "2" smd rect
			(at -1.18491 0.94996 270)
			(size 0.6096 1.0668)
			(layers "F.Cu" "F.Mask" "F.Paste")
			(net "GND")
		)
		(pad "3" smd rect
			(at 1.18491 0 270)
			(size 0.6096 1.0668)
			(layers "F.Cu" "F.Mask" "F.Paste")
			(net "Net_8630")
		)
	)
	(footprint ""
		(layer "F.Cu")
		(at 352.270314 -255.053846 90)
		(property "Reference" "C982"
			(at 0 0 90)
			(layer "F.SilkS")
			(hide yes)
			(effects
				(font
					(size 1.27 1.27)
				)
			)
		)
		(property "Value" ""
			(at 0 0 90)
			(layer "F.Fab")
			(effects
				(font
					(size 1.27 1.27)
				)
			)
		)
		(duplicate_pad_numbers_are_jumpers no)
		(fp_line
			(start 0.7874 -0.4064)
			(end 0.7874 0.4064)
			(stroke
				(width 0.1524)
				(type default)
			)
			(layer "F.SilkS")
		)
		(fp_line
			(start -0.7874 -0.4064)
			(end 0.7874 -0.4064)
			(stroke
				(width 0.1524)
				(type default)
			)
			(layer "F.SilkS")
		)
		(fp_line
			(start 0.7874 0.4064)
			(end -0.7874 0.4064)
			(stroke
				(width 0.1524)
				(type default)
			)
			(layer "F.SilkS")
		)
		(fp_line
			(start -0.7874 0.4064)
			(end -0.7874 -0.4064)
			(stroke
				(width 0.1524)
				(type default)
			)
			(layer "F.SilkS")
		)
		(fp_line
			(start -0.12065 -0.305054)
			(end -0.12065 -0.2794)
			(stroke
				(width 0.1)
				(type default)
			)
			(layer "F.Fab")
		)
		(fp_line
			(start -0.67945 -0.305054)
			(end -0.12065 -0.305054)
			(stroke
				(width 0.1)
				(type default)
			)
			(layer "F.Fab")
		)
		(fp_line
			(start 0.67945 -0.3048)
			(end 0.67945 0.3048)
			(stroke
				(width 0.1)
				(type default)
			)
			(layer "F.Fab")
		)
		(fp_line
			(start 0.12065 -0.3048)
			(end 0.67945 -0.3048)
			(stroke
				(width 0.1)
				(type default)
			)
			(layer "F.Fab")
		)
		(fp_line
			(start 0.12065 -0.2794)
			(end 0.12065 -0.3048)
			(stroke
				(width 0.1)
				(type default)
			)
			(layer "F.Fab")
		)
		(fp_line
			(start -0.12065 -0.2794)
			(end 0.12065 -0.2794)
			(stroke
				(width 0.1)
				(type default)
			)
			(layer "F.Fab")
		)
		(fp_line
			(start 0.120396 0.2794)
			(end -0.12065 0.2794)
			(stroke
				(width 0.1)
				(type default)
			)
			(layer "F.Fab")
		)
		(fp_line
			(start -0.12065 0.2794)
			(end -0.12065 0.3048)
			(stroke
				(width 0.1)
				(type default)
			)
			(layer "F.Fab")
		)
		(fp_line
			(start 0.67945 0.3048)
			(end 0.120396 0.3048)
			(stroke
				(width 0.1)
				(type default)
			)
			(layer "F.Fab")
		)
		(fp_line
			(start 0.120396 0.3048)
			(end 0.120396 0.2794)
			(stroke
				(width 0.1)
				(type default)
			)
			(layer "F.Fab")
		)
		(fp_line
			(start -0.12065 0.3048)
			(end -0.67945 0.3048)
			(stroke
				(width 0.1)
				(type default)
			)
			(layer "F.Fab")
		)
		(fp_line
			(start -0.67945 0.3048)
			(end -0.67945 -0.305054)
			(stroke
				(width 0.1)
				(type default)
			)
			(layer "F.Fab")
		)
		(pad "1" smd circle
			(at -0.40005 0 90)
			(size 0 0)
			(layers "F.Cu" "F.Mask" "F.Paste")
			(net "PVCCIN_CPU0")
		)
		(pad "2" smd circle
			(at 0.40005 0 90)
			(size 0 0)
			(layers "F.Cu" "F.Mask" "F.Paste")
			(net "GND")
		)
	)
	(footprint ""
		(layer "F.Cu")
		(at 201.00036 -119.344948 180)
		(property "Reference" "R735"
			(at 0 0 180)
			(layer "F.SilkS")
			(hide yes)
			(effects
				(font
					(size 1.27 1.27)
				)
			)
		)
		(property "Value" ""
			(at 0 0 180)
			(layer "F.Fab")
			(effects
				(font
					(size 1.27 1.27)
				)
			)
		)
		(duplicate_pad_numbers_are_jumpers no)
		(fp_line
			(start 0.7874 0.4064)
			(end -0.7874 0.4064)
			(stroke
				(width 0.1524)
				(type default)
			)
			(layer "F.SilkS")
		)
		(fp_line
			(start 0.7874 -0.4064)
			(end 0.7874 0.4064)
			(stroke
				(width 0.1524)
				(type default)
			)
			(layer "F.SilkS")
		)
		(fp_line
			(start -0.7874 0.4064)
			(end -0.7874 -0.4064)
			(stroke
				(width 0.1524)
				(type default)
			)
			(layer "F.SilkS")
		)
		(fp_line
			(start -0.7874 -0.4064)
			(end 0.7874 -0.4064)
			(stroke
				(width 0.1524)
				(type default)
			)
			(layer "F.SilkS")
		)
		(fp_line
			(start 0.67945 0.3048)
			(end 0.120396 0.3048)
			(stroke
				(width 0.1)
				(type default)
			)
			(layer "F.Fab")
		)
		(fp_line
			(start 0.67945 -0.3048)
			(end 0.67945 0.3048)
			(stroke
				(width 0.1)
				(type default)
			)
			(layer "F.Fab")
		)
		(fp_line
			(start 0.12065 -0.2794)
			(end 0.12065 -0.3048)
			(stroke
				(width 0.1)
				(type default)
			)
			(layer "F.Fab")
		)
		(fp_line
			(start 0.12065 -0.3048)
			(end 0.67945 -0.3048)
			(stroke
				(width 0.1)
				(type default)
			)
			(layer "F.Fab")
		)
		(fp_line
			(start 0.120396 0.3048)
			(end 0.120396 0.2794)
			(stroke
				(width 0.1)
				(type default)
			)
			(layer "F.Fab")
		)
		(fp_line
			(start 0.120396 0.2794)
			(end -0.12065 0.2794)
			(stroke
				(width 0.1)
				(type default)
			)
			(layer "F.Fab")
		)
		(fp_line
			(start -0.12065 0.3048)
			(end -0.67945 0.3048)
			(stroke
				(width 0.1)
				(type default)
			)
			(layer "F.Fab")
		)
		(fp_line
			(start -0.12065 0.2794)
			(end -0.12065 0.3048)
			(stroke
				(width 0.1)
				(type default)
			)
			(layer "F.Fab")
		)
		(fp_line
			(start -0.12065 -0.2794)
			(end 0.12065 -0.2794)
			(stroke
				(width 0.1)
				(type default)
			)
			(layer "F.Fab")
		)
		(fp_line
			(start -0.12065 -0.305054)
			(end -0.12065 -0.2794)
			(stroke
				(width 0.1)
				(type default)
			)
			(layer "F.Fab")
		)
		(fp_line
			(start -0.67945 0.3048)
			(end -0.67945 -0.305054)
			(stroke
				(width 0.1)
				(type default)
			)
			(layer "F.Fab")
		)
		(fp_line
			(start -0.67945 -0.305054)
			(end -0.12065 -0.305054)
			(stroke
				(width 0.1)
				(type default)
			)
			(layer "F.Fab")
		)
		(pad "1" smd circle
			(at -0.40005 0 180)
			(size 0 0)
			(layers "F.Cu" "F.Mask" "F.Paste")
			(net "P3V3_AUX")
		)
		(pad "2" smd circle
			(at 0.40005 0 180)
			(size 0 0)
			(layers "F.Cu" "F.Mask" "F.Paste")
			(net "FM_DIMM_12V_CPS_SX_N")
		)
	)
	(footprint ""
		(layer "F.Cu")
		(at 134.21106 -127.056388 180)
		(property "Reference" "R3158"
			(at 0 0 180)
			(layer "F.SilkS")
			(hide yes)
			(effects
				(font
					(size 1.27 1.27)
				)
			)
		)
		(property "Value" ""
			(at 0 0 180)
			(layer "F.Fab")
			(effects
				(font
					(size 1.27 1.27)
				)
			)
		)
		(duplicate_pad_numbers_are_jumpers no)
		(fp_line
			(start 0.7874 0.4064)
			(end -0.7874 0.4064)
			(stroke
				(width 0.1524)
				(type default)
			)
			(layer "F.SilkS")
		)
		(fp_line
			(start 0.7874 -0.4064)
			(end 0.7874 0.4064)
			(stroke
				(width 0.1524)
				(type default)
			)
			(layer "F.SilkS")
		)
		(fp_line
			(start -0.7874 0.4064)
			(end -0.7874 -0.4064)
			(stroke
				(width 0.1524)
				(type default)
			)
			(layer "F.SilkS")
		)
		(fp_line
			(start -0.7874 -0.4064)
			(end 0.7874 -0.4064)
			(stroke
				(width 0.1524)
				(type default)
			)
			(layer "F.SilkS")
		)
		(fp_line
			(start 0.67945 0.3048)
			(end 0.120396 0.3048)
			(stroke
				(width 0.1)
				(type default)
			)
			(layer "F.Fab")
		)
		(fp_line
			(start 0.67945 -0.3048)
			(end 0.67945 0.3048)
			(stroke
				(width 0.1)
				(type default)
			)
			(layer "F.Fab")
		)
		(fp_line
			(start 0.12065 -0.2794)
			(end 0.12065 -0.3048)
			(stroke
				(width 0.1)
				(type default)
			)
			(layer "F.Fab")
		)
		(fp_line
			(start 0.12065 -0.3048)
			(end 0.67945 -0.3048)
			(stroke
				(width 0.1)
				(type default)
			)
			(layer "F.Fab")
		)
		(fp_line
			(start 0.120396 0.3048)
			(end 0.120396 0.2794)
			(stroke
				(width 0.1)
				(type default)
			)
			(layer "F.Fab")
		)
		(fp_line
			(start 0.120396 0.2794)
			(end -0.12065 0.2794)
			(stroke
				(width 0.1)
				(type default)
			)
			(layer "F.Fab")
		)
		(fp_line
			(start -0.12065 0.3048)
			(end -0.67945 0.3048)
			(stroke
				(width 0.1)
				(type default)
			)
			(layer "F.Fab")
		)
		(fp_line
			(start -0.12065 0.2794)
			(end -0.12065 0.3048)
			(stroke
				(width 0.1)
				(type default)
			)
			(layer "F.Fab")
		)
		(fp_line
			(start -0.12065 -0.2794)
			(end 0.12065 -0.2794)
			(stroke
				(width 0.1)
				(type default)
			)
			(layer "F.Fab")
		)
		(fp_line
			(start -0.12065 -0.305054)
			(end -0.12065 -0.2794)
			(stroke
				(width 0.1)
				(type default)
			)
			(layer "F.Fab")
		)
		(fp_line
			(start -0.67945 0.3048)
			(end -0.67945 -0.305054)
			(stroke
				(width 0.1)
				(type default)
			)
			(layer "F.Fab")
		)
		(fp_line
			(start -0.67945 -0.305054)
			(end -0.12065 -0.305054)
			(stroke
				(width 0.1)
				(type default)
			)
			(layer "F.Fab")
		)
		(pad "1" smd circle
			(at -0.40005 0 180)
			(size 0 0)
			(layers "F.Cu" "F.Mask" "F.Paste")
			(net "FM_SMB_CPU1_ALERT")
		)
		(pad "2" smd circle
			(at 0.40005 0 180)
			(size 0 0)
			(layers "F.Cu" "F.Mask" "F.Paste")
			(net "FM_SMB_PEHPCPU1_PCIE_ALERT_N")
		)
	)
	(footprint ""
		(layer "F.Cu")
		(at 120.57888 -92.674948 -90)
		(property "Reference" "R4395"
			(at 0 0 270)
			(layer "F.SilkS")
			(hide yes)
			(effects
				(font
					(size 1.27 1.27)
				)
			)
		)
		(property "Value" ""
			(at 0 0 270)
			(layer "F.Fab")
			(effects
				(font
					(size 1.27 1.27)
				)
			)
		)
		(duplicate_pad_numbers_are_jumpers no)
		(fp_line
			(start -0.7874 0.4064)
			(end -0.7874 -0.4064)
			(stroke
				(width 0.1524)
				(type default)
			)
			(layer "F.SilkS")
		)
		(fp_line
			(start 0.7874 0.4064)
			(end -0.7874 0.4064)
			(stroke
				(width 0.1524)
				(type default)
			)
			(layer "F.SilkS")
		)
		(fp_line
			(start -0.7874 -0.4064)
			(end 0.7874 -0.4064)
			(stroke
				(width 0.1524)
				(type default)
			)
			(layer "F.SilkS")
		)
		(fp_line
			(start 0.7874 -0.4064)
			(end 0.7874 0.4064)
			(stroke
				(width 0.1524)
				(type default)
			)
			(layer "F.SilkS")
		)
		(fp_line
			(start -0.67945 0.3048)
			(end -0.67945 -0.305054)
			(stroke
				(width 0.1)
				(type default)
			)
			(layer "F.Fab")
		)
		(fp_line
			(start -0.12065 0.3048)
			(end -0.67945 0.3048)
			(stroke
				(width 0.1)
				(type default)
			)
			(layer "F.Fab")
		)
		(fp_line
			(start 0.120396 0.3048)
			(end 0.120396 0.2794)
			(stroke
				(width 0.1)
				(type default)
			)
			(layer "F.Fab")
		)
		(fp_line
			(start 0.67945 0.3048)
			(end 0.120396 0.3048)
			(stroke
				(width 0.1)
				(type default)
			)
			(layer "F.Fab")
		)
		(fp_line
			(start -0.12065 0.2794)
			(end -0.12065 0.3048)
			(stroke
				(width 0.1)
				(type default)
			)
			(layer "F.Fab")
		)
		(fp_line
			(start 0.120396 0.2794)
			(end -0.12065 0.2794)
			(stroke
				(width 0.1)
				(type default)
			)
			(layer "F.Fab")
		)
		(fp_line
			(start -0.12065 -0.2794)
			(end 0.12065 -0.2794)
			(stroke
				(width 0.1)
				(type default)
			)
			(layer "F.Fab")
		)
		(fp_line
			(start 0.12065 -0.2794)
			(end 0.12065 -0.3048)
			(stroke
				(width 0.1)
				(type default)
			)
			(layer "F.Fab")
		)
		(fp_line
			(start 0.12065 -0.3048)
			(end 0.67945 -0.3048)
			(stroke
				(width 0.1)
				(type default)
			)
			(layer "F.Fab")
		)
		(fp_line
			(start 0.67945 -0.3048)
			(end 0.67945 0.3048)
			(stroke
				(width 0.1)
				(type default)
			)
			(layer "F.Fab")
		)
		(fp_line
			(start -0.67945 -0.305054)
			(end -0.12065 -0.305054)
			(stroke
				(width 0.1)
				(type default)
			)
			(layer "F.Fab")
		)
		(fp_line
			(start -0.12065 -0.305054)
			(end -0.12065 -0.2794)
			(stroke
				(width 0.1)
				(type default)
			)
			(layer "F.Fab")
		)
		(pad "1" smd circle
			(at -0.40005 0 270)
			(size 0 0)
			(layers "F.Cu" "F.Mask" "F.Paste")
			(net "PVNN_TERM_CPU0")
		)
		(pad "2" smd circle
			(at 0.40005 0 270)
			(size 0 0)
			(layers "F.Cu" "F.Mask" "F.Paste")
			(net "H_CPU0_THERMTRIP_LVC1_R_N")
		)
	)
	(footprint ""
		(layer "F.Cu")
		(at 98.31705 -32.636714)
		(property "Reference" "R3520"
			(at 0 0 0)
			(layer "F.SilkS")
			(hide yes)
			(effects
				(font
					(size 1.27 1.27)
				)
			)
		)
		(property "Value" ""
			(at 0 0 0)
			(layer "F.Fab")
			(effects
				(font
					(size 1.27 1.27)
				)
			)
		)
		(duplicate_pad_numbers_are_jumpers no)
		(fp_line
			(start -0.7874 -0.4064)
			(end 0.7874 -0.4064)
			(stroke
				(width 0.1524)
				(type default)
			)
			(layer "F.SilkS")
		)
		(fp_line
			(start -0.7874 0.4064)
			(end -0.7874 -0.4064)
			(stroke
				(width 0.1524)
				(type default)
			)
			(layer "F.SilkS")
		)
		(fp_line
			(start 0.7874 -0.4064)
			(end 0.7874 0.4064)
			(stroke
				(width 0.1524)
				(type default)
			)
			(layer "F.SilkS")
		)
		(fp_line
			(start 0.7874 0.4064)
			(end -0.7874 0.4064)
			(stroke
				(width 0.1524)
				(type default)
			)
			(layer "F.SilkS")
		)
		(fp_line
			(start -0.67945 -0.305054)
			(end -0.12065 -0.305054)
			(stroke
				(width 0.1)
				(type default)
			)
			(layer "F.Fab")
		)
		(fp_line
			(start -0.67945 0.3048)
			(end -0.67945 -0.305054)
			(stroke
				(width 0.1)
				(type default)
			)
			(layer "F.Fab")
		)
		(fp_line
			(start -0.12065 -0.305054)
			(end -0.12065 -0.2794)
			(stroke
				(width 0.1)
				(type default)
			)
			(layer "F.Fab")
		)
		(fp_line
			(start -0.12065 -0.2794)
			(end 0.12065 -0.2794)
			(stroke
				(width 0.1)
				(type default)
			)
			(layer "F.Fab")
		)
		(fp_line
			(start -0.12065 0.2794)
			(end -0.12065 0.3048)
			(stroke
				(width 0.1)
				(type default)
			)
			(layer "F.Fab")
		)
		(fp_line
			(start -0.12065 0.3048)
			(end -0.67945 0.3048)
			(stroke
				(width 0.1)
				(type default)
			)
			(layer "F.Fab")
		)
		(fp_line
			(start 0.120396 0.2794)
			(end -0.12065 0.2794)
			(stroke
				(width 0.1)
				(type default)
			)
			(layer "F.Fab")
		)
		(fp_line
			(start 0.120396 0.3048)
			(end 0.120396 0.2794)
			(stroke
				(width 0.1)
				(type default)
			)
			(layer "F.Fab")
		)
		(fp_line
			(start 0.12065 -0.3048)
			(end 0.67945 -0.3048)
			(stroke
				(width 0.1)
				(type default)
			)
			(layer "F.Fab")
		)
		(fp_line
			(start 0.12065 -0.2794)
			(end 0.12065 -0.3048)
			(stroke
				(width 0.1)
				(type default)
			)
			(layer "F.Fab")
		)
		(fp_line
			(start 0.67945 -0.3048)
			(end 0.67945 0.3048)
			(stroke
				(width 0.1)
				(type default)
			)
			(layer "F.Fab")
		)
		(fp_line
			(start 0.67945 0.3048)
			(end 0.120396 0.3048)
			(stroke
				(width 0.1)
				(type default)
			)
			(layer "F.Fab")
		)
		(pad "1" smd circle
			(at -0.40005 0)
			(size 0 0)
			(layers "F.Cu" "F.Mask" "F.Paste")
			(net "P3V3_OCP_V3_2")
		)
		(pad "2" smd circle
			(at 0.40005 0)
			(size 0 0)
			(layers "F.Cu" "F.Mask" "F.Paste")
			(net "SMB_OCP_V3_2_3V3AUX_BUF_SDA")
		)
	)
	(footprint ""
		(layer "F.Cu")
		(at 421.9702 -17.612614 90)
		(property "Reference" "C861"
			(at 0 0 90)
			(layer "F.SilkS")
			(hide yes)
			(effects
				(font
					(size 1.27 1.27)
				)
			)
		)
		(property "Value" ""
			(at 0 0 90)
			(layer "F.Fab")
			(effects
				(font
					(size 1.27 1.27)
				)
			)
		)
		(duplicate_pad_numbers_are_jumpers no)
		(fp_line
			(start 0.299974 -0.150114)
			(end 0.299974 0.150114)
			(stroke
				(width 0.1)
				(type default)
			)
			(layer "F.Fab")
		)
		(fp_line
			(start -0.299974 -0.150114)
			(end 0.299974 -0.150114)
			(stroke
				(width 0.1)
				(type default)
			)
			(layer "F.Fab")
		)
		(fp_line
			(start 0.299974 0.150114)
			(end -0.299974 0.150114)
			(stroke
				(width 0.1)
				(type default)
			)
			(layer "F.Fab")
		)
		(fp_line
			(start -0.299974 0.150114)
			(end -0.299974 -0.150114)
			(stroke
				(width 0.1)
				(type default)
			)
			(layer "F.Fab")
		)
		(pad "1" smd rect
			(at -0.2667 0 90)
			(size 0.3048 0.381)
			(layers "F.Cu" "F.Mask" "F.Paste")
			(net "P5E_CPU0_PE1_TX_C_DP<4>")
		)
		(pad "2" smd rect
			(at 0.2667 0 90)
			(size 0.3048 0.381)
			(layers "F.Cu" "F.Mask" "F.Paste")
			(net "P5E_CPU0_PE1_TX_DP<4>")
		)
	)
	(footprint ""
		(layer "F.Cu")
		(at 25.9715 -396.888462 -90)
		(property "Reference" "R4663"
			(at 0 0 270)
			(layer "F.SilkS")
			(hide yes)
			(effects
				(font
					(size 1.27 1.27)
				)
			)
		)
		(property "Value" ""
			(at 0 0 270)
			(layer "F.Fab")
			(effects
				(font
					(size 1.27 1.27)
				)
			)
		)
		(duplicate_pad_numbers_are_jumpers no)
		(fp_line
			(start -0.7874 0.4064)
			(end -0.7874 -0.4064)
			(stroke
				(width 0.1524)
				(type default)
			)
			(layer "F.SilkS")
		)
		(fp_line
			(start 0.7874 0.4064)
			(end 0.003302 0.4064)
			(stroke
				(width 0.1524)
				(type default)
			)
			(layer "F.SilkS")
		)
		(fp_line
			(start -0.7874 -0.4064)
			(end 0.7874 -0.4064)
			(stroke
				(width 0.1524)
				(type default)
			)
			(layer "F.SilkS")
		)
		(fp_line
			(start -0.67945 0.3048)
			(end -0.67945 -0.305054)
			(stroke
				(width 0.1)
				(type default)
			)
			(layer "F.Fab")
		)
		(fp_line
			(start -0.12065 0.3048)
			(end -0.67945 0.3048)
			(stroke
				(width 0.1)
				(type default)
			)
			(layer "F.Fab")
		)
		(fp_line
			(start 0.120396 0.3048)
			(end 0.120396 0.2794)
			(stroke
				(width 0.1)
				(type default)
			)
			(layer "F.Fab")
		)
		(fp_line
			(start 0.67945 0.3048)
			(end 0.120396 0.3048)
			(stroke
				(width 0.1)
				(type default)
			)
			(layer "F.Fab")
		)
		(fp_line
			(start -0.12065 0.2794)
			(end -0.12065 0.3048)
			(stroke
				(width 0.1)
				(type default)
			)
			(layer "F.Fab")
		)
		(fp_line
			(start 0.120396 0.2794)
			(end -0.12065 0.2794)
			(stroke
				(width 0.1)
				(type default)
			)
			(layer "F.Fab")
		)
		(fp_line
			(start -0.12065 -0.2794)
			(end 0.12065 -0.2794)
			(stroke
				(width 0.1)
				(type default)
			)
			(layer "F.Fab")
		)
		(fp_line
			(start 0.12065 -0.2794)
			(end 0.12065 -0.3048)
			(stroke
				(width 0.1)
				(type default)
			)
			(layer "F.Fab")
		)
		(fp_line
			(start 0.12065 -0.3048)
			(end 0.67945 -0.3048)
			(stroke
				(width 0.1)
				(type default)
			)
			(layer "F.Fab")
		)
		(fp_line
			(start 0.67945 -0.3048)
			(end 0.67945 0.3048)
			(stroke
				(width 0.1)
				(type default)
			)
			(layer "F.Fab")
		)
		(fp_line
			(start -0.67945 -0.305054)
			(end -0.12065 -0.305054)
			(stroke
				(width 0.1)
				(type default)
			)
			(layer "F.Fab")
		)
		(fp_line
			(start -0.12065 -0.305054)
			(end -0.12065 -0.2794)
			(stroke
				(width 0.1)
				(type default)
			)
			(layer "F.Fab")
		)
		(pad "1" smd rect
			(at -0.40005 0 90)
			(size 0.4572 0.508)
			(layers "F.Cu" "F.Mask" "F.Paste")
			(net "P2E_MB_BMC_RX_DP<0>")
		)
		(pad "2" smd rect
			(at 0.40005 0 90)
			(size 0.4572 0.508)
			(layers "F.Cu" "F.Mask" "F.Paste")
			(net "P2E_MB_BMC_RX_R1_DP<0>")
		)
	)
	(footprint ""
		(layer "F.Cu")
		(at 248.22658 -398.78 90)
		(property "Reference" "PPQ2"
			(at -8.221472 -1.44272 0)
			(unlocked yes)
			(layer "F.SilkS")
			(effects
				(font
					(size 0.7874 0.5842)
					(thickness 0.1524)
				)
				(justify left)
			)
		)
		(property "Value" ""
			(at 0 0 90)
			(layer "F.Fab")
			(effects
				(font
					(size 1.27 1.27)
				)
			)
		)
		(duplicate_pad_numbers_are_jumpers no)
		(fp_line
			(start 2.350008 -2.649982)
			(end 2.350008 -2.4892)
			(stroke
				(width 0.1524)
				(type default)
			)
			(layer "F.SilkS")
		)
		(fp_line
			(start -2.350008 -2.649982)
			(end 2.350008 -2.649982)
			(stroke
				(width 0.1524)
				(type default)
			)
			(layer "F.SilkS")
		)
		(fp_line
			(start -2.350008 -2.4384)
			(end -2.350008 -2.649982)
			(stroke
				(width 0.1524)
				(type default)
			)
			(layer "F.SilkS")
		)
		(fp_line
			(start 2.350008 2.4892)
			(end 2.350008 2.649982)
			(stroke
				(width 0.1524)
				(type default)
			)
			(layer "F.SilkS")
		)
		(fp_line
			(start 2.350008 2.649982)
			(end -2.350008 2.649982)
			(stroke
				(width 0.1524)
				(type default)
			)
			(layer "F.SilkS")
		)
		(fp_line
			(start -2.350008 2.649982)
			(end -2.350008 2.413)
			(stroke
				(width 0.1524)
				(type default)
			)
			(layer "F.SilkS")
		)
		(fp_poly
			(pts
				(xy -3.717544 -1.905) (xy -4.758944 -2.3241) (xy -4.758944 -1.524)
			)
			(stroke
				(width 0)
				(type default)
			)
			(fill yes)
			(layer "F.SilkS")
		)
		(fp_line
			(start 2.350008 -2.649982)
			(end 2.350008 2.649982)
			(stroke
				(width 0.1)
				(type default)
			)
			(layer "F.Fab")
		)
		(fp_line
			(start -2.350008 -2.649982)
			(end 2.350008 -2.649982)
			(stroke
				(width 0.1)
				(type default)
			)
			(layer "F.Fab")
		)
		(fp_line
			(start 2.350008 2.649982)
			(end -2.350008 2.649982)
			(stroke
				(width 0.1)
				(type default)
			)
			(layer "F.Fab")
		)
		(fp_line
			(start -2.350008 2.649982)
			(end -2.350008 -2.649982)
			(stroke
				(width 0.1)
				(type default)
			)
			(layer "F.Fab")
		)
		(fp_poly
			(pts
				(xy -3.717544 -1.905) (xy -4.758944 -2.3241) (xy -4.758944 -1.524)
			)
			(stroke
				(width 0)
				(type default)
			)
			(fill yes)
			(layer "F.Fab")
		)
		(pad "1" smd rect
			(at -2.999994 -1.905)
			(size 0.7112 1.1684)
			(layers "F.Cu" "F.Mask" "F.Paste")
			(net "P12V_AUX")
		)
		(pad "2" smd rect
			(at -2.999994 -0.635)
			(size 0.7112 1.1684)
			(layers "F.Cu" "F.Mask" "F.Paste")
			(net "P12V_AUX")
		)
		(pad "3" smd rect
			(at -2.999994 0.635)
			(size 0.7112 1.1684)
			(layers "F.Cu" "F.Mask" "F.Paste")
			(net "P12V_AUX")
		)
		(pad "4" smd rect
			(at -2.999994 1.905)
			(size 0.7112 1.1684)
			(layers "F.Cu" "F.Mask" "F.Paste")
			(net "P12V_HSC_GATE_G6")
		)
		(pad "5" smd circle
			(at 0.925068 0)
			(size 0 0)
			(layers "F.Cu" "F.Mask" "F.Paste")
			(net "P12V_MAIN_R")
		)
		(zone
			(layer "F.Cu")
			(hatch none 0.5)
			(connect_pads
				(clearance 0)
			)
			(min_thickness 0.25)
			(keepout
				(tracks not_allowed)
				(vias allowed)
				(pads allowed)
				(copperpour not_allowed)
				(footprints allowed)
			)
			(placement
				(enabled no)
				(sheetname "")
			)
			(fill
				(thermal_gap 0.5)
				(thermal_bridge_width 0.5)
				(island_removal_mode 0)
			)
			(polygon
				(pts
					(xy 246.06758 -397.3322) (xy 250.38558 -397.3322) (xy 250.47702 -397.24076) (xy 250.86818 -397.24076)
					(xy 250.86818 -396.4305) (xy 245.58498 -396.4305) (xy 245.58498 -397.3322)
				)
			)
		)
	)
	(footprint ""
		(layer "F.Cu")
		(at 178.13782 -356.03053 90)
		(property "Reference" "PC1191"
			(at 0 0 90)
			(layer "F.SilkS")
			(hide yes)
			(effects
				(font
					(size 1.27 1.27)
				)
			)
		)
		(property "Value" ""
			(at 0 0 90)
			(layer "F.Fab")
			(effects
				(font
					(size 1.27 1.27)
				)
			)
		)
		(duplicate_pad_numbers_are_jumpers no)
		(fp_line
			(start 0.7874 -0.4064)
			(end 0.7874 0.4064)
			(stroke
				(width 0.1524)
				(type default)
			)
			(layer "F.SilkS")
		)
		(fp_line
			(start -0.7874 -0.4064)
			(end 0.7874 -0.4064)
			(stroke
				(width 0.1524)
				(type default)
			)
			(layer "F.SilkS")
		)
		(fp_line
			(start 0.7874 0.4064)
			(end -0.7874 0.4064)
			(stroke
				(width 0.1524)
				(type default)
			)
			(layer "F.SilkS")
		)
		(fp_line
			(start -0.7874 0.4064)
			(end -0.7874 -0.4064)
			(stroke
				(width 0.1524)
				(type default)
			)
			(layer "F.SilkS")
		)
		(fp_line
			(start -0.12065 -0.305054)
			(end -0.12065 -0.2794)
			(stroke
				(width 0.1)
				(type default)
			)
			(layer "F.Fab")
		)
		(fp_line
			(start -0.67945 -0.305054)
			(end -0.12065 -0.305054)
			(stroke
				(width 0.1)
				(type default)
			)
			(layer "F.Fab")
		)
		(fp_line
			(start 0.67945 -0.3048)
			(end 0.67945 0.3048)
			(stroke
				(width 0.1)
				(type default)
			)
			(layer "F.Fab")
		)
		(fp_line
			(start 0.12065 -0.3048)
			(end 0.67945 -0.3048)
			(stroke
				(width 0.1)
				(type default)
			)
			(layer "F.Fab")
		)
		(fp_line
			(start 0.12065 -0.2794)
			(end 0.12065 -0.3048)
			(stroke
				(width 0.1)
				(type default)
			)
			(layer "F.Fab")
		)
		(fp_line
			(start -0.12065 -0.2794)
			(end 0.12065 -0.2794)
			(stroke
				(width 0.1)
				(type default)
			)
			(layer "F.Fab")
		)
		(fp_line
			(start 0.120396 0.2794)
			(end -0.12065 0.2794)
			(stroke
				(width 0.1)
				(type default)
			)
			(layer "F.Fab")
		)
		(fp_line
			(start -0.12065 0.2794)
			(end -0.12065 0.3048)
			(stroke
				(width 0.1)
				(type default)
			)
			(layer "F.Fab")
		)
		(fp_line
			(start 0.67945 0.3048)
			(end 0.120396 0.3048)
			(stroke
				(width 0.1)
				(type default)
			)
			(layer "F.Fab")
		)
		(fp_line
			(start 0.120396 0.3048)
			(end 0.120396 0.2794)
			(stroke
				(width 0.1)
				(type default)
			)
			(layer "F.Fab")
		)
		(fp_line
			(start -0.12065 0.3048)
			(end -0.67945 0.3048)
			(stroke
				(width 0.1)
				(type default)
			)
			(layer "F.Fab")
		)
		(fp_line
			(start -0.67945 0.3048)
			(end -0.67945 -0.305054)
			(stroke
				(width 0.1)
				(type default)
			)
			(layer "F.Fab")
		)
		(pad "1" smd circle
			(at -0.40005 0 90)
			(size 0 0)
			(layers "F.Cu" "F.Mask" "F.Paste")
			(net "PVCCFA_EHV_FIVRA_CPU1_VDD3")
		)
		(pad "2" smd circle
			(at 0.40005 0 90)
			(size 0 0)
			(layers "F.Cu" "F.Mask" "F.Paste")
			(net "GND")
		)
	)
	(footprint ""
		(layer "F.Cu")
		(at 405.09317 -402.371052 -90)
		(property "Reference" "C957"
			(at 0 0 270)
			(layer "F.SilkS")
			(hide yes)
			(effects
				(font
					(size 1.27 1.27)
				)
			)
		)
		(property "Value" ""
			(at 0 0 270)
			(layer "F.Fab")
			(effects
				(font
					(size 1.27 1.27)
				)
			)
		)
		(duplicate_pad_numbers_are_jumpers no)
		(fp_line
			(start -0.299974 0.150114)
			(end -0.299974 -0.150114)
			(stroke
				(width 0.1)
				(type default)
			)
			(layer "F.Fab")
		)
		(fp_line
			(start 0.299974 0.150114)
			(end -0.299974 0.150114)
			(stroke
				(width 0.1)
				(type default)
			)
			(layer "F.Fab")
		)
		(fp_line
			(start -0.299974 -0.150114)
			(end 0.299974 -0.150114)
			(stroke
				(width 0.1)
				(type default)
			)
			(layer "F.Fab")
		)
		(fp_line
			(start 0.299974 -0.150114)
			(end 0.299974 0.150114)
			(stroke
				(width 0.1)
				(type default)
			)
			(layer "F.Fab")
		)
		(pad "1" smd rect
			(at -0.2667 0 270)
			(size 0.3048 0.381)
			(layers "F.Cu" "F.Mask" "F.Paste")
			(net "P5E_CPU0_PE2_TX_C_DP<4>")
		)
		(pad "2" smd rect
			(at 0.2667 0 270)
			(size 0.3048 0.381)
			(layers "F.Cu" "F.Mask" "F.Paste")
			(net "P5E_CPU0_PE2_TX_DP<4>")
		)
	)
	(footprint ""
		(layer "F.Cu")
		(at 194.371468 -76.016866)
		(property "Reference" "R1291"
			(at 0 0 0)
			(layer "F.SilkS")
			(hide yes)
			(effects
				(font
					(size 1.27 1.27)
				)
			)
		)
		(property "Value" ""
			(at 0 0 0)
			(layer "F.Fab")
			(effects
				(font
					(size 1.27 1.27)
				)
			)
		)
		(duplicate_pad_numbers_are_jumpers no)
		(fp_line
			(start -0.7874 -0.4064)
			(end 0.7874 -0.4064)
			(stroke
				(width 0.1524)
				(type default)
			)
			(layer "F.SilkS")
		)
		(fp_line
			(start -0.7874 0.4064)
			(end -0.7874 -0.4064)
			(stroke
				(width 0.1524)
				(type default)
			)
			(layer "F.SilkS")
		)
		(fp_line
			(start 0.7874 -0.4064)
			(end 0.7874 0.4064)
			(stroke
				(width 0.1524)
				(type default)
			)
			(layer "F.SilkS")
		)
		(fp_line
			(start 0.7874 0.4064)
			(end -0.7874 0.4064)
			(stroke
				(width 0.1524)
				(type default)
			)
			(layer "F.SilkS")
		)
		(fp_line
			(start -0.67945 -0.305054)
			(end -0.12065 -0.305054)
			(stroke
				(width 0.1)
				(type default)
			)
			(layer "F.Fab")
		)
		(fp_line
			(start -0.67945 0.3048)
			(end -0.67945 -0.305054)
			(stroke
				(width 0.1)
				(type default)
			)
			(layer "F.Fab")
		)
		(fp_line
			(start -0.12065 -0.305054)
			(end -0.12065 -0.2794)
			(stroke
				(width 0.1)
				(type default)
			)
			(layer "F.Fab")
		)
		(fp_line
			(start -0.12065 -0.2794)
			(end 0.12065 -0.2794)
			(stroke
				(width 0.1)
				(type default)
			)
			(layer "F.Fab")
		)
		(fp_line
			(start -0.12065 0.2794)
			(end -0.12065 0.3048)
			(stroke
				(width 0.1)
				(type default)
			)
			(layer "F.Fab")
		)
		(fp_line
			(start -0.12065 0.3048)
			(end -0.67945 0.3048)
			(stroke
				(width 0.1)
				(type default)
			)
			(layer "F.Fab")
		)
		(fp_line
			(start 0.120396 0.2794)
			(end -0.12065 0.2794)
			(stroke
				(width 0.1)
				(type default)
			)
			(layer "F.Fab")
		)
		(fp_line
			(start 0.120396 0.3048)
			(end 0.120396 0.2794)
			(stroke
				(width 0.1)
				(type default)
			)
			(layer "F.Fab")
		)
		(fp_line
			(start 0.12065 -0.3048)
			(end 0.67945 -0.3048)
			(stroke
				(width 0.1)
				(type default)
			)
			(layer "F.Fab")
		)
		(fp_line
			(start 0.12065 -0.2794)
			(end 0.12065 -0.3048)
			(stroke
				(width 0.1)
				(type default)
			)
			(layer "F.Fab")
		)
		(fp_line
			(start 0.67945 -0.3048)
			(end 0.67945 0.3048)
			(stroke
				(width 0.1)
				(type default)
			)
			(layer "F.Fab")
		)
		(fp_line
			(start 0.67945 0.3048)
			(end 0.120396 0.3048)
			(stroke
				(width 0.1)
				(type default)
			)
			(layer "F.Fab")
		)
		(pad "1" smd circle
			(at -0.40005 0)
			(size 0 0)
			(layers "F.Cu" "F.Mask" "F.Paste")
			(net "NCSI_BMC_CRS_DV_R")
		)
		(pad "2" smd circle
			(at 0.40005 0)
			(size 0 0)
			(layers "F.Cu" "F.Mask" "F.Paste")
			(net "RMII_OCP_BMC_CRSDV")
		)
	)
	(footprint ""
		(layer "F.Cu")
		(at 33.7693 -133.444996 180)
		(property "Reference" "PC468"
			(at 0 0 180)
			(layer "F.SilkS")
			(hide yes)
			(effects
				(font
					(size 1.27 1.27)
				)
			)
		)
		(property "Value" ""
			(at 0 0 180)
			(layer "F.Fab")
			(effects
				(font
					(size 1.27 1.27)
				)
			)
		)
		(duplicate_pad_numbers_are_jumpers no)
		(fp_line
			(start 0.7874 0.4064)
			(end -0.7874 0.4064)
			(stroke
				(width 0.1524)
				(type default)
			)
			(layer "F.SilkS")
		)
		(fp_line
			(start 0.7874 -0.4064)
			(end 0.7874 0.4064)
			(stroke
				(width 0.1524)
				(type default)
			)
			(layer "F.SilkS")
		)
		(fp_line
			(start -0.7874 0.4064)
			(end -0.7874 -0.4064)
			(stroke
				(width 0.1524)
				(type default)
			)
			(layer "F.SilkS")
		)
		(fp_line
			(start -0.7874 -0.4064)
			(end 0.7874 -0.4064)
			(stroke
				(width 0.1524)
				(type default)
			)
			(layer "F.SilkS")
		)
		(fp_line
			(start 0.67945 0.3048)
			(end 0.120396 0.3048)
			(stroke
				(width 0.1)
				(type default)
			)
			(layer "F.Fab")
		)
		(fp_line
			(start 0.67945 -0.3048)
			(end 0.67945 0.3048)
			(stroke
				(width 0.1)
				(type default)
			)
			(layer "F.Fab")
		)
		(fp_line
			(start 0.12065 -0.2794)
			(end 0.12065 -0.3048)
			(stroke
				(width 0.1)
				(type default)
			)
			(layer "F.Fab")
		)
		(fp_line
			(start 0.12065 -0.3048)
			(end 0.67945 -0.3048)
			(stroke
				(width 0.1)
				(type default)
			)
			(layer "F.Fab")
		)
		(fp_line
			(start 0.120396 0.3048)
			(end 0.120396 0.2794)
			(stroke
				(width 0.1)
				(type default)
			)
			(layer "F.Fab")
		)
		(fp_line
			(start 0.120396 0.2794)
			(end -0.12065 0.2794)
			(stroke
				(width 0.1)
				(type default)
			)
			(layer "F.Fab")
		)
		(fp_line
			(start -0.12065 0.3048)
			(end -0.67945 0.3048)
			(stroke
				(width 0.1)
				(type default)
			)
			(layer "F.Fab")
		)
		(fp_line
			(start -0.12065 0.2794)
			(end -0.12065 0.3048)
			(stroke
				(width 0.1)
				(type default)
			)
			(layer "F.Fab")
		)
		(fp_line
			(start -0.12065 -0.2794)
			(end 0.12065 -0.2794)
			(stroke
				(width 0.1)
				(type default)
			)
			(layer "F.Fab")
		)
		(fp_line
			(start -0.12065 -0.305054)
			(end -0.12065 -0.2794)
			(stroke
				(width 0.1)
				(type default)
			)
			(layer "F.Fab")
		)
		(fp_line
			(start -0.67945 0.3048)
			(end -0.67945 -0.305054)
			(stroke
				(width 0.1)
				(type default)
			)
			(layer "F.Fab")
		)
		(fp_line
			(start -0.67945 -0.305054)
			(end -0.12065 -0.305054)
			(stroke
				(width 0.1)
				(type default)
			)
			(layer "F.Fab")
		)
		(pad "1" smd circle
			(at -0.40005 0 180)
			(size 0 0)
			(layers "F.Cu" "F.Mask" "F.Paste")
			(net "SH_PVCCINFAON_CPU1_R")
		)
		(pad "2" smd circle
			(at 0.40005 0 180)
			(size 0 0)
			(layers "F.Cu" "F.Mask" "F.Paste")
			(net "VSENSE_PVCCINFAON_CPU1_DN")
		)
	)
	(footprint ""
		(layer "F.Cu")
		(at 195.06184 -92.832428 90)
		(property "Reference" "R4609"
			(at 0 0 90)
			(layer "F.SilkS")
			(hide yes)
			(effects
				(font
					(size 1.27 1.27)
				)
			)
		)
		(property "Value" ""
			(at 0 0 90)
			(layer "F.Fab")
			(effects
				(font
					(size 1.27 1.27)
				)
			)
		)
		(duplicate_pad_numbers_are_jumpers no)
		(fp_line
			(start 0.7874 -0.4064)
			(end 0.7874 0.4064)
			(stroke
				(width 0.1524)
				(type default)
			)
			(layer "F.SilkS")
		)
		(fp_line
			(start -0.7874 -0.4064)
			(end 0.7874 -0.4064)
			(stroke
				(width 0.1524)
				(type default)
			)
			(layer "F.SilkS")
		)
		(fp_line
			(start 0.7874 0.4064)
			(end -0.7874 0.4064)
			(stroke
				(width 0.1524)
				(type default)
			)
			(layer "F.SilkS")
		)
		(fp_line
			(start -0.7874 0.4064)
			(end -0.7874 -0.4064)
			(stroke
				(width 0.1524)
				(type default)
			)
			(layer "F.SilkS")
		)
		(fp_line
			(start -0.12065 -0.305054)
			(end -0.12065 -0.2794)
			(stroke
				(width 0.1)
				(type default)
			)
			(layer "F.Fab")
		)
		(fp_line
			(start -0.67945 -0.305054)
			(end -0.12065 -0.305054)
			(stroke
				(width 0.1)
				(type default)
			)
			(layer "F.Fab")
		)
		(fp_line
			(start 0.67945 -0.3048)
			(end 0.67945 0.3048)
			(stroke
				(width 0.1)
				(type default)
			)
			(layer "F.Fab")
		)
		(fp_line
			(start 0.12065 -0.3048)
			(end 0.67945 -0.3048)
			(stroke
				(width 0.1)
				(type default)
			)
			(layer "F.Fab")
		)
		(fp_line
			(start 0.12065 -0.2794)
			(end 0.12065 -0.3048)
			(stroke
				(width 0.1)
				(type default)
			)
			(layer "F.Fab")
		)
		(fp_line
			(start -0.12065 -0.2794)
			(end 0.12065 -0.2794)
			(stroke
				(width 0.1)
				(type default)
			)
			(layer "F.Fab")
		)
		(fp_line
			(start 0.120396 0.2794)
			(end -0.12065 0.2794)
			(stroke
				(width 0.1)
				(type default)
			)
			(layer "F.Fab")
		)
		(fp_line
			(start -0.12065 0.2794)
			(end -0.12065 0.3048)
			(stroke
				(width 0.1)
				(type default)
			)
			(layer "F.Fab")
		)
		(fp_line
			(start 0.67945 0.3048)
			(end 0.120396 0.3048)
			(stroke
				(width 0.1)
				(type default)
			)
			(layer "F.Fab")
		)
		(fp_line
			(start 0.120396 0.3048)
			(end 0.120396 0.2794)
			(stroke
				(width 0.1)
				(type default)
			)
			(layer "F.Fab")
		)
		(fp_line
			(start -0.12065 0.3048)
			(end -0.67945 0.3048)
			(stroke
				(width 0.1)
				(type default)
			)
			(layer "F.Fab")
		)
		(fp_line
			(start -0.67945 0.3048)
			(end -0.67945 -0.305054)
			(stroke
				(width 0.1)
				(type default)
			)
			(layer "F.Fab")
		)
		(pad "1" smd circle
			(at -0.40005 0 90)
			(size 0 0)
			(layers "F.Cu" "F.Mask" "F.Paste")
			(net "FM_JTAG_TCK_MUX_SEL_R")
		)
		(pad "2" smd circle
			(at 0.40005 0 90)
			(size 0 0)
			(layers "F.Cu" "F.Mask" "F.Paste")
			(net "FM_JTAG_TCK_MUX_SEL")
		)
	)
	(footprint ""
		(layer "F.Cu")
		(at 190.80988 -133.695948 90)
		(property "Reference" "R1308"
			(at 0 0 90)
			(layer "F.SilkS")
			(hide yes)
			(effects
				(font
					(size 1.27 1.27)
				)
			)
		)
		(property "Value" ""
			(at 0 0 90)
			(layer "F.Fab")
			(effects
				(font
					(size 1.27 1.27)
				)
			)
		)
		(duplicate_pad_numbers_are_jumpers no)
		(fp_line
			(start 0.7874 -0.4064)
			(end 0.7874 0.4064)
			(stroke
				(width 0.1524)
				(type default)
			)
			(layer "F.SilkS")
		)
		(fp_line
			(start -0.7874 -0.4064)
			(end 0.7874 -0.4064)
			(stroke
				(width 0.1524)
				(type default)
			)
			(layer "F.SilkS")
		)
		(fp_line
			(start 0.7874 0.4064)
			(end -0.7874 0.4064)
			(stroke
				(width 0.1524)
				(type default)
			)
			(layer "F.SilkS")
		)
		(fp_line
			(start -0.7874 0.4064)
			(end -0.7874 -0.4064)
			(stroke
				(width 0.1524)
				(type default)
			)
			(layer "F.SilkS")
		)
		(fp_line
			(start -0.12065 -0.305054)
			(end -0.12065 -0.2794)
			(stroke
				(width 0.1)
				(type default)
			)
			(layer "F.Fab")
		)
		(fp_line
			(start -0.67945 -0.305054)
			(end -0.12065 -0.305054)
			(stroke
				(width 0.1)
				(type default)
			)
			(layer "F.Fab")
		)
		(fp_line
			(start 0.67945 -0.3048)
			(end 0.67945 0.3048)
			(stroke
				(width 0.1)
				(type default)
			)
			(layer "F.Fab")
		)
		(fp_line
			(start 0.12065 -0.3048)
			(end 0.67945 -0.3048)
			(stroke
				(width 0.1)
				(type default)
			)
			(layer "F.Fab")
		)
		(fp_line
			(start 0.12065 -0.2794)
			(end 0.12065 -0.3048)
			(stroke
				(width 0.1)
				(type default)
			)
			(layer "F.Fab")
		)
		(fp_line
			(start -0.12065 -0.2794)
			(end 0.12065 -0.2794)
			(stroke
				(width 0.1)
				(type default)
			)
			(layer "F.Fab")
		)
		(fp_line
			(start 0.120396 0.2794)
			(end -0.12065 0.2794)
			(stroke
				(width 0.1)
				(type default)
			)
			(layer "F.Fab")
		)
		(fp_line
			(start -0.12065 0.2794)
			(end -0.12065 0.3048)
			(stroke
				(width 0.1)
				(type default)
			)
			(layer "F.Fab")
		)
		(fp_line
			(start 0.67945 0.3048)
			(end 0.120396 0.3048)
			(stroke
				(width 0.1)
				(type default)
			)
			(layer "F.Fab")
		)
		(fp_line
			(start 0.120396 0.3048)
			(end 0.120396 0.2794)
			(stroke
				(width 0.1)
				(type default)
			)
			(layer "F.Fab")
		)
		(fp_line
			(start -0.12065 0.3048)
			(end -0.67945 0.3048)
			(stroke
				(width 0.1)
				(type default)
			)
			(layer "F.Fab")
		)
		(fp_line
			(start -0.67945 0.3048)
			(end -0.67945 -0.305054)
			(stroke
				(width 0.1)
				(type default)
			)
			(layer "F.Fab")
		)
		(pad "1" smd circle
			(at -0.40005 0 90)
			(size 0 0)
			(layers "F.Cu" "F.Mask" "F.Paste")
			(net "FM_RST_PERST_BIT1")
		)
		(pad "2" smd circle
			(at 0.40005 0 90)
			(size 0 0)
			(layers "F.Cu" "F.Mask" "F.Paste")
			(net "GND")
		)
	)
	(footprint ""
		(layer "F.Cu")
		(at 144.54378 -345.129358 180)
		(property "Reference" "PR640"
			(at 0 0 180)
			(layer "F.SilkS")
			(hide yes)
			(effects
				(font
					(size 1.27 1.27)
				)
			)
		)
		(property "Value" ""
			(at 0 0 180)
			(layer "F.Fab")
			(effects
				(font
					(size 1.27 1.27)
				)
			)
		)
		(duplicate_pad_numbers_are_jumpers no)
		(fp_line
			(start 0.7874 0.4064)
			(end -0.7874 0.4064)
			(stroke
				(width 0.1524)
				(type default)
			)
			(layer "F.SilkS")
		)
		(fp_line
			(start 0.7874 -0.4064)
			(end 0.7874 0.4064)
			(stroke
				(width 0.1524)
				(type default)
			)
			(layer "F.SilkS")
		)
		(fp_line
			(start -0.7874 0.4064)
			(end -0.7874 -0.4064)
			(stroke
				(width 0.1524)
				(type default)
			)
			(layer "F.SilkS")
		)
		(fp_line
			(start -0.7874 -0.4064)
			(end 0.7874 -0.4064)
			(stroke
				(width 0.1524)
				(type default)
			)
			(layer "F.SilkS")
		)
		(fp_line
			(start 0.67945 0.3048)
			(end 0.120396 0.3048)
			(stroke
				(width 0.1)
				(type default)
			)
			(layer "F.Fab")
		)
		(fp_line
			(start 0.67945 -0.3048)
			(end 0.67945 0.3048)
			(stroke
				(width 0.1)
				(type default)
			)
			(layer "F.Fab")
		)
		(fp_line
			(start 0.12065 -0.2794)
			(end 0.12065 -0.3048)
			(stroke
				(width 0.1)
				(type default)
			)
			(layer "F.Fab")
		)
		(fp_line
			(start 0.12065 -0.3048)
			(end 0.67945 -0.3048)
			(stroke
				(width 0.1)
				(type default)
			)
			(layer "F.Fab")
		)
		(fp_line
			(start 0.120396 0.3048)
			(end 0.120396 0.2794)
			(stroke
				(width 0.1)
				(type default)
			)
			(layer "F.Fab")
		)
		(fp_line
			(start 0.120396 0.2794)
			(end -0.12065 0.2794)
			(stroke
				(width 0.1)
				(type default)
			)
			(layer "F.Fab")
		)
		(fp_line
			(start -0.12065 0.3048)
			(end -0.67945 0.3048)
			(stroke
				(width 0.1)
				(type default)
			)
			(layer "F.Fab")
		)
		(fp_line
			(start -0.12065 0.2794)
			(end -0.12065 0.3048)
			(stroke
				(width 0.1)
				(type default)
			)
			(layer "F.Fab")
		)
		(fp_line
			(start -0.12065 -0.2794)
			(end 0.12065 -0.2794)
			(stroke
				(width 0.1)
				(type default)
			)
			(layer "F.Fab")
		)
		(fp_line
			(start -0.12065 -0.305054)
			(end -0.12065 -0.2794)
			(stroke
				(width 0.1)
				(type default)
			)
			(layer "F.Fab")
		)
		(fp_line
			(start -0.67945 0.3048)
			(end -0.67945 -0.305054)
			(stroke
				(width 0.1)
				(type default)
			)
			(layer "F.Fab")
		)
		(fp_line
			(start -0.67945 -0.305054)
			(end -0.12065 -0.305054)
			(stroke
				(width 0.1)
				(type default)
			)
			(layer "F.Fab")
		)
		(pad "1" smd circle
			(at -0.40005 0 180)
			(size 0 0)
			(layers "F.Cu" "F.Mask" "F.Paste")
			(net "P3V3")
		)
		(pad "2" smd circle
			(at 0.40005 0 180)
			(size 0 0)
			(layers "F.Cu" "F.Mask" "F.Paste")
			(net "PVCCIN_CPU1_PVCC")
		)
	)
	(footprint ""
		(layer "F.Cu")
		(at 197.41388 -103.685848)
		(property "Reference" "R1844"
			(at 0 0 0)
			(layer "F.SilkS")
			(hide yes)
			(effects
				(font
					(size 1.27 1.27)
				)
			)
		)
		(property "Value" ""
			(at 0 0 0)
			(layer "F.Fab")
			(effects
				(font
					(size 1.27 1.27)
				)
			)
		)
		(duplicate_pad_numbers_are_jumpers no)
		(fp_line
			(start -0.7874 -0.4064)
			(end 0.7874 -0.4064)
			(stroke
				(width 0.1524)
				(type default)
			)
			(layer "F.SilkS")
		)
		(fp_line
			(start -0.7874 0.4064)
			(end -0.7874 -0.4064)
			(stroke
				(width 0.1524)
				(type default)
			)
			(layer "F.SilkS")
		)
		(fp_line
			(start 0.7874 -0.4064)
			(end 0.7874 0.4064)
			(stroke
				(width 0.1524)
				(type default)
			)
			(layer "F.SilkS")
		)
		(fp_line
			(start 0.7874 0.4064)
			(end -0.7874 0.4064)
			(stroke
				(width 0.1524)
				(type default)
			)
			(layer "F.SilkS")
		)
		(fp_line
			(start -0.67945 -0.305054)
			(end -0.12065 -0.305054)
			(stroke
				(width 0.1)
				(type default)
			)
			(layer "F.Fab")
		)
		(fp_line
			(start -0.67945 0.3048)
			(end -0.67945 -0.305054)
			(stroke
				(width 0.1)
				(type default)
			)
			(layer "F.Fab")
		)
		(fp_line
			(start -0.12065 -0.305054)
			(end -0.12065 -0.2794)
			(stroke
				(width 0.1)
				(type default)
			)
			(layer "F.Fab")
		)
		(fp_line
			(start -0.12065 -0.2794)
			(end 0.12065 -0.2794)
			(stroke
				(width 0.1)
				(type default)
			)
			(layer "F.Fab")
		)
		(fp_line
			(start -0.12065 0.2794)
			(end -0.12065 0.3048)
			(stroke
				(width 0.1)
				(type default)
			)
			(layer "F.Fab")
		)
		(fp_line
			(start -0.12065 0.3048)
			(end -0.67945 0.3048)
			(stroke
				(width 0.1)
				(type default)
			)
			(layer "F.Fab")
		)
		(fp_line
			(start 0.120396 0.2794)
			(end -0.12065 0.2794)
			(stroke
				(width 0.1)
				(type default)
			)
			(layer "F.Fab")
		)
		(fp_line
			(start 0.120396 0.3048)
			(end 0.120396 0.2794)
			(stroke
				(width 0.1)
				(type default)
			)
			(layer "F.Fab")
		)
		(fp_line
			(start 0.12065 -0.3048)
			(end 0.67945 -0.3048)
			(stroke
				(width 0.1)
				(type default)
			)
			(layer "F.Fab")
		)
		(fp_line
			(start 0.12065 -0.2794)
			(end 0.12065 -0.3048)
			(stroke
				(width 0.1)
				(type default)
			)
			(layer "F.Fab")
		)
		(fp_line
			(start 0.67945 -0.3048)
			(end 0.67945 0.3048)
			(stroke
				(width 0.1)
				(type default)
			)
			(layer "F.Fab")
		)
		(fp_line
			(start 0.67945 0.3048)
			(end 0.120396 0.3048)
			(stroke
				(width 0.1)
				(type default)
			)
			(layer "F.Fab")
		)
		(pad "1" smd circle
			(at -0.40005 0)
			(size 0 0)
			(layers "F.Cu" "F.Mask" "F.Paste")
			(net "RST_PFR_OVR_SRTC_R")
		)
		(pad "2" smd circle
			(at 0.40005 0)
			(size 0 0)
			(layers "F.Cu" "F.Mask" "F.Paste")
			(net "RST_PFR_OVR_SRTC")
		)
	)
	(footprint ""
		(layer "F.Cu")
		(at 126.770384 -66.856356 90)
		(property "Reference" "R927"
			(at 0 0 90)
			(layer "F.SilkS")
			(hide yes)
			(effects
				(font
					(size 1.27 1.27)
				)
			)
		)
		(property "Value" ""
			(at 0 0 90)
			(layer "F.Fab")
			(effects
				(font
					(size 1.27 1.27)
				)
			)
		)
		(duplicate_pad_numbers_are_jumpers no)
		(fp_line
			(start 0.7874 -0.4064)
			(end 0.7874 0.4064)
			(stroke
				(width 0.1524)
				(type default)
			)
			(layer "F.SilkS")
		)
		(fp_line
			(start -0.7874 -0.4064)
			(end 0.7874 -0.4064)
			(stroke
				(width 0.1524)
				(type default)
			)
			(layer "F.SilkS")
		)
		(fp_line
			(start 0.7874 0.4064)
			(end -0.7874 0.4064)
			(stroke
				(width 0.1524)
				(type default)
			)
			(layer "F.SilkS")
		)
		(fp_line
			(start -0.7874 0.4064)
			(end -0.7874 -0.4064)
			(stroke
				(width 0.1524)
				(type default)
			)
			(layer "F.SilkS")
		)
		(fp_line
			(start -0.12065 -0.305054)
			(end -0.12065 -0.2794)
			(stroke
				(width 0.1)
				(type default)
			)
			(layer "F.Fab")
		)
		(fp_line
			(start -0.67945 -0.305054)
			(end -0.12065 -0.305054)
			(stroke
				(width 0.1)
				(type default)
			)
			(layer "F.Fab")
		)
		(fp_line
			(start 0.67945 -0.3048)
			(end 0.67945 0.3048)
			(stroke
				(width 0.1)
				(type default)
			)
			(layer "F.Fab")
		)
		(fp_line
			(start 0.12065 -0.3048)
			(end 0.67945 -0.3048)
			(stroke
				(width 0.1)
				(type default)
			)
			(layer "F.Fab")
		)
		(fp_line
			(start 0.12065 -0.2794)
			(end 0.12065 -0.3048)
			(stroke
				(width 0.1)
				(type default)
			)
			(layer "F.Fab")
		)
		(fp_line
			(start -0.12065 -0.2794)
			(end 0.12065 -0.2794)
			(stroke
				(width 0.1)
				(type default)
			)
			(layer "F.Fab")
		)
		(fp_line
			(start 0.120396 0.2794)
			(end -0.12065 0.2794)
			(stroke
				(width 0.1)
				(type default)
			)
			(layer "F.Fab")
		)
		(fp_line
			(start -0.12065 0.2794)
			(end -0.12065 0.3048)
			(stroke
				(width 0.1)
				(type default)
			)
			(layer "F.Fab")
		)
		(fp_line
			(start 0.67945 0.3048)
			(end 0.120396 0.3048)
			(stroke
				(width 0.1)
				(type default)
			)
			(layer "F.Fab")
		)
		(fp_line
			(start 0.120396 0.3048)
			(end 0.120396 0.2794)
			(stroke
				(width 0.1)
				(type default)
			)
			(layer "F.Fab")
		)
		(fp_line
			(start -0.12065 0.3048)
			(end -0.67945 0.3048)
			(stroke
				(width 0.1)
				(type default)
			)
			(layer "F.Fab")
		)
		(fp_line
			(start -0.67945 0.3048)
			(end -0.67945 -0.305054)
			(stroke
				(width 0.1)
				(type default)
			)
			(layer "F.Fab")
		)
		(pad "1" smd circle
			(at -0.40005 0 90)
			(size 0 0)
			(layers "F.Cu" "F.Mask" "F.Paste")
			(net "P3V3_AUX")
		)
		(pad "2" smd circle
			(at 0.40005 0 90)
			(size 0 0)
			(layers "F.Cu" "F.Mask" "F.Paste")
			(net "JTAG_BMC_PLD_TDI")
		)
	)
	(footprint ""
		(layer "F.Cu")
		(at 27.628596 -394.358876 180)
		(property "Reference" "R3269"
			(at 0 0 180)
			(layer "F.SilkS")
			(hide yes)
			(effects
				(font
					(size 1.27 1.27)
				)
			)
		)
		(property "Value" ""
			(at 0 0 180)
			(layer "F.Fab")
			(effects
				(font
					(size 1.27 1.27)
				)
			)
		)
		(duplicate_pad_numbers_are_jumpers no)
		(fp_line
			(start 0.7874 0.4064)
			(end -0.7874 0.4064)
			(stroke
				(width 0.1524)
				(type default)
			)
			(layer "F.SilkS")
		)
		(fp_line
			(start 0.7874 -0.4064)
			(end 0.7874 0.4064)
			(stroke
				(width 0.1524)
				(type default)
			)
			(layer "F.SilkS")
		)
		(fp_line
			(start -0.7874 0.4064)
			(end -0.7874 -0.4064)
			(stroke
				(width 0.1524)
				(type default)
			)
			(layer "F.SilkS")
		)
		(fp_line
			(start -0.7874 -0.4064)
			(end 0.7874 -0.4064)
			(stroke
				(width 0.1524)
				(type default)
			)
			(layer "F.SilkS")
		)
		(fp_line
			(start 0.67945 0.3048)
			(end 0.120396 0.3048)
			(stroke
				(width 0.1)
				(type default)
			)
			(layer "F.Fab")
		)
		(fp_line
			(start 0.67945 -0.3048)
			(end 0.67945 0.3048)
			(stroke
				(width 0.1)
				(type default)
			)
			(layer "F.Fab")
		)
		(fp_line
			(start 0.12065 -0.2794)
			(end 0.12065 -0.3048)
			(stroke
				(width 0.1)
				(type default)
			)
			(layer "F.Fab")
		)
		(fp_line
			(start 0.12065 -0.3048)
			(end 0.67945 -0.3048)
			(stroke
				(width 0.1)
				(type default)
			)
			(layer "F.Fab")
		)
		(fp_line
			(start 0.120396 0.3048)
			(end 0.120396 0.2794)
			(stroke
				(width 0.1)
				(type default)
			)
			(layer "F.Fab")
		)
		(fp_line
			(start 0.120396 0.2794)
			(end -0.12065 0.2794)
			(stroke
				(width 0.1)
				(type default)
			)
			(layer "F.Fab")
		)
		(fp_line
			(start -0.12065 0.3048)
			(end -0.67945 0.3048)
			(stroke
				(width 0.1)
				(type default)
			)
			(layer "F.Fab")
		)
		(fp_line
			(start -0.12065 0.2794)
			(end -0.12065 0.3048)
			(stroke
				(width 0.1)
				(type default)
			)
			(layer "F.Fab")
		)
		(fp_line
			(start -0.12065 -0.2794)
			(end 0.12065 -0.2794)
			(stroke
				(width 0.1)
				(type default)
			)
			(layer "F.Fab")
		)
		(fp_line
			(start -0.12065 -0.305054)
			(end -0.12065 -0.2794)
			(stroke
				(width 0.1)
				(type default)
			)
			(layer "F.Fab")
		)
		(fp_line
			(start -0.67945 0.3048)
			(end -0.67945 -0.305054)
			(stroke
				(width 0.1)
				(type default)
			)
			(layer "F.Fab")
		)
		(fp_line
			(start -0.67945 -0.305054)
			(end -0.12065 -0.305054)
			(stroke
				(width 0.1)
				(type default)
			)
			(layer "F.Fab")
		)
		(pad "1" smd circle
			(at -0.40005 0 180)
			(size 0 0)
			(layers "F.Cu" "F.Mask" "F.Paste")
			(net "P3V3_AUX")
		)
		(pad "2" smd circle
			(at 0.40005 0 180)
			(size 0 0)
			(layers "F.Cu" "F.Mask" "F.Paste")
			(net "FM_P2E_FGB")
		)
	)
	(footprint ""
		(layer "F.Cu")
		(at 448.177412 -30.131258 90)
		(property "Reference" "PC2154"
			(at 0 0 90)
			(layer "F.SilkS")
			(hide yes)
			(effects
				(font
					(size 1.27 1.27)
				)
			)
		)
		(property "Value" ""
			(at 0 0 90)
			(layer "F.Fab")
			(effects
				(font
					(size 1.27 1.27)
				)
			)
		)
		(duplicate_pad_numbers_are_jumpers no)
		(fp_line
			(start 0.7874 -0.4064)
			(end 0.7874 0.4064)
			(stroke
				(width 0.1524)
				(type default)
			)
			(layer "F.SilkS")
		)
		(fp_line
			(start -0.7874 -0.4064)
			(end 0.7874 -0.4064)
			(stroke
				(width 0.1524)
				(type default)
			)
			(layer "F.SilkS")
		)
		(fp_line
			(start 0.7874 0.4064)
			(end -0.7874 0.4064)
			(stroke
				(width 0.1524)
				(type default)
			)
			(layer "F.SilkS")
		)
		(fp_line
			(start -0.7874 0.4064)
			(end -0.7874 -0.4064)
			(stroke
				(width 0.1524)
				(type default)
			)
			(layer "F.SilkS")
		)
		(fp_line
			(start -0.12065 -0.305054)
			(end -0.12065 -0.2794)
			(stroke
				(width 0.1)
				(type default)
			)
			(layer "F.Fab")
		)
		(fp_line
			(start -0.67945 -0.305054)
			(end -0.12065 -0.305054)
			(stroke
				(width 0.1)
				(type default)
			)
			(layer "F.Fab")
		)
		(fp_line
			(start 0.67945 -0.3048)
			(end 0.67945 0.3048)
			(stroke
				(width 0.1)
				(type default)
			)
			(layer "F.Fab")
		)
		(fp_line
			(start 0.12065 -0.3048)
			(end 0.67945 -0.3048)
			(stroke
				(width 0.1)
				(type default)
			)
			(layer "F.Fab")
		)
		(fp_line
			(start 0.12065 -0.2794)
			(end 0.12065 -0.3048)
			(stroke
				(width 0.1)
				(type default)
			)
			(layer "F.Fab")
		)
		(fp_line
			(start -0.12065 -0.2794)
			(end 0.12065 -0.2794)
			(stroke
				(width 0.1)
				(type default)
			)
			(layer "F.Fab")
		)
		(fp_line
			(start 0.120396 0.2794)
			(end -0.12065 0.2794)
			(stroke
				(width 0.1)
				(type default)
			)
			(layer "F.Fab")
		)
		(fp_line
			(start -0.12065 0.2794)
			(end -0.12065 0.3048)
			(stroke
				(width 0.1)
				(type default)
			)
			(layer "F.Fab")
		)
		(fp_line
			(start 0.67945 0.3048)
			(end 0.120396 0.3048)
			(stroke
				(width 0.1)
				(type default)
			)
			(layer "F.Fab")
		)
		(fp_line
			(start 0.120396 0.3048)
			(end 0.120396 0.2794)
			(stroke
				(width 0.1)
				(type default)
			)
			(layer "F.Fab")
		)
		(fp_line
			(start -0.12065 0.3048)
			(end -0.67945 0.3048)
			(stroke
				(width 0.1)
				(type default)
			)
			(layer "F.Fab")
		)
		(fp_line
			(start -0.67945 0.3048)
			(end -0.67945 -0.305054)
			(stroke
				(width 0.1)
				(type default)
			)
			(layer "F.Fab")
		)
		(pad "1" smd circle
			(at -0.40005 0 90)
			(size 0 0)
			(layers "F.Cu" "F.Mask" "F.Paste")
			(net "P12V_AUX")
		)
		(pad "2" smd circle
			(at 0.40005 0 90)
			(size 0 0)
			(layers "F.Cu" "F.Mask" "F.Paste")
			(net "GND")
		)
	)
	(footprint ""
		(layer "F.Cu")
		(at 331.523848 -402.371052 -90)
		(property "Reference" "C1560"
			(at 0 0 270)
			(layer "F.SilkS")
			(hide yes)
			(effects
				(font
					(size 1.27 1.27)
				)
			)
		)
		(property "Value" ""
			(at 0 0 270)
			(layer "F.Fab")
			(effects
				(font
					(size 1.27 1.27)
				)
			)
		)
		(duplicate_pad_numbers_are_jumpers no)
		(fp_line
			(start -0.299974 0.150114)
			(end -0.299974 -0.150114)
			(stroke
				(width 0.1)
				(type default)
			)
			(layer "F.Fab")
		)
		(fp_line
			(start 0.299974 0.150114)
			(end -0.299974 0.150114)
			(stroke
				(width 0.1)
				(type default)
			)
			(layer "F.Fab")
		)
		(fp_line
			(start -0.299974 -0.150114)
			(end 0.299974 -0.150114)
			(stroke
				(width 0.1)
				(type default)
			)
			(layer "F.Fab")
		)
		(fp_line
			(start 0.299974 -0.150114)
			(end 0.299974 0.150114)
			(stroke
				(width 0.1)
				(type default)
			)
			(layer "F.Fab")
		)
		(pad "1" smd rect
			(at -0.2667 0 270)
			(size 0.3048 0.381)
			(layers "F.Cu" "F.Mask" "F.Paste")
			(net "P5E_CPU0_PE4_TX_C_DN<9>")
		)
		(pad "2" smd rect
			(at 0.2667 0 270)
			(size 0.3048 0.381)
			(layers "F.Cu" "F.Mask" "F.Paste")
			(net "P5E_CPU0_PE4_TX_DN<9>")
		)
	)
	(footprint ""
		(layer "F.Cu")
		(at 418.90188 -156.632148 90)
		(property "Reference" "PC175"
			(at 0 0 90)
			(layer "F.SilkS")
			(hide yes)
			(effects
				(font
					(size 1.27 1.27)
				)
			)
		)
		(property "Value" ""
			(at 0 0 90)
			(layer "F.Fab")
			(effects
				(font
					(size 1.27 1.27)
				)
			)
		)
		(duplicate_pad_numbers_are_jumpers no)
		(fp_line
			(start 0.7874 -0.4064)
			(end 0.7874 0.4064)
			(stroke
				(width 0.1524)
				(type default)
			)
			(layer "F.SilkS")
		)
		(fp_line
			(start -0.7874 -0.4064)
			(end 0.7874 -0.4064)
			(stroke
				(width 0.1524)
				(type default)
			)
			(layer "F.SilkS")
		)
		(fp_line
			(start 0.7874 0.4064)
			(end -0.7874 0.4064)
			(stroke
				(width 0.1524)
				(type default)
			)
			(layer "F.SilkS")
		)
		(fp_line
			(start -0.7874 0.4064)
			(end -0.7874 -0.4064)
			(stroke
				(width 0.1524)
				(type default)
			)
			(layer "F.SilkS")
		)
		(fp_line
			(start -0.12065 -0.305054)
			(end -0.12065 -0.2794)
			(stroke
				(width 0.1)
				(type default)
			)
			(layer "F.Fab")
		)
		(fp_line
			(start -0.67945 -0.305054)
			(end -0.12065 -0.305054)
			(stroke
				(width 0.1)
				(type default)
			)
			(layer "F.Fab")
		)
		(fp_line
			(start 0.67945 -0.3048)
			(end 0.67945 0.3048)
			(stroke
				(width 0.1)
				(type default)
			)
			(layer "F.Fab")
		)
		(fp_line
			(start 0.12065 -0.3048)
			(end 0.67945 -0.3048)
			(stroke
				(width 0.1)
				(type default)
			)
			(layer "F.Fab")
		)
		(fp_line
			(start 0.12065 -0.2794)
			(end 0.12065 -0.3048)
			(stroke
				(width 0.1)
				(type default)
			)
			(layer "F.Fab")
		)
		(fp_line
			(start -0.12065 -0.2794)
			(end 0.12065 -0.2794)
			(stroke
				(width 0.1)
				(type default)
			)
			(layer "F.Fab")
		)
		(fp_line
			(start 0.120396 0.2794)
			(end -0.12065 0.2794)
			(stroke
				(width 0.1)
				(type default)
			)
			(layer "F.Fab")
		)
		(fp_line
			(start -0.12065 0.2794)
			(end -0.12065 0.3048)
			(stroke
				(width 0.1)
				(type default)
			)
			(layer "F.Fab")
		)
		(fp_line
			(start 0.67945 0.3048)
			(end 0.120396 0.3048)
			(stroke
				(width 0.1)
				(type default)
			)
			(layer "F.Fab")
		)
		(fp_line
			(start 0.120396 0.3048)
			(end 0.120396 0.2794)
			(stroke
				(width 0.1)
				(type default)
			)
			(layer "F.Fab")
		)
		(fp_line
			(start -0.12065 0.3048)
			(end -0.67945 0.3048)
			(stroke
				(width 0.1)
				(type default)
			)
			(layer "F.Fab")
		)
		(fp_line
			(start -0.67945 0.3048)
			(end -0.67945 -0.305054)
			(stroke
				(width 0.1)
				(type default)
			)
			(layer "F.Fab")
		)
		(pad "1" smd circle
			(at -0.40005 0 90)
			(size 0 0)
			(layers "F.Cu" "F.Mask" "F.Paste")
			(net "PVCCFA_EHV_CPU0_VDD1")
		)
		(pad "2" smd circle
			(at 0.40005 0 90)
			(size 0 0)
			(layers "F.Cu" "F.Mask" "F.Paste")
			(net "GND")
		)
	)
	(footprint ""
		(layer "F.Cu")
		(at 94.045278 -96.176846)
		(property "Reference" "Q97"
			(at -3.64236 -0.033528 0)
			(unlocked yes)
			(layer "F.SilkS")
			(effects
				(font
					(size 0.7874 0.5842)
					(thickness 0.1524)
				)
			)
		)
		(property "Value" ""
			(at 0 0 0)
			(layer "F.Fab")
			(effects
				(font
					(size 1.27 1.27)
				)
			)
		)
		(duplicate_pad_numbers_are_jumpers no)
		(fp_line
			(start -1.376172 -1.199896)
			(end -0.508 -1.199896)
			(stroke
				(width 0.1524)
				(type default)
			)
			(layer "F.SilkS")
		)
		(fp_line
			(start -1.376172 1.199896)
			(end -1.376172 -1.199896)
			(stroke
				(width 0.1524)
				(type default)
			)
			(layer "F.SilkS")
		)
		(fp_line
			(start -0.508 -1.199896)
			(end 0 -0.762)
			(stroke
				(width 0.1524)
				(type default)
			)
			(layer "F.SilkS")
		)
		(fp_line
			(start 0 -0.762)
			(end 0.508 -1.199896)
			(stroke
				(width 0.1524)
				(type default)
			)
			(layer "F.SilkS")
		)
		(fp_line
			(start 0.508 -1.199896)
			(end 1.376172 -1.199896)
			(stroke
				(width 0.1524)
				(type default)
			)
			(layer "F.SilkS")
		)
		(fp_line
			(start 1.376172 -1.199896)
			(end 1.376172 1.199896)
			(stroke
				(width 0.1524)
				(type default)
			)
			(layer "F.SilkS")
		)
		(fp_line
			(start 1.376172 1.199896)
			(end -1.376172 1.199896)
			(stroke
				(width 0.1524)
				(type default)
			)
			(layer "F.SilkS")
		)
		(fp_poly
			(pts
				(xy -0.9144 -1.302004) (xy -1.2954 -2.064004) (xy -0.5334 -2.064004)
			)
			(stroke
				(width 0)
				(type default)
			)
			(fill yes)
			(layer "F.SilkS")
		)
		(fp_line
			(start -0.674878 -1.100074)
			(end 0.674878 -1.100074)
			(stroke
				(width 0.1)
				(type default)
			)
			(layer "F.Fab")
		)
		(fp_line
			(start -0.674878 1.100074)
			(end -0.674878 -1.100074)
			(stroke
				(width 0.1)
				(type default)
			)
			(layer "F.Fab")
		)
		(fp_line
			(start 0.674878 -1.100074)
			(end 0.674878 1.100074)
			(stroke
				(width 0.1)
				(type default)
			)
			(layer "F.Fab")
		)
		(fp_line
			(start 0.674878 1.100074)
			(end -0.674878 1.100074)
			(stroke
				(width 0.1)
				(type default)
			)
			(layer "F.Fab")
		)
		(fp_poly
			(pts
				(xy -1.4605 -0.7493) (xy -2.2225 -1.1303) (xy -2.2225 -0.3683)
			)
			(stroke
				(width 0)
				(type default)
			)
			(fill yes)
			(layer "F.Fab")
		)
		(pad "1" smd rect
			(at -0.899922 -0.750062 270)
			(size 0.6096 0.6096)
			(layers "F.Cu" "F.Mask" "F.Paste")
			(net "GND")
		)
		(pad "2" smd rect
			(at -0.899922 0 270)
			(size 0.4064 0.6096)
			(layers "F.Cu" "F.Mask" "F.Paste")
			(net "RST_PLD_CPU0_DRAM_EF_N")
		)
		(pad "3" smd rect
			(at -0.899922 0.750062 270)
			(size 0.6096 0.6096)
			(layers "F.Cu" "F.Mask" "F.Paste")
			(net "LED_RST_PLD_CPU0_DRAM_GH_N_D")
		)
		(pad "4" smd rect
			(at 0.899922 0.750062 270)
			(size 0.6096 0.6096)
			(layers "F.Cu" "F.Mask" "F.Paste")
			(net "GND")
		)
		(pad "5" smd rect
			(at 0.899922 0 270)
			(size 0.4064 0.6096)
			(layers "F.Cu" "F.Mask" "F.Paste")
			(net "RST_PLD_CPU0_DRAM_GH_N")
		)
		(pad "6" smd rect
			(at 0.899922 -0.750062 270)
			(size 0.6096 0.6096)
			(layers "F.Cu" "F.Mask" "F.Paste")
			(net "LED_RST_PLD_CPU0_DRAM_EF_N_D")
		)
	)
	(footprint ""
		(layer "F.Cu")
		(at 211.76361 -57.548272 -90)
		(property "Reference" "R3763"
			(at 0 0 270)
			(layer "F.SilkS")
			(hide yes)
			(effects
				(font
					(size 1.27 1.27)
				)
			)
		)
		(property "Value" ""
			(at 0 0 270)
			(layer "F.Fab")
			(effects
				(font
					(size 1.27 1.27)
				)
			)
		)
		(duplicate_pad_numbers_are_jumpers no)
		(fp_line
			(start -0.7874 0.4064)
			(end -0.7874 -0.4064)
			(stroke
				(width 0.1524)
				(type default)
			)
			(layer "F.SilkS")
		)
		(fp_line
			(start 0.7874 0.4064)
			(end -0.7874 0.4064)
			(stroke
				(width 0.1524)
				(type default)
			)
			(layer "F.SilkS")
		)
		(fp_line
			(start -0.7874 -0.4064)
			(end 0.7874 -0.4064)
			(stroke
				(width 0.1524)
				(type default)
			)
			(layer "F.SilkS")
		)
		(fp_line
			(start 0.7874 -0.4064)
			(end 0.7874 0.4064)
			(stroke
				(width 0.1524)
				(type default)
			)
			(layer "F.SilkS")
		)
		(fp_line
			(start -0.67945 0.3048)
			(end -0.67945 -0.305054)
			(stroke
				(width 0.1)
				(type default)
			)
			(layer "F.Fab")
		)
		(fp_line
			(start -0.12065 0.3048)
			(end -0.67945 0.3048)
			(stroke
				(width 0.1)
				(type default)
			)
			(layer "F.Fab")
		)
		(fp_line
			(start 0.120396 0.3048)
			(end 0.120396 0.2794)
			(stroke
				(width 0.1)
				(type default)
			)
			(layer "F.Fab")
		)
		(fp_line
			(start 0.67945 0.3048)
			(end 0.120396 0.3048)
			(stroke
				(width 0.1)
				(type default)
			)
			(layer "F.Fab")
		)
		(fp_line
			(start -0.12065 0.2794)
			(end -0.12065 0.3048)
			(stroke
				(width 0.1)
				(type default)
			)
			(layer "F.Fab")
		)
		(fp_line
			(start 0.120396 0.2794)
			(end -0.12065 0.2794)
			(stroke
				(width 0.1)
				(type default)
			)
			(layer "F.Fab")
		)
		(fp_line
			(start -0.12065 -0.2794)
			(end 0.12065 -0.2794)
			(stroke
				(width 0.1)
				(type default)
			)
			(layer "F.Fab")
		)
		(fp_line
			(start 0.12065 -0.2794)
			(end 0.12065 -0.3048)
			(stroke
				(width 0.1)
				(type default)
			)
			(layer "F.Fab")
		)
		(fp_line
			(start 0.12065 -0.3048)
			(end 0.67945 -0.3048)
			(stroke
				(width 0.1)
				(type default)
			)
			(layer "F.Fab")
		)
		(fp_line
			(start 0.67945 -0.3048)
			(end 0.67945 0.3048)
			(stroke
				(width 0.1)
				(type default)
			)
			(layer "F.Fab")
		)
		(fp_line
			(start -0.67945 -0.305054)
			(end -0.12065 -0.305054)
			(stroke
				(width 0.1)
				(type default)
			)
			(layer "F.Fab")
		)
		(fp_line
			(start -0.12065 -0.305054)
			(end -0.12065 -0.2794)
			(stroke
				(width 0.1)
				(type default)
			)
			(layer "F.Fab")
		)
		(pad "1" smd circle
			(at -0.40005 0 270)
			(size 0 0)
			(layers "F.Cu" "F.Mask" "F.Paste")
			(net "GND")
		)
		(pad "2" smd circle
			(at 0.40005 0 270)
			(size 0 0)
			(layers "F.Cu" "F.Mask" "F.Paste")
			(net "INA230_2_A1")
		)
	)
	(footprint ""
		(layer "F.Cu")
		(at 435.142386 -175.20285 90)
		(property "Reference" "PR4698"
			(at 0 0 90)
			(layer "F.SilkS")
			(hide yes)
			(effects
				(font
					(size 1.27 1.27)
				)
			)
		)
		(property "Value" ""
			(at 0 0 90)
			(layer "F.Fab")
			(effects
				(font
					(size 1.27 1.27)
				)
			)
		)
		(duplicate_pad_numbers_are_jumpers no)
		(fp_line
			(start 0.7874 -0.4064)
			(end 0.7874 0.4064)
			(stroke
				(width 0.1524)
				(type default)
			)
			(layer "F.SilkS")
		)
		(fp_line
			(start -0.7874 -0.4064)
			(end 0.7874 -0.4064)
			(stroke
				(width 0.1524)
				(type default)
			)
			(layer "F.SilkS")
		)
		(fp_line
			(start 0.7874 0.4064)
			(end -0.7874 0.4064)
			(stroke
				(width 0.1524)
				(type default)
			)
			(layer "F.SilkS")
		)
		(fp_line
			(start -0.7874 0.4064)
			(end -0.7874 -0.4064)
			(stroke
				(width 0.1524)
				(type default)
			)
			(layer "F.SilkS")
		)
		(fp_line
			(start -0.12065 -0.305054)
			(end -0.12065 -0.2794)
			(stroke
				(width 0.1)
				(type default)
			)
			(layer "F.Fab")
		)
		(fp_line
			(start -0.67945 -0.305054)
			(end -0.12065 -0.305054)
			(stroke
				(width 0.1)
				(type default)
			)
			(layer "F.Fab")
		)
		(fp_line
			(start 0.67945 -0.3048)
			(end 0.67945 0.3048)
			(stroke
				(width 0.1)
				(type default)
			)
			(layer "F.Fab")
		)
		(fp_line
			(start 0.12065 -0.3048)
			(end 0.67945 -0.3048)
			(stroke
				(width 0.1)
				(type default)
			)
			(layer "F.Fab")
		)
		(fp_line
			(start 0.12065 -0.2794)
			(end 0.12065 -0.3048)
			(stroke
				(width 0.1)
				(type default)
			)
			(layer "F.Fab")
		)
		(fp_line
			(start -0.12065 -0.2794)
			(end 0.12065 -0.2794)
			(stroke
				(width 0.1)
				(type default)
			)
			(layer "F.Fab")
		)
		(fp_line
			(start 0.120396 0.2794)
			(end -0.12065 0.2794)
			(stroke
				(width 0.1)
				(type default)
			)
			(layer "F.Fab")
		)
		(fp_line
			(start -0.12065 0.2794)
			(end -0.12065 0.3048)
			(stroke
				(width 0.1)
				(type default)
			)
			(layer "F.Fab")
		)
		(fp_line
			(start 0.67945 0.3048)
			(end 0.120396 0.3048)
			(stroke
				(width 0.1)
				(type default)
			)
			(layer "F.Fab")
		)
		(fp_line
			(start 0.120396 0.3048)
			(end 0.120396 0.2794)
			(stroke
				(width 0.1)
				(type default)
			)
			(layer "F.Fab")
		)
		(fp_line
			(start -0.12065 0.3048)
			(end -0.67945 0.3048)
			(stroke
				(width 0.1)
				(type default)
			)
			(layer "F.Fab")
		)
		(fp_line
			(start -0.67945 0.3048)
			(end -0.67945 -0.305054)
			(stroke
				(width 0.1)
				(type default)
			)
			(layer "F.Fab")
		)
		(pad "1" smd circle
			(at -0.40005 0 90)
			(size 0 0)
			(layers "F.Cu" "F.Mask" "F.Paste")
			(net "PVNN_MAIN_CPU0_FB_RC")
		)
		(pad "2" smd circle
			(at 0.40005 0 90)
			(size 0 0)
			(layers "F.Cu" "F.Mask" "F.Paste")
			(net "PVNN_MAIN_CPU0")
		)
	)
	(footprint ""
		(layer "F.Cu")
		(at 51.593496 -117.53977)
		(property "Reference" "R3706"
			(at 0 0 0)
			(layer "F.SilkS")
			(hide yes)
			(effects
				(font
					(size 1.27 1.27)
				)
			)
		)
		(property "Value" ""
			(at 0 0 0)
			(layer "F.Fab")
			(effects
				(font
					(size 1.27 1.27)
				)
			)
		)
		(duplicate_pad_numbers_are_jumpers no)
		(fp_line
			(start -0.7874 -0.4064)
			(end 0.7874 -0.4064)
			(stroke
				(width 0.1524)
				(type default)
			)
			(layer "F.SilkS")
		)
		(fp_line
			(start -0.7874 0.4064)
			(end -0.7874 -0.4064)
			(stroke
				(width 0.1524)
				(type default)
			)
			(layer "F.SilkS")
		)
		(fp_line
			(start 0.7874 -0.4064)
			(end 0.7874 0.4064)
			(stroke
				(width 0.1524)
				(type default)
			)
			(layer "F.SilkS")
		)
		(fp_line
			(start 0.7874 0.4064)
			(end -0.7874 0.4064)
			(stroke
				(width 0.1524)
				(type default)
			)
			(layer "F.SilkS")
		)
		(fp_line
			(start -0.67945 -0.305054)
			(end -0.12065 -0.305054)
			(stroke
				(width 0.1)
				(type default)
			)
			(layer "F.Fab")
		)
		(fp_line
			(start -0.67945 0.3048)
			(end -0.67945 -0.305054)
			(stroke
				(width 0.1)
				(type default)
			)
			(layer "F.Fab")
		)
		(fp_line
			(start -0.12065 -0.305054)
			(end -0.12065 -0.2794)
			(stroke
				(width 0.1)
				(type default)
			)
			(layer "F.Fab")
		)
		(fp_line
			(start -0.12065 -0.2794)
			(end 0.12065 -0.2794)
			(stroke
				(width 0.1)
				(type default)
			)
			(layer "F.Fab")
		)
		(fp_line
			(start -0.12065 0.2794)
			(end -0.12065 0.3048)
			(stroke
				(width 0.1)
				(type default)
			)
			(layer "F.Fab")
		)
		(fp_line
			(start -0.12065 0.3048)
			(end -0.67945 0.3048)
			(stroke
				(width 0.1)
				(type default)
			)
			(layer "F.Fab")
		)
		(fp_line
			(start 0.120396 0.2794)
			(end -0.12065 0.2794)
			(stroke
				(width 0.1)
				(type default)
			)
			(layer "F.Fab")
		)
		(fp_line
			(start 0.120396 0.3048)
			(end 0.120396 0.2794)
			(stroke
				(width 0.1)
				(type default)
			)
			(layer "F.Fab")
		)
		(fp_line
			(start 0.12065 -0.3048)
			(end 0.67945 -0.3048)
			(stroke
				(width 0.1)
				(type default)
			)
			(layer "F.Fab")
		)
		(fp_line
			(start 0.12065 -0.2794)
			(end 0.12065 -0.3048)
			(stroke
				(width 0.1)
				(type default)
			)
			(layer "F.Fab")
		)
		(fp_line
			(start 0.67945 -0.3048)
			(end 0.67945 0.3048)
			(stroke
				(width 0.1)
				(type default)
			)
			(layer "F.Fab")
		)
		(fp_line
			(start 0.67945 0.3048)
			(end 0.120396 0.3048)
			(stroke
				(width 0.1)
				(type default)
			)
			(layer "F.Fab")
		)
		(pad "1" smd circle
			(at -0.40005 0)
			(size 0 0)
			(layers "F.Cu" "F.Mask" "F.Paste")
			(net "P3V3_AUX")
		)
		(pad "2" smd circle
			(at 0.40005 0)
			(size 0 0)
			(layers "F.Cu" "F.Mask" "F.Paste")
			(net "PCA9548_PCIE0_ADDR1")
		)
	)
	(footprint ""
		(layer "F.Cu")
		(at 84.181696 -70.78599)
		(property "Reference" "D90"
			(at -43.164506 50.178462 90)
			(unlocked yes)
			(layer "F.SilkS")
			(effects
				(font
					(size 0.635 0.4064)
					(thickness 0.1524)
				)
				(justify left)
			)
		)
		(property "Value" ""
			(at 0 0 0)
			(layer "F.Fab")
			(effects
				(font
					(size 1.27 1.27)
				)
			)
		)
		(duplicate_pad_numbers_are_jumpers no)
		(fp_line
			(start -0.90678 0.4826)
			(end -0.90678 -0.4699)
			(stroke
				(width 0.1524)
				(type default)
			)
			(layer "F.SilkS")
		)
		(fp_line
			(start -0.89408 -0.4826)
			(end 0.90678 -0.4826)
			(stroke
				(width 0.1524)
				(type default)
			)
			(layer "F.SilkS")
		)
		(fp_line
			(start -0.79248 -0.4826)
			(end 1.03378 -0.4826)
			(stroke
				(width 0.1524)
				(type default)
			)
			(layer "F.SilkS")
		)
		(fp_line
			(start -0.64008 -0.4826)
			(end 1.16078 -0.4826)
			(stroke
				(width 0.1524)
				(type default)
			)
			(layer "F.SilkS")
		)
		(fp_line
			(start 0.90678 -0.4826)
			(end 0.90678 0.4826)
			(stroke
				(width 0.1524)
				(type default)
			)
			(layer "F.SilkS")
		)
		(fp_line
			(start 0.90678 0.4826)
			(end -0.90678 0.4826)
			(stroke
				(width 0.1524)
				(type default)
			)
			(layer "F.SilkS")
		)
		(fp_line
			(start 1.03378 -0.4826)
			(end 1.03378 0.4826)
			(stroke
				(width 0.1524)
				(type default)
			)
			(layer "F.SilkS")
		)
		(fp_line
			(start 1.03378 0.4826)
			(end -0.79248 0.4826)
			(stroke
				(width 0.1524)
				(type default)
			)
			(layer "F.SilkS")
		)
		(fp_line
			(start 1.16078 -0.4826)
			(end 1.16078 0.4826)
			(stroke
				(width 0.1524)
				(type default)
			)
			(layer "F.SilkS")
		)
		(fp_line
			(start 1.16078 0.4826)
			(end -0.64008 0.4826)
			(stroke
				(width 0.1524)
				(type default)
			)
			(layer "F.SilkS")
		)
		(fp_line
			(start -0.499872 -0.249936)
			(end 0.499872 -0.249936)
			(stroke
				(width 0.1)
				(type default)
			)
			(layer "F.Fab")
		)
		(fp_line
			(start -0.499872 0.249936)
			(end -0.499872 -0.249936)
			(stroke
				(width 0.1)
				(type default)
			)
			(layer "F.Fab")
		)
		(fp_line
			(start 0.499872 -0.249936)
			(end 0.499872 0.249936)
			(stroke
				(width 0.1)
				(type default)
			)
			(layer "F.Fab")
		)
		(fp_line
			(start 0.499872 0.249936)
			(end -0.499872 0.249936)
			(stroke
				(width 0.1)
				(type default)
			)
			(layer "F.Fab")
		)
		(pad "A" smd rect
			(at -0.47498 0)
			(size 0.6096 0.7112)
			(layers "F.Cu" "F.Mask" "F.Paste")
			(net "LED_RST_PLTRST_N")
		)
		(pad "C" smd rect
			(at 0.47498 0)
			(size 0.6096 0.7112)
			(layers "F.Cu" "F.Mask" "F.Paste")
			(net "LED_RST_PLTRST_N_D")
		)
	)
	(footprint ""
		(layer "F.Cu")
		(at 416.009582 -162.185858 -90)
		(property "Reference" "PU36"
			(at -1.68148 -6.204458 0)
			(unlocked yes)
			(layer "F.SilkS")
			(effects
				(font
					(size 0.7874 0.5842)
					(thickness 0.1524)
				)
				(justify left)
			)
		)
		(property "Value" ""
			(at 0 0 270)
			(layer "F.Fab")
			(effects
				(font
					(size 1.27 1.27)
				)
			)
		)
		(duplicate_pad_numbers_are_jumpers no)
		(fp_line
			(start -2.500122 2.999994)
			(end -2.500122 2.339594)
			(stroke
				(width 0.1524)
				(type default)
			)
			(layer "F.SilkS")
		)
		(fp_line
			(start -2.2987 2.999994)
			(end -2.500122 2.999994)
			(stroke
				(width 0.1524)
				(type default)
			)
			(layer "F.SilkS")
		)
		(fp_line
			(start 2.500122 2.999994)
			(end 2.2987 2.999994)
			(stroke
				(width 0.1524)
				(type default)
			)
			(layer "F.SilkS")
		)
		(fp_line
			(start 2.500122 2.339594)
			(end 2.500122 2.999994)
			(stroke
				(width 0.1524)
				(type default)
			)
			(layer "F.SilkS")
		)
		(fp_line
			(start -2.500122 0.6604)
			(end -2.500122 0.229108)
			(stroke
				(width 0.1524)
				(type default)
			)
			(layer "F.SilkS")
		)
		(fp_line
			(start -2.500122 -2.529078)
			(end -2.500122 -2.999994)
			(stroke
				(width 0.1524)
				(type default)
			)
			(layer "F.SilkS")
		)
		(fp_line
			(start -2.500122 -2.999994)
			(end -2.24409 -2.999994)
			(stroke
				(width 0.1524)
				(type default)
			)
			(layer "F.SilkS")
		)
		(fp_line
			(start 2.31394 -2.999994)
			(end 2.500122 -2.999994)
			(stroke
				(width 0.1524)
				(type default)
			)
			(layer "F.SilkS")
		)
		(fp_line
			(start 2.500122 -2.999994)
			(end 2.500122 -2.44348)
			(stroke
				(width 0.1524)
				(type default)
			)
			(layer "F.SilkS")
		)
		(fp_poly
			(pts
				(xy -4.253992 -2.254758) (xy -5.269992 -1.746758) (xy -5.269992 -2.762758)
			)
			(stroke
				(width 0)
				(type default)
			)
			(fill yes)
			(layer "F.SilkS")
		)
		(fp_line
			(start -2.500122 2.999994)
			(end -2.500122 -2.999994)
			(stroke
				(width 0.1)
				(type default)
			)
			(layer "F.Fab")
		)
		(fp_line
			(start 2.500122 2.999994)
			(end -2.500122 2.999994)
			(stroke
				(width 0.1)
				(type default)
			)
			(layer "F.Fab")
		)
		(fp_line
			(start -2.500122 -2.999994)
			(end 2.500122 -2.999994)
			(stroke
				(width 0.1)
				(type default)
			)
			(layer "F.Fab")
		)
		(fp_line
			(start 2.500122 -2.999994)
			(end 2.500122 2.999994)
			(stroke
				(width 0.1)
				(type default)
			)
			(layer "F.Fab")
		)
		(fp_poly
			(pts
				(xy -4.218432 -2.783078) (xy -4.218432 -1.767078) (xy -3.202432 -2.275078)
			)
			(stroke
				(width 0)
				(type default)
			)
			(fill yes)
			(layer "F.Fab")
		)
		(pad "1" smd rect
			(at -2.400046 -2.275078)
			(size 0.2286 0.6096)
			(layers "F.Cu" "F.Mask" "F.Paste")
			(net "PVCCD_HV_CPU0_VOS")
		)
		(pad "2" smd rect
			(at -2.400046 -1.82499)
			(size 0.2286 0.6096)
			(layers "F.Cu" "F.Mask" "F.Paste")
			(net "GND")
		)
		(pad "3" smd rect
			(at -2.400046 -1.374902)
			(size 0.2286 0.6096)
			(layers "F.Cu" "F.Mask" "F.Paste")
			(net "PVCCD_HV_CPU0_VDD1")
		)
		(pad "4" smd rect
			(at -2.400046 -0.925068)
			(size 0.2286 0.6096)
			(layers "F.Cu" "F.Mask" "F.Paste")
			(net "PVCCFA_EHV_CPU0_PVCC")
		)
		(pad "5" smd rect
			(at -2.400046 -0.47498)
			(size 0.2286 0.6096)
			(layers "F.Cu" "F.Mask" "F.Paste")
			(net "GND")
		)
		(pad "6" smd rect
			(at -2.400046 -0.024892)
			(size 0.2286 0.6096)
			(layers "F.Cu" "F.Mask" "F.Paste")
			(net "Net_1920")
		)
		(pad "7_9-20_24" smd circle
			(at 0 1.150112)
			(size 0 0)
			(layers "F.Cu" "F.Mask" "F.Paste")
			(net "GND")
		)
		(pad "10_19" smd rect
			(at 0 2.899918)
			(size 0.6096 4.318)
			(layers "F.Cu" "F.Mask" "F.Paste")
			(net "SW_PVCCD_HV_CPU0_SW1")
		)
		(pad "25_29" smd rect
			(at 1.549908 -1.279906 180)
			(size 2.0574 2.3114)
			(layers "F.Cu" "F.Mask" "F.Paste")
			(net "SW_P12V_PVCCINFAON_CPU0_FLT")
		)
		(pad "30" smd rect
			(at 2.05994 -2.899918 270)
			(size 0.2286 0.6096)
			(layers "F.Cu" "F.Mask" "F.Paste")
			(net "SW_P12V_PVCCINFAON_CPU0_FLT")
		)
		(pad "31" smd rect
			(at 1.610106 -2.899918 270)
			(size 0.2286 0.6096)
			(layers "F.Cu" "F.Mask" "F.Paste")
			(net "Net_1919")
		)
		(pad "32" smd rect
			(at 1.160018 -2.899918 270)
			(size 0.2286 0.6096)
			(layers "F.Cu" "F.Mask" "F.Paste")
			(net "SW_PVCCD_HV_CPU0_BOOTR1")
		)
		(pad "33" smd rect
			(at 0.70993 -2.899918 270)
			(size 0.2286 0.6096)
			(layers "F.Cu" "F.Mask" "F.Paste")
			(net "SW_PVCCD_HV_CPU0_BOOT1")
		)
		(pad "34" smd rect
			(at 0.260096 -2.899918 270)
			(size 0.2286 0.6096)
			(layers "F.Cu" "F.Mask" "F.Paste")
			(net "PVCCD_HV_CPU0_APWM1")
		)
		(pad "35" smd rect
			(at -0.189992 -2.899918 270)
			(size 0.2286 0.6096)
			(layers "F.Cu" "F.Mask" "F.Paste")
			(net "PVCCD_HV_CPU0_VDD1")
		)
		(pad "36" smd rect
			(at -0.64008 -2.899918 270)
			(size 0.2286 0.6096)
			(layers "F.Cu" "F.Mask" "F.Paste")
			(net "PVCCD_HV_CPU0_ATSEN")
		)
		(pad "37" smd rect
			(at -1.089914 -2.899918 270)
			(size 0.2286 0.6096)
			(layers "F.Cu" "F.Mask" "F.Paste")
			(net "PVCCD_HV_CPU0_LSET1")
		)
		(pad "38" smd rect
			(at -1.540002 -2.899918 270)
			(size 0.2286 0.6096)
			(layers "F.Cu" "F.Mask" "F.Paste")
			(net "PVCCD_HV_CPU0_ACSP1")
		)
		(pad "39" smd rect
			(at -1.99009 -2.899918 270)
			(size 0.2286 0.6096)
			(layers "F.Cu" "F.Mask" "F.Paste")
			(net "PVCCD_HV_CPU0_VREF")
		)
		(pad "40" smd rect
			(at -0.87503 -1.27508 270)
			(size 1.7526 1.9558)
			(layers "F.Cu" "F.Mask" "F.Paste")
			(net "GND")
		)
		(pad "41" smd rect
			(at -1.525016 0.249936 180)
			(size 0.3048 0.4572)
			(layers "F.Cu" "F.Mask" "F.Paste")
			(net "Net_1921")
		)
	)
	(footprint ""
		(layer "F.Cu")
		(at 39.26332 -400.153886 -90)
		(property "Reference" "R4649"
			(at 0 0 270)
			(layer "F.SilkS")
			(hide yes)
			(effects
				(font
					(size 1.27 1.27)
				)
			)
		)
		(property "Value" ""
			(at 0 0 270)
			(layer "F.Fab")
			(effects
				(font
					(size 1.27 1.27)
				)
			)
		)
		(duplicate_pad_numbers_are_jumpers no)
		(fp_line
			(start -0.7874 0.4064)
			(end -0.7874 -0.4064)
			(stroke
				(width 0.1524)
				(type default)
			)
			(layer "F.SilkS")
		)
		(fp_line
			(start 0.7874 0.4064)
			(end -0.7874 0.4064)
			(stroke
				(width 0.1524)
				(type default)
			)
			(layer "F.SilkS")
		)
		(fp_line
			(start -0.7874 -0.4064)
			(end 0.7874 -0.4064)
			(stroke
				(width 0.1524)
				(type default)
			)
			(layer "F.SilkS")
		)
		(fp_line
			(start 0.7874 -0.4064)
			(end 0.7874 0.4064)
			(stroke
				(width 0.1524)
				(type default)
			)
			(layer "F.SilkS")
		)
		(fp_line
			(start -0.67945 0.3048)
			(end -0.67945 -0.305054)
			(stroke
				(width 0.1)
				(type default)
			)
			(layer "F.Fab")
		)
		(fp_line
			(start -0.12065 0.3048)
			(end -0.67945 0.3048)
			(stroke
				(width 0.1)
				(type default)
			)
			(layer "F.Fab")
		)
		(fp_line
			(start 0.120396 0.3048)
			(end 0.120396 0.2794)
			(stroke
				(width 0.1)
				(type default)
			)
			(layer "F.Fab")
		)
		(fp_line
			(start 0.67945 0.3048)
			(end 0.120396 0.3048)
			(stroke
				(width 0.1)
				(type default)
			)
			(layer "F.Fab")
		)
		(fp_line
			(start -0.12065 0.2794)
			(end -0.12065 0.3048)
			(stroke
				(width 0.1)
				(type default)
			)
			(layer "F.Fab")
		)
		(fp_line
			(start 0.120396 0.2794)
			(end -0.12065 0.2794)
			(stroke
				(width 0.1)
				(type default)
			)
			(layer "F.Fab")
		)
		(fp_line
			(start -0.12065 -0.2794)
			(end 0.12065 -0.2794)
			(stroke
				(width 0.1)
				(type default)
			)
			(layer "F.Fab")
		)
		(fp_line
			(start 0.12065 -0.2794)
			(end 0.12065 -0.3048)
			(stroke
				(width 0.1)
				(type default)
			)
			(layer "F.Fab")
		)
		(fp_line
			(start 0.12065 -0.3048)
			(end 0.67945 -0.3048)
			(stroke
				(width 0.1)
				(type default)
			)
			(layer "F.Fab")
		)
		(fp_line
			(start 0.67945 -0.3048)
			(end 0.67945 0.3048)
			(stroke
				(width 0.1)
				(type default)
			)
			(layer "F.Fab")
		)
		(fp_line
			(start -0.67945 -0.305054)
			(end -0.12065 -0.305054)
			(stroke
				(width 0.1)
				(type default)
			)
			(layer "F.Fab")
		)
		(fp_line
			(start -0.12065 -0.305054)
			(end -0.12065 -0.2794)
			(stroke
				(width 0.1)
				(type default)
			)
			(layer "F.Fab")
		)
		(pad "1" smd circle
			(at -0.40005 0 270)
			(size 0 0)
			(layers "F.Cu" "F.Mask" "F.Paste")
			(net "P3V3_AUX")
		)
		(pad "2" smd circle
			(at 0.40005 0 270)
			(size 0 0)
			(layers "F.Cu" "F.Mask" "F.Paste")
			(net "FM_P2E_BUF2_EQA0")
		)
	)
	(footprint ""
		(layer "F.Cu")
		(at 387.633972 -29.10967 -90)
		(property "Reference" "C188"
			(at 0 0 270)
			(layer "F.SilkS")
			(hide yes)
			(effects
				(font
					(size 1.27 1.27)
				)
			)
		)
		(property "Value" ""
			(at 0 0 270)
			(layer "F.Fab")
			(effects
				(font
					(size 1.27 1.27)
				)
			)
		)
		(duplicate_pad_numbers_are_jumpers no)
		(fp_line
			(start -0.7874 0.4064)
			(end -0.7874 -0.4064)
			(stroke
				(width 0.1524)
				(type default)
			)
			(layer "F.SilkS")
		)
		(fp_line
			(start 0.7874 0.4064)
			(end -0.7874 0.4064)
			(stroke
				(width 0.1524)
				(type default)
			)
			(layer "F.SilkS")
		)
		(fp_line
			(start -0.7874 -0.4064)
			(end 0.7874 -0.4064)
			(stroke
				(width 0.1524)
				(type default)
			)
			(layer "F.SilkS")
		)
		(fp_line
			(start 0.7874 -0.4064)
			(end 0.7874 0.4064)
			(stroke
				(width 0.1524)
				(type default)
			)
			(layer "F.SilkS")
		)
		(fp_line
			(start -0.67945 0.3048)
			(end -0.67945 -0.305054)
			(stroke
				(width 0.1)
				(type default)
			)
			(layer "F.Fab")
		)
		(fp_line
			(start -0.12065 0.3048)
			(end -0.67945 0.3048)
			(stroke
				(width 0.1)
				(type default)
			)
			(layer "F.Fab")
		)
		(fp_line
			(start 0.120396 0.3048)
			(end 0.120396 0.2794)
			(stroke
				(width 0.1)
				(type default)
			)
			(layer "F.Fab")
		)
		(fp_line
			(start 0.67945 0.3048)
			(end 0.120396 0.3048)
			(stroke
				(width 0.1)
				(type default)
			)
			(layer "F.Fab")
		)
		(fp_line
			(start -0.12065 0.2794)
			(end -0.12065 0.3048)
			(stroke
				(width 0.1)
				(type default)
			)
			(layer "F.Fab")
		)
		(fp_line
			(start 0.120396 0.2794)
			(end -0.12065 0.2794)
			(stroke
				(width 0.1)
				(type default)
			)
			(layer "F.Fab")
		)
		(fp_line
			(start -0.12065 -0.2794)
			(end 0.12065 -0.2794)
			(stroke
				(width 0.1)
				(type default)
			)
			(layer "F.Fab")
		)
		(fp_line
			(start 0.12065 -0.2794)
			(end 0.12065 -0.3048)
			(stroke
				(width 0.1)
				(type default)
			)
			(layer "F.Fab")
		)
		(fp_line
			(start 0.12065 -0.3048)
			(end 0.67945 -0.3048)
			(stroke
				(width 0.1)
				(type default)
			)
			(layer "F.Fab")
		)
		(fp_line
			(start 0.67945 -0.3048)
			(end 0.67945 0.3048)
			(stroke
				(width 0.1)
				(type default)
			)
			(layer "F.Fab")
		)
		(fp_line
			(start -0.67945 -0.305054)
			(end -0.12065 -0.305054)
			(stroke
				(width 0.1)
				(type default)
			)
			(layer "F.Fab")
		)
		(fp_line
			(start -0.12065 -0.305054)
			(end -0.12065 -0.2794)
			(stroke
				(width 0.1)
				(type default)
			)
			(layer "F.Fab")
		)
		(pad "1" smd circle
			(at -0.40005 0 270)
			(size 0 0)
			(layers "F.Cu" "F.Mask" "F.Paste")
			(net "P3V3_AUX")
		)
		(pad "2" smd circle
			(at 0.40005 0 270)
			(size 0 0)
			(layers "F.Cu" "F.Mask" "F.Paste")
			(net "GND")
		)
	)
	(footprint ""
		(layer "F.Cu")
		(at 353.36988 -294.01008 180)
		(property "Reference" "C212"
			(at 0 0 180)
			(layer "F.SilkS")
			(hide yes)
			(effects
				(font
					(size 1.27 1.27)
				)
			)
		)
		(property "Value" ""
			(at 0 0 180)
			(layer "F.Fab")
			(effects
				(font
					(size 1.27 1.27)
				)
			)
		)
		(duplicate_pad_numbers_are_jumpers no)
		(fp_line
			(start 1.524 0.762)
			(end -1.524 0.762)
			(stroke
				(width 0.1524)
				(type default)
			)
			(layer "F.SilkS")
		)
		(fp_line
			(start 1.524 -0.762)
			(end 1.524 0.762)
			(stroke
				(width 0.1524)
				(type default)
			)
			(layer "F.SilkS")
		)
		(fp_line
			(start -1.524 0.762)
			(end -1.524 -0.762)
			(stroke
				(width 0.1524)
				(type default)
			)
			(layer "F.SilkS")
		)
		(fp_line
			(start -1.524 -0.762)
			(end 1.524 -0.762)
			(stroke
				(width 0.1524)
				(type default)
			)
			(layer "F.SilkS")
		)
		(fp_line
			(start 1.1049 0.724916)
			(end 1.1049 -0.724916)
			(stroke
				(width 0.1)
				(type default)
			)
			(layer "F.Fab")
		)
		(fp_line
			(start 1.1049 -0.724916)
			(end -1.1049 -0.724916)
			(stroke
				(width 0.1)
				(type default)
			)
			(layer "F.Fab")
		)
		(fp_line
			(start -1.1049 0.724916)
			(end 1.1049 0.724916)
			(stroke
				(width 0.1)
				(type default)
			)
			(layer "F.Fab")
		)
		(fp_line
			(start -1.1049 -0.724916)
			(end -1.1049 0.724916)
			(stroke
				(width 0.1)
				(type default)
			)
			(layer "F.Fab")
		)
		(pad "1" smd rect
			(at -0.889 0)
			(size 1.016 1.27)
			(layers "F.Cu" "F.Mask" "F.Paste")
			(net "PVCCIN_CPU0")
		)
		(pad "2" smd rect
			(at 0.889 0)
			(size 1.016 1.27)
			(layers "F.Cu" "F.Mask" "F.Paste")
			(net "GND")
		)
	)
	(footprint ""
		(layer "F.Cu")
		(at 24.050752 -402.806408 180)
		(property "Reference" "C1881"
			(at 0 0 180)
			(layer "F.SilkS")
			(hide yes)
			(effects
				(font
					(size 1.27 1.27)
				)
			)
		)
		(property "Value" ""
			(at 0 0 180)
			(layer "F.Fab")
			(effects
				(font
					(size 1.27 1.27)
				)
			)
		)
		(duplicate_pad_numbers_are_jumpers no)
		(fp_line
			(start 0.7874 0.4064)
			(end -0.7874 0.4064)
			(stroke
				(width 0.1524)
				(type default)
			)
			(layer "F.SilkS")
		)
		(fp_line
			(start 0.7874 -0.4064)
			(end 0.7874 0.4064)
			(stroke
				(width 0.1524)
				(type default)
			)
			(layer "F.SilkS")
		)
		(fp_line
			(start -0.7874 0.4064)
			(end -0.7874 -0.4064)
			(stroke
				(width 0.1524)
				(type default)
			)
			(layer "F.SilkS")
		)
		(fp_line
			(start -0.7874 -0.4064)
			(end 0.7874 -0.4064)
			(stroke
				(width 0.1524)
				(type default)
			)
			(layer "F.SilkS")
		)
		(fp_line
			(start 0.67945 0.3048)
			(end 0.120396 0.3048)
			(stroke
				(width 0.1)
				(type default)
			)
			(layer "F.Fab")
		)
		(fp_line
			(start 0.67945 -0.3048)
			(end 0.67945 0.3048)
			(stroke
				(width 0.1)
				(type default)
			)
			(layer "F.Fab")
		)
		(fp_line
			(start 0.12065 -0.2794)
			(end 0.12065 -0.3048)
			(stroke
				(width 0.1)
				(type default)
			)
			(layer "F.Fab")
		)
		(fp_line
			(start 0.12065 -0.3048)
			(end 0.67945 -0.3048)
			(stroke
				(width 0.1)
				(type default)
			)
			(layer "F.Fab")
		)
		(fp_line
			(start 0.120396 0.3048)
			(end 0.120396 0.2794)
			(stroke
				(width 0.1)
				(type default)
			)
			(layer "F.Fab")
		)
		(fp_line
			(start 0.120396 0.2794)
			(end -0.12065 0.2794)
			(stroke
				(width 0.1)
				(type default)
			)
			(layer "F.Fab")
		)
		(fp_line
			(start -0.12065 0.3048)
			(end -0.67945 0.3048)
			(stroke
				(width 0.1)
				(type default)
			)
			(layer "F.Fab")
		)
		(fp_line
			(start -0.12065 0.2794)
			(end -0.12065 0.3048)
			(stroke
				(width 0.1)
				(type default)
			)
			(layer "F.Fab")
		)
		(fp_line
			(start -0.12065 -0.2794)
			(end 0.12065 -0.2794)
			(stroke
				(width 0.1)
				(type default)
			)
			(layer "F.Fab")
		)
		(fp_line
			(start -0.12065 -0.305054)
			(end -0.12065 -0.2794)
			(stroke
				(width 0.1)
				(type default)
			)
			(layer "F.Fab")
		)
		(fp_line
			(start -0.67945 0.3048)
			(end -0.67945 -0.305054)
			(stroke
				(width 0.1)
				(type default)
			)
			(layer "F.Fab")
		)
		(fp_line
			(start -0.67945 -0.305054)
			(end -0.12065 -0.305054)
			(stroke
				(width 0.1)
				(type default)
			)
			(layer "F.Fab")
		)
		(pad "1" smd circle
			(at -0.40005 0 180)
			(size 0 0)
			(layers "F.Cu" "F.Mask" "F.Paste")
			(net "GPU_FPGA_READY_ISO")
		)
		(pad "2" smd circle
			(at 0.40005 0 180)
			(size 0 0)
			(layers "F.Cu" "F.Mask" "F.Paste")
			(net "GND")
		)
	)
	(footprint ""
		(layer "F.Cu")
		(at 214.75827 -75.254358 90)
		(property "Reference" "R1353"
			(at 0 0 90)
			(layer "F.SilkS")
			(hide yes)
			(effects
				(font
					(size 1.27 1.27)
				)
			)
		)
		(property "Value" ""
			(at 0 0 90)
			(layer "F.Fab")
			(effects
				(font
					(size 1.27 1.27)
				)
			)
		)
		(duplicate_pad_numbers_are_jumpers no)
		(fp_line
			(start 0.7874 -0.4064)
			(end 0.7874 0.4064)
			(stroke
				(width 0.1524)
				(type default)
			)
			(layer "F.SilkS")
		)
		(fp_line
			(start -0.7874 -0.4064)
			(end 0.7874 -0.4064)
			(stroke
				(width 0.1524)
				(type default)
			)
			(layer "F.SilkS")
		)
		(fp_line
			(start 0.7874 0.4064)
			(end -0.7874 0.4064)
			(stroke
				(width 0.1524)
				(type default)
			)
			(layer "F.SilkS")
		)
		(fp_line
			(start -0.7874 0.4064)
			(end -0.7874 -0.4064)
			(stroke
				(width 0.1524)
				(type default)
			)
			(layer "F.SilkS")
		)
		(fp_line
			(start -0.12065 -0.305054)
			(end -0.12065 -0.2794)
			(stroke
				(width 0.1)
				(type default)
			)
			(layer "F.Fab")
		)
		(fp_line
			(start -0.67945 -0.305054)
			(end -0.12065 -0.305054)
			(stroke
				(width 0.1)
				(type default)
			)
			(layer "F.Fab")
		)
		(fp_line
			(start 0.67945 -0.3048)
			(end 0.67945 0.3048)
			(stroke
				(width 0.1)
				(type default)
			)
			(layer "F.Fab")
		)
		(fp_line
			(start 0.12065 -0.3048)
			(end 0.67945 -0.3048)
			(stroke
				(width 0.1)
				(type default)
			)
			(layer "F.Fab")
		)
		(fp_line
			(start 0.12065 -0.2794)
			(end 0.12065 -0.3048)
			(stroke
				(width 0.1)
				(type default)
			)
			(layer "F.Fab")
		)
		(fp_line
			(start -0.12065 -0.2794)
			(end 0.12065 -0.2794)
			(stroke
				(width 0.1)
				(type default)
			)
			(layer "F.Fab")
		)
		(fp_line
			(start 0.120396 0.2794)
			(end -0.12065 0.2794)
			(stroke
				(width 0.1)
				(type default)
			)
			(layer "F.Fab")
		)
		(fp_line
			(start -0.12065 0.2794)
			(end -0.12065 0.3048)
			(stroke
				(width 0.1)
				(type default)
			)
			(layer "F.Fab")
		)
		(fp_line
			(start 0.67945 0.3048)
			(end 0.120396 0.3048)
			(stroke
				(width 0.1)
				(type default)
			)
			(layer "F.Fab")
		)
		(fp_line
			(start 0.120396 0.3048)
			(end 0.120396 0.2794)
			(stroke
				(width 0.1)
				(type default)
			)
			(layer "F.Fab")
		)
		(fp_line
			(start -0.12065 0.3048)
			(end -0.67945 0.3048)
			(stroke
				(width 0.1)
				(type default)
			)
			(layer "F.Fab")
		)
		(fp_line
			(start -0.67945 0.3048)
			(end -0.67945 -0.305054)
			(stroke
				(width 0.1)
				(type default)
			)
			(layer "F.Fab")
		)
		(pad "1" smd circle
			(at -0.40005 0 90)
			(size 0 0)
			(layers "F.Cu" "F.Mask" "F.Paste")
			(net "RMII_BMC_OCP_TX_EN")
		)
		(pad "2" smd circle
			(at 0.40005 0 90)
			(size 0 0)
			(layers "F.Cu" "F.Mask" "F.Paste")
			(net "GND")
		)
	)
	(footprint ""
		(layer "F.Cu")
		(at 149.25421 -42.488104)
		(property "Reference" "U239"
			(at -4.5593 -1.791208 0)
			(unlocked yes)
			(layer "F.SilkS")
			(effects
				(font
					(size 0.7874 0.5842)
					(thickness 0.1524)
				)
				(justify left)
			)
		)
		(property "Value" ""
			(at 0 0 0)
			(layer "F.Fab")
			(effects
				(font
					(size 1.27 1.27)
				)
			)
		)
		(duplicate_pad_numbers_are_jumpers no)
		(fp_line
			(start -1.400048 1.100074)
			(end -1.400048 -1.100074)
			(stroke
				(width 0.1524)
				(type default)
			)
			(layer "F.SilkS")
		)
		(fp_line
			(start 1.400048 -1.100074)
			(end -1.400048 -1.100074)
			(stroke
				(width 0.1524)
				(type default)
			)
			(layer "F.SilkS")
		)
		(fp_line
			(start 1.400048 -1.100074)
			(end 1.400048 1.100074)
			(stroke
				(width 0.1524)
				(type default)
			)
			(layer "F.SilkS")
		)
		(fp_line
			(start 1.400048 1.100074)
			(end -1.400048 1.100074)
			(stroke
				(width 0.1524)
				(type default)
			)
			(layer "F.SilkS")
		)
		(fp_poly
			(pts
				(xy -1.054608 -1.316482) (xy -1.562608 -2.332482) (xy -0.546608 -2.332482)
			)
			(stroke
				(width 0)
				(type default)
			)
			(fill yes)
			(layer "F.SilkS")
		)
		(fp_line
			(start -0.674878 -1.100074)
			(end 0.674878 -1.100074)
			(stroke
				(width 0.1)
				(type default)
			)
			(layer "F.Fab")
		)
		(fp_line
			(start -0.674878 1.100074)
			(end -0.674878 -1.100074)
			(stroke
				(width 0.1)
				(type default)
			)
			(layer "F.Fab")
		)
		(fp_line
			(start 0.674878 -1.100074)
			(end 0.674878 1.100074)
			(stroke
				(width 0.1)
				(type default)
			)
			(layer "F.Fab")
		)
		(fp_line
			(start 0.674878 1.100074)
			(end -0.674878 1.100074)
			(stroke
				(width 0.1)
				(type default)
			)
			(layer "F.Fab")
		)
		(fp_poly
			(pts
				(xy -1.590548 -0.649986) (xy -2.606548 -1.157986) (xy -2.606548 -0.141986)
			)
			(stroke
				(width 0)
				(type default)
			)
			(fill yes)
			(layer "F.Fab")
		)
		(pad "1" smd rect
			(at -0.94996 -0.649986 270)
			(size 0.4318 0.6096)
			(layers "F.Cu" "F.Mask" "F.Paste")
			(net "PU_BUFFER_HDD_ACTIVITY")
		)
		(pad "2" smd rect
			(at -0.94996 0 270)
			(size 0.4318 0.6096)
			(layers "F.Cu" "F.Mask" "F.Paste")
			(net "LED_HDD_ACTIVITY_N")
		)
		(pad "3" smd rect
			(at -0.94996 0.649986 270)
			(size 0.4318 0.6096)
			(layers "F.Cu" "F.Mask" "F.Paste")
			(net "GND")
		)
		(pad "4" smd rect
			(at 0.94996 0.649986 270)
			(size 0.4318 0.6096)
			(layers "F.Cu" "F.Mask" "F.Paste")
			(net "LED_HDD_ACTIVITY_B_N")
		)
		(pad "5" smd rect
			(at 0.94996 -0.649986 270)
			(size 0.4318 0.6096)
			(layers "F.Cu" "F.Mask" "F.Paste")
			(net "P3V3_AUX")
		)
	)
	(footprint ""
		(layer "F.Cu")
		(at 293.497 -346.700348)
		(property "Reference" "PC620"
			(at 0 0 0)
			(layer "F.SilkS")
			(hide yes)
			(effects
				(font
					(size 1.27 1.27)
				)
			)
		)
		(property "Value" ""
			(at 0 0 0)
			(layer "F.Fab")
			(effects
				(font
					(size 1.27 1.27)
				)
			)
		)
		(duplicate_pad_numbers_are_jumpers no)
		(fp_line
			(start 2.750058 0.999998)
			(end -2.750058 0.999998)
			(stroke
				(width 0.1524)
				(type default)
			)
			(layer "F.SilkS")
		)
		(fp_circle
			(center 0 0.999998)
			(end 2.750058 0.999998)
			(stroke
				(width 0.1524)
				(type default)
			)
			(fill no)
			(layer "F.SilkS")
		)
		(fp_poly
			(pts
				(arc
					(start 2.750058 0.999998)
					(mid 0 3.750056)
					(end -2.750058 0.999998)
				)
			)
			(stroke
				(width 0)
				(type default)
			)
			(fill yes)
			(layer "F.SilkS")
		)
		(fp_circle
			(center 0 0.999998)
			(end 2.750058 0.999998)
			(stroke
				(width 0.1)
				(type default)
			)
			(fill no)
			(layer "F.Fab")
		)
		(pad "1" thru_hole rect
			(at 0 0)
			(size 1.5748 1.5748)
			(drill 1.0668)
			(layers "*.Cu" "*.Mask")
			(remove_unused_layers no)
			(net "PVCCFA_EHV_FIVRA_CPU0")
			(clearance 0)
			(padstack
				(mode front_inner_back)
				(layer "Inner"
					(shape circle)
					(size 1.5748 1.5748)
					(clearance 0)
				)
				(layer "B.Cu"
					(shape rect)
					(size 1.5748 1.5748)
					(clearance 0)
				)
			)
		)
		(pad "2" thru_hole circle
			(at 0 1.999996)
			(size 1.5748 1.5748)
			(drill 1.0668)
			(layers "*.Cu" "*.Mask")
			(remove_unused_layers no)
			(net "GND")
			(clearance 0)
		)
	)
	(footprint ""
		(layer "F.Cu")
		(at 449.973954 -118.336822 180)
		(property "Reference" "R1126"
			(at 0 0 180)
			(layer "F.SilkS")
			(hide yes)
			(effects
				(font
					(size 1.27 1.27)
				)
			)
		)
		(property "Value" ""
			(at 0 0 180)
			(layer "F.Fab")
			(effects
				(font
					(size 1.27 1.27)
				)
			)
		)
		(duplicate_pad_numbers_are_jumpers no)
		(fp_line
			(start 0.7874 0.4064)
			(end -0.7874 0.4064)
			(stroke
				(width 0.1524)
				(type default)
			)
			(layer "F.SilkS")
		)
		(fp_line
			(start 0.7874 -0.4064)
			(end 0.7874 0.4064)
			(stroke
				(width 0.1524)
				(type default)
			)
			(layer "F.SilkS")
		)
		(fp_line
			(start -0.7874 0.4064)
			(end -0.7874 -0.4064)
			(stroke
				(width 0.1524)
				(type default)
			)
			(layer "F.SilkS")
		)
		(fp_line
			(start -0.7874 -0.4064)
			(end 0.7874 -0.4064)
			(stroke
				(width 0.1524)
				(type default)
			)
			(layer "F.SilkS")
		)
		(fp_line
			(start 0.67945 0.3048)
			(end 0.120396 0.3048)
			(stroke
				(width 0.1)
				(type default)
			)
			(layer "F.Fab")
		)
		(fp_line
			(start 0.67945 -0.3048)
			(end 0.67945 0.3048)
			(stroke
				(width 0.1)
				(type default)
			)
			(layer "F.Fab")
		)
		(fp_line
			(start 0.12065 -0.2794)
			(end 0.12065 -0.3048)
			(stroke
				(width 0.1)
				(type default)
			)
			(layer "F.Fab")
		)
		(fp_line
			(start 0.12065 -0.3048)
			(end 0.67945 -0.3048)
			(stroke
				(width 0.1)
				(type default)
			)
			(layer "F.Fab")
		)
		(fp_line
			(start 0.120396 0.3048)
			(end 0.120396 0.2794)
			(stroke
				(width 0.1)
				(type default)
			)
			(layer "F.Fab")
		)
		(fp_line
			(start 0.120396 0.2794)
			(end -0.12065 0.2794)
			(stroke
				(width 0.1)
				(type default)
			)
			(layer "F.Fab")
		)
		(fp_line
			(start -0.12065 0.3048)
			(end -0.67945 0.3048)
			(stroke
				(width 0.1)
				(type default)
			)
			(layer "F.Fab")
		)
		(fp_line
			(start -0.12065 0.2794)
			(end -0.12065 0.3048)
			(stroke
				(width 0.1)
				(type default)
			)
			(layer "F.Fab")
		)
		(fp_line
			(start -0.12065 -0.2794)
			(end 0.12065 -0.2794)
			(stroke
				(width 0.1)
				(type default)
			)
			(layer "F.Fab")
		)
		(fp_line
			(start -0.12065 -0.305054)
			(end -0.12065 -0.2794)
			(stroke
				(width 0.1)
				(type default)
			)
			(layer "F.Fab")
		)
		(fp_line
			(start -0.67945 0.3048)
			(end -0.67945 -0.305054)
			(stroke
				(width 0.1)
				(type default)
			)
			(layer "F.Fab")
		)
		(fp_line
			(start -0.67945 -0.305054)
			(end -0.12065 -0.305054)
			(stroke
				(width 0.1)
				(type default)
			)
			(layer "F.Fab")
		)
		(pad "1" smd circle
			(at -0.40005 0 180)
			(size 0 0)
			(layers "F.Cu" "F.Mask" "F.Paste")
			(net "PD_SMB_OCP1_HP_ADD1")
		)
		(pad "2" smd circle
			(at 0.40005 0 180)
			(size 0 0)
			(layers "F.Cu" "F.Mask" "F.Paste")
			(net "GND")
		)
	)
	(footprint ""
		(layer "F.Cu")
		(at 193.3956 -125.336808 180)
		(property "Reference" "R4086"
			(at 0 0 180)
			(layer "F.SilkS")
			(hide yes)
			(effects
				(font
					(size 1.27 1.27)
				)
			)
		)
		(property "Value" ""
			(at 0 0 180)
			(layer "F.Fab")
			(effects
				(font
					(size 1.27 1.27)
				)
			)
		)
		(duplicate_pad_numbers_are_jumpers no)
		(fp_line
			(start 0.7874 0.4064)
			(end -0.7874 0.4064)
			(stroke
				(width 0.1524)
				(type default)
			)
			(layer "F.SilkS")
		)
		(fp_line
			(start 0.7874 -0.4064)
			(end 0.7874 0.4064)
			(stroke
				(width 0.1524)
				(type default)
			)
			(layer "F.SilkS")
		)
		(fp_line
			(start -0.7874 0.4064)
			(end -0.7874 -0.4064)
			(stroke
				(width 0.1524)
				(type default)
			)
			(layer "F.SilkS")
		)
		(fp_line
			(start -0.7874 -0.4064)
			(end 0.7874 -0.4064)
			(stroke
				(width 0.1524)
				(type default)
			)
			(layer "F.SilkS")
		)
		(fp_line
			(start 0.67945 0.3048)
			(end 0.120396 0.3048)
			(stroke
				(width 0.1)
				(type default)
			)
			(layer "F.Fab")
		)
		(fp_line
			(start 0.67945 -0.3048)
			(end 0.67945 0.3048)
			(stroke
				(width 0.1)
				(type default)
			)
			(layer "F.Fab")
		)
		(fp_line
			(start 0.12065 -0.2794)
			(end 0.12065 -0.3048)
			(stroke
				(width 0.1)
				(type default)
			)
			(layer "F.Fab")
		)
		(fp_line
			(start 0.12065 -0.3048)
			(end 0.67945 -0.3048)
			(stroke
				(width 0.1)
				(type default)
			)
			(layer "F.Fab")
		)
		(fp_line
			(start 0.120396 0.3048)
			(end 0.120396 0.2794)
			(stroke
				(width 0.1)
				(type default)
			)
			(layer "F.Fab")
		)
		(fp_line
			(start 0.120396 0.2794)
			(end -0.12065 0.2794)
			(stroke
				(width 0.1)
				(type default)
			)
			(layer "F.Fab")
		)
		(fp_line
			(start -0.12065 0.3048)
			(end -0.67945 0.3048)
			(stroke
				(width 0.1)
				(type default)
			)
			(layer "F.Fab")
		)
		(fp_line
			(start -0.12065 0.2794)
			(end -0.12065 0.3048)
			(stroke
				(width 0.1)
				(type default)
			)
			(layer "F.Fab")
		)
		(fp_line
			(start -0.12065 -0.2794)
			(end 0.12065 -0.2794)
			(stroke
				(width 0.1)
				(type default)
			)
			(layer "F.Fab")
		)
		(fp_line
			(start -0.12065 -0.305054)
			(end -0.12065 -0.2794)
			(stroke
				(width 0.1)
				(type default)
			)
			(layer "F.Fab")
		)
		(fp_line
			(start -0.67945 0.3048)
			(end -0.67945 -0.305054)
			(stroke
				(width 0.1)
				(type default)
			)
			(layer "F.Fab")
		)
		(fp_line
			(start -0.67945 -0.305054)
			(end -0.12065 -0.305054)
			(stroke
				(width 0.1)
				(type default)
			)
			(layer "F.Fab")
		)
		(pad "1" smd circle
			(at -0.40005 0 180)
			(size 0 0)
			(layers "F.Cu" "F.Mask" "F.Paste")
			(net "P3V3_AUX_FPGA_VCCIO2")
		)
		(pad "2" smd circle
			(at 0.40005 0 180)
			(size 0 0)
			(layers "F.Cu" "F.Mask" "F.Paste")
			(net "PULL_FPGA_PB46A")
		)
	)
	(footprint ""
		(layer "F.Cu")
		(at 22.723094 -168.181274 90)
		(property "Reference" "R2557"
			(at 0 0 90)
			(layer "F.SilkS")
			(hide yes)
			(effects
				(font
					(size 1.27 1.27)
				)
			)
		)
		(property "Value" ""
			(at 0 0 90)
			(layer "F.Fab")
			(effects
				(font
					(size 1.27 1.27)
				)
			)
		)
		(duplicate_pad_numbers_are_jumpers no)
		(fp_line
			(start 0.7874 -0.4064)
			(end 0.7874 0.4064)
			(stroke
				(width 0.1524)
				(type default)
			)
			(layer "F.SilkS")
		)
		(fp_line
			(start -0.7874 -0.4064)
			(end 0.7874 -0.4064)
			(stroke
				(width 0.1524)
				(type default)
			)
			(layer "F.SilkS")
		)
		(fp_line
			(start 0.7874 0.4064)
			(end -0.7874 0.4064)
			(stroke
				(width 0.1524)
				(type default)
			)
			(layer "F.SilkS")
		)
		(fp_line
			(start -0.7874 0.4064)
			(end -0.7874 -0.4064)
			(stroke
				(width 0.1524)
				(type default)
			)
			(layer "F.SilkS")
		)
		(fp_line
			(start -0.12065 -0.305054)
			(end -0.12065 -0.2794)
			(stroke
				(width 0.1)
				(type default)
			)
			(layer "F.Fab")
		)
		(fp_line
			(start -0.67945 -0.305054)
			(end -0.12065 -0.305054)
			(stroke
				(width 0.1)
				(type default)
			)
			(layer "F.Fab")
		)
		(fp_line
			(start 0.67945 -0.3048)
			(end 0.67945 0.3048)
			(stroke
				(width 0.1)
				(type default)
			)
			(layer "F.Fab")
		)
		(fp_line
			(start 0.12065 -0.3048)
			(end 0.67945 -0.3048)
			(stroke
				(width 0.1)
				(type default)
			)
			(layer "F.Fab")
		)
		(fp_line
			(start 0.12065 -0.2794)
			(end 0.12065 -0.3048)
			(stroke
				(width 0.1)
				(type default)
			)
			(layer "F.Fab")
		)
		(fp_line
			(start -0.12065 -0.2794)
			(end 0.12065 -0.2794)
			(stroke
				(width 0.1)
				(type default)
			)
			(layer "F.Fab")
		)
		(fp_line
			(start 0.120396 0.2794)
			(end -0.12065 0.2794)
			(stroke
				(width 0.1)
				(type default)
			)
			(layer "F.Fab")
		)
		(fp_line
			(start -0.12065 0.2794)
			(end -0.12065 0.3048)
			(stroke
				(width 0.1)
				(type default)
			)
			(layer "F.Fab")
		)
		(fp_line
			(start 0.67945 0.3048)
			(end 0.120396 0.3048)
			(stroke
				(width 0.1)
				(type default)
			)
			(layer "F.Fab")
		)
		(fp_line
			(start 0.120396 0.3048)
			(end 0.120396 0.2794)
			(stroke
				(width 0.1)
				(type default)
			)
			(layer "F.Fab")
		)
		(fp_line
			(start -0.12065 0.3048)
			(end -0.67945 0.3048)
			(stroke
				(width 0.1)
				(type default)
			)
			(layer "F.Fab")
		)
		(fp_line
			(start -0.67945 0.3048)
			(end -0.67945 -0.305054)
			(stroke
				(width 0.1)
				(type default)
			)
			(layer "F.Fab")
		)
		(pad "1" smd circle
			(at -0.40005 0 90)
			(size 0 0)
			(layers "F.Cu" "F.Mask" "F.Paste")
			(net "IRQ_PVCCD_CPU1_VRHOT_LVC3_R_N")
		)
		(pad "2" smd circle
			(at 0.40005 0 90)
			(size 0 0)
			(layers "F.Cu" "F.Mask" "F.Paste")
			(net "IRQ_PVCCD_CPU1_VRHOT_LVC3_N")
		)
	)
	(footprint ""
		(layer "F.Cu")
		(at 177.156364 -337.483958)
		(property "Reference" "PC1204"
			(at 0 0 0)
			(layer "F.SilkS")
			(hide yes)
			(effects
				(font
					(size 1.27 1.27)
				)
			)
		)
		(property "Value" ""
			(at 0 0 0)
			(layer "F.Fab")
			(effects
				(font
					(size 1.27 1.27)
				)
			)
		)
		(duplicate_pad_numbers_are_jumpers no)
		(fp_line
			(start 2.750058 0.999998)
			(end -2.750058 0.999998)
			(stroke
				(width 0.1524)
				(type default)
			)
			(layer "F.SilkS")
		)
		(fp_circle
			(center 0 0.999998)
			(end 2.750058 0.999998)
			(stroke
				(width 0.1524)
				(type default)
			)
			(fill no)
			(layer "F.SilkS")
		)
		(fp_poly
			(pts
				(arc
					(start 2.750058 0.999998)
					(mid 0 3.750056)
					(end -2.750058 0.999998)
				)
			)
			(stroke
				(width 0)
				(type default)
			)
			(fill yes)
			(layer "F.SilkS")
		)
		(fp_circle
			(center 0 0.999998)
			(end 2.750058 0.999998)
			(stroke
				(width 0.1)
				(type default)
			)
			(fill no)
			(layer "F.Fab")
		)
		(pad "1" thru_hole rect
			(at 0 0)
			(size 1.5748 1.5748)
			(drill 1.0668)
			(layers "*.Cu" "*.Mask")
			(remove_unused_layers no)
			(net "PVCCFA_EHV_FIVRA_CPU1")
			(clearance 0)
			(padstack
				(mode front_inner_back)
				(layer "Inner"
					(shape circle)
					(size 1.5748 1.5748)
					(clearance 0)
				)
				(layer "B.Cu"
					(shape rect)
					(size 1.5748 1.5748)
					(clearance 0)
				)
			)
		)
		(pad "2" thru_hole circle
			(at 0 1.999996)
			(size 1.5748 1.5748)
			(drill 1.0668)
			(layers "*.Cu" "*.Mask")
			(remove_unused_layers no)
			(net "GND")
			(clearance 0)
		)
	)
	(footprint ""
		(layer "F.Cu")
		(at 150.57247 -92.291916)
		(property "Reference" "R4392"
			(at 0 0 0)
			(layer "F.SilkS")
			(hide yes)
			(effects
				(font
					(size 1.27 1.27)
				)
			)
		)
		(property "Value" ""
			(at 0 0 0)
			(layer "F.Fab")
			(effects
				(font
					(size 1.27 1.27)
				)
			)
		)
		(duplicate_pad_numbers_are_jumpers no)
		(fp_line
			(start -0.7874 -0.4064)
			(end 0.7874 -0.4064)
			(stroke
				(width 0.1524)
				(type default)
			)
			(layer "F.SilkS")
		)
		(fp_line
			(start -0.7874 0.4064)
			(end -0.7874 -0.4064)
			(stroke
				(width 0.1524)
				(type default)
			)
			(layer "F.SilkS")
		)
		(fp_line
			(start 0.7874 -0.4064)
			(end 0.7874 0.4064)
			(stroke
				(width 0.1524)
				(type default)
			)
			(layer "F.SilkS")
		)
		(fp_line
			(start 0.7874 0.4064)
			(end -0.7874 0.4064)
			(stroke
				(width 0.1524)
				(type default)
			)
			(layer "F.SilkS")
		)
		(fp_line
			(start -0.67945 -0.305054)
			(end -0.12065 -0.305054)
			(stroke
				(width 0.1)
				(type default)
			)
			(layer "F.Fab")
		)
		(fp_line
			(start -0.67945 0.3048)
			(end -0.67945 -0.305054)
			(stroke
				(width 0.1)
				(type default)
			)
			(layer "F.Fab")
		)
		(fp_line
			(start -0.12065 -0.305054)
			(end -0.12065 -0.2794)
			(stroke
				(width 0.1)
				(type default)
			)
			(layer "F.Fab")
		)
		(fp_line
			(start -0.12065 -0.2794)
			(end 0.12065 -0.2794)
			(stroke
				(width 0.1)
				(type default)
			)
			(layer "F.Fab")
		)
		(fp_line
			(start -0.12065 0.2794)
			(end -0.12065 0.3048)
			(stroke
				(width 0.1)
				(type default)
			)
			(layer "F.Fab")
		)
		(fp_line
			(start -0.12065 0.3048)
			(end -0.67945 0.3048)
			(stroke
				(width 0.1)
				(type default)
			)
			(layer "F.Fab")
		)
		(fp_line
			(start 0.120396 0.2794)
			(end -0.12065 0.2794)
			(stroke
				(width 0.1)
				(type default)
			)
			(layer "F.Fab")
		)
		(fp_line
			(start 0.120396 0.3048)
			(end 0.120396 0.2794)
			(stroke
				(width 0.1)
				(type default)
			)
			(layer "F.Fab")
		)
		(fp_line
			(start 0.12065 -0.3048)
			(end 0.67945 -0.3048)
			(stroke
				(width 0.1)
				(type default)
			)
			(layer "F.Fab")
		)
		(fp_line
			(start 0.12065 -0.2794)
			(end 0.12065 -0.3048)
			(stroke
				(width 0.1)
				(type default)
			)
			(layer "F.Fab")
		)
		(fp_line
			(start 0.67945 -0.3048)
			(end 0.67945 0.3048)
			(stroke
				(width 0.1)
				(type default)
			)
			(layer "F.Fab")
		)
		(fp_line
			(start 0.67945 0.3048)
			(end 0.120396 0.3048)
			(stroke
				(width 0.1)
				(type default)
			)
			(layer "F.Fab")
		)
		(pad "1" smd circle
			(at -0.40005 0)
			(size 0 0)
			(layers "F.Cu" "F.Mask" "F.Paste")
			(net "H_CPU_ERR0_LVC2_R_N")
		)
		(pad "2" smd circle
			(at 0.40005 0)
			(size 0 0)
			(layers "F.Cu" "F.Mask" "F.Paste")
			(net "H_CPU_ERR0_PCH_R_N")
		)
	)
	(footprint ""
		(layer "F.Cu")
		(at 55.87873 -16.099536 90)
		(property "Reference" "C834"
			(at 0 0 90)
			(layer "F.SilkS")
			(hide yes)
			(effects
				(font
					(size 1.27 1.27)
				)
			)
		)
		(property "Value" ""
			(at 0 0 90)
			(layer "F.Fab")
			(effects
				(font
					(size 1.27 1.27)
				)
			)
		)
		(duplicate_pad_numbers_are_jumpers no)
		(fp_line
			(start 0.299974 -0.150114)
			(end 0.299974 0.150114)
			(stroke
				(width 0.1)
				(type default)
			)
			(layer "F.Fab")
		)
		(fp_line
			(start -0.299974 -0.150114)
			(end 0.299974 -0.150114)
			(stroke
				(width 0.1)
				(type default)
			)
			(layer "F.Fab")
		)
		(fp_line
			(start 0.299974 0.150114)
			(end -0.299974 0.150114)
			(stroke
				(width 0.1)
				(type default)
			)
			(layer "F.Fab")
		)
		(fp_line
			(start -0.299974 0.150114)
			(end -0.299974 -0.150114)
			(stroke
				(width 0.1)
				(type default)
			)
			(layer "F.Fab")
		)
		(pad "1" smd rect
			(at -0.2667 0 90)
			(size 0.3048 0.381)
			(layers "F.Cu" "F.Mask" "F.Paste")
			(net "P5E_CPU1_PE1_TX_C_DN<1>")
		)
		(pad "2" smd rect
			(at 0.2667 0 90)
			(size 0.3048 0.381)
			(layers "F.Cu" "F.Mask" "F.Paste")
			(net "P5E_CPU1_PE1_TX_DN<1>")
		)
	)
	(footprint ""
		(layer "F.Cu")
		(at 430.386236 -16.088614 90)
		(property "Reference" "C866"
			(at 0 0 90)
			(layer "F.SilkS")
			(hide yes)
			(effects
				(font
					(size 1.27 1.27)
				)
			)
		)
		(property "Value" ""
			(at 0 0 90)
			(layer "F.Fab")
			(effects
				(font
					(size 1.27 1.27)
				)
			)
		)
		(duplicate_pad_numbers_are_jumpers no)
		(fp_line
			(start 0.299974 -0.150114)
			(end 0.299974 0.150114)
			(stroke
				(width 0.1)
				(type default)
			)
			(layer "F.Fab")
		)
		(fp_line
			(start -0.299974 -0.150114)
			(end 0.299974 -0.150114)
			(stroke
				(width 0.1)
				(type default)
			)
			(layer "F.Fab")
		)
		(fp_line
			(start 0.299974 0.150114)
			(end -0.299974 0.150114)
			(stroke
				(width 0.1)
				(type default)
			)
			(layer "F.Fab")
		)
		(fp_line
			(start -0.299974 0.150114)
			(end -0.299974 -0.150114)
			(stroke
				(width 0.1)
				(type default)
			)
			(layer "F.Fab")
		)
		(pad "1" smd rect
			(at -0.2667 0 90)
			(size 0.3048 0.381)
			(layers "F.Cu" "F.Mask" "F.Paste")
			(net "P5E_CPU0_PE1_TX_C_DN<1>")
		)
		(pad "2" smd rect
			(at 0.2667 0 90)
			(size 0.3048 0.381)
			(layers "F.Cu" "F.Mask" "F.Paste")
			(net "P5E_CPU0_PE1_TX_DN<1>")
		)
	)
	(footprint ""
		(layer "F.Cu")
		(at 127.288544 -74.853292 -90)
		(property "Reference" "C1322"
			(at 0 0 270)
			(layer "F.SilkS")
			(hide yes)
			(effects
				(font
					(size 1.27 1.27)
				)
			)
		)
		(property "Value" ""
			(at 0 0 270)
			(layer "F.Fab")
			(effects
				(font
					(size 1.27 1.27)
				)
			)
		)
		(duplicate_pad_numbers_are_jumpers no)
		(fp_line
			(start -0.7874 0.4064)
			(end -0.7874 -0.4064)
			(stroke
				(width 0.1524)
				(type default)
			)
			(layer "F.SilkS")
		)
		(fp_line
			(start 0.7874 0.4064)
			(end -0.7874 0.4064)
			(stroke
				(width 0.1524)
				(type default)
			)
			(layer "F.SilkS")
		)
		(fp_line
			(start -0.7874 -0.4064)
			(end 0.7874 -0.4064)
			(stroke
				(width 0.1524)
				(type default)
			)
			(layer "F.SilkS")
		)
		(fp_line
			(start 0.7874 -0.4064)
			(end 0.7874 0.4064)
			(stroke
				(width 0.1524)
				(type default)
			)
			(layer "F.SilkS")
		)
		(fp_line
			(start -0.67945 0.3048)
			(end -0.67945 -0.305054)
			(stroke
				(width 0.1)
				(type default)
			)
			(layer "F.Fab")
		)
		(fp_line
			(start -0.12065 0.3048)
			(end -0.67945 0.3048)
			(stroke
				(width 0.1)
				(type default)
			)
			(layer "F.Fab")
		)
		(fp_line
			(start 0.120396 0.3048)
			(end 0.120396 0.2794)
			(stroke
				(width 0.1)
				(type default)
			)
			(layer "F.Fab")
		)
		(fp_line
			(start 0.67945 0.3048)
			(end 0.120396 0.3048)
			(stroke
				(width 0.1)
				(type default)
			)
			(layer "F.Fab")
		)
		(fp_line
			(start -0.12065 0.2794)
			(end -0.12065 0.3048)
			(stroke
				(width 0.1)
				(type default)
			)
			(layer "F.Fab")
		)
		(fp_line
			(start 0.120396 0.2794)
			(end -0.12065 0.2794)
			(stroke
				(width 0.1)
				(type default)
			)
			(layer "F.Fab")
		)
		(fp_line
			(start -0.12065 -0.2794)
			(end 0.12065 -0.2794)
			(stroke
				(width 0.1)
				(type default)
			)
			(layer "F.Fab")
		)
		(fp_line
			(start 0.12065 -0.2794)
			(end 0.12065 -0.3048)
			(stroke
				(width 0.1)
				(type default)
			)
			(layer "F.Fab")
		)
		(fp_line
			(start 0.12065 -0.3048)
			(end 0.67945 -0.3048)
			(stroke
				(width 0.1)
				(type default)
			)
			(layer "F.Fab")
		)
		(fp_line
			(start 0.67945 -0.3048)
			(end 0.67945 0.3048)
			(stroke
				(width 0.1)
				(type default)
			)
			(layer "F.Fab")
		)
		(fp_line
			(start -0.67945 -0.305054)
			(end -0.12065 -0.305054)
			(stroke
				(width 0.1)
				(type default)
			)
			(layer "F.Fab")
		)
		(fp_line
			(start -0.12065 -0.305054)
			(end -0.12065 -0.2794)
			(stroke
				(width 0.1)
				(type default)
			)
			(layer "F.Fab")
		)
		(pad "1" smd circle
			(at -0.40005 0 270)
			(size 0 0)
			(layers "F.Cu" "F.Mask" "F.Paste")
			(net "P3V3_AUX")
		)
		(pad "2" smd circle
			(at 0.40005 0 270)
			(size 0 0)
			(layers "F.Cu" "F.Mask" "F.Paste")
			(net "GND")
		)
	)
	(footprint ""
		(layer "F.Cu")
		(at 15.197582 -408.516836 90)
		(property "Reference" "R2921"
			(at 0 0 90)
			(layer "F.SilkS")
			(hide yes)
			(effects
				(font
					(size 1.27 1.27)
				)
			)
		)
		(property "Value" ""
			(at 0 0 90)
			(layer "F.Fab")
			(effects
				(font
					(size 1.27 1.27)
				)
			)
		)
		(duplicate_pad_numbers_are_jumpers no)
		(fp_line
			(start 0.7874 -0.4064)
			(end 0.7874 0.4064)
			(stroke
				(width 0.1524)
				(type default)
			)
			(layer "F.SilkS")
		)
		(fp_line
			(start -0.7874 -0.4064)
			(end 0.7874 -0.4064)
			(stroke
				(width 0.1524)
				(type default)
			)
			(layer "F.SilkS")
		)
		(fp_line
			(start 0.7874 0.4064)
			(end -0.7874 0.4064)
			(stroke
				(width 0.1524)
				(type default)
			)
			(layer "F.SilkS")
		)
		(fp_line
			(start -0.7874 0.4064)
			(end -0.7874 -0.4064)
			(stroke
				(width 0.1524)
				(type default)
			)
			(layer "F.SilkS")
		)
		(fp_line
			(start -0.12065 -0.305054)
			(end -0.12065 -0.2794)
			(stroke
				(width 0.1)
				(type default)
			)
			(layer "F.Fab")
		)
		(fp_line
			(start -0.67945 -0.305054)
			(end -0.12065 -0.305054)
			(stroke
				(width 0.1)
				(type default)
			)
			(layer "F.Fab")
		)
		(fp_line
			(start 0.67945 -0.3048)
			(end 0.67945 0.3048)
			(stroke
				(width 0.1)
				(type default)
			)
			(layer "F.Fab")
		)
		(fp_line
			(start 0.12065 -0.3048)
			(end 0.67945 -0.3048)
			(stroke
				(width 0.1)
				(type default)
			)
			(layer "F.Fab")
		)
		(fp_line
			(start 0.12065 -0.2794)
			(end 0.12065 -0.3048)
			(stroke
				(width 0.1)
				(type default)
			)
			(layer "F.Fab")
		)
		(fp_line
			(start -0.12065 -0.2794)
			(end 0.12065 -0.2794)
			(stroke
				(width 0.1)
				(type default)
			)
			(layer "F.Fab")
		)
		(fp_line
			(start 0.120396 0.2794)
			(end -0.12065 0.2794)
			(stroke
				(width 0.1)
				(type default)
			)
			(layer "F.Fab")
		)
		(fp_line
			(start -0.12065 0.2794)
			(end -0.12065 0.3048)
			(stroke
				(width 0.1)
				(type default)
			)
			(layer "F.Fab")
		)
		(fp_line
			(start 0.67945 0.3048)
			(end 0.120396 0.3048)
			(stroke
				(width 0.1)
				(type default)
			)
			(layer "F.Fab")
		)
		(fp_line
			(start 0.120396 0.3048)
			(end 0.120396 0.2794)
			(stroke
				(width 0.1)
				(type default)
			)
			(layer "F.Fab")
		)
		(fp_line
			(start -0.12065 0.3048)
			(end -0.67945 0.3048)
			(stroke
				(width 0.1)
				(type default)
			)
			(layer "F.Fab")
		)
		(fp_line
			(start -0.67945 0.3048)
			(end -0.67945 -0.305054)
			(stroke
				(width 0.1)
				(type default)
			)
			(layer "F.Fab")
		)
		(pad "1" smd circle
			(at -0.40005 0 90)
			(size 0 0)
			(layers "F.Cu" "F.Mask" "F.Paste")
			(net "P3V3_AUX")
		)
		(pad "2" smd circle
			(at 0.40005 0 90)
			(size 0 0)
			(layers "F.Cu" "F.Mask" "F.Paste")
			(net "RST_SMB_SWITCH_N")
		)
	)
	(footprint ""
		(layer "F.Cu")
		(at 367.44783 -240.276888 90)
		(property "Reference" "C404"
			(at 0 0 90)
			(layer "F.SilkS")
			(hide yes)
			(effects
				(font
					(size 1.27 1.27)
				)
			)
		)
		(property "Value" ""
			(at 0 0 90)
			(layer "F.Fab")
			(effects
				(font
					(size 1.27 1.27)
				)
			)
		)
		(duplicate_pad_numbers_are_jumpers no)
		(fp_line
			(start 0.7874 -0.4064)
			(end 0.7874 0.4064)
			(stroke
				(width 0.1524)
				(type default)
			)
			(layer "F.SilkS")
		)
		(fp_line
			(start -0.7874 -0.4064)
			(end 0.7874 -0.4064)
			(stroke
				(width 0.1524)
				(type default)
			)
			(layer "F.SilkS")
		)
		(fp_line
			(start 0.7874 0.4064)
			(end -0.7874 0.4064)
			(stroke
				(width 0.1524)
				(type default)
			)
			(layer "F.SilkS")
		)
		(fp_line
			(start -0.7874 0.4064)
			(end -0.7874 -0.4064)
			(stroke
				(width 0.1524)
				(type default)
			)
			(layer "F.SilkS")
		)
		(fp_line
			(start -0.12065 -0.305054)
			(end -0.12065 -0.2794)
			(stroke
				(width 0.1)
				(type default)
			)
			(layer "F.Fab")
		)
		(fp_line
			(start -0.67945 -0.305054)
			(end -0.12065 -0.305054)
			(stroke
				(width 0.1)
				(type default)
			)
			(layer "F.Fab")
		)
		(fp_line
			(start 0.67945 -0.3048)
			(end 0.67945 0.3048)
			(stroke
				(width 0.1)
				(type default)
			)
			(layer "F.Fab")
		)
		(fp_line
			(start 0.12065 -0.3048)
			(end 0.67945 -0.3048)
			(stroke
				(width 0.1)
				(type default)
			)
			(layer "F.Fab")
		)
		(fp_line
			(start 0.12065 -0.2794)
			(end 0.12065 -0.3048)
			(stroke
				(width 0.1)
				(type default)
			)
			(layer "F.Fab")
		)
		(fp_line
			(start -0.12065 -0.2794)
			(end 0.12065 -0.2794)
			(stroke
				(width 0.1)
				(type default)
			)
			(layer "F.Fab")
		)
		(fp_line
			(start 0.120396 0.2794)
			(end -0.12065 0.2794)
			(stroke
				(width 0.1)
				(type default)
			)
			(layer "F.Fab")
		)
		(fp_line
			(start -0.12065 0.2794)
			(end -0.12065 0.3048)
			(stroke
				(width 0.1)
				(type default)
			)
			(layer "F.Fab")
		)
		(fp_line
			(start 0.67945 0.3048)
			(end 0.120396 0.3048)
			(stroke
				(width 0.1)
				(type default)
			)
			(layer "F.Fab")
		)
		(fp_line
			(start 0.120396 0.3048)
			(end 0.120396 0.2794)
			(stroke
				(width 0.1)
				(type default)
			)
			(layer "F.Fab")
		)
		(fp_line
			(start -0.12065 0.3048)
			(end -0.67945 0.3048)
			(stroke
				(width 0.1)
				(type default)
			)
			(layer "F.Fab")
		)
		(fp_line
			(start -0.67945 0.3048)
			(end -0.67945 -0.305054)
			(stroke
				(width 0.1)
				(type default)
			)
			(layer "F.Fab")
		)
		(pad "1" smd circle
			(at -0.40005 0 90)
			(size 0 0)
			(layers "F.Cu" "F.Mask" "F.Paste")
			(net "PVCCFA_EHV_FIVRA_CPU0")
		)
		(pad "2" smd circle
			(at 0.40005 0 90)
			(size 0 0)
			(layers "F.Cu" "F.Mask" "F.Paste")
			(net "GND")
		)
	)
	(footprint ""
		(layer "F.Cu")
		(at 51.593496 -110.93577)
		(property "Reference" "R3725"
			(at 0 0 0)
			(layer "F.SilkS")
			(hide yes)
			(effects
				(font
					(size 1.27 1.27)
				)
			)
		)
		(property "Value" ""
			(at 0 0 0)
			(layer "F.Fab")
			(effects
				(font
					(size 1.27 1.27)
				)
			)
		)
		(duplicate_pad_numbers_are_jumpers no)
		(fp_line
			(start -0.7874 -0.4064)
			(end 0.7874 -0.4064)
			(stroke
				(width 0.1524)
				(type default)
			)
			(layer "F.SilkS")
		)
		(fp_line
			(start -0.7874 0.4064)
			(end -0.7874 -0.4064)
			(stroke
				(width 0.1524)
				(type default)
			)
			(layer "F.SilkS")
		)
		(fp_line
			(start 0.7874 -0.4064)
			(end 0.7874 0.4064)
			(stroke
				(width 0.1524)
				(type default)
			)
			(layer "F.SilkS")
		)
		(fp_line
			(start 0.7874 0.4064)
			(end -0.7874 0.4064)
			(stroke
				(width 0.1524)
				(type default)
			)
			(layer "F.SilkS")
		)
		(fp_line
			(start -0.67945 -0.305054)
			(end -0.12065 -0.305054)
			(stroke
				(width 0.1)
				(type default)
			)
			(layer "F.Fab")
		)
		(fp_line
			(start -0.67945 0.3048)
			(end -0.67945 -0.305054)
			(stroke
				(width 0.1)
				(type default)
			)
			(layer "F.Fab")
		)
		(fp_line
			(start -0.12065 -0.305054)
			(end -0.12065 -0.2794)
			(stroke
				(width 0.1)
				(type default)
			)
			(layer "F.Fab")
		)
		(fp_line
			(start -0.12065 -0.2794)
			(end 0.12065 -0.2794)
			(stroke
				(width 0.1)
				(type default)
			)
			(layer "F.Fab")
		)
		(fp_line
			(start -0.12065 0.2794)
			(end -0.12065 0.3048)
			(stroke
				(width 0.1)
				(type default)
			)
			(layer "F.Fab")
		)
		(fp_line
			(start -0.12065 0.3048)
			(end -0.67945 0.3048)
			(stroke
				(width 0.1)
				(type default)
			)
			(layer "F.Fab")
		)
		(fp_line
			(start 0.120396 0.2794)
			(end -0.12065 0.2794)
			(stroke
				(width 0.1)
				(type default)
			)
			(layer "F.Fab")
		)
		(fp_line
			(start 0.120396 0.3048)
			(end 0.120396 0.2794)
			(stroke
				(width 0.1)
				(type default)
			)
			(layer "F.Fab")
		)
		(fp_line
			(start 0.12065 -0.3048)
			(end 0.67945 -0.3048)
			(stroke
				(width 0.1)
				(type default)
			)
			(layer "F.Fab")
		)
		(fp_line
			(start 0.12065 -0.2794)
			(end 0.12065 -0.3048)
			(stroke
				(width 0.1)
				(type default)
			)
			(layer "F.Fab")
		)
		(fp_line
			(start 0.67945 -0.3048)
			(end 0.67945 0.3048)
			(stroke
				(width 0.1)
				(type default)
			)
			(layer "F.Fab")
		)
		(fp_line
			(start 0.67945 0.3048)
			(end 0.120396 0.3048)
			(stroke
				(width 0.1)
				(type default)
			)
			(layer "F.Fab")
		)
		(pad "1" smd circle
			(at -0.40005 0)
			(size 0 0)
			(layers "F.Cu" "F.Mask" "F.Paste")
			(net "P3V3_AUX")
		)
		(pad "2" smd circle
			(at 0.40005 0)
			(size 0 0)
			(layers "F.Cu" "F.Mask" "F.Paste")
			(net "SMB_LM75_0_3V3AUX_SCL")
		)
	)
	(footprint ""
		(layer "F.Cu")
		(at 145.131536 -64.701928)
		(property "Reference" "U145"
			(at -1.47066 2.016252 0)
			(unlocked yes)
			(layer "F.SilkS")
			(effects
				(font
					(size 0.7874 0.5842)
					(thickness 0.1524)
				)
				(justify left)
			)
		)
		(property "Value" ""
			(at 0 0 0)
			(layer "F.Fab")
			(effects
				(font
					(size 1.27 1.27)
				)
			)
		)
		(duplicate_pad_numbers_are_jumpers no)
		(fp_line
			(start -1.400048 1.100074)
			(end -1.400048 -1.100074)
			(stroke
				(width 0.1524)
				(type default)
			)
			(layer "F.SilkS")
		)
		(fp_line
			(start 1.400048 -1.100074)
			(end -1.400048 -1.100074)
			(stroke
				(width 0.1524)
				(type default)
			)
			(layer "F.SilkS")
		)
		(fp_line
			(start 1.400048 -1.100074)
			(end 1.400048 1.100074)
			(stroke
				(width 0.1524)
				(type default)
			)
			(layer "F.SilkS")
		)
		(fp_line
			(start 1.400048 1.100074)
			(end -1.400048 1.100074)
			(stroke
				(width 0.1524)
				(type default)
			)
			(layer "F.SilkS")
		)
		(fp_poly
			(pts
				(xy -1.05283 -1.437132) (xy -1.56083 -2.453132) (xy -0.54483 -2.453132)
			)
			(stroke
				(width 0)
				(type default)
			)
			(fill yes)
			(layer "F.SilkS")
		)
		(fp_line
			(start -0.674878 -1.100074)
			(end 0.674878 -1.100074)
			(stroke
				(width 0.1)
				(type default)
			)
			(layer "F.Fab")
		)
		(fp_line
			(start -0.674878 1.100074)
			(end -0.674878 -1.100074)
			(stroke
				(width 0.1)
				(type default)
			)
			(layer "F.Fab")
		)
		(fp_line
			(start 0.674878 -1.100074)
			(end 0.674878 1.100074)
			(stroke
				(width 0.1)
				(type default)
			)
			(layer "F.Fab")
		)
		(fp_line
			(start 0.674878 1.100074)
			(end -0.674878 1.100074)
			(stroke
				(width 0.1)
				(type default)
			)
			(layer "F.Fab")
		)
		(fp_poly
			(pts
				(xy -1.590548 -0.649986) (xy -2.606548 -1.157986) (xy -2.606548 -0.141986)
			)
			(stroke
				(width 0)
				(type default)
			)
			(fill yes)
			(layer "F.Fab")
		)
		(pad "1" smd rect
			(at -0.94996 -0.649986 270)
			(size 0.4318 0.6096)
			(layers "F.Cu" "F.Mask" "F.Paste")
			(net "FM_PS_EN_PLD_BUF1_R1")
		)
		(pad "2" smd rect
			(at -0.94996 0 270)
			(size 0.4318 0.6096)
			(layers "F.Cu" "F.Mask" "F.Paste")
			(net "E1S_0_PRSNT")
		)
		(pad "3" smd rect
			(at -0.94996 0.649986 270)
			(size 0.4318 0.6096)
			(layers "F.Cu" "F.Mask" "F.Paste")
			(net "GND")
		)
		(pad "4" smd rect
			(at 0.94996 0.649986 270)
			(size 0.4318 0.6096)
			(layers "F.Cu" "F.Mask" "F.Paste")
			(net "E1S_0_EN")
		)
		(pad "5" smd rect
			(at 0.94996 -0.649986 270)
			(size 0.4318 0.6096)
			(layers "F.Cu" "F.Mask" "F.Paste")
			(net "P3V3_AUX")
		)
	)
	(footprint ""
		(layer "F.Cu")
		(at 58.67273 -17.623536 90)
		(property "Reference" "C837"
			(at 0 0 90)
			(layer "F.SilkS")
			(hide yes)
			(effects
				(font
					(size 1.27 1.27)
				)
			)
		)
		(property "Value" ""
			(at 0 0 90)
			(layer "F.Fab")
			(effects
				(font
					(size 1.27 1.27)
				)
			)
		)
		(duplicate_pad_numbers_are_jumpers no)
		(fp_line
			(start 0.299974 -0.150114)
			(end 0.299974 0.150114)
			(stroke
				(width 0.1)
				(type default)
			)
			(layer "F.Fab")
		)
		(fp_line
			(start -0.299974 -0.150114)
			(end 0.299974 -0.150114)
			(stroke
				(width 0.1)
				(type default)
			)
			(layer "F.Fab")
		)
		(fp_line
			(start 0.299974 0.150114)
			(end -0.299974 0.150114)
			(stroke
				(width 0.1)
				(type default)
			)
			(layer "F.Fab")
		)
		(fp_line
			(start -0.299974 0.150114)
			(end -0.299974 -0.150114)
			(stroke
				(width 0.1)
				(type default)
			)
			(layer "F.Fab")
		)
		(pad "1" smd rect
			(at -0.2667 0 90)
			(size 0.3048 0.381)
			(layers "F.Cu" "F.Mask" "F.Paste")
			(net "P5E_CPU1_PE1_TX_C_DP<0>")
		)
		(pad "2" smd rect
			(at 0.2667 0 90)
			(size 0.3048 0.381)
			(layers "F.Cu" "F.Mask" "F.Paste")
			(net "P5E_CPU1_PE1_TX_DP<0>")
		)
	)
	(footprint ""
		(layer "F.Cu")
		(at 208.49336 -118.074948 180)
		(property "Reference" "R4170"
			(at 0 0 180)
			(layer "F.SilkS")
			(hide yes)
			(effects
				(font
					(size 1.27 1.27)
				)
			)
		)
		(property "Value" ""
			(at 0 0 180)
			(layer "F.Fab")
			(effects
				(font
					(size 1.27 1.27)
				)
			)
		)
		(duplicate_pad_numbers_are_jumpers no)
		(fp_line
			(start 0.7874 0.4064)
			(end -0.7874 0.4064)
			(stroke
				(width 0.1524)
				(type default)
			)
			(layer "F.SilkS")
		)
		(fp_line
			(start 0.7874 -0.4064)
			(end 0.7874 0.4064)
			(stroke
				(width 0.1524)
				(type default)
			)
			(layer "F.SilkS")
		)
		(fp_line
			(start -0.7874 0.4064)
			(end -0.7874 -0.4064)
			(stroke
				(width 0.1524)
				(type default)
			)
			(layer "F.SilkS")
		)
		(fp_line
			(start -0.7874 -0.4064)
			(end 0.7874 -0.4064)
			(stroke
				(width 0.1524)
				(type default)
			)
			(layer "F.SilkS")
		)
		(fp_line
			(start 0.67945 0.3048)
			(end 0.120396 0.3048)
			(stroke
				(width 0.1)
				(type default)
			)
			(layer "F.Fab")
		)
		(fp_line
			(start 0.67945 -0.3048)
			(end 0.67945 0.3048)
			(stroke
				(width 0.1)
				(type default)
			)
			(layer "F.Fab")
		)
		(fp_line
			(start 0.12065 -0.2794)
			(end 0.12065 -0.3048)
			(stroke
				(width 0.1)
				(type default)
			)
			(layer "F.Fab")
		)
		(fp_line
			(start 0.12065 -0.3048)
			(end 0.67945 -0.3048)
			(stroke
				(width 0.1)
				(type default)
			)
			(layer "F.Fab")
		)
		(fp_line
			(start 0.120396 0.3048)
			(end 0.120396 0.2794)
			(stroke
				(width 0.1)
				(type default)
			)
			(layer "F.Fab")
		)
		(fp_line
			(start 0.120396 0.2794)
			(end -0.12065 0.2794)
			(stroke
				(width 0.1)
				(type default)
			)
			(layer "F.Fab")
		)
		(fp_line
			(start -0.12065 0.3048)
			(end -0.67945 0.3048)
			(stroke
				(width 0.1)
				(type default)
			)
			(layer "F.Fab")
		)
		(fp_line
			(start -0.12065 0.2794)
			(end -0.12065 0.3048)
			(stroke
				(width 0.1)
				(type default)
			)
			(layer "F.Fab")
		)
		(fp_line
			(start -0.12065 -0.2794)
			(end 0.12065 -0.2794)
			(stroke
				(width 0.1)
				(type default)
			)
			(layer "F.Fab")
		)
		(fp_line
			(start -0.12065 -0.305054)
			(end -0.12065 -0.2794)
			(stroke
				(width 0.1)
				(type default)
			)
			(layer "F.Fab")
		)
		(fp_line
			(start -0.67945 0.3048)
			(end -0.67945 -0.305054)
			(stroke
				(width 0.1)
				(type default)
			)
			(layer "F.Fab")
		)
		(fp_line
			(start -0.67945 -0.305054)
			(end -0.12065 -0.305054)
			(stroke
				(width 0.1)
				(type default)
			)
			(layer "F.Fab")
		)
		(pad "1" smd circle
			(at -0.40005 0 180)
			(size 0 0)
			(layers "F.Cu" "F.Mask" "F.Paste")
			(net "GPU_3V3IO_RSVD1_ISO")
		)
		(pad "2" smd circle
			(at 0.40005 0 180)
			(size 0 0)
			(layers "F.Cu" "F.Mask" "F.Paste")
			(net "GPU_3V3IO_RSVD1_ISO_R")
		)
	)
	(footprint ""
		(layer "F.Cu")
		(at 32.761428 -98.570034 180)
		(property "Reference" "C2175"
			(at 0 0 180)
			(layer "F.SilkS")
			(hide yes)
			(effects
				(font
					(size 1.27 1.27)
				)
			)
		)
		(property "Value" ""
			(at 0 0 180)
			(layer "F.Fab")
			(effects
				(font
					(size 1.27 1.27)
				)
			)
		)
		(duplicate_pad_numbers_are_jumpers no)
		(fp_line
			(start 0.7874 0.4064)
			(end -0.7874 0.4064)
			(stroke
				(width 0.1524)
				(type default)
			)
			(layer "F.SilkS")
		)
		(fp_line
			(start 0.7874 -0.4064)
			(end 0.7874 0.4064)
			(stroke
				(width 0.1524)
				(type default)
			)
			(layer "F.SilkS")
		)
		(fp_line
			(start -0.7874 0.4064)
			(end -0.7874 -0.4064)
			(stroke
				(width 0.1524)
				(type default)
			)
			(layer "F.SilkS")
		)
		(fp_line
			(start -0.7874 -0.4064)
			(end 0.7874 -0.4064)
			(stroke
				(width 0.1524)
				(type default)
			)
			(layer "F.SilkS")
		)
		(fp_line
			(start 0.67945 0.3048)
			(end 0.120396 0.3048)
			(stroke
				(width 0.1)
				(type default)
			)
			(layer "F.Fab")
		)
		(fp_line
			(start 0.67945 -0.3048)
			(end 0.67945 0.3048)
			(stroke
				(width 0.1)
				(type default)
			)
			(layer "F.Fab")
		)
		(fp_line
			(start 0.12065 -0.2794)
			(end 0.12065 -0.3048)
			(stroke
				(width 0.1)
				(type default)
			)
			(layer "F.Fab")
		)
		(fp_line
			(start 0.12065 -0.3048)
			(end 0.67945 -0.3048)
			(stroke
				(width 0.1)
				(type default)
			)
			(layer "F.Fab")
		)
		(fp_line
			(start 0.120396 0.3048)
			(end 0.120396 0.2794)
			(stroke
				(width 0.1)
				(type default)
			)
			(layer "F.Fab")
		)
		(fp_line
			(start 0.120396 0.2794)
			(end -0.12065 0.2794)
			(stroke
				(width 0.1)
				(type default)
			)
			(layer "F.Fab")
		)
		(fp_line
			(start -0.12065 0.3048)
			(end -0.67945 0.3048)
			(stroke
				(width 0.1)
				(type default)
			)
			(layer "F.Fab")
		)
		(fp_line
			(start -0.12065 0.2794)
			(end -0.12065 0.3048)
			(stroke
				(width 0.1)
				(type default)
			)
			(layer "F.Fab")
		)
		(fp_line
			(start -0.12065 -0.2794)
			(end 0.12065 -0.2794)
			(stroke
				(width 0.1)
				(type default)
			)
			(layer "F.Fab")
		)
		(fp_line
			(start -0.12065 -0.305054)
			(end -0.12065 -0.2794)
			(stroke
				(width 0.1)
				(type default)
			)
			(layer "F.Fab")
		)
		(fp_line
			(start -0.67945 0.3048)
			(end -0.67945 -0.305054)
			(stroke
				(width 0.1)
				(type default)
			)
			(layer "F.Fab")
		)
		(fp_line
			(start -0.67945 -0.305054)
			(end -0.12065 -0.305054)
			(stroke
				(width 0.1)
				(type default)
			)
			(layer "F.Fab")
		)
		(pad "1" smd circle
			(at -0.40005 0 180)
			(size 0 0)
			(layers "F.Cu" "F.Mask" "F.Paste")
			(net "P12V_OCP_V3_2_ISENSE_MAM")
		)
		(pad "2" smd circle
			(at 0.40005 0 180)
			(size 0 0)
			(layers "F.Cu" "F.Mask" "F.Paste")
			(net "GND")
		)
	)
	(footprint ""
		(layer "F.Cu")
		(at 85.627718 -402.371052 -90)
		(property "Reference" "C735"
			(at 0 0 270)
			(layer "F.SilkS")
			(hide yes)
			(effects
				(font
					(size 1.27 1.27)
				)
			)
		)
		(property "Value" ""
			(at 0 0 270)
			(layer "F.Fab")
			(effects
				(font
					(size 1.27 1.27)
				)
			)
		)
		(duplicate_pad_numbers_are_jumpers no)
		(fp_line
			(start -0.299974 0.150114)
			(end -0.299974 -0.150114)
			(stroke
				(width 0.1)
				(type default)
			)
			(layer "F.Fab")
		)
		(fp_line
			(start 0.299974 0.150114)
			(end -0.299974 0.150114)
			(stroke
				(width 0.1)
				(type default)
			)
			(layer "F.Fab")
		)
		(fp_line
			(start -0.299974 -0.150114)
			(end 0.299974 -0.150114)
			(stroke
				(width 0.1)
				(type default)
			)
			(layer "F.Fab")
		)
		(fp_line
			(start 0.299974 -0.150114)
			(end 0.299974 0.150114)
			(stroke
				(width 0.1)
				(type default)
			)
			(layer "F.Fab")
		)
		(pad "1" smd rect
			(at -0.2667 0 270)
			(size 0.3048 0.381)
			(layers "F.Cu" "F.Mask" "F.Paste")
			(net "P5E_CPU1_PE0_TX_C_DP<3>")
		)
		(pad "2" smd rect
			(at 0.2667 0 270)
			(size 0.3048 0.381)
			(layers "F.Cu" "F.Mask" "F.Paste")
			(net "P5E_CPU1_PE0_TX_DP<3>")
		)
	)
	(footprint ""
		(layer "F.Cu")
		(at 122.61088 -92.674948 90)
		(property "Reference" "R241"
			(at 0 0 90)
			(layer "F.SilkS")
			(hide yes)
			(effects
				(font
					(size 1.27 1.27)
				)
			)
		)
		(property "Value" ""
			(at 0 0 90)
			(layer "F.Fab")
			(effects
				(font
					(size 1.27 1.27)
				)
			)
		)
		(duplicate_pad_numbers_are_jumpers no)
		(fp_line
			(start 0.7874 -0.4064)
			(end 0.7874 0.4064)
			(stroke
				(width 0.1524)
				(type default)
			)
			(layer "F.SilkS")
		)
		(fp_line
			(start -0.7874 -0.4064)
			(end 0.7874 -0.4064)
			(stroke
				(width 0.1524)
				(type default)
			)
			(layer "F.SilkS")
		)
		(fp_line
			(start 0.7874 0.4064)
			(end -0.7874 0.4064)
			(stroke
				(width 0.1524)
				(type default)
			)
			(layer "F.SilkS")
		)
		(fp_line
			(start -0.7874 0.4064)
			(end -0.7874 -0.4064)
			(stroke
				(width 0.1524)
				(type default)
			)
			(layer "F.SilkS")
		)
		(fp_line
			(start -0.12065 -0.305054)
			(end -0.12065 -0.2794)
			(stroke
				(width 0.1)
				(type default)
			)
			(layer "F.Fab")
		)
		(fp_line
			(start -0.67945 -0.305054)
			(end -0.12065 -0.305054)
			(stroke
				(width 0.1)
				(type default)
			)
			(layer "F.Fab")
		)
		(fp_line
			(start 0.67945 -0.3048)
			(end 0.67945 0.3048)
			(stroke
				(width 0.1)
				(type default)
			)
			(layer "F.Fab")
		)
		(fp_line
			(start 0.12065 -0.3048)
			(end 0.67945 -0.3048)
			(stroke
				(width 0.1)
				(type default)
			)
			(layer "F.Fab")
		)
		(fp_line
			(start 0.12065 -0.2794)
			(end 0.12065 -0.3048)
			(stroke
				(width 0.1)
				(type default)
			)
			(layer "F.Fab")
		)
		(fp_line
			(start -0.12065 -0.2794)
			(end 0.12065 -0.2794)
			(stroke
				(width 0.1)
				(type default)
			)
			(layer "F.Fab")
		)
		(fp_line
			(start 0.120396 0.2794)
			(end -0.12065 0.2794)
			(stroke
				(width 0.1)
				(type default)
			)
			(layer "F.Fab")
		)
		(fp_line
			(start -0.12065 0.2794)
			(end -0.12065 0.3048)
			(stroke
				(width 0.1)
				(type default)
			)
			(layer "F.Fab")
		)
		(fp_line
			(start 0.67945 0.3048)
			(end 0.120396 0.3048)
			(stroke
				(width 0.1)
				(type default)
			)
			(layer "F.Fab")
		)
		(fp_line
			(start 0.120396 0.3048)
			(end 0.120396 0.2794)
			(stroke
				(width 0.1)
				(type default)
			)
			(layer "F.Fab")
		)
		(fp_line
			(start -0.12065 0.3048)
			(end -0.67945 0.3048)
			(stroke
				(width 0.1)
				(type default)
			)
			(layer "F.Fab")
		)
		(fp_line
			(start -0.67945 0.3048)
			(end -0.67945 -0.305054)
			(stroke
				(width 0.1)
				(type default)
			)
			(layer "F.Fab")
		)
		(pad "1" smd circle
			(at -0.40005 0 90)
			(size 0 0)
			(layers "F.Cu" "F.Mask" "F.Paste")
			(net "P3V3")
		)
		(pad "2" smd circle
			(at 0.40005 0 90)
			(size 0 0)
			(layers "F.Cu" "F.Mask" "F.Paste")
			(net "H_CPU0_THERMTRIP_VT_N")
		)
	)
	(footprint ""
		(layer "F.Cu")
		(at 201.02068 -99.939348)
		(property "Reference" "R4294"
			(at 0 0 0)
			(layer "F.SilkS")
			(hide yes)
			(effects
				(font
					(size 1.27 1.27)
				)
			)
		)
		(property "Value" ""
			(at 0 0 0)
			(layer "F.Fab")
			(effects
				(font
					(size 1.27 1.27)
				)
			)
		)
		(duplicate_pad_numbers_are_jumpers no)
		(fp_line
			(start -0.7874 -0.4064)
			(end 0.7874 -0.4064)
			(stroke
				(width 0.1524)
				(type default)
			)
			(layer "F.SilkS")
		)
		(fp_line
			(start -0.7874 0.4064)
			(end -0.7874 -0.4064)
			(stroke
				(width 0.1524)
				(type default)
			)
			(layer "F.SilkS")
		)
		(fp_line
			(start 0.7874 -0.4064)
			(end 0.7874 0.4064)
			(stroke
				(width 0.1524)
				(type default)
			)
			(layer "F.SilkS")
		)
		(fp_line
			(start 0.7874 0.4064)
			(end -0.7874 0.4064)
			(stroke
				(width 0.1524)
				(type default)
			)
			(layer "F.SilkS")
		)
		(fp_line
			(start -0.67945 -0.305054)
			(end -0.12065 -0.305054)
			(stroke
				(width 0.1)
				(type default)
			)
			(layer "F.Fab")
		)
		(fp_line
			(start -0.67945 0.3048)
			(end -0.67945 -0.305054)
			(stroke
				(width 0.1)
				(type default)
			)
			(layer "F.Fab")
		)
		(fp_line
			(start -0.12065 -0.305054)
			(end -0.12065 -0.2794)
			(stroke
				(width 0.1)
				(type default)
			)
			(layer "F.Fab")
		)
		(fp_line
			(start -0.12065 -0.2794)
			(end 0.12065 -0.2794)
			(stroke
				(width 0.1)
				(type default)
			)
			(layer "F.Fab")
		)
		(fp_line
			(start -0.12065 0.2794)
			(end -0.12065 0.3048)
			(stroke
				(width 0.1)
				(type default)
			)
			(layer "F.Fab")
		)
		(fp_line
			(start -0.12065 0.3048)
			(end -0.67945 0.3048)
			(stroke
				(width 0.1)
				(type default)
			)
			(layer "F.Fab")
		)
		(fp_line
			(start 0.120396 0.2794)
			(end -0.12065 0.2794)
			(stroke
				(width 0.1)
				(type default)
			)
			(layer "F.Fab")
		)
		(fp_line
			(start 0.120396 0.3048)
			(end 0.120396 0.2794)
			(stroke
				(width 0.1)
				(type default)
			)
			(layer "F.Fab")
		)
		(fp_line
			(start 0.12065 -0.3048)
			(end 0.67945 -0.3048)
			(stroke
				(width 0.1)
				(type default)
			)
			(layer "F.Fab")
		)
		(fp_line
			(start 0.12065 -0.2794)
			(end 0.12065 -0.3048)
			(stroke
				(width 0.1)
				(type default)
			)
			(layer "F.Fab")
		)
		(fp_line
			(start 0.67945 -0.3048)
			(end 0.67945 0.3048)
			(stroke
				(width 0.1)
				(type default)
			)
			(layer "F.Fab")
		)
		(fp_line
			(start 0.67945 0.3048)
			(end 0.120396 0.3048)
			(stroke
				(width 0.1)
				(type default)
			)
			(layer "F.Fab")
		)
		(pad "1" smd circle
			(at -0.40005 0)
			(size 0 0)
			(layers "F.Cu" "F.Mask" "F.Paste")
			(net "H_CPU1_MEMHOT_IN_LVC1_R1_N")
		)
		(pad "2" smd circle
			(at 0.40005 0)
			(size 0 0)
			(layers "F.Cu" "F.Mask" "F.Paste")
			(net "H_CPU1_MEMHOT_IN_LVC1_N")
		)
	)
	(footprint ""
		(layer "F.Cu")
		(at 317.396622 -59.299348 180)
		(property "Reference" "R1221"
			(at 0 0 180)
			(layer "F.SilkS")
			(hide yes)
			(effects
				(font
					(size 1.27 1.27)
				)
			)
		)
		(property "Value" ""
			(at 0 0 180)
			(layer "F.Fab")
			(effects
				(font
					(size 1.27 1.27)
				)
			)
		)
		(duplicate_pad_numbers_are_jumpers no)
		(fp_line
			(start 0.7874 0.4064)
			(end -0.7874 0.4064)
			(stroke
				(width 0.1524)
				(type default)
			)
			(layer "F.SilkS")
		)
		(fp_line
			(start 0.7874 -0.4064)
			(end 0.7874 0.4064)
			(stroke
				(width 0.1524)
				(type default)
			)
			(layer "F.SilkS")
		)
		(fp_line
			(start -0.7874 0.4064)
			(end -0.7874 -0.4064)
			(stroke
				(width 0.1524)
				(type default)
			)
			(layer "F.SilkS")
		)
		(fp_line
			(start -0.7874 -0.4064)
			(end 0.7874 -0.4064)
			(stroke
				(width 0.1524)
				(type default)
			)
			(layer "F.SilkS")
		)
		(fp_line
			(start 0.67945 0.3048)
			(end 0.120396 0.3048)
			(stroke
				(width 0.1)
				(type default)
			)
			(layer "F.Fab")
		)
		(fp_line
			(start 0.67945 -0.3048)
			(end 0.67945 0.3048)
			(stroke
				(width 0.1)
				(type default)
			)
			(layer "F.Fab")
		)
		(fp_line
			(start 0.12065 -0.2794)
			(end 0.12065 -0.3048)
			(stroke
				(width 0.1)
				(type default)
			)
			(layer "F.Fab")
		)
		(fp_line
			(start 0.12065 -0.3048)
			(end 0.67945 -0.3048)
			(stroke
				(width 0.1)
				(type default)
			)
			(layer "F.Fab")
		)
		(fp_line
			(start 0.120396 0.3048)
			(end 0.120396 0.2794)
			(stroke
				(width 0.1)
				(type default)
			)
			(layer "F.Fab")
		)
		(fp_line
			(start 0.120396 0.2794)
			(end -0.12065 0.2794)
			(stroke
				(width 0.1)
				(type default)
			)
			(layer "F.Fab")
		)
		(fp_line
			(start -0.12065 0.3048)
			(end -0.67945 0.3048)
			(stroke
				(width 0.1)
				(type default)
			)
			(layer "F.Fab")
		)
		(fp_line
			(start -0.12065 0.2794)
			(end -0.12065 0.3048)
			(stroke
				(width 0.1)
				(type default)
			)
			(layer "F.Fab")
		)
		(fp_line
			(start -0.12065 -0.2794)
			(end 0.12065 -0.2794)
			(stroke
				(width 0.1)
				(type default)
			)
			(layer "F.Fab")
		)
		(fp_line
			(start -0.12065 -0.305054)
			(end -0.12065 -0.2794)
			(stroke
				(width 0.1)
				(type default)
			)
			(layer "F.Fab")
		)
		(fp_line
			(start -0.67945 0.3048)
			(end -0.67945 -0.305054)
			(stroke
				(width 0.1)
				(type default)
			)
			(layer "F.Fab")
		)
		(fp_line
			(start -0.67945 -0.305054)
			(end -0.12065 -0.305054)
			(stroke
				(width 0.1)
				(type default)
			)
			(layer "F.Fab")
		)
		(pad "1" smd circle
			(at -0.40005 0 180)
			(size 0 0)
			(layers "F.Cu" "F.Mask" "F.Paste")
			(net "FM_PCH_MCRO_LDO")
		)
		(pad "2" smd circle
			(at 0.40005 0 180)
			(size 0 0)
			(layers "F.Cu" "F.Mask" "F.Paste")
			(net "GND")
		)
	)
	(footprint ""
		(layer "F.Cu")
		(at 205.397608 -402.791422 180)
		(property "Reference" "PR1101"
			(at 0 0 180)
			(layer "F.SilkS")
			(hide yes)
			(effects
				(font
					(size 1.27 1.27)
				)
			)
		)
		(property "Value" ""
			(at 0 0 180)
			(layer "F.Fab")
			(effects
				(font
					(size 1.27 1.27)
				)
			)
		)
		(duplicate_pad_numbers_are_jumpers no)
		(fp_line
			(start 0.7874 0.4064)
			(end -0.7874 0.4064)
			(stroke
				(width 0.1524)
				(type default)
			)
			(layer "F.SilkS")
		)
		(fp_line
			(start 0.7874 -0.4064)
			(end 0.7874 0.4064)
			(stroke
				(width 0.1524)
				(type default)
			)
			(layer "F.SilkS")
		)
		(fp_line
			(start -0.7874 0.4064)
			(end -0.7874 -0.4064)
			(stroke
				(width 0.1524)
				(type default)
			)
			(layer "F.SilkS")
		)
		(fp_line
			(start -0.7874 -0.4064)
			(end 0.7874 -0.4064)
			(stroke
				(width 0.1524)
				(type default)
			)
			(layer "F.SilkS")
		)
		(fp_line
			(start 0.67945 0.3048)
			(end 0.120396 0.3048)
			(stroke
				(width 0.1)
				(type default)
			)
			(layer "F.Fab")
		)
		(fp_line
			(start 0.67945 -0.3048)
			(end 0.67945 0.3048)
			(stroke
				(width 0.1)
				(type default)
			)
			(layer "F.Fab")
		)
		(fp_line
			(start 0.12065 -0.2794)
			(end 0.12065 -0.3048)
			(stroke
				(width 0.1)
				(type default)
			)
			(layer "F.Fab")
		)
		(fp_line
			(start 0.12065 -0.3048)
			(end 0.67945 -0.3048)
			(stroke
				(width 0.1)
				(type default)
			)
			(layer "F.Fab")
		)
		(fp_line
			(start 0.120396 0.3048)
			(end 0.120396 0.2794)
			(stroke
				(width 0.1)
				(type default)
			)
			(layer "F.Fab")
		)
		(fp_line
			(start 0.120396 0.2794)
			(end -0.12065 0.2794)
			(stroke
				(width 0.1)
				(type default)
			)
			(layer "F.Fab")
		)
		(fp_line
			(start -0.12065 0.3048)
			(end -0.67945 0.3048)
			(stroke
				(width 0.1)
				(type default)
			)
			(layer "F.Fab")
		)
		(fp_line
			(start -0.12065 0.2794)
			(end -0.12065 0.3048)
			(stroke
				(width 0.1)
				(type default)
			)
			(layer "F.Fab")
		)
		(fp_line
			(start -0.12065 -0.2794)
			(end 0.12065 -0.2794)
			(stroke
				(width 0.1)
				(type default)
			)
			(layer "F.Fab")
		)
		(fp_line
			(start -0.12065 -0.305054)
			(end -0.12065 -0.2794)
			(stroke
				(width 0.1)
				(type default)
			)
			(layer "F.Fab")
		)
		(fp_line
			(start -0.67945 0.3048)
			(end -0.67945 -0.305054)
			(stroke
				(width 0.1)
				(type default)
			)
			(layer "F.Fab")
		)
		(fp_line
			(start -0.67945 -0.305054)
			(end -0.12065 -0.305054)
			(stroke
				(width 0.1)
				(type default)
			)
			(layer "F.Fab")
		)
		(pad "1" smd circle
			(at -0.40005 0 180)
			(size 0 0)
			(layers "F.Cu" "F.Mask" "F.Paste")
			(net "HSC_IMON")
		)
		(pad "2" smd circle
			(at 0.40005 0 180)
			(size 0 0)
			(layers "F.Cu" "F.Mask" "F.Paste")
			(net "AGND_HSC")
		)
	)
	(footprint ""
		(layer "F.Cu")
		(at 307.932328 -402.371052 -90)
		(property "Reference" "C1576"
			(at 0 0 270)
			(layer "F.SilkS")
			(hide yes)
			(effects
				(font
					(size 1.27 1.27)
				)
			)
		)
		(property "Value" ""
			(at 0 0 270)
			(layer "F.Fab")
			(effects
				(font
					(size 1.27 1.27)
				)
			)
		)
		(duplicate_pad_numbers_are_jumpers no)
		(fp_line
			(start -0.299974 0.150114)
			(end -0.299974 -0.150114)
			(stroke
				(width 0.1)
				(type default)
			)
			(layer "F.Fab")
		)
		(fp_line
			(start 0.299974 0.150114)
			(end -0.299974 0.150114)
			(stroke
				(width 0.1)
				(type default)
			)
			(layer "F.Fab")
		)
		(fp_line
			(start -0.299974 -0.150114)
			(end 0.299974 -0.150114)
			(stroke
				(width 0.1)
				(type default)
			)
			(layer "F.Fab")
		)
		(fp_line
			(start 0.299974 -0.150114)
			(end 0.299974 0.150114)
			(stroke
				(width 0.1)
				(type default)
			)
			(layer "F.Fab")
		)
		(pad "1" smd rect
			(at -0.2667 0 270)
			(size 0.3048 0.381)
			(layers "F.Cu" "F.Mask" "F.Paste")
			(net "P5E_CPU0_PE4_TX_C_DN<1>")
		)
		(pad "2" smd rect
			(at 0.2667 0 270)
			(size 0.3048 0.381)
			(layers "F.Cu" "F.Mask" "F.Paste")
			(net "P5E_CPU0_PE4_TX_DN<1>")
		)
	)
	(footprint ""
		(layer "F.Cu")
		(at 96.57588 -54.066948 180)
		(property "Reference" "R1375"
			(at 0 0 180)
			(layer "F.SilkS")
			(hide yes)
			(effects
				(font
					(size 1.27 1.27)
				)
			)
		)
		(property "Value" ""
			(at 0 0 180)
			(layer "F.Fab")
			(effects
				(font
					(size 1.27 1.27)
				)
			)
		)
		(duplicate_pad_numbers_are_jumpers no)
		(fp_line
			(start 0.7874 0.4064)
			(end -0.7874 0.4064)
			(stroke
				(width 0.1524)
				(type default)
			)
			(layer "F.SilkS")
		)
		(fp_line
			(start 0.7874 -0.4064)
			(end 0.7874 0.4064)
			(stroke
				(width 0.1524)
				(type default)
			)
			(layer "F.SilkS")
		)
		(fp_line
			(start -0.7874 0.4064)
			(end -0.7874 -0.4064)
			(stroke
				(width 0.1524)
				(type default)
			)
			(layer "F.SilkS")
		)
		(fp_line
			(start -0.7874 -0.4064)
			(end 0.7874 -0.4064)
			(stroke
				(width 0.1524)
				(type default)
			)
			(layer "F.SilkS")
		)
		(fp_line
			(start 0.67945 0.3048)
			(end 0.120396 0.3048)
			(stroke
				(width 0.1)
				(type default)
			)
			(layer "F.Fab")
		)
		(fp_line
			(start 0.67945 -0.3048)
			(end 0.67945 0.3048)
			(stroke
				(width 0.1)
				(type default)
			)
			(layer "F.Fab")
		)
		(fp_line
			(start 0.12065 -0.2794)
			(end 0.12065 -0.3048)
			(stroke
				(width 0.1)
				(type default)
			)
			(layer "F.Fab")
		)
		(fp_line
			(start 0.12065 -0.3048)
			(end 0.67945 -0.3048)
			(stroke
				(width 0.1)
				(type default)
			)
			(layer "F.Fab")
		)
		(fp_line
			(start 0.120396 0.3048)
			(end 0.120396 0.2794)
			(stroke
				(width 0.1)
				(type default)
			)
			(layer "F.Fab")
		)
		(fp_line
			(start 0.120396 0.2794)
			(end -0.12065 0.2794)
			(stroke
				(width 0.1)
				(type default)
			)
			(layer "F.Fab")
		)
		(fp_line
			(start -0.12065 0.3048)
			(end -0.67945 0.3048)
			(stroke
				(width 0.1)
				(type default)
			)
			(layer "F.Fab")
		)
		(fp_line
			(start -0.12065 0.2794)
			(end -0.12065 0.3048)
			(stroke
				(width 0.1)
				(type default)
			)
			(layer "F.Fab")
		)
		(fp_line
			(start -0.12065 -0.2794)
			(end 0.12065 -0.2794)
			(stroke
				(width 0.1)
				(type default)
			)
			(layer "F.Fab")
		)
		(fp_line
			(start -0.12065 -0.305054)
			(end -0.12065 -0.2794)
			(stroke
				(width 0.1)
				(type default)
			)
			(layer "F.Fab")
		)
		(fp_line
			(start -0.67945 0.3048)
			(end -0.67945 -0.305054)
			(stroke
				(width 0.1)
				(type default)
			)
			(layer "F.Fab")
		)
		(fp_line
			(start -0.67945 -0.305054)
			(end -0.12065 -0.305054)
			(stroke
				(width 0.1)
				(type default)
			)
			(layer "F.Fab")
		)
		(pad "1" smd circle
			(at -0.40005 0 180)
			(size 0 0)
			(layers "F.Cu" "F.Mask" "F.Paste")
			(net "FM_BMC_EN_DET")
		)
		(pad "2" smd circle
			(at 0.40005 0 180)
			(size 0 0)
			(layers "F.Cu" "F.Mask" "F.Paste")
			(net "GND")
		)
	)
	(footprint ""
		(layer "F.Cu")
		(at 424.204892 -389.600948)
		(property "Reference" "R2933"
			(at 0 0 0)
			(layer "F.SilkS")
			(hide yes)
			(effects
				(font
					(size 1.27 1.27)
				)
			)
		)
		(property "Value" ""
			(at 0 0 0)
			(layer "F.Fab")
			(effects
				(font
					(size 1.27 1.27)
				)
			)
		)
		(duplicate_pad_numbers_are_jumpers no)
		(fp_line
			(start -0.7874 -0.4064)
			(end 0.7874 -0.4064)
			(stroke
				(width 0.1524)
				(type default)
			)
			(layer "F.SilkS")
		)
		(fp_line
			(start -0.7874 0.4064)
			(end -0.7874 -0.4064)
			(stroke
				(width 0.1524)
				(type default)
			)
			(layer "F.SilkS")
		)
		(fp_line
			(start 0.7874 -0.4064)
			(end 0.7874 0.4064)
			(stroke
				(width 0.1524)
				(type default)
			)
			(layer "F.SilkS")
		)
		(fp_line
			(start 0.7874 0.4064)
			(end -0.7874 0.4064)
			(stroke
				(width 0.1524)
				(type default)
			)
			(layer "F.SilkS")
		)
		(fp_line
			(start -0.67945 -0.305054)
			(end -0.12065 -0.305054)
			(stroke
				(width 0.1)
				(type default)
			)
			(layer "F.Fab")
		)
		(fp_line
			(start -0.67945 0.3048)
			(end -0.67945 -0.305054)
			(stroke
				(width 0.1)
				(type default)
			)
			(layer "F.Fab")
		)
		(fp_line
			(start -0.12065 -0.305054)
			(end -0.12065 -0.2794)
			(stroke
				(width 0.1)
				(type default)
			)
			(layer "F.Fab")
		)
		(fp_line
			(start -0.12065 -0.2794)
			(end 0.12065 -0.2794)
			(stroke
				(width 0.1)
				(type default)
			)
			(layer "F.Fab")
		)
		(fp_line
			(start -0.12065 0.2794)
			(end -0.12065 0.3048)
			(stroke
				(width 0.1)
				(type default)
			)
			(layer "F.Fab")
		)
		(fp_line
			(start -0.12065 0.3048)
			(end -0.67945 0.3048)
			(stroke
				(width 0.1)
				(type default)
			)
			(layer "F.Fab")
		)
		(fp_line
			(start 0.120396 0.2794)
			(end -0.12065 0.2794)
			(stroke
				(width 0.1)
				(type default)
			)
			(layer "F.Fab")
		)
		(fp_line
			(start 0.120396 0.3048)
			(end 0.120396 0.2794)
			(stroke
				(width 0.1)
				(type default)
			)
			(layer "F.Fab")
		)
		(fp_line
			(start 0.12065 -0.3048)
			(end 0.67945 -0.3048)
			(stroke
				(width 0.1)
				(type default)
			)
			(layer "F.Fab")
		)
		(fp_line
			(start 0.12065 -0.2794)
			(end 0.12065 -0.3048)
			(stroke
				(width 0.1)
				(type default)
			)
			(layer "F.Fab")
		)
		(fp_line
			(start 0.67945 -0.3048)
			(end 0.67945 0.3048)
			(stroke
				(width 0.1)
				(type default)
			)
			(layer "F.Fab")
		)
		(fp_line
			(start 0.67945 0.3048)
			(end 0.120396 0.3048)
			(stroke
				(width 0.1)
				(type default)
			)
			(layer "F.Fab")
		)
		(pad "1" smd circle
			(at -0.40005 0)
			(size 0 0)
			(layers "F.Cu" "F.Mask" "F.Paste")
			(net "P3V3_AUX")
		)
		(pad "2" smd circle
			(at 0.40005 0)
			(size 0 0)
			(layers "F.Cu" "F.Mask" "F.Paste")
			(net "FM_SWB_BIC_READY_ISO_N")
		)
	)
	(footprint ""
		(layer "F.Cu")
		(at 50.785014 -160.800542 90)
		(property "Reference" "PC442_P1_1"
			(at 0 0 90)
			(layer "F.SilkS")
			(hide yes)
			(effects
				(font
					(size 1.27 1.27)
				)
			)
		)
		(property "Value" ""
			(at 0 0 90)
			(layer "F.Fab")
			(effects
				(font
					(size 1.27 1.27)
				)
			)
		)
		(duplicate_pad_numbers_are_jumpers no)
		(fp_line
			(start 0.7874 -0.4064)
			(end 0.7874 0.4064)
			(stroke
				(width 0.1524)
				(type default)
			)
			(layer "F.SilkS")
		)
		(fp_line
			(start -0.7874 -0.4064)
			(end 0.7874 -0.4064)
			(stroke
				(width 0.1524)
				(type default)
			)
			(layer "F.SilkS")
		)
		(fp_line
			(start 0.7874 0.4064)
			(end -0.7874 0.4064)
			(stroke
				(width 0.1524)
				(type default)
			)
			(layer "F.SilkS")
		)
		(fp_line
			(start -0.7874 0.4064)
			(end -0.7874 -0.4064)
			(stroke
				(width 0.1524)
				(type default)
			)
			(layer "F.SilkS")
		)
		(fp_line
			(start -0.12065 -0.305054)
			(end -0.12065 -0.2794)
			(stroke
				(width 0.1)
				(type default)
			)
			(layer "F.Fab")
		)
		(fp_line
			(start -0.67945 -0.305054)
			(end -0.12065 -0.305054)
			(stroke
				(width 0.1)
				(type default)
			)
			(layer "F.Fab")
		)
		(fp_line
			(start 0.67945 -0.3048)
			(end 0.67945 0.3048)
			(stroke
				(width 0.1)
				(type default)
			)
			(layer "F.Fab")
		)
		(fp_line
			(start 0.12065 -0.3048)
			(end 0.67945 -0.3048)
			(stroke
				(width 0.1)
				(type default)
			)
			(layer "F.Fab")
		)
		(fp_line
			(start 0.12065 -0.2794)
			(end 0.12065 -0.3048)
			(stroke
				(width 0.1)
				(type default)
			)
			(layer "F.Fab")
		)
		(fp_line
			(start -0.12065 -0.2794)
			(end 0.12065 -0.2794)
			(stroke
				(width 0.1)
				(type default)
			)
			(layer "F.Fab")
		)
		(fp_line
			(start 0.120396 0.2794)
			(end -0.12065 0.2794)
			(stroke
				(width 0.1)
				(type default)
			)
			(layer "F.Fab")
		)
		(fp_line
			(start -0.12065 0.2794)
			(end -0.12065 0.3048)
			(stroke
				(width 0.1)
				(type default)
			)
			(layer "F.Fab")
		)
		(fp_line
			(start 0.67945 0.3048)
			(end 0.120396 0.3048)
			(stroke
				(width 0.1)
				(type default)
			)
			(layer "F.Fab")
		)
		(fp_line
			(start 0.120396 0.3048)
			(end 0.120396 0.2794)
			(stroke
				(width 0.1)
				(type default)
			)
			(layer "F.Fab")
		)
		(fp_line
			(start -0.12065 0.3048)
			(end -0.67945 0.3048)
			(stroke
				(width 0.1)
				(type default)
			)
			(layer "F.Fab")
		)
		(fp_line
			(start -0.67945 0.3048)
			(end -0.67945 -0.305054)
			(stroke
				(width 0.1)
				(type default)
			)
			(layer "F.Fab")
		)
		(pad "1" smd circle
			(at -0.40005 0 90)
			(size 0 0)
			(layers "F.Cu" "F.Mask" "F.Paste")
			(net "SW_P12V_PVCCINFAON_CPU1_FLT")
		)
		(pad "2" smd circle
			(at 0.40005 0 90)
			(size 0 0)
			(layers "F.Cu" "F.Mask" "F.Paste")
			(net "GND")
		)
	)
	(footprint ""
		(layer "F.Cu")
		(at 131.466844 -131.310126 180)
		(property "Reference" "R651"
			(at 0 0 180)
			(layer "F.SilkS")
			(hide yes)
			(effects
				(font
					(size 1.27 1.27)
				)
			)
		)
		(property "Value" ""
			(at 0 0 180)
			(layer "F.Fab")
			(effects
				(font
					(size 1.27 1.27)
				)
			)
		)
		(duplicate_pad_numbers_are_jumpers no)
		(fp_line
			(start 0.7874 0.4064)
			(end -0.7874 0.4064)
			(stroke
				(width 0.1524)
				(type default)
			)
			(layer "F.SilkS")
		)
		(fp_line
			(start 0.7874 -0.4064)
			(end 0.7874 0.4064)
			(stroke
				(width 0.1524)
				(type default)
			)
			(layer "F.SilkS")
		)
		(fp_line
			(start -0.7874 0.4064)
			(end -0.7874 -0.4064)
			(stroke
				(width 0.1524)
				(type default)
			)
			(layer "F.SilkS")
		)
		(fp_line
			(start -0.7874 -0.4064)
			(end 0.7874 -0.4064)
			(stroke
				(width 0.1524)
				(type default)
			)
			(layer "F.SilkS")
		)
		(fp_line
			(start 0.67945 0.3048)
			(end 0.120396 0.3048)
			(stroke
				(width 0.1)
				(type default)
			)
			(layer "F.Fab")
		)
		(fp_line
			(start 0.67945 -0.3048)
			(end 0.67945 0.3048)
			(stroke
				(width 0.1)
				(type default)
			)
			(layer "F.Fab")
		)
		(fp_line
			(start 0.12065 -0.2794)
			(end 0.12065 -0.3048)
			(stroke
				(width 0.1)
				(type default)
			)
			(layer "F.Fab")
		)
		(fp_line
			(start 0.12065 -0.3048)
			(end 0.67945 -0.3048)
			(stroke
				(width 0.1)
				(type default)
			)
			(layer "F.Fab")
		)
		(fp_line
			(start 0.120396 0.3048)
			(end 0.120396 0.2794)
			(stroke
				(width 0.1)
				(type default)
			)
			(layer "F.Fab")
		)
		(fp_line
			(start 0.120396 0.2794)
			(end -0.12065 0.2794)
			(stroke
				(width 0.1)
				(type default)
			)
			(layer "F.Fab")
		)
		(fp_line
			(start -0.12065 0.3048)
			(end -0.67945 0.3048)
			(stroke
				(width 0.1)
				(type default)
			)
			(layer "F.Fab")
		)
		(fp_line
			(start -0.12065 0.2794)
			(end -0.12065 0.3048)
			(stroke
				(width 0.1)
				(type default)
			)
			(layer "F.Fab")
		)
		(fp_line
			(start -0.12065 -0.2794)
			(end 0.12065 -0.2794)
			(stroke
				(width 0.1)
				(type default)
			)
			(layer "F.Fab")
		)
		(fp_line
			(start -0.12065 -0.305054)
			(end -0.12065 -0.2794)
			(stroke
				(width 0.1)
				(type default)
			)
			(layer "F.Fab")
		)
		(fp_line
			(start -0.67945 0.3048)
			(end -0.67945 -0.305054)
			(stroke
				(width 0.1)
				(type default)
			)
			(layer "F.Fab")
		)
		(fp_line
			(start -0.67945 -0.305054)
			(end -0.12065 -0.305054)
			(stroke
				(width 0.1)
				(type default)
			)
			(layer "F.Fab")
		)
		(pad "1" smd circle
			(at -0.40005 0 180)
			(size 0 0)
			(layers "F.Cu" "F.Mask" "F.Paste")
			(net "P3V3_AUX")
		)
		(pad "2" smd circle
			(at 0.40005 0 180)
			(size 0 0)
			(layers "F.Cu" "F.Mask" "F.Paste")
			(net "SMB_FRU_3V3AUX_SCL")
		)
	)
	(footprint ""
		(layer "F.Cu")
		(at 54.811168 -160.047178)
		(property "Reference" "PC444_P1_1"
			(at 0 0 0)
			(layer "F.SilkS")
			(hide yes)
			(effects
				(font
					(size 1.27 1.27)
				)
			)
		)
		(property "Value" ""
			(at 0 0 0)
			(layer "F.Fab")
			(effects
				(font
					(size 1.27 1.27)
				)
			)
		)
		(duplicate_pad_numbers_are_jumpers no)
		(fp_line
			(start -0.7874 -0.4064)
			(end 0.7874 -0.4064)
			(stroke
				(width 0.1524)
				(type default)
			)
			(layer "F.SilkS")
		)
		(fp_line
			(start -0.7874 0.4064)
			(end -0.7874 -0.4064)
			(stroke
				(width 0.1524)
				(type default)
			)
			(layer "F.SilkS")
		)
		(fp_line
			(start 0.7874 -0.4064)
			(end 0.7874 0.4064)
			(stroke
				(width 0.1524)
				(type default)
			)
			(layer "F.SilkS")
		)
		(fp_line
			(start 0.7874 0.4064)
			(end -0.7874 0.4064)
			(stroke
				(width 0.1524)
				(type default)
			)
			(layer "F.SilkS")
		)
		(fp_line
			(start -0.67945 -0.305054)
			(end -0.12065 -0.305054)
			(stroke
				(width 0.1)
				(type default)
			)
			(layer "F.Fab")
		)
		(fp_line
			(start -0.67945 0.3048)
			(end -0.67945 -0.305054)
			(stroke
				(width 0.1)
				(type default)
			)
			(layer "F.Fab")
		)
		(fp_line
			(start -0.12065 -0.305054)
			(end -0.12065 -0.2794)
			(stroke
				(width 0.1)
				(type default)
			)
			(layer "F.Fab")
		)
		(fp_line
			(start -0.12065 -0.2794)
			(end 0.12065 -0.2794)
			(stroke
				(width 0.1)
				(type default)
			)
			(layer "F.Fab")
		)
		(fp_line
			(start -0.12065 0.2794)
			(end -0.12065 0.3048)
			(stroke
				(width 0.1)
				(type default)
			)
			(layer "F.Fab")
		)
		(fp_line
			(start -0.12065 0.3048)
			(end -0.67945 0.3048)
			(stroke
				(width 0.1)
				(type default)
			)
			(layer "F.Fab")
		)
		(fp_line
			(start 0.120396 0.2794)
			(end -0.12065 0.2794)
			(stroke
				(width 0.1)
				(type default)
			)
			(layer "F.Fab")
		)
		(fp_line
			(start 0.120396 0.3048)
			(end 0.120396 0.2794)
			(stroke
				(width 0.1)
				(type default)
			)
			(layer "F.Fab")
		)
		(fp_line
			(start 0.12065 -0.3048)
			(end 0.67945 -0.3048)
			(stroke
				(width 0.1)
				(type default)
			)
			(layer "F.Fab")
		)
		(fp_line
			(start 0.12065 -0.2794)
			(end 0.12065 -0.3048)
			(stroke
				(width 0.1)
				(type default)
			)
			(layer "F.Fab")
		)
		(fp_line
			(start 0.67945 -0.3048)
			(end 0.67945 0.3048)
			(stroke
				(width 0.1)
				(type default)
			)
			(layer "F.Fab")
		)
		(fp_line
			(start 0.67945 0.3048)
			(end 0.120396 0.3048)
			(stroke
				(width 0.1)
				(type default)
			)
			(layer "F.Fab")
		)
		(pad "1" smd circle
			(at -0.40005 0)
			(size 0 0)
			(layers "F.Cu" "F.Mask" "F.Paste")
			(net "SW_P12V_PVCCINFAON_CPU1_FLT")
		)
		(pad "2" smd circle
			(at 0.40005 0)
			(size 0 0)
			(layers "F.Cu" "F.Mask" "F.Paste")
			(net "GND")
		)
	)
	(footprint ""
		(layer "F.Cu")
		(at 280.20645 -394.17117)
		(property "Reference" "PR2538"
			(at 0 0 0)
			(layer "F.SilkS")
			(hide yes)
			(effects
				(font
					(size 1.27 1.27)
				)
			)
		)
		(property "Value" ""
			(at 0 0 0)
			(layer "F.Fab")
			(effects
				(font
					(size 1.27 1.27)
				)
			)
		)
		(duplicate_pad_numbers_are_jumpers no)
		(fp_line
			(start -0.7874 -0.4064)
			(end 0.7874 -0.4064)
			(stroke
				(width 0.1524)
				(type default)
			)
			(layer "F.SilkS")
		)
		(fp_line
			(start -0.7874 0.4064)
			(end -0.7874 -0.4064)
			(stroke
				(width 0.1524)
				(type default)
			)
			(layer "F.SilkS")
		)
		(fp_line
			(start 0.7874 -0.4064)
			(end 0.7874 0.4064)
			(stroke
				(width 0.1524)
				(type default)
			)
			(layer "F.SilkS")
		)
		(fp_line
			(start 0.7874 0.4064)
			(end -0.7874 0.4064)
			(stroke
				(width 0.1524)
				(type default)
			)
			(layer "F.SilkS")
		)
		(fp_line
			(start -0.67945 -0.305054)
			(end -0.12065 -0.305054)
			(stroke
				(width 0.1)
				(type default)
			)
			(layer "F.Fab")
		)
		(fp_line
			(start -0.67945 0.3048)
			(end -0.67945 -0.305054)
			(stroke
				(width 0.1)
				(type default)
			)
			(layer "F.Fab")
		)
		(fp_line
			(start -0.12065 -0.305054)
			(end -0.12065 -0.2794)
			(stroke
				(width 0.1)
				(type default)
			)
			(layer "F.Fab")
		)
		(fp_line
			(start -0.12065 -0.2794)
			(end 0.12065 -0.2794)
			(stroke
				(width 0.1)
				(type default)
			)
			(layer "F.Fab")
		)
		(fp_line
			(start -0.12065 0.2794)
			(end -0.12065 0.3048)
			(stroke
				(width 0.1)
				(type default)
			)
			(layer "F.Fab")
		)
		(fp_line
			(start -0.12065 0.3048)
			(end -0.67945 0.3048)
			(stroke
				(width 0.1)
				(type default)
			)
			(layer "F.Fab")
		)
		(fp_line
			(start 0.120396 0.2794)
			(end -0.12065 0.2794)
			(stroke
				(width 0.1)
				(type default)
			)
			(layer "F.Fab")
		)
		(fp_line
			(start 0.120396 0.3048)
			(end 0.120396 0.2794)
			(stroke
				(width 0.1)
				(type default)
			)
			(layer "F.Fab")
		)
		(fp_line
			(start 0.12065 -0.3048)
			(end 0.67945 -0.3048)
			(stroke
				(width 0.1)
				(type default)
			)
			(layer "F.Fab")
		)
		(fp_line
			(start 0.12065 -0.2794)
			(end 0.12065 -0.3048)
			(stroke
				(width 0.1)
				(type default)
			)
			(layer "F.Fab")
		)
		(fp_line
			(start 0.67945 -0.3048)
			(end 0.67945 0.3048)
			(stroke
				(width 0.1)
				(type default)
			)
			(layer "F.Fab")
		)
		(fp_line
			(start 0.67945 0.3048)
			(end 0.120396 0.3048)
			(stroke
				(width 0.1)
				(type default)
			)
			(layer "F.Fab")
		)
		(pad "1" smd circle
			(at -0.40005 0)
			(size 0 0)
			(layers "F.Cu" "F.Mask" "F.Paste")
			(net "MB0_CM_GATE_G0")
		)
		(pad "2" smd circle
			(at 0.40005 0)
			(size 0 0)
			(layers "F.Cu" "F.Mask" "F.Paste")
			(net "P12V_HSC_GATE1")
		)
	)
	(footprint ""
		(layer "F.Cu")
		(at 361.573826 -365.290354 90)
		(property "Reference" "PC1173"
			(at 0 0 90)
			(layer "F.SilkS")
			(hide yes)
			(effects
				(font
					(size 1.27 1.27)
				)
			)
		)
		(property "Value" ""
			(at 0 0 90)
			(layer "F.Fab")
			(effects
				(font
					(size 1.27 1.27)
				)
			)
		)
		(duplicate_pad_numbers_are_jumpers no)
		(fp_line
			(start 0.7874 -0.4064)
			(end 0.7874 0.4064)
			(stroke
				(width 0.1524)
				(type default)
			)
			(layer "F.SilkS")
		)
		(fp_line
			(start -0.7874 -0.4064)
			(end 0.7874 -0.4064)
			(stroke
				(width 0.1524)
				(type default)
			)
			(layer "F.SilkS")
		)
		(fp_line
			(start 0.7874 0.4064)
			(end -0.7874 0.4064)
			(stroke
				(width 0.1524)
				(type default)
			)
			(layer "F.SilkS")
		)
		(fp_line
			(start -0.7874 0.4064)
			(end -0.7874 -0.4064)
			(stroke
				(width 0.1524)
				(type default)
			)
			(layer "F.SilkS")
		)
		(fp_line
			(start -0.12065 -0.305054)
			(end -0.12065 -0.2794)
			(stroke
				(width 0.1)
				(type default)
			)
			(layer "F.Fab")
		)
		(fp_line
			(start -0.67945 -0.305054)
			(end -0.12065 -0.305054)
			(stroke
				(width 0.1)
				(type default)
			)
			(layer "F.Fab")
		)
		(fp_line
			(start 0.67945 -0.3048)
			(end 0.67945 0.3048)
			(stroke
				(width 0.1)
				(type default)
			)
			(layer "F.Fab")
		)
		(fp_line
			(start 0.12065 -0.3048)
			(end 0.67945 -0.3048)
			(stroke
				(width 0.1)
				(type default)
			)
			(layer "F.Fab")
		)
		(fp_line
			(start 0.12065 -0.2794)
			(end 0.12065 -0.3048)
			(stroke
				(width 0.1)
				(type default)
			)
			(layer "F.Fab")
		)
		(fp_line
			(start -0.12065 -0.2794)
			(end 0.12065 -0.2794)
			(stroke
				(width 0.1)
				(type default)
			)
			(layer "F.Fab")
		)
		(fp_line
			(start 0.120396 0.2794)
			(end -0.12065 0.2794)
			(stroke
				(width 0.1)
				(type default)
			)
			(layer "F.Fab")
		)
		(fp_line
			(start -0.12065 0.2794)
			(end -0.12065 0.3048)
			(stroke
				(width 0.1)
				(type default)
			)
			(layer "F.Fab")
		)
		(fp_line
			(start 0.67945 0.3048)
			(end 0.120396 0.3048)
			(stroke
				(width 0.1)
				(type default)
			)
			(layer "F.Fab")
		)
		(fp_line
			(start 0.120396 0.3048)
			(end 0.120396 0.2794)
			(stroke
				(width 0.1)
				(type default)
			)
			(layer "F.Fab")
		)
		(fp_line
			(start -0.12065 0.3048)
			(end -0.67945 0.3048)
			(stroke
				(width 0.1)
				(type default)
			)
			(layer "F.Fab")
		)
		(fp_line
			(start -0.67945 0.3048)
			(end -0.67945 -0.305054)
			(stroke
				(width 0.1)
				(type default)
			)
			(layer "F.Fab")
		)
		(pad "1" smd circle
			(at -0.40005 0 90)
			(size 0 0)
			(layers "F.Cu" "F.Mask" "F.Paste")
			(net "PVCCIN_CPU0_VREF")
		)
		(pad "2" smd circle
			(at 0.40005 0 90)
			(size 0 0)
			(layers "F.Cu" "F.Mask" "F.Paste")
			(net "GND")
		)
	)
	(footprint ""
		(layer "F.Cu")
		(at 164.247576 -36.825428)
		(property "Reference" "R4464"
			(at 0 0 0)
			(layer "F.SilkS")
			(hide yes)
			(effects
				(font
					(size 1.27 1.27)
				)
			)
		)
		(property "Value" ""
			(at 0 0 0)
			(layer "F.Fab")
			(effects
				(font
					(size 1.27 1.27)
				)
			)
		)
		(duplicate_pad_numbers_are_jumpers no)
		(fp_line
			(start -0.7874 -0.4064)
			(end 0.7874 -0.4064)
			(stroke
				(width 0.1524)
				(type default)
			)
			(layer "F.SilkS")
		)
		(fp_line
			(start -0.7874 0.4064)
			(end -0.7874 -0.4064)
			(stroke
				(width 0.1524)
				(type default)
			)
			(layer "F.SilkS")
		)
		(fp_line
			(start 0.7874 -0.4064)
			(end 0.7874 0.4064)
			(stroke
				(width 0.1524)
				(type default)
			)
			(layer "F.SilkS")
		)
		(fp_line
			(start 0.7874 0.4064)
			(end -0.7874 0.4064)
			(stroke
				(width 0.1524)
				(type default)
			)
			(layer "F.SilkS")
		)
		(fp_line
			(start -0.67945 -0.305054)
			(end -0.12065 -0.305054)
			(stroke
				(width 0.1)
				(type default)
			)
			(layer "F.Fab")
		)
		(fp_line
			(start -0.67945 0.3048)
			(end -0.67945 -0.305054)
			(stroke
				(width 0.1)
				(type default)
			)
			(layer "F.Fab")
		)
		(fp_line
			(start -0.12065 -0.305054)
			(end -0.12065 -0.2794)
			(stroke
				(width 0.1)
				(type default)
			)
			(layer "F.Fab")
		)
		(fp_line
			(start -0.12065 -0.2794)
			(end 0.12065 -0.2794)
			(stroke
				(width 0.1)
				(type default)
			)
			(layer "F.Fab")
		)
		(fp_line
			(start -0.12065 0.2794)
			(end -0.12065 0.3048)
			(stroke
				(width 0.1)
				(type default)
			)
			(layer "F.Fab")
		)
		(fp_line
			(start -0.12065 0.3048)
			(end -0.67945 0.3048)
			(stroke
				(width 0.1)
				(type default)
			)
			(layer "F.Fab")
		)
		(fp_line
			(start 0.120396 0.2794)
			(end -0.12065 0.2794)
			(stroke
				(width 0.1)
				(type default)
			)
			(layer "F.Fab")
		)
		(fp_line
			(start 0.120396 0.3048)
			(end 0.120396 0.2794)
			(stroke
				(width 0.1)
				(type default)
			)
			(layer "F.Fab")
		)
		(fp_line
			(start 0.12065 -0.3048)
			(end 0.67945 -0.3048)
			(stroke
				(width 0.1)
				(type default)
			)
			(layer "F.Fab")
		)
		(fp_line
			(start 0.12065 -0.2794)
			(end 0.12065 -0.3048)
			(stroke
				(width 0.1)
				(type default)
			)
			(layer "F.Fab")
		)
		(fp_line
			(start 0.67945 -0.3048)
			(end 0.67945 0.3048)
			(stroke
				(width 0.1)
				(type default)
			)
			(layer "F.Fab")
		)
		(fp_line
			(start 0.67945 0.3048)
			(end 0.120396 0.3048)
			(stroke
				(width 0.1)
				(type default)
			)
			(layer "F.Fab")
		)
		(pad "1" smd circle
			(at -0.40005 0)
			(size 0 0)
			(layers "F.Cu" "F.Mask" "F.Paste")
			(net "USB_HUB_2_PGANG")
		)
		(pad "2" smd circle
			(at 0.40005 0)
			(size 0 0)
			(layers "F.Cu" "F.Mask" "F.Paste")
			(net "GND")
		)
	)
	(footprint ""
		(layer "F.Cu")
		(at 352.301048 -247.715024 90)
		(property "Reference" "C405"
			(at 0 0 90)
			(layer "F.SilkS")
			(hide yes)
			(effects
				(font
					(size 1.27 1.27)
				)
			)
		)
		(property "Value" ""
			(at 0 0 90)
			(layer "F.Fab")
			(effects
				(font
					(size 1.27 1.27)
				)
			)
		)
		(duplicate_pad_numbers_are_jumpers no)
		(fp_line
			(start 0.7874 -0.4064)
			(end 0.7874 0.4064)
			(stroke
				(width 0.1524)
				(type default)
			)
			(layer "F.SilkS")
		)
		(fp_line
			(start -0.7874 -0.4064)
			(end 0.7874 -0.4064)
			(stroke
				(width 0.1524)
				(type default)
			)
			(layer "F.SilkS")
		)
		(fp_line
			(start 0.7874 0.4064)
			(end -0.7874 0.4064)
			(stroke
				(width 0.1524)
				(type default)
			)
			(layer "F.SilkS")
		)
		(fp_line
			(start -0.7874 0.4064)
			(end -0.7874 -0.4064)
			(stroke
				(width 0.1524)
				(type default)
			)
			(layer "F.SilkS")
		)
		(fp_line
			(start -0.12065 -0.305054)
			(end -0.12065 -0.2794)
			(stroke
				(width 0.1)
				(type default)
			)
			(layer "F.Fab")
		)
		(fp_line
			(start -0.67945 -0.305054)
			(end -0.12065 -0.305054)
			(stroke
				(width 0.1)
				(type default)
			)
			(layer "F.Fab")
		)
		(fp_line
			(start 0.67945 -0.3048)
			(end 0.67945 0.3048)
			(stroke
				(width 0.1)
				(type default)
			)
			(layer "F.Fab")
		)
		(fp_line
			(start 0.12065 -0.3048)
			(end 0.67945 -0.3048)
			(stroke
				(width 0.1)
				(type default)
			)
			(layer "F.Fab")
		)
		(fp_line
			(start 0.12065 -0.2794)
			(end 0.12065 -0.3048)
			(stroke
				(width 0.1)
				(type default)
			)
			(layer "F.Fab")
		)
		(fp_line
			(start -0.12065 -0.2794)
			(end 0.12065 -0.2794)
			(stroke
				(width 0.1)
				(type default)
			)
			(layer "F.Fab")
		)
		(fp_line
			(start 0.120396 0.2794)
			(end -0.12065 0.2794)
			(stroke
				(width 0.1)
				(type default)
			)
			(layer "F.Fab")
		)
		(fp_line
			(start -0.12065 0.2794)
			(end -0.12065 0.3048)
			(stroke
				(width 0.1)
				(type default)
			)
			(layer "F.Fab")
		)
		(fp_line
			(start 0.67945 0.3048)
			(end 0.120396 0.3048)
			(stroke
				(width 0.1)
				(type default)
			)
			(layer "F.Fab")
		)
		(fp_line
			(start 0.120396 0.3048)
			(end 0.120396 0.2794)
			(stroke
				(width 0.1)
				(type default)
			)
			(layer "F.Fab")
		)
		(fp_line
			(start -0.12065 0.3048)
			(end -0.67945 0.3048)
			(stroke
				(width 0.1)
				(type default)
			)
			(layer "F.Fab")
		)
		(fp_line
			(start -0.67945 0.3048)
			(end -0.67945 -0.305054)
			(stroke
				(width 0.1)
				(type default)
			)
			(layer "F.Fab")
		)
		(pad "1" smd circle
			(at -0.40005 0 90)
			(size 0 0)
			(layers "F.Cu" "F.Mask" "F.Paste")
			(net "PVCCD_HV_CPU0")
		)
		(pad "2" smd circle
			(at 0.40005 0 90)
			(size 0 0)
			(layers "F.Cu" "F.Mask" "F.Paste")
			(net "GND")
		)
	)
	(footprint ""
		(layer "F.Cu")
		(at 32.191452 -165.761162)
		(property "Reference" "PC386"
			(at 0 0 0)
			(layer "F.SilkS")
			(hide yes)
			(effects
				(font
					(size 1.27 1.27)
				)
			)
		)
		(property "Value" ""
			(at 0 0 0)
			(layer "F.Fab")
			(effects
				(font
					(size 1.27 1.27)
				)
			)
		)
		(duplicate_pad_numbers_are_jumpers no)
		(fp_line
			(start -0.7874 -0.4064)
			(end 0.7874 -0.4064)
			(stroke
				(width 0.1524)
				(type default)
			)
			(layer "F.SilkS")
		)
		(fp_line
			(start -0.7874 0.4064)
			(end -0.7874 -0.4064)
			(stroke
				(width 0.1524)
				(type default)
			)
			(layer "F.SilkS")
		)
		(fp_line
			(start 0.7874 -0.4064)
			(end 0.7874 0.4064)
			(stroke
				(width 0.1524)
				(type default)
			)
			(layer "F.SilkS")
		)
		(fp_line
			(start 0.7874 0.4064)
			(end -0.7874 0.4064)
			(stroke
				(width 0.1524)
				(type default)
			)
			(layer "F.SilkS")
		)
		(fp_line
			(start -0.67945 -0.305054)
			(end -0.12065 -0.305054)
			(stroke
				(width 0.1)
				(type default)
			)
			(layer "F.Fab")
		)
		(fp_line
			(start -0.67945 0.3048)
			(end -0.67945 -0.305054)
			(stroke
				(width 0.1)
				(type default)
			)
			(layer "F.Fab")
		)
		(fp_line
			(start -0.12065 -0.305054)
			(end -0.12065 -0.2794)
			(stroke
				(width 0.1)
				(type default)
			)
			(layer "F.Fab")
		)
		(fp_line
			(start -0.12065 -0.2794)
			(end 0.12065 -0.2794)
			(stroke
				(width 0.1)
				(type default)
			)
			(layer "F.Fab")
		)
		(fp_line
			(start -0.12065 0.2794)
			(end -0.12065 0.3048)
			(stroke
				(width 0.1)
				(type default)
			)
			(layer "F.Fab")
		)
		(fp_line
			(start -0.12065 0.3048)
			(end -0.67945 0.3048)
			(stroke
				(width 0.1)
				(type default)
			)
			(layer "F.Fab")
		)
		(fp_line
			(start 0.120396 0.2794)
			(end -0.12065 0.2794)
			(stroke
				(width 0.1)
				(type default)
			)
			(layer "F.Fab")
		)
		(fp_line
			(start 0.120396 0.3048)
			(end 0.120396 0.2794)
			(stroke
				(width 0.1)
				(type default)
			)
			(layer "F.Fab")
		)
		(fp_line
			(start 0.12065 -0.3048)
			(end 0.67945 -0.3048)
			(stroke
				(width 0.1)
				(type default)
			)
			(layer "F.Fab")
		)
		(fp_line
			(start 0.12065 -0.2794)
			(end 0.12065 -0.3048)
			(stroke
				(width 0.1)
				(type default)
			)
			(layer "F.Fab")
		)
		(fp_line
			(start 0.67945 -0.3048)
			(end 0.67945 0.3048)
			(stroke
				(width 0.1)
				(type default)
			)
			(layer "F.Fab")
		)
		(fp_line
			(start 0.67945 0.3048)
			(end 0.120396 0.3048)
			(stroke
				(width 0.1)
				(type default)
			)
			(layer "F.Fab")
		)
		(pad "1" smd circle
			(at -0.40005 0)
			(size 0 0)
			(layers "F.Cu" "F.Mask" "F.Paste")
			(net "PVCCD_HV_CPU1_ISENSE_P")
		)
		(pad "2" smd circle
			(at 0.40005 0)
			(size 0 0)
			(layers "F.Cu" "F.Mask" "F.Paste")
			(net "GND")
		)
	)
	(footprint ""
		(layer "F.Cu")
		(at 370.232686 -357.11638 90)
		(property "Reference" "PR1310"
			(at 0 0 90)
			(layer "F.SilkS")
			(hide yes)
			(effects
				(font
					(size 1.27 1.27)
				)
			)
		)
		(property "Value" ""
			(at 0 0 90)
			(layer "F.Fab")
			(effects
				(font
					(size 1.27 1.27)
				)
			)
		)
		(duplicate_pad_numbers_are_jumpers no)
		(fp_line
			(start 0.7874 -0.4064)
			(end 0.7874 0.4064)
			(stroke
				(width 0.1524)
				(type default)
			)
			(layer "F.SilkS")
		)
		(fp_line
			(start -0.7874 -0.4064)
			(end 0.7874 -0.4064)
			(stroke
				(width 0.1524)
				(type default)
			)
			(layer "F.SilkS")
		)
		(fp_line
			(start 0.7874 0.4064)
			(end -0.7874 0.4064)
			(stroke
				(width 0.1524)
				(type default)
			)
			(layer "F.SilkS")
		)
		(fp_line
			(start -0.7874 0.4064)
			(end -0.7874 -0.4064)
			(stroke
				(width 0.1524)
				(type default)
			)
			(layer "F.SilkS")
		)
		(fp_line
			(start -0.12065 -0.305054)
			(end -0.12065 -0.2794)
			(stroke
				(width 0.1)
				(type default)
			)
			(layer "F.Fab")
		)
		(fp_line
			(start -0.67945 -0.305054)
			(end -0.12065 -0.305054)
			(stroke
				(width 0.1)
				(type default)
			)
			(layer "F.Fab")
		)
		(fp_line
			(start 0.67945 -0.3048)
			(end 0.67945 0.3048)
			(stroke
				(width 0.1)
				(type default)
			)
			(layer "F.Fab")
		)
		(fp_line
			(start 0.12065 -0.3048)
			(end 0.67945 -0.3048)
			(stroke
				(width 0.1)
				(type default)
			)
			(layer "F.Fab")
		)
		(fp_line
			(start 0.12065 -0.2794)
			(end 0.12065 -0.3048)
			(stroke
				(width 0.1)
				(type default)
			)
			(layer "F.Fab")
		)
		(fp_line
			(start -0.12065 -0.2794)
			(end 0.12065 -0.2794)
			(stroke
				(width 0.1)
				(type default)
			)
			(layer "F.Fab")
		)
		(fp_line
			(start 0.120396 0.2794)
			(end -0.12065 0.2794)
			(stroke
				(width 0.1)
				(type default)
			)
			(layer "F.Fab")
		)
		(fp_line
			(start -0.12065 0.2794)
			(end -0.12065 0.3048)
			(stroke
				(width 0.1)
				(type default)
			)
			(layer "F.Fab")
		)
		(fp_line
			(start 0.67945 0.3048)
			(end 0.120396 0.3048)
			(stroke
				(width 0.1)
				(type default)
			)
			(layer "F.Fab")
		)
		(fp_line
			(start 0.120396 0.3048)
			(end 0.120396 0.2794)
			(stroke
				(width 0.1)
				(type default)
			)
			(layer "F.Fab")
		)
		(fp_line
			(start -0.12065 0.3048)
			(end -0.67945 0.3048)
			(stroke
				(width 0.1)
				(type default)
			)
			(layer "F.Fab")
		)
		(fp_line
			(start -0.67945 0.3048)
			(end -0.67945 -0.305054)
			(stroke
				(width 0.1)
				(type default)
			)
			(layer "F.Fab")
		)
		(pad "1" smd circle
			(at -0.40005 0 90)
			(size 0 0)
			(layers "F.Cu" "F.Mask" "F.Paste")
			(net "PVPP_HBM_CPU0_FB")
		)
		(pad "2" smd circle
			(at 0.40005 0 90)
			(size 0 0)
			(layers "F.Cu" "F.Mask" "F.Paste")
			(net "SH_PVPP_HBM_CPU0_N")
		)
	)
	(footprint ""
		(layer "F.Cu")
		(at 22.100032 -176.329086)
		(property "Reference" "PR51"
			(at 0 0 0)
			(layer "F.SilkS")
			(hide yes)
			(effects
				(font
					(size 1.27 1.27)
				)
			)
		)
		(property "Value" ""
			(at 0 0 0)
			(layer "F.Fab")
			(effects
				(font
					(size 1.27 1.27)
				)
			)
		)
		(duplicate_pad_numbers_are_jumpers no)
		(fp_line
			(start -0.7874 -0.4064)
			(end 0.7874 -0.4064)
			(stroke
				(width 0.1524)
				(type default)
			)
			(layer "F.SilkS")
		)
		(fp_line
			(start -0.7874 0.4064)
			(end -0.7874 -0.4064)
			(stroke
				(width 0.1524)
				(type default)
			)
			(layer "F.SilkS")
		)
		(fp_line
			(start 0.7874 -0.4064)
			(end 0.7874 0.4064)
			(stroke
				(width 0.1524)
				(type default)
			)
			(layer "F.SilkS")
		)
		(fp_line
			(start 0.7874 0.4064)
			(end -0.7874 0.4064)
			(stroke
				(width 0.1524)
				(type default)
			)
			(layer "F.SilkS")
		)
		(fp_line
			(start -0.67945 -0.305054)
			(end -0.12065 -0.305054)
			(stroke
				(width 0.1)
				(type default)
			)
			(layer "F.Fab")
		)
		(fp_line
			(start -0.67945 0.3048)
			(end -0.67945 -0.305054)
			(stroke
				(width 0.1)
				(type default)
			)
			(layer "F.Fab")
		)
		(fp_line
			(start -0.12065 -0.305054)
			(end -0.12065 -0.2794)
			(stroke
				(width 0.1)
				(type default)
			)
			(layer "F.Fab")
		)
		(fp_line
			(start -0.12065 -0.2794)
			(end 0.12065 -0.2794)
			(stroke
				(width 0.1)
				(type default)
			)
			(layer "F.Fab")
		)
		(fp_line
			(start -0.12065 0.2794)
			(end -0.12065 0.3048)
			(stroke
				(width 0.1)
				(type default)
			)
			(layer "F.Fab")
		)
		(fp_line
			(start -0.12065 0.3048)
			(end -0.67945 0.3048)
			(stroke
				(width 0.1)
				(type default)
			)
			(layer "F.Fab")
		)
		(fp_line
			(start 0.120396 0.2794)
			(end -0.12065 0.2794)
			(stroke
				(width 0.1)
				(type default)
			)
			(layer "F.Fab")
		)
		(fp_line
			(start 0.120396 0.3048)
			(end 0.120396 0.2794)
			(stroke
				(width 0.1)
				(type default)
			)
			(layer "F.Fab")
		)
		(fp_line
			(start 0.12065 -0.3048)
			(end 0.67945 -0.3048)
			(stroke
				(width 0.1)
				(type default)
			)
			(layer "F.Fab")
		)
		(fp_line
			(start 0.12065 -0.2794)
			(end 0.12065 -0.3048)
			(stroke
				(width 0.1)
				(type default)
			)
			(layer "F.Fab")
		)
		(fp_line
			(start 0.67945 -0.3048)
			(end 0.67945 0.3048)
			(stroke
				(width 0.1)
				(type default)
			)
			(layer "F.Fab")
		)
		(fp_line
			(start 0.67945 0.3048)
			(end 0.120396 0.3048)
			(stroke
				(width 0.1)
				(type default)
			)
			(layer "F.Fab")
		)
		(pad "1" smd circle
			(at -0.40005 0)
			(size 0 0)
			(layers "F.Cu" "F.Mask" "F.Paste")
			(net "PVNN_MAIN_CPU1_FB")
		)
		(pad "2" smd circle
			(at 0.40005 0)
			(size 0 0)
			(layers "F.Cu" "F.Mask" "F.Paste")
			(net "GND")
		)
	)
	(footprint ""
		(layer "F.Cu")
		(at 157.351984 -81.90738 90)
		(property "Reference" "R3126"
			(at 0 0 90)
			(layer "F.SilkS")
			(hide yes)
			(effects
				(font
					(size 1.27 1.27)
				)
			)
		)
		(property "Value" ""
			(at 0 0 90)
			(layer "F.Fab")
			(effects
				(font
					(size 1.27 1.27)
				)
			)
		)
		(duplicate_pad_numbers_are_jumpers no)
		(fp_line
			(start 0.7874 -0.4064)
			(end 0.7874 0.4064)
			(stroke
				(width 0.1524)
				(type default)
			)
			(layer "F.SilkS")
		)
		(fp_line
			(start -0.7874 -0.4064)
			(end 0.7874 -0.4064)
			(stroke
				(width 0.1524)
				(type default)
			)
			(layer "F.SilkS")
		)
		(fp_line
			(start 0.7874 0.4064)
			(end -0.7874 0.4064)
			(stroke
				(width 0.1524)
				(type default)
			)
			(layer "F.SilkS")
		)
		(fp_line
			(start -0.7874 0.4064)
			(end -0.7874 -0.4064)
			(stroke
				(width 0.1524)
				(type default)
			)
			(layer "F.SilkS")
		)
		(fp_line
			(start -0.12065 -0.305054)
			(end -0.12065 -0.2794)
			(stroke
				(width 0.1)
				(type default)
			)
			(layer "F.Fab")
		)
		(fp_line
			(start -0.67945 -0.305054)
			(end -0.12065 -0.305054)
			(stroke
				(width 0.1)
				(type default)
			)
			(layer "F.Fab")
		)
		(fp_line
			(start 0.67945 -0.3048)
			(end 0.67945 0.3048)
			(stroke
				(width 0.1)
				(type default)
			)
			(layer "F.Fab")
		)
		(fp_line
			(start 0.12065 -0.3048)
			(end 0.67945 -0.3048)
			(stroke
				(width 0.1)
				(type default)
			)
			(layer "F.Fab")
		)
		(fp_line
			(start 0.12065 -0.2794)
			(end 0.12065 -0.3048)
			(stroke
				(width 0.1)
				(type default)
			)
			(layer "F.Fab")
		)
		(fp_line
			(start -0.12065 -0.2794)
			(end 0.12065 -0.2794)
			(stroke
				(width 0.1)
				(type default)
			)
			(layer "F.Fab")
		)
		(fp_line
			(start 0.120396 0.2794)
			(end -0.12065 0.2794)
			(stroke
				(width 0.1)
				(type default)
			)
			(layer "F.Fab")
		)
		(fp_line
			(start -0.12065 0.2794)
			(end -0.12065 0.3048)
			(stroke
				(width 0.1)
				(type default)
			)
			(layer "F.Fab")
		)
		(fp_line
			(start 0.67945 0.3048)
			(end 0.120396 0.3048)
			(stroke
				(width 0.1)
				(type default)
			)
			(layer "F.Fab")
		)
		(fp_line
			(start 0.120396 0.3048)
			(end 0.120396 0.2794)
			(stroke
				(width 0.1)
				(type default)
			)
			(layer "F.Fab")
		)
		(fp_line
			(start -0.12065 0.3048)
			(end -0.67945 0.3048)
			(stroke
				(width 0.1)
				(type default)
			)
			(layer "F.Fab")
		)
		(fp_line
			(start -0.67945 0.3048)
			(end -0.67945 -0.305054)
			(stroke
				(width 0.1)
				(type default)
			)
			(layer "F.Fab")
		)
		(pad "1" smd circle
			(at -0.40005 0 90)
			(size 0 0)
			(layers "F.Cu" "F.Mask" "F.Paste")
			(net "SMB_S3M_CPU1_PIROM_3V3AUX_SDA_R")
		)
		(pad "2" smd circle
			(at 0.40005 0 90)
			(size 0 0)
			(layers "F.Cu" "F.Mask" "F.Paste")
			(net "SMB_S3M_CPU1_PIROM_3V3AUX_SDA")
		)
	)
	(footprint ""
		(layer "F.Cu")
		(at 404.29053 -408.517344 -90)
		(property "Reference" "C891"
			(at 0 0 270)
			(layer "F.SilkS")
			(hide yes)
			(effects
				(font
					(size 1.27 1.27)
				)
			)
		)
		(property "Value" ""
			(at 0 0 270)
			(layer "F.Fab")
			(effects
				(font
					(size 1.27 1.27)
				)
			)
		)
		(duplicate_pad_numbers_are_jumpers no)
		(fp_line
			(start -0.299974 0.150114)
			(end -0.299974 -0.150114)
			(stroke
				(width 0.1)
				(type default)
			)
			(layer "F.Fab")
		)
		(fp_line
			(start 0.299974 0.150114)
			(end -0.299974 0.150114)
			(stroke
				(width 0.1)
				(type default)
			)
			(layer "F.Fab")
		)
		(fp_line
			(start -0.299974 -0.150114)
			(end 0.299974 -0.150114)
			(stroke
				(width 0.1)
				(type default)
			)
			(layer "F.Fab")
		)
		(fp_line
			(start 0.299974 -0.150114)
			(end 0.299974 0.150114)
			(stroke
				(width 0.1)
				(type default)
			)
			(layer "F.Fab")
		)
		(pad "1" smd rect
			(at -0.2667 0 270)
			(size 0.3048 0.381)
			(layers "F.Cu" "F.Mask" "F.Paste")
			(net "P5E_CPU0_PE3_TX_C_DP<5>")
		)
		(pad "2" smd rect
			(at 0.2667 0 270)
			(size 0.3048 0.381)
			(layers "F.Cu" "F.Mask" "F.Paste")
			(net "P5E_CPU0_PE3_TX_DP<5>")
		)
	)
	(footprint ""
		(layer "F.Cu")
		(at 160.83788 -109.565948)
		(property "Reference" "R2847"
			(at 0 0 0)
			(layer "F.SilkS")
			(hide yes)
			(effects
				(font
					(size 1.27 1.27)
				)
			)
		)
		(property "Value" ""
			(at 0 0 0)
			(layer "F.Fab")
			(effects
				(font
					(size 1.27 1.27)
				)
			)
		)
		(duplicate_pad_numbers_are_jumpers no)
		(fp_line
			(start -0.7874 -0.4064)
			(end 0.7874 -0.4064)
			(stroke
				(width 0.1524)
				(type default)
			)
			(layer "F.SilkS")
		)
		(fp_line
			(start -0.7874 0.4064)
			(end -0.7874 -0.4064)
			(stroke
				(width 0.1524)
				(type default)
			)
			(layer "F.SilkS")
		)
		(fp_line
			(start 0.7874 -0.4064)
			(end 0.7874 0.4064)
			(stroke
				(width 0.1524)
				(type default)
			)
			(layer "F.SilkS")
		)
		(fp_line
			(start 0.7874 0.4064)
			(end -0.7874 0.4064)
			(stroke
				(width 0.1524)
				(type default)
			)
			(layer "F.SilkS")
		)
		(fp_line
			(start -0.67945 -0.305054)
			(end -0.12065 -0.305054)
			(stroke
				(width 0.1)
				(type default)
			)
			(layer "F.Fab")
		)
		(fp_line
			(start -0.67945 0.3048)
			(end -0.67945 -0.305054)
			(stroke
				(width 0.1)
				(type default)
			)
			(layer "F.Fab")
		)
		(fp_line
			(start -0.12065 -0.305054)
			(end -0.12065 -0.2794)
			(stroke
				(width 0.1)
				(type default)
			)
			(layer "F.Fab")
		)
		(fp_line
			(start -0.12065 -0.2794)
			(end 0.12065 -0.2794)
			(stroke
				(width 0.1)
				(type default)
			)
			(layer "F.Fab")
		)
		(fp_line
			(start -0.12065 0.2794)
			(end -0.12065 0.3048)
			(stroke
				(width 0.1)
				(type default)
			)
			(layer "F.Fab")
		)
		(fp_line
			(start -0.12065 0.3048)
			(end -0.67945 0.3048)
			(stroke
				(width 0.1)
				(type default)
			)
			(layer "F.Fab")
		)
		(fp_line
			(start 0.120396 0.2794)
			(end -0.12065 0.2794)
			(stroke
				(width 0.1)
				(type default)
			)
			(layer "F.Fab")
		)
		(fp_line
			(start 0.120396 0.3048)
			(end 0.120396 0.2794)
			(stroke
				(width 0.1)
				(type default)
			)
			(layer "F.Fab")
		)
		(fp_line
			(start 0.12065 -0.3048)
			(end 0.67945 -0.3048)
			(stroke
				(width 0.1)
				(type default)
			)
			(layer "F.Fab")
		)
		(fp_line
			(start 0.12065 -0.2794)
			(end 0.12065 -0.3048)
			(stroke
				(width 0.1)
				(type default)
			)
			(layer "F.Fab")
		)
		(fp_line
			(start 0.67945 -0.3048)
			(end 0.67945 0.3048)
			(stroke
				(width 0.1)
				(type default)
			)
			(layer "F.Fab")
		)
		(fp_line
			(start 0.67945 0.3048)
			(end 0.120396 0.3048)
			(stroke
				(width 0.1)
				(type default)
			)
			(layer "F.Fab")
		)
		(pad "1" smd circle
			(at -0.40005 0)
			(size 0 0)
			(layers "F.Cu" "F.Mask" "F.Paste")
			(net "RST_BMC_FROM_SWB_ISO_N")
		)
		(pad "2" smd circle
			(at 0.40005 0)
			(size 0 0)
			(layers "F.Cu" "F.Mask" "F.Paste")
			(net "RST_BMC_FROM_SWB_ISO_R_N")
		)
	)
	(footprint ""
		(layer "F.Cu")
		(at 107.2769 -255.0541 90)
		(property "Reference" "C279"
			(at 0 0 90)
			(layer "F.SilkS")
			(hide yes)
			(effects
				(font
					(size 1.27 1.27)
				)
			)
		)
		(property "Value" ""
			(at 0 0 90)
			(layer "F.Fab")
			(effects
				(font
					(size 1.27 1.27)
				)
			)
		)
		(duplicate_pad_numbers_are_jumpers no)
		(fp_line
			(start 0.7874 -0.4064)
			(end 0.7874 0.4064)
			(stroke
				(width 0.1524)
				(type default)
			)
			(layer "F.SilkS")
		)
		(fp_line
			(start -0.7874 -0.4064)
			(end 0.7874 -0.4064)
			(stroke
				(width 0.1524)
				(type default)
			)
			(layer "F.SilkS")
		)
		(fp_line
			(start 0.7874 0.4064)
			(end -0.7874 0.4064)
			(stroke
				(width 0.1524)
				(type default)
			)
			(layer "F.SilkS")
		)
		(fp_line
			(start -0.7874 0.4064)
			(end -0.7874 -0.4064)
			(stroke
				(width 0.1524)
				(type default)
			)
			(layer "F.SilkS")
		)
		(fp_line
			(start -0.12065 -0.305054)
			(end -0.12065 -0.2794)
			(stroke
				(width 0.1)
				(type default)
			)
			(layer "F.Fab")
		)
		(fp_line
			(start -0.67945 -0.305054)
			(end -0.12065 -0.305054)
			(stroke
				(width 0.1)
				(type default)
			)
			(layer "F.Fab")
		)
		(fp_line
			(start 0.67945 -0.3048)
			(end 0.67945 0.3048)
			(stroke
				(width 0.1)
				(type default)
			)
			(layer "F.Fab")
		)
		(fp_line
			(start 0.12065 -0.3048)
			(end 0.67945 -0.3048)
			(stroke
				(width 0.1)
				(type default)
			)
			(layer "F.Fab")
		)
		(fp_line
			(start 0.12065 -0.2794)
			(end 0.12065 -0.3048)
			(stroke
				(width 0.1)
				(type default)
			)
			(layer "F.Fab")
		)
		(fp_line
			(start -0.12065 -0.2794)
			(end 0.12065 -0.2794)
			(stroke
				(width 0.1)
				(type default)
			)
			(layer "F.Fab")
		)
		(fp_line
			(start 0.120396 0.2794)
			(end -0.12065 0.2794)
			(stroke
				(width 0.1)
				(type default)
			)
			(layer "F.Fab")
		)
		(fp_line
			(start -0.12065 0.2794)
			(end -0.12065 0.3048)
			(stroke
				(width 0.1)
				(type default)
			)
			(layer "F.Fab")
		)
		(fp_line
			(start 0.67945 0.3048)
			(end 0.120396 0.3048)
			(stroke
				(width 0.1)
				(type default)
			)
			(layer "F.Fab")
		)
		(fp_line
			(start 0.120396 0.3048)
			(end 0.120396 0.2794)
			(stroke
				(width 0.1)
				(type default)
			)
			(layer "F.Fab")
		)
		(fp_line
			(start -0.12065 0.3048)
			(end -0.67945 0.3048)
			(stroke
				(width 0.1)
				(type default)
			)
			(layer "F.Fab")
		)
		(fp_line
			(start -0.67945 0.3048)
			(end -0.67945 -0.305054)
			(stroke
				(width 0.1)
				(type default)
			)
			(layer "F.Fab")
		)
		(pad "1" smd circle
			(at -0.40005 0 90)
			(size 0 0)
			(layers "F.Cu" "F.Mask" "F.Paste")
			(net "PVCCIN_CPU1")
		)
		(pad "2" smd circle
			(at 0.40005 0 90)
			(size 0 0)
			(layers "F.Cu" "F.Mask" "F.Paste")
			(net "GND")
		)
	)
	(footprint ""
		(layer "F.Cu")
		(at 358.237282 -57.898792)
		(property "Reference" "R748"
			(at 0 0 0)
			(layer "F.SilkS")
			(hide yes)
			(effects
				(font
					(size 1.27 1.27)
				)
			)
		)
		(property "Value" ""
			(at 0 0 0)
			(layer "F.Fab")
			(effects
				(font
					(size 1.27 1.27)
				)
			)
		)
		(duplicate_pad_numbers_are_jumpers no)
		(fp_line
			(start -0.7874 -0.4064)
			(end 0.7874 -0.4064)
			(stroke
				(width 0.1524)
				(type default)
			)
			(layer "F.SilkS")
		)
		(fp_line
			(start -0.7874 0.4064)
			(end -0.7874 -0.4064)
			(stroke
				(width 0.1524)
				(type default)
			)
			(layer "F.SilkS")
		)
		(fp_line
			(start 0.7874 -0.4064)
			(end 0.7874 0.4064)
			(stroke
				(width 0.1524)
				(type default)
			)
			(layer "F.SilkS")
		)
		(fp_line
			(start 0.7874 0.4064)
			(end -0.7874 0.4064)
			(stroke
				(width 0.1524)
				(type default)
			)
			(layer "F.SilkS")
		)
		(fp_line
			(start -0.67945 -0.305054)
			(end -0.12065 -0.305054)
			(stroke
				(width 0.1)
				(type default)
			)
			(layer "F.Fab")
		)
		(fp_line
			(start -0.67945 0.3048)
			(end -0.67945 -0.305054)
			(stroke
				(width 0.1)
				(type default)
			)
			(layer "F.Fab")
		)
		(fp_line
			(start -0.12065 -0.305054)
			(end -0.12065 -0.2794)
			(stroke
				(width 0.1)
				(type default)
			)
			(layer "F.Fab")
		)
		(fp_line
			(start -0.12065 -0.2794)
			(end 0.12065 -0.2794)
			(stroke
				(width 0.1)
				(type default)
			)
			(layer "F.Fab")
		)
		(fp_line
			(start -0.12065 0.2794)
			(end -0.12065 0.3048)
			(stroke
				(width 0.1)
				(type default)
			)
			(layer "F.Fab")
		)
		(fp_line
			(start -0.12065 0.3048)
			(end -0.67945 0.3048)
			(stroke
				(width 0.1)
				(type default)
			)
			(layer "F.Fab")
		)
		(fp_line
			(start 0.120396 0.2794)
			(end -0.12065 0.2794)
			(stroke
				(width 0.1)
				(type default)
			)
			(layer "F.Fab")
		)
		(fp_line
			(start 0.120396 0.3048)
			(end 0.120396 0.2794)
			(stroke
				(width 0.1)
				(type default)
			)
			(layer "F.Fab")
		)
		(fp_line
			(start 0.12065 -0.3048)
			(end 0.67945 -0.3048)
			(stroke
				(width 0.1)
				(type default)
			)
			(layer "F.Fab")
		)
		(fp_line
			(start 0.12065 -0.2794)
			(end 0.12065 -0.3048)
			(stroke
				(width 0.1)
				(type default)
			)
			(layer "F.Fab")
		)
		(fp_line
			(start 0.67945 -0.3048)
			(end 0.67945 0.3048)
			(stroke
				(width 0.1)
				(type default)
			)
			(layer "F.Fab")
		)
		(fp_line
			(start 0.67945 0.3048)
			(end 0.120396 0.3048)
			(stroke
				(width 0.1)
				(type default)
			)
			(layer "F.Fab")
		)
		(pad "1" smd circle
			(at -0.40005 0)
			(size 0 0)
			(layers "F.Cu" "F.Mask" "F.Paste")
			(net "P1V05_PCH_AUX")
		)
		(pad "2" smd circle
			(at 0.40005 0)
			(size 0 0)
			(layers "F.Cu" "F.Mask" "F.Paste")
			(net "JTAG_DBP_TDI_PCH")
		)
	)
	(footprint ""
		(layer "F.Cu")
		(at 406.43937 -408.517344 -90)
		(property "Reference" "C892"
			(at 0 0 270)
			(layer "F.SilkS")
			(hide yes)
			(effects
				(font
					(size 1.27 1.27)
				)
			)
		)
		(property "Value" ""
			(at 0 0 270)
			(layer "F.Fab")
			(effects
				(font
					(size 1.27 1.27)
				)
			)
		)
		(duplicate_pad_numbers_are_jumpers no)
		(fp_line
			(start -0.299974 0.150114)
			(end -0.299974 -0.150114)
			(stroke
				(width 0.1)
				(type default)
			)
			(layer "F.Fab")
		)
		(fp_line
			(start 0.299974 0.150114)
			(end -0.299974 0.150114)
			(stroke
				(width 0.1)
				(type default)
			)
			(layer "F.Fab")
		)
		(fp_line
			(start -0.299974 -0.150114)
			(end 0.299974 -0.150114)
			(stroke
				(width 0.1)
				(type default)
			)
			(layer "F.Fab")
		)
		(fp_line
			(start 0.299974 -0.150114)
			(end 0.299974 0.150114)
			(stroke
				(width 0.1)
				(type default)
			)
			(layer "F.Fab")
		)
		(pad "1" smd rect
			(at -0.2667 0 270)
			(size 0.3048 0.381)
			(layers "F.Cu" "F.Mask" "F.Paste")
			(net "P5E_CPU0_PE3_TX_C_DN<4>")
		)
		(pad "2" smd rect
			(at 0.2667 0 270)
			(size 0.3048 0.381)
			(layers "F.Cu" "F.Mask" "F.Paste")
			(net "P5E_CPU0_PE3_TX_DN<4>")
		)
	)
	(footprint ""
		(layer "F.Cu")
		(at 28.578048 -69.7992)
		(property "Reference" "R4753"
			(at 0 0 0)
			(layer "F.SilkS")
			(hide yes)
			(effects
				(font
					(size 1.27 1.27)
				)
			)
		)
		(property "Value" ""
			(at 0 0 0)
			(layer "F.Fab")
			(effects
				(font
					(size 1.27 1.27)
				)
			)
		)
		(duplicate_pad_numbers_are_jumpers no)
		(fp_line
			(start -0.7874 -0.4064)
			(end 0.7874 -0.4064)
			(stroke
				(width 0.1524)
				(type default)
			)
			(layer "F.SilkS")
		)
		(fp_line
			(start -0.7874 0.4064)
			(end -0.7874 -0.4064)
			(stroke
				(width 0.1524)
				(type default)
			)
			(layer "F.SilkS")
		)
		(fp_line
			(start 0.7874 -0.4064)
			(end 0.7874 0.4064)
			(stroke
				(width 0.1524)
				(type default)
			)
			(layer "F.SilkS")
		)
		(fp_line
			(start 0.7874 0.4064)
			(end -0.7874 0.4064)
			(stroke
				(width 0.1524)
				(type default)
			)
			(layer "F.SilkS")
		)
		(fp_line
			(start -0.67945 -0.305054)
			(end -0.12065 -0.305054)
			(stroke
				(width 0.1)
				(type default)
			)
			(layer "F.Fab")
		)
		(fp_line
			(start -0.67945 0.3048)
			(end -0.67945 -0.305054)
			(stroke
				(width 0.1)
				(type default)
			)
			(layer "F.Fab")
		)
		(fp_line
			(start -0.12065 -0.305054)
			(end -0.12065 -0.2794)
			(stroke
				(width 0.1)
				(type default)
			)
			(layer "F.Fab")
		)
		(fp_line
			(start -0.12065 -0.2794)
			(end 0.12065 -0.2794)
			(stroke
				(width 0.1)
				(type default)
			)
			(layer "F.Fab")
		)
		(fp_line
			(start -0.12065 0.2794)
			(end -0.12065 0.3048)
			(stroke
				(width 0.1)
				(type default)
			)
			(layer "F.Fab")
		)
		(fp_line
			(start -0.12065 0.3048)
			(end -0.67945 0.3048)
			(stroke
				(width 0.1)
				(type default)
			)
			(layer "F.Fab")
		)
		(fp_line
			(start 0.120396 0.2794)
			(end -0.12065 0.2794)
			(stroke
				(width 0.1)
				(type default)
			)
			(layer "F.Fab")
		)
		(fp_line
			(start 0.120396 0.3048)
			(end 0.120396 0.2794)
			(stroke
				(width 0.1)
				(type default)
			)
			(layer "F.Fab")
		)
		(fp_line
			(start 0.12065 -0.3048)
			(end 0.67945 -0.3048)
			(stroke
				(width 0.1)
				(type default)
			)
			(layer "F.Fab")
		)
		(fp_line
			(start 0.12065 -0.2794)
			(end 0.12065 -0.3048)
			(stroke
				(width 0.1)
				(type default)
			)
			(layer "F.Fab")
		)
		(fp_line
			(start 0.67945 -0.3048)
			(end 0.67945 0.3048)
			(stroke
				(width 0.1)
				(type default)
			)
			(layer "F.Fab")
		)
		(fp_line
			(start 0.67945 0.3048)
			(end 0.120396 0.3048)
			(stroke
				(width 0.1)
				(type default)
			)
			(layer "F.Fab")
		)
		(pad "1" smd circle
			(at -0.40005 0)
			(size 0 0)
			(layers "F.Cu" "F.Mask" "F.Paste")
			(net "HP_LVC3_OCP_V3_2_PRSNT2_N_R")
		)
		(pad "2" smd circle
			(at 0.40005 0)
			(size 0 0)
			(layers "F.Cu" "F.Mask" "F.Paste")
			(net "HP_LVC3_OCP_V3_2_PRSNT2_PLD_N")
		)
	)
	(footprint ""
		(layer "F.Cu")
		(at 142.486126 -343.018872 -90)
		(property "Reference" "PC483_P1_8"
			(at 0 0 270)
			(layer "F.SilkS")
			(hide yes)
			(effects
				(font
					(size 1.27 1.27)
				)
			)
		)
		(property "Value" ""
			(at 0 0 270)
			(layer "F.Fab")
			(effects
				(font
					(size 1.27 1.27)
				)
			)
		)
		(duplicate_pad_numbers_are_jumpers no)
		(fp_line
			(start -0.7874 0.4064)
			(end -0.7874 -0.4064)
			(stroke
				(width 0.1524)
				(type default)
			)
			(layer "F.SilkS")
		)
		(fp_line
			(start 0.7874 0.4064)
			(end -0.7874 0.4064)
			(stroke
				(width 0.1524)
				(type default)
			)
			(layer "F.SilkS")
		)
		(fp_line
			(start -0.7874 -0.4064)
			(end 0.7874 -0.4064)
			(stroke
				(width 0.1524)
				(type default)
			)
			(layer "F.SilkS")
		)
		(fp_line
			(start 0.7874 -0.4064)
			(end 0.7874 0.4064)
			(stroke
				(width 0.1524)
				(type default)
			)
			(layer "F.SilkS")
		)
		(fp_line
			(start -0.67945 0.3048)
			(end -0.67945 -0.305054)
			(stroke
				(width 0.1)
				(type default)
			)
			(layer "F.Fab")
		)
		(fp_line
			(start -0.12065 0.3048)
			(end -0.67945 0.3048)
			(stroke
				(width 0.1)
				(type default)
			)
			(layer "F.Fab")
		)
		(fp_line
			(start 0.120396 0.3048)
			(end 0.120396 0.2794)
			(stroke
				(width 0.1)
				(type default)
			)
			(layer "F.Fab")
		)
		(fp_line
			(start 0.67945 0.3048)
			(end 0.120396 0.3048)
			(stroke
				(width 0.1)
				(type default)
			)
			(layer "F.Fab")
		)
		(fp_line
			(start -0.12065 0.2794)
			(end -0.12065 0.3048)
			(stroke
				(width 0.1)
				(type default)
			)
			(layer "F.Fab")
		)
		(fp_line
			(start 0.120396 0.2794)
			(end -0.12065 0.2794)
			(stroke
				(width 0.1)
				(type default)
			)
			(layer "F.Fab")
		)
		(fp_line
			(start -0.12065 -0.2794)
			(end 0.12065 -0.2794)
			(stroke
				(width 0.1)
				(type default)
			)
			(layer "F.Fab")
		)
		(fp_line
			(start 0.12065 -0.2794)
			(end 0.12065 -0.3048)
			(stroke
				(width 0.1)
				(type default)
			)
			(layer "F.Fab")
		)
		(fp_line
			(start 0.12065 -0.3048)
			(end 0.67945 -0.3048)
			(stroke
				(width 0.1)
				(type default)
			)
			(layer "F.Fab")
		)
		(fp_line
			(start 0.67945 -0.3048)
			(end 0.67945 0.3048)
			(stroke
				(width 0.1)
				(type default)
			)
			(layer "F.Fab")
		)
		(fp_line
			(start -0.67945 -0.305054)
			(end -0.12065 -0.305054)
			(stroke
				(width 0.1)
				(type default)
			)
			(layer "F.Fab")
		)
		(fp_line
			(start -0.12065 -0.305054)
			(end -0.12065 -0.2794)
			(stroke
				(width 0.1)
				(type default)
			)
			(layer "F.Fab")
		)
		(pad "1" smd circle
			(at -0.40005 0 270)
			(size 0 0)
			(layers "F.Cu" "F.Mask" "F.Paste")
			(net "SW_P12V_PVCCIN_CPU1_FLT")
		)
		(pad "2" smd circle
			(at 0.40005 0 270)
			(size 0 0)
			(layers "F.Cu" "F.Mask" "F.Paste")
			(net "GND")
		)
	)
	(footprint ""
		(layer "F.Cu")
		(at 86.868 -65.173098 -90)
		(property "Reference" "R1044"
			(at 0 0 270)
			(layer "F.SilkS")
			(hide yes)
			(effects
				(font
					(size 1.27 1.27)
				)
			)
		)
		(property "Value" ""
			(at 0 0 270)
			(layer "F.Fab")
			(effects
				(font
					(size 1.27 1.27)
				)
			)
		)
		(duplicate_pad_numbers_are_jumpers no)
		(fp_line
			(start -0.7874 0.4064)
			(end -0.7874 -0.4064)
			(stroke
				(width 0.1524)
				(type default)
			)
			(layer "F.SilkS")
		)
		(fp_line
			(start 0.7874 0.4064)
			(end -0.7874 0.4064)
			(stroke
				(width 0.1524)
				(type default)
			)
			(layer "F.SilkS")
		)
		(fp_line
			(start -0.7874 -0.4064)
			(end 0.7874 -0.4064)
			(stroke
				(width 0.1524)
				(type default)
			)
			(layer "F.SilkS")
		)
		(fp_line
			(start 0.7874 -0.4064)
			(end 0.7874 0.4064)
			(stroke
				(width 0.1524)
				(type default)
			)
			(layer "F.SilkS")
		)
		(fp_line
			(start -0.67945 0.3048)
			(end -0.67945 -0.305054)
			(stroke
				(width 0.1)
				(type default)
			)
			(layer "F.Fab")
		)
		(fp_line
			(start -0.12065 0.3048)
			(end -0.67945 0.3048)
			(stroke
				(width 0.1)
				(type default)
			)
			(layer "F.Fab")
		)
		(fp_line
			(start 0.120396 0.3048)
			(end 0.120396 0.2794)
			(stroke
				(width 0.1)
				(type default)
			)
			(layer "F.Fab")
		)
		(fp_line
			(start 0.67945 0.3048)
			(end 0.120396 0.3048)
			(stroke
				(width 0.1)
				(type default)
			)
			(layer "F.Fab")
		)
		(fp_line
			(start -0.12065 0.2794)
			(end -0.12065 0.3048)
			(stroke
				(width 0.1)
				(type default)
			)
			(layer "F.Fab")
		)
		(fp_line
			(start 0.120396 0.2794)
			(end -0.12065 0.2794)
			(stroke
				(width 0.1)
				(type default)
			)
			(layer "F.Fab")
		)
		(fp_line
			(start -0.12065 -0.2794)
			(end 0.12065 -0.2794)
			(stroke
				(width 0.1)
				(type default)
			)
			(layer "F.Fab")
		)
		(fp_line
			(start 0.12065 -0.2794)
			(end 0.12065 -0.3048)
			(stroke
				(width 0.1)
				(type default)
			)
			(layer "F.Fab")
		)
		(fp_line
			(start 0.12065 -0.3048)
			(end 0.67945 -0.3048)
			(stroke
				(width 0.1)
				(type default)
			)
			(layer "F.Fab")
		)
		(fp_line
			(start 0.67945 -0.3048)
			(end 0.67945 0.3048)
			(stroke
				(width 0.1)
				(type default)
			)
			(layer "F.Fab")
		)
		(fp_line
			(start -0.67945 -0.305054)
			(end -0.12065 -0.305054)
			(stroke
				(width 0.1)
				(type default)
			)
			(layer "F.Fab")
		)
		(fp_line
			(start -0.12065 -0.305054)
			(end -0.12065 -0.2794)
			(stroke
				(width 0.1)
				(type default)
			)
			(layer "F.Fab")
		)
		(pad "1" smd circle
			(at -0.40005 0 270)
			(size 0 0)
			(layers "F.Cu" "F.Mask" "F.Paste")
			(net "LED_PWRGD_CPUPWRGD_GTL")
		)
		(pad "2" smd circle
			(at 0.40005 0 270)
			(size 0 0)
			(layers "F.Cu" "F.Mask" "F.Paste")
			(net "P3V3_AUX")
		)
	)
	(footprint ""
		(layer "F.Cu")
		(at 7.42188 -59.019948 180)
		(property "Reference" "R582"
			(at 0 0 180)
			(layer "F.SilkS")
			(hide yes)
			(effects
				(font
					(size 1.27 1.27)
				)
			)
		)
		(property "Value" ""
			(at 0 0 180)
			(layer "F.Fab")
			(effects
				(font
					(size 1.27 1.27)
				)
			)
		)
		(duplicate_pad_numbers_are_jumpers no)
		(fp_line
			(start 0.7874 0.4064)
			(end -0.7874 0.4064)
			(stroke
				(width 0.1524)
				(type default)
			)
			(layer "F.SilkS")
		)
		(fp_line
			(start 0.7874 -0.4064)
			(end 0.7874 0.4064)
			(stroke
				(width 0.1524)
				(type default)
			)
			(layer "F.SilkS")
		)
		(fp_line
			(start -0.7874 0.4064)
			(end -0.7874 -0.4064)
			(stroke
				(width 0.1524)
				(type default)
			)
			(layer "F.SilkS")
		)
		(fp_line
			(start -0.7874 -0.4064)
			(end 0.7874 -0.4064)
			(stroke
				(width 0.1524)
				(type default)
			)
			(layer "F.SilkS")
		)
		(fp_line
			(start 0.67945 0.3048)
			(end 0.120396 0.3048)
			(stroke
				(width 0.1)
				(type default)
			)
			(layer "F.Fab")
		)
		(fp_line
			(start 0.67945 -0.3048)
			(end 0.67945 0.3048)
			(stroke
				(width 0.1)
				(type default)
			)
			(layer "F.Fab")
		)
		(fp_line
			(start 0.12065 -0.2794)
			(end 0.12065 -0.3048)
			(stroke
				(width 0.1)
				(type default)
			)
			(layer "F.Fab")
		)
		(fp_line
			(start 0.12065 -0.3048)
			(end 0.67945 -0.3048)
			(stroke
				(width 0.1)
				(type default)
			)
			(layer "F.Fab")
		)
		(fp_line
			(start 0.120396 0.3048)
			(end 0.120396 0.2794)
			(stroke
				(width 0.1)
				(type default)
			)
			(layer "F.Fab")
		)
		(fp_line
			(start 0.120396 0.2794)
			(end -0.12065 0.2794)
			(stroke
				(width 0.1)
				(type default)
			)
			(layer "F.Fab")
		)
		(fp_line
			(start -0.12065 0.3048)
			(end -0.67945 0.3048)
			(stroke
				(width 0.1)
				(type default)
			)
			(layer "F.Fab")
		)
		(fp_line
			(start -0.12065 0.2794)
			(end -0.12065 0.3048)
			(stroke
				(width 0.1)
				(type default)
			)
			(layer "F.Fab")
		)
		(fp_line
			(start -0.12065 -0.2794)
			(end 0.12065 -0.2794)
			(stroke
				(width 0.1)
				(type default)
			)
			(layer "F.Fab")
		)
		(fp_line
			(start -0.12065 -0.305054)
			(end -0.12065 -0.2794)
			(stroke
				(width 0.1)
				(type default)
			)
			(layer "F.Fab")
		)
		(fp_line
			(start -0.67945 0.3048)
			(end -0.67945 -0.305054)
			(stroke
				(width 0.1)
				(type default)
			)
			(layer "F.Fab")
		)
		(fp_line
			(start -0.67945 -0.305054)
			(end -0.12065 -0.305054)
			(stroke
				(width 0.1)
				(type default)
			)
			(layer "F.Fab")
		)
		(pad "1" smd circle
			(at -0.40005 0 180)
			(size 0 0)
			(layers "F.Cu" "F.Mask" "F.Paste")
			(net "SMB_SML0_3V3AUX_SDA")
		)
		(pad "2" smd circle
			(at 0.40005 0 180)
			(size 0 0)
			(layers "F.Cu" "F.Mask" "F.Paste")
			(net "SMB_SML0_3V3AUX_PCH_SDA")
		)
	)
	(footprint ""
		(layer "F.Cu")
		(at 162.622484 -53.267864 90)
		(property "Reference" "R3634"
			(at 0 0 90)
			(layer "F.SilkS")
			(hide yes)
			(effects
				(font
					(size 1.27 1.27)
				)
			)
		)
		(property "Value" ""
			(at 0 0 90)
			(layer "F.Fab")
			(effects
				(font
					(size 1.27 1.27)
				)
			)
		)
		(duplicate_pad_numbers_are_jumpers no)
		(fp_line
			(start 4.0386 -1.7526)
			(end 4.0386 1.7526)
			(stroke
				(width 0.1524)
				(type default)
			)
			(layer "F.SilkS")
		)
		(fp_line
			(start -4.0386 -1.7526)
			(end 4.0386 -1.7526)
			(stroke
				(width 0.1524)
				(type default)
			)
			(layer "F.SilkS")
		)
		(fp_line
			(start 4.0386 1.7526)
			(end -4.0386 1.7526)
			(stroke
				(width 0.1524)
				(type default)
			)
			(layer "F.SilkS")
		)
		(fp_line
			(start -4.0386 1.7526)
			(end -4.0386 -1.7526)
			(stroke
				(width 0.1524)
				(type default)
			)
			(layer "F.SilkS")
		)
		(fp_line
			(start 4.0386 -1.7526)
			(end 4.0386 1.7526)
			(stroke
				(width 0.1)
				(type default)
			)
			(layer "F.Fab")
		)
		(fp_line
			(start -4.0386 -1.7526)
			(end 4.0386 -1.7526)
			(stroke
				(width 0.1)
				(type default)
			)
			(layer "F.Fab")
		)
		(fp_line
			(start 4.0386 1.7526)
			(end -4.0386 1.7526)
			(stroke
				(width 0.1)
				(type default)
			)
			(layer "F.Fab")
		)
		(fp_line
			(start -4.0386 1.7526)
			(end -4.0386 -1.7526)
			(stroke
				(width 0.1)
				(type default)
			)
			(layer "F.Fab")
		)
		(pad "1" smd rect
			(at -3.1115 0 90)
			(size 1.524 3.2004)
			(layers "F.Cu" "F.Mask" "F.Paste")
			(net "P3V3_M2_0")
		)
		(pad "2" smd rect
			(at 3.1115 0 90)
			(size 1.524 3.2004)
			(layers "F.Cu" "F.Mask" "F.Paste")
			(net "P3V3")
		)
	)
	(footprint ""
		(layer "F.Cu")
		(at 300.728634 -16.715994)
		(property "Reference" "R4205"
			(at 0 0 0)
			(layer "F.SilkS")
			(hide yes)
			(effects
				(font
					(size 1.27 1.27)
				)
			)
		)
		(property "Value" ""
			(at 0 0 0)
			(layer "F.Fab")
			(effects
				(font
					(size 1.27 1.27)
				)
			)
		)
		(duplicate_pad_numbers_are_jumpers no)
		(fp_line
			(start -0.7874 -0.4064)
			(end 0.7874 -0.4064)
			(stroke
				(width 0.1524)
				(type default)
			)
			(layer "F.SilkS")
		)
		(fp_line
			(start -0.7874 0.4064)
			(end -0.7874 -0.4064)
			(stroke
				(width 0.1524)
				(type default)
			)
			(layer "F.SilkS")
		)
		(fp_line
			(start 0.7874 -0.4064)
			(end 0.7874 0.4064)
			(stroke
				(width 0.1524)
				(type default)
			)
			(layer "F.SilkS")
		)
		(fp_line
			(start 0.7874 0.4064)
			(end -0.7874 0.4064)
			(stroke
				(width 0.1524)
				(type default)
			)
			(layer "F.SilkS")
		)
		(fp_line
			(start -0.67945 -0.305054)
			(end -0.12065 -0.305054)
			(stroke
				(width 0.1)
				(type default)
			)
			(layer "F.Fab")
		)
		(fp_line
			(start -0.67945 0.3048)
			(end -0.67945 -0.305054)
			(stroke
				(width 0.1)
				(type default)
			)
			(layer "F.Fab")
		)
		(fp_line
			(start -0.12065 -0.305054)
			(end -0.12065 -0.2794)
			(stroke
				(width 0.1)
				(type default)
			)
			(layer "F.Fab")
		)
		(fp_line
			(start -0.12065 -0.2794)
			(end 0.12065 -0.2794)
			(stroke
				(width 0.1)
				(type default)
			)
			(layer "F.Fab")
		)
		(fp_line
			(start -0.12065 0.2794)
			(end -0.12065 0.3048)
			(stroke
				(width 0.1)
				(type default)
			)
			(layer "F.Fab")
		)
		(fp_line
			(start -0.12065 0.3048)
			(end -0.67945 0.3048)
			(stroke
				(width 0.1)
				(type default)
			)
			(layer "F.Fab")
		)
		(fp_line
			(start 0.120396 0.2794)
			(end -0.12065 0.2794)
			(stroke
				(width 0.1)
				(type default)
			)
			(layer "F.Fab")
		)
		(fp_line
			(start 0.120396 0.3048)
			(end 0.120396 0.2794)
			(stroke
				(width 0.1)
				(type default)
			)
			(layer "F.Fab")
		)
		(fp_line
			(start 0.12065 -0.3048)
			(end 0.67945 -0.3048)
			(stroke
				(width 0.1)
				(type default)
			)
			(layer "F.Fab")
		)
		(fp_line
			(start 0.12065 -0.2794)
			(end 0.12065 -0.3048)
			(stroke
				(width 0.1)
				(type default)
			)
			(layer "F.Fab")
		)
		(fp_line
			(start 0.67945 -0.3048)
			(end 0.67945 0.3048)
			(stroke
				(width 0.1)
				(type default)
			)
			(layer "F.Fab")
		)
		(fp_line
			(start 0.67945 0.3048)
			(end 0.120396 0.3048)
			(stroke
				(width 0.1)
				(type default)
			)
			(layer "F.Fab")
		)
		(pad "1" smd circle
			(at -0.40005 0)
			(size 0 0)
			(layers "F.Cu" "F.Mask" "F.Paste")
			(net "U271_1_ADD0")
		)
		(pad "2" smd circle
			(at 0.40005 0)
			(size 0 0)
			(layers "F.Cu" "F.Mask" "F.Paste")
			(net "GND")
		)
	)
	(footprint ""
		(layer "F.Cu")
		(at 160.760918 -22.361906 180)
		(property "Reference" "R4152"
			(at 0 0 180)
			(layer "F.SilkS")
			(hide yes)
			(effects
				(font
					(size 1.27 1.27)
				)
			)
		)
		(property "Value" ""
			(at 0 0 180)
			(layer "F.Fab")
			(effects
				(font
					(size 1.27 1.27)
				)
			)
		)
		(duplicate_pad_numbers_are_jumpers no)
		(fp_line
			(start 0.7874 0.4064)
			(end -0.7874 0.4064)
			(stroke
				(width 0.1524)
				(type default)
			)
			(layer "F.SilkS")
		)
		(fp_line
			(start 0.7874 -0.4064)
			(end 0.7874 0.4064)
			(stroke
				(width 0.1524)
				(type default)
			)
			(layer "F.SilkS")
		)
		(fp_line
			(start -0.7874 0.4064)
			(end -0.7874 -0.4064)
			(stroke
				(width 0.1524)
				(type default)
			)
			(layer "F.SilkS")
		)
		(fp_line
			(start -0.7874 -0.4064)
			(end 0.7874 -0.4064)
			(stroke
				(width 0.1524)
				(type default)
			)
			(layer "F.SilkS")
		)
		(fp_line
			(start 0.67945 0.3048)
			(end 0.120396 0.3048)
			(stroke
				(width 0.1)
				(type default)
			)
			(layer "F.Fab")
		)
		(fp_line
			(start 0.67945 -0.3048)
			(end 0.67945 0.3048)
			(stroke
				(width 0.1)
				(type default)
			)
			(layer "F.Fab")
		)
		(fp_line
			(start 0.12065 -0.2794)
			(end 0.12065 -0.3048)
			(stroke
				(width 0.1)
				(type default)
			)
			(layer "F.Fab")
		)
		(fp_line
			(start 0.12065 -0.3048)
			(end 0.67945 -0.3048)
			(stroke
				(width 0.1)
				(type default)
			)
			(layer "F.Fab")
		)
		(fp_line
			(start 0.120396 0.3048)
			(end 0.120396 0.2794)
			(stroke
				(width 0.1)
				(type default)
			)
			(layer "F.Fab")
		)
		(fp_line
			(start 0.120396 0.2794)
			(end -0.12065 0.2794)
			(stroke
				(width 0.1)
				(type default)
			)
			(layer "F.Fab")
		)
		(fp_line
			(start -0.12065 0.3048)
			(end -0.67945 0.3048)
			(stroke
				(width 0.1)
				(type default)
			)
			(layer "F.Fab")
		)
		(fp_line
			(start -0.12065 0.2794)
			(end -0.12065 0.3048)
			(stroke
				(width 0.1)
				(type default)
			)
			(layer "F.Fab")
		)
		(fp_line
			(start -0.12065 -0.2794)
			(end 0.12065 -0.2794)
			(stroke
				(width 0.1)
				(type default)
			)
			(layer "F.Fab")
		)
		(fp_line
			(start -0.12065 -0.305054)
			(end -0.12065 -0.2794)
			(stroke
				(width 0.1)
				(type default)
			)
			(layer "F.Fab")
		)
		(fp_line
			(start -0.67945 0.3048)
			(end -0.67945 -0.305054)
			(stroke
				(width 0.1)
				(type default)
			)
			(layer "F.Fab")
		)
		(fp_line
			(start -0.67945 -0.305054)
			(end -0.12065 -0.305054)
			(stroke
				(width 0.1)
				(type default)
			)
			(layer "F.Fab")
		)
		(pad "1" smd circle
			(at -0.40005 0 180)
			(size 0 0)
			(layers "F.Cu" "F.Mask" "F.Paste")
			(net "SMB_1_PLD_3V3AUX_SDA")
		)
		(pad "2" smd circle
			(at 0.40005 0 180)
			(size 0 0)
			(layers "F.Cu" "F.Mask" "F.Paste")
			(net "SMB_2_PLD_3V3AUX_SDA_R1")
		)
	)
	(footprint ""
		(layer "F.Cu")
		(at 386.499354 -347.520514 90)
		(property "Reference" "PR1772"
			(at 0 0 90)
			(layer "F.SilkS")
			(hide yes)
			(effects
				(font
					(size 1.27 1.27)
				)
			)
		)
		(property "Value" ""
			(at 0 0 90)
			(layer "F.Fab")
			(effects
				(font
					(size 1.27 1.27)
				)
			)
		)
		(duplicate_pad_numbers_are_jumpers no)
		(fp_line
			(start 0.7874 -0.4064)
			(end 0.7874 0.4064)
			(stroke
				(width 0.1524)
				(type default)
			)
			(layer "F.SilkS")
		)
		(fp_line
			(start -0.7874 -0.4064)
			(end 0.7874 -0.4064)
			(stroke
				(width 0.1524)
				(type default)
			)
			(layer "F.SilkS")
		)
		(fp_line
			(start 0.7874 0.4064)
			(end -0.7874 0.4064)
			(stroke
				(width 0.1524)
				(type default)
			)
			(layer "F.SilkS")
		)
		(fp_line
			(start -0.7874 0.4064)
			(end -0.7874 -0.4064)
			(stroke
				(width 0.1524)
				(type default)
			)
			(layer "F.SilkS")
		)
		(fp_line
			(start -0.12065 -0.305054)
			(end -0.12065 -0.2794)
			(stroke
				(width 0.1)
				(type default)
			)
			(layer "F.Fab")
		)
		(fp_line
			(start -0.67945 -0.305054)
			(end -0.12065 -0.305054)
			(stroke
				(width 0.1)
				(type default)
			)
			(layer "F.Fab")
		)
		(fp_line
			(start 0.67945 -0.3048)
			(end 0.67945 0.3048)
			(stroke
				(width 0.1)
				(type default)
			)
			(layer "F.Fab")
		)
		(fp_line
			(start 0.12065 -0.3048)
			(end 0.67945 -0.3048)
			(stroke
				(width 0.1)
				(type default)
			)
			(layer "F.Fab")
		)
		(fp_line
			(start 0.12065 -0.2794)
			(end 0.12065 -0.3048)
			(stroke
				(width 0.1)
				(type default)
			)
			(layer "F.Fab")
		)
		(fp_line
			(start -0.12065 -0.2794)
			(end 0.12065 -0.2794)
			(stroke
				(width 0.1)
				(type default)
			)
			(layer "F.Fab")
		)
		(fp_line
			(start 0.120396 0.2794)
			(end -0.12065 0.2794)
			(stroke
				(width 0.1)
				(type default)
			)
			(layer "F.Fab")
		)
		(fp_line
			(start -0.12065 0.2794)
			(end -0.12065 0.3048)
			(stroke
				(width 0.1)
				(type default)
			)
			(layer "F.Fab")
		)
		(fp_line
			(start 0.67945 0.3048)
			(end 0.120396 0.3048)
			(stroke
				(width 0.1)
				(type default)
			)
			(layer "F.Fab")
		)
		(fp_line
			(start 0.120396 0.3048)
			(end 0.120396 0.2794)
			(stroke
				(width 0.1)
				(type default)
			)
			(layer "F.Fab")
		)
		(fp_line
			(start -0.12065 0.3048)
			(end -0.67945 0.3048)
			(stroke
				(width 0.1)
				(type default)
			)
			(layer "F.Fab")
		)
		(fp_line
			(start -0.67945 0.3048)
			(end -0.67945 -0.305054)
			(stroke
				(width 0.1)
				(type default)
			)
			(layer "F.Fab")
		)
		(pad "1" smd circle
			(at -0.40005 0 90)
			(size 0 0)
			(layers "F.Cu" "F.Mask" "F.Paste")
			(net "SW_PVCCIN_CPU0_BOOT8")
		)
		(pad "2" smd circle
			(at 0.40005 0 90)
			(size 0 0)
			(layers "F.Cu" "F.Mask" "F.Paste")
			(net "SW_PVCCIN_CPU0_BOOT8_R")
		)
	)
	(footprint ""
		(layer "F.Cu")
		(at 409.573984 -17.612614 90)
		(property "Reference" "C852"
			(at 0 0 90)
			(layer "F.SilkS")
			(hide yes)
			(effects
				(font
					(size 1.27 1.27)
				)
			)
		)
		(property "Value" ""
			(at 0 0 90)
			(layer "F.Fab")
			(effects
				(font
					(size 1.27 1.27)
				)
			)
		)
		(duplicate_pad_numbers_are_jumpers no)
		(fp_line
			(start 0.299974 -0.150114)
			(end 0.299974 0.150114)
			(stroke
				(width 0.1)
				(type default)
			)
			(layer "F.Fab")
		)
		(fp_line
			(start -0.299974 -0.150114)
			(end 0.299974 -0.150114)
			(stroke
				(width 0.1)
				(type default)
			)
			(layer "F.Fab")
		)
		(fp_line
			(start 0.299974 0.150114)
			(end -0.299974 0.150114)
			(stroke
				(width 0.1)
				(type default)
			)
			(layer "F.Fab")
		)
		(fp_line
			(start -0.299974 0.150114)
			(end -0.299974 -0.150114)
			(stroke
				(width 0.1)
				(type default)
			)
			(layer "F.Fab")
		)
		(pad "1" smd rect
			(at -0.2667 0 90)
			(size 0.3048 0.381)
			(layers "F.Cu" "F.Mask" "F.Paste")
			(net "P5E_CPU0_PE1_TX_C_DN<8>")
		)
		(pad "2" smd rect
			(at 0.2667 0 90)
			(size 0.3048 0.381)
			(layers "F.Cu" "F.Mask" "F.Paste")
			(net "P5E_CPU0_PE1_TX_DN<8>")
		)
	)
	(footprint ""
		(layer "F.Cu")
		(at 96.57588 -53.050948 180)
		(property "Reference" "R1348"
			(at 0 0 180)
			(layer "F.SilkS")
			(hide yes)
			(effects
				(font
					(size 1.27 1.27)
				)
			)
		)
		(property "Value" ""
			(at 0 0 180)
			(layer "F.Fab")
			(effects
				(font
					(size 1.27 1.27)
				)
			)
		)
		(duplicate_pad_numbers_are_jumpers no)
		(fp_line
			(start 0.7874 0.4064)
			(end -0.7874 0.4064)
			(stroke
				(width 0.1524)
				(type default)
			)
			(layer "F.SilkS")
		)
		(fp_line
			(start 0.7874 -0.4064)
			(end 0.7874 0.4064)
			(stroke
				(width 0.1524)
				(type default)
			)
			(layer "F.SilkS")
		)
		(fp_line
			(start -0.7874 0.4064)
			(end -0.7874 -0.4064)
			(stroke
				(width 0.1524)
				(type default)
			)
			(layer "F.SilkS")
		)
		(fp_line
			(start -0.7874 -0.4064)
			(end 0.7874 -0.4064)
			(stroke
				(width 0.1524)
				(type default)
			)
			(layer "F.SilkS")
		)
		(fp_line
			(start 0.67945 0.3048)
			(end 0.120396 0.3048)
			(stroke
				(width 0.1)
				(type default)
			)
			(layer "F.Fab")
		)
		(fp_line
			(start 0.67945 -0.3048)
			(end 0.67945 0.3048)
			(stroke
				(width 0.1)
				(type default)
			)
			(layer "F.Fab")
		)
		(fp_line
			(start 0.12065 -0.2794)
			(end 0.12065 -0.3048)
			(stroke
				(width 0.1)
				(type default)
			)
			(layer "F.Fab")
		)
		(fp_line
			(start 0.12065 -0.3048)
			(end 0.67945 -0.3048)
			(stroke
				(width 0.1)
				(type default)
			)
			(layer "F.Fab")
		)
		(fp_line
			(start 0.120396 0.3048)
			(end 0.120396 0.2794)
			(stroke
				(width 0.1)
				(type default)
			)
			(layer "F.Fab")
		)
		(fp_line
			(start 0.120396 0.2794)
			(end -0.12065 0.2794)
			(stroke
				(width 0.1)
				(type default)
			)
			(layer "F.Fab")
		)
		(fp_line
			(start -0.12065 0.3048)
			(end -0.67945 0.3048)
			(stroke
				(width 0.1)
				(type default)
			)
			(layer "F.Fab")
		)
		(fp_line
			(start -0.12065 0.2794)
			(end -0.12065 0.3048)
			(stroke
				(width 0.1)
				(type default)
			)
			(layer "F.Fab")
		)
		(fp_line
			(start -0.12065 -0.2794)
			(end 0.12065 -0.2794)
			(stroke
				(width 0.1)
				(type default)
			)
			(layer "F.Fab")
		)
		(fp_line
			(start -0.12065 -0.305054)
			(end -0.12065 -0.2794)
			(stroke
				(width 0.1)
				(type default)
			)
			(layer "F.Fab")
		)
		(fp_line
			(start -0.67945 0.3048)
			(end -0.67945 -0.305054)
			(stroke
				(width 0.1)
				(type default)
			)
			(layer "F.Fab")
		)
		(fp_line
			(start -0.67945 -0.305054)
			(end -0.12065 -0.305054)
			(stroke
				(width 0.1)
				(type default)
			)
			(layer "F.Fab")
		)
		(pad "1" smd circle
			(at -0.40005 0 180)
			(size 0 0)
			(layers "F.Cu" "F.Mask" "F.Paste")
			(net "JTAG_DBP_CPU_GTL_TCK_R1")
		)
		(pad "2" smd circle
			(at 0.40005 0 180)
			(size 0 0)
			(layers "F.Cu" "F.Mask" "F.Paste")
			(net "JTAG_DBP_CPU_GTL_TCK")
		)
	)
	(footprint ""
		(layer "F.Cu")
		(at 131.65074 -112.791748 180)
		(property "Reference" "U215"
			(at -0.04572 -2.506472 0)
			(unlocked yes)
			(layer "F.SilkS")
			(effects
				(font
					(size 0.7874 0.5842)
					(thickness 0.1524)
				)
			)
		)
		(property "Value" ""
			(at 0 0 180)
			(layer "F.Fab")
			(effects
				(font
					(size 1.27 1.27)
				)
			)
		)
		(duplicate_pad_numbers_are_jumpers no)
		(fp_line
			(start 1.949958 1.610106)
			(end -1.949958 1.610106)
			(stroke
				(width 0.1524)
				(type default)
			)
			(layer "F.SilkS")
		)
		(fp_line
			(start 1.949958 -1.560068)
			(end 1.949958 1.610106)
			(stroke
				(width 0.1524)
				(type default)
			)
			(layer "F.SilkS")
		)
		(fp_line
			(start -1.949958 1.610106)
			(end -1.949958 -1.610106)
			(stroke
				(width 0.1524)
				(type default)
			)
			(layer "F.SilkS")
		)
		(fp_line
			(start -1.949958 -1.610106)
			(end 1.949958 -1.610106)
			(stroke
				(width 0.1524)
				(type default)
			)
			(layer "F.SilkS")
		)
		(fp_line
			(start 0.750062 1.560068)
			(end -0.750062 1.560068)
			(stroke
				(width 0.1)
				(type default)
			)
			(layer "F.Fab")
		)
		(fp_line
			(start 0.750062 -1.560068)
			(end 0.750062 1.560068)
			(stroke
				(width 0.1)
				(type default)
			)
			(layer "F.Fab")
		)
		(fp_line
			(start -0.750062 1.560068)
			(end -0.750062 -1.560068)
			(stroke
				(width 0.1)
				(type default)
			)
			(layer "F.Fab")
		)
		(fp_line
			(start -0.750062 -1.560068)
			(end 0.750062 -1.560068)
			(stroke
				(width 0.1)
				(type default)
			)
			(layer "F.Fab")
		)
		(pad "D" smd rect
			(at 1.100074 0 90)
			(size 1.016 1.4224)
			(layers "F.Cu" "F.Mask" "F.Paste")
			(net "HP_LVC3_OCP_V3_2_PRSNT2")
		)
		(pad "G" smd rect
			(at -1.100074 -0.94996 90)
			(size 1.016 1.4224)
			(layers "F.Cu" "F.Mask" "F.Paste")
			(net "HP_LVC3_OCP_V3_2_PRSNT2_N")
		)
		(pad "S" smd rect
			(at -1.100074 0.94996 90)
			(size 1.016 1.4224)
			(layers "F.Cu" "F.Mask" "F.Paste")
			(net "GND")
		)
	)
	(footprint ""
		(layer "F.Cu")
		(at 29.715714 -109.333538)
		(property "Reference" "U269"
			(at -3.27914 -4.806188 0)
			(unlocked yes)
			(layer "F.SilkS")
			(effects
				(font
					(size 0.7874 0.5842)
					(thickness 0.1524)
				)
				(justify left)
			)
		)
		(property "Value" ""
			(at 0 0 0)
			(layer "F.Fab")
			(effects
				(font
					(size 1.27 1.27)
				)
			)
		)
		(duplicate_pad_numbers_are_jumpers no)
		(fp_line
			(start -1.868932 -2.549906)
			(end -1.868932 2.549906)
			(stroke
				(width 0.1524)
				(type default)
			)
			(layer "F.SilkS")
		)
		(fp_line
			(start -1.868932 2.549906)
			(end 1.868932 2.549906)
			(stroke
				(width 0.1524)
				(type default)
			)
			(layer "F.SilkS")
		)
		(fp_line
			(start -1.025906 -2.549906)
			(end -1.868932 -2.549906)
			(stroke
				(width 0.1524)
				(type default)
			)
			(layer "F.SilkS")
		)
		(fp_line
			(start 0 -1.524)
			(end -1.025906 -2.549906)
			(stroke
				(width 0.1524)
				(type default)
			)
			(layer "F.SilkS")
		)
		(fp_line
			(start 1.025906 -2.549906)
			(end 0 -1.524)
			(stroke
				(width 0.1524)
				(type default)
			)
			(layer "F.SilkS")
		)
		(fp_line
			(start 1.868932 -2.549906)
			(end 1.025906 -2.549906)
			(stroke
				(width 0.1524)
				(type default)
			)
			(layer "F.SilkS")
		)
		(fp_line
			(start 1.868932 2.549906)
			(end 1.868932 -2.549906)
			(stroke
				(width 0.1524)
				(type default)
			)
			(layer "F.SilkS")
		)
		(fp_poly
			(pts
				(xy -2.227326 -3.828796) (xy -2.735326 -2.812796) (xy -3.243326 -3.828796)
			)
			(stroke
				(width 0)
				(type default)
			)
			(fill yes)
			(layer "F.SilkS")
		)
		(fp_line
			(start -2.249932 -2.549906)
			(end -2.249932 2.549906)
			(stroke
				(width 0.1)
				(type default)
			)
			(layer "F.Fab")
		)
		(fp_line
			(start -2.249932 2.549906)
			(end 2.249932 2.549906)
			(stroke
				(width 0.1)
				(type default)
			)
			(layer "F.Fab")
		)
		(fp_line
			(start 2.249932 -2.549906)
			(end -2.249932 -2.549906)
			(stroke
				(width 0.1)
				(type default)
			)
			(layer "F.Fab")
		)
		(fp_line
			(start 2.249932 2.549906)
			(end 2.249932 -2.549906)
			(stroke
				(width 0.1)
				(type default)
			)
			(layer "F.Fab")
		)
		(fp_poly
			(pts
				(xy -4.7752 -1.787398) (xy -4.7752 -2.803398) (xy -3.7592 -2.295398)
			)
			(stroke
				(width 0)
				(type default)
			)
			(fill yes)
			(layer "F.Fab")
		)
		(pad "1" smd rect
			(at -2.800096 -2.275078 270)
			(size 0.3556 1.6002)
			(layers "F.Cu" "F.Mask" "F.Paste")
			(net "ADC128_VREF")
		)
		(pad "2" smd rect
			(at -2.800096 -1.625092 270)
			(size 0.3556 1.6002)
			(layers "F.Cu" "F.Mask" "F.Paste")
			(net "SMB_SEN_TIC_3V3AUX_SDA")
		)
		(pad "3" smd rect
			(at -2.800096 -0.975106 270)
			(size 0.3556 1.6002)
			(layers "F.Cu" "F.Mask" "F.Paste")
			(net "SMB_SEN_TIC_3V3AUX_SCL")
		)
		(pad "4" smd rect
			(at -2.800096 -0.32512 270)
			(size 0.3556 1.6002)
			(layers "F.Cu" "F.Mask" "F.Paste")
			(net "GND")
		)
		(pad "5" smd rect
			(at -2.800096 0.32512 270)
			(size 0.3556 1.6002)
			(layers "F.Cu" "F.Mask" "F.Paste")
			(net "P3V3_ADC128_VCC")
		)
		(pad "6" smd rect
			(at -2.800096 0.975106 270)
			(size 0.3556 1.6002)
			(layers "F.Cu" "F.Mask" "F.Paste")
			(net "TP_ADC128_INT")
		)
		(pad "7" smd rect
			(at -2.800096 1.625092 270)
			(size 0.3556 1.6002)
			(layers "F.Cu" "F.Mask" "F.Paste")
			(net "ADC128_A0")
		)
		(pad "8" smd rect
			(at -2.800096 2.275078 270)
			(size 0.3556 1.6002)
			(layers "F.Cu" "F.Mask" "F.Paste")
			(net "ADC128_A1")
		)
		(pad "9" smd rect
			(at 2.800096 2.275078 270)
			(size 0.3556 1.6002)
			(layers "F.Cu" "F.Mask" "F.Paste")
			(net "P12V_E1S_0_ISENSE_TIC")
		)
		(pad "10" smd rect
			(at 2.800096 1.625092 270)
			(size 0.3556 1.6002)
			(layers "F.Cu" "F.Mask" "F.Paste")
			(net "P3V3_PDB_AUX_ADC_TIC")
		)
		(pad "11" smd rect
			(at 2.800096 0.975106 270)
			(size 0.3556 1.6002)
			(layers "F.Cu" "F.Mask" "F.Paste")
			(net "P3V3_AUX_ADC_TIC")
		)
		(pad "12" smd rect
			(at 2.800096 0.32512 270)
			(size 0.3556 1.6002)
			(layers "F.Cu" "F.Mask" "F.Paste")
			(net "P3V3_ADC_TIC")
		)
		(pad "13" smd rect
			(at 2.800096 -0.32512 270)
			(size 0.3556 1.6002)
			(layers "F.Cu" "F.Mask" "F.Paste")
			(net "P5V_ADC_TIC")
		)
		(pad "14" smd rect
			(at 2.800096 -0.975106 270)
			(size 0.3556 1.6002)
			(layers "F.Cu" "F.Mask" "F.Paste")
			(net "P12V_OCP_V3_2_ISENSE_TIC")
		)
		(pad "15" smd rect
			(at 2.800096 -1.625092 270)
			(size 0.3556 1.6002)
			(layers "F.Cu" "F.Mask" "F.Paste")
			(net "P12V_OCP_SFF_ISENSE_TIC")
		)
		(pad "16" smd rect
			(at 2.800096 -2.275078 270)
			(size 0.3556 1.6002)
			(layers "F.Cu" "F.Mask" "F.Paste")
			(net "P12V_AUX_ADC_TIC")
		)
	)
	(footprint ""
		(layer "F.Cu")
		(at 169.44848 -422.874948 180)
		(property "Reference" "R2916"
			(at 0 0 180)
			(layer "F.SilkS")
			(hide yes)
			(effects
				(font
					(size 1.27 1.27)
				)
			)
		)
		(property "Value" ""
			(at 0 0 180)
			(layer "F.Fab")
			(effects
				(font
					(size 1.27 1.27)
				)
			)
		)
		(duplicate_pad_numbers_are_jumpers no)
		(fp_line
			(start 0.7874 0.4064)
			(end -0.7874 0.4064)
			(stroke
				(width 0.1524)
				(type default)
			)
			(layer "F.SilkS")
		)
		(fp_line
			(start 0.7874 -0.4064)
			(end 0.7874 0.4064)
			(stroke
				(width 0.1524)
				(type default)
			)
			(layer "F.SilkS")
		)
		(fp_line
			(start -0.7874 0.4064)
			(end -0.7874 -0.4064)
			(stroke
				(width 0.1524)
				(type default)
			)
			(layer "F.SilkS")
		)
		(fp_line
			(start -0.7874 -0.4064)
			(end 0.7874 -0.4064)
			(stroke
				(width 0.1524)
				(type default)
			)
			(layer "F.SilkS")
		)
		(fp_line
			(start 0.67945 0.3048)
			(end 0.120396 0.3048)
			(stroke
				(width 0.1)
				(type default)
			)
			(layer "F.Fab")
		)
		(fp_line
			(start 0.67945 -0.3048)
			(end 0.67945 0.3048)
			(stroke
				(width 0.1)
				(type default)
			)
			(layer "F.Fab")
		)
		(fp_line
			(start 0.12065 -0.2794)
			(end 0.12065 -0.3048)
			(stroke
				(width 0.1)
				(type default)
			)
			(layer "F.Fab")
		)
		(fp_line
			(start 0.12065 -0.3048)
			(end 0.67945 -0.3048)
			(stroke
				(width 0.1)
				(type default)
			)
			(layer "F.Fab")
		)
		(fp_line
			(start 0.120396 0.3048)
			(end 0.120396 0.2794)
			(stroke
				(width 0.1)
				(type default)
			)
			(layer "F.Fab")
		)
		(fp_line
			(start 0.120396 0.2794)
			(end -0.12065 0.2794)
			(stroke
				(width 0.1)
				(type default)
			)
			(layer "F.Fab")
		)
		(fp_line
			(start -0.12065 0.3048)
			(end -0.67945 0.3048)
			(stroke
				(width 0.1)
				(type default)
			)
			(layer "F.Fab")
		)
		(fp_line
			(start -0.12065 0.2794)
			(end -0.12065 0.3048)
			(stroke
				(width 0.1)
				(type default)
			)
			(layer "F.Fab")
		)
		(fp_line
			(start -0.12065 -0.2794)
			(end 0.12065 -0.2794)
			(stroke
				(width 0.1)
				(type default)
			)
			(layer "F.Fab")
		)
		(fp_line
			(start -0.12065 -0.305054)
			(end -0.12065 -0.2794)
			(stroke
				(width 0.1)
				(type default)
			)
			(layer "F.Fab")
		)
		(fp_line
			(start -0.67945 0.3048)
			(end -0.67945 -0.305054)
			(stroke
				(width 0.1)
				(type default)
			)
			(layer "F.Fab")
		)
		(fp_line
			(start -0.67945 -0.305054)
			(end -0.12065 -0.305054)
			(stroke
				(width 0.1)
				(type default)
			)
			(layer "F.Fab")
		)
		(pad "1" smd circle
			(at -0.40005 0 180)
			(size 0 0)
			(layers "F.Cu" "F.Mask" "F.Paste")
			(net "RST_SWB_BIC_R_N")
		)
		(pad "2" smd circle
			(at 0.40005 0 180)
			(size 0 0)
			(layers "F.Cu" "F.Mask" "F.Paste")
			(net "GND")
		)
	)
	(footprint ""
		(layer "F.Cu")
		(at 180.64988 -130.266948 90)
		(property "Reference" "R1418"
			(at 0 0 90)
			(layer "F.SilkS")
			(hide yes)
			(effects
				(font
					(size 1.27 1.27)
				)
			)
		)
		(property "Value" ""
			(at 0 0 90)
			(layer "F.Fab")
			(effects
				(font
					(size 1.27 1.27)
				)
			)
		)
		(duplicate_pad_numbers_are_jumpers no)
		(fp_line
			(start 0.7874 -0.4064)
			(end 0.7874 0.4064)
			(stroke
				(width 0.1524)
				(type default)
			)
			(layer "F.SilkS")
		)
		(fp_line
			(start -0.7874 -0.4064)
			(end 0.7874 -0.4064)
			(stroke
				(width 0.1524)
				(type default)
			)
			(layer "F.SilkS")
		)
		(fp_line
			(start 0.7874 0.4064)
			(end -0.7874 0.4064)
			(stroke
				(width 0.1524)
				(type default)
			)
			(layer "F.SilkS")
		)
		(fp_line
			(start -0.7874 0.4064)
			(end -0.7874 -0.4064)
			(stroke
				(width 0.1524)
				(type default)
			)
			(layer "F.SilkS")
		)
		(fp_line
			(start -0.12065 -0.305054)
			(end -0.12065 -0.2794)
			(stroke
				(width 0.1)
				(type default)
			)
			(layer "F.Fab")
		)
		(fp_line
			(start -0.67945 -0.305054)
			(end -0.12065 -0.305054)
			(stroke
				(width 0.1)
				(type default)
			)
			(layer "F.Fab")
		)
		(fp_line
			(start 0.67945 -0.3048)
			(end 0.67945 0.3048)
			(stroke
				(width 0.1)
				(type default)
			)
			(layer "F.Fab")
		)
		(fp_line
			(start 0.12065 -0.3048)
			(end 0.67945 -0.3048)
			(stroke
				(width 0.1)
				(type default)
			)
			(layer "F.Fab")
		)
		(fp_line
			(start 0.12065 -0.2794)
			(end 0.12065 -0.3048)
			(stroke
				(width 0.1)
				(type default)
			)
			(layer "F.Fab")
		)
		(fp_line
			(start -0.12065 -0.2794)
			(end 0.12065 -0.2794)
			(stroke
				(width 0.1)
				(type default)
			)
			(layer "F.Fab")
		)
		(fp_line
			(start 0.120396 0.2794)
			(end -0.12065 0.2794)
			(stroke
				(width 0.1)
				(type default)
			)
			(layer "F.Fab")
		)
		(fp_line
			(start -0.12065 0.2794)
			(end -0.12065 0.3048)
			(stroke
				(width 0.1)
				(type default)
			)
			(layer "F.Fab")
		)
		(fp_line
			(start 0.67945 0.3048)
			(end 0.120396 0.3048)
			(stroke
				(width 0.1)
				(type default)
			)
			(layer "F.Fab")
		)
		(fp_line
			(start 0.120396 0.3048)
			(end 0.120396 0.2794)
			(stroke
				(width 0.1)
				(type default)
			)
			(layer "F.Fab")
		)
		(fp_line
			(start -0.12065 0.3048)
			(end -0.67945 0.3048)
			(stroke
				(width 0.1)
				(type default)
			)
			(layer "F.Fab")
		)
		(fp_line
			(start -0.67945 0.3048)
			(end -0.67945 -0.305054)
			(stroke
				(width 0.1)
				(type default)
			)
			(layer "F.Fab")
		)
		(pad "1" smd circle
			(at -0.40005 0 90)
			(size 0 0)
			(layers "F.Cu" "F.Mask" "F.Paste")
			(net "RST_PCIE_CPU1_DEV_PERST_N")
		)
		(pad "2" smd circle
			(at 0.40005 0 90)
			(size 0 0)
			(layers "F.Cu" "F.Mask" "F.Paste")
			(net "GND")
		)
	)
	(footprint ""
		(layer "F.Cu")
		(at 367.44783 -255.053846 90)
		(property "Reference" "C1012"
			(at 0 0 90)
			(layer "F.SilkS")
			(hide yes)
			(effects
				(font
					(size 1.27 1.27)
				)
			)
		)
		(property "Value" ""
			(at 0 0 90)
			(layer "F.Fab")
			(effects
				(font
					(size 1.27 1.27)
				)
			)
		)
		(duplicate_pad_numbers_are_jumpers no)
		(fp_line
			(start 0.7874 -0.4064)
			(end 0.7874 0.4064)
			(stroke
				(width 0.1524)
				(type default)
			)
			(layer "F.SilkS")
		)
		(fp_line
			(start -0.7874 -0.4064)
			(end 0.7874 -0.4064)
			(stroke
				(width 0.1524)
				(type default)
			)
			(layer "F.SilkS")
		)
		(fp_line
			(start 0.7874 0.4064)
			(end -0.7874 0.4064)
			(stroke
				(width 0.1524)
				(type default)
			)
			(layer "F.SilkS")
		)
		(fp_line
			(start -0.7874 0.4064)
			(end -0.7874 -0.4064)
			(stroke
				(width 0.1524)
				(type default)
			)
			(layer "F.SilkS")
		)
		(fp_line
			(start -0.12065 -0.305054)
			(end -0.12065 -0.2794)
			(stroke
				(width 0.1)
				(type default)
			)
			(layer "F.Fab")
		)
		(fp_line
			(start -0.67945 -0.305054)
			(end -0.12065 -0.305054)
			(stroke
				(width 0.1)
				(type default)
			)
			(layer "F.Fab")
		)
		(fp_line
			(start 0.67945 -0.3048)
			(end 0.67945 0.3048)
			(stroke
				(width 0.1)
				(type default)
			)
			(layer "F.Fab")
		)
		(fp_line
			(start 0.12065 -0.3048)
			(end 0.67945 -0.3048)
			(stroke
				(width 0.1)
				(type default)
			)
			(layer "F.Fab")
		)
		(fp_line
			(start 0.12065 -0.2794)
			(end 0.12065 -0.3048)
			(stroke
				(width 0.1)
				(type default)
			)
			(layer "F.Fab")
		)
		(fp_line
			(start -0.12065 -0.2794)
			(end 0.12065 -0.2794)
			(stroke
				(width 0.1)
				(type default)
			)
			(layer "F.Fab")
		)
		(fp_line
			(start 0.120396 0.2794)
			(end -0.12065 0.2794)
			(stroke
				(width 0.1)
				(type default)
			)
			(layer "F.Fab")
		)
		(fp_line
			(start -0.12065 0.2794)
			(end -0.12065 0.3048)
			(stroke
				(width 0.1)
				(type default)
			)
			(layer "F.Fab")
		)
		(fp_line
			(start 0.67945 0.3048)
			(end 0.120396 0.3048)
			(stroke
				(width 0.1)
				(type default)
			)
			(layer "F.Fab")
		)
		(fp_line
			(start 0.120396 0.3048)
			(end 0.120396 0.2794)
			(stroke
				(width 0.1)
				(type default)
			)
			(layer "F.Fab")
		)
		(fp_line
			(start -0.12065 0.3048)
			(end -0.67945 0.3048)
			(stroke
				(width 0.1)
				(type default)
			)
			(layer "F.Fab")
		)
		(fp_line
			(start -0.67945 0.3048)
			(end -0.67945 -0.305054)
			(stroke
				(width 0.1)
				(type default)
			)
			(layer "F.Fab")
		)
		(pad "1" smd circle
			(at -0.40005 0 90)
			(size 0 0)
			(layers "F.Cu" "F.Mask" "F.Paste")
			(net "PVCCIN_CPU0")
		)
		(pad "2" smd circle
			(at 0.40005 0 90)
			(size 0 0)
			(layers "F.Cu" "F.Mask" "F.Paste")
			(net "GND")
		)
	)
	(footprint ""
		(layer "F.Cu")
		(at 386.71373 -402.371052 -90)
		(property "Reference" "C945"
			(at 0 0 270)
			(layer "F.SilkS")
			(hide yes)
			(effects
				(font
					(size 1.27 1.27)
				)
			)
		)
		(property "Value" ""
			(at 0 0 270)
			(layer "F.Fab")
			(effects
				(font
					(size 1.27 1.27)
				)
			)
		)
		(duplicate_pad_numbers_are_jumpers no)
		(fp_line
			(start -0.299974 0.150114)
			(end -0.299974 -0.150114)
			(stroke
				(width 0.1)
				(type default)
			)
			(layer "F.Fab")
		)
		(fp_line
			(start 0.299974 0.150114)
			(end -0.299974 0.150114)
			(stroke
				(width 0.1)
				(type default)
			)
			(layer "F.Fab")
		)
		(fp_line
			(start -0.299974 -0.150114)
			(end 0.299974 -0.150114)
			(stroke
				(width 0.1)
				(type default)
			)
			(layer "F.Fab")
		)
		(fp_line
			(start 0.299974 -0.150114)
			(end 0.299974 0.150114)
			(stroke
				(width 0.1)
				(type default)
			)
			(layer "F.Fab")
		)
		(pad "1" smd rect
			(at -0.2667 0 270)
			(size 0.3048 0.381)
			(layers "F.Cu" "F.Mask" "F.Paste")
			(net "P5E_CPU0_PE2_TX_C_DP<10>")
		)
		(pad "2" smd rect
			(at 0.2667 0 270)
			(size 0.3048 0.381)
			(layers "F.Cu" "F.Mask" "F.Paste")
			(net "P5E_CPU0_PE2_TX_DP<10>")
		)
	)
	(footprint ""
		(layer "F.Cu")
		(at 180.77688 -39.969948)
		(property "Reference" "R1396"
			(at 0 0 0)
			(layer "F.SilkS")
			(hide yes)
			(effects
				(font
					(size 1.27 1.27)
				)
			)
		)
		(property "Value" ""
			(at 0 0 0)
			(layer "F.Fab")
			(effects
				(font
					(size 1.27 1.27)
				)
			)
		)
		(duplicate_pad_numbers_are_jumpers no)
		(fp_line
			(start -0.7874 -0.4064)
			(end 0.7874 -0.4064)
			(stroke
				(width 0.1524)
				(type default)
			)
			(layer "F.SilkS")
		)
		(fp_line
			(start -0.7874 0.4064)
			(end -0.7874 -0.4064)
			(stroke
				(width 0.1524)
				(type default)
			)
			(layer "F.SilkS")
		)
		(fp_line
			(start 0.7874 -0.4064)
			(end 0.7874 0.4064)
			(stroke
				(width 0.1524)
				(type default)
			)
			(layer "F.SilkS")
		)
		(fp_line
			(start 0.7874 0.4064)
			(end -0.7874 0.4064)
			(stroke
				(width 0.1524)
				(type default)
			)
			(layer "F.SilkS")
		)
		(fp_line
			(start -0.67945 -0.305054)
			(end -0.12065 -0.305054)
			(stroke
				(width 0.1)
				(type default)
			)
			(layer "F.Fab")
		)
		(fp_line
			(start -0.67945 0.3048)
			(end -0.67945 -0.305054)
			(stroke
				(width 0.1)
				(type default)
			)
			(layer "F.Fab")
		)
		(fp_line
			(start -0.12065 -0.305054)
			(end -0.12065 -0.2794)
			(stroke
				(width 0.1)
				(type default)
			)
			(layer "F.Fab")
		)
		(fp_line
			(start -0.12065 -0.2794)
			(end 0.12065 -0.2794)
			(stroke
				(width 0.1)
				(type default)
			)
			(layer "F.Fab")
		)
		(fp_line
			(start -0.12065 0.2794)
			(end -0.12065 0.3048)
			(stroke
				(width 0.1)
				(type default)
			)
			(layer "F.Fab")
		)
		(fp_line
			(start -0.12065 0.3048)
			(end -0.67945 0.3048)
			(stroke
				(width 0.1)
				(type default)
			)
			(layer "F.Fab")
		)
		(fp_line
			(start 0.120396 0.2794)
			(end -0.12065 0.2794)
			(stroke
				(width 0.1)
				(type default)
			)
			(layer "F.Fab")
		)
		(fp_line
			(start 0.120396 0.3048)
			(end 0.120396 0.2794)
			(stroke
				(width 0.1)
				(type default)
			)
			(layer "F.Fab")
		)
		(fp_line
			(start 0.12065 -0.3048)
			(end 0.67945 -0.3048)
			(stroke
				(width 0.1)
				(type default)
			)
			(layer "F.Fab")
		)
		(fp_line
			(start 0.12065 -0.2794)
			(end 0.12065 -0.3048)
			(stroke
				(width 0.1)
				(type default)
			)
			(layer "F.Fab")
		)
		(fp_line
			(start 0.67945 -0.3048)
			(end 0.67945 0.3048)
			(stroke
				(width 0.1)
				(type default)
			)
			(layer "F.Fab")
		)
		(fp_line
			(start 0.67945 0.3048)
			(end 0.120396 0.3048)
			(stroke
				(width 0.1)
				(type default)
			)
			(layer "F.Fab")
		)
		(pad "1" smd circle
			(at -0.40005 0)
			(size 0 0)
			(layers "F.Cu" "F.Mask" "F.Paste")
			(net "FM_M2_SSD_0_PEDET")
		)
		(pad "2" smd circle
			(at 0.40005 0)
			(size 0 0)
			(layers "F.Cu" "F.Mask" "F.Paste")
			(net "P3V3_AUX")
		)
	)
	(footprint ""
		(layer "F.Cu")
		(at 87.196676 -79.078836)
		(property "Reference" "D99"
			(at -44.30141 38.649402 90)
			(unlocked yes)
			(layer "F.SilkS")
			(effects
				(font
					(size 0.635 0.4064)
					(thickness 0.1524)
				)
				(justify left)
			)
		)
		(property "Value" ""
			(at 0 0 0)
			(layer "F.Fab")
			(effects
				(font
					(size 1.27 1.27)
				)
			)
		)
		(duplicate_pad_numbers_are_jumpers no)
		(fp_line
			(start -0.90678 0.4826)
			(end -0.90678 -0.4699)
			(stroke
				(width 0.1524)
				(type default)
			)
			(layer "F.SilkS")
		)
		(fp_line
			(start -0.89408 -0.4826)
			(end 0.90678 -0.4826)
			(stroke
				(width 0.1524)
				(type default)
			)
			(layer "F.SilkS")
		)
		(fp_line
			(start -0.79248 -0.4826)
			(end 1.03378 -0.4826)
			(stroke
				(width 0.1524)
				(type default)
			)
			(layer "F.SilkS")
		)
		(fp_line
			(start -0.64008 -0.4826)
			(end 1.16078 -0.4826)
			(stroke
				(width 0.1524)
				(type default)
			)
			(layer "F.SilkS")
		)
		(fp_line
			(start 0.90678 -0.4826)
			(end 0.90678 0.4826)
			(stroke
				(width 0.1524)
				(type default)
			)
			(layer "F.SilkS")
		)
		(fp_line
			(start 0.90678 0.4826)
			(end -0.90678 0.4826)
			(stroke
				(width 0.1524)
				(type default)
			)
			(layer "F.SilkS")
		)
		(fp_line
			(start 1.03378 -0.4826)
			(end 1.03378 0.4826)
			(stroke
				(width 0.1524)
				(type default)
			)
			(layer "F.SilkS")
		)
		(fp_line
			(start 1.03378 0.4826)
			(end -0.79248 0.4826)
			(stroke
				(width 0.1524)
				(type default)
			)
			(layer "F.SilkS")
		)
		(fp_line
			(start 1.16078 -0.4826)
			(end 1.16078 0.4826)
			(stroke
				(width 0.1524)
				(type default)
			)
			(layer "F.SilkS")
		)
		(fp_line
			(start 1.16078 0.4826)
			(end -0.64008 0.4826)
			(stroke
				(width 0.1524)
				(type default)
			)
			(layer "F.SilkS")
		)
		(fp_line
			(start -0.499872 -0.249936)
			(end 0.499872 -0.249936)
			(stroke
				(width 0.1)
				(type default)
			)
			(layer "F.Fab")
		)
		(fp_line
			(start -0.499872 0.249936)
			(end -0.499872 -0.249936)
			(stroke
				(width 0.1)
				(type default)
			)
			(layer "F.Fab")
		)
		(fp_line
			(start 0.499872 -0.249936)
			(end 0.499872 0.249936)
			(stroke
				(width 0.1)
				(type default)
			)
			(layer "F.Fab")
		)
		(fp_line
			(start 0.499872 0.249936)
			(end -0.499872 0.249936)
			(stroke
				(width 0.1)
				(type default)
			)
			(layer "F.Fab")
		)
		(pad "A" smd rect
			(at -0.47498 0)
			(size 0.6096 0.7112)
			(layers "F.Cu" "F.Mask" "F.Paste")
			(net "LED_P3V3")
		)
		(pad "C" smd rect
			(at 0.47498 0)
			(size 0.6096 0.7112)
			(layers "F.Cu" "F.Mask" "F.Paste")
			(net "GND")
		)
	)
	(footprint ""
		(layer "F.Cu")
		(at 417.558728 -156.17063 180)
		(property "Reference" "PR1709"
			(at 0 0 180)
			(layer "F.SilkS")
			(hide yes)
			(effects
				(font
					(size 1.27 1.27)
				)
			)
		)
		(property "Value" ""
			(at 0 0 180)
			(layer "F.Fab")
			(effects
				(font
					(size 1.27 1.27)
				)
			)
		)
		(duplicate_pad_numbers_are_jumpers no)
		(fp_line
			(start 0.7874 0.4064)
			(end -0.7874 0.4064)
			(stroke
				(width 0.1524)
				(type default)
			)
			(layer "F.SilkS")
		)
		(fp_line
			(start 0.7874 -0.4064)
			(end 0.7874 0.4064)
			(stroke
				(width 0.1524)
				(type default)
			)
			(layer "F.SilkS")
		)
		(fp_line
			(start -0.7874 0.4064)
			(end -0.7874 -0.4064)
			(stroke
				(width 0.1524)
				(type default)
			)
			(layer "F.SilkS")
		)
		(fp_line
			(start -0.7874 -0.4064)
			(end 0.7874 -0.4064)
			(stroke
				(width 0.1524)
				(type default)
			)
			(layer "F.SilkS")
		)
		(fp_line
			(start 0.67945 0.3048)
			(end 0.120396 0.3048)
			(stroke
				(width 0.1)
				(type default)
			)
			(layer "F.Fab")
		)
		(fp_line
			(start 0.67945 -0.3048)
			(end 0.67945 0.3048)
			(stroke
				(width 0.1)
				(type default)
			)
			(layer "F.Fab")
		)
		(fp_line
			(start 0.12065 -0.2794)
			(end 0.12065 -0.3048)
			(stroke
				(width 0.1)
				(type default)
			)
			(layer "F.Fab")
		)
		(fp_line
			(start 0.12065 -0.3048)
			(end 0.67945 -0.3048)
			(stroke
				(width 0.1)
				(type default)
			)
			(layer "F.Fab")
		)
		(fp_line
			(start 0.120396 0.3048)
			(end 0.120396 0.2794)
			(stroke
				(width 0.1)
				(type default)
			)
			(layer "F.Fab")
		)
		(fp_line
			(start 0.120396 0.2794)
			(end -0.12065 0.2794)
			(stroke
				(width 0.1)
				(type default)
			)
			(layer "F.Fab")
		)
		(fp_line
			(start -0.12065 0.3048)
			(end -0.67945 0.3048)
			(stroke
				(width 0.1)
				(type default)
			)
			(layer "F.Fab")
		)
		(fp_line
			(start -0.12065 0.2794)
			(end -0.12065 0.3048)
			(stroke
				(width 0.1)
				(type default)
			)
			(layer "F.Fab")
		)
		(fp_line
			(start -0.12065 -0.2794)
			(end 0.12065 -0.2794)
			(stroke
				(width 0.1)
				(type default)
			)
			(layer "F.Fab")
		)
		(fp_line
			(start -0.12065 -0.305054)
			(end -0.12065 -0.2794)
			(stroke
				(width 0.1)
				(type default)
			)
			(layer "F.Fab")
		)
		(fp_line
			(start -0.67945 0.3048)
			(end -0.67945 -0.305054)
			(stroke
				(width 0.1)
				(type default)
			)
			(layer "F.Fab")
		)
		(fp_line
			(start -0.67945 -0.305054)
			(end -0.12065 -0.305054)
			(stroke
				(width 0.1)
				(type default)
			)
			(layer "F.Fab")
		)
		(pad "1" smd circle
			(at -0.40005 0 180)
			(size 0 0)
			(layers "F.Cu" "F.Mask" "F.Paste")
			(net "PVCCFA_EHV_CPU0_LSET1")
		)
		(pad "2" smd circle
			(at 0.40005 0 180)
			(size 0 0)
			(layers "F.Cu" "F.Mask" "F.Paste")
			(net "GND")
		)
	)
	(footprint ""
		(layer "F.Cu")
		(at 164.64788 -118.836948)
		(property "Reference" "R3324"
			(at 0 0 0)
			(layer "F.SilkS")
			(hide yes)
			(effects
				(font
					(size 1.27 1.27)
				)
			)
		)
		(property "Value" ""
			(at 0 0 0)
			(layer "F.Fab")
			(effects
				(font
					(size 1.27 1.27)
				)
			)
		)
		(duplicate_pad_numbers_are_jumpers no)
		(fp_line
			(start -0.7874 -0.4064)
			(end 0.7874 -0.4064)
			(stroke
				(width 0.1524)
				(type default)
			)
			(layer "F.SilkS")
		)
		(fp_line
			(start -0.7874 0.4064)
			(end -0.7874 -0.4064)
			(stroke
				(width 0.1524)
				(type default)
			)
			(layer "F.SilkS")
		)
		(fp_line
			(start 0.7874 -0.4064)
			(end 0.7874 0.4064)
			(stroke
				(width 0.1524)
				(type default)
			)
			(layer "F.SilkS")
		)
		(fp_line
			(start 0.7874 0.4064)
			(end -0.7874 0.4064)
			(stroke
				(width 0.1524)
				(type default)
			)
			(layer "F.SilkS")
		)
		(fp_line
			(start -0.67945 -0.305054)
			(end -0.12065 -0.305054)
			(stroke
				(width 0.1)
				(type default)
			)
			(layer "F.Fab")
		)
		(fp_line
			(start -0.67945 0.3048)
			(end -0.67945 -0.305054)
			(stroke
				(width 0.1)
				(type default)
			)
			(layer "F.Fab")
		)
		(fp_line
			(start -0.12065 -0.305054)
			(end -0.12065 -0.2794)
			(stroke
				(width 0.1)
				(type default)
			)
			(layer "F.Fab")
		)
		(fp_line
			(start -0.12065 -0.2794)
			(end 0.12065 -0.2794)
			(stroke
				(width 0.1)
				(type default)
			)
			(layer "F.Fab")
		)
		(fp_line
			(start -0.12065 0.2794)
			(end -0.12065 0.3048)
			(stroke
				(width 0.1)
				(type default)
			)
			(layer "F.Fab")
		)
		(fp_line
			(start -0.12065 0.3048)
			(end -0.67945 0.3048)
			(stroke
				(width 0.1)
				(type default)
			)
			(layer "F.Fab")
		)
		(fp_line
			(start 0.120396 0.2794)
			(end -0.12065 0.2794)
			(stroke
				(width 0.1)
				(type default)
			)
			(layer "F.Fab")
		)
		(fp_line
			(start 0.120396 0.3048)
			(end 0.120396 0.2794)
			(stroke
				(width 0.1)
				(type default)
			)
			(layer "F.Fab")
		)
		(fp_line
			(start 0.12065 -0.3048)
			(end 0.67945 -0.3048)
			(stroke
				(width 0.1)
				(type default)
			)
			(layer "F.Fab")
		)
		(fp_line
			(start 0.12065 -0.2794)
			(end 0.12065 -0.3048)
			(stroke
				(width 0.1)
				(type default)
			)
			(layer "F.Fab")
		)
		(fp_line
			(start 0.67945 -0.3048)
			(end 0.67945 0.3048)
			(stroke
				(width 0.1)
				(type default)
			)
			(layer "F.Fab")
		)
		(fp_line
			(start 0.67945 0.3048)
			(end 0.120396 0.3048)
			(stroke
				(width 0.1)
				(type default)
			)
			(layer "F.Fab")
		)
		(pad "1" smd circle
			(at -0.40005 0)
			(size 0 0)
			(layers "F.Cu" "F.Mask" "F.Paste")
			(net "GPU_FPGA_READY_ISO")
		)
		(pad "2" smd circle
			(at 0.40005 0)
			(size 0 0)
			(layers "F.Cu" "F.Mask" "F.Paste")
			(net "GPU_FPGA_READY_ISO_R")
		)
	)
	(footprint ""
		(layer "F.Cu")
		(at 20.831556 -178.077368 -90)
		(property "Reference" "PR2222"
			(at 0 0 270)
			(layer "F.SilkS")
			(hide yes)
			(effects
				(font
					(size 1.27 1.27)
				)
			)
		)
		(property "Value" ""
			(at 0 0 270)
			(layer "F.Fab")
			(effects
				(font
					(size 1.27 1.27)
				)
			)
		)
		(duplicate_pad_numbers_are_jumpers no)
		(fp_line
			(start -0.7874 0.4064)
			(end -0.7874 -0.4064)
			(stroke
				(width 0.1524)
				(type default)
			)
			(layer "F.SilkS")
		)
		(fp_line
			(start 0.7874 0.4064)
			(end -0.7874 0.4064)
			(stroke
				(width 0.1524)
				(type default)
			)
			(layer "F.SilkS")
		)
		(fp_line
			(start -0.7874 -0.4064)
			(end 0.7874 -0.4064)
			(stroke
				(width 0.1524)
				(type default)
			)
			(layer "F.SilkS")
		)
		(fp_line
			(start 0.7874 -0.4064)
			(end 0.7874 0.4064)
			(stroke
				(width 0.1524)
				(type default)
			)
			(layer "F.SilkS")
		)
		(fp_line
			(start -0.67945 0.3048)
			(end -0.67945 -0.305054)
			(stroke
				(width 0.1)
				(type default)
			)
			(layer "F.Fab")
		)
		(fp_line
			(start -0.12065 0.3048)
			(end -0.67945 0.3048)
			(stroke
				(width 0.1)
				(type default)
			)
			(layer "F.Fab")
		)
		(fp_line
			(start 0.120396 0.3048)
			(end 0.120396 0.2794)
			(stroke
				(width 0.1)
				(type default)
			)
			(layer "F.Fab")
		)
		(fp_line
			(start 0.67945 0.3048)
			(end 0.120396 0.3048)
			(stroke
				(width 0.1)
				(type default)
			)
			(layer "F.Fab")
		)
		(fp_line
			(start -0.12065 0.2794)
			(end -0.12065 0.3048)
			(stroke
				(width 0.1)
				(type default)
			)
			(layer "F.Fab")
		)
		(fp_line
			(start 0.120396 0.2794)
			(end -0.12065 0.2794)
			(stroke
				(width 0.1)
				(type default)
			)
			(layer "F.Fab")
		)
		(fp_line
			(start -0.12065 -0.2794)
			(end 0.12065 -0.2794)
			(stroke
				(width 0.1)
				(type default)
			)
			(layer "F.Fab")
		)
		(fp_line
			(start 0.12065 -0.2794)
			(end 0.12065 -0.3048)
			(stroke
				(width 0.1)
				(type default)
			)
			(layer "F.Fab")
		)
		(fp_line
			(start 0.12065 -0.3048)
			(end 0.67945 -0.3048)
			(stroke
				(width 0.1)
				(type default)
			)
			(layer "F.Fab")
		)
		(fp_line
			(start 0.67945 -0.3048)
			(end 0.67945 0.3048)
			(stroke
				(width 0.1)
				(type default)
			)
			(layer "F.Fab")
		)
		(fp_line
			(start -0.67945 -0.305054)
			(end -0.12065 -0.305054)
			(stroke
				(width 0.1)
				(type default)
			)
			(layer "F.Fab")
		)
		(fp_line
			(start -0.12065 -0.305054)
			(end -0.12065 -0.2794)
			(stroke
				(width 0.1)
				(type default)
			)
			(layer "F.Fab")
		)
		(pad "1" smd circle
			(at -0.40005 0 270)
			(size 0 0)
			(layers "F.Cu" "F.Mask" "F.Paste")
			(net "PVNN_MAIN_CPU1_CS")
		)
		(pad "2" smd circle
			(at 0.40005 0 270)
			(size 0 0)
			(layers "F.Cu" "F.Mask" "F.Paste")
			(net "GND")
		)
	)
	(footprint ""
		(layer "F.Cu")
		(at 27.81681 -55.015384)
		(property "Reference" "R3051"
			(at 0 0 0)
			(layer "F.SilkS")
			(hide yes)
			(effects
				(font
					(size 1.27 1.27)
				)
			)
		)
		(property "Value" ""
			(at 0 0 0)
			(layer "F.Fab")
			(effects
				(font
					(size 1.27 1.27)
				)
			)
		)
		(duplicate_pad_numbers_are_jumpers no)
		(fp_line
			(start -0.7874 -0.4064)
			(end 0.7874 -0.4064)
			(stroke
				(width 0.1524)
				(type default)
			)
			(layer "F.SilkS")
		)
		(fp_line
			(start -0.7874 0.4064)
			(end -0.7874 -0.4064)
			(stroke
				(width 0.1524)
				(type default)
			)
			(layer "F.SilkS")
		)
		(fp_line
			(start 0.7874 -0.4064)
			(end 0.7874 0.4064)
			(stroke
				(width 0.1524)
				(type default)
			)
			(layer "F.SilkS")
		)
		(fp_line
			(start 0.7874 0.4064)
			(end -0.7874 0.4064)
			(stroke
				(width 0.1524)
				(type default)
			)
			(layer "F.SilkS")
		)
		(fp_line
			(start -0.67945 -0.305054)
			(end -0.12065 -0.305054)
			(stroke
				(width 0.1)
				(type default)
			)
			(layer "F.Fab")
		)
		(fp_line
			(start -0.67945 0.3048)
			(end -0.67945 -0.305054)
			(stroke
				(width 0.1)
				(type default)
			)
			(layer "F.Fab")
		)
		(fp_line
			(start -0.12065 -0.305054)
			(end -0.12065 -0.2794)
			(stroke
				(width 0.1)
				(type default)
			)
			(layer "F.Fab")
		)
		(fp_line
			(start -0.12065 -0.2794)
			(end 0.12065 -0.2794)
			(stroke
				(width 0.1)
				(type default)
			)
			(layer "F.Fab")
		)
		(fp_line
			(start -0.12065 0.2794)
			(end -0.12065 0.3048)
			(stroke
				(width 0.1)
				(type default)
			)
			(layer "F.Fab")
		)
		(fp_line
			(start -0.12065 0.3048)
			(end -0.67945 0.3048)
			(stroke
				(width 0.1)
				(type default)
			)
			(layer "F.Fab")
		)
		(fp_line
			(start 0.120396 0.2794)
			(end -0.12065 0.2794)
			(stroke
				(width 0.1)
				(type default)
			)
			(layer "F.Fab")
		)
		(fp_line
			(start 0.120396 0.3048)
			(end 0.120396 0.2794)
			(stroke
				(width 0.1)
				(type default)
			)
			(layer "F.Fab")
		)
		(fp_line
			(start 0.12065 -0.3048)
			(end 0.67945 -0.3048)
			(stroke
				(width 0.1)
				(type default)
			)
			(layer "F.Fab")
		)
		(fp_line
			(start 0.12065 -0.2794)
			(end 0.12065 -0.3048)
			(stroke
				(width 0.1)
				(type default)
			)
			(layer "F.Fab")
		)
		(fp_line
			(start 0.67945 -0.3048)
			(end 0.67945 0.3048)
			(stroke
				(width 0.1)
				(type default)
			)
			(layer "F.Fab")
		)
		(fp_line
			(start 0.67945 0.3048)
			(end 0.120396 0.3048)
			(stroke
				(width 0.1)
				(type default)
			)
			(layer "F.Fab")
		)
		(pad "1" smd circle
			(at -0.40005 0)
			(size 0 0)
			(layers "F.Cu" "F.Mask" "F.Paste")
			(net "IRQ_SML1_PMBUS_ALERT_R_N")
		)
		(pad "2" smd circle
			(at 0.40005 0)
			(size 0 0)
			(layers "F.Cu" "F.Mask" "F.Paste")
			(net "IRQ_SML1_PMBUS_ALERT_N")
		)
	)
	(footprint ""
		(layer "F.Cu")
		(at 73.28408 -143.769588 180)
		(property "Reference" "PR568"
			(at 0 0 180)
			(layer "F.SilkS")
			(hide yes)
			(effects
				(font
					(size 1.27 1.27)
				)
			)
		)
		(property "Value" ""
			(at 0 0 180)
			(layer "F.Fab")
			(effects
				(font
					(size 1.27 1.27)
				)
			)
		)
		(duplicate_pad_numbers_are_jumpers no)
		(fp_line
			(start 0.7874 0.4064)
			(end -0.7874 0.4064)
			(stroke
				(width 0.1524)
				(type default)
			)
			(layer "F.SilkS")
		)
		(fp_line
			(start 0.7874 -0.4064)
			(end 0.7874 0.4064)
			(stroke
				(width 0.1524)
				(type default)
			)
			(layer "F.SilkS")
		)
		(fp_line
			(start -0.7874 0.4064)
			(end -0.7874 -0.4064)
			(stroke
				(width 0.1524)
				(type default)
			)
			(layer "F.SilkS")
		)
		(fp_line
			(start -0.7874 -0.4064)
			(end 0.7874 -0.4064)
			(stroke
				(width 0.1524)
				(type default)
			)
			(layer "F.SilkS")
		)
		(fp_line
			(start 0.67945 0.3048)
			(end 0.120396 0.3048)
			(stroke
				(width 0.1)
				(type default)
			)
			(layer "F.Fab")
		)
		(fp_line
			(start 0.67945 -0.3048)
			(end 0.67945 0.3048)
			(stroke
				(width 0.1)
				(type default)
			)
			(layer "F.Fab")
		)
		(fp_line
			(start 0.12065 -0.2794)
			(end 0.12065 -0.3048)
			(stroke
				(width 0.1)
				(type default)
			)
			(layer "F.Fab")
		)
		(fp_line
			(start 0.12065 -0.3048)
			(end 0.67945 -0.3048)
			(stroke
				(width 0.1)
				(type default)
			)
			(layer "F.Fab")
		)
		(fp_line
			(start 0.120396 0.3048)
			(end 0.120396 0.2794)
			(stroke
				(width 0.1)
				(type default)
			)
			(layer "F.Fab")
		)
		(fp_line
			(start 0.120396 0.2794)
			(end -0.12065 0.2794)
			(stroke
				(width 0.1)
				(type default)
			)
			(layer "F.Fab")
		)
		(fp_line
			(start -0.12065 0.3048)
			(end -0.67945 0.3048)
			(stroke
				(width 0.1)
				(type default)
			)
			(layer "F.Fab")
		)
		(fp_line
			(start -0.12065 0.2794)
			(end -0.12065 0.3048)
			(stroke
				(width 0.1)
				(type default)
			)
			(layer "F.Fab")
		)
		(fp_line
			(start -0.12065 -0.2794)
			(end 0.12065 -0.2794)
			(stroke
				(width 0.1)
				(type default)
			)
			(layer "F.Fab")
		)
		(fp_line
			(start -0.12065 -0.305054)
			(end -0.12065 -0.2794)
			(stroke
				(width 0.1)
				(type default)
			)
			(layer "F.Fab")
		)
		(fp_line
			(start -0.67945 0.3048)
			(end -0.67945 -0.305054)
			(stroke
				(width 0.1)
				(type default)
			)
			(layer "F.Fab")
		)
		(fp_line
			(start -0.67945 -0.305054)
			(end -0.12065 -0.305054)
			(stroke
				(width 0.1)
				(type default)
			)
			(layer "F.Fab")
		)
		(pad "1" smd circle
			(at -0.40005 0 180)
			(size 0 0)
			(layers "F.Cu" "F.Mask" "F.Paste")
			(net "VSENSE_PVCCINFAON_CPU1_DP")
		)
		(pad "2" smd circle
			(at 0.40005 0 180)
			(size 0 0)
			(layers "F.Cu" "F.Mask" "F.Paste")
			(net "PVCCINFAON_CPU1")
		)
	)
	(footprint ""
		(layer "F.Cu")
		(at 299.02023 -55.416196)
		(property "Reference" "R2979"
			(at 0 0 0)
			(layer "F.SilkS")
			(hide yes)
			(effects
				(font
					(size 1.27 1.27)
				)
			)
		)
		(property "Value" ""
			(at 0 0 0)
			(layer "F.Fab")
			(effects
				(font
					(size 1.27 1.27)
				)
			)
		)
		(duplicate_pad_numbers_are_jumpers no)
		(fp_line
			(start -0.7874 -0.4064)
			(end 0.7874 -0.4064)
			(stroke
				(width 0.1524)
				(type default)
			)
			(layer "F.SilkS")
		)
		(fp_line
			(start -0.7874 0.4064)
			(end -0.7874 -0.4064)
			(stroke
				(width 0.1524)
				(type default)
			)
			(layer "F.SilkS")
		)
		(fp_line
			(start 0.7874 -0.4064)
			(end 0.7874 0.4064)
			(stroke
				(width 0.1524)
				(type default)
			)
			(layer "F.SilkS")
		)
		(fp_line
			(start 0.7874 0.4064)
			(end -0.7874 0.4064)
			(stroke
				(width 0.1524)
				(type default)
			)
			(layer "F.SilkS")
		)
		(fp_line
			(start -0.67945 -0.305054)
			(end -0.12065 -0.305054)
			(stroke
				(width 0.1)
				(type default)
			)
			(layer "F.Fab")
		)
		(fp_line
			(start -0.67945 0.3048)
			(end -0.67945 -0.305054)
			(stroke
				(width 0.1)
				(type default)
			)
			(layer "F.Fab")
		)
		(fp_line
			(start -0.12065 -0.305054)
			(end -0.12065 -0.2794)
			(stroke
				(width 0.1)
				(type default)
			)
			(layer "F.Fab")
		)
		(fp_line
			(start -0.12065 -0.2794)
			(end 0.12065 -0.2794)
			(stroke
				(width 0.1)
				(type default)
			)
			(layer "F.Fab")
		)
		(fp_line
			(start -0.12065 0.2794)
			(end -0.12065 0.3048)
			(stroke
				(width 0.1)
				(type default)
			)
			(layer "F.Fab")
		)
		(fp_line
			(start -0.12065 0.3048)
			(end -0.67945 0.3048)
			(stroke
				(width 0.1)
				(type default)
			)
			(layer "F.Fab")
		)
		(fp_line
			(start 0.120396 0.2794)
			(end -0.12065 0.2794)
			(stroke
				(width 0.1)
				(type default)
			)
			(layer "F.Fab")
		)
		(fp_line
			(start 0.120396 0.3048)
			(end 0.120396 0.2794)
			(stroke
				(width 0.1)
				(type default)
			)
			(layer "F.Fab")
		)
		(fp_line
			(start 0.12065 -0.3048)
			(end 0.67945 -0.3048)
			(stroke
				(width 0.1)
				(type default)
			)
			(layer "F.Fab")
		)
		(fp_line
			(start 0.12065 -0.2794)
			(end 0.12065 -0.3048)
			(stroke
				(width 0.1)
				(type default)
			)
			(layer "F.Fab")
		)
		(fp_line
			(start 0.67945 -0.3048)
			(end 0.67945 0.3048)
			(stroke
				(width 0.1)
				(type default)
			)
			(layer "F.Fab")
		)
		(fp_line
			(start 0.67945 0.3048)
			(end 0.120396 0.3048)
			(stroke
				(width 0.1)
				(type default)
			)
			(layer "F.Fab")
		)
		(pad "1" smd circle
			(at -0.40005 0)
			(size 0 0)
			(layers "F.Cu" "F.Mask" "F.Paste")
			(net "P1V05_PCH_AUX")
		)
		(pad "2" smd circle
			(at 0.40005 0)
			(size 0 0)
			(layers "F.Cu" "F.Mask" "F.Paste")
			(net "FM_BOARD_SKU_ID2")
		)
	)
	(footprint ""
		(layer "F.Cu")
		(at 140.73378 -121.211848)
		(property "Reference" "U51"
			(at -2.2606 -4.663948 0)
			(unlocked yes)
			(layer "F.SilkS")
			(effects
				(font
					(size 0.7874 0.5842)
					(thickness 0.1524)
				)
				(justify left)
			)
		)
		(property "Value" ""
			(at 0 0 0)
			(layer "F.Fab")
			(effects
				(font
					(size 1.27 1.27)
				)
			)
		)
		(duplicate_pad_numbers_are_jumpers no)
		(fp_line
			(start -2.097532 -3.949954)
			(end -2.097532 3.949954)
			(stroke
				(width 0.1524)
				(type default)
			)
			(layer "F.SilkS")
		)
		(fp_line
			(start -2.097532 3.949954)
			(end 2.097532 3.949954)
			(stroke
				(width 0.1524)
				(type default)
			)
			(layer "F.SilkS")
		)
		(fp_line
			(start -1.409954 -3.949954)
			(end -2.097532 -3.949954)
			(stroke
				(width 0.1524)
				(type default)
			)
			(layer "F.SilkS")
		)
		(fp_line
			(start 0 -2.54)
			(end -1.409954 -3.949954)
			(stroke
				(width 0.1524)
				(type default)
			)
			(layer "F.SilkS")
		)
		(fp_line
			(start 1.409954 -3.949954)
			(end 0 -2.54)
			(stroke
				(width 0.1524)
				(type default)
			)
			(layer "F.SilkS")
		)
		(fp_line
			(start 2.097532 -3.949954)
			(end 1.409954 -3.949954)
			(stroke
				(width 0.1524)
				(type default)
			)
			(layer "F.SilkS")
		)
		(fp_line
			(start 2.097532 3.949954)
			(end 2.097532 -3.949954)
			(stroke
				(width 0.1524)
				(type default)
			)
			(layer "F.SilkS")
		)
		(fp_poly
			(pts
				(xy -4.7498 -4.182872) (xy -4.7498 -3.166872) (xy -3.7338 -3.674872)
			)
			(stroke
				(width 0)
				(type default)
			)
			(fill yes)
			(layer "F.SilkS")
		)
		(fp_line
			(start -2.249932 -3.949954)
			(end -2.249932 3.949954)
			(stroke
				(width 0.1)
				(type default)
			)
			(layer "F.Fab")
		)
		(fp_line
			(start -2.249932 3.949954)
			(end 2.249932 3.949954)
			(stroke
				(width 0.1)
				(type default)
			)
			(layer "F.Fab")
		)
		(fp_line
			(start 2.249932 -3.949954)
			(end -2.249932 -3.949954)
			(stroke
				(width 0.1)
				(type default)
			)
			(layer "F.Fab")
		)
		(fp_line
			(start 2.249932 3.949954)
			(end 2.249932 -3.949954)
			(stroke
				(width 0.1)
				(type default)
			)
			(layer "F.Fab")
		)
		(fp_poly
			(pts
				(xy -4.7498 -4.182872) (xy -4.7498 -3.166872) (xy -3.7338 -3.674872)
			)
			(stroke
				(width 0)
				(type default)
			)
			(fill yes)
			(layer "F.Fab")
		)
		(pad "1" smd rect
			(at -2.925064 -3.674872 270)
			(size 0.6096 1.3716)
			(layers "F.Cu" "F.Mask" "F.Paste")
			(net "FM_SMB_CPU1_ALERT")
		)
		(pad "2" smd rect
			(at -2.925064 -2.925064 270)
			(size 0.4064 1.3716)
			(layers "F.Cu" "F.Mask" "F.Paste")
			(net "PD_SMB_OCP2_HP_ADD1")
		)
		(pad "3" smd rect
			(at -2.925064 -2.275078 270)
			(size 0.4064 1.3716)
			(layers "F.Cu" "F.Mask" "F.Paste")
			(net "PD_SMB_OCP2_HP_ADD2")
		)
		(pad "4" smd rect
			(at -2.925064 -1.625092 270)
			(size 0.4064 1.3716)
			(layers "F.Cu" "F.Mask" "F.Paste")
			(net "TP_PCA9555_U51_P00")
		)
		(pad "5" smd rect
			(at -2.925064 -0.975106 270)
			(size 0.4064 1.3716)
			(layers "F.Cu" "F.Mask" "F.Paste")
			(net "TP_PCA9555_U51_P01")
		)
		(pad "6" smd rect
			(at -2.925064 -0.32512 270)
			(size 0.4064 1.3716)
			(layers "F.Cu" "F.Mask" "F.Paste")
			(net "HP_OCP_V3_2_EN")
		)
		(pad "7" smd rect
			(at -2.925064 0.32512 270)
			(size 0.4064 1.3716)
			(layers "F.Cu" "F.Mask" "F.Paste")
			(net "HP_LVC3_OCP_V3_2_ATTN_OUT_SW_N")
		)
		(pad "8" smd rect
			(at -2.925064 0.975106 270)
			(size 0.4064 1.3716)
			(layers "F.Cu" "F.Mask" "F.Paste")
			(net "HP_LVC3_OCP_V3_2_PRSNT2_N")
		)
		(pad "9" smd rect
			(at -2.925064 1.625092 270)
			(size 0.4064 1.3716)
			(layers "F.Cu" "F.Mask" "F.Paste")
			(net "TP_PCA9555_U51_P05")
		)
		(pad "10" smd rect
			(at -2.925064 2.275078 270)
			(size 0.4064 1.3716)
			(layers "F.Cu" "F.Mask" "F.Paste")
			(net "TP_PCA9555_U51_P06")
		)
		(pad "11" smd rect
			(at -2.925064 2.925064 270)
			(size 0.4064 1.3716)
			(layers "F.Cu" "F.Mask" "F.Paste")
			(net "TP_PCA9555_U51_P07")
		)
		(pad "12" smd rect
			(at -2.925064 3.674872 270)
			(size 0.6096 1.3716)
			(layers "F.Cu" "F.Mask" "F.Paste")
			(net "GND")
		)
		(pad "13" smd rect
			(at 2.925064 3.674872 270)
			(size 0.6096 1.3716)
			(layers "F.Cu" "F.Mask" "F.Paste")
			(net "TP_PCA9555_U51_P10")
		)
		(pad "14" smd rect
			(at 2.925064 2.925064 270)
			(size 0.4064 1.3716)
			(layers "F.Cu" "F.Mask" "F.Paste")
			(net "TP_PCA9555_U51_P11")
		)
		(pad "15" smd rect
			(at 2.925064 2.275078 270)
			(size 0.4064 1.3716)
			(layers "F.Cu" "F.Mask" "F.Paste")
			(net "TP_PCA9555_U51_P12")
		)
		(pad "16" smd rect
			(at 2.925064 1.625092 270)
			(size 0.4064 1.3716)
			(layers "F.Cu" "F.Mask" "F.Paste")
			(net "TP_PCA9555_U51_P13")
		)
		(pad "17" smd rect
			(at 2.925064 0.975106 270)
			(size 0.4064 1.3716)
			(layers "F.Cu" "F.Mask" "F.Paste")
			(net "TP_PCA9555_U51_P14")
		)
		(pad "18" smd rect
			(at 2.925064 0.32512 270)
			(size 0.4064 1.3716)
			(layers "F.Cu" "F.Mask" "F.Paste")
			(net "TP_PCA9555_U51_P15")
		)
		(pad "19" smd rect
			(at 2.925064 -0.32512 270)
			(size 0.4064 1.3716)
			(layers "F.Cu" "F.Mask" "F.Paste")
			(net "TP_PCA9555_U51_P16")
		)
		(pad "20" smd rect
			(at 2.925064 -0.975106 270)
			(size 0.4064 1.3716)
			(layers "F.Cu" "F.Mask" "F.Paste")
			(net "TP_PCA9555_U51_P17")
		)
		(pad "21" smd rect
			(at 2.925064 -1.625092 270)
			(size 0.4064 1.3716)
			(layers "F.Cu" "F.Mask" "F.Paste")
			(net "PD_SMB_OCP2_HP_ADD0")
		)
		(pad "22" smd rect
			(at 2.925064 -2.275078 270)
			(size 0.4064 1.3716)
			(layers "F.Cu" "F.Mask" "F.Paste")
			(net "SMB_PEHPCPU1_LVC3_R3_SCL")
		)
		(pad "23" smd rect
			(at 2.925064 -2.925064 270)
			(size 0.4064 1.3716)
			(layers "F.Cu" "F.Mask" "F.Paste")
			(net "SMB_PEHPCPU1_LVC3_R3_SDA")
		)
		(pad "24" smd rect
			(at 2.925064 -3.674872 270)
			(size 0.6096 1.3716)
			(layers "F.Cu" "F.Mask" "F.Paste")
			(net "P3V3_AUX")
		)
	)
	(footprint ""
		(layer "F.Cu")
		(at 29.948124 -393.198858)
		(property "Reference" "R4656"
			(at 0 0 0)
			(layer "F.SilkS")
			(hide yes)
			(effects
				(font
					(size 1.27 1.27)
				)
			)
		)
		(property "Value" ""
			(at 0 0 0)
			(layer "F.Fab")
			(effects
				(font
					(size 1.27 1.27)
				)
			)
		)
		(duplicate_pad_numbers_are_jumpers no)
		(fp_line
			(start -0.7874 -0.4064)
			(end 0.7874 -0.4064)
			(stroke
				(width 0.1524)
				(type default)
			)
			(layer "F.SilkS")
		)
		(fp_line
			(start -0.7874 0.4064)
			(end -0.7874 -0.4064)
			(stroke
				(width 0.1524)
				(type default)
			)
			(layer "F.SilkS")
		)
		(fp_line
			(start 0.7874 -0.4064)
			(end 0.7874 0.4064)
			(stroke
				(width 0.1524)
				(type default)
			)
			(layer "F.SilkS")
		)
		(fp_line
			(start 0.7874 0.4064)
			(end -0.7874 0.4064)
			(stroke
				(width 0.1524)
				(type default)
			)
			(layer "F.SilkS")
		)
		(fp_line
			(start -0.67945 -0.305054)
			(end -0.12065 -0.305054)
			(stroke
				(width 0.1)
				(type default)
			)
			(layer "F.Fab")
		)
		(fp_line
			(start -0.67945 0.3048)
			(end -0.67945 -0.305054)
			(stroke
				(width 0.1)
				(type default)
			)
			(layer "F.Fab")
		)
		(fp_line
			(start -0.12065 -0.305054)
			(end -0.12065 -0.2794)
			(stroke
				(width 0.1)
				(type default)
			)
			(layer "F.Fab")
		)
		(fp_line
			(start -0.12065 -0.2794)
			(end 0.12065 -0.2794)
			(stroke
				(width 0.1)
				(type default)
			)
			(layer "F.Fab")
		)
		(fp_line
			(start -0.12065 0.2794)
			(end -0.12065 0.3048)
			(stroke
				(width 0.1)
				(type default)
			)
			(layer "F.Fab")
		)
		(fp_line
			(start -0.12065 0.3048)
			(end -0.67945 0.3048)
			(stroke
				(width 0.1)
				(type default)
			)
			(layer "F.Fab")
		)
		(fp_line
			(start 0.120396 0.2794)
			(end -0.12065 0.2794)
			(stroke
				(width 0.1)
				(type default)
			)
			(layer "F.Fab")
		)
		(fp_line
			(start 0.120396 0.3048)
			(end 0.120396 0.2794)
			(stroke
				(width 0.1)
				(type default)
			)
			(layer "F.Fab")
		)
		(fp_line
			(start 0.12065 -0.3048)
			(end 0.67945 -0.3048)
			(stroke
				(width 0.1)
				(type default)
			)
			(layer "F.Fab")
		)
		(fp_line
			(start 0.12065 -0.2794)
			(end 0.12065 -0.3048)
			(stroke
				(width 0.1)
				(type default)
			)
			(layer "F.Fab")
		)
		(fp_line
			(start 0.67945 -0.3048)
			(end 0.67945 0.3048)
			(stroke
				(width 0.1)
				(type default)
			)
			(layer "F.Fab")
		)
		(fp_line
			(start 0.67945 0.3048)
			(end 0.120396 0.3048)
			(stroke
				(width 0.1)
				(type default)
			)
			(layer "F.Fab")
		)
		(pad "1" smd circle
			(at -0.40005 0)
			(size 0 0)
			(layers "F.Cu" "F.Mask" "F.Paste")
			(net "P3V3_AUX")
		)
		(pad "2" smd circle
			(at 0.40005 0)
			(size 0 0)
			(layers "F.Cu" "F.Mask" "F.Paste")
			(net "FM_P2E_BUF2_SD_TH")
		)
	)
	(footprint ""
		(layer "F.Cu")
		(at 131.364736 -118.226078 -90)
		(property "Reference" "U50"
			(at 1.24968 -2.246884 0)
			(unlocked yes)
			(layer "F.SilkS")
			(effects
				(font
					(size 0.7874 0.5842)
					(thickness 0.1524)
				)
				(justify left)
			)
		)
		(property "Value" ""
			(at 0 0 270)
			(layer "F.Fab")
			(effects
				(font
					(size 1.27 1.27)
				)
			)
		)
		(duplicate_pad_numbers_are_jumpers no)
		(fp_line
			(start -1.733296 1.549908)
			(end 1.733296 1.549908)
			(stroke
				(width 0.1524)
				(type default)
			)
			(layer "F.SilkS")
		)
		(fp_line
			(start 1.733296 1.549908)
			(end 1.733296 -1.549908)
			(stroke
				(width 0.1524)
				(type default)
			)
			(layer "F.SilkS")
		)
		(fp_line
			(start 0 -0.889)
			(end -0.660908 -1.549908)
			(stroke
				(width 0.1524)
				(type default)
			)
			(layer "F.SilkS")
		)
		(fp_line
			(start -1.733296 -1.549908)
			(end -1.733296 1.549908)
			(stroke
				(width 0.1524)
				(type default)
			)
			(layer "F.SilkS")
		)
		(fp_line
			(start -0.660908 -1.549908)
			(end -1.733296 -1.549908)
			(stroke
				(width 0.1524)
				(type default)
			)
			(layer "F.SilkS")
		)
		(fp_line
			(start 0.660908 -1.549908)
			(end 0 -0.889)
			(stroke
				(width 0.1524)
				(type default)
			)
			(layer "F.SilkS")
		)
		(fp_line
			(start 1.733296 -1.549908)
			(end 0.660908 -1.549908)
			(stroke
				(width 0.1524)
				(type default)
			)
			(layer "F.SilkS")
		)
		(fp_poly
			(pts
				(xy -2.41046 -1.18618) (xy -1.90246 -0.93218) (xy -2.41046 -0.67818)
			)
			(stroke
				(width 0)
				(type default)
			)
			(fill yes)
			(layer "F.SilkS")
		)
		(fp_line
			(start -0.849884 1.549908)
			(end 0.849884 1.549908)
			(stroke
				(width 0.1)
				(type default)
			)
			(layer "F.Fab")
		)
		(fp_line
			(start 0.849884 1.549908)
			(end 0.849884 -1.549908)
			(stroke
				(width 0.1)
				(type default)
			)
			(layer "F.Fab")
		)
		(fp_line
			(start -0.849884 -1.549908)
			(end -0.849884 1.549908)
			(stroke
				(width 0.1)
				(type default)
			)
			(layer "F.Fab")
		)
		(fp_line
			(start 0.849884 -1.549908)
			(end -0.849884 -1.549908)
			(stroke
				(width 0.1)
				(type default)
			)
			(layer "F.Fab")
		)
		(fp_poly
			(pts
				(xy -2.4384 -1.20396) (xy -2.4384 -0.69596) (xy -1.9304 -0.94996)
			)
			(stroke
				(width 0)
				(type default)
			)
			(fill yes)
			(layer "F.Fab")
		)
		(pad "1" smd rect
			(at -1.199896 -0.94996 180)
			(size 0.5588 0.8128)
			(layers "F.Cu" "F.Mask" "F.Paste")
			(net "HP_OCP_V3_2_EN")
		)
		(pad "2" smd rect
			(at -1.199896 0 180)
			(size 0.5588 0.8128)
			(layers "F.Cu" "F.Mask" "F.Paste")
			(net "HP_LVC3_OCP_V3_2_PRSNT2")
		)
		(pad "3" smd rect
			(at -1.199896 0.94996 180)
			(size 0.5588 0.8128)
			(layers "F.Cu" "F.Mask" "F.Paste")
			(net "GND")
		)
		(pad "4" smd rect
			(at 1.199896 0.94996 180)
			(size 0.5588 0.8128)
			(layers "F.Cu" "F.Mask" "F.Paste")
			(net "HP_LVC3_OCP_V3_2_EN")
		)
		(pad "5" smd rect
			(at 1.199896 -0.94996 180)
			(size 0.5588 0.8128)
			(layers "F.Cu" "F.Mask" "F.Paste")
			(net "P3V3_AUX")
		)
	)
	(footprint ""
		(layer "F.Cu")
		(at 184.96788 -99.659948 -90)
		(property "Reference" "R130"
			(at 0 0 270)
			(layer "F.SilkS")
			(hide yes)
			(effects
				(font
					(size 1.27 1.27)
				)
			)
		)
		(property "Value" ""
			(at 0 0 270)
			(layer "F.Fab")
			(effects
				(font
					(size 1.27 1.27)
				)
			)
		)
		(duplicate_pad_numbers_are_jumpers no)
		(fp_line
			(start -0.7874 0.4064)
			(end -0.7874 -0.4064)
			(stroke
				(width 0.1524)
				(type default)
			)
			(layer "F.SilkS")
		)
		(fp_line
			(start 0.7874 0.4064)
			(end -0.7874 0.4064)
			(stroke
				(width 0.1524)
				(type default)
			)
			(layer "F.SilkS")
		)
		(fp_line
			(start -0.7874 -0.4064)
			(end 0.7874 -0.4064)
			(stroke
				(width 0.1524)
				(type default)
			)
			(layer "F.SilkS")
		)
		(fp_line
			(start 0.7874 -0.4064)
			(end 0.7874 0.4064)
			(stroke
				(width 0.1524)
				(type default)
			)
			(layer "F.SilkS")
		)
		(fp_line
			(start -0.67945 0.3048)
			(end -0.67945 -0.305054)
			(stroke
				(width 0.1)
				(type default)
			)
			(layer "F.Fab")
		)
		(fp_line
			(start -0.12065 0.3048)
			(end -0.67945 0.3048)
			(stroke
				(width 0.1)
				(type default)
			)
			(layer "F.Fab")
		)
		(fp_line
			(start 0.120396 0.3048)
			(end 0.120396 0.2794)
			(stroke
				(width 0.1)
				(type default)
			)
			(layer "F.Fab")
		)
		(fp_line
			(start 0.67945 0.3048)
			(end 0.120396 0.3048)
			(stroke
				(width 0.1)
				(type default)
			)
			(layer "F.Fab")
		)
		(fp_line
			(start -0.12065 0.2794)
			(end -0.12065 0.3048)
			(stroke
				(width 0.1)
				(type default)
			)
			(layer "F.Fab")
		)
		(fp_line
			(start 0.120396 0.2794)
			(end -0.12065 0.2794)
			(stroke
				(width 0.1)
				(type default)
			)
			(layer "F.Fab")
		)
		(fp_line
			(start -0.12065 -0.2794)
			(end 0.12065 -0.2794)
			(stroke
				(width 0.1)
				(type default)
			)
			(layer "F.Fab")
		)
		(fp_line
			(start 0.12065 -0.2794)
			(end 0.12065 -0.3048)
			(stroke
				(width 0.1)
				(type default)
			)
			(layer "F.Fab")
		)
		(fp_line
			(start 0.12065 -0.3048)
			(end 0.67945 -0.3048)
			(stroke
				(width 0.1)
				(type default)
			)
			(layer "F.Fab")
		)
		(fp_line
			(start 0.67945 -0.3048)
			(end 0.67945 0.3048)
			(stroke
				(width 0.1)
				(type default)
			)
			(layer "F.Fab")
		)
		(fp_line
			(start -0.67945 -0.305054)
			(end -0.12065 -0.305054)
			(stroke
				(width 0.1)
				(type default)
			)
			(layer "F.Fab")
		)
		(fp_line
			(start -0.12065 -0.305054)
			(end -0.12065 -0.2794)
			(stroke
				(width 0.1)
				(type default)
			)
			(layer "F.Fab")
		)
		(pad "1" smd circle
			(at -0.40005 0 270)
			(size 0 0)
			(layers "F.Cu" "F.Mask" "F.Paste")
			(net "PWRGD_CPU1_LVC1_R")
		)
		(pad "2" smd circle
			(at 0.40005 0 270)
			(size 0 0)
			(layers "F.Cu" "F.Mask" "F.Paste")
			(net "PWRGD_CPU1_BUF_R")
		)
	)
	(footprint ""
		(layer "F.Cu")
		(at 185.928762 -25.899872 180)
		(property "Reference" "PR4004"
			(at 0 0 180)
			(layer "F.SilkS")
			(hide yes)
			(effects
				(font
					(size 1.27 1.27)
				)
			)
		)
		(property "Value" ""
			(at 0 0 180)
			(layer "F.Fab")
			(effects
				(font
					(size 1.27 1.27)
				)
			)
		)
		(duplicate_pad_numbers_are_jumpers no)
		(fp_line
			(start 0.7874 0.4064)
			(end -0.7874 0.4064)
			(stroke
				(width 0.1524)
				(type default)
			)
			(layer "F.SilkS")
		)
		(fp_line
			(start 0.7874 -0.4064)
			(end 0.7874 0.4064)
			(stroke
				(width 0.1524)
				(type default)
			)
			(layer "F.SilkS")
		)
		(fp_line
			(start -0.7874 0.4064)
			(end -0.7874 -0.4064)
			(stroke
				(width 0.1524)
				(type default)
			)
			(layer "F.SilkS")
		)
		(fp_line
			(start -0.7874 -0.4064)
			(end 0.7874 -0.4064)
			(stroke
				(width 0.1524)
				(type default)
			)
			(layer "F.SilkS")
		)
		(fp_line
			(start 0.67945 0.3048)
			(end 0.120396 0.3048)
			(stroke
				(width 0.1)
				(type default)
			)
			(layer "F.Fab")
		)
		(fp_line
			(start 0.67945 -0.3048)
			(end 0.67945 0.3048)
			(stroke
				(width 0.1)
				(type default)
			)
			(layer "F.Fab")
		)
		(fp_line
			(start 0.12065 -0.2794)
			(end 0.12065 -0.3048)
			(stroke
				(width 0.1)
				(type default)
			)
			(layer "F.Fab")
		)
		(fp_line
			(start 0.12065 -0.3048)
			(end 0.67945 -0.3048)
			(stroke
				(width 0.1)
				(type default)
			)
			(layer "F.Fab")
		)
		(fp_line
			(start 0.120396 0.3048)
			(end 0.120396 0.2794)
			(stroke
				(width 0.1)
				(type default)
			)
			(layer "F.Fab")
		)
		(fp_line
			(start 0.120396 0.2794)
			(end -0.12065 0.2794)
			(stroke
				(width 0.1)
				(type default)
			)
			(layer "F.Fab")
		)
		(fp_line
			(start -0.12065 0.3048)
			(end -0.67945 0.3048)
			(stroke
				(width 0.1)
				(type default)
			)
			(layer "F.Fab")
		)
		(fp_line
			(start -0.12065 0.2794)
			(end -0.12065 0.3048)
			(stroke
				(width 0.1)
				(type default)
			)
			(layer "F.Fab")
		)
		(fp_line
			(start -0.12065 -0.2794)
			(end 0.12065 -0.2794)
			(stroke
				(width 0.1)
				(type default)
			)
			(layer "F.Fab")
		)
		(fp_line
			(start -0.12065 -0.305054)
			(end -0.12065 -0.2794)
			(stroke
				(width 0.1)
				(type default)
			)
			(layer "F.Fab")
		)
		(fp_line
			(start -0.67945 0.3048)
			(end -0.67945 -0.305054)
			(stroke
				(width 0.1)
				(type default)
			)
			(layer "F.Fab")
		)
		(fp_line
			(start -0.67945 -0.305054)
			(end -0.12065 -0.305054)
			(stroke
				(width 0.1)
				(type default)
			)
			(layer "F.Fab")
		)
		(pad "1" smd circle
			(at -0.40005 0 180)
			(size 0 0)
			(layers "F.Cu" "F.Mask" "F.Paste")
			(net "P12V_SCM_CB")
		)
		(pad "2" smd circle
			(at 0.40005 0 180)
			(size 0 0)
			(layers "F.Cu" "F.Mask" "F.Paste")
			(net "GND")
		)
	)
	(footprint ""
		(layer "F.Cu")
		(at 160.83788 -117.566948)
		(property "Reference" "R3249"
			(at 0 0 0)
			(layer "F.SilkS")
			(hide yes)
			(effects
				(font
					(size 1.27 1.27)
				)
			)
		)
		(property "Value" ""
			(at 0 0 0)
			(layer "F.Fab")
			(effects
				(font
					(size 1.27 1.27)
				)
			)
		)
		(duplicate_pad_numbers_are_jumpers no)
		(fp_line
			(start -0.7874 -0.4064)
			(end 0.7874 -0.4064)
			(stroke
				(width 0.1524)
				(type default)
			)
			(layer "F.SilkS")
		)
		(fp_line
			(start -0.7874 0.4064)
			(end -0.7874 -0.4064)
			(stroke
				(width 0.1524)
				(type default)
			)
			(layer "F.SilkS")
		)
		(fp_line
			(start 0.7874 -0.4064)
			(end 0.7874 0.4064)
			(stroke
				(width 0.1524)
				(type default)
			)
			(layer "F.SilkS")
		)
		(fp_line
			(start 0.7874 0.4064)
			(end -0.7874 0.4064)
			(stroke
				(width 0.1524)
				(type default)
			)
			(layer "F.SilkS")
		)
		(fp_line
			(start -0.67945 -0.305054)
			(end -0.12065 -0.305054)
			(stroke
				(width 0.1)
				(type default)
			)
			(layer "F.Fab")
		)
		(fp_line
			(start -0.67945 0.3048)
			(end -0.67945 -0.305054)
			(stroke
				(width 0.1)
				(type default)
			)
			(layer "F.Fab")
		)
		(fp_line
			(start -0.12065 -0.305054)
			(end -0.12065 -0.2794)
			(stroke
				(width 0.1)
				(type default)
			)
			(layer "F.Fab")
		)
		(fp_line
			(start -0.12065 -0.2794)
			(end 0.12065 -0.2794)
			(stroke
				(width 0.1)
				(type default)
			)
			(layer "F.Fab")
		)
		(fp_line
			(start -0.12065 0.2794)
			(end -0.12065 0.3048)
			(stroke
				(width 0.1)
				(type default)
			)
			(layer "F.Fab")
		)
		(fp_line
			(start -0.12065 0.3048)
			(end -0.67945 0.3048)
			(stroke
				(width 0.1)
				(type default)
			)
			(layer "F.Fab")
		)
		(fp_line
			(start 0.120396 0.2794)
			(end -0.12065 0.2794)
			(stroke
				(width 0.1)
				(type default)
			)
			(layer "F.Fab")
		)
		(fp_line
			(start 0.120396 0.3048)
			(end 0.120396 0.2794)
			(stroke
				(width 0.1)
				(type default)
			)
			(layer "F.Fab")
		)
		(fp_line
			(start 0.12065 -0.3048)
			(end 0.67945 -0.3048)
			(stroke
				(width 0.1)
				(type default)
			)
			(layer "F.Fab")
		)
		(fp_line
			(start 0.12065 -0.2794)
			(end 0.12065 -0.3048)
			(stroke
				(width 0.1)
				(type default)
			)
			(layer "F.Fab")
		)
		(fp_line
			(start 0.67945 -0.3048)
			(end 0.67945 0.3048)
			(stroke
				(width 0.1)
				(type default)
			)
			(layer "F.Fab")
		)
		(fp_line
			(start 0.67945 0.3048)
			(end 0.120396 0.3048)
			(stroke
				(width 0.1)
				(type default)
			)
			(layer "F.Fab")
		)
		(pad "1" smd circle
			(at -0.40005 0)
			(size 0 0)
			(layers "F.Cu" "F.Mask" "F.Paste")
			(net "P3V3_AUX")
		)
		(pad "2" smd circle
			(at 0.40005 0)
			(size 0 0)
			(layers "F.Cu" "F.Mask" "F.Paste")
			(net "PU_FPGA_D12_PROGRAMN")
		)
	)
	(footprint ""
		(layer "F.Cu")
		(at 297.152314 -14.506194 180)
		(property "Reference" "R4188"
			(at 0 0 180)
			(layer "F.SilkS")
			(hide yes)
			(effects
				(font
					(size 1.27 1.27)
				)
			)
		)
		(property "Value" ""
			(at 0 0 180)
			(layer "F.Fab")
			(effects
				(font
					(size 1.27 1.27)
				)
			)
		)
		(duplicate_pad_numbers_are_jumpers no)
		(fp_line
			(start 0.7874 0.4064)
			(end -0.7874 0.4064)
			(stroke
				(width 0.1524)
				(type default)
			)
			(layer "F.SilkS")
		)
		(fp_line
			(start 0.7874 -0.4064)
			(end 0.7874 0.4064)
			(stroke
				(width 0.1524)
				(type default)
			)
			(layer "F.SilkS")
		)
		(fp_line
			(start -0.7874 0.4064)
			(end -0.7874 -0.4064)
			(stroke
				(width 0.1524)
				(type default)
			)
			(layer "F.SilkS")
		)
		(fp_line
			(start -0.7874 -0.4064)
			(end 0.7874 -0.4064)
			(stroke
				(width 0.1524)
				(type default)
			)
			(layer "F.SilkS")
		)
		(fp_line
			(start 0.67945 0.3048)
			(end 0.120396 0.3048)
			(stroke
				(width 0.1)
				(type default)
			)
			(layer "F.Fab")
		)
		(fp_line
			(start 0.67945 -0.3048)
			(end 0.67945 0.3048)
			(stroke
				(width 0.1)
				(type default)
			)
			(layer "F.Fab")
		)
		(fp_line
			(start 0.12065 -0.2794)
			(end 0.12065 -0.3048)
			(stroke
				(width 0.1)
				(type default)
			)
			(layer "F.Fab")
		)
		(fp_line
			(start 0.12065 -0.3048)
			(end 0.67945 -0.3048)
			(stroke
				(width 0.1)
				(type default)
			)
			(layer "F.Fab")
		)
		(fp_line
			(start 0.120396 0.3048)
			(end 0.120396 0.2794)
			(stroke
				(width 0.1)
				(type default)
			)
			(layer "F.Fab")
		)
		(fp_line
			(start 0.120396 0.2794)
			(end -0.12065 0.2794)
			(stroke
				(width 0.1)
				(type default)
			)
			(layer "F.Fab")
		)
		(fp_line
			(start -0.12065 0.3048)
			(end -0.67945 0.3048)
			(stroke
				(width 0.1)
				(type default)
			)
			(layer "F.Fab")
		)
		(fp_line
			(start -0.12065 0.2794)
			(end -0.12065 0.3048)
			(stroke
				(width 0.1)
				(type default)
			)
			(layer "F.Fab")
		)
		(fp_line
			(start -0.12065 -0.2794)
			(end 0.12065 -0.2794)
			(stroke
				(width 0.1)
				(type default)
			)
			(layer "F.Fab")
		)
		(fp_line
			(start -0.12065 -0.305054)
			(end -0.12065 -0.2794)
			(stroke
				(width 0.1)
				(type default)
			)
			(layer "F.Fab")
		)
		(fp_line
			(start -0.67945 0.3048)
			(end -0.67945 -0.305054)
			(stroke
				(width 0.1)
				(type default)
			)
			(layer "F.Fab")
		)
		(fp_line
			(start -0.67945 -0.305054)
			(end -0.12065 -0.305054)
			(stroke
				(width 0.1)
				(type default)
			)
			(layer "F.Fab")
		)
		(pad "1" smd circle
			(at -0.40005 0 180)
			(size 0 0)
			(layers "F.Cu" "F.Mask" "F.Paste")
			(net "P3V3_AUX")
		)
		(pad "2" smd circle
			(at 0.40005 0 180)
			(size 0 0)
			(layers "F.Cu" "F.Mask" "F.Paste")
			(net "U271_1_ADD2")
		)
	)
	(footprint ""
		(layer "F.Cu")
		(at 248.845832 -39.21379 -90)
		(property "Reference" "C1277"
			(at 0 0 270)
			(layer "F.SilkS")
			(hide yes)
			(effects
				(font
					(size 1.27 1.27)
				)
			)
		)
		(property "Value" ""
			(at 0 0 270)
			(layer "F.Fab")
			(effects
				(font
					(size 1.27 1.27)
				)
			)
		)
		(duplicate_pad_numbers_are_jumpers no)
		(fp_line
			(start -1.524 0.762)
			(end -1.524 -0.762)
			(stroke
				(width 0.1524)
				(type default)
			)
			(layer "F.SilkS")
		)
		(fp_line
			(start 1.524 0.762)
			(end -1.524 0.762)
			(stroke
				(width 0.1524)
				(type default)
			)
			(layer "F.SilkS")
		)
		(fp_line
			(start -1.524 -0.762)
			(end 1.524 -0.762)
			(stroke
				(width 0.1524)
				(type default)
			)
			(layer "F.SilkS")
		)
		(fp_line
			(start 1.524 -0.762)
			(end 1.524 0.762)
			(stroke
				(width 0.1524)
				(type default)
			)
			(layer "F.SilkS")
		)
		(fp_line
			(start -1.1049 0.724916)
			(end 1.1049 0.724916)
			(stroke
				(width 0.1)
				(type default)
			)
			(layer "F.Fab")
		)
		(fp_line
			(start 1.1049 0.724916)
			(end 1.1049 -0.724916)
			(stroke
				(width 0.1)
				(type default)
			)
			(layer "F.Fab")
		)
		(fp_line
			(start -1.1049 -0.724916)
			(end -1.1049 0.724916)
			(stroke
				(width 0.1)
				(type default)
			)
			(layer "F.Fab")
		)
		(fp_line
			(start 1.1049 -0.724916)
			(end -1.1049 -0.724916)
			(stroke
				(width 0.1)
				(type default)
			)
			(layer "F.Fab")
		)
		(pad "1" smd rect
			(at -0.889 0 90)
			(size 1.016 1.27)
			(layers "F.Cu" "F.Mask" "F.Paste")
			(net "P12V_E1S_0")
		)
		(pad "2" smd rect
			(at 0.889 0 90)
			(size 1.016 1.27)
			(layers "F.Cu" "F.Mask" "F.Paste")
			(net "GND")
		)
	)
	(footprint ""
		(layer "F.Cu")
		(at 422.740074 -151.119586 180)
		(property "Reference" "PC178"
			(at 0 0 180)
			(layer "F.SilkS")
			(hide yes)
			(effects
				(font
					(size 1.27 1.27)
				)
			)
		)
		(property "Value" ""
			(at 0 0 180)
			(layer "F.Fab")
			(effects
				(font
					(size 1.27 1.27)
				)
			)
		)
		(duplicate_pad_numbers_are_jumpers no)
		(fp_line
			(start 0.7874 0.4064)
			(end -0.7874 0.4064)
			(stroke
				(width 0.1524)
				(type default)
			)
			(layer "F.SilkS")
		)
		(fp_line
			(start 0.7874 -0.4064)
			(end 0.7874 0.4064)
			(stroke
				(width 0.1524)
				(type default)
			)
			(layer "F.SilkS")
		)
		(fp_line
			(start -0.7874 0.4064)
			(end -0.7874 -0.4064)
			(stroke
				(width 0.1524)
				(type default)
			)
			(layer "F.SilkS")
		)
		(fp_line
			(start -0.7874 -0.4064)
			(end 0.7874 -0.4064)
			(stroke
				(width 0.1524)
				(type default)
			)
			(layer "F.SilkS")
		)
		(fp_line
			(start 0.67945 0.3048)
			(end 0.120396 0.3048)
			(stroke
				(width 0.1)
				(type default)
			)
			(layer "F.Fab")
		)
		(fp_line
			(start 0.67945 -0.3048)
			(end 0.67945 0.3048)
			(stroke
				(width 0.1)
				(type default)
			)
			(layer "F.Fab")
		)
		(fp_line
			(start 0.12065 -0.2794)
			(end 0.12065 -0.3048)
			(stroke
				(width 0.1)
				(type default)
			)
			(layer "F.Fab")
		)
		(fp_line
			(start 0.12065 -0.3048)
			(end 0.67945 -0.3048)
			(stroke
				(width 0.1)
				(type default)
			)
			(layer "F.Fab")
		)
		(fp_line
			(start 0.120396 0.3048)
			(end 0.120396 0.2794)
			(stroke
				(width 0.1)
				(type default)
			)
			(layer "F.Fab")
		)
		(fp_line
			(start 0.120396 0.2794)
			(end -0.12065 0.2794)
			(stroke
				(width 0.1)
				(type default)
			)
			(layer "F.Fab")
		)
		(fp_line
			(start -0.12065 0.3048)
			(end -0.67945 0.3048)
			(stroke
				(width 0.1)
				(type default)
			)
			(layer "F.Fab")
		)
		(fp_line
			(start -0.12065 0.2794)
			(end -0.12065 0.3048)
			(stroke
				(width 0.1)
				(type default)
			)
			(layer "F.Fab")
		)
		(fp_line
			(start -0.12065 -0.2794)
			(end 0.12065 -0.2794)
			(stroke
				(width 0.1)
				(type default)
			)
			(layer "F.Fab")
		)
		(fp_line
			(start -0.12065 -0.305054)
			(end -0.12065 -0.2794)
			(stroke
				(width 0.1)
				(type default)
			)
			(layer "F.Fab")
		)
		(fp_line
			(start -0.67945 0.3048)
			(end -0.67945 -0.305054)
			(stroke
				(width 0.1)
				(type default)
			)
			(layer "F.Fab")
		)
		(fp_line
			(start -0.67945 -0.305054)
			(end -0.12065 -0.305054)
			(stroke
				(width 0.1)
				(type default)
			)
			(layer "F.Fab")
		)
		(pad "1" smd circle
			(at -0.40005 0 180)
			(size 0 0)
			(layers "F.Cu" "F.Mask" "F.Paste")
			(net "SW_PVCCFA_EHV_CPU0_BOOT1_R")
		)
		(pad "2" smd circle
			(at 0.40005 0 180)
			(size 0 0)
			(layers "F.Cu" "F.Mask" "F.Paste")
			(net "SW_PVCCFA_EHV_CPU0_BOOTR1")
		)
	)
	(footprint ""
		(layer "F.Cu")
		(at 107.296204 -244.032024 90)
		(property "Reference" "C288"
			(at 0 0 90)
			(layer "F.SilkS")
			(hide yes)
			(effects
				(font
					(size 1.27 1.27)
				)
			)
		)
		(property "Value" ""
			(at 0 0 90)
			(layer "F.Fab")
			(effects
				(font
					(size 1.27 1.27)
				)
			)
		)
		(duplicate_pad_numbers_are_jumpers no)
		(fp_line
			(start 0.7874 -0.4064)
			(end 0.7874 0.4064)
			(stroke
				(width 0.1524)
				(type default)
			)
			(layer "F.SilkS")
		)
		(fp_line
			(start -0.7874 -0.4064)
			(end 0.7874 -0.4064)
			(stroke
				(width 0.1524)
				(type default)
			)
			(layer "F.SilkS")
		)
		(fp_line
			(start 0.7874 0.4064)
			(end -0.7874 0.4064)
			(stroke
				(width 0.1524)
				(type default)
			)
			(layer "F.SilkS")
		)
		(fp_line
			(start -0.7874 0.4064)
			(end -0.7874 -0.4064)
			(stroke
				(width 0.1524)
				(type default)
			)
			(layer "F.SilkS")
		)
		(fp_line
			(start -0.12065 -0.305054)
			(end -0.12065 -0.2794)
			(stroke
				(width 0.1)
				(type default)
			)
			(layer "F.Fab")
		)
		(fp_line
			(start -0.67945 -0.305054)
			(end -0.12065 -0.305054)
			(stroke
				(width 0.1)
				(type default)
			)
			(layer "F.Fab")
		)
		(fp_line
			(start 0.67945 -0.3048)
			(end 0.67945 0.3048)
			(stroke
				(width 0.1)
				(type default)
			)
			(layer "F.Fab")
		)
		(fp_line
			(start 0.12065 -0.3048)
			(end 0.67945 -0.3048)
			(stroke
				(width 0.1)
				(type default)
			)
			(layer "F.Fab")
		)
		(fp_line
			(start 0.12065 -0.2794)
			(end 0.12065 -0.3048)
			(stroke
				(width 0.1)
				(type default)
			)
			(layer "F.Fab")
		)
		(fp_line
			(start -0.12065 -0.2794)
			(end 0.12065 -0.2794)
			(stroke
				(width 0.1)
				(type default)
			)
			(layer "F.Fab")
		)
		(fp_line
			(start 0.120396 0.2794)
			(end -0.12065 0.2794)
			(stroke
				(width 0.1)
				(type default)
			)
			(layer "F.Fab")
		)
		(fp_line
			(start -0.12065 0.2794)
			(end -0.12065 0.3048)
			(stroke
				(width 0.1)
				(type default)
			)
			(layer "F.Fab")
		)
		(fp_line
			(start 0.67945 0.3048)
			(end 0.120396 0.3048)
			(stroke
				(width 0.1)
				(type default)
			)
			(layer "F.Fab")
		)
		(fp_line
			(start 0.120396 0.3048)
			(end 0.120396 0.2794)
			(stroke
				(width 0.1)
				(type default)
			)
			(layer "F.Fab")
		)
		(fp_line
			(start -0.12065 0.3048)
			(end -0.67945 0.3048)
			(stroke
				(width 0.1)
				(type default)
			)
			(layer "F.Fab")
		)
		(fp_line
			(start -0.67945 0.3048)
			(end -0.67945 -0.305054)
			(stroke
				(width 0.1)
				(type default)
			)
			(layer "F.Fab")
		)
		(pad "1" smd circle
			(at -0.40005 0 90)
			(size 0 0)
			(layers "F.Cu" "F.Mask" "F.Paste")
			(net "PVCCIN_CPU1")
		)
		(pad "2" smd circle
			(at 0.40005 0 90)
			(size 0 0)
			(layers "F.Cu" "F.Mask" "F.Paste")
			(net "GND")
		)
	)
	(footprint ""
		(layer "F.Cu")
		(at 75.705462 -39.675562)
		(property "Reference" "C2017"
			(at 0 0 0)
			(layer "F.SilkS")
			(hide yes)
			(effects
				(font
					(size 1.27 1.27)
				)
			)
		)
		(property "Value" ""
			(at 0 0 0)
			(layer "F.Fab")
			(effects
				(font
					(size 1.27 1.27)
				)
			)
		)
		(duplicate_pad_numbers_are_jumpers no)
		(fp_line
			(start -0.7874 -0.4064)
			(end 0.7874 -0.4064)
			(stroke
				(width 0.1524)
				(type default)
			)
			(layer "F.SilkS")
		)
		(fp_line
			(start -0.7874 0.4064)
			(end -0.7874 -0.4064)
			(stroke
				(width 0.1524)
				(type default)
			)
			(layer "F.SilkS")
		)
		(fp_line
			(start 0.7874 -0.4064)
			(end 0.7874 0.4064)
			(stroke
				(width 0.1524)
				(type default)
			)
			(layer "F.SilkS")
		)
		(fp_line
			(start 0.7874 0.4064)
			(end -0.7874 0.4064)
			(stroke
				(width 0.1524)
				(type default)
			)
			(layer "F.SilkS")
		)
		(fp_line
			(start -0.67945 -0.305054)
			(end -0.12065 -0.305054)
			(stroke
				(width 0.1)
				(type default)
			)
			(layer "F.Fab")
		)
		(fp_line
			(start -0.67945 0.3048)
			(end -0.67945 -0.305054)
			(stroke
				(width 0.1)
				(type default)
			)
			(layer "F.Fab")
		)
		(fp_line
			(start -0.12065 -0.305054)
			(end -0.12065 -0.2794)
			(stroke
				(width 0.1)
				(type default)
			)
			(layer "F.Fab")
		)
		(fp_line
			(start -0.12065 -0.2794)
			(end 0.12065 -0.2794)
			(stroke
				(width 0.1)
				(type default)
			)
			(layer "F.Fab")
		)
		(fp_line
			(start -0.12065 0.2794)
			(end -0.12065 0.3048)
			(stroke
				(width 0.1)
				(type default)
			)
			(layer "F.Fab")
		)
		(fp_line
			(start -0.12065 0.3048)
			(end -0.67945 0.3048)
			(stroke
				(width 0.1)
				(type default)
			)
			(layer "F.Fab")
		)
		(fp_line
			(start 0.120396 0.2794)
			(end -0.12065 0.2794)
			(stroke
				(width 0.1)
				(type default)
			)
			(layer "F.Fab")
		)
		(fp_line
			(start 0.120396 0.3048)
			(end 0.120396 0.2794)
			(stroke
				(width 0.1)
				(type default)
			)
			(layer "F.Fab")
		)
		(fp_line
			(start 0.12065 -0.3048)
			(end 0.67945 -0.3048)
			(stroke
				(width 0.1)
				(type default)
			)
			(layer "F.Fab")
		)
		(fp_line
			(start 0.12065 -0.2794)
			(end 0.12065 -0.3048)
			(stroke
				(width 0.1)
				(type default)
			)
			(layer "F.Fab")
		)
		(fp_line
			(start 0.67945 -0.3048)
			(end 0.67945 0.3048)
			(stroke
				(width 0.1)
				(type default)
			)
			(layer "F.Fab")
		)
		(fp_line
			(start 0.67945 0.3048)
			(end 0.120396 0.3048)
			(stroke
				(width 0.1)
				(type default)
			)
			(layer "F.Fab")
		)
		(pad "1" smd circle
			(at -0.40005 0)
			(size 0 0)
			(layers "F.Cu" "F.Mask" "F.Paste")
			(net "P3V3_OCP_V3_2_R")
		)
		(pad "2" smd circle
			(at 0.40005 0)
			(size 0 0)
			(layers "F.Cu" "F.Mask" "F.Paste")
			(net "GND")
		)
	)
	(footprint ""
		(layer "F.Cu")
		(at 403.951186 -61.94806)
		(property "Reference" "R777"
			(at 0 0 0)
			(layer "F.SilkS")
			(hide yes)
			(effects
				(font
					(size 1.27 1.27)
				)
			)
		)
		(property "Value" ""
			(at 0 0 0)
			(layer "F.Fab")
			(effects
				(font
					(size 1.27 1.27)
				)
			)
		)
		(duplicate_pad_numbers_are_jumpers no)
		(fp_line
			(start -0.7874 -0.4064)
			(end 0.7874 -0.4064)
			(stroke
				(width 0.1524)
				(type default)
			)
			(layer "F.SilkS")
		)
		(fp_line
			(start -0.7874 0.4064)
			(end -0.7874 -0.4064)
			(stroke
				(width 0.1524)
				(type default)
			)
			(layer "F.SilkS")
		)
		(fp_line
			(start 0.7874 -0.4064)
			(end 0.7874 0.4064)
			(stroke
				(width 0.1524)
				(type default)
			)
			(layer "F.SilkS")
		)
		(fp_line
			(start 0.7874 0.4064)
			(end -0.7874 0.4064)
			(stroke
				(width 0.1524)
				(type default)
			)
			(layer "F.SilkS")
		)
		(fp_line
			(start -0.67945 -0.305054)
			(end -0.12065 -0.305054)
			(stroke
				(width 0.1)
				(type default)
			)
			(layer "F.Fab")
		)
		(fp_line
			(start -0.67945 0.3048)
			(end -0.67945 -0.305054)
			(stroke
				(width 0.1)
				(type default)
			)
			(layer "F.Fab")
		)
		(fp_line
			(start -0.12065 -0.305054)
			(end -0.12065 -0.2794)
			(stroke
				(width 0.1)
				(type default)
			)
			(layer "F.Fab")
		)
		(fp_line
			(start -0.12065 -0.2794)
			(end 0.12065 -0.2794)
			(stroke
				(width 0.1)
				(type default)
			)
			(layer "F.Fab")
		)
		(fp_line
			(start -0.12065 0.2794)
			(end -0.12065 0.3048)
			(stroke
				(width 0.1)
				(type default)
			)
			(layer "F.Fab")
		)
		(fp_line
			(start -0.12065 0.3048)
			(end -0.67945 0.3048)
			(stroke
				(width 0.1)
				(type default)
			)
			(layer "F.Fab")
		)
		(fp_line
			(start 0.120396 0.2794)
			(end -0.12065 0.2794)
			(stroke
				(width 0.1)
				(type default)
			)
			(layer "F.Fab")
		)
		(fp_line
			(start 0.120396 0.3048)
			(end 0.120396 0.2794)
			(stroke
				(width 0.1)
				(type default)
			)
			(layer "F.Fab")
		)
		(fp_line
			(start 0.12065 -0.3048)
			(end 0.67945 -0.3048)
			(stroke
				(width 0.1)
				(type default)
			)
			(layer "F.Fab")
		)
		(fp_line
			(start 0.12065 -0.2794)
			(end 0.12065 -0.3048)
			(stroke
				(width 0.1)
				(type default)
			)
			(layer "F.Fab")
		)
		(fp_line
			(start 0.67945 -0.3048)
			(end 0.67945 0.3048)
			(stroke
				(width 0.1)
				(type default)
			)
			(layer "F.Fab")
		)
		(fp_line
			(start 0.67945 0.3048)
			(end 0.120396 0.3048)
			(stroke
				(width 0.1)
				(type default)
			)
			(layer "F.Fab")
		)
		(pad "1" smd circle
			(at -0.40005 0)
			(size 0 0)
			(layers "F.Cu" "F.Mask" "F.Paste")
			(net "JTAG_DBP_PREQ_N_R")
		)
		(pad "2" smd circle
			(at 0.40005 0)
			(size 0 0)
			(layers "F.Cu" "F.Mask" "F.Paste")
			(net "JTAG_DBP_PREQ_N")
		)
	)
	(footprint ""
		(layer "F.Cu")
		(at 56.950102 -337.022186 180)
		(property "Reference" "PR561"
			(at 0 0 180)
			(layer "F.SilkS")
			(hide yes)
			(effects
				(font
					(size 1.27 1.27)
				)
			)
		)
		(property "Value" ""
			(at 0 0 180)
			(layer "F.Fab")
			(effects
				(font
					(size 1.27 1.27)
				)
			)
		)
		(duplicate_pad_numbers_are_jumpers no)
		(fp_line
			(start 0.7874 0.4064)
			(end -0.7874 0.4064)
			(stroke
				(width 0.1524)
				(type default)
			)
			(layer "F.SilkS")
		)
		(fp_line
			(start 0.7874 -0.4064)
			(end 0.7874 0.4064)
			(stroke
				(width 0.1524)
				(type default)
			)
			(layer "F.SilkS")
		)
		(fp_line
			(start -0.7874 0.4064)
			(end -0.7874 -0.4064)
			(stroke
				(width 0.1524)
				(type default)
			)
			(layer "F.SilkS")
		)
		(fp_line
			(start -0.7874 -0.4064)
			(end 0.7874 -0.4064)
			(stroke
				(width 0.1524)
				(type default)
			)
			(layer "F.SilkS")
		)
		(fp_line
			(start 0.67945 0.3048)
			(end 0.120396 0.3048)
			(stroke
				(width 0.1)
				(type default)
			)
			(layer "F.Fab")
		)
		(fp_line
			(start 0.67945 -0.3048)
			(end 0.67945 0.3048)
			(stroke
				(width 0.1)
				(type default)
			)
			(layer "F.Fab")
		)
		(fp_line
			(start 0.12065 -0.2794)
			(end 0.12065 -0.3048)
			(stroke
				(width 0.1)
				(type default)
			)
			(layer "F.Fab")
		)
		(fp_line
			(start 0.12065 -0.3048)
			(end 0.67945 -0.3048)
			(stroke
				(width 0.1)
				(type default)
			)
			(layer "F.Fab")
		)
		(fp_line
			(start 0.120396 0.3048)
			(end 0.120396 0.2794)
			(stroke
				(width 0.1)
				(type default)
			)
			(layer "F.Fab")
		)
		(fp_line
			(start 0.120396 0.2794)
			(end -0.12065 0.2794)
			(stroke
				(width 0.1)
				(type default)
			)
			(layer "F.Fab")
		)
		(fp_line
			(start -0.12065 0.3048)
			(end -0.67945 0.3048)
			(stroke
				(width 0.1)
				(type default)
			)
			(layer "F.Fab")
		)
		(fp_line
			(start -0.12065 0.2794)
			(end -0.12065 0.3048)
			(stroke
				(width 0.1)
				(type default)
			)
			(layer "F.Fab")
		)
		(fp_line
			(start -0.12065 -0.2794)
			(end 0.12065 -0.2794)
			(stroke
				(width 0.1)
				(type default)
			)
			(layer "F.Fab")
		)
		(fp_line
			(start -0.12065 -0.305054)
			(end -0.12065 -0.2794)
			(stroke
				(width 0.1)
				(type default)
			)
			(layer "F.Fab")
		)
		(fp_line
			(start -0.67945 0.3048)
			(end -0.67945 -0.305054)
			(stroke
				(width 0.1)
				(type default)
			)
			(layer "F.Fab")
		)
		(fp_line
			(start -0.67945 -0.305054)
			(end -0.12065 -0.305054)
			(stroke
				(width 0.1)
				(type default)
			)
			(layer "F.Fab")
		)
		(pad "1" smd circle
			(at -0.40005 0 180)
			(size 0 0)
			(layers "F.Cu" "F.Mask" "F.Paste")
			(net "VSENSE_PVCCFA_EHV_FIVRA_CPU1_DP")
		)
		(pad "2" smd circle
			(at 0.40005 0 180)
			(size 0 0)
			(layers "F.Cu" "F.Mask" "F.Paste")
			(net "PVCCFA_EHV_FIVRA_CPU1")
		)
	)
	(footprint ""
		(layer "F.Cu")
		(at 228.760782 -127.399542 180)
		(property "Reference" "R563"
			(at 0 0 180)
			(layer "F.SilkS")
			(hide yes)
			(effects
				(font
					(size 1.27 1.27)
				)
			)
		)
		(property "Value" ""
			(at 0 0 180)
			(layer "F.Fab")
			(effects
				(font
					(size 1.27 1.27)
				)
			)
		)
		(duplicate_pad_numbers_are_jumpers no)
		(fp_line
			(start 0.7874 0.4064)
			(end -0.7874 0.4064)
			(stroke
				(width 0.1524)
				(type default)
			)
			(layer "F.SilkS")
		)
		(fp_line
			(start 0.7874 -0.107442)
			(end 0.7874 0.4064)
			(stroke
				(width 0.1524)
				(type default)
			)
			(layer "F.SilkS")
		)
		(fp_line
			(start -0.433578 -0.4064)
			(end 0.330962 -0.4064)
			(stroke
				(width 0.1524)
				(type default)
			)
			(layer "F.SilkS")
		)
		(fp_line
			(start -0.7874 0.4064)
			(end -0.7874 -0.041402)
			(stroke
				(width 0.1524)
				(type default)
			)
			(layer "F.SilkS")
		)
		(fp_line
			(start 0.67945 0.3048)
			(end 0.120396 0.3048)
			(stroke
				(width 0.1)
				(type default)
			)
			(layer "F.Fab")
		)
		(fp_line
			(start 0.67945 -0.3048)
			(end 0.67945 0.3048)
			(stroke
				(width 0.1)
				(type default)
			)
			(layer "F.Fab")
		)
		(fp_line
			(start 0.12065 -0.2794)
			(end 0.12065 -0.3048)
			(stroke
				(width 0.1)
				(type default)
			)
			(layer "F.Fab")
		)
		(fp_line
			(start 0.12065 -0.3048)
			(end 0.67945 -0.3048)
			(stroke
				(width 0.1)
				(type default)
			)
			(layer "F.Fab")
		)
		(fp_line
			(start 0.120396 0.3048)
			(end 0.120396 0.2794)
			(stroke
				(width 0.1)
				(type default)
			)
			(layer "F.Fab")
		)
		(fp_line
			(start 0.120396 0.2794)
			(end -0.12065 0.2794)
			(stroke
				(width 0.1)
				(type default)
			)
			(layer "F.Fab")
		)
		(fp_line
			(start -0.12065 0.3048)
			(end -0.67945 0.3048)
			(stroke
				(width 0.1)
				(type default)
			)
			(layer "F.Fab")
		)
		(fp_line
			(start -0.12065 0.2794)
			(end -0.12065 0.3048)
			(stroke
				(width 0.1)
				(type default)
			)
			(layer "F.Fab")
		)
		(fp_line
			(start -0.12065 -0.2794)
			(end 0.12065 -0.2794)
			(stroke
				(width 0.1)
				(type default)
			)
			(layer "F.Fab")
		)
		(fp_line
			(start -0.12065 -0.305054)
			(end -0.12065 -0.2794)
			(stroke
				(width 0.1)
				(type default)
			)
			(layer "F.Fab")
		)
		(fp_line
			(start -0.67945 0.3048)
			(end -0.67945 -0.305054)
			(stroke
				(width 0.1)
				(type default)
			)
			(layer "F.Fab")
		)
		(fp_line
			(start -0.67945 -0.305054)
			(end -0.12065 -0.305054)
			(stroke
				(width 0.1)
				(type default)
			)
			(layer "F.Fab")
		)
		(pad "1" smd circle
			(at -0.40005 0 180)
			(size 0 0)
			(layers "F.Cu" "F.Mask" "F.Paste")
			(net "CLK_100M_OCP_SFF_0_R_DP")
		)
		(pad "2" smd circle
			(at 0.40005 0 180)
			(size 0 0)
			(layers "F.Cu" "F.Mask" "F.Paste")
			(net "CLK_100M_OCP_SFF_0_DP")
		)
	)
	(footprint ""
		(layer "F.Cu")
		(at 398.16405 -408.517344 -90)
		(property "Reference" "C887"
			(at 0 0 270)
			(layer "F.SilkS")
			(hide yes)
			(effects
				(font
					(size 1.27 1.27)
				)
			)
		)
		(property "Value" ""
			(at 0 0 270)
			(layer "F.Fab")
			(effects
				(font
					(size 1.27 1.27)
				)
			)
		)
		(duplicate_pad_numbers_are_jumpers no)
		(fp_line
			(start -0.299974 0.150114)
			(end -0.299974 -0.150114)
			(stroke
				(width 0.1)
				(type default)
			)
			(layer "F.Fab")
		)
		(fp_line
			(start 0.299974 0.150114)
			(end -0.299974 0.150114)
			(stroke
				(width 0.1)
				(type default)
			)
			(layer "F.Fab")
		)
		(fp_line
			(start -0.299974 -0.150114)
			(end 0.299974 -0.150114)
			(stroke
				(width 0.1)
				(type default)
			)
			(layer "F.Fab")
		)
		(fp_line
			(start 0.299974 -0.150114)
			(end 0.299974 0.150114)
			(stroke
				(width 0.1)
				(type default)
			)
			(layer "F.Fab")
		)
		(pad "1" smd rect
			(at -0.2667 0 270)
			(size 0.3048 0.381)
			(layers "F.Cu" "F.Mask" "F.Paste")
			(net "P5E_CPU0_PE3_TX_C_DP<7>")
		)
		(pad "2" smd rect
			(at 0.2667 0 270)
			(size 0.3048 0.381)
			(layers "F.Cu" "F.Mask" "F.Paste")
			(net "P5E_CPU0_PE3_TX_DP<7>")
		)
	)
	(footprint ""
		(layer "F.Cu")
		(at 147.698714 -402.371052 -90)
		(property "Reference" "C761"
			(at 0 0 270)
			(layer "F.SilkS")
			(hide yes)
			(effects
				(font
					(size 1.27 1.27)
				)
			)
		)
		(property "Value" ""
			(at 0 0 270)
			(layer "F.Fab")
			(effects
				(font
					(size 1.27 1.27)
				)
			)
		)
		(duplicate_pad_numbers_are_jumpers no)
		(fp_line
			(start -0.299974 0.150114)
			(end -0.299974 -0.150114)
			(stroke
				(width 0.1)
				(type default)
			)
			(layer "F.Fab")
		)
		(fp_line
			(start 0.299974 0.150114)
			(end -0.299974 0.150114)
			(stroke
				(width 0.1)
				(type default)
			)
			(layer "F.Fab")
		)
		(fp_line
			(start -0.299974 -0.150114)
			(end 0.299974 -0.150114)
			(stroke
				(width 0.1)
				(type default)
			)
			(layer "F.Fab")
		)
		(fp_line
			(start 0.299974 -0.150114)
			(end 0.299974 0.150114)
			(stroke
				(width 0.1)
				(type default)
			)
			(layer "F.Fab")
		)
		(pad "1" smd rect
			(at -0.2667 0 270)
			(size 0.3048 0.381)
			(layers "F.Cu" "F.Mask" "F.Paste")
			(net "P5E_CPU1_PE2_TX_C_DP<6>")
		)
		(pad "2" smd rect
			(at 0.2667 0 270)
			(size 0.3048 0.381)
			(layers "F.Cu" "F.Mask" "F.Paste")
			(net "P5E_CPU1_PE2_TX_DP<6>")
		)
	)
	(footprint ""
		(layer "F.Cu")
		(at 99.388422 -414.776666 -90)
		(property "Reference" "R4203"
			(at 0 0 270)
			(layer "F.SilkS")
			(hide yes)
			(effects
				(font
					(size 1.27 1.27)
				)
			)
		)
		(property "Value" ""
			(at 0 0 270)
			(layer "F.Fab")
			(effects
				(font
					(size 1.27 1.27)
				)
			)
		)
		(duplicate_pad_numbers_are_jumpers no)
		(fp_line
			(start -0.7874 0.4064)
			(end -0.7874 -0.4064)
			(stroke
				(width 0.1524)
				(type default)
			)
			(layer "F.SilkS")
		)
		(fp_line
			(start 0.7874 0.4064)
			(end -0.7874 0.4064)
			(stroke
				(width 0.1524)
				(type default)
			)
			(layer "F.SilkS")
		)
		(fp_line
			(start -0.7874 -0.4064)
			(end 0.7874 -0.4064)
			(stroke
				(width 0.1524)
				(type default)
			)
			(layer "F.SilkS")
		)
		(fp_line
			(start 0.7874 -0.4064)
			(end 0.7874 0.4064)
			(stroke
				(width 0.1524)
				(type default)
			)
			(layer "F.SilkS")
		)
		(fp_line
			(start -0.67945 0.3048)
			(end -0.67945 -0.305054)
			(stroke
				(width 0.1)
				(type default)
			)
			(layer "F.Fab")
		)
		(fp_line
			(start -0.12065 0.3048)
			(end -0.67945 0.3048)
			(stroke
				(width 0.1)
				(type default)
			)
			(layer "F.Fab")
		)
		(fp_line
			(start 0.120396 0.3048)
			(end 0.120396 0.2794)
			(stroke
				(width 0.1)
				(type default)
			)
			(layer "F.Fab")
		)
		(fp_line
			(start 0.67945 0.3048)
			(end 0.120396 0.3048)
			(stroke
				(width 0.1)
				(type default)
			)
			(layer "F.Fab")
		)
		(fp_line
			(start -0.12065 0.2794)
			(end -0.12065 0.3048)
			(stroke
				(width 0.1)
				(type default)
			)
			(layer "F.Fab")
		)
		(fp_line
			(start 0.120396 0.2794)
			(end -0.12065 0.2794)
			(stroke
				(width 0.1)
				(type default)
			)
			(layer "F.Fab")
		)
		(fp_line
			(start -0.12065 -0.2794)
			(end 0.12065 -0.2794)
			(stroke
				(width 0.1)
				(type default)
			)
			(layer "F.Fab")
		)
		(fp_line
			(start 0.12065 -0.2794)
			(end 0.12065 -0.3048)
			(stroke
				(width 0.1)
				(type default)
			)
			(layer "F.Fab")
		)
		(fp_line
			(start 0.12065 -0.3048)
			(end 0.67945 -0.3048)
			(stroke
				(width 0.1)
				(type default)
			)
			(layer "F.Fab")
		)
		(fp_line
			(start 0.67945 -0.3048)
			(end 0.67945 0.3048)
			(stroke
				(width 0.1)
				(type default)
			)
			(layer "F.Fab")
		)
		(fp_line
			(start -0.67945 -0.305054)
			(end -0.12065 -0.305054)
			(stroke
				(width 0.1)
				(type default)
			)
			(layer "F.Fab")
		)
		(fp_line
			(start -0.12065 -0.305054)
			(end -0.12065 -0.2794)
			(stroke
				(width 0.1)
				(type default)
			)
			(layer "F.Fab")
		)
		(pad "1" smd circle
			(at -0.40005 0 270)
			(size 0 0)
			(layers "F.Cu" "F.Mask" "F.Paste")
			(net "U272_2_ADD0")
		)
		(pad "2" smd circle
			(at 0.40005 0 270)
			(size 0 0)
			(layers "F.Cu" "F.Mask" "F.Paste")
			(net "GND")
		)
	)
	(footprint ""
		(layer "F.Cu")
		(at 372.74373 -408.517344 -90)
		(property "Reference" "C870"
			(at 0 0 270)
			(layer "F.SilkS")
			(hide yes)
			(effects
				(font
					(size 1.27 1.27)
				)
			)
		)
		(property "Value" ""
			(at 0 0 270)
			(layer "F.Fab")
			(effects
				(font
					(size 1.27 1.27)
				)
			)
		)
		(duplicate_pad_numbers_are_jumpers no)
		(fp_line
			(start -0.299974 0.150114)
			(end -0.299974 -0.150114)
			(stroke
				(width 0.1)
				(type default)
			)
			(layer "F.Fab")
		)
		(fp_line
			(start 0.299974 0.150114)
			(end -0.299974 0.150114)
			(stroke
				(width 0.1)
				(type default)
			)
			(layer "F.Fab")
		)
		(fp_line
			(start -0.299974 -0.150114)
			(end 0.299974 -0.150114)
			(stroke
				(width 0.1)
				(type default)
			)
			(layer "F.Fab")
		)
		(fp_line
			(start 0.299974 -0.150114)
			(end 0.299974 0.150114)
			(stroke
				(width 0.1)
				(type default)
			)
			(layer "F.Fab")
		)
		(pad "1" smd rect
			(at -0.2667 0 270)
			(size 0.3048 0.381)
			(layers "F.Cu" "F.Mask" "F.Paste")
			(net "P5E_CPU0_PE3_TX_C_DN<15>")
		)
		(pad "2" smd rect
			(at 0.2667 0 270)
			(size 0.3048 0.381)
			(layers "F.Cu" "F.Mask" "F.Paste")
			(net "P5E_CPU0_PE3_TX_DN<15>")
		)
	)
	(footprint ""
		(layer "F.Cu")
		(at 109.744002 -333.525368 -90)
		(property "Reference" "PC526_P1_3"
			(at 0 0 270)
			(layer "F.SilkS")
			(hide yes)
			(effects
				(font
					(size 1.27 1.27)
				)
			)
		)
		(property "Value" ""
			(at 0 0 270)
			(layer "F.Fab")
			(effects
				(font
					(size 1.27 1.27)
				)
			)
		)
		(duplicate_pad_numbers_are_jumpers no)
		(fp_line
			(start -0.7874 0.4064)
			(end -0.7874 -0.4064)
			(stroke
				(width 0.1524)
				(type default)
			)
			(layer "F.SilkS")
		)
		(fp_line
			(start 0.7874 0.4064)
			(end -0.7874 0.4064)
			(stroke
				(width 0.1524)
				(type default)
			)
			(layer "F.SilkS")
		)
		(fp_line
			(start -0.7874 -0.4064)
			(end 0.7874 -0.4064)
			(stroke
				(width 0.1524)
				(type default)
			)
			(layer "F.SilkS")
		)
		(fp_line
			(start 0.7874 -0.4064)
			(end 0.7874 0.4064)
			(stroke
				(width 0.1524)
				(type default)
			)
			(layer "F.SilkS")
		)
		(fp_line
			(start -0.67945 0.3048)
			(end -0.67945 -0.305054)
			(stroke
				(width 0.1)
				(type default)
			)
			(layer "F.Fab")
		)
		(fp_line
			(start -0.12065 0.3048)
			(end -0.67945 0.3048)
			(stroke
				(width 0.1)
				(type default)
			)
			(layer "F.Fab")
		)
		(fp_line
			(start 0.120396 0.3048)
			(end 0.120396 0.2794)
			(stroke
				(width 0.1)
				(type default)
			)
			(layer "F.Fab")
		)
		(fp_line
			(start 0.67945 0.3048)
			(end 0.120396 0.3048)
			(stroke
				(width 0.1)
				(type default)
			)
			(layer "F.Fab")
		)
		(fp_line
			(start -0.12065 0.2794)
			(end -0.12065 0.3048)
			(stroke
				(width 0.1)
				(type default)
			)
			(layer "F.Fab")
		)
		(fp_line
			(start 0.120396 0.2794)
			(end -0.12065 0.2794)
			(stroke
				(width 0.1)
				(type default)
			)
			(layer "F.Fab")
		)
		(fp_line
			(start -0.12065 -0.2794)
			(end 0.12065 -0.2794)
			(stroke
				(width 0.1)
				(type default)
			)
			(layer "F.Fab")
		)
		(fp_line
			(start 0.12065 -0.2794)
			(end 0.12065 -0.3048)
			(stroke
				(width 0.1)
				(type default)
			)
			(layer "F.Fab")
		)
		(fp_line
			(start 0.12065 -0.3048)
			(end 0.67945 -0.3048)
			(stroke
				(width 0.1)
				(type default)
			)
			(layer "F.Fab")
		)
		(fp_line
			(start 0.67945 -0.3048)
			(end 0.67945 0.3048)
			(stroke
				(width 0.1)
				(type default)
			)
			(layer "F.Fab")
		)
		(fp_line
			(start -0.67945 -0.305054)
			(end -0.12065 -0.305054)
			(stroke
				(width 0.1)
				(type default)
			)
			(layer "F.Fab")
		)
		(fp_line
			(start -0.12065 -0.305054)
			(end -0.12065 -0.2794)
			(stroke
				(width 0.1)
				(type default)
			)
			(layer "F.Fab")
		)
		(pad "1" smd circle
			(at -0.40005 0 270)
			(size 0 0)
			(layers "F.Cu" "F.Mask" "F.Paste")
			(net "PVCCIN_CPU1_PVCC")
		)
		(pad "2" smd circle
			(at 0.40005 0 270)
			(size 0 0)
			(layers "F.Cu" "F.Mask" "F.Paste")
			(net "GND")
		)
	)
	(footprint ""
		(layer "F.Cu")
		(at 49.755552 -146.550634 90)
		(property "Reference" "PR1727"
			(at 0 0 90)
			(layer "F.SilkS")
			(hide yes)
			(effects
				(font
					(size 1.27 1.27)
				)
			)
		)
		(property "Value" ""
			(at 0 0 90)
			(layer "F.Fab")
			(effects
				(font
					(size 1.27 1.27)
				)
			)
		)
		(duplicate_pad_numbers_are_jumpers no)
		(fp_line
			(start 0.7874 -0.4064)
			(end 0.7874 0.4064)
			(stroke
				(width 0.1524)
				(type default)
			)
			(layer "F.SilkS")
		)
		(fp_line
			(start -0.7874 -0.4064)
			(end 0.7874 -0.4064)
			(stroke
				(width 0.1524)
				(type default)
			)
			(layer "F.SilkS")
		)
		(fp_line
			(start 0.7874 0.4064)
			(end -0.7874 0.4064)
			(stroke
				(width 0.1524)
				(type default)
			)
			(layer "F.SilkS")
		)
		(fp_line
			(start -0.7874 0.4064)
			(end -0.7874 -0.4064)
			(stroke
				(width 0.1524)
				(type default)
			)
			(layer "F.SilkS")
		)
		(fp_line
			(start -0.12065 -0.305054)
			(end -0.12065 -0.2794)
			(stroke
				(width 0.1)
				(type default)
			)
			(layer "F.Fab")
		)
		(fp_line
			(start -0.67945 -0.305054)
			(end -0.12065 -0.305054)
			(stroke
				(width 0.1)
				(type default)
			)
			(layer "F.Fab")
		)
		(fp_line
			(start 0.67945 -0.3048)
			(end 0.67945 0.3048)
			(stroke
				(width 0.1)
				(type default)
			)
			(layer "F.Fab")
		)
		(fp_line
			(start 0.12065 -0.3048)
			(end 0.67945 -0.3048)
			(stroke
				(width 0.1)
				(type default)
			)
			(layer "F.Fab")
		)
		(fp_line
			(start 0.12065 -0.2794)
			(end 0.12065 -0.3048)
			(stroke
				(width 0.1)
				(type default)
			)
			(layer "F.Fab")
		)
		(fp_line
			(start -0.12065 -0.2794)
			(end 0.12065 -0.2794)
			(stroke
				(width 0.1)
				(type default)
			)
			(layer "F.Fab")
		)
		(fp_line
			(start 0.120396 0.2794)
			(end -0.12065 0.2794)
			(stroke
				(width 0.1)
				(type default)
			)
			(layer "F.Fab")
		)
		(fp_line
			(start -0.12065 0.2794)
			(end -0.12065 0.3048)
			(stroke
				(width 0.1)
				(type default)
			)
			(layer "F.Fab")
		)
		(fp_line
			(start 0.67945 0.3048)
			(end 0.120396 0.3048)
			(stroke
				(width 0.1)
				(type default)
			)
			(layer "F.Fab")
		)
		(fp_line
			(start 0.120396 0.3048)
			(end 0.120396 0.2794)
			(stroke
				(width 0.1)
				(type default)
			)
			(layer "F.Fab")
		)
		(fp_line
			(start -0.12065 0.3048)
			(end -0.67945 0.3048)
			(stroke
				(width 0.1)
				(type default)
			)
			(layer "F.Fab")
		)
		(fp_line
			(start -0.67945 0.3048)
			(end -0.67945 -0.305054)
			(stroke
				(width 0.1)
				(type default)
			)
			(layer "F.Fab")
		)
		(pad "1" smd circle
			(at -0.40005 0 90)
			(size 0 0)
			(layers "F.Cu" "F.Mask" "F.Paste")
			(net "PVCCINFAON_CPU1_LSET2")
		)
		(pad "2" smd circle
			(at 0.40005 0 90)
			(size 0 0)
			(layers "F.Cu" "F.Mask" "F.Paste")
			(net "GND")
		)
	)
	(footprint ""
		(layer "F.Cu")
		(at 122.809 -60.035948 -90)
		(property "Reference" "R4624"
			(at 0 0 270)
			(layer "F.SilkS")
			(hide yes)
			(effects
				(font
					(size 1.27 1.27)
				)
			)
		)
		(property "Value" ""
			(at 0 0 270)
			(layer "F.Fab")
			(effects
				(font
					(size 1.27 1.27)
				)
			)
		)
		(duplicate_pad_numbers_are_jumpers no)
		(fp_line
			(start -0.7874 0.4064)
			(end -0.7874 -0.4064)
			(stroke
				(width 0.1524)
				(type default)
			)
			(layer "F.SilkS")
		)
		(fp_line
			(start 0.7874 0.4064)
			(end -0.7874 0.4064)
			(stroke
				(width 0.1524)
				(type default)
			)
			(layer "F.SilkS")
		)
		(fp_line
			(start -0.7874 -0.4064)
			(end 0.7874 -0.4064)
			(stroke
				(width 0.1524)
				(type default)
			)
			(layer "F.SilkS")
		)
		(fp_line
			(start 0.7874 -0.4064)
			(end 0.7874 0.4064)
			(stroke
				(width 0.1524)
				(type default)
			)
			(layer "F.SilkS")
		)
		(fp_line
			(start -0.67945 0.3048)
			(end -0.67945 -0.305054)
			(stroke
				(width 0.1)
				(type default)
			)
			(layer "F.Fab")
		)
		(fp_line
			(start -0.12065 0.3048)
			(end -0.67945 0.3048)
			(stroke
				(width 0.1)
				(type default)
			)
			(layer "F.Fab")
		)
		(fp_line
			(start 0.120396 0.3048)
			(end 0.120396 0.2794)
			(stroke
				(width 0.1)
				(type default)
			)
			(layer "F.Fab")
		)
		(fp_line
			(start 0.67945 0.3048)
			(end 0.120396 0.3048)
			(stroke
				(width 0.1)
				(type default)
			)
			(layer "F.Fab")
		)
		(fp_line
			(start -0.12065 0.2794)
			(end -0.12065 0.3048)
			(stroke
				(width 0.1)
				(type default)
			)
			(layer "F.Fab")
		)
		(fp_line
			(start 0.120396 0.2794)
			(end -0.12065 0.2794)
			(stroke
				(width 0.1)
				(type default)
			)
			(layer "F.Fab")
		)
		(fp_line
			(start -0.12065 -0.2794)
			(end 0.12065 -0.2794)
			(stroke
				(width 0.1)
				(type default)
			)
			(layer "F.Fab")
		)
		(fp_line
			(start 0.12065 -0.2794)
			(end 0.12065 -0.3048)
			(stroke
				(width 0.1)
				(type default)
			)
			(layer "F.Fab")
		)
		(fp_line
			(start 0.12065 -0.3048)
			(end 0.67945 -0.3048)
			(stroke
				(width 0.1)
				(type default)
			)
			(layer "F.Fab")
		)
		(fp_line
			(start 0.67945 -0.3048)
			(end 0.67945 0.3048)
			(stroke
				(width 0.1)
				(type default)
			)
			(layer "F.Fab")
		)
		(fp_line
			(start -0.67945 -0.305054)
			(end -0.12065 -0.305054)
			(stroke
				(width 0.1)
				(type default)
			)
			(layer "F.Fab")
		)
		(fp_line
			(start -0.12065 -0.305054)
			(end -0.12065 -0.2794)
			(stroke
				(width 0.1)
				(type default)
			)
			(layer "F.Fab")
		)
		(pad "1" smd circle
			(at -0.40005 0 270)
			(size 0 0)
			(layers "F.Cu" "F.Mask" "F.Paste")
			(net "JTAG_BMC_SW_OE")
		)
		(pad "2" smd circle
			(at 0.40005 0 270)
			(size 0 0)
			(layers "F.Cu" "F.Mask" "F.Paste")
			(net "JTAG_BMC_SW_R_OE")
		)
	)
	(footprint ""
		(layer "F.Cu")
		(at 384.359912 -76.14412 180)
		(property "Reference" "PU74"
			(at -2.749042 -2.999232 0)
			(unlocked yes)
			(layer "F.SilkS")
			(effects
				(font
					(size 0.7874 0.5842)
					(thickness 0.1524)
				)
				(justify left)
			)
		)
		(property "Value" ""
			(at 0 0 180)
			(layer "F.Fab")
			(effects
				(font
					(size 1.27 1.27)
				)
			)
		)
		(duplicate_pad_numbers_are_jumpers no)
		(fp_line
			(start 1.050036 1.549908)
			(end 1.050036 0.762)
			(stroke
				(width 0.1524)
				(type default)
			)
			(layer "F.SilkS")
		)
		(fp_line
			(start 1.050036 -0.762)
			(end 1.050036 -1.549908)
			(stroke
				(width 0.1524)
				(type default)
			)
			(layer "F.SilkS")
		)
		(fp_line
			(start 1.050036 -1.549908)
			(end 1.016 -1.549908)
			(stroke
				(width 0.1524)
				(type default)
			)
			(layer "F.SilkS")
		)
		(fp_line
			(start 1.016 1.549908)
			(end 1.050036 1.549908)
			(stroke
				(width 0.1524)
				(type default)
			)
			(layer "F.SilkS")
		)
		(fp_line
			(start -1.016 -1.549908)
			(end -1.050036 -1.549908)
			(stroke
				(width 0.1524)
				(type default)
			)
			(layer "F.SilkS")
		)
		(fp_line
			(start -1.050036 1.549908)
			(end -1.016 1.549908)
			(stroke
				(width 0.1524)
				(type default)
			)
			(layer "F.SilkS")
		)
		(fp_line
			(start -1.050036 0.762)
			(end -1.050036 1.549908)
			(stroke
				(width 0.1524)
				(type default)
			)
			(layer "F.SilkS")
		)
		(fp_line
			(start -1.050036 -0.2286)
			(end -1.050036 0.2286)
			(stroke
				(width 0.1524)
				(type default)
			)
			(layer "F.SilkS")
		)
		(fp_line
			(start -1.050036 -1.549908)
			(end -1.050036 -0.762)
			(stroke
				(width 0.1524)
				(type default)
			)
			(layer "F.SilkS")
		)
		(fp_poly
			(pts
				(xy -1.446022 -0.736854) (xy -1.913382 -0.89281) (xy -1.601724 -1.204468)
			)
			(stroke
				(width 0)
				(type default)
			)
			(fill yes)
			(layer "F.SilkS")
		)
		(fp_line
			(start 1.050036 1.549908)
			(end 1.050036 -1.549908)
			(stroke
				(width 0.1)
				(type default)
			)
			(layer "F.Fab")
		)
		(fp_line
			(start 1.050036 -1.549908)
			(end -1.050036 -1.549908)
			(stroke
				(width 0.1)
				(type default)
			)
			(layer "F.Fab")
		)
		(fp_line
			(start -1.050036 1.549908)
			(end 1.050036 1.549908)
			(stroke
				(width 0.1)
				(type default)
			)
			(layer "F.Fab")
		)
		(fp_line
			(start -1.050036 -1.549908)
			(end -1.050036 1.549908)
			(stroke
				(width 0.1)
				(type default)
			)
			(layer "F.Fab")
		)
		(fp_poly
			(pts
				(xy -1.851914 -0.720344) (xy -1.411224 -0.499872) (xy -1.851914 -0.279654)
			)
			(stroke
				(width 0)
				(type default)
			)
			(fill yes)
			(layer "F.Fab")
		)
		(pad "1" smd rect
			(at -0.54991 -0.499872 270)
			(size 0.254 1.4986)
			(layers "F.Cu" "F.Mask" "F.Paste")
			(net "SW_P1V8_PCH_AUX_FLT")
		)
		(pad "2" smd rect
			(at -0.54991 0.499872 270)
			(size 0.254 1.4986)
			(layers "F.Cu" "F.Mask" "F.Paste")
			(net "GND")
		)
		(pad "3" smd rect
			(at -0.750062 1.450086 180)
			(size 0.254 0.7112)
			(layers "F.Cu" "F.Mask" "F.Paste")
			(net "P1V8_PCH_AUX_VCC")
		)
		(pad "4" smd rect
			(at -0.249936 1.450086 180)
			(size 0.254 0.7112)
			(layers "F.Cu" "F.Mask" "F.Paste")
			(net "GND")
		)
		(pad "5" smd rect
			(at 0.249936 1.450086 180)
			(size 0.254 0.7112)
			(layers "F.Cu" "F.Mask" "F.Paste")
			(net "FM_PCH_P1V8_AUX_EN_R")
		)
		(pad "6" smd rect
			(at 0.750062 1.450086 180)
			(size 0.254 0.7112)
			(layers "F.Cu" "F.Mask" "F.Paste")
			(net "P1V8_PCH_AUX_VCC")
		)
		(pad "7" smd rect
			(at 0.94996 0.499872 270)
			(size 0.254 0.7112)
			(layers "F.Cu" "F.Mask" "F.Paste")
			(net "P1V8_PCH_AUX_MODE")
		)
		(pad "8" smd rect
			(at 0.54991 0 270)
			(size 0.254 1.4986)
			(layers "F.Cu" "F.Mask" "F.Paste")
			(net "SW_P1V8_PCH_AUX_SW")
		)
		(pad "9" smd rect
			(at 0.94996 -0.499872 270)
			(size 0.254 0.7112)
			(layers "F.Cu" "F.Mask" "F.Paste")
			(net "SW_P1V8_PCH_AUX_BST")
		)
		(pad "10" smd rect
			(at 0.750062 -1.450086 180)
			(size 0.254 0.7112)
			(layers "F.Cu" "F.Mask" "F.Paste")
			(net "P1V8_PCH_AUX_VCC")
		)
		(pad "11" smd rect
			(at 0.249936 -1.450086 180)
			(size 0.254 0.7112)
			(layers "F.Cu" "F.Mask" "F.Paste")
			(net "GND")
		)
		(pad "12" smd rect
			(at -0.249936 -1.450086 180)
			(size 0.254 0.7112)
			(layers "F.Cu" "F.Mask" "F.Paste")
			(net "P1V8_PCH_AUX")
		)
		(pad "13" smd rect
			(at -0.750062 -1.450086 180)
			(size 0.254 0.7112)
			(layers "F.Cu" "F.Mask" "F.Paste")
			(net "PWRGD_P1V8_PCH_AUX_R")
		)
	)
	(footprint ""
		(layer "F.Cu")
		(at 182.781448 -407.462482 90)
		(property "Reference" "R3925"
			(at 0 0 90)
			(layer "F.SilkS")
			(hide yes)
			(effects
				(font
					(size 1.27 1.27)
				)
			)
		)
		(property "Value" ""
			(at 0 0 90)
			(layer "F.Fab")
			(effects
				(font
					(size 1.27 1.27)
				)
			)
		)
		(duplicate_pad_numbers_are_jumpers no)
		(fp_line
			(start 0.7874 -0.4064)
			(end 0.7874 0.4064)
			(stroke
				(width 0.1524)
				(type default)
			)
			(layer "F.SilkS")
		)
		(fp_line
			(start -0.7874 -0.4064)
			(end 0.7874 -0.4064)
			(stroke
				(width 0.1524)
				(type default)
			)
			(layer "F.SilkS")
		)
		(fp_line
			(start 0.7874 0.4064)
			(end -0.7874 0.4064)
			(stroke
				(width 0.1524)
				(type default)
			)
			(layer "F.SilkS")
		)
		(fp_line
			(start -0.7874 0.4064)
			(end -0.7874 -0.4064)
			(stroke
				(width 0.1524)
				(type default)
			)
			(layer "F.SilkS")
		)
		(fp_line
			(start -0.12065 -0.305054)
			(end -0.12065 -0.2794)
			(stroke
				(width 0.1)
				(type default)
			)
			(layer "F.Fab")
		)
		(fp_line
			(start -0.67945 -0.305054)
			(end -0.12065 -0.305054)
			(stroke
				(width 0.1)
				(type default)
			)
			(layer "F.Fab")
		)
		(fp_line
			(start 0.67945 -0.3048)
			(end 0.67945 0.3048)
			(stroke
				(width 0.1)
				(type default)
			)
			(layer "F.Fab")
		)
		(fp_line
			(start 0.12065 -0.3048)
			(end 0.67945 -0.3048)
			(stroke
				(width 0.1)
				(type default)
			)
			(layer "F.Fab")
		)
		(fp_line
			(start 0.12065 -0.2794)
			(end 0.12065 -0.3048)
			(stroke
				(width 0.1)
				(type default)
			)
			(layer "F.Fab")
		)
		(fp_line
			(start -0.12065 -0.2794)
			(end 0.12065 -0.2794)
			(stroke
				(width 0.1)
				(type default)
			)
			(layer "F.Fab")
		)
		(fp_line
			(start 0.120396 0.2794)
			(end -0.12065 0.2794)
			(stroke
				(width 0.1)
				(type default)
			)
			(layer "F.Fab")
		)
		(fp_line
			(start -0.12065 0.2794)
			(end -0.12065 0.3048)
			(stroke
				(width 0.1)
				(type default)
			)
			(layer "F.Fab")
		)
		(fp_line
			(start 0.67945 0.3048)
			(end 0.120396 0.3048)
			(stroke
				(width 0.1)
				(type default)
			)
			(layer "F.Fab")
		)
		(fp_line
			(start 0.120396 0.3048)
			(end 0.120396 0.2794)
			(stroke
				(width 0.1)
				(type default)
			)
			(layer "F.Fab")
		)
		(fp_line
			(start -0.12065 0.3048)
			(end -0.67945 0.3048)
			(stroke
				(width 0.1)
				(type default)
			)
			(layer "F.Fab")
		)
		(fp_line
			(start -0.67945 0.3048)
			(end -0.67945 -0.305054)
			(stroke
				(width 0.1)
				(type default)
			)
			(layer "F.Fab")
		)
		(pad "1" smd circle
			(at -0.40005 0 90)
			(size 0 0)
			(layers "F.Cu" "F.Mask" "F.Paste")
			(net "IRQ_SML1_PMBUS_ALERT")
		)
		(pad "2" smd circle
			(at 0.40005 0 90)
			(size 0 0)
			(layers "F.Cu" "F.Mask" "F.Paste")
			(net "P3V3_AUX")
		)
	)
	(footprint ""
		(layer "F.Cu")
		(at 98.33864 -31.577788)
		(property "Reference" "R3519"
			(at 0 0 0)
			(layer "F.SilkS")
			(hide yes)
			(effects
				(font
					(size 1.27 1.27)
				)
			)
		)
		(property "Value" ""
			(at 0 0 0)
			(layer "F.Fab")
			(effects
				(font
					(size 1.27 1.27)
				)
			)
		)
		(duplicate_pad_numbers_are_jumpers no)
		(fp_line
			(start -0.7874 -0.4064)
			(end 0.7874 -0.4064)
			(stroke
				(width 0.1524)
				(type default)
			)
			(layer "F.SilkS")
		)
		(fp_line
			(start -0.7874 0.4064)
			(end -0.7874 -0.4064)
			(stroke
				(width 0.1524)
				(type default)
			)
			(layer "F.SilkS")
		)
		(fp_line
			(start 0.7874 -0.4064)
			(end 0.7874 0.4064)
			(stroke
				(width 0.1524)
				(type default)
			)
			(layer "F.SilkS")
		)
		(fp_line
			(start 0.7874 0.4064)
			(end -0.7874 0.4064)
			(stroke
				(width 0.1524)
				(type default)
			)
			(layer "F.SilkS")
		)
		(fp_line
			(start -0.67945 -0.305054)
			(end -0.12065 -0.305054)
			(stroke
				(width 0.1)
				(type default)
			)
			(layer "F.Fab")
		)
		(fp_line
			(start -0.67945 0.3048)
			(end -0.67945 -0.305054)
			(stroke
				(width 0.1)
				(type default)
			)
			(layer "F.Fab")
		)
		(fp_line
			(start -0.12065 -0.305054)
			(end -0.12065 -0.2794)
			(stroke
				(width 0.1)
				(type default)
			)
			(layer "F.Fab")
		)
		(fp_line
			(start -0.12065 -0.2794)
			(end 0.12065 -0.2794)
			(stroke
				(width 0.1)
				(type default)
			)
			(layer "F.Fab")
		)
		(fp_line
			(start -0.12065 0.2794)
			(end -0.12065 0.3048)
			(stroke
				(width 0.1)
				(type default)
			)
			(layer "F.Fab")
		)
		(fp_line
			(start -0.12065 0.3048)
			(end -0.67945 0.3048)
			(stroke
				(width 0.1)
				(type default)
			)
			(layer "F.Fab")
		)
		(fp_line
			(start 0.120396 0.2794)
			(end -0.12065 0.2794)
			(stroke
				(width 0.1)
				(type default)
			)
			(layer "F.Fab")
		)
		(fp_line
			(start 0.120396 0.3048)
			(end 0.120396 0.2794)
			(stroke
				(width 0.1)
				(type default)
			)
			(layer "F.Fab")
		)
		(fp_line
			(start 0.12065 -0.3048)
			(end 0.67945 -0.3048)
			(stroke
				(width 0.1)
				(type default)
			)
			(layer "F.Fab")
		)
		(fp_line
			(start 0.12065 -0.2794)
			(end 0.12065 -0.3048)
			(stroke
				(width 0.1)
				(type default)
			)
			(layer "F.Fab")
		)
		(fp_line
			(start 0.67945 -0.3048)
			(end 0.67945 0.3048)
			(stroke
				(width 0.1)
				(type default)
			)
			(layer "F.Fab")
		)
		(fp_line
			(start 0.67945 0.3048)
			(end 0.120396 0.3048)
			(stroke
				(width 0.1)
				(type default)
			)
			(layer "F.Fab")
		)
		(pad "1" smd circle
			(at -0.40005 0)
			(size 0 0)
			(layers "F.Cu" "F.Mask" "F.Paste")
			(net "P3V3_OCP_V3_2")
		)
		(pad "2" smd circle
			(at 0.40005 0)
			(size 0 0)
			(layers "F.Cu" "F.Mask" "F.Paste")
			(net "SMB_OCP_V3_2_3V3AUX_BUF_SCL")
		)
	)
	(footprint ""
		(layer "F.Cu")
		(at 450.060314 -25.10028 -90)
		(property "Reference" "PR3792"
			(at 0 0 270)
			(layer "F.SilkS")
			(hide yes)
			(effects
				(font
					(size 1.27 1.27)
				)
			)
		)
		(property "Value" ""
			(at 0 0 270)
			(layer "F.Fab")
			(effects
				(font
					(size 1.27 1.27)
				)
			)
		)
		(duplicate_pad_numbers_are_jumpers no)
		(fp_line
			(start -0.7874 0.4064)
			(end -0.7874 -0.4064)
			(stroke
				(width 0.1524)
				(type default)
			)
			(layer "F.SilkS")
		)
		(fp_line
			(start 0.7874 0.4064)
			(end -0.7874 0.4064)
			(stroke
				(width 0.1524)
				(type default)
			)
			(layer "F.SilkS")
		)
		(fp_line
			(start -0.7874 -0.4064)
			(end 0.7874 -0.4064)
			(stroke
				(width 0.1524)
				(type default)
			)
			(layer "F.SilkS")
		)
		(fp_line
			(start 0.7874 -0.4064)
			(end 0.7874 0.4064)
			(stroke
				(width 0.1524)
				(type default)
			)
			(layer "F.SilkS")
		)
		(fp_line
			(start -0.67945 0.3048)
			(end -0.67945 -0.305054)
			(stroke
				(width 0.1)
				(type default)
			)
			(layer "F.Fab")
		)
		(fp_line
			(start -0.12065 0.3048)
			(end -0.67945 0.3048)
			(stroke
				(width 0.1)
				(type default)
			)
			(layer "F.Fab")
		)
		(fp_line
			(start 0.120396 0.3048)
			(end 0.120396 0.2794)
			(stroke
				(width 0.1)
				(type default)
			)
			(layer "F.Fab")
		)
		(fp_line
			(start 0.67945 0.3048)
			(end 0.120396 0.3048)
			(stroke
				(width 0.1)
				(type default)
			)
			(layer "F.Fab")
		)
		(fp_line
			(start -0.12065 0.2794)
			(end -0.12065 0.3048)
			(stroke
				(width 0.1)
				(type default)
			)
			(layer "F.Fab")
		)
		(fp_line
			(start 0.120396 0.2794)
			(end -0.12065 0.2794)
			(stroke
				(width 0.1)
				(type default)
			)
			(layer "F.Fab")
		)
		(fp_line
			(start -0.12065 -0.2794)
			(end 0.12065 -0.2794)
			(stroke
				(width 0.1)
				(type default)
			)
			(layer "F.Fab")
		)
		(fp_line
			(start 0.12065 -0.2794)
			(end 0.12065 -0.3048)
			(stroke
				(width 0.1)
				(type default)
			)
			(layer "F.Fab")
		)
		(fp_line
			(start 0.12065 -0.3048)
			(end 0.67945 -0.3048)
			(stroke
				(width 0.1)
				(type default)
			)
			(layer "F.Fab")
		)
		(fp_line
			(start 0.67945 -0.3048)
			(end 0.67945 0.3048)
			(stroke
				(width 0.1)
				(type default)
			)
			(layer "F.Fab")
		)
		(fp_line
			(start -0.67945 -0.305054)
			(end -0.12065 -0.305054)
			(stroke
				(width 0.1)
				(type default)
			)
			(layer "F.Fab")
		)
		(fp_line
			(start -0.12065 -0.305054)
			(end -0.12065 -0.2794)
			(stroke
				(width 0.1)
				(type default)
			)
			(layer "F.Fab")
		)
		(pad "1" smd circle
			(at -0.40005 0 270)
			(size 0 0)
			(layers "F.Cu" "F.Mask" "F.Paste")
			(net "P12V_AUX")
		)
		(pad "2" smd circle
			(at 0.40005 0 270)
			(size 0 0)
			(layers "F.Cu" "F.Mask" "F.Paste")
			(net "P12V_OCP_VCC_1")
		)
	)
	(footprint ""
		(layer "F.Cu")
		(at 364.50143 -240.276888 90)
		(property "Reference" "C1041"
			(at 0 0 90)
			(layer "F.SilkS")
			(hide yes)
			(effects
				(font
					(size 1.27 1.27)
				)
			)
		)
		(property "Value" ""
			(at 0 0 90)
			(layer "F.Fab")
			(effects
				(font
					(size 1.27 1.27)
				)
			)
		)
		(duplicate_pad_numbers_are_jumpers no)
		(fp_line
			(start 0.7874 -0.4064)
			(end 0.7874 0.4064)
			(stroke
				(width 0.1524)
				(type default)
			)
			(layer "F.SilkS")
		)
		(fp_line
			(start -0.7874 -0.4064)
			(end 0.7874 -0.4064)
			(stroke
				(width 0.1524)
				(type default)
			)
			(layer "F.SilkS")
		)
		(fp_line
			(start 0.7874 0.4064)
			(end -0.7874 0.4064)
			(stroke
				(width 0.1524)
				(type default)
			)
			(layer "F.SilkS")
		)
		(fp_line
			(start -0.7874 0.4064)
			(end -0.7874 -0.4064)
			(stroke
				(width 0.1524)
				(type default)
			)
			(layer "F.SilkS")
		)
		(fp_line
			(start -0.12065 -0.305054)
			(end -0.12065 -0.2794)
			(stroke
				(width 0.1)
				(type default)
			)
			(layer "F.Fab")
		)
		(fp_line
			(start -0.67945 -0.305054)
			(end -0.12065 -0.305054)
			(stroke
				(width 0.1)
				(type default)
			)
			(layer "F.Fab")
		)
		(fp_line
			(start 0.67945 -0.3048)
			(end 0.67945 0.3048)
			(stroke
				(width 0.1)
				(type default)
			)
			(layer "F.Fab")
		)
		(fp_line
			(start 0.12065 -0.3048)
			(end 0.67945 -0.3048)
			(stroke
				(width 0.1)
				(type default)
			)
			(layer "F.Fab")
		)
		(fp_line
			(start 0.12065 -0.2794)
			(end 0.12065 -0.3048)
			(stroke
				(width 0.1)
				(type default)
			)
			(layer "F.Fab")
		)
		(fp_line
			(start -0.12065 -0.2794)
			(end 0.12065 -0.2794)
			(stroke
				(width 0.1)
				(type default)
			)
			(layer "F.Fab")
		)
		(fp_line
			(start 0.120396 0.2794)
			(end -0.12065 0.2794)
			(stroke
				(width 0.1)
				(type default)
			)
			(layer "F.Fab")
		)
		(fp_line
			(start -0.12065 0.2794)
			(end -0.12065 0.3048)
			(stroke
				(width 0.1)
				(type default)
			)
			(layer "F.Fab")
		)
		(fp_line
			(start 0.67945 0.3048)
			(end 0.120396 0.3048)
			(stroke
				(width 0.1)
				(type default)
			)
			(layer "F.Fab")
		)
		(fp_line
			(start 0.120396 0.3048)
			(end 0.120396 0.2794)
			(stroke
				(width 0.1)
				(type default)
			)
			(layer "F.Fab")
		)
		(fp_line
			(start -0.12065 0.3048)
			(end -0.67945 0.3048)
			(stroke
				(width 0.1)
				(type default)
			)
			(layer "F.Fab")
		)
		(fp_line
			(start -0.67945 0.3048)
			(end -0.67945 -0.305054)
			(stroke
				(width 0.1)
				(type default)
			)
			(layer "F.Fab")
		)
		(pad "1" smd circle
			(at -0.40005 0 90)
			(size 0 0)
			(layers "F.Cu" "F.Mask" "F.Paste")
			(net "PVCCIN_CPU0")
		)
		(pad "2" smd circle
			(at 0.40005 0 90)
			(size 0 0)
			(layers "F.Cu" "F.Mask" "F.Paste")
			(net "GND")
		)
	)
	(footprint ""
		(layer "F.Cu")
		(at 83.996276 -79.078836)
		(property "Reference" "D73"
			(at -42.90441 34.331402 90)
			(unlocked yes)
			(layer "F.SilkS")
			(effects
				(font
					(size 0.635 0.4064)
					(thickness 0.1524)
				)
				(justify left)
			)
		)
		(property "Value" ""
			(at 0 0 0)
			(layer "F.Fab")
			(effects
				(font
					(size 1.27 1.27)
				)
			)
		)
		(duplicate_pad_numbers_are_jumpers no)
		(fp_line
			(start -0.90678 0.4826)
			(end -0.90678 -0.4699)
			(stroke
				(width 0.1524)
				(type default)
			)
			(layer "F.SilkS")
		)
		(fp_line
			(start -0.89408 -0.4826)
			(end 0.90678 -0.4826)
			(stroke
				(width 0.1524)
				(type default)
			)
			(layer "F.SilkS")
		)
		(fp_line
			(start -0.79248 -0.4826)
			(end 1.03378 -0.4826)
			(stroke
				(width 0.1524)
				(type default)
			)
			(layer "F.SilkS")
		)
		(fp_line
			(start -0.64008 -0.4826)
			(end 1.16078 -0.4826)
			(stroke
				(width 0.1524)
				(type default)
			)
			(layer "F.SilkS")
		)
		(fp_line
			(start 0.90678 -0.4826)
			(end 0.90678 0.4826)
			(stroke
				(width 0.1524)
				(type default)
			)
			(layer "F.SilkS")
		)
		(fp_line
			(start 0.90678 0.4826)
			(end -0.90678 0.4826)
			(stroke
				(width 0.1524)
				(type default)
			)
			(layer "F.SilkS")
		)
		(fp_line
			(start 1.03378 -0.4826)
			(end 1.03378 0.4826)
			(stroke
				(width 0.1524)
				(type default)
			)
			(layer "F.SilkS")
		)
		(fp_line
			(start 1.03378 0.4826)
			(end -0.79248 0.4826)
			(stroke
				(width 0.1524)
				(type default)
			)
			(layer "F.SilkS")
		)
		(fp_line
			(start 1.16078 -0.4826)
			(end 1.16078 0.4826)
			(stroke
				(width 0.1524)
				(type default)
			)
			(layer "F.SilkS")
		)
		(fp_line
			(start 1.16078 0.4826)
			(end -0.64008 0.4826)
			(stroke
				(width 0.1524)
				(type default)
			)
			(layer "F.SilkS")
		)
		(fp_line
			(start -0.499872 -0.249936)
			(end 0.499872 -0.249936)
			(stroke
				(width 0.1)
				(type default)
			)
			(layer "F.Fab")
		)
		(fp_line
			(start -0.499872 0.249936)
			(end -0.499872 -0.249936)
			(stroke
				(width 0.1)
				(type default)
			)
			(layer "F.Fab")
		)
		(fp_line
			(start 0.499872 -0.249936)
			(end 0.499872 0.249936)
			(stroke
				(width 0.1)
				(type default)
			)
			(layer "F.Fab")
		)
		(fp_line
			(start 0.499872 0.249936)
			(end -0.499872 0.249936)
			(stroke
				(width 0.1)
				(type default)
			)
			(layer "F.Fab")
		)
		(pad "A" smd rect
			(at -0.47498 0)
			(size 0.6096 0.7112)
			(layers "F.Cu" "F.Mask" "F.Paste")
			(net "LED_PWRGD_PVCCD_HV_CPU0")
		)
		(pad "C" smd rect
			(at 0.47498 0)
			(size 0.6096 0.7112)
			(layers "F.Cu" "F.Mask" "F.Paste")
			(net "LED_PWRGD_PVCCD_HV_CPU0_D")
		)
	)
	(footprint ""
		(layer "F.Cu")
		(at 46.582584 -107.031282 180)
		(property "Reference" "R2907"
			(at 0 0 180)
			(layer "F.SilkS")
			(hide yes)
			(effects
				(font
					(size 1.27 1.27)
				)
			)
		)
		(property "Value" ""
			(at 0 0 180)
			(layer "F.Fab")
			(effects
				(font
					(size 1.27 1.27)
				)
			)
		)
		(duplicate_pad_numbers_are_jumpers no)
		(fp_line
			(start 0.7874 0.4064)
			(end -0.7874 0.4064)
			(stroke
				(width 0.1524)
				(type default)
			)
			(layer "F.SilkS")
		)
		(fp_line
			(start 0.7874 -0.4064)
			(end 0.7874 0.4064)
			(stroke
				(width 0.1524)
				(type default)
			)
			(layer "F.SilkS")
		)
		(fp_line
			(start -0.7874 0.4064)
			(end -0.7874 -0.4064)
			(stroke
				(width 0.1524)
				(type default)
			)
			(layer "F.SilkS")
		)
		(fp_line
			(start -0.7874 -0.4064)
			(end 0.7874 -0.4064)
			(stroke
				(width 0.1524)
				(type default)
			)
			(layer "F.SilkS")
		)
		(fp_line
			(start 0.67945 0.3048)
			(end 0.120396 0.3048)
			(stroke
				(width 0.1)
				(type default)
			)
			(layer "F.Fab")
		)
		(fp_line
			(start 0.67945 -0.3048)
			(end 0.67945 0.3048)
			(stroke
				(width 0.1)
				(type default)
			)
			(layer "F.Fab")
		)
		(fp_line
			(start 0.12065 -0.2794)
			(end 0.12065 -0.3048)
			(stroke
				(width 0.1)
				(type default)
			)
			(layer "F.Fab")
		)
		(fp_line
			(start 0.12065 -0.3048)
			(end 0.67945 -0.3048)
			(stroke
				(width 0.1)
				(type default)
			)
			(layer "F.Fab")
		)
		(fp_line
			(start 0.120396 0.3048)
			(end 0.120396 0.2794)
			(stroke
				(width 0.1)
				(type default)
			)
			(layer "F.Fab")
		)
		(fp_line
			(start 0.120396 0.2794)
			(end -0.12065 0.2794)
			(stroke
				(width 0.1)
				(type default)
			)
			(layer "F.Fab")
		)
		(fp_line
			(start -0.12065 0.3048)
			(end -0.67945 0.3048)
			(stroke
				(width 0.1)
				(type default)
			)
			(layer "F.Fab")
		)
		(fp_line
			(start -0.12065 0.2794)
			(end -0.12065 0.3048)
			(stroke
				(width 0.1)
				(type default)
			)
			(layer "F.Fab")
		)
		(fp_line
			(start -0.12065 -0.2794)
			(end 0.12065 -0.2794)
			(stroke
				(width 0.1)
				(type default)
			)
			(layer "F.Fab")
		)
		(fp_line
			(start -0.12065 -0.305054)
			(end -0.12065 -0.2794)
			(stroke
				(width 0.1)
				(type default)
			)
			(layer "F.Fab")
		)
		(fp_line
			(start -0.67945 0.3048)
			(end -0.67945 -0.305054)
			(stroke
				(width 0.1)
				(type default)
			)
			(layer "F.Fab")
		)
		(fp_line
			(start -0.67945 -0.305054)
			(end -0.12065 -0.305054)
			(stroke
				(width 0.1)
				(type default)
			)
			(layer "F.Fab")
		)
		(pad "1" smd circle
			(at -0.40005 0 180)
			(size 0 0)
			(layers "F.Cu" "F.Mask" "F.Paste")
			(net "P3V3_AUX")
		)
		(pad "2" smd circle
			(at 0.40005 0 180)
			(size 0 0)
			(layers "F.Cu" "F.Mask" "F.Paste")
			(net "P3V3_AUX_ADC")
		)
	)
	(footprint ""
		(layer "F.Cu")
		(at 170.732958 -358.698292)
		(property "Reference" "PR225"
			(at 0 0 0)
			(layer "F.SilkS")
			(hide yes)
			(effects
				(font
					(size 1.27 1.27)
				)
			)
		)
		(property "Value" ""
			(at 0 0 0)
			(layer "F.Fab")
			(effects
				(font
					(size 1.27 1.27)
				)
			)
		)
		(duplicate_pad_numbers_are_jumpers no)
		(fp_line
			(start -0.7874 -0.4064)
			(end 0.7874 -0.4064)
			(stroke
				(width 0.1524)
				(type default)
			)
			(layer "F.SilkS")
		)
		(fp_line
			(start -0.7874 0.4064)
			(end -0.7874 -0.4064)
			(stroke
				(width 0.1524)
				(type default)
			)
			(layer "F.SilkS")
		)
		(fp_line
			(start 0.7874 -0.4064)
			(end 0.7874 0.4064)
			(stroke
				(width 0.1524)
				(type default)
			)
			(layer "F.SilkS")
		)
		(fp_line
			(start 0.7874 0.4064)
			(end -0.7874 0.4064)
			(stroke
				(width 0.1524)
				(type default)
			)
			(layer "F.SilkS")
		)
		(fp_line
			(start -0.67945 -0.305054)
			(end -0.12065 -0.305054)
			(stroke
				(width 0.1)
				(type default)
			)
			(layer "F.Fab")
		)
		(fp_line
			(start -0.67945 0.3048)
			(end -0.67945 -0.305054)
			(stroke
				(width 0.1)
				(type default)
			)
			(layer "F.Fab")
		)
		(fp_line
			(start -0.12065 -0.305054)
			(end -0.12065 -0.2794)
			(stroke
				(width 0.1)
				(type default)
			)
			(layer "F.Fab")
		)
		(fp_line
			(start -0.12065 -0.2794)
			(end 0.12065 -0.2794)
			(stroke
				(width 0.1)
				(type default)
			)
			(layer "F.Fab")
		)
		(fp_line
			(start -0.12065 0.2794)
			(end -0.12065 0.3048)
			(stroke
				(width 0.1)
				(type default)
			)
			(layer "F.Fab")
		)
		(fp_line
			(start -0.12065 0.3048)
			(end -0.67945 0.3048)
			(stroke
				(width 0.1)
				(type default)
			)
			(layer "F.Fab")
		)
		(fp_line
			(start 0.120396 0.2794)
			(end -0.12065 0.2794)
			(stroke
				(width 0.1)
				(type default)
			)
			(layer "F.Fab")
		)
		(fp_line
			(start 0.120396 0.3048)
			(end 0.120396 0.2794)
			(stroke
				(width 0.1)
				(type default)
			)
			(layer "F.Fab")
		)
		(fp_line
			(start 0.12065 -0.3048)
			(end 0.67945 -0.3048)
			(stroke
				(width 0.1)
				(type default)
			)
			(layer "F.Fab")
		)
		(fp_line
			(start 0.12065 -0.2794)
			(end 0.12065 -0.3048)
			(stroke
				(width 0.1)
				(type default)
			)
			(layer "F.Fab")
		)
		(fp_line
			(start 0.67945 -0.3048)
			(end 0.67945 0.3048)
			(stroke
				(width 0.1)
				(type default)
			)
			(layer "F.Fab")
		)
		(fp_line
			(start 0.67945 0.3048)
			(end 0.120396 0.3048)
			(stroke
				(width 0.1)
				(type default)
			)
			(layer "F.Fab")
		)
		(pad "1" smd circle
			(at -0.40005 0)
			(size 0 0)
			(layers "F.Cu" "F.Mask" "F.Paste")
			(net "PVCCFA_EHV_FIVRA_CPU1_LSET1")
		)
		(pad "2" smd circle
			(at 0.40005 0)
			(size 0 0)
			(layers "F.Cu" "F.Mask" "F.Paste")
			(net "GND")
		)
	)
	(footprint ""
		(layer "F.Cu")
		(at 160.83788 -104.485948)
		(property "Reference" "R2846"
			(at 0 0 0)
			(layer "F.SilkS")
			(hide yes)
			(effects
				(font
					(size 1.27 1.27)
				)
			)
		)
		(property "Value" ""
			(at 0 0 0)
			(layer "F.Fab")
			(effects
				(font
					(size 1.27 1.27)
				)
			)
		)
		(duplicate_pad_numbers_are_jumpers no)
		(fp_line
			(start -0.7874 -0.4064)
			(end 0.7874 -0.4064)
			(stroke
				(width 0.1524)
				(type default)
			)
			(layer "F.SilkS")
		)
		(fp_line
			(start -0.7874 0.4064)
			(end -0.7874 -0.4064)
			(stroke
				(width 0.1524)
				(type default)
			)
			(layer "F.SilkS")
		)
		(fp_line
			(start 0.7874 -0.4064)
			(end 0.7874 0.4064)
			(stroke
				(width 0.1524)
				(type default)
			)
			(layer "F.SilkS")
		)
		(fp_line
			(start 0.7874 0.4064)
			(end -0.7874 0.4064)
			(stroke
				(width 0.1524)
				(type default)
			)
			(layer "F.SilkS")
		)
		(fp_line
			(start -0.67945 -0.305054)
			(end -0.12065 -0.305054)
			(stroke
				(width 0.1)
				(type default)
			)
			(layer "F.Fab")
		)
		(fp_line
			(start -0.67945 0.3048)
			(end -0.67945 -0.305054)
			(stroke
				(width 0.1)
				(type default)
			)
			(layer "F.Fab")
		)
		(fp_line
			(start -0.12065 -0.305054)
			(end -0.12065 -0.2794)
			(stroke
				(width 0.1)
				(type default)
			)
			(layer "F.Fab")
		)
		(fp_line
			(start -0.12065 -0.2794)
			(end 0.12065 -0.2794)
			(stroke
				(width 0.1)
				(type default)
			)
			(layer "F.Fab")
		)
		(fp_line
			(start -0.12065 0.2794)
			(end -0.12065 0.3048)
			(stroke
				(width 0.1)
				(type default)
			)
			(layer "F.Fab")
		)
		(fp_line
			(start -0.12065 0.3048)
			(end -0.67945 0.3048)
			(stroke
				(width 0.1)
				(type default)
			)
			(layer "F.Fab")
		)
		(fp_line
			(start 0.120396 0.2794)
			(end -0.12065 0.2794)
			(stroke
				(width 0.1)
				(type default)
			)
			(layer "F.Fab")
		)
		(fp_line
			(start 0.120396 0.3048)
			(end 0.120396 0.2794)
			(stroke
				(width 0.1)
				(type default)
			)
			(layer "F.Fab")
		)
		(fp_line
			(start 0.12065 -0.3048)
			(end 0.67945 -0.3048)
			(stroke
				(width 0.1)
				(type default)
			)
			(layer "F.Fab")
		)
		(fp_line
			(start 0.12065 -0.2794)
			(end 0.12065 -0.3048)
			(stroke
				(width 0.1)
				(type default)
			)
			(layer "F.Fab")
		)
		(fp_line
			(start 0.67945 -0.3048)
			(end 0.67945 0.3048)
			(stroke
				(width 0.1)
				(type default)
			)
			(layer "F.Fab")
		)
		(fp_line
			(start 0.67945 0.3048)
			(end 0.120396 0.3048)
			(stroke
				(width 0.1)
				(type default)
			)
			(layer "F.Fab")
		)
		(pad "1" smd circle
			(at -0.40005 0)
			(size 0 0)
			(layers "F.Cu" "F.Mask" "F.Paste")
			(net "BIC_MONITER_ISO")
		)
		(pad "2" smd circle
			(at 0.40005 0)
			(size 0 0)
			(layers "F.Cu" "F.Mask" "F.Paste")
			(net "BIC_MONITER_ISO_R")
		)
	)
	(footprint ""
		(layer "F.Cu")
		(at 19.19859 -385.065524 -90)
		(property "Reference" "R4661"
			(at 0 0 270)
			(layer "F.SilkS")
			(hide yes)
			(effects
				(font
					(size 1.27 1.27)
				)
			)
		)
		(property "Value" ""
			(at 0 0 270)
			(layer "F.Fab")
			(effects
				(font
					(size 1.27 1.27)
				)
			)
		)
		(duplicate_pad_numbers_are_jumpers no)
		(fp_line
			(start -0.7874 0.4064)
			(end -0.7874 -0.4064)
			(stroke
				(width 0.1524)
				(type default)
			)
			(layer "F.SilkS")
		)
		(fp_line
			(start 0.7874 0.4064)
			(end -0.7874 0.4064)
			(stroke
				(width 0.1524)
				(type default)
			)
			(layer "F.SilkS")
		)
		(fp_line
			(start 0.029464 -0.4064)
			(end 0.7874 -0.4064)
			(stroke
				(width 0.1524)
				(type default)
			)
			(layer "F.SilkS")
		)
		(fp_line
			(start -0.67945 0.3048)
			(end -0.67945 -0.305054)
			(stroke
				(width 0.1)
				(type default)
			)
			(layer "F.Fab")
		)
		(fp_line
			(start -0.12065 0.3048)
			(end -0.67945 0.3048)
			(stroke
				(width 0.1)
				(type default)
			)
			(layer "F.Fab")
		)
		(fp_line
			(start 0.120396 0.3048)
			(end 0.120396 0.2794)
			(stroke
				(width 0.1)
				(type default)
			)
			(layer "F.Fab")
		)
		(fp_line
			(start 0.67945 0.3048)
			(end 0.120396 0.3048)
			(stroke
				(width 0.1)
				(type default)
			)
			(layer "F.Fab")
		)
		(fp_line
			(start -0.12065 0.2794)
			(end -0.12065 0.3048)
			(stroke
				(width 0.1)
				(type default)
			)
			(layer "F.Fab")
		)
		(fp_line
			(start 0.120396 0.2794)
			(end -0.12065 0.2794)
			(stroke
				(width 0.1)
				(type default)
			)
			(layer "F.Fab")
		)
		(fp_line
			(start -0.12065 -0.2794)
			(end 0.12065 -0.2794)
			(stroke
				(width 0.1)
				(type default)
			)
			(layer "F.Fab")
		)
		(fp_line
			(start 0.12065 -0.2794)
			(end 0.12065 -0.3048)
			(stroke
				(width 0.1)
				(type default)
			)
			(layer "F.Fab")
		)
		(fp_line
			(start 0.12065 -0.3048)
			(end 0.67945 -0.3048)
			(stroke
				(width 0.1)
				(type default)
			)
			(layer "F.Fab")
		)
		(fp_line
			(start 0.67945 -0.3048)
			(end 0.67945 0.3048)
			(stroke
				(width 0.1)
				(type default)
			)
			(layer "F.Fab")
		)
		(fp_line
			(start -0.67945 -0.305054)
			(end -0.12065 -0.305054)
			(stroke
				(width 0.1)
				(type default)
			)
			(layer "F.Fab")
		)
		(fp_line
			(start -0.12065 -0.305054)
			(end -0.12065 -0.2794)
			(stroke
				(width 0.1)
				(type default)
			)
			(layer "F.Fab")
		)
		(pad "1" smd rect
			(at -0.40005 0 90)
			(size 0.4572 0.508)
			(layers "F.Cu" "F.Mask" "F.Paste")
			(net "P2E_MB_BMC_TX_C_DP<0>")
		)
		(pad "2" smd rect
			(at 0.40005 0 90)
			(size 0.4572 0.508)
			(layers "F.Cu" "F.Mask" "F.Paste")
			(net "P2E_MB_BMC_TX_C_R2_DP<0>")
		)
	)
	(footprint ""
		(layer "F.Cu")
		(at 377.54052 -109.720888)
		(property "Reference" "R2512"
			(at 0 0 0)
			(layer "F.SilkS")
			(hide yes)
			(effects
				(font
					(size 1.27 1.27)
				)
			)
		)
		(property "Value" ""
			(at 0 0 0)
			(layer "F.Fab")
			(effects
				(font
					(size 1.27 1.27)
				)
			)
		)
		(duplicate_pad_numbers_are_jumpers no)
		(fp_line
			(start -0.7874 -0.4064)
			(end 0.7874 -0.4064)
			(stroke
				(width 0.1524)
				(type default)
			)
			(layer "F.SilkS")
		)
		(fp_line
			(start -0.7874 0.4064)
			(end -0.7874 -0.4064)
			(stroke
				(width 0.1524)
				(type default)
			)
			(layer "F.SilkS")
		)
		(fp_line
			(start 0.7874 -0.4064)
			(end 0.7874 0.4064)
			(stroke
				(width 0.1524)
				(type default)
			)
			(layer "F.SilkS")
		)
		(fp_line
			(start 0.7874 0.4064)
			(end -0.7874 0.4064)
			(stroke
				(width 0.1524)
				(type default)
			)
			(layer "F.SilkS")
		)
		(fp_line
			(start -0.67945 -0.305054)
			(end -0.12065 -0.305054)
			(stroke
				(width 0.1)
				(type default)
			)
			(layer "F.Fab")
		)
		(fp_line
			(start -0.67945 0.3048)
			(end -0.67945 -0.305054)
			(stroke
				(width 0.1)
				(type default)
			)
			(layer "F.Fab")
		)
		(fp_line
			(start -0.12065 -0.305054)
			(end -0.12065 -0.2794)
			(stroke
				(width 0.1)
				(type default)
			)
			(layer "F.Fab")
		)
		(fp_line
			(start -0.12065 -0.2794)
			(end 0.12065 -0.2794)
			(stroke
				(width 0.1)
				(type default)
			)
			(layer "F.Fab")
		)
		(fp_line
			(start -0.12065 0.2794)
			(end -0.12065 0.3048)
			(stroke
				(width 0.1)
				(type default)
			)
			(layer "F.Fab")
		)
		(fp_line
			(start -0.12065 0.3048)
			(end -0.67945 0.3048)
			(stroke
				(width 0.1)
				(type default)
			)
			(layer "F.Fab")
		)
		(fp_line
			(start 0.120396 0.2794)
			(end -0.12065 0.2794)
			(stroke
				(width 0.1)
				(type default)
			)
			(layer "F.Fab")
		)
		(fp_line
			(start 0.120396 0.3048)
			(end 0.120396 0.2794)
			(stroke
				(width 0.1)
				(type default)
			)
			(layer "F.Fab")
		)
		(fp_line
			(start 0.12065 -0.3048)
			(end 0.67945 -0.3048)
			(stroke
				(width 0.1)
				(type default)
			)
			(layer "F.Fab")
		)
		(fp_line
			(start 0.12065 -0.2794)
			(end 0.12065 -0.3048)
			(stroke
				(width 0.1)
				(type default)
			)
			(layer "F.Fab")
		)
		(fp_line
			(start 0.67945 -0.3048)
			(end 0.67945 0.3048)
			(stroke
				(width 0.1)
				(type default)
			)
			(layer "F.Fab")
		)
		(fp_line
			(start 0.67945 0.3048)
			(end 0.120396 0.3048)
			(stroke
				(width 0.1)
				(type default)
			)
			(layer "F.Fab")
		)
		(pad "1" smd circle
			(at -0.40005 0)
			(size 0 0)
			(layers "F.Cu" "F.Mask" "F.Paste")
			(net "P1V05_PCH_AUX")
		)
		(pad "2" smd circle
			(at 0.40005 0)
			(size 0 0)
			(layers "F.Cu" "F.Mask" "F.Paste")
			(net "P0V7_JTAG_VREF_2")
		)
	)
	(footprint ""
		(layer "F.Cu")
		(at 396.81785 -402.371052 -90)
		(property "Reference" "C950"
			(at 0 0 270)
			(layer "F.SilkS")
			(hide yes)
			(effects
				(font
					(size 1.27 1.27)
				)
			)
		)
		(property "Value" ""
			(at 0 0 270)
			(layer "F.Fab")
			(effects
				(font
					(size 1.27 1.27)
				)
			)
		)
		(duplicate_pad_numbers_are_jumpers no)
		(fp_line
			(start -0.299974 0.150114)
			(end -0.299974 -0.150114)
			(stroke
				(width 0.1)
				(type default)
			)
			(layer "F.Fab")
		)
		(fp_line
			(start 0.299974 0.150114)
			(end -0.299974 0.150114)
			(stroke
				(width 0.1)
				(type default)
			)
			(layer "F.Fab")
		)
		(fp_line
			(start -0.299974 -0.150114)
			(end 0.299974 -0.150114)
			(stroke
				(width 0.1)
				(type default)
			)
			(layer "F.Fab")
		)
		(fp_line
			(start 0.299974 -0.150114)
			(end 0.299974 0.150114)
			(stroke
				(width 0.1)
				(type default)
			)
			(layer "F.Fab")
		)
		(pad "1" smd rect
			(at -0.2667 0 270)
			(size 0.3048 0.381)
			(layers "F.Cu" "F.Mask" "F.Paste")
			(net "P5E_CPU0_PE2_TX_C_DN<7>")
		)
		(pad "2" smd rect
			(at 0.2667 0 270)
			(size 0.3048 0.381)
			(layers "F.Cu" "F.Mask" "F.Paste")
			(net "P5E_CPU0_PE2_TX_DN<7>")
		)
	)
	(footprint ""
		(layer "F.Cu")
		(at 373.577358 -92.962984 90)
		(property "Reference" "R480"
			(at 0 0 90)
			(layer "F.SilkS")
			(hide yes)
			(effects
				(font
					(size 1.27 1.27)
				)
			)
		)
		(property "Value" ""
			(at 0 0 90)
			(layer "F.Fab")
			(effects
				(font
					(size 1.27 1.27)
				)
			)
		)
		(duplicate_pad_numbers_are_jumpers no)
		(fp_line
			(start 0.7874 -0.4064)
			(end 0.7874 0.4064)
			(stroke
				(width 0.1524)
				(type default)
			)
			(layer "F.SilkS")
		)
		(fp_line
			(start -0.7874 -0.4064)
			(end 0.7874 -0.4064)
			(stroke
				(width 0.1524)
				(type default)
			)
			(layer "F.SilkS")
		)
		(fp_line
			(start 0.7874 0.4064)
			(end -0.7874 0.4064)
			(stroke
				(width 0.1524)
				(type default)
			)
			(layer "F.SilkS")
		)
		(fp_line
			(start -0.7874 0.4064)
			(end -0.7874 -0.4064)
			(stroke
				(width 0.1524)
				(type default)
			)
			(layer "F.SilkS")
		)
		(fp_line
			(start -0.12065 -0.305054)
			(end -0.12065 -0.2794)
			(stroke
				(width 0.1)
				(type default)
			)
			(layer "F.Fab")
		)
		(fp_line
			(start -0.67945 -0.305054)
			(end -0.12065 -0.305054)
			(stroke
				(width 0.1)
				(type default)
			)
			(layer "F.Fab")
		)
		(fp_line
			(start 0.67945 -0.3048)
			(end 0.67945 0.3048)
			(stroke
				(width 0.1)
				(type default)
			)
			(layer "F.Fab")
		)
		(fp_line
			(start 0.12065 -0.3048)
			(end 0.67945 -0.3048)
			(stroke
				(width 0.1)
				(type default)
			)
			(layer "F.Fab")
		)
		(fp_line
			(start 0.12065 -0.2794)
			(end 0.12065 -0.3048)
			(stroke
				(width 0.1)
				(type default)
			)
			(layer "F.Fab")
		)
		(fp_line
			(start -0.12065 -0.2794)
			(end 0.12065 -0.2794)
			(stroke
				(width 0.1)
				(type default)
			)
			(layer "F.Fab")
		)
		(fp_line
			(start 0.120396 0.2794)
			(end -0.12065 0.2794)
			(stroke
				(width 0.1)
				(type default)
			)
			(layer "F.Fab")
		)
		(fp_line
			(start -0.12065 0.2794)
			(end -0.12065 0.3048)
			(stroke
				(width 0.1)
				(type default)
			)
			(layer "F.Fab")
		)
		(fp_line
			(start 0.67945 0.3048)
			(end 0.120396 0.3048)
			(stroke
				(width 0.1)
				(type default)
			)
			(layer "F.Fab")
		)
		(fp_line
			(start 0.120396 0.3048)
			(end 0.120396 0.2794)
			(stroke
				(width 0.1)
				(type default)
			)
			(layer "F.Fab")
		)
		(fp_line
			(start -0.12065 0.3048)
			(end -0.67945 0.3048)
			(stroke
				(width 0.1)
				(type default)
			)
			(layer "F.Fab")
		)
		(fp_line
			(start -0.67945 0.3048)
			(end -0.67945 -0.305054)
			(stroke
				(width 0.1)
				(type default)
			)
			(layer "F.Fab")
		)
		(pad "1" smd circle
			(at -0.40005 0 90)
			(size 0 0)
			(layers "F.Cu" "F.Mask" "F.Paste")
			(net "JTAG_DBP_TMS")
		)
		(pad "2" smd circle
			(at 0.40005 0 90)
			(size 0 0)
			(layers "F.Cu" "F.Mask" "F.Paste")
			(net "JTAG_DBP_FB_TMS")
		)
	)
	(footprint ""
		(layer "F.Cu")
		(at 420.682166 -135.146034 180)
		(property "Reference" "PC221"
			(at 0 0 180)
			(layer "F.SilkS")
			(hide yes)
			(effects
				(font
					(size 1.27 1.27)
				)
			)
		)
		(property "Value" ""
			(at 0 0 180)
			(layer "F.Fab")
			(effects
				(font
					(size 1.27 1.27)
				)
			)
		)
		(duplicate_pad_numbers_are_jumpers no)
		(fp_line
			(start 0.7874 0.4064)
			(end -0.7874 0.4064)
			(stroke
				(width 0.1524)
				(type default)
			)
			(layer "F.SilkS")
		)
		(fp_line
			(start 0.7874 -0.4064)
			(end 0.7874 0.4064)
			(stroke
				(width 0.1524)
				(type default)
			)
			(layer "F.SilkS")
		)
		(fp_line
			(start -0.7874 0.4064)
			(end -0.7874 -0.4064)
			(stroke
				(width 0.1524)
				(type default)
			)
			(layer "F.SilkS")
		)
		(fp_line
			(start -0.7874 -0.4064)
			(end 0.7874 -0.4064)
			(stroke
				(width 0.1524)
				(type default)
			)
			(layer "F.SilkS")
		)
		(fp_line
			(start 0.67945 0.3048)
			(end 0.120396 0.3048)
			(stroke
				(width 0.1)
				(type default)
			)
			(layer "F.Fab")
		)
		(fp_line
			(start 0.67945 -0.3048)
			(end 0.67945 0.3048)
			(stroke
				(width 0.1)
				(type default)
			)
			(layer "F.Fab")
		)
		(fp_line
			(start 0.12065 -0.2794)
			(end 0.12065 -0.3048)
			(stroke
				(width 0.1)
				(type default)
			)
			(layer "F.Fab")
		)
		(fp_line
			(start 0.12065 -0.3048)
			(end 0.67945 -0.3048)
			(stroke
				(width 0.1)
				(type default)
			)
			(layer "F.Fab")
		)
		(fp_line
			(start 0.120396 0.3048)
			(end 0.120396 0.2794)
			(stroke
				(width 0.1)
				(type default)
			)
			(layer "F.Fab")
		)
		(fp_line
			(start 0.120396 0.2794)
			(end -0.12065 0.2794)
			(stroke
				(width 0.1)
				(type default)
			)
			(layer "F.Fab")
		)
		(fp_line
			(start -0.12065 0.3048)
			(end -0.67945 0.3048)
			(stroke
				(width 0.1)
				(type default)
			)
			(layer "F.Fab")
		)
		(fp_line
			(start -0.12065 0.2794)
			(end -0.12065 0.3048)
			(stroke
				(width 0.1)
				(type default)
			)
			(layer "F.Fab")
		)
		(fp_line
			(start -0.12065 -0.2794)
			(end 0.12065 -0.2794)
			(stroke
				(width 0.1)
				(type default)
			)
			(layer "F.Fab")
		)
		(fp_line
			(start -0.12065 -0.305054)
			(end -0.12065 -0.2794)
			(stroke
				(width 0.1)
				(type default)
			)
			(layer "F.Fab")
		)
		(fp_line
			(start -0.67945 0.3048)
			(end -0.67945 -0.305054)
			(stroke
				(width 0.1)
				(type default)
			)
			(layer "F.Fab")
		)
		(fp_line
			(start -0.67945 -0.305054)
			(end -0.12065 -0.305054)
			(stroke
				(width 0.1)
				(type default)
			)
			(layer "F.Fab")
		)
		(pad "1" smd circle
			(at -0.40005 0 180)
			(size 0 0)
			(layers "F.Cu" "F.Mask" "F.Paste")
			(net "PVCCINFAON_CPU0_VIN_CSNIN")
		)
		(pad "2" smd circle
			(at 0.40005 0 180)
			(size 0 0)
			(layers "F.Cu" "F.Mask" "F.Paste")
			(net "GND")
		)
	)
	(footprint ""
		(layer "F.Cu")
		(at 189.79769 -36.0807)
		(property "Reference" "R1856"
			(at 0 0 0)
			(layer "F.SilkS")
			(hide yes)
			(effects
				(font
					(size 1.27 1.27)
				)
			)
		)
		(property "Value" ""
			(at 0 0 0)
			(layer "F.Fab")
			(effects
				(font
					(size 1.27 1.27)
				)
			)
		)
		(duplicate_pad_numbers_are_jumpers no)
		(fp_line
			(start -0.7874 -0.4064)
			(end 0.7874 -0.4064)
			(stroke
				(width 0.1524)
				(type default)
			)
			(layer "F.SilkS")
		)
		(fp_line
			(start -0.7874 0.4064)
			(end -0.7874 -0.4064)
			(stroke
				(width 0.1524)
				(type default)
			)
			(layer "F.SilkS")
		)
		(fp_line
			(start 0.7874 -0.4064)
			(end 0.7874 0.4064)
			(stroke
				(width 0.1524)
				(type default)
			)
			(layer "F.SilkS")
		)
		(fp_line
			(start 0.7874 0.4064)
			(end -0.7874 0.4064)
			(stroke
				(width 0.1524)
				(type default)
			)
			(layer "F.SilkS")
		)
		(fp_line
			(start -0.67945 -0.305054)
			(end -0.12065 -0.305054)
			(stroke
				(width 0.1)
				(type default)
			)
			(layer "F.Fab")
		)
		(fp_line
			(start -0.67945 0.3048)
			(end -0.67945 -0.305054)
			(stroke
				(width 0.1)
				(type default)
			)
			(layer "F.Fab")
		)
		(fp_line
			(start -0.12065 -0.305054)
			(end -0.12065 -0.2794)
			(stroke
				(width 0.1)
				(type default)
			)
			(layer "F.Fab")
		)
		(fp_line
			(start -0.12065 -0.2794)
			(end 0.12065 -0.2794)
			(stroke
				(width 0.1)
				(type default)
			)
			(layer "F.Fab")
		)
		(fp_line
			(start -0.12065 0.2794)
			(end -0.12065 0.3048)
			(stroke
				(width 0.1)
				(type default)
			)
			(layer "F.Fab")
		)
		(fp_line
			(start -0.12065 0.3048)
			(end -0.67945 0.3048)
			(stroke
				(width 0.1)
				(type default)
			)
			(layer "F.Fab")
		)
		(fp_line
			(start 0.120396 0.2794)
			(end -0.12065 0.2794)
			(stroke
				(width 0.1)
				(type default)
			)
			(layer "F.Fab")
		)
		(fp_line
			(start 0.120396 0.3048)
			(end 0.120396 0.2794)
			(stroke
				(width 0.1)
				(type default)
			)
			(layer "F.Fab")
		)
		(fp_line
			(start 0.12065 -0.3048)
			(end 0.67945 -0.3048)
			(stroke
				(width 0.1)
				(type default)
			)
			(layer "F.Fab")
		)
		(fp_line
			(start 0.12065 -0.2794)
			(end 0.12065 -0.3048)
			(stroke
				(width 0.1)
				(type default)
			)
			(layer "F.Fab")
		)
		(fp_line
			(start 0.67945 -0.3048)
			(end 0.67945 0.3048)
			(stroke
				(width 0.1)
				(type default)
			)
			(layer "F.Fab")
		)
		(fp_line
			(start 0.67945 0.3048)
			(end 0.120396 0.3048)
			(stroke
				(width 0.1)
				(type default)
			)
			(layer "F.Fab")
		)
		(pad "1" smd circle
			(at -0.40005 0)
			(size 0 0)
			(layers "F.Cu" "F.Mask" "F.Paste")
			(net "FM_SCM_PRSNT1_N")
		)
		(pad "2" smd circle
			(at 0.40005 0)
			(size 0 0)
			(layers "F.Cu" "F.Mask" "F.Paste")
			(net "FM_SCM_PRSNT1_R_N")
		)
	)
	(footprint ""
		(layer "F.Cu")
		(at 328.523092 -73.509378 90)
		(property "Reference" "R4303"
			(at 0 0 90)
			(layer "F.SilkS")
			(hide yes)
			(effects
				(font
					(size 1.27 1.27)
				)
			)
		)
		(property "Value" ""
			(at 0 0 90)
			(layer "F.Fab")
			(effects
				(font
					(size 1.27 1.27)
				)
			)
		)
		(duplicate_pad_numbers_are_jumpers no)
		(fp_line
			(start 0.7874 -0.4064)
			(end 0.7874 0.4064)
			(stroke
				(width 0.1524)
				(type default)
			)
			(layer "F.SilkS")
		)
		(fp_line
			(start -0.7874 -0.4064)
			(end 0.7874 -0.4064)
			(stroke
				(width 0.1524)
				(type default)
			)
			(layer "F.SilkS")
		)
		(fp_line
			(start 0.7874 0.4064)
			(end -0.7874 0.4064)
			(stroke
				(width 0.1524)
				(type default)
			)
			(layer "F.SilkS")
		)
		(fp_line
			(start -0.7874 0.4064)
			(end -0.7874 -0.4064)
			(stroke
				(width 0.1524)
				(type default)
			)
			(layer "F.SilkS")
		)
		(fp_line
			(start -0.12065 -0.305054)
			(end -0.12065 -0.2794)
			(stroke
				(width 0.1)
				(type default)
			)
			(layer "F.Fab")
		)
		(fp_line
			(start -0.67945 -0.305054)
			(end -0.12065 -0.305054)
			(stroke
				(width 0.1)
				(type default)
			)
			(layer "F.Fab")
		)
		(fp_line
			(start 0.67945 -0.3048)
			(end 0.67945 0.3048)
			(stroke
				(width 0.1)
				(type default)
			)
			(layer "F.Fab")
		)
		(fp_line
			(start 0.12065 -0.3048)
			(end 0.67945 -0.3048)
			(stroke
				(width 0.1)
				(type default)
			)
			(layer "F.Fab")
		)
		(fp_line
			(start 0.12065 -0.2794)
			(end 0.12065 -0.3048)
			(stroke
				(width 0.1)
				(type default)
			)
			(layer "F.Fab")
		)
		(fp_line
			(start -0.12065 -0.2794)
			(end 0.12065 -0.2794)
			(stroke
				(width 0.1)
				(type default)
			)
			(layer "F.Fab")
		)
		(fp_line
			(start 0.120396 0.2794)
			(end -0.12065 0.2794)
			(stroke
				(width 0.1)
				(type default)
			)
			(layer "F.Fab")
		)
		(fp_line
			(start -0.12065 0.2794)
			(end -0.12065 0.3048)
			(stroke
				(width 0.1)
				(type default)
			)
			(layer "F.Fab")
		)
		(fp_line
			(start 0.67945 0.3048)
			(end 0.120396 0.3048)
			(stroke
				(width 0.1)
				(type default)
			)
			(layer "F.Fab")
		)
		(fp_line
			(start 0.120396 0.3048)
			(end 0.120396 0.2794)
			(stroke
				(width 0.1)
				(type default)
			)
			(layer "F.Fab")
		)
		(fp_line
			(start -0.12065 0.3048)
			(end -0.67945 0.3048)
			(stroke
				(width 0.1)
				(type default)
			)
			(layer "F.Fab")
		)
		(fp_line
			(start -0.67945 0.3048)
			(end -0.67945 -0.305054)
			(stroke
				(width 0.1)
				(type default)
			)
			(layer "F.Fab")
		)
		(pad "1" smd circle
			(at -0.40005 0 90)
			(size 0 0)
			(layers "F.Cu" "F.Mask" "F.Paste")
			(net "CLK_100M_E1S_0_R_DP")
		)
		(pad "2" smd circle
			(at 0.40005 0 90)
			(size 0 0)
			(layers "F.Cu" "F.Mask" "F.Paste")
			(net "CLK_100M_E1S_0_DP")
		)
	)
	(footprint ""
		(layer "F.Cu")
		(at 353.266248 -249.320304 -90)
		(property "Reference" "C1034"
			(at 0 0 270)
			(layer "F.SilkS")
			(hide yes)
			(effects
				(font
					(size 1.27 1.27)
				)
			)
		)
		(property "Value" ""
			(at 0 0 270)
			(layer "F.Fab")
			(effects
				(font
					(size 1.27 1.27)
				)
			)
		)
		(duplicate_pad_numbers_are_jumpers no)
		(fp_line
			(start -0.7874 0.4064)
			(end -0.7874 -0.4064)
			(stroke
				(width 0.1524)
				(type default)
			)
			(layer "F.SilkS")
		)
		(fp_line
			(start 0.7874 0.4064)
			(end -0.7874 0.4064)
			(stroke
				(width 0.1524)
				(type default)
			)
			(layer "F.SilkS")
		)
		(fp_line
			(start -0.7874 -0.4064)
			(end 0.7874 -0.4064)
			(stroke
				(width 0.1524)
				(type default)
			)
			(layer "F.SilkS")
		)
		(fp_line
			(start 0.7874 -0.4064)
			(end 0.7874 0.4064)
			(stroke
				(width 0.1524)
				(type default)
			)
			(layer "F.SilkS")
		)
		(fp_line
			(start -0.67945 0.3048)
			(end -0.67945 -0.305054)
			(stroke
				(width 0.1)
				(type default)
			)
			(layer "F.Fab")
		)
		(fp_line
			(start -0.12065 0.3048)
			(end -0.67945 0.3048)
			(stroke
				(width 0.1)
				(type default)
			)
			(layer "F.Fab")
		)
		(fp_line
			(start 0.120396 0.3048)
			(end 0.120396 0.2794)
			(stroke
				(width 0.1)
				(type default)
			)
			(layer "F.Fab")
		)
		(fp_line
			(start 0.67945 0.3048)
			(end 0.120396 0.3048)
			(stroke
				(width 0.1)
				(type default)
			)
			(layer "F.Fab")
		)
		(fp_line
			(start -0.12065 0.2794)
			(end -0.12065 0.3048)
			(stroke
				(width 0.1)
				(type default)
			)
			(layer "F.Fab")
		)
		(fp_line
			(start 0.120396 0.2794)
			(end -0.12065 0.2794)
			(stroke
				(width 0.1)
				(type default)
			)
			(layer "F.Fab")
		)
		(fp_line
			(start -0.12065 -0.2794)
			(end 0.12065 -0.2794)
			(stroke
				(width 0.1)
				(type default)
			)
			(layer "F.Fab")
		)
		(fp_line
			(start 0.12065 -0.2794)
			(end 0.12065 -0.3048)
			(stroke
				(width 0.1)
				(type default)
			)
			(layer "F.Fab")
		)
		(fp_line
			(start 0.12065 -0.3048)
			(end 0.67945 -0.3048)
			(stroke
				(width 0.1)
				(type default)
			)
			(layer "F.Fab")
		)
		(fp_line
			(start 0.67945 -0.3048)
			(end 0.67945 0.3048)
			(stroke
				(width 0.1)
				(type default)
			)
			(layer "F.Fab")
		)
		(fp_line
			(start -0.67945 -0.305054)
			(end -0.12065 -0.305054)
			(stroke
				(width 0.1)
				(type default)
			)
			(layer "F.Fab")
		)
		(fp_line
			(start -0.12065 -0.305054)
			(end -0.12065 -0.2794)
			(stroke
				(width 0.1)
				(type default)
			)
			(layer "F.Fab")
		)
		(pad "1" smd circle
			(at -0.40005 0 270)
			(size 0 0)
			(layers "F.Cu" "F.Mask" "F.Paste")
			(net "PVCCIN_CPU0")
		)
		(pad "2" smd circle
			(at 0.40005 0 270)
			(size 0 0)
			(layers "F.Cu" "F.Mask" "F.Paste")
			(net "GND")
		)
	)
	(footprint ""
		(layer "F.Cu")
		(at 431.434748 -258.091686)
		(property "Reference" "J11"
			(at -3.683 -81.702148 0)
			(unlocked yes)
			(layer "F.SilkS")
			(effects
				(font
					(size 0.7874 0.5842)
					(thickness 0.1524)
				)
				(justify left)
			)
		)
		(property "Value" ""
			(at 0 0 0)
			(layer "F.Fab")
			(effects
				(font
					(size 1.27 1.27)
				)
			)
		)
		(duplicate_pad_numbers_are_jumpers no)
		(fp_line
			(start -3.24993 -81.000092)
			(end -3.24993 81.000092)
			(stroke
				(width 0.1524)
				(type default)
			)
			(layer "F.SilkS")
		)
		(fp_line
			(start -3.24993 81.000092)
			(end 3.24993 81.000092)
			(stroke
				(width 0.1524)
				(type default)
			)
			(layer "F.SilkS")
		)
		(fp_line
			(start 3.24993 -81.000092)
			(end -3.24993 -81.000092)
			(stroke
				(width 0.1524)
				(type default)
			)
			(layer "F.SilkS")
		)
		(fp_line
			(start 3.24993 -72.00011)
			(end -3.24993 -72.00011)
			(stroke
				(width 0.1524)
				(type default)
			)
			(layer "F.SilkS")
		)
		(fp_line
			(start 3.24993 72.00011)
			(end -3.24993 72.00011)
			(stroke
				(width 0.1524)
				(type default)
			)
			(layer "F.SilkS")
		)
		(fp_line
			(start 3.24993 79.366618)
			(end 3.24993 -81.000092)
			(stroke
				(width 0.1524)
				(type default)
			)
			(layer "F.SilkS")
		)
		(fp_line
			(start 3.24993 81.000092)
			(end 3.24993 80.677258)
			(stroke
				(width 0.1524)
				(type default)
			)
			(layer "F.SilkS")
		)
		(fp_poly
			(pts
				(xy -4.204208 -63.728854) (xy -3.325368 -63.289434) (xy -4.204208 -62.850014)
			)
			(stroke
				(width 0)
				(type default)
			)
			(fill yes)
			(layer "F.SilkS")
		)
		(fp_line
			(start -3.24993 -81.000092)
			(end -3.24993 81.000092)
			(stroke
				(width 0.1)
				(type default)
			)
			(layer "F.Fab")
		)
		(fp_line
			(start -3.24993 81.000092)
			(end 3.24993 81.000092)
			(stroke
				(width 0.1)
				(type default)
			)
			(layer "F.Fab")
		)
		(fp_line
			(start 3.24993 -81.000092)
			(end -3.24993 -81.000092)
			(stroke
				(width 0.1)
				(type default)
			)
			(layer "F.Fab")
		)
		(fp_line
			(start 3.24993 -72.00011)
			(end -3.24993 -72.00011)
			(stroke
				(width 0.1)
				(type default)
			)
			(layer "F.Fab")
		)
		(fp_line
			(start 3.24993 -71.000112)
			(end -3.24993 -71.000112)
			(stroke
				(width 0.1)
				(type default)
			)
			(layer "F.Fab")
		)
		(fp_line
			(start 3.24993 71.000112)
			(end -3.24993 71.000112)
			(stroke
				(width 0.1)
				(type default)
			)
			(layer "F.Fab")
		)
		(fp_line
			(start 3.24993 72.00011)
			(end -3.24993 72.00011)
			(stroke
				(width 0.1)
				(type default)
			)
			(layer "F.Fab")
		)
		(fp_line
			(start 3.24993 81.000092)
			(end 3.24993 -81.000092)
			(stroke
				(width 0.1)
				(type default)
			)
			(layer "F.Fab")
		)
		(fp_poly
			(pts
				(xy -4.445 -63.832994) (xy -4.445 -62.816994) (xy -3.429 -63.324994)
			)
			(stroke
				(width 0)
				(type default)
			)
			(fill yes)
			(layer "F.Fab")
		)
		(pad "1" smd rect
			(at -2.050034 -63.324994 270)
			(size 0.519938 1.4986)
			(layers "F.Cu" "F.Mask" "F.Paste")
			(net "P12V_S3_AUX_CPU0_NVDIMM")
		)
		(pad "2" smd rect
			(at -2.050034 -62.47511 270)
			(size 0.519938 1.4986)
			(layers "F.Cu" "F.Mask" "F.Paste")
			(net "TP_CHF_CPU0_DIMM1_FRU_0")
		)
		(pad "3" smd rect
			(at -2.050034 -61.624972 270)
			(size 0.519938 1.4986)
			(layers "F.Cu" "F.Mask" "F.Paste")
			(net "P3V3_AUX")
		)
		(pad "4" smd rect
			(at -2.050034 -60.775088 270)
			(size 0.519938 1.4986)
			(layers "F.Cu" "F.Mask" "F.Paste")
			(net "I3C_SPD_DDREFGH_CPU0_LVC1_SCL_2")
		)
		(pad "5" smd rect
			(at -2.050034 -59.92495 270)
			(size 0.519938 1.4986)
			(layers "F.Cu" "F.Mask" "F.Paste")
			(net "I3C_SPD_DDREFGH_CPU0_LVC1_SDA")
		)
		(pad "6" smd rect
			(at -2.050034 -59.075066 270)
			(size 0.519938 1.4986)
			(layers "F.Cu" "F.Mask" "F.Paste")
			(net "GND")
		)
		(pad "7" smd rect
			(at -2.050034 -58.224928 270)
			(size 0.519938 1.4986)
			(layers "F.Cu" "F.Mask" "F.Paste")
			(net "M_F_CPU0_SA_DQ<0>")
		)
		(pad "8" smd rect
			(at -2.050034 -57.375044 270)
			(size 0.519938 1.4986)
			(layers "F.Cu" "F.Mask" "F.Paste")
			(net "GND")
		)
		(pad "9" smd rect
			(at -2.050034 -56.524906 270)
			(size 0.519938 1.4986)
			(layers "F.Cu" "F.Mask" "F.Paste")
			(net "M_F_CPU0_SA_DQ<1>")
		)
		(pad "10" smd rect
			(at -2.050034 -55.675022 270)
			(size 0.519938 1.4986)
			(layers "F.Cu" "F.Mask" "F.Paste")
			(net "GND")
		)
		(pad "11" smd rect
			(at -2.050034 -54.824884 270)
			(size 0.519938 1.4986)
			(layers "F.Cu" "F.Mask" "F.Paste")
			(net "M_F_CPU0_SA_DQS_DP<0>")
		)
		(pad "12" smd rect
			(at -2.050034 -53.975 270)
			(size 0.519938 1.4986)
			(layers "F.Cu" "F.Mask" "F.Paste")
			(net "M_F_CPU0_SA_DQS_DN<0>")
		)
		(pad "13" smd rect
			(at -2.050034 -53.125116 270)
			(size 0.519938 1.4986)
			(layers "F.Cu" "F.Mask" "F.Paste")
			(net "GND")
		)
		(pad "14" smd rect
			(at -2.050034 -52.274978 270)
			(size 0.519938 1.4986)
			(layers "F.Cu" "F.Mask" "F.Paste")
			(net "M_F_CPU0_SA_DQ<4>")
		)
		(pad "15" smd rect
			(at -2.050034 -51.425094 270)
			(size 0.519938 1.4986)
			(layers "F.Cu" "F.Mask" "F.Paste")
			(net "GND")
		)
		(pad "16" smd rect
			(at -2.050034 -50.574956 270)
			(size 0.519938 1.4986)
			(layers "F.Cu" "F.Mask" "F.Paste")
			(net "M_F_CPU0_SA_DQ<5>")
		)
		(pad "17" smd rect
			(at -2.050034 -49.725072 270)
			(size 0.519938 1.4986)
			(layers "F.Cu" "F.Mask" "F.Paste")
			(net "GND")
		)
		(pad "18" smd rect
			(at -2.050034 -48.874934 270)
			(size 0.519938 1.4986)
			(layers "F.Cu" "F.Mask" "F.Paste")
			(net "M_F_CPU0_SA_DQ<8>")
		)
		(pad "19" smd rect
			(at -2.050034 -48.02505 270)
			(size 0.519938 1.4986)
			(layers "F.Cu" "F.Mask" "F.Paste")
			(net "GND")
		)
		(pad "20" smd rect
			(at -2.050034 -47.174912 270)
			(size 0.519938 1.4986)
			(layers "F.Cu" "F.Mask" "F.Paste")
			(net "M_F_CPU0_SA_DQ<9>")
		)
		(pad "21" smd rect
			(at -2.050034 -46.325028 270)
			(size 0.519938 1.4986)
			(layers "F.Cu" "F.Mask" "F.Paste")
			(net "GND")
		)
		(pad "22" smd rect
			(at -2.050034 -45.47489 270)
			(size 0.519938 1.4986)
			(layers "F.Cu" "F.Mask" "F.Paste")
			(net "M_F_CPU0_SA_DQS_DP<1>")
		)
		(pad "23" smd rect
			(at -2.050034 -44.625006 270)
			(size 0.519938 1.4986)
			(layers "F.Cu" "F.Mask" "F.Paste")
			(net "M_F_CPU0_SA_DQS_DN<1>")
		)
		(pad "24" smd rect
			(at -2.050034 -43.775122 270)
			(size 0.519938 1.4986)
			(layers "F.Cu" "F.Mask" "F.Paste")
			(net "GND")
		)
		(pad "25" smd rect
			(at -2.050034 -42.924984 270)
			(size 0.519938 1.4986)
			(layers "F.Cu" "F.Mask" "F.Paste")
			(net "M_F_CPU0_SA_DQ<12>")
		)
		(pad "26" smd rect
			(at -2.050034 -42.0751 270)
			(size 0.519938 1.4986)
			(layers "F.Cu" "F.Mask" "F.Paste")
			(net "GND")
		)
		(pad "27" smd rect
			(at -2.050034 -41.224962 270)
			(size 0.519938 1.4986)
			(layers "F.Cu" "F.Mask" "F.Paste")
			(net "M_F_CPU0_SA_DQ<13>")
		)
		(pad "28" smd rect
			(at -2.050034 -40.375078 270)
			(size 0.519938 1.4986)
			(layers "F.Cu" "F.Mask" "F.Paste")
			(net "GND")
		)
		(pad "29" smd rect
			(at -2.050034 -39.52494 270)
			(size 0.519938 1.4986)
			(layers "F.Cu" "F.Mask" "F.Paste")
			(net "M_F_CPU0_SA_DQ<16>")
		)
		(pad "30" smd rect
			(at -2.050034 -38.675056 270)
			(size 0.519938 1.4986)
			(layers "F.Cu" "F.Mask" "F.Paste")
			(net "GND")
		)
		(pad "31" smd rect
			(at -2.050034 -37.824918 270)
			(size 0.519938 1.4986)
			(layers "F.Cu" "F.Mask" "F.Paste")
			(net "M_F_CPU0_SA_DQ<17>")
		)
		(pad "32" smd rect
			(at -2.050034 -36.975034 270)
			(size 0.519938 1.4986)
			(layers "F.Cu" "F.Mask" "F.Paste")
			(net "GND")
		)
		(pad "33" smd rect
			(at -2.050034 -36.124896 270)
			(size 0.519938 1.4986)
			(layers "F.Cu" "F.Mask" "F.Paste")
			(net "M_F_CPU0_SA_DQS_DP<2>")
		)
		(pad "34" smd rect
			(at -2.050034 -35.275012 270)
			(size 0.519938 1.4986)
			(layers "F.Cu" "F.Mask" "F.Paste")
			(net "M_F_CPU0_SA_DQS_DN<2>")
		)
		(pad "35" smd rect
			(at -2.050034 -34.425128 270)
			(size 0.519938 1.4986)
			(layers "F.Cu" "F.Mask" "F.Paste")
			(net "GND")
		)
		(pad "36" smd rect
			(at -2.050034 -33.57499 270)
			(size 0.519938 1.4986)
			(layers "F.Cu" "F.Mask" "F.Paste")
			(net "M_F_CPU0_SA_DQ<20>")
		)
		(pad "37" smd rect
			(at -2.050034 -32.725106 270)
			(size 0.519938 1.4986)
			(layers "F.Cu" "F.Mask" "F.Paste")
			(net "GND")
		)
		(pad "38" smd rect
			(at -2.050034 -31.874968 270)
			(size 0.519938 1.4986)
			(layers "F.Cu" "F.Mask" "F.Paste")
			(net "M_F_CPU0_SA_DQ<21>")
		)
		(pad "39" smd rect
			(at -2.050034 -31.025084 270)
			(size 0.519938 1.4986)
			(layers "F.Cu" "F.Mask" "F.Paste")
			(net "GND")
		)
		(pad "40" smd rect
			(at -2.050034 -30.174946 270)
			(size 0.519938 1.4986)
			(layers "F.Cu" "F.Mask" "F.Paste")
			(net "M_F_CPU0_SA_DQ<24>")
		)
		(pad "41" smd rect
			(at -2.050034 -29.325062 270)
			(size 0.519938 1.4986)
			(layers "F.Cu" "F.Mask" "F.Paste")
			(net "GND")
		)
		(pad "42" smd rect
			(at -2.050034 -28.474924 270)
			(size 0.519938 1.4986)
			(layers "F.Cu" "F.Mask" "F.Paste")
			(net "M_F_CPU0_SA_DQ<25>")
		)
		(pad "43" smd rect
			(at -2.050034 -27.62504 270)
			(size 0.519938 1.4986)
			(layers "F.Cu" "F.Mask" "F.Paste")
			(net "GND")
		)
		(pad "44" smd rect
			(at -2.050034 -26.774902 270)
			(size 0.519938 1.4986)
			(layers "F.Cu" "F.Mask" "F.Paste")
			(net "M_F_CPU0_SA_DQS_DP<3>")
		)
		(pad "45" smd rect
			(at -2.050034 -25.925018 270)
			(size 0.519938 1.4986)
			(layers "F.Cu" "F.Mask" "F.Paste")
			(net "M_F_CPU0_SA_DQS_DN<3>")
		)
		(pad "46" smd rect
			(at -2.050034 -25.07488 270)
			(size 0.519938 1.4986)
			(layers "F.Cu" "F.Mask" "F.Paste")
			(net "GND")
		)
		(pad "47" smd rect
			(at -2.050034 -24.224996 270)
			(size 0.519938 1.4986)
			(layers "F.Cu" "F.Mask" "F.Paste")
			(net "M_F_CPU0_SA_DQ<28>")
		)
		(pad "48" smd rect
			(at -2.050034 -23.375112 270)
			(size 0.519938 1.4986)
			(layers "F.Cu" "F.Mask" "F.Paste")
			(net "GND")
		)
		(pad "49" smd rect
			(at -2.050034 -22.524974 270)
			(size 0.519938 1.4986)
			(layers "F.Cu" "F.Mask" "F.Paste")
			(net "M_F_CPU0_SA_DQ<29>")
		)
		(pad "50" smd rect
			(at -2.050034 -21.67509 270)
			(size 0.519938 1.4986)
			(layers "F.Cu" "F.Mask" "F.Paste")
			(net "GND")
		)
		(pad "51" smd rect
			(at -2.050034 -20.824952 270)
			(size 0.519938 1.4986)
			(layers "F.Cu" "F.Mask" "F.Paste")
			(net "M_F_CPU0_SA_CB<0>")
		)
		(pad "52" smd rect
			(at -2.050034 -19.975068 270)
			(size 0.519938 1.4986)
			(layers "F.Cu" "F.Mask" "F.Paste")
			(net "GND")
		)
		(pad "53" smd rect
			(at -2.050034 -19.12493 270)
			(size 0.519938 1.4986)
			(layers "F.Cu" "F.Mask" "F.Paste")
			(net "M_F_CPU0_SA_CB<1>")
		)
		(pad "54" smd rect
			(at -2.050034 -18.275046 270)
			(size 0.519938 1.4986)
			(layers "F.Cu" "F.Mask" "F.Paste")
			(net "GND")
		)
		(pad "55" smd rect
			(at -2.050034 -17.424908 270)
			(size 0.519938 1.4986)
			(layers "F.Cu" "F.Mask" "F.Paste")
			(net "M_F_CPU0_SA_DQS_DP<4>")
		)
		(pad "56" smd rect
			(at -2.050034 -16.575024 270)
			(size 0.519938 1.4986)
			(layers "F.Cu" "F.Mask" "F.Paste")
			(net "M_F_CPU0_SA_DQS_DN<4>")
		)
		(pad "57" smd rect
			(at -2.050034 -15.724886 270)
			(size 0.519938 1.4986)
			(layers "F.Cu" "F.Mask" "F.Paste")
			(net "GND")
		)
		(pad "58" smd rect
			(at -2.050034 -14.875002 270)
			(size 0.519938 1.4986)
			(layers "F.Cu" "F.Mask" "F.Paste")
			(net "M_F_CPU0_SA_CB<4>")
		)
		(pad "59" smd rect
			(at -2.050034 -14.025118 270)
			(size 0.519938 1.4986)
			(layers "F.Cu" "F.Mask" "F.Paste")
			(net "GND")
		)
		(pad "60" smd rect
			(at -2.050034 -13.17498 270)
			(size 0.519938 1.4986)
			(layers "F.Cu" "F.Mask" "F.Paste")
			(net "M_F_CPU0_SA_CB<5>")
		)
		(pad "61" smd rect
			(at -2.050034 -12.325096 270)
			(size 0.519938 1.4986)
			(layers "F.Cu" "F.Mask" "F.Paste")
			(net "GND")
		)
		(pad "62" smd rect
			(at -2.050034 -11.474958 270)
			(size 0.519938 1.4986)
			(layers "F.Cu" "F.Mask" "F.Paste")
			(net "M_F_CPU0_ALERT_N")
		)
		(pad "63" smd rect
			(at -2.050034 -10.625074 270)
			(size 0.519938 1.4986)
			(layers "F.Cu" "F.Mask" "F.Paste")
			(net "GND")
		)
		(pad "64" smd rect
			(at -2.050034 -9.774936 270)
			(size 0.519938 1.4986)
			(layers "F.Cu" "F.Mask" "F.Paste")
			(net "M_F_CPU0_SA_CS_N<0>")
		)
		(pad "65" smd rect
			(at -2.050034 -8.925052 270)
			(size 0.519938 1.4986)
			(layers "F.Cu" "F.Mask" "F.Paste")
			(net "GND")
		)
		(pad "66" smd rect
			(at -2.050034 -8.074914 270)
			(size 0.519938 1.4986)
			(layers "F.Cu" "F.Mask" "F.Paste")
			(net "M_F_CPU0_SA_CA<0>")
		)
		(pad "67" smd rect
			(at -2.050034 -7.22503 270)
			(size 0.519938 1.4986)
			(layers "F.Cu" "F.Mask" "F.Paste")
			(net "GND")
		)
		(pad "68" smd rect
			(at -2.050034 -6.374892 270)
			(size 0.519938 1.4986)
			(layers "F.Cu" "F.Mask" "F.Paste")
			(net "M_F_CPU0_SA_CA<2>")
		)
		(pad "69" smd rect
			(at -2.050034 -5.525008 270)
			(size 0.519938 1.4986)
			(layers "F.Cu" "F.Mask" "F.Paste")
			(net "GND")
		)
		(pad "70" smd rect
			(at -2.050034 -4.675124 270)
			(size 0.519938 1.4986)
			(layers "F.Cu" "F.Mask" "F.Paste")
			(net "M_F_CPU0_SA_CA<4>")
		)
		(pad "71" smd rect
			(at -2.050034 -3.824986 270)
			(size 0.519938 1.4986)
			(layers "F.Cu" "F.Mask" "F.Paste")
			(net "GND")
		)
		(pad "72" smd rect
			(at -2.050034 -2.975102 270)
			(size 0.519938 1.4986)
			(layers "F.Cu" "F.Mask" "F.Paste")
			(net "M_F_CPU0_SA_CA<6>")
		)
		(pad "73" smd rect
			(at -2.050034 -2.124964 270)
			(size 0.519938 1.4986)
			(layers "F.Cu" "F.Mask" "F.Paste")
			(net "GND")
		)
		(pad "74" smd rect
			(at -2.050034 -1.27508 270)
			(size 0.519938 1.4986)
			(layers "F.Cu" "F.Mask" "F.Paste")
			(net "M_F_CPU0_SA_PAR")
		)
		(pad "75" smd rect
			(at -2.050034 -0.424942 270)
			(size 0.519938 1.4986)
			(layers "F.Cu" "F.Mask" "F.Paste")
			(net "GND")
		)
		(pad "76" smd rect
			(at -2.050034 5.525008 270)
			(size 0.519938 1.4986)
			(layers "F.Cu" "F.Mask" "F.Paste")
			(net "M_F_CPU0_SB_CA<0>")
		)
		(pad "77" smd rect
			(at -2.050034 6.374892 270)
			(size 0.519938 1.4986)
			(layers "F.Cu" "F.Mask" "F.Paste")
			(net "GND")
		)
		(pad "78" smd rect
			(at -2.050034 7.22503 270)
			(size 0.519938 1.4986)
			(layers "F.Cu" "F.Mask" "F.Paste")
			(net "M_F_CPU0_SB_CA<2>")
		)
		(pad "79" smd rect
			(at -2.050034 8.074914 270)
			(size 0.519938 1.4986)
			(layers "F.Cu" "F.Mask" "F.Paste")
			(net "GND")
		)
		(pad "80" smd rect
			(at -2.050034 8.925052 270)
			(size 0.519938 1.4986)
			(layers "F.Cu" "F.Mask" "F.Paste")
			(net "M_F_CPU0_SB_CA<4>")
		)
		(pad "81" smd rect
			(at -2.050034 9.774936 270)
			(size 0.519938 1.4986)
			(layers "F.Cu" "F.Mask" "F.Paste")
			(net "GND")
		)
		(pad "82" smd rect
			(at -2.050034 10.625074 270)
			(size 0.519938 1.4986)
			(layers "F.Cu" "F.Mask" "F.Paste")
			(net "M_F_CPU0_SB_CA<6>")
		)
		(pad "83" smd rect
			(at -2.050034 11.474958 270)
			(size 0.519938 1.4986)
			(layers "F.Cu" "F.Mask" "F.Paste")
			(net "GND")
		)
		(pad "84" smd rect
			(at -2.050034 12.325096 270)
			(size 0.519938 1.4986)
			(layers "F.Cu" "F.Mask" "F.Paste")
			(net "M_F_CPU0_SB_CS_N<0>")
		)
		(pad "85" smd rect
			(at -2.050034 13.17498 270)
			(size 0.519938 1.4986)
			(layers "F.Cu" "F.Mask" "F.Paste")
			(net "GND")
		)
		(pad "86" smd rect
			(at -2.050034 14.025118 270)
			(size 0.519938 1.4986)
			(layers "F.Cu" "F.Mask" "F.Paste")
			(net "M_F_CPU0_SA_RSP<0>")
		)
		(pad "87" smd rect
			(at -2.050034 14.875002 270)
			(size 0.519938 1.4986)
			(layers "F.Cu" "F.Mask" "F.Paste")
			(net "M_F_CPU0_SB_RSP<0>")
		)
		(pad "88" smd rect
			(at -2.050034 15.724886 270)
			(size 0.519938 1.4986)
			(layers "F.Cu" "F.Mask" "F.Paste")
			(net "GND")
		)
		(pad "89" smd rect
			(at -2.050034 16.575024 270)
			(size 0.519938 1.4986)
			(layers "F.Cu" "F.Mask" "F.Paste")
			(net "M_F_CPU0_SB_CB<4>")
		)
		(pad "90" smd rect
			(at -2.050034 17.424908 270)
			(size 0.519938 1.4986)
			(layers "F.Cu" "F.Mask" "F.Paste")
			(net "GND")
		)
		(pad "91" smd rect
			(at -2.050034 18.275046 270)
			(size 0.519938 1.4986)
			(layers "F.Cu" "F.Mask" "F.Paste")
			(net "M_F_CPU0_SB_CB<5>")
		)
		(pad "92" smd rect
			(at -2.050034 19.12493 270)
			(size 0.519938 1.4986)
			(layers "F.Cu" "F.Mask" "F.Paste")
			(net "GND")
		)
		(pad "93" smd rect
			(at -2.050034 19.975068 270)
			(size 0.519938 1.4986)
			(layers "F.Cu" "F.Mask" "F.Paste")
			(net "M_F_CPU0_SB_DQS_DP<9>")
		)
		(pad "94" smd rect
			(at -2.050034 20.824952 270)
			(size 0.519938 1.4986)
			(layers "F.Cu" "F.Mask" "F.Paste")
			(net "M_F_CPU0_SB_DQS_DN<9>")
		)
		(pad "95" smd rect
			(at -2.050034 21.67509 270)
			(size 0.519938 1.4986)
			(layers "F.Cu" "F.Mask" "F.Paste")
			(net "GND")
		)
		(pad "96" smd rect
			(at -2.050034 22.524974 270)
			(size 0.519938 1.4986)
			(layers "F.Cu" "F.Mask" "F.Paste")
			(net "M_F_CPU0_SB_CB<0>")
		)
		(pad "97" smd rect
			(at -2.050034 23.375112 270)
			(size 0.519938 1.4986)
			(layers "F.Cu" "F.Mask" "F.Paste")
			(net "GND")
		)
		(pad "98" smd rect
			(at -2.050034 24.224996 270)
			(size 0.519938 1.4986)
			(layers "F.Cu" "F.Mask" "F.Paste")
			(net "M_F_CPU0_SB_CB<1>")
		)
		(pad "99" smd rect
			(at -2.050034 25.07488 270)
			(size 0.519938 1.4986)
			(layers "F.Cu" "F.Mask" "F.Paste")
			(net "GND")
		)
		(pad "100" smd rect
			(at -2.050034 25.925018 270)
			(size 0.519938 1.4986)
			(layers "F.Cu" "F.Mask" "F.Paste")
			(net "M_F_CPU0_SB_DQ<0>")
		)
		(pad "101" smd rect
			(at -2.050034 26.774902 270)
			(size 0.519938 1.4986)
			(layers "F.Cu" "F.Mask" "F.Paste")
			(net "GND")
		)
		(pad "102" smd rect
			(at -2.050034 27.62504 270)
			(size 0.519938 1.4986)
			(layers "F.Cu" "F.Mask" "F.Paste")
			(net "M_F_CPU0_SB_DQ<1>")
		)
		(pad "103" smd rect
			(at -2.050034 28.474924 270)
			(size 0.519938 1.4986)
			(layers "F.Cu" "F.Mask" "F.Paste")
			(net "GND")
		)
		(pad "104" smd rect
			(at -2.050034 29.325062 270)
			(size 0.519938 1.4986)
			(layers "F.Cu" "F.Mask" "F.Paste")
			(net "M_F_CPU0_SB_DQS_DP<0>")
		)
		(pad "105" smd rect
			(at -2.050034 30.174946 270)
			(size 0.519938 1.4986)
			(layers "F.Cu" "F.Mask" "F.Paste")
			(net "M_F_CPU0_SB_DQS_DN<0>")
		)
		(pad "106" smd rect
			(at -2.050034 31.025084 270)
			(size 0.519938 1.4986)
			(layers "F.Cu" "F.Mask" "F.Paste")
			(net "GND")
		)
		(pad "107" smd rect
			(at -2.050034 31.874968 270)
			(size 0.519938 1.4986)
			(layers "F.Cu" "F.Mask" "F.Paste")
			(net "M_F_CPU0_SB_DQ<4>")
		)
		(pad "108" smd rect
			(at -2.050034 32.725106 270)
			(size 0.519938 1.4986)
			(layers "F.Cu" "F.Mask" "F.Paste")
			(net "GND")
		)
		(pad "109" smd rect
			(at -2.050034 33.57499 270)
			(size 0.519938 1.4986)
			(layers "F.Cu" "F.Mask" "F.Paste")
			(net "M_F_CPU0_SB_DQ<5>")
		)
		(pad "110" smd rect
			(at -2.050034 34.425128 270)
			(size 0.519938 1.4986)
			(layers "F.Cu" "F.Mask" "F.Paste")
			(net "GND")
		)
		(pad "111" smd rect
			(at -2.050034 35.275012 270)
			(size 0.519938 1.4986)
			(layers "F.Cu" "F.Mask" "F.Paste")
			(net "M_F_CPU0_SB_DQ<8>")
		)
		(pad "112" smd rect
			(at -2.050034 36.124896 270)
			(size 0.519938 1.4986)
			(layers "F.Cu" "F.Mask" "F.Paste")
			(net "GND")
		)
		(pad "113" smd rect
			(at -2.050034 36.975034 270)
			(size 0.519938 1.4986)
			(layers "F.Cu" "F.Mask" "F.Paste")
			(net "M_F_CPU0_SB_DQ<9>")
		)
		(pad "114" smd rect
			(at -2.050034 37.824918 270)
			(size 0.519938 1.4986)
			(layers "F.Cu" "F.Mask" "F.Paste")
			(net "GND")
		)
		(pad "115" smd rect
			(at -2.050034 38.675056 270)
			(size 0.519938 1.4986)
			(layers "F.Cu" "F.Mask" "F.Paste")
			(net "M_F_CPU0_SB_DQS_DP<1>")
		)
		(pad "116" smd rect
			(at -2.050034 39.52494 270)
			(size 0.519938 1.4986)
			(layers "F.Cu" "F.Mask" "F.Paste")
			(net "M_F_CPU0_SB_DQS_DN<1>")
		)
		(pad "117" smd rect
			(at -2.050034 40.375078 270)
			(size 0.519938 1.4986)
			(layers "F.Cu" "F.Mask" "F.Paste")
			(net "GND")
		)
		(pad "118" smd rect
			(at -2.050034 41.224962 270)
			(size 0.519938 1.4986)
			(layers "F.Cu" "F.Mask" "F.Paste")
			(net "M_F_CPU0_SB_DQ<12>")
		)
		(pad "119" smd rect
			(at -2.050034 42.0751 270)
			(size 0.519938 1.4986)
			(layers "F.Cu" "F.Mask" "F.Paste")
			(net "GND")
		)
		(pad "120" smd rect
			(at -2.050034 42.924984 270)
			(size 0.519938 1.4986)
			(layers "F.Cu" "F.Mask" "F.Paste")
			(net "M_F_CPU0_SB_DQ<13>")
		)
		(pad "121" smd rect
			(at -2.050034 43.775122 270)
			(size 0.519938 1.4986)
			(layers "F.Cu" "F.Mask" "F.Paste")
			(net "GND")
		)
		(pad "122" smd rect
			(at -2.050034 44.625006 270)
			(size 0.519938 1.4986)
			(layers "F.Cu" "F.Mask" "F.Paste")
			(net "M_F_CPU0_SB_DQ<16>")
		)
		(pad "123" smd rect
			(at -2.050034 45.47489 270)
			(size 0.519938 1.4986)
			(layers "F.Cu" "F.Mask" "F.Paste")
			(net "GND")
		)
		(pad "124" smd rect
			(at -2.050034 46.325028 270)
			(size 0.519938 1.4986)
			(layers "F.Cu" "F.Mask" "F.Paste")
			(net "M_F_CPU0_SB_DQ<17>")
		)
		(pad "125" smd rect
			(at -2.050034 47.174912 270)
			(size 0.519938 1.4986)
			(layers "F.Cu" "F.Mask" "F.Paste")
			(net "GND")
		)
		(pad "126" smd rect
			(at -2.050034 48.02505 270)
			(size 0.519938 1.4986)
			(layers "F.Cu" "F.Mask" "F.Paste")
			(net "M_F_CPU0_SB_DQS_DP<2>")
		)
		(pad "127" smd rect
			(at -2.050034 48.874934 270)
			(size 0.519938 1.4986)
			(layers "F.Cu" "F.Mask" "F.Paste")
			(net "M_F_CPU0_SB_DQS_DN<2>")
		)
		(pad "128" smd rect
			(at -2.050034 49.725072 270)
			(size 0.519938 1.4986)
			(layers "F.Cu" "F.Mask" "F.Paste")
			(net "GND")
		)
		(pad "129" smd rect
			(at -2.050034 50.574956 270)
			(size 0.519938 1.4986)
			(layers "F.Cu" "F.Mask" "F.Paste")
			(net "M_F_CPU0_SB_DQ<20>")
		)
		(pad "130" smd rect
			(at -2.050034 51.425094 270)
			(size 0.519938 1.4986)
			(layers "F.Cu" "F.Mask" "F.Paste")
			(net "GND")
		)
		(pad "131" smd rect
			(at -2.050034 52.274978 270)
			(size 0.519938 1.4986)
			(layers "F.Cu" "F.Mask" "F.Paste")
			(net "M_F_CPU0_SB_DQ<21>")
		)
		(pad "132" smd rect
			(at -2.050034 53.125116 270)
			(size 0.519938 1.4986)
			(layers "F.Cu" "F.Mask" "F.Paste")
			(net "GND")
		)
		(pad "133" smd rect
			(at -2.050034 53.975 270)
			(size 0.519938 1.4986)
			(layers "F.Cu" "F.Mask" "F.Paste")
			(net "M_F_CPU0_SB_DQ<24>")
		)
		(pad "134" smd rect
			(at -2.050034 54.824884 270)
			(size 0.519938 1.4986)
			(layers "F.Cu" "F.Mask" "F.Paste")
			(net "GND")
		)
		(pad "135" smd rect
			(at -2.050034 55.675022 270)
			(size 0.519938 1.4986)
			(layers "F.Cu" "F.Mask" "F.Paste")
			(net "M_F_CPU0_SB_DQ<25>")
		)
		(pad "136" smd rect
			(at -2.050034 56.524906 270)
			(size 0.519938 1.4986)
			(layers "F.Cu" "F.Mask" "F.Paste")
			(net "GND")
		)
		(pad "137" smd rect
			(at -2.050034 57.375044 270)
			(size 0.519938 1.4986)
			(layers "F.Cu" "F.Mask" "F.Paste")
			(net "M_F_CPU0_SB_DQS_DP<3>")
		)
		(pad "138" smd rect
			(at -2.050034 58.224928 270)
			(size 0.519938 1.4986)
			(layers "F.Cu" "F.Mask" "F.Paste")
			(net "M_F_CPU0_SB_DQS_DN<3>")
		)
		(pad "139" smd rect
			(at -2.050034 59.075066 270)
			(size 0.519938 1.4986)
			(layers "F.Cu" "F.Mask" "F.Paste")
			(net "GND")
		)
		(pad "140" smd rect
			(at -2.050034 59.92495 270)
			(size 0.519938 1.4986)
			(layers "F.Cu" "F.Mask" "F.Paste")
			(net "M_F_CPU0_SB_DQ<28>")
		)
		(pad "141" smd rect
			(at -2.050034 60.775088 270)
			(size 0.519938 1.4986)
			(layers "F.Cu" "F.Mask" "F.Paste")
			(net "GND")
		)
		(pad "142" smd rect
			(at -2.050034 61.624972 270)
			(size 0.519938 1.4986)
			(layers "F.Cu" "F.Mask" "F.Paste")
			(net "M_F_CPU0_SB_DQ<29>")
		)
		(pad "143" smd rect
			(at -2.050034 62.47511 270)
			(size 0.519938 1.4986)
			(layers "F.Cu" "F.Mask" "F.Paste")
			(net "GND")
		)
		(pad "144" smd rect
			(at -2.050034 63.324994 270)
			(size 0.519938 1.4986)
			(layers "F.Cu" "F.Mask" "F.Paste")
			(net "TP_CHF_CPU0_DIMM1_FRU_1")
		)
		(pad "145" smd rect
			(at 2.050034 -63.324994 270)
			(size 0.519938 1.4986)
			(layers "F.Cu" "F.Mask" "F.Paste")
			(net "P12V_S3_AUX_CPU0_NVDIMM")
		)
		(pad "146" smd rect
			(at 2.050034 -62.47511 270)
			(size 0.519938 1.4986)
			(layers "F.Cu" "F.Mask" "F.Paste")
			(net "P12V_S3_AUX_CPU0_NVDIMM")
		)
		(pad "147" smd rect
			(at 2.050034 -61.624972 270)
			(size 0.519938 1.4986)
			(layers "F.Cu" "F.Mask" "F.Paste")
			(net "PWRGD_CHF_CPU0_DIMM1")
		)
		(pad "148" smd rect
			(at 2.050034 -60.775088 270)
			(size 0.519938 1.4986)
			(layers "F.Cu" "F.Mask" "F.Paste")
			(net "PD_CHF_CPU0_DIMM1_SAA")
		)
		(pad "149" smd rect
			(at 2.050034 -59.92495 270)
			(size 0.519938 1.4986)
			(layers "F.Cu" "F.Mask" "F.Paste")
			(net "TP_CHF_CPU0_DIMM1_FRU_2")
		)
		(pad "150" smd rect
			(at 2.050034 -59.075066 270)
			(size 0.519938 1.4986)
			(layers "F.Cu" "F.Mask" "F.Paste")
			(net "TP_CHF_CPU0_DIMM1_FRU_3")
		)
		(pad "151" smd rect
			(at 2.050034 -58.224928 270)
			(size 0.519938 1.4986)
			(layers "F.Cu" "F.Mask" "F.Paste")
			(net "GND")
		)
		(pad "152" smd rect
			(at 2.050034 -57.375044 270)
			(size 0.519938 1.4986)
			(layers "F.Cu" "F.Mask" "F.Paste")
			(net "M_F_CPU0_SA_DQ<2>")
		)
		(pad "153" smd rect
			(at 2.050034 -56.524906 270)
			(size 0.519938 1.4986)
			(layers "F.Cu" "F.Mask" "F.Paste")
			(net "GND")
		)
		(pad "154" smd rect
			(at 2.050034 -55.675022 270)
			(size 0.519938 1.4986)
			(layers "F.Cu" "F.Mask" "F.Paste")
			(net "M_F_CPU0_SA_DQ<3>")
		)
		(pad "155" smd rect
			(at 2.050034 -54.824884 270)
			(size 0.519938 1.4986)
			(layers "F.Cu" "F.Mask" "F.Paste")
			(net "GND")
		)
		(pad "156" smd rect
			(at 2.050034 -53.975 270)
			(size 0.519938 1.4986)
			(layers "F.Cu" "F.Mask" "F.Paste")
			(net "M_F_CPU0_SA_DQS_DN<5>")
		)
		(pad "157" smd rect
			(at 2.050034 -53.125116 270)
			(size 0.519938 1.4986)
			(layers "F.Cu" "F.Mask" "F.Paste")
			(net "M_F_CPU0_SA_DQS_DP<5>")
		)
		(pad "158" smd rect
			(at 2.050034 -52.274978 270)
			(size 0.519938 1.4986)
			(layers "F.Cu" "F.Mask" "F.Paste")
			(net "GND")
		)
		(pad "159" smd rect
			(at 2.050034 -51.425094 270)
			(size 0.519938 1.4986)
			(layers "F.Cu" "F.Mask" "F.Paste")
			(net "M_F_CPU0_SA_DQ<6>")
		)
		(pad "160" smd rect
			(at 2.050034 -50.574956 270)
			(size 0.519938 1.4986)
			(layers "F.Cu" "F.Mask" "F.Paste")
			(net "GND")
		)
		(pad "161" smd rect
			(at 2.050034 -49.725072 270)
			(size 0.519938 1.4986)
			(layers "F.Cu" "F.Mask" "F.Paste")
			(net "M_F_CPU0_SA_DQ<7>")
		)
		(pad "162" smd rect
			(at 2.050034 -48.874934 270)
			(size 0.519938 1.4986)
			(layers "F.Cu" "F.Mask" "F.Paste")
			(net "GND")
		)
		(pad "163" smd rect
			(at 2.050034 -48.02505 270)
			(size 0.519938 1.4986)
			(layers "F.Cu" "F.Mask" "F.Paste")
			(net "M_F_CPU0_SA_DQ<10>")
		)
		(pad "164" smd rect
			(at 2.050034 -47.174912 270)
			(size 0.519938 1.4986)
			(layers "F.Cu" "F.Mask" "F.Paste")
			(net "GND")
		)
		(pad "165" smd rect
			(at 2.050034 -46.325028 270)
			(size 0.519938 1.4986)
			(layers "F.Cu" "F.Mask" "F.Paste")
			(net "M_F_CPU0_SA_DQ<11>")
		)
		(pad "166" smd rect
			(at 2.050034 -45.47489 270)
			(size 0.519938 1.4986)
			(layers "F.Cu" "F.Mask" "F.Paste")
			(net "GND")
		)
		(pad "167" smd rect
			(at 2.050034 -44.625006 270)
			(size 0.519938 1.4986)
			(layers "F.Cu" "F.Mask" "F.Paste")
			(net "M_F_CPU0_SA_DQS_DN<6>")
		)
		(pad "168" smd rect
			(at 2.050034 -43.775122 270)
			(size 0.519938 1.4986)
			(layers "F.Cu" "F.Mask" "F.Paste")
			(net "M_F_CPU0_SA_DQS_DP<6>")
		)
		(pad "169" smd rect
			(at 2.050034 -42.924984 270)
			(size 0.519938 1.4986)
			(layers "F.Cu" "F.Mask" "F.Paste")
			(net "GND")
		)
		(pad "170" smd rect
			(at 2.050034 -42.0751 270)
			(size 0.519938 1.4986)
			(layers "F.Cu" "F.Mask" "F.Paste")
			(net "M_F_CPU0_SA_DQ<14>")
		)
		(pad "171" smd rect
			(at 2.050034 -41.224962 270)
			(size 0.519938 1.4986)
			(layers "F.Cu" "F.Mask" "F.Paste")
			(net "GND")
		)
		(pad "172" smd rect
			(at 2.050034 -40.375078 270)
			(size 0.519938 1.4986)
			(layers "F.Cu" "F.Mask" "F.Paste")
			(net "M_F_CPU0_SA_DQ<15>")
		)
		(pad "173" smd rect
			(at 2.050034 -39.52494 270)
			(size 0.519938 1.4986)
			(layers "F.Cu" "F.Mask" "F.Paste")
			(net "GND")
		)
		(pad "174" smd rect
			(at 2.050034 -38.675056 270)
			(size 0.519938 1.4986)
			(layers "F.Cu" "F.Mask" "F.Paste")
			(net "M_F_CPU0_SA_DQ<18>")
		)
		(pad "175" smd rect
			(at 2.050034 -37.824918 270)
			(size 0.519938 1.4986)
			(layers "F.Cu" "F.Mask" "F.Paste")
			(net "GND")
		)
		(pad "176" smd rect
			(at 2.050034 -36.975034 270)
			(size 0.519938 1.4986)
			(layers "F.Cu" "F.Mask" "F.Paste")
			(net "M_F_CPU0_SA_DQ<19>")
		)
		(pad "177" smd rect
			(at 2.050034 -36.124896 270)
			(size 0.519938 1.4986)
			(layers "F.Cu" "F.Mask" "F.Paste")
			(net "GND")
		)
		(pad "178" smd rect
			(at 2.050034 -35.275012 270)
			(size 0.519938 1.4986)
			(layers "F.Cu" "F.Mask" "F.Paste")
			(net "M_F_CPU0_SA_DQS_DN<7>")
		)
		(pad "179" smd rect
			(at 2.050034 -34.425128 270)
			(size 0.519938 1.4986)
			(layers "F.Cu" "F.Mask" "F.Paste")
			(net "M_F_CPU0_SA_DQS_DP<7>")
		)
		(pad "180" smd rect
			(at 2.050034 -33.57499 270)
			(size 0.519938 1.4986)
			(layers "F.Cu" "F.Mask" "F.Paste")
			(net "GND")
		)
		(pad "181" smd rect
			(at 2.050034 -32.725106 270)
			(size 0.519938 1.4986)
			(layers "F.Cu" "F.Mask" "F.Paste")
			(net "M_F_CPU0_SA_DQ<22>")
		)
		(pad "182" smd rect
			(at 2.050034 -31.874968 270)
			(size 0.519938 1.4986)
			(layers "F.Cu" "F.Mask" "F.Paste")
			(net "GND")
		)
		(pad "183" smd rect
			(at 2.050034 -31.025084 270)
			(size 0.519938 1.4986)
			(layers "F.Cu" "F.Mask" "F.Paste")
			(net "M_F_CPU0_SA_DQ<23>")
		)
		(pad "184" smd rect
			(at 2.050034 -30.174946 270)
			(size 0.519938 1.4986)
			(layers "F.Cu" "F.Mask" "F.Paste")
			(net "GND")
		)
		(pad "185" smd rect
			(at 2.050034 -29.325062 270)
			(size 0.519938 1.4986)
			(layers "F.Cu" "F.Mask" "F.Paste")
			(net "M_F_CPU0_SA_DQ<26>")
		)
		(pad "186" smd rect
			(at 2.050034 -28.474924 270)
			(size 0.519938 1.4986)
			(layers "F.Cu" "F.Mask" "F.Paste")
			(net "GND")
		)
		(pad "187" smd rect
			(at 2.050034 -27.62504 270)
			(size 0.519938 1.4986)
			(layers "F.Cu" "F.Mask" "F.Paste")
			(net "M_F_CPU0_SA_DQ<27>")
		)
		(pad "188" smd rect
			(at 2.050034 -26.774902 270)
			(size 0.519938 1.4986)
			(layers "F.Cu" "F.Mask" "F.Paste")
			(net "GND")
		)
		(pad "189" smd rect
			(at 2.050034 -25.925018 270)
			(size 0.519938 1.4986)
			(layers "F.Cu" "F.Mask" "F.Paste")
			(net "M_F_CPU0_SA_DQS_DN<8>")
		)
		(pad "190" smd rect
			(at 2.050034 -25.07488 270)
			(size 0.519938 1.4986)
			(layers "F.Cu" "F.Mask" "F.Paste")
			(net "M_F_CPU0_SA_DQS_DP<8>")
		)
		(pad "191" smd rect
			(at 2.050034 -24.224996 270)
			(size 0.519938 1.4986)
			(layers "F.Cu" "F.Mask" "F.Paste")
			(net "GND")
		)
		(pad "192" smd rect
			(at 2.050034 -23.375112 270)
			(size 0.519938 1.4986)
			(layers "F.Cu" "F.Mask" "F.Paste")
			(net "M_F_CPU0_SA_DQ<30>")
		)
		(pad "193" smd rect
			(at 2.050034 -22.524974 270)
			(size 0.519938 1.4986)
			(layers "F.Cu" "F.Mask" "F.Paste")
			(net "GND")
		)
		(pad "194" smd rect
			(at 2.050034 -21.67509 270)
			(size 0.519938 1.4986)
			(layers "F.Cu" "F.Mask" "F.Paste")
			(net "M_F_CPU0_SA_DQ<31>")
		)
		(pad "195" smd rect
			(at 2.050034 -20.824952 270)
			(size 0.519938 1.4986)
			(layers "F.Cu" "F.Mask" "F.Paste")
			(net "GND")
		)
		(pad "196" smd rect
			(at 2.050034 -19.975068 270)
			(size 0.519938 1.4986)
			(layers "F.Cu" "F.Mask" "F.Paste")
			(net "M_F_CPU0_SA_CB<2>")
		)
		(pad "197" smd rect
			(at 2.050034 -19.12493 270)
			(size 0.519938 1.4986)
			(layers "F.Cu" "F.Mask" "F.Paste")
			(net "GND")
		)
		(pad "198" smd rect
			(at 2.050034 -18.275046 270)
			(size 0.519938 1.4986)
			(layers "F.Cu" "F.Mask" "F.Paste")
			(net "M_F_CPU0_SA_CB<3>")
		)
		(pad "199" smd rect
			(at 2.050034 -17.424908 270)
			(size 0.519938 1.4986)
			(layers "F.Cu" "F.Mask" "F.Paste")
			(net "GND")
		)
		(pad "200" smd rect
			(at 2.050034 -16.575024 270)
			(size 0.519938 1.4986)
			(layers "F.Cu" "F.Mask" "F.Paste")
			(net "M_F_CPU0_SA_DQS_DN<9>")
		)
		(pad "201" smd rect
			(at 2.050034 -15.724886 270)
			(size 0.519938 1.4986)
			(layers "F.Cu" "F.Mask" "F.Paste")
			(net "M_F_CPU0_SA_DQS_DP<9>")
		)
		(pad "202" smd rect
			(at 2.050034 -14.875002 270)
			(size 0.519938 1.4986)
			(layers "F.Cu" "F.Mask" "F.Paste")
			(net "GND")
		)
		(pad "203" smd rect
			(at 2.050034 -14.025118 270)
			(size 0.519938 1.4986)
			(layers "F.Cu" "F.Mask" "F.Paste")
			(net "M_F_CPU0_SA_CB<6>")
		)
		(pad "204" smd rect
			(at 2.050034 -13.17498 270)
			(size 0.519938 1.4986)
			(layers "F.Cu" "F.Mask" "F.Paste")
			(net "GND")
		)
		(pad "205" smd rect
			(at 2.050034 -12.325096 270)
			(size 0.519938 1.4986)
			(layers "F.Cu" "F.Mask" "F.Paste")
			(net "M_F_CPU0_SA_CB<7>")
		)
		(pad "206" smd rect
			(at 2.050034 -11.474958 270)
			(size 0.519938 1.4986)
			(layers "F.Cu" "F.Mask" "F.Paste")
			(net "GND")
		)
		(pad "207" smd rect
			(at 2.050034 -10.625074 270)
			(size 0.519938 1.4986)
			(layers "F.Cu" "F.Mask" "F.Paste")
			(net "RST_M_EF_CPU0_FPGA_N")
		)
		(pad "208" smd rect
			(at 2.050034 -9.774936 270)
			(size 0.519938 1.4986)
			(layers "F.Cu" "F.Mask" "F.Paste")
			(net "GND")
		)
		(pad "209" smd rect
			(at 2.050034 -8.925052 270)
			(size 0.519938 1.4986)
			(layers "F.Cu" "F.Mask" "F.Paste")
			(net "M_F_CPU0_SA_CS_N<1>")
		)
		(pad "210" smd rect
			(at 2.050034 -8.074914 270)
			(size 0.519938 1.4986)
			(layers "F.Cu" "F.Mask" "F.Paste")
			(net "GND")
		)
		(pad "211" smd rect
			(at 2.050034 -7.22503 270)
			(size 0.519938 1.4986)
			(layers "F.Cu" "F.Mask" "F.Paste")
			(net "M_F_CPU0_SA_CA<1>")
		)
		(pad "212" smd rect
			(at 2.050034 -6.374892 270)
			(size 0.519938 1.4986)
			(layers "F.Cu" "F.Mask" "F.Paste")
			(net "GND")
		)
		(pad "213" smd rect
			(at 2.050034 -5.525008 270)
			(size 0.519938 1.4986)
			(layers "F.Cu" "F.Mask" "F.Paste")
			(net "M_F_CPU0_SA_CA<3>")
		)
		(pad "214" smd rect
			(at 2.050034 -4.675124 270)
			(size 0.519938 1.4986)
			(layers "F.Cu" "F.Mask" "F.Paste")
			(net "GND")
		)
		(pad "215" smd rect
			(at 2.050034 -3.824986 270)
			(size 0.519938 1.4986)
			(layers "F.Cu" "F.Mask" "F.Paste")
			(net "M_F_CPU0_SA_CA<5>")
		)
		(pad "216" smd rect
			(at 2.050034 -2.975102 270)
			(size 0.519938 1.4986)
			(layers "F.Cu" "F.Mask" "F.Paste")
			(net "GND")
		)
		(pad "217" smd rect
			(at 2.050034 -2.124964 270)
			(size 0.519938 1.4986)
			(layers "F.Cu" "F.Mask" "F.Paste")
			(net "M_F_CPU0_CLK_DP<0>")
		)
		(pad "218" smd rect
			(at 2.050034 -1.27508 270)
			(size 0.519938 1.4986)
			(layers "F.Cu" "F.Mask" "F.Paste")
			(net "M_F_CPU0_CLK_DN<0>")
		)
		(pad "219" smd rect
			(at 2.050034 -0.424942 270)
			(size 0.519938 1.4986)
			(layers "F.Cu" "F.Mask" "F.Paste")
			(net "GND")
		)
		(pad "220" smd rect
			(at 2.050034 5.525008 270)
			(size 0.519938 1.4986)
			(layers "F.Cu" "F.Mask" "F.Paste")
			(net "TP_CHF_CPU0_DIMM1_FRU_4")
		)
		(pad "221" smd rect
			(at 2.050034 6.374892 270)
			(size 0.519938 1.4986)
			(layers "F.Cu" "F.Mask" "F.Paste")
			(net "M_F_CPU0_SB_CA<1>")
		)
		(pad "222" smd rect
			(at 2.050034 7.22503 270)
			(size 0.519938 1.4986)
			(layers "F.Cu" "F.Mask" "F.Paste")
			(net "GND")
		)
		(pad "223" smd rect
			(at 2.050034 8.074914 270)
			(size 0.519938 1.4986)
			(layers "F.Cu" "F.Mask" "F.Paste")
			(net "M_F_CPU0_SB_CA<3>")
		)
		(pad "224" smd rect
			(at 2.050034 8.925052 270)
			(size 0.519938 1.4986)
			(layers "F.Cu" "F.Mask" "F.Paste")
			(net "GND")
		)
		(pad "225" smd rect
			(at 2.050034 9.774936 270)
			(size 0.519938 1.4986)
			(layers "F.Cu" "F.Mask" "F.Paste")
			(net "M_F_CPU0_SB_CA<5>")
		)
		(pad "226" smd rect
			(at 2.050034 10.625074 270)
			(size 0.519938 1.4986)
			(layers "F.Cu" "F.Mask" "F.Paste")
			(net "GND")
		)
		(pad "227" smd rect
			(at 2.050034 11.474958 270)
			(size 0.519938 1.4986)
			(layers "F.Cu" "F.Mask" "F.Paste")
			(net "M_F_CPU0_SB_PAR")
		)
		(pad "228" smd rect
			(at 2.050034 12.325096 270)
			(size 0.519938 1.4986)
			(layers "F.Cu" "F.Mask" "F.Paste")
			(net "GND")
		)
		(pad "229" smd rect
			(at 2.050034 13.17498 270)
			(size 0.519938 1.4986)
			(layers "F.Cu" "F.Mask" "F.Paste")
			(net "M_F_CPU0_SB_CS_N<1>")
		)
		(pad "230" smd rect
			(at 2.050034 14.025118 270)
			(size 0.519938 1.4986)
			(layers "F.Cu" "F.Mask" "F.Paste")
			(net "GND")
		)
		(pad "231" smd rect
			(at 2.050034 14.875002 270)
			(size 0.519938 1.4986)
			(layers "F.Cu" "F.Mask" "F.Paste")
			(net "TP_CHF_CPU0_DIMM1_FRU_5")
		)
		(pad "232" smd rect
			(at 2.050034 15.724886 270)
			(size 0.519938 1.4986)
			(layers "F.Cu" "F.Mask" "F.Paste")
			(net "TP_CHF_CPU0_DIMM1_FRU_6")
		)
		(pad "233" smd rect
			(at 2.050034 16.575024 270)
			(size 0.519938 1.4986)
			(layers "F.Cu" "F.Mask" "F.Paste")
			(net "GND")
		)
		(pad "234" smd rect
			(at 2.050034 17.424908 270)
			(size 0.519938 1.4986)
			(layers "F.Cu" "F.Mask" "F.Paste")
			(net "M_F_CPU0_SB_CB<6>")
		)
		(pad "235" smd rect
			(at 2.050034 18.275046 270)
			(size 0.519938 1.4986)
			(layers "F.Cu" "F.Mask" "F.Paste")
			(net "GND")
		)
		(pad "236" smd rect
			(at 2.050034 19.12493 270)
			(size 0.519938 1.4986)
			(layers "F.Cu" "F.Mask" "F.Paste")
			(net "M_F_CPU0_SB_CB<7>")
		)
		(pad "237" smd rect
			(at 2.050034 19.975068 270)
			(size 0.519938 1.4986)
			(layers "F.Cu" "F.Mask" "F.Paste")
			(net "GND")
		)
		(pad "238" smd rect
			(at 2.050034 20.824952 270)
			(size 0.519938 1.4986)
			(layers "F.Cu" "F.Mask" "F.Paste")
			(net "M_F_CPU0_SB_DQS_DN<4>")
		)
		(pad "239" smd rect
			(at 2.050034 21.67509 270)
			(size 0.519938 1.4986)
			(layers "F.Cu" "F.Mask" "F.Paste")
			(net "M_F_CPU0_SB_DQS_DP<4>")
		)
		(pad "240" smd rect
			(at 2.050034 22.524974 270)
			(size 0.519938 1.4986)
			(layers "F.Cu" "F.Mask" "F.Paste")
			(net "GND")
		)
		(pad "241" smd rect
			(at 2.050034 23.375112 270)
			(size 0.519938 1.4986)
			(layers "F.Cu" "F.Mask" "F.Paste")
			(net "M_F_CPU0_SB_CB<2>")
		)
		(pad "242" smd rect
			(at 2.050034 24.224996 270)
			(size 0.519938 1.4986)
			(layers "F.Cu" "F.Mask" "F.Paste")
			(net "GND")
		)
		(pad "243" smd rect
			(at 2.050034 25.07488 270)
			(size 0.519938 1.4986)
			(layers "F.Cu" "F.Mask" "F.Paste")
			(net "M_F_CPU0_SB_CB<3>")
		)
		(pad "244" smd rect
			(at 2.050034 25.925018 270)
			(size 0.519938 1.4986)
			(layers "F.Cu" "F.Mask" "F.Paste")
			(net "GND")
		)
		(pad "245" smd rect
			(at 2.050034 26.774902 270)
			(size 0.519938 1.4986)
			(layers "F.Cu" "F.Mask" "F.Paste")
			(net "M_F_CPU0_SB_DQ<2>")
		)
		(pad "246" smd rect
			(at 2.050034 27.62504 270)
			(size 0.519938 1.4986)
			(layers "F.Cu" "F.Mask" "F.Paste")
			(net "GND")
		)
		(pad "247" smd rect
			(at 2.050034 28.474924 270)
			(size 0.519938 1.4986)
			(layers "F.Cu" "F.Mask" "F.Paste")
			(net "M_F_CPU0_SB_DQ<3>")
		)
		(pad "248" smd rect
			(at 2.050034 29.325062 270)
			(size 0.519938 1.4986)
			(layers "F.Cu" "F.Mask" "F.Paste")
			(net "GND")
		)
		(pad "249" smd rect
			(at 2.050034 30.174946 270)
			(size 0.519938 1.4986)
			(layers "F.Cu" "F.Mask" "F.Paste")
			(net "M_F_CPU0_SB_DQS_DN<5>")
		)
		(pad "250" smd rect
			(at 2.050034 31.025084 270)
			(size 0.519938 1.4986)
			(layers "F.Cu" "F.Mask" "F.Paste")
			(net "M_F_CPU0_SB_DQS_DP<5>")
		)
		(pad "251" smd rect
			(at 2.050034 31.874968 270)
			(size 0.519938 1.4986)
			(layers "F.Cu" "F.Mask" "F.Paste")
			(net "GND")
		)
		(pad "252" smd rect
			(at 2.050034 32.725106 270)
			(size 0.519938 1.4986)
			(layers "F.Cu" "F.Mask" "F.Paste")
			(net "M_F_CPU0_SB_DQ<6>")
		)
		(pad "253" smd rect
			(at 2.050034 33.57499 270)
			(size 0.519938 1.4986)
			(layers "F.Cu" "F.Mask" "F.Paste")
			(net "GND")
		)
		(pad "254" smd rect
			(at 2.050034 34.425128 270)
			(size 0.519938 1.4986)
			(layers "F.Cu" "F.Mask" "F.Paste")
			(net "M_F_CPU0_SB_DQ<7>")
		)
		(pad "255" smd rect
			(at 2.050034 35.275012 270)
			(size 0.519938 1.4986)
			(layers "F.Cu" "F.Mask" "F.Paste")
			(net "GND")
		)
		(pad "256" smd rect
			(at 2.050034 36.124896 270)
			(size 0.519938 1.4986)
			(layers "F.Cu" "F.Mask" "F.Paste")
			(net "M_F_CPU0_SB_DQ<10>")
		)
		(pad "257" smd rect
			(at 2.050034 36.975034 270)
			(size 0.519938 1.4986)
			(layers "F.Cu" "F.Mask" "F.Paste")
			(net "GND")
		)
		(pad "258" smd rect
			(at 2.050034 37.824918 270)
			(size 0.519938 1.4986)
			(layers "F.Cu" "F.Mask" "F.Paste")
			(net "M_F_CPU0_SB_DQ<11>")
		)
		(pad "259" smd rect
			(at 2.050034 38.675056 270)
			(size 0.519938 1.4986)
			(layers "F.Cu" "F.Mask" "F.Paste")
			(net "GND")
		)
		(pad "260" smd rect
			(at 2.050034 39.52494 270)
			(size 0.519938 1.4986)
			(layers "F.Cu" "F.Mask" "F.Paste")
			(net "M_F_CPU0_SB_DQS_DN<6>")
		)
		(pad "261" smd rect
			(at 2.050034 40.375078 270)
			(size 0.519938 1.4986)
			(layers "F.Cu" "F.Mask" "F.Paste")
			(net "M_F_CPU0_SB_DQS_DP<6>")
		)
		(pad "262" smd rect
			(at 2.050034 41.224962 270)
			(size 0.519938 1.4986)
			(layers "F.Cu" "F.Mask" "F.Paste")
			(net "GND")
		)
		(pad "263" smd rect
			(at 2.050034 42.0751 270)
			(size 0.519938 1.4986)
			(layers "F.Cu" "F.Mask" "F.Paste")
			(net "M_F_CPU0_SB_DQ<14>")
		)
		(pad "264" smd rect
			(at 2.050034 42.924984 270)
			(size 0.519938 1.4986)
			(layers "F.Cu" "F.Mask" "F.Paste")
			(net "GND")
		)
		(pad "265" smd rect
			(at 2.050034 43.775122 270)
			(size 0.519938 1.4986)
			(layers "F.Cu" "F.Mask" "F.Paste")
			(net "M_F_CPU0_SB_DQ<15>")
		)
		(pad "266" smd rect
			(at 2.050034 44.625006 270)
			(size 0.519938 1.4986)
			(layers "F.Cu" "F.Mask" "F.Paste")
			(net "GND")
		)
		(pad "267" smd rect
			(at 2.050034 45.47489 270)
			(size 0.519938 1.4986)
			(layers "F.Cu" "F.Mask" "F.Paste")
			(net "M_F_CPU0_SB_DQ<18>")
		)
		(pad "268" smd rect
			(at 2.050034 46.325028 270)
			(size 0.519938 1.4986)
			(layers "F.Cu" "F.Mask" "F.Paste")
			(net "GND")
		)
		(pad "269" smd rect
			(at 2.050034 47.174912 270)
			(size 0.519938 1.4986)
			(layers "F.Cu" "F.Mask" "F.Paste")
			(net "M_F_CPU0_SB_DQ<19>")
		)
		(pad "270" smd rect
			(at 2.050034 48.02505 270)
			(size 0.519938 1.4986)
			(layers "F.Cu" "F.Mask" "F.Paste")
			(net "GND")
		)
		(pad "271" smd rect
			(at 2.050034 48.874934 270)
			(size 0.519938 1.4986)
			(layers "F.Cu" "F.Mask" "F.Paste")
			(net "M_F_CPU0_SB_DQS_DN<7>")
		)
		(pad "272" smd rect
			(at 2.050034 49.725072 270)
			(size 0.519938 1.4986)
			(layers "F.Cu" "F.Mask" "F.Paste")
			(net "M_F_CPU0_SB_DQS_DP<7>")
		)
		(pad "273" smd rect
			(at 2.050034 50.574956 270)
			(size 0.519938 1.4986)
			(layers "F.Cu" "F.Mask" "F.Paste")
			(net "GND")
		)
		(pad "274" smd rect
			(at 2.050034 51.425094 270)
			(size 0.519938 1.4986)
			(layers "F.Cu" "F.Mask" "F.Paste")
			(net "M_F_CPU0_SB_DQ<22>")
		)
		(pad "275" smd rect
			(at 2.050034 52.274978 270)
			(size 0.519938 1.4986)
			(layers "F.Cu" "F.Mask" "F.Paste")
			(net "GND")
		)
		(pad "276" smd rect
			(at 2.050034 53.125116 270)
			(size 0.519938 1.4986)
			(layers "F.Cu" "F.Mask" "F.Paste")
			(net "M_F_CPU0_SB_DQ<23>")
		)
		(pad "277" smd rect
			(at 2.050034 53.975 270)
			(size 0.519938 1.4986)
			(layers "F.Cu" "F.Mask" "F.Paste")
			(net "GND")
		)
		(pad "278" smd rect
			(at 2.050034 54.824884 270)
			(size 0.519938 1.4986)
			(layers "F.Cu" "F.Mask" "F.Paste")
			(net "M_F_CPU0_SB_DQ<26>")
		)
		(pad "279" smd rect
			(at 2.050034 55.675022 270)
			(size 0.519938 1.4986)
			(layers "F.Cu" "F.Mask" "F.Paste")
			(net "GND")
		)
		(pad "280" smd rect
			(at 2.050034 56.524906 270)
			(size 0.519938 1.4986)
			(layers "F.Cu" "F.Mask" "F.Paste")
			(net "M_F_CPU0_SB_DQ<27>")
		)
		(pad "281" smd rect
			(at 2.050034 57.375044 270)
			(size 0.519938 1.4986)
			(layers "F.Cu" "F.Mask" "F.Paste")
			(net "GND")
		)
		(pad "282" smd rect
			(at 2.050034 58.224928 270)
			(size 0.519938 1.4986)
			(layers "F.Cu" "F.Mask" "F.Paste")
			(net "M_F_CPU0_SB_DQS_DN<8>")
		)
		(pad "283" smd rect
			(at 2.050034 59.075066 270)
			(size 0.519938 1.4986)
			(layers "F.Cu" "F.Mask" "F.Paste")
			(net "M_F_CPU0_SB_DQS_DP<8>")
		)
		(pad "284" smd rect
			(at 2.050034 59.92495 270)
			(size 0.519938 1.4986)
			(layers "F.Cu" "F.Mask" "F.Paste")
			(net "GND")
		)
		(pad "285" smd rect
			(at 2.050034 60.775088 270)
			(size 0.519938 1.4986)
			(layers "F.Cu" "F.Mask" "F.Paste")
			(net "M_F_CPU0_SB_DQ<30>")
		)
		(pad "286" smd rect
			(at 2.050034 61.624972 270)
			(size 0.519938 1.4986)
			(layers "F.Cu" "F.Mask" "F.Paste")
			(net "GND")
		)
		(pad "287" smd rect
			(at 2.050034 62.47511 270)
			(size 0.519938 1.4986)
			(layers "F.Cu" "F.Mask" "F.Paste")
			(net "M_F_CPU0_SB_DQ<31>")
		)
		(pad "288" smd rect
			(at 2.050034 63.324994 270)
			(size 0.519938 1.4986)
			(layers "F.Cu" "F.Mask" "F.Paste")
			(net "GND")
		)
		(pad "G1" thru_hole oval
			(at 0 -68.97497)
			(size 2.8194 1.5748)
			(drill oval 2.4384 1.1938)
			(layers "*.Cu" "*.Mask")
			(remove_unused_layers no)
			(net "GND")
			(clearance 0.127)
			(thermal_gap 0.127)
		)
		(pad "G2" thru_hole oval
			(at 0 3.875024)
			(size 2.8194 1.5748)
			(drill oval 2.4384 1.1938)
			(layers "*.Cu" "*.Mask")
			(remove_unused_layers no)
			(net "GND")
			(clearance 0.127)
			(thermal_gap 0.127)
		)
		(pad "G3" thru_hole oval
			(at 0 68.97497)
			(size 2.8194 1.5748)
			(drill oval 2.4384 1.1938)
			(layers "*.Cu" "*.Mask")
			(remove_unused_layers no)
			(net "GND")
			(clearance 0.127)
			(thermal_gap 0.127)
		)
	)
	(footprint ""
		(layer "F.Cu")
		(at 166.351458 -133.77672 90)
		(property "Reference" "C1226"
			(at 0 0 90)
			(layer "F.SilkS")
			(hide yes)
			(effects
				(font
					(size 1.27 1.27)
				)
			)
		)
		(property "Value" ""
			(at 0 0 90)
			(layer "F.Fab")
			(effects
				(font
					(size 1.27 1.27)
				)
			)
		)
		(duplicate_pad_numbers_are_jumpers no)
		(fp_line
			(start 0.7874 -0.4064)
			(end 0.7874 0.4064)
			(stroke
				(width 0.1524)
				(type default)
			)
			(layer "F.SilkS")
		)
		(fp_line
			(start -0.7874 -0.4064)
			(end 0.7874 -0.4064)
			(stroke
				(width 0.1524)
				(type default)
			)
			(layer "F.SilkS")
		)
		(fp_line
			(start 0.7874 0.4064)
			(end -0.7874 0.4064)
			(stroke
				(width 0.1524)
				(type default)
			)
			(layer "F.SilkS")
		)
		(fp_line
			(start -0.7874 0.4064)
			(end -0.7874 -0.4064)
			(stroke
				(width 0.1524)
				(type default)
			)
			(layer "F.SilkS")
		)
		(fp_line
			(start -0.12065 -0.305054)
			(end -0.12065 -0.2794)
			(stroke
				(width 0.1)
				(type default)
			)
			(layer "F.Fab")
		)
		(fp_line
			(start -0.67945 -0.305054)
			(end -0.12065 -0.305054)
			(stroke
				(width 0.1)
				(type default)
			)
			(layer "F.Fab")
		)
		(fp_line
			(start 0.67945 -0.3048)
			(end 0.67945 0.3048)
			(stroke
				(width 0.1)
				(type default)
			)
			(layer "F.Fab")
		)
		(fp_line
			(start 0.12065 -0.3048)
			(end 0.67945 -0.3048)
			(stroke
				(width 0.1)
				(type default)
			)
			(layer "F.Fab")
		)
		(fp_line
			(start 0.12065 -0.2794)
			(end 0.12065 -0.3048)
			(stroke
				(width 0.1)
				(type default)
			)
			(layer "F.Fab")
		)
		(fp_line
			(start -0.12065 -0.2794)
			(end 0.12065 -0.2794)
			(stroke
				(width 0.1)
				(type default)
			)
			(layer "F.Fab")
		)
		(fp_line
			(start 0.120396 0.2794)
			(end -0.12065 0.2794)
			(stroke
				(width 0.1)
				(type default)
			)
			(layer "F.Fab")
		)
		(fp_line
			(start -0.12065 0.2794)
			(end -0.12065 0.3048)
			(stroke
				(width 0.1)
				(type default)
			)
			(layer "F.Fab")
		)
		(fp_line
			(start 0.67945 0.3048)
			(end 0.120396 0.3048)
			(stroke
				(width 0.1)
				(type default)
			)
			(layer "F.Fab")
		)
		(fp_line
			(start 0.120396 0.3048)
			(end 0.120396 0.2794)
			(stroke
				(width 0.1)
				(type default)
			)
			(layer "F.Fab")
		)
		(fp_line
			(start -0.12065 0.3048)
			(end -0.67945 0.3048)
			(stroke
				(width 0.1)
				(type default)
			)
			(layer "F.Fab")
		)
		(fp_line
			(start -0.67945 0.3048)
			(end -0.67945 -0.305054)
			(stroke
				(width 0.1)
				(type default)
			)
			(layer "F.Fab")
		)
		(pad "1" smd circle
			(at -0.40005 0 90)
			(size 0 0)
			(layers "F.Cu" "F.Mask" "F.Paste")
			(net "VR_P5V_EN_D_R")
		)
		(pad "2" smd circle
			(at 0.40005 0 90)
			(size 0 0)
			(layers "F.Cu" "F.Mask" "F.Paste")
			(net "GND")
		)
	)
	(footprint ""
		(layer "F.Cu")
		(at 178.816 -19.776948 90)
		(property "Reference" "R1387"
			(at 0 0 90)
			(layer "F.SilkS")
			(hide yes)
			(effects
				(font
					(size 1.27 1.27)
				)
			)
		)
		(property "Value" ""
			(at 0 0 90)
			(layer "F.Fab")
			(effects
				(font
					(size 1.27 1.27)
				)
			)
		)
		(duplicate_pad_numbers_are_jumpers no)
		(fp_line
			(start 0.7874 -0.4064)
			(end 0.7874 0.4064)
			(stroke
				(width 0.1524)
				(type default)
			)
			(layer "F.SilkS")
		)
		(fp_line
			(start -0.7874 -0.4064)
			(end 0.7874 -0.4064)
			(stroke
				(width 0.1524)
				(type default)
			)
			(layer "F.SilkS")
		)
		(fp_line
			(start 0.7874 0.4064)
			(end -0.7874 0.4064)
			(stroke
				(width 0.1524)
				(type default)
			)
			(layer "F.SilkS")
		)
		(fp_line
			(start -0.7874 0.4064)
			(end -0.7874 -0.4064)
			(stroke
				(width 0.1524)
				(type default)
			)
			(layer "F.SilkS")
		)
		(fp_line
			(start -0.12065 -0.305054)
			(end -0.12065 -0.2794)
			(stroke
				(width 0.1)
				(type default)
			)
			(layer "F.Fab")
		)
		(fp_line
			(start -0.67945 -0.305054)
			(end -0.12065 -0.305054)
			(stroke
				(width 0.1)
				(type default)
			)
			(layer "F.Fab")
		)
		(fp_line
			(start 0.67945 -0.3048)
			(end 0.67945 0.3048)
			(stroke
				(width 0.1)
				(type default)
			)
			(layer "F.Fab")
		)
		(fp_line
			(start 0.12065 -0.3048)
			(end 0.67945 -0.3048)
			(stroke
				(width 0.1)
				(type default)
			)
			(layer "F.Fab")
		)
		(fp_line
			(start 0.12065 -0.2794)
			(end 0.12065 -0.3048)
			(stroke
				(width 0.1)
				(type default)
			)
			(layer "F.Fab")
		)
		(fp_line
			(start -0.12065 -0.2794)
			(end 0.12065 -0.2794)
			(stroke
				(width 0.1)
				(type default)
			)
			(layer "F.Fab")
		)
		(fp_line
			(start 0.120396 0.2794)
			(end -0.12065 0.2794)
			(stroke
				(width 0.1)
				(type default)
			)
			(layer "F.Fab")
		)
		(fp_line
			(start -0.12065 0.2794)
			(end -0.12065 0.3048)
			(stroke
				(width 0.1)
				(type default)
			)
			(layer "F.Fab")
		)
		(fp_line
			(start 0.67945 0.3048)
			(end 0.120396 0.3048)
			(stroke
				(width 0.1)
				(type default)
			)
			(layer "F.Fab")
		)
		(fp_line
			(start 0.120396 0.3048)
			(end 0.120396 0.2794)
			(stroke
				(width 0.1)
				(type default)
			)
			(layer "F.Fab")
		)
		(fp_line
			(start -0.12065 0.3048)
			(end -0.67945 0.3048)
			(stroke
				(width 0.1)
				(type default)
			)
			(layer "F.Fab")
		)
		(fp_line
			(start -0.67945 0.3048)
			(end -0.67945 -0.305054)
			(stroke
				(width 0.1)
				(type default)
			)
			(layer "F.Fab")
		)
		(pad "1" smd circle
			(at -0.40005 0 90)
			(size 0 0)
			(layers "F.Cu" "F.Mask" "F.Paste")
			(net "SMB_SML1_PMBUS_3V3AUX_PCH_SDA")
		)
		(pad "2" smd circle
			(at 0.40005 0 90)
			(size 0 0)
			(layers "F.Cu" "F.Mask" "F.Paste")
			(net "P3V3_AUX")
		)
	)
	(footprint ""
		(layer "F.Cu")
		(at 74.720958 -408.517344 -90)
		(property "Reference" "C693"
			(at 0 0 270)
			(layer "F.SilkS")
			(hide yes)
			(effects
				(font
					(size 1.27 1.27)
				)
			)
		)
		(property "Value" ""
			(at 0 0 270)
			(layer "F.Fab")
			(effects
				(font
					(size 1.27 1.27)
				)
			)
		)
		(duplicate_pad_numbers_are_jumpers no)
		(fp_line
			(start -0.299974 0.150114)
			(end -0.299974 -0.150114)
			(stroke
				(width 0.1)
				(type default)
			)
			(layer "F.Fab")
		)
		(fp_line
			(start 0.299974 0.150114)
			(end -0.299974 0.150114)
			(stroke
				(width 0.1)
				(type default)
			)
			(layer "F.Fab")
		)
		(fp_line
			(start -0.299974 -0.150114)
			(end 0.299974 -0.150114)
			(stroke
				(width 0.1)
				(type default)
			)
			(layer "F.Fab")
		)
		(fp_line
			(start 0.299974 -0.150114)
			(end 0.299974 0.150114)
			(stroke
				(width 0.1)
				(type default)
			)
			(layer "F.Fab")
		)
		(pad "1" smd rect
			(at -0.2667 0 270)
			(size 0.3048 0.381)
			(layers "F.Cu" "F.Mask" "F.Paste")
			(net "P5E_CPU1_PE4_TX_C_DP<8>")
		)
		(pad "2" smd rect
			(at 0.2667 0 270)
			(size 0.3048 0.381)
			(layers "F.Cu" "F.Mask" "F.Paste")
			(net "P5E_CPU1_PE4_TX_DP<8>")
		)
	)
	(footprint ""
		(layer "F.Cu")
		(at 320.190622 -56.251348)
		(property "Reference" "R611"
			(at 0 0 0)
			(layer "F.SilkS")
			(hide yes)
			(effects
				(font
					(size 1.27 1.27)
				)
			)
		)
		(property "Value" ""
			(at 0 0 0)
			(layer "F.Fab")
			(effects
				(font
					(size 1.27 1.27)
				)
			)
		)
		(duplicate_pad_numbers_are_jumpers no)
		(fp_line
			(start -0.7874 -0.4064)
			(end 0.7874 -0.4064)
			(stroke
				(width 0.1524)
				(type default)
			)
			(layer "F.SilkS")
		)
		(fp_line
			(start -0.7874 0.4064)
			(end -0.7874 -0.4064)
			(stroke
				(width 0.1524)
				(type default)
			)
			(layer "F.SilkS")
		)
		(fp_line
			(start 0.7874 -0.4064)
			(end 0.7874 0.4064)
			(stroke
				(width 0.1524)
				(type default)
			)
			(layer "F.SilkS")
		)
		(fp_line
			(start 0.7874 0.4064)
			(end -0.7874 0.4064)
			(stroke
				(width 0.1524)
				(type default)
			)
			(layer "F.SilkS")
		)
		(fp_line
			(start -0.67945 -0.305054)
			(end -0.12065 -0.305054)
			(stroke
				(width 0.1)
				(type default)
			)
			(layer "F.Fab")
		)
		(fp_line
			(start -0.67945 0.3048)
			(end -0.67945 -0.305054)
			(stroke
				(width 0.1)
				(type default)
			)
			(layer "F.Fab")
		)
		(fp_line
			(start -0.12065 -0.305054)
			(end -0.12065 -0.2794)
			(stroke
				(width 0.1)
				(type default)
			)
			(layer "F.Fab")
		)
		(fp_line
			(start -0.12065 -0.2794)
			(end 0.12065 -0.2794)
			(stroke
				(width 0.1)
				(type default)
			)
			(layer "F.Fab")
		)
		(fp_line
			(start -0.12065 0.2794)
			(end -0.12065 0.3048)
			(stroke
				(width 0.1)
				(type default)
			)
			(layer "F.Fab")
		)
		(fp_line
			(start -0.12065 0.3048)
			(end -0.67945 0.3048)
			(stroke
				(width 0.1)
				(type default)
			)
			(layer "F.Fab")
		)
		(fp_line
			(start 0.120396 0.2794)
			(end -0.12065 0.2794)
			(stroke
				(width 0.1)
				(type default)
			)
			(layer "F.Fab")
		)
		(fp_line
			(start 0.120396 0.3048)
			(end 0.120396 0.2794)
			(stroke
				(width 0.1)
				(type default)
			)
			(layer "F.Fab")
		)
		(fp_line
			(start 0.12065 -0.3048)
			(end 0.67945 -0.3048)
			(stroke
				(width 0.1)
				(type default)
			)
			(layer "F.Fab")
		)
		(fp_line
			(start 0.12065 -0.2794)
			(end 0.12065 -0.3048)
			(stroke
				(width 0.1)
				(type default)
			)
			(layer "F.Fab")
		)
		(fp_line
			(start 0.67945 -0.3048)
			(end 0.67945 0.3048)
			(stroke
				(width 0.1)
				(type default)
			)
			(layer "F.Fab")
		)
		(fp_line
			(start 0.67945 0.3048)
			(end 0.120396 0.3048)
			(stroke
				(width 0.1)
				(type default)
			)
			(layer "F.Fab")
		)
		(pad "1" smd circle
			(at -0.40005 0)
			(size 0 0)
			(layers "F.Cu" "F.Mask" "F.Paste")
			(net "P3V3_AUX")
		)
		(pad "2" smd circle
			(at 0.40005 0)
			(size 0 0)
			(layers "F.Cu" "F.Mask" "F.Paste")
			(net "FM_PCH_EXTERNALCLKMODE")
		)
	)
	(footprint ""
		(layer "F.Cu")
		(at 210.560412 -100.908104)
		(property "Reference" "R2233"
			(at 0 0 0)
			(layer "F.SilkS")
			(hide yes)
			(effects
				(font
					(size 1.27 1.27)
				)
			)
		)
		(property "Value" ""
			(at 0 0 0)
			(layer "F.Fab")
			(effects
				(font
					(size 1.27 1.27)
				)
			)
		)
		(duplicate_pad_numbers_are_jumpers no)
		(fp_line
			(start -0.7874 -0.4064)
			(end 0.7874 -0.4064)
			(stroke
				(width 0.1524)
				(type default)
			)
			(layer "F.SilkS")
		)
		(fp_line
			(start -0.7874 0.4064)
			(end -0.7874 -0.4064)
			(stroke
				(width 0.1524)
				(type default)
			)
			(layer "F.SilkS")
		)
		(fp_line
			(start 0.7874 -0.4064)
			(end 0.7874 0.4064)
			(stroke
				(width 0.1524)
				(type default)
			)
			(layer "F.SilkS")
		)
		(fp_line
			(start 0.7874 0.4064)
			(end -0.7874 0.4064)
			(stroke
				(width 0.1524)
				(type default)
			)
			(layer "F.SilkS")
		)
		(fp_line
			(start -0.67945 -0.305054)
			(end -0.12065 -0.305054)
			(stroke
				(width 0.1)
				(type default)
			)
			(layer "F.Fab")
		)
		(fp_line
			(start -0.67945 0.3048)
			(end -0.67945 -0.305054)
			(stroke
				(width 0.1)
				(type default)
			)
			(layer "F.Fab")
		)
		(fp_line
			(start -0.12065 -0.305054)
			(end -0.12065 -0.2794)
			(stroke
				(width 0.1)
				(type default)
			)
			(layer "F.Fab")
		)
		(fp_line
			(start -0.12065 -0.2794)
			(end 0.12065 -0.2794)
			(stroke
				(width 0.1)
				(type default)
			)
			(layer "F.Fab")
		)
		(fp_line
			(start -0.12065 0.2794)
			(end -0.12065 0.3048)
			(stroke
				(width 0.1)
				(type default)
			)
			(layer "F.Fab")
		)
		(fp_line
			(start -0.12065 0.3048)
			(end -0.67945 0.3048)
			(stroke
				(width 0.1)
				(type default)
			)
			(layer "F.Fab")
		)
		(fp_line
			(start 0.120396 0.2794)
			(end -0.12065 0.2794)
			(stroke
				(width 0.1)
				(type default)
			)
			(layer "F.Fab")
		)
		(fp_line
			(start 0.120396 0.3048)
			(end 0.120396 0.2794)
			(stroke
				(width 0.1)
				(type default)
			)
			(layer "F.Fab")
		)
		(fp_line
			(start 0.12065 -0.3048)
			(end 0.67945 -0.3048)
			(stroke
				(width 0.1)
				(type default)
			)
			(layer "F.Fab")
		)
		(fp_line
			(start 0.12065 -0.2794)
			(end 0.12065 -0.3048)
			(stroke
				(width 0.1)
				(type default)
			)
			(layer "F.Fab")
		)
		(fp_line
			(start 0.67945 -0.3048)
			(end 0.67945 0.3048)
			(stroke
				(width 0.1)
				(type default)
			)
			(layer "F.Fab")
		)
		(fp_line
			(start 0.67945 0.3048)
			(end 0.120396 0.3048)
			(stroke
				(width 0.1)
				(type default)
			)
			(layer "F.Fab")
		)
		(pad "1" smd circle
			(at -0.40005 0)
			(size 0 0)
			(layers "F.Cu" "F.Mask" "F.Paste")
			(net "P3V3_AUX")
		)
		(pad "2" smd circle
			(at 0.40005 0)
			(size 0 0)
			(layers "F.Cu" "F.Mask" "F.Paste")
			(net "FM_UV_ADR_TRIGGER_N")
		)
	)
	(footprint ""
		(layer "F.Cu")
		(at 353.254818 -244.03177 90)
		(property "Reference" "C999"
			(at 0 0 90)
			(layer "F.SilkS")
			(hide yes)
			(effects
				(font
					(size 1.27 1.27)
				)
			)
		)
		(property "Value" ""
			(at 0 0 90)
			(layer "F.Fab")
			(effects
				(font
					(size 1.27 1.27)
				)
			)
		)
		(duplicate_pad_numbers_are_jumpers no)
		(fp_line
			(start 0.7874 -0.4064)
			(end 0.7874 0.4064)
			(stroke
				(width 0.1524)
				(type default)
			)
			(layer "F.SilkS")
		)
		(fp_line
			(start -0.7874 -0.4064)
			(end 0.7874 -0.4064)
			(stroke
				(width 0.1524)
				(type default)
			)
			(layer "F.SilkS")
		)
		(fp_line
			(start 0.7874 0.4064)
			(end -0.7874 0.4064)
			(stroke
				(width 0.1524)
				(type default)
			)
			(layer "F.SilkS")
		)
		(fp_line
			(start -0.7874 0.4064)
			(end -0.7874 -0.4064)
			(stroke
				(width 0.1524)
				(type default)
			)
			(layer "F.SilkS")
		)
		(fp_line
			(start -0.12065 -0.305054)
			(end -0.12065 -0.2794)
			(stroke
				(width 0.1)
				(type default)
			)
			(layer "F.Fab")
		)
		(fp_line
			(start -0.67945 -0.305054)
			(end -0.12065 -0.305054)
			(stroke
				(width 0.1)
				(type default)
			)
			(layer "F.Fab")
		)
		(fp_line
			(start 0.67945 -0.3048)
			(end 0.67945 0.3048)
			(stroke
				(width 0.1)
				(type default)
			)
			(layer "F.Fab")
		)
		(fp_line
			(start 0.12065 -0.3048)
			(end 0.67945 -0.3048)
			(stroke
				(width 0.1)
				(type default)
			)
			(layer "F.Fab")
		)
		(fp_line
			(start 0.12065 -0.2794)
			(end 0.12065 -0.3048)
			(stroke
				(width 0.1)
				(type default)
			)
			(layer "F.Fab")
		)
		(fp_line
			(start -0.12065 -0.2794)
			(end 0.12065 -0.2794)
			(stroke
				(width 0.1)
				(type default)
			)
			(layer "F.Fab")
		)
		(fp_line
			(start 0.120396 0.2794)
			(end -0.12065 0.2794)
			(stroke
				(width 0.1)
				(type default)
			)
			(layer "F.Fab")
		)
		(fp_line
			(start -0.12065 0.2794)
			(end -0.12065 0.3048)
			(stroke
				(width 0.1)
				(type default)
			)
			(layer "F.Fab")
		)
		(fp_line
			(start 0.67945 0.3048)
			(end 0.120396 0.3048)
			(stroke
				(width 0.1)
				(type default)
			)
			(layer "F.Fab")
		)
		(fp_line
			(start 0.120396 0.3048)
			(end 0.120396 0.2794)
			(stroke
				(width 0.1)
				(type default)
			)
			(layer "F.Fab")
		)
		(fp_line
			(start -0.12065 0.3048)
			(end -0.67945 0.3048)
			(stroke
				(width 0.1)
				(type default)
			)
			(layer "F.Fab")
		)
		(fp_line
			(start -0.67945 0.3048)
			(end -0.67945 -0.305054)
			(stroke
				(width 0.1)
				(type default)
			)
			(layer "F.Fab")
		)
		(pad "1" smd circle
			(at -0.40005 0 90)
			(size 0 0)
			(layers "F.Cu" "F.Mask" "F.Paste")
			(net "PVCCIN_CPU0")
		)
		(pad "2" smd circle
			(at 0.40005 0 90)
			(size 0 0)
			(layers "F.Cu" "F.Mask" "F.Paste")
			(net "GND")
		)
	)
	(footprint ""
		(layer "F.Cu")
		(at 102.306374 -409.57754 90)
		(property "Reference" "C2075"
			(at 0 0 90)
			(layer "F.SilkS")
			(hide yes)
			(effects
				(font
					(size 1.27 1.27)
				)
			)
		)
		(property "Value" ""
			(at 0 0 90)
			(layer "F.Fab")
			(effects
				(font
					(size 1.27 1.27)
				)
			)
		)
		(duplicate_pad_numbers_are_jumpers no)
		(fp_line
			(start 0.299974 -0.150114)
			(end 0.299974 0.150114)
			(stroke
				(width 0.1)
				(type default)
			)
			(layer "F.Fab")
		)
		(fp_line
			(start -0.299974 -0.150114)
			(end 0.299974 -0.150114)
			(stroke
				(width 0.1)
				(type default)
			)
			(layer "F.Fab")
		)
		(fp_line
			(start 0.299974 0.150114)
			(end -0.299974 0.150114)
			(stroke
				(width 0.1)
				(type default)
			)
			(layer "F.Fab")
		)
		(fp_line
			(start -0.299974 0.150114)
			(end -0.299974 -0.150114)
			(stroke
				(width 0.1)
				(type default)
			)
			(layer "F.Fab")
		)
		(pad "1" smd rect
			(at -0.2667 0 90)
			(size 0.3048 0.381)
			(layers "F.Cu" "F.Mask" "F.Paste")
			(net "P3E_PCH_NVS_TX_DP<0>")
		)
		(pad "2" smd rect
			(at 0.2667 0 90)
			(size 0.3048 0.381)
			(layers "F.Cu" "F.Mask" "F.Paste")
			(net "P3E_PCH_NVS_TX_C_DP<0>")
		)
		(zone
			(layer "In1.Cu")
			(hatch none 0.5)
			(connect_pads
				(clearance 0)
			)
			(min_thickness 0.25)
			(keepout
				(tracks not_allowed)
				(vias allowed)
				(pads allowed)
				(copperpour not_allowed)
				(footprints allowed)
			)
			(placement
				(enabled no)
				(sheetname "")
			)
			(fill
				(thermal_gap 0.5)
				(thermal_bridge_width 0.5)
				(island_removal_mode 0)
			)
			(polygon
				(pts
					(arc
						(start 102.547674 -409.71724)
						(mid 102.525356 -409.663358)
						(end 102.471474 -409.64104)
					)
					(arc
						(start 102.141274 -409.64104)
						(mid 102.087392 -409.663358)
						(end 102.065074 -409.71724)
					)
					(arc
						(start 102.065074 -409.97124)
						(mid 102.087392 -410.025122)
						(end 102.141274 -410.04744)
					)
					(arc
						(start 102.471474 -410.04744)
						(mid 102.525356 -410.025122)
						(end 102.547674 -409.97124)
					)
				)
			)
		)
		(zone
			(layer "In1.Cu")
			(hatch none 0.5)
			(connect_pads
				(clearance 0)
			)
			(min_thickness 0.25)
			(keepout
				(tracks not_allowed)
				(vias allowed)
				(pads allowed)
				(copperpour not_allowed)
				(footprints allowed)
			)
			(placement
				(enabled no)
				(sheetname "")
			)
			(fill
				(thermal_gap 0.5)
				(thermal_bridge_width 0.5)
				(island_removal_mode 0)
			)
			(polygon
				(pts
					(arc
						(start 102.547674 -409.18384)
						(mid 102.525356 -409.129958)
						(end 102.471474 -409.10764)
					)
					(arc
						(start 102.141274 -409.10764)
						(mid 102.087392 -409.129958)
						(end 102.065074 -409.18384)
					)
					(arc
						(start 102.065074 -409.43784)
						(mid 102.087392 -409.491722)
						(end 102.141274 -409.51404)
					)
					(arc
						(start 102.471474 -409.51404)
						(mid 102.525356 -409.491722)
						(end 102.547674 -409.43784)
					)
				)
			)
		)
	)
	(footprint ""
		(layer "F.Cu")
		(at 379.319536 -105.483152 90)
		(property "Reference" "R1369"
			(at 0 0 90)
			(layer "F.SilkS")
			(hide yes)
			(effects
				(font
					(size 1.27 1.27)
				)
			)
		)
		(property "Value" ""
			(at 0 0 90)
			(layer "F.Fab")
			(effects
				(font
					(size 1.27 1.27)
				)
			)
		)
		(duplicate_pad_numbers_are_jumpers no)
		(fp_line
			(start 0.7874 -0.4064)
			(end 0.7874 0.4064)
			(stroke
				(width 0.1524)
				(type default)
			)
			(layer "F.SilkS")
		)
		(fp_line
			(start -0.7874 -0.4064)
			(end 0.7874 -0.4064)
			(stroke
				(width 0.1524)
				(type default)
			)
			(layer "F.SilkS")
		)
		(fp_line
			(start 0.7874 0.4064)
			(end -0.7874 0.4064)
			(stroke
				(width 0.1524)
				(type default)
			)
			(layer "F.SilkS")
		)
		(fp_line
			(start -0.7874 0.4064)
			(end -0.7874 -0.4064)
			(stroke
				(width 0.1524)
				(type default)
			)
			(layer "F.SilkS")
		)
		(fp_line
			(start -0.12065 -0.305054)
			(end -0.12065 -0.2794)
			(stroke
				(width 0.1)
				(type default)
			)
			(layer "F.Fab")
		)
		(fp_line
			(start -0.67945 -0.305054)
			(end -0.12065 -0.305054)
			(stroke
				(width 0.1)
				(type default)
			)
			(layer "F.Fab")
		)
		(fp_line
			(start 0.67945 -0.3048)
			(end 0.67945 0.3048)
			(stroke
				(width 0.1)
				(type default)
			)
			(layer "F.Fab")
		)
		(fp_line
			(start 0.12065 -0.3048)
			(end 0.67945 -0.3048)
			(stroke
				(width 0.1)
				(type default)
			)
			(layer "F.Fab")
		)
		(fp_line
			(start 0.12065 -0.2794)
			(end 0.12065 -0.3048)
			(stroke
				(width 0.1)
				(type default)
			)
			(layer "F.Fab")
		)
		(fp_line
			(start -0.12065 -0.2794)
			(end 0.12065 -0.2794)
			(stroke
				(width 0.1)
				(type default)
			)
			(layer "F.Fab")
		)
		(fp_line
			(start 0.120396 0.2794)
			(end -0.12065 0.2794)
			(stroke
				(width 0.1)
				(type default)
			)
			(layer "F.Fab")
		)
		(fp_line
			(start -0.12065 0.2794)
			(end -0.12065 0.3048)
			(stroke
				(width 0.1)
				(type default)
			)
			(layer "F.Fab")
		)
		(fp_line
			(start 0.67945 0.3048)
			(end 0.120396 0.3048)
			(stroke
				(width 0.1)
				(type default)
			)
			(layer "F.Fab")
		)
		(fp_line
			(start 0.120396 0.3048)
			(end 0.120396 0.2794)
			(stroke
				(width 0.1)
				(type default)
			)
			(layer "F.Fab")
		)
		(fp_line
			(start -0.12065 0.3048)
			(end -0.67945 0.3048)
			(stroke
				(width 0.1)
				(type default)
			)
			(layer "F.Fab")
		)
		(fp_line
			(start -0.67945 0.3048)
			(end -0.67945 -0.305054)
			(stroke
				(width 0.1)
				(type default)
			)
			(layer "F.Fab")
		)
		(pad "1" smd circle
			(at -0.40005 0 90)
			(size 0 0)
			(layers "F.Cu" "F.Mask" "F.Paste")
			(net "PD_JTAG_DBP_B0")
		)
		(pad "2" smd circle
			(at 0.40005 0 90)
			(size 0 0)
			(layers "F.Cu" "F.Mask" "F.Paste")
			(net "GND")
		)
	)
	(footprint ""
		(layer "F.Cu")
		(at 459.22946 -420.632128)
		(property "Reference" ""
			(at 0 0 0)
			(layer "F.SilkS")
			(hide yes)
			(effects
				(font
					(size 1.27 1.27)
				)
			)
		)
		(property "Value" ""
			(at 0 0 0)
			(layer "F.Fab")
			(effects
				(font
					(size 1.27 1.27)
				)
			)
		)
		(duplicate_pad_numbers_are_jumpers no)
		(pad "1" smd circle
			(at 0 0)
			(size 0.9906 0.9906)
			(layers "F.Cu" "F.Mask" "F.Paste")
			(net "Net_285")
		)
		(zone
			(layer "F.Cu")
			(hatch none 0.5)
			(connect_pads
				(clearance 0)
			)
			(min_thickness 0.25)
			(keepout
				(tracks not_allowed)
				(vias allowed)
				(pads allowed)
				(copperpour not_allowed)
				(footprints allowed)
			)
			(placement
				(enabled no)
				(sheetname "")
			)
			(fill
				(thermal_gap 0.5)
				(thermal_bridge_width 0.5)
				(island_removal_mode 0)
			)
			(polygon
				(pts
					(arc
						(start 460.85506 -420.632128)
						(mid 457.60386 -420.632128)
						(end 460.85506 -420.632128)
					)
				)
			)
		)
	)
	(footprint ""
		(layer "F.Cu")
		(at 121.430034 -358.430576)
		(property "Reference" "PC1264"
			(at 0 0 0)
			(layer "F.SilkS")
			(hide yes)
			(effects
				(font
					(size 1.27 1.27)
				)
			)
		)
		(property "Value" ""
			(at 0 0 0)
			(layer "F.Fab")
			(effects
				(font
					(size 1.27 1.27)
				)
			)
		)
		(duplicate_pad_numbers_are_jumpers no)
		(fp_line
			(start -0.7874 -0.4064)
			(end 0.7874 -0.4064)
			(stroke
				(width 0.1524)
				(type default)
			)
			(layer "F.SilkS")
		)
		(fp_line
			(start -0.7874 0.4064)
			(end -0.7874 -0.4064)
			(stroke
				(width 0.1524)
				(type default)
			)
			(layer "F.SilkS")
		)
		(fp_line
			(start 0.7874 -0.4064)
			(end 0.7874 0.4064)
			(stroke
				(width 0.1524)
				(type default)
			)
			(layer "F.SilkS")
		)
		(fp_line
			(start 0.7874 0.4064)
			(end -0.7874 0.4064)
			(stroke
				(width 0.1524)
				(type default)
			)
			(layer "F.SilkS")
		)
		(fp_line
			(start -0.67945 -0.305054)
			(end -0.12065 -0.305054)
			(stroke
				(width 0.1)
				(type default)
			)
			(layer "F.Fab")
		)
		(fp_line
			(start -0.67945 0.3048)
			(end -0.67945 -0.305054)
			(stroke
				(width 0.1)
				(type default)
			)
			(layer "F.Fab")
		)
		(fp_line
			(start -0.12065 -0.305054)
			(end -0.12065 -0.2794)
			(stroke
				(width 0.1)
				(type default)
			)
			(layer "F.Fab")
		)
		(fp_line
			(start -0.12065 -0.2794)
			(end 0.12065 -0.2794)
			(stroke
				(width 0.1)
				(type default)
			)
			(layer "F.Fab")
		)
		(fp_line
			(start -0.12065 0.2794)
			(end -0.12065 0.3048)
			(stroke
				(width 0.1)
				(type default)
			)
			(layer "F.Fab")
		)
		(fp_line
			(start -0.12065 0.3048)
			(end -0.67945 0.3048)
			(stroke
				(width 0.1)
				(type default)
			)
			(layer "F.Fab")
		)
		(fp_line
			(start 0.120396 0.2794)
			(end -0.12065 0.2794)
			(stroke
				(width 0.1)
				(type default)
			)
			(layer "F.Fab")
		)
		(fp_line
			(start 0.120396 0.3048)
			(end 0.120396 0.2794)
			(stroke
				(width 0.1)
				(type default)
			)
			(layer "F.Fab")
		)
		(fp_line
			(start 0.12065 -0.3048)
			(end 0.67945 -0.3048)
			(stroke
				(width 0.1)
				(type default)
			)
			(layer "F.Fab")
		)
		(fp_line
			(start 0.12065 -0.2794)
			(end 0.12065 -0.3048)
			(stroke
				(width 0.1)
				(type default)
			)
			(layer "F.Fab")
		)
		(fp_line
			(start 0.67945 -0.3048)
			(end 0.67945 0.3048)
			(stroke
				(width 0.1)
				(type default)
			)
			(layer "F.Fab")
		)
		(fp_line
			(start 0.67945 0.3048)
			(end 0.120396 0.3048)
			(stroke
				(width 0.1)
				(type default)
			)
			(layer "F.Fab")
		)
		(pad "1" smd circle
			(at -0.40005 0)
			(size 0 0)
			(layers "F.Cu" "F.Mask" "F.Paste")
			(net "PVPP_HBM_CPU1_REF")
		)
		(pad "2" smd circle
			(at 0.40005 0)
			(size 0 0)
			(layers "F.Cu" "F.Mask" "F.Paste")
			(net "SH_PVPP_HBM_CPU1_N")
		)
	)
	(footprint ""
		(layer "F.Cu")
		(at 107.287314 -258.72694 90)
		(property "Reference" "C221"
			(at 0 0 90)
			(layer "F.SilkS")
			(hide yes)
			(effects
				(font
					(size 1.27 1.27)
				)
			)
		)
		(property "Value" ""
			(at 0 0 90)
			(layer "F.Fab")
			(effects
				(font
					(size 1.27 1.27)
				)
			)
		)
		(duplicate_pad_numbers_are_jumpers no)
		(fp_line
			(start 0.7874 -0.4064)
			(end 0.7874 0.4064)
			(stroke
				(width 0.1524)
				(type default)
			)
			(layer "F.SilkS")
		)
		(fp_line
			(start -0.7874 -0.4064)
			(end 0.7874 -0.4064)
			(stroke
				(width 0.1524)
				(type default)
			)
			(layer "F.SilkS")
		)
		(fp_line
			(start 0.7874 0.4064)
			(end -0.7874 0.4064)
			(stroke
				(width 0.1524)
				(type default)
			)
			(layer "F.SilkS")
		)
		(fp_line
			(start -0.7874 0.4064)
			(end -0.7874 -0.4064)
			(stroke
				(width 0.1524)
				(type default)
			)
			(layer "F.SilkS")
		)
		(fp_line
			(start -0.12065 -0.305054)
			(end -0.12065 -0.2794)
			(stroke
				(width 0.1)
				(type default)
			)
			(layer "F.Fab")
		)
		(fp_line
			(start -0.67945 -0.305054)
			(end -0.12065 -0.305054)
			(stroke
				(width 0.1)
				(type default)
			)
			(layer "F.Fab")
		)
		(fp_line
			(start 0.67945 -0.3048)
			(end 0.67945 0.3048)
			(stroke
				(width 0.1)
				(type default)
			)
			(layer "F.Fab")
		)
		(fp_line
			(start 0.12065 -0.3048)
			(end 0.67945 -0.3048)
			(stroke
				(width 0.1)
				(type default)
			)
			(layer "F.Fab")
		)
		(fp_line
			(start 0.12065 -0.2794)
			(end 0.12065 -0.3048)
			(stroke
				(width 0.1)
				(type default)
			)
			(layer "F.Fab")
		)
		(fp_line
			(start -0.12065 -0.2794)
			(end 0.12065 -0.2794)
			(stroke
				(width 0.1)
				(type default)
			)
			(layer "F.Fab")
		)
		(fp_line
			(start 0.120396 0.2794)
			(end -0.12065 0.2794)
			(stroke
				(width 0.1)
				(type default)
			)
			(layer "F.Fab")
		)
		(fp_line
			(start -0.12065 0.2794)
			(end -0.12065 0.3048)
			(stroke
				(width 0.1)
				(type default)
			)
			(layer "F.Fab")
		)
		(fp_line
			(start 0.67945 0.3048)
			(end 0.120396 0.3048)
			(stroke
				(width 0.1)
				(type default)
			)
			(layer "F.Fab")
		)
		(fp_line
			(start 0.120396 0.3048)
			(end 0.120396 0.2794)
			(stroke
				(width 0.1)
				(type default)
			)
			(layer "F.Fab")
		)
		(fp_line
			(start -0.12065 0.3048)
			(end -0.67945 0.3048)
			(stroke
				(width 0.1)
				(type default)
			)
			(layer "F.Fab")
		)
		(fp_line
			(start -0.67945 0.3048)
			(end -0.67945 -0.305054)
			(stroke
				(width 0.1)
				(type default)
			)
			(layer "F.Fab")
		)
		(pad "1" smd circle
			(at -0.40005 0 90)
			(size 0 0)
			(layers "F.Cu" "F.Mask" "F.Paste")
			(net "PVCCIN_CPU1")
		)
		(pad "2" smd circle
			(at 0.40005 0 90)
			(size 0 0)
			(layers "F.Cu" "F.Mask" "F.Paste")
			(net "GND")
		)
	)
	(footprint ""
		(layer "F.Cu")
		(at 439.295032 -25.084278 180)
		(property "Reference" "PC2158"
			(at 0 0 180)
			(layer "F.SilkS")
			(hide yes)
			(effects
				(font
					(size 1.27 1.27)
				)
			)
		)
		(property "Value" ""
			(at 0 0 180)
			(layer "F.Fab")
			(effects
				(font
					(size 1.27 1.27)
				)
			)
		)
		(duplicate_pad_numbers_are_jumpers no)
		(fp_line
			(start 1.2954 0.5842)
			(end -1.2954 0.5842)
			(stroke
				(width 0.1524)
				(type default)
			)
			(layer "F.SilkS")
		)
		(fp_line
			(start 1.2954 -0.5842)
			(end 1.2954 0.5842)
			(stroke
				(width 0.1524)
				(type default)
			)
			(layer "F.SilkS")
		)
		(fp_line
			(start 0 -0.5842)
			(end 0 0.5842)
			(stroke
				(width 0.1524)
				(type default)
			)
			(layer "F.SilkS")
		)
		(fp_line
			(start -1.2954 0.5842)
			(end -1.2954 -0.5842)
			(stroke
				(width 0.1524)
				(type default)
			)
			(layer "F.SilkS")
		)
		(fp_line
			(start -1.2954 -0.5842)
			(end 1.2954 -0.5842)
			(stroke
				(width 0.1524)
				(type default)
			)
			(layer "F.SilkS")
		)
		(fp_line
			(start 1.1938 0.4064)
			(end 0.8636 0.4064)
			(stroke
				(width 0.1)
				(type default)
			)
			(layer "F.Fab")
		)
		(fp_line
			(start 1.1938 -0.4064)
			(end 1.1938 0.4064)
			(stroke
				(width 0.1)
				(type default)
			)
			(layer "F.Fab")
		)
		(fp_line
			(start 0.8636 0.4572)
			(end -0.8636 0.4572)
			(stroke
				(width 0.1)
				(type default)
			)
			(layer "F.Fab")
		)
		(fp_line
			(start 0.8636 0.4064)
			(end 0.8636 0.4572)
			(stroke
				(width 0.1)
				(type default)
			)
			(layer "F.Fab")
		)
		(fp_line
			(start 0.8636 -0.4064)
			(end 1.1938 -0.4064)
			(stroke
				(width 0.1)
				(type default)
			)
			(layer "F.Fab")
		)
		(fp_line
			(start 0.8636 -0.4572)
			(end 0.8636 -0.4064)
			(stroke
				(width 0.1)
				(type default)
			)
			(layer "F.Fab")
		)
		(fp_line
			(start -0.8636 0.4572)
			(end -0.8636 0.4064)
			(stroke
				(width 0.1)
				(type default)
			)
			(layer "F.Fab")
		)
		(fp_line
			(start -0.8636 0.4064)
			(end -1.1938 0.4064)
			(stroke
				(width 0.1)
				(type default)
			)
			(layer "F.Fab")
		)
		(fp_line
			(start -0.8636 -0.4064)
			(end -0.8636 -0.4572)
			(stroke
				(width 0.1)
				(type default)
			)
			(layer "F.Fab")
		)
		(fp_line
			(start -0.8636 -0.4572)
			(end 0.8636 -0.4572)
			(stroke
				(width 0.1)
				(type default)
			)
			(layer "F.Fab")
		)
		(fp_line
			(start -1.1938 0.4064)
			(end -1.1938 -0.4064)
			(stroke
				(width 0.1)
				(type default)
			)
			(layer "F.Fab")
		)
		(fp_line
			(start -1.1938 -0.4064)
			(end -0.8636 -0.4064)
			(stroke
				(width 0.1)
				(type default)
			)
			(layer "F.Fab")
		)
		(pad "1" smd rect
			(at -0.7366 0 90)
			(size 0.7112 0.8128)
			(layers "F.Cu" "F.Mask" "F.Paste")
			(net "P12V_OCP_AVIN_PD_1")
		)
		(pad "2" smd rect
			(at 0.7366 0 90)
			(size 0.7112 0.8128)
			(layers "F.Cu" "F.Mask" "F.Paste")
			(net "GND")
		)
	)
	(footprint ""
		(layer "F.Cu")
		(at 184.976008 -398.651222 180)
		(property "Reference" "R2586"
			(at 0 0 180)
			(layer "F.SilkS")
			(hide yes)
			(effects
				(font
					(size 1.27 1.27)
				)
			)
		)
		(property "Value" ""
			(at 0 0 180)
			(layer "F.Fab")
			(effects
				(font
					(size 1.27 1.27)
				)
			)
		)
		(duplicate_pad_numbers_are_jumpers no)
		(fp_line
			(start 0.7874 0.4064)
			(end -0.7874 0.4064)
			(stroke
				(width 0.1524)
				(type default)
			)
			(layer "F.SilkS")
		)
		(fp_line
			(start 0.7874 -0.4064)
			(end 0.7874 0.4064)
			(stroke
				(width 0.1524)
				(type default)
			)
			(layer "F.SilkS")
		)
		(fp_line
			(start -0.7874 0.4064)
			(end -0.7874 -0.4064)
			(stroke
				(width 0.1524)
				(type default)
			)
			(layer "F.SilkS")
		)
		(fp_line
			(start -0.7874 -0.4064)
			(end 0.7874 -0.4064)
			(stroke
				(width 0.1524)
				(type default)
			)
			(layer "F.SilkS")
		)
		(fp_line
			(start 0.67945 0.3048)
			(end 0.120396 0.3048)
			(stroke
				(width 0.1)
				(type default)
			)
			(layer "F.Fab")
		)
		(fp_line
			(start 0.67945 -0.3048)
			(end 0.67945 0.3048)
			(stroke
				(width 0.1)
				(type default)
			)
			(layer "F.Fab")
		)
		(fp_line
			(start 0.12065 -0.2794)
			(end 0.12065 -0.3048)
			(stroke
				(width 0.1)
				(type default)
			)
			(layer "F.Fab")
		)
		(fp_line
			(start 0.12065 -0.3048)
			(end 0.67945 -0.3048)
			(stroke
				(width 0.1)
				(type default)
			)
			(layer "F.Fab")
		)
		(fp_line
			(start 0.120396 0.3048)
			(end 0.120396 0.2794)
			(stroke
				(width 0.1)
				(type default)
			)
			(layer "F.Fab")
		)
		(fp_line
			(start 0.120396 0.2794)
			(end -0.12065 0.2794)
			(stroke
				(width 0.1)
				(type default)
			)
			(layer "F.Fab")
		)
		(fp_line
			(start -0.12065 0.3048)
			(end -0.67945 0.3048)
			(stroke
				(width 0.1)
				(type default)
			)
			(layer "F.Fab")
		)
		(fp_line
			(start -0.12065 0.2794)
			(end -0.12065 0.3048)
			(stroke
				(width 0.1)
				(type default)
			)
			(layer "F.Fab")
		)
		(fp_line
			(start -0.12065 -0.2794)
			(end 0.12065 -0.2794)
			(stroke
				(width 0.1)
				(type default)
			)
			(layer "F.Fab")
		)
		(fp_line
			(start -0.12065 -0.305054)
			(end -0.12065 -0.2794)
			(stroke
				(width 0.1)
				(type default)
			)
			(layer "F.Fab")
		)
		(fp_line
			(start -0.67945 0.3048)
			(end -0.67945 -0.305054)
			(stroke
				(width 0.1)
				(type default)
			)
			(layer "F.Fab")
		)
		(fp_line
			(start -0.67945 -0.305054)
			(end -0.12065 -0.305054)
			(stroke
				(width 0.1)
				(type default)
			)
			(layer "F.Fab")
		)
		(pad "1" smd circle
			(at -0.40005 0 180)
			(size 0 0)
			(layers "F.Cu" "F.Mask" "F.Paste")
			(net "HSC_EN")
		)
		(pad "2" smd circle
			(at 0.40005 0 180)
			(size 0 0)
			(layers "F.Cu" "F.Mask" "F.Paste")
			(net "HSC_EN_R")
		)
	)
	(footprint ""
		(layer "F.Cu")
		(at 141.240256 -64.313308)
		(property "Reference" "R2282"
			(at 0 0 0)
			(layer "F.SilkS")
			(hide yes)
			(effects
				(font
					(size 1.27 1.27)
				)
			)
		)
		(property "Value" ""
			(at 0 0 0)
			(layer "F.Fab")
			(effects
				(font
					(size 1.27 1.27)
				)
			)
		)
		(duplicate_pad_numbers_are_jumpers no)
		(fp_line
			(start -0.7874 -0.4064)
			(end 0.7874 -0.4064)
			(stroke
				(width 0.1524)
				(type default)
			)
			(layer "F.SilkS")
		)
		(fp_line
			(start -0.7874 0.4064)
			(end -0.7874 -0.4064)
			(stroke
				(width 0.1524)
				(type default)
			)
			(layer "F.SilkS")
		)
		(fp_line
			(start 0.7874 -0.4064)
			(end 0.7874 0.4064)
			(stroke
				(width 0.1524)
				(type default)
			)
			(layer "F.SilkS")
		)
		(fp_line
			(start 0.7874 0.4064)
			(end -0.7874 0.4064)
			(stroke
				(width 0.1524)
				(type default)
			)
			(layer "F.SilkS")
		)
		(fp_line
			(start -0.67945 -0.305054)
			(end -0.12065 -0.305054)
			(stroke
				(width 0.1)
				(type default)
			)
			(layer "F.Fab")
		)
		(fp_line
			(start -0.67945 0.3048)
			(end -0.67945 -0.305054)
			(stroke
				(width 0.1)
				(type default)
			)
			(layer "F.Fab")
		)
		(fp_line
			(start -0.12065 -0.305054)
			(end -0.12065 -0.2794)
			(stroke
				(width 0.1)
				(type default)
			)
			(layer "F.Fab")
		)
		(fp_line
			(start -0.12065 -0.2794)
			(end 0.12065 -0.2794)
			(stroke
				(width 0.1)
				(type default)
			)
			(layer "F.Fab")
		)
		(fp_line
			(start -0.12065 0.2794)
			(end -0.12065 0.3048)
			(stroke
				(width 0.1)
				(type default)
			)
			(layer "F.Fab")
		)
		(fp_line
			(start -0.12065 0.3048)
			(end -0.67945 0.3048)
			(stroke
				(width 0.1)
				(type default)
			)
			(layer "F.Fab")
		)
		(fp_line
			(start 0.120396 0.2794)
			(end -0.12065 0.2794)
			(stroke
				(width 0.1)
				(type default)
			)
			(layer "F.Fab")
		)
		(fp_line
			(start 0.120396 0.3048)
			(end 0.120396 0.2794)
			(stroke
				(width 0.1)
				(type default)
			)
			(layer "F.Fab")
		)
		(fp_line
			(start 0.12065 -0.3048)
			(end 0.67945 -0.3048)
			(stroke
				(width 0.1)
				(type default)
			)
			(layer "F.Fab")
		)
		(fp_line
			(start 0.12065 -0.2794)
			(end 0.12065 -0.3048)
			(stroke
				(width 0.1)
				(type default)
			)
			(layer "F.Fab")
		)
		(fp_line
			(start 0.67945 -0.3048)
			(end 0.67945 0.3048)
			(stroke
				(width 0.1)
				(type default)
			)
			(layer "F.Fab")
		)
		(fp_line
			(start 0.67945 0.3048)
			(end 0.120396 0.3048)
			(stroke
				(width 0.1)
				(type default)
			)
			(layer "F.Fab")
		)
		(pad "1" smd circle
			(at -0.40005 0)
			(size 0 0)
			(layers "F.Cu" "F.Mask" "F.Paste")
			(net "P3V3_AUX")
		)
		(pad "2" smd circle
			(at 0.40005 0)
			(size 0 0)
			(layers "F.Cu" "F.Mask" "F.Paste")
			(net "E1S_0_PRSNT")
		)
	)
	(footprint ""
		(layer "F.Cu")
		(at 210.566 -97.6376)
		(property "Reference" "R2227"
			(at 0 0 0)
			(layer "F.SilkS")
			(hide yes)
			(effects
				(font
					(size 1.27 1.27)
				)
			)
		)
		(property "Value" ""
			(at 0 0 0)
			(layer "F.Fab")
			(effects
				(font
					(size 1.27 1.27)
				)
			)
		)
		(duplicate_pad_numbers_are_jumpers no)
		(fp_line
			(start -0.7874 -0.4064)
			(end 0.7874 -0.4064)
			(stroke
				(width 0.1524)
				(type default)
			)
			(layer "F.SilkS")
		)
		(fp_line
			(start -0.7874 0.4064)
			(end -0.7874 -0.4064)
			(stroke
				(width 0.1524)
				(type default)
			)
			(layer "F.SilkS")
		)
		(fp_line
			(start 0.7874 -0.4064)
			(end 0.7874 0.4064)
			(stroke
				(width 0.1524)
				(type default)
			)
			(layer "F.SilkS")
		)
		(fp_line
			(start 0.7874 0.4064)
			(end -0.7874 0.4064)
			(stroke
				(width 0.1524)
				(type default)
			)
			(layer "F.SilkS")
		)
		(fp_line
			(start -0.67945 -0.305054)
			(end -0.12065 -0.305054)
			(stroke
				(width 0.1)
				(type default)
			)
			(layer "F.Fab")
		)
		(fp_line
			(start -0.67945 0.3048)
			(end -0.67945 -0.305054)
			(stroke
				(width 0.1)
				(type default)
			)
			(layer "F.Fab")
		)
		(fp_line
			(start -0.12065 -0.305054)
			(end -0.12065 -0.2794)
			(stroke
				(width 0.1)
				(type default)
			)
			(layer "F.Fab")
		)
		(fp_line
			(start -0.12065 -0.2794)
			(end 0.12065 -0.2794)
			(stroke
				(width 0.1)
				(type default)
			)
			(layer "F.Fab")
		)
		(fp_line
			(start -0.12065 0.2794)
			(end -0.12065 0.3048)
			(stroke
				(width 0.1)
				(type default)
			)
			(layer "F.Fab")
		)
		(fp_line
			(start -0.12065 0.3048)
			(end -0.67945 0.3048)
			(stroke
				(width 0.1)
				(type default)
			)
			(layer "F.Fab")
		)
		(fp_line
			(start 0.120396 0.2794)
			(end -0.12065 0.2794)
			(stroke
				(width 0.1)
				(type default)
			)
			(layer "F.Fab")
		)
		(fp_line
			(start 0.120396 0.3048)
			(end 0.120396 0.2794)
			(stroke
				(width 0.1)
				(type default)
			)
			(layer "F.Fab")
		)
		(fp_line
			(start 0.12065 -0.3048)
			(end 0.67945 -0.3048)
			(stroke
				(width 0.1)
				(type default)
			)
			(layer "F.Fab")
		)
		(fp_line
			(start 0.12065 -0.2794)
			(end 0.12065 -0.3048)
			(stroke
				(width 0.1)
				(type default)
			)
			(layer "F.Fab")
		)
		(fp_line
			(start 0.67945 -0.3048)
			(end 0.67945 0.3048)
			(stroke
				(width 0.1)
				(type default)
			)
			(layer "F.Fab")
		)
		(fp_line
			(start 0.67945 0.3048)
			(end 0.120396 0.3048)
			(stroke
				(width 0.1)
				(type default)
			)
			(layer "F.Fab")
		)
		(pad "1" smd circle
			(at -0.40005 0)
			(size 0 0)
			(layers "F.Cu" "F.Mask" "F.Paste")
			(net "A_P12V_STBY_ADR_TRIGGER")
		)
		(pad "2" smd circle
			(at 0.40005 0)
			(size 0 0)
			(layers "F.Cu" "F.Mask" "F.Paste")
			(net "GND")
		)
	)
	(footprint ""
		(layer "F.Cu")
		(at 40.27678 -387.35127 -90)
		(property "Reference" "C2357"
			(at 0 0 270)
			(layer "F.SilkS")
			(hide yes)
			(effects
				(font
					(size 1.27 1.27)
				)
			)
		)
		(property "Value" ""
			(at 0 0 270)
			(layer "F.Fab")
			(effects
				(font
					(size 1.27 1.27)
				)
			)
		)
		(duplicate_pad_numbers_are_jumpers no)
		(fp_line
			(start -0.7874 0.4064)
			(end -0.7874 -0.4064)
			(stroke
				(width 0.1524)
				(type default)
			)
			(layer "F.SilkS")
		)
		(fp_line
			(start 0.7874 0.4064)
			(end -0.7874 0.4064)
			(stroke
				(width 0.1524)
				(type default)
			)
			(layer "F.SilkS")
		)
		(fp_line
			(start -0.7874 -0.4064)
			(end 0.7874 -0.4064)
			(stroke
				(width 0.1524)
				(type default)
			)
			(layer "F.SilkS")
		)
		(fp_line
			(start 0.7874 -0.4064)
			(end 0.7874 0.4064)
			(stroke
				(width 0.1524)
				(type default)
			)
			(layer "F.SilkS")
		)
		(fp_line
			(start -0.67945 0.3048)
			(end -0.67945 -0.305054)
			(stroke
				(width 0.1)
				(type default)
			)
			(layer "F.Fab")
		)
		(fp_line
			(start -0.12065 0.3048)
			(end -0.67945 0.3048)
			(stroke
				(width 0.1)
				(type default)
			)
			(layer "F.Fab")
		)
		(fp_line
			(start 0.120396 0.3048)
			(end 0.120396 0.2794)
			(stroke
				(width 0.1)
				(type default)
			)
			(layer "F.Fab")
		)
		(fp_line
			(start 0.67945 0.3048)
			(end 0.120396 0.3048)
			(stroke
				(width 0.1)
				(type default)
			)
			(layer "F.Fab")
		)
		(fp_line
			(start -0.12065 0.2794)
			(end -0.12065 0.3048)
			(stroke
				(width 0.1)
				(type default)
			)
			(layer "F.Fab")
		)
		(fp_line
			(start 0.120396 0.2794)
			(end -0.12065 0.2794)
			(stroke
				(width 0.1)
				(type default)
			)
			(layer "F.Fab")
		)
		(fp_line
			(start -0.12065 -0.2794)
			(end 0.12065 -0.2794)
			(stroke
				(width 0.1)
				(type default)
			)
			(layer "F.Fab")
		)
		(fp_line
			(start 0.12065 -0.2794)
			(end 0.12065 -0.3048)
			(stroke
				(width 0.1)
				(type default)
			)
			(layer "F.Fab")
		)
		(fp_line
			(start 0.12065 -0.3048)
			(end 0.67945 -0.3048)
			(stroke
				(width 0.1)
				(type default)
			)
			(layer "F.Fab")
		)
		(fp_line
			(start 0.67945 -0.3048)
			(end 0.67945 0.3048)
			(stroke
				(width 0.1)
				(type default)
			)
			(layer "F.Fab")
		)
		(fp_line
			(start -0.67945 -0.305054)
			(end -0.12065 -0.305054)
			(stroke
				(width 0.1)
				(type default)
			)
			(layer "F.Fab")
		)
		(fp_line
			(start -0.12065 -0.305054)
			(end -0.12065 -0.2794)
			(stroke
				(width 0.1)
				(type default)
			)
			(layer "F.Fab")
		)
		(pad "1" smd circle
			(at -0.40005 0 270)
			(size 0 0)
			(layers "F.Cu" "F.Mask" "F.Paste")
			(net "P2E_BUF2_VDD")
		)
		(pad "2" smd circle
			(at 0.40005 0 270)
			(size 0 0)
			(layers "F.Cu" "F.Mask" "F.Paste")
			(net "GND")
		)
	)
	(footprint ""
		(layer "F.Cu")
		(at 61.593476 -79.078836)
		(property "Reference" "D83"
			(at -33.022286 34.341308 90)
			(unlocked yes)
			(layer "F.SilkS")
			(effects
				(font
					(size 0.635 0.4064)
					(thickness 0.1524)
				)
				(justify left)
			)
		)
		(property "Value" ""
			(at 0 0 0)
			(layer "F.Fab")
			(effects
				(font
					(size 1.27 1.27)
				)
			)
		)
		(duplicate_pad_numbers_are_jumpers no)
		(fp_line
			(start -0.90678 0.4826)
			(end -0.90678 -0.4699)
			(stroke
				(width 0.1524)
				(type default)
			)
			(layer "F.SilkS")
		)
		(fp_line
			(start -0.89408 -0.4826)
			(end 0.90678 -0.4826)
			(stroke
				(width 0.1524)
				(type default)
			)
			(layer "F.SilkS")
		)
		(fp_line
			(start -0.79248 -0.4826)
			(end 1.03378 -0.4826)
			(stroke
				(width 0.1524)
				(type default)
			)
			(layer "F.SilkS")
		)
		(fp_line
			(start -0.64008 -0.4826)
			(end 1.16078 -0.4826)
			(stroke
				(width 0.1524)
				(type default)
			)
			(layer "F.SilkS")
		)
		(fp_line
			(start 0.90678 -0.4826)
			(end 0.90678 0.4826)
			(stroke
				(width 0.1524)
				(type default)
			)
			(layer "F.SilkS")
		)
		(fp_line
			(start 0.90678 0.4826)
			(end -0.90678 0.4826)
			(stroke
				(width 0.1524)
				(type default)
			)
			(layer "F.SilkS")
		)
		(fp_line
			(start 1.03378 -0.4826)
			(end 1.03378 0.4826)
			(stroke
				(width 0.1524)
				(type default)
			)
			(layer "F.SilkS")
		)
		(fp_line
			(start 1.03378 0.4826)
			(end -0.79248 0.4826)
			(stroke
				(width 0.1524)
				(type default)
			)
			(layer "F.SilkS")
		)
		(fp_line
			(start 1.16078 -0.4826)
			(end 1.16078 0.4826)
			(stroke
				(width 0.1524)
				(type default)
			)
			(layer "F.SilkS")
		)
		(fp_line
			(start 1.16078 0.4826)
			(end -0.64008 0.4826)
			(stroke
				(width 0.1524)
				(type default)
			)
			(layer "F.SilkS")
		)
		(fp_line
			(start -0.499872 -0.249936)
			(end 0.499872 -0.249936)
			(stroke
				(width 0.1)
				(type default)
			)
			(layer "F.Fab")
		)
		(fp_line
			(start -0.499872 0.249936)
			(end -0.499872 -0.249936)
			(stroke
				(width 0.1)
				(type default)
			)
			(layer "F.Fab")
		)
		(fp_line
			(start 0.499872 -0.249936)
			(end 0.499872 0.249936)
			(stroke
				(width 0.1)
				(type default)
			)
			(layer "F.Fab")
		)
		(fp_line
			(start 0.499872 0.249936)
			(end -0.499872 0.249936)
			(stroke
				(width 0.1)
				(type default)
			)
			(layer "F.Fab")
		)
		(pad "A" smd rect
			(at -0.47498 0)
			(size 0.6096 0.7112)
			(layers "F.Cu" "F.Mask" "F.Paste")
			(net "LED_PWRGD_PVCCFA_EHV_FIVRA_CPU1")
		)
		(pad "C" smd rect
			(at 0.47498 0)
			(size 0.6096 0.7112)
			(layers "F.Cu" "F.Mask" "F.Paste")
			(net "LED_PWRGD_PVCCFA_EHV_FIVRA_CP_2")
		)
	)
	(footprint ""
		(layer "F.Cu")
		(at 40.6146 -104.993948 180)
		(property "Reference" "R4567"
			(at 0 0 180)
			(layer "F.SilkS")
			(hide yes)
			(effects
				(font
					(size 1.27 1.27)
				)
			)
		)
		(property "Value" ""
			(at 0 0 180)
			(layer "F.Fab")
			(effects
				(font
					(size 1.27 1.27)
				)
			)
		)
		(duplicate_pad_numbers_are_jumpers no)
		(fp_line
			(start 0.7874 0.4064)
			(end -0.7874 0.4064)
			(stroke
				(width 0.1524)
				(type default)
			)
			(layer "F.SilkS")
		)
		(fp_line
			(start 0.7874 -0.4064)
			(end 0.7874 0.4064)
			(stroke
				(width 0.1524)
				(type default)
			)
			(layer "F.SilkS")
		)
		(fp_line
			(start -0.7874 0.4064)
			(end -0.7874 -0.4064)
			(stroke
				(width 0.1524)
				(type default)
			)
			(layer "F.SilkS")
		)
		(fp_line
			(start -0.7874 -0.4064)
			(end 0.7874 -0.4064)
			(stroke
				(width 0.1524)
				(type default)
			)
			(layer "F.SilkS")
		)
		(fp_line
			(start 0.67945 0.3048)
			(end 0.120396 0.3048)
			(stroke
				(width 0.1)
				(type default)
			)
			(layer "F.Fab")
		)
		(fp_line
			(start 0.67945 -0.3048)
			(end 0.67945 0.3048)
			(stroke
				(width 0.1)
				(type default)
			)
			(layer "F.Fab")
		)
		(fp_line
			(start 0.12065 -0.2794)
			(end 0.12065 -0.3048)
			(stroke
				(width 0.1)
				(type default)
			)
			(layer "F.Fab")
		)
		(fp_line
			(start 0.12065 -0.3048)
			(end 0.67945 -0.3048)
			(stroke
				(width 0.1)
				(type default)
			)
			(layer "F.Fab")
		)
		(fp_line
			(start 0.120396 0.3048)
			(end 0.120396 0.2794)
			(stroke
				(width 0.1)
				(type default)
			)
			(layer "F.Fab")
		)
		(fp_line
			(start 0.120396 0.2794)
			(end -0.12065 0.2794)
			(stroke
				(width 0.1)
				(type default)
			)
			(layer "F.Fab")
		)
		(fp_line
			(start -0.12065 0.3048)
			(end -0.67945 0.3048)
			(stroke
				(width 0.1)
				(type default)
			)
			(layer "F.Fab")
		)
		(fp_line
			(start -0.12065 0.2794)
			(end -0.12065 0.3048)
			(stroke
				(width 0.1)
				(type default)
			)
			(layer "F.Fab")
		)
		(fp_line
			(start -0.12065 -0.2794)
			(end 0.12065 -0.2794)
			(stroke
				(width 0.1)
				(type default)
			)
			(layer "F.Fab")
		)
		(fp_line
			(start -0.12065 -0.305054)
			(end -0.12065 -0.2794)
			(stroke
				(width 0.1)
				(type default)
			)
			(layer "F.Fab")
		)
		(fp_line
			(start -0.67945 0.3048)
			(end -0.67945 -0.305054)
			(stroke
				(width 0.1)
				(type default)
			)
			(layer "F.Fab")
		)
		(fp_line
			(start -0.67945 -0.305054)
			(end -0.12065 -0.305054)
			(stroke
				(width 0.1)
				(type default)
			)
			(layer "F.Fab")
		)
		(pad "1" smd circle
			(at -0.40005 0 180)
			(size 0 0)
			(layers "F.Cu" "F.Mask" "F.Paste")
			(net "P3V3_PDB_AUX_ADC")
		)
		(pad "2" smd circle
			(at 0.40005 0 180)
			(size 0 0)
			(layers "F.Cu" "F.Mask" "F.Paste")
			(net "P1V581_PDB_ADC")
		)
	)
	(footprint ""
		(layer "F.Cu")
		(at 223.70288 -44.922948)
		(property "Reference" "R3534"
			(at 0 0 0)
			(layer "F.SilkS")
			(hide yes)
			(effects
				(font
					(size 1.27 1.27)
				)
			)
		)
		(property "Value" ""
			(at 0 0 0)
			(layer "F.Fab")
			(effects
				(font
					(size 1.27 1.27)
				)
			)
		)
		(duplicate_pad_numbers_are_jumpers no)
		(fp_line
			(start -0.7874 -0.4064)
			(end 0.7874 -0.4064)
			(stroke
				(width 0.1524)
				(type default)
			)
			(layer "F.SilkS")
		)
		(fp_line
			(start -0.7874 0.4064)
			(end -0.7874 -0.4064)
			(stroke
				(width 0.1524)
				(type default)
			)
			(layer "F.SilkS")
		)
		(fp_line
			(start 0.7874 -0.4064)
			(end 0.7874 0.4064)
			(stroke
				(width 0.1524)
				(type default)
			)
			(layer "F.SilkS")
		)
		(fp_line
			(start 0.7874 0.4064)
			(end -0.7874 0.4064)
			(stroke
				(width 0.1524)
				(type default)
			)
			(layer "F.SilkS")
		)
		(fp_line
			(start -0.67945 -0.305054)
			(end -0.12065 -0.305054)
			(stroke
				(width 0.1)
				(type default)
			)
			(layer "F.Fab")
		)
		(fp_line
			(start -0.67945 0.3048)
			(end -0.67945 -0.305054)
			(stroke
				(width 0.1)
				(type default)
			)
			(layer "F.Fab")
		)
		(fp_line
			(start -0.12065 -0.305054)
			(end -0.12065 -0.2794)
			(stroke
				(width 0.1)
				(type default)
			)
			(layer "F.Fab")
		)
		(fp_line
			(start -0.12065 -0.2794)
			(end 0.12065 -0.2794)
			(stroke
				(width 0.1)
				(type default)
			)
			(layer "F.Fab")
		)
		(fp_line
			(start -0.12065 0.2794)
			(end -0.12065 0.3048)
			(stroke
				(width 0.1)
				(type default)
			)
			(layer "F.Fab")
		)
		(fp_line
			(start -0.12065 0.3048)
			(end -0.67945 0.3048)
			(stroke
				(width 0.1)
				(type default)
			)
			(layer "F.Fab")
		)
		(fp_line
			(start 0.120396 0.2794)
			(end -0.12065 0.2794)
			(stroke
				(width 0.1)
				(type default)
			)
			(layer "F.Fab")
		)
		(fp_line
			(start 0.120396 0.3048)
			(end 0.120396 0.2794)
			(stroke
				(width 0.1)
				(type default)
			)
			(layer "F.Fab")
		)
		(fp_line
			(start 0.12065 -0.3048)
			(end 0.67945 -0.3048)
			(stroke
				(width 0.1)
				(type default)
			)
			(layer "F.Fab")
		)
		(fp_line
			(start 0.12065 -0.2794)
			(end 0.12065 -0.3048)
			(stroke
				(width 0.1)
				(type default)
			)
			(layer "F.Fab")
		)
		(fp_line
			(start 0.67945 -0.3048)
			(end 0.67945 0.3048)
			(stroke
				(width 0.1)
				(type default)
			)
			(layer "F.Fab")
		)
		(fp_line
			(start 0.67945 0.3048)
			(end 0.120396 0.3048)
			(stroke
				(width 0.1)
				(type default)
			)
			(layer "F.Fab")
		)
		(pad "1" smd circle
			(at -0.40005 0)
			(size 0 0)
			(layers "F.Cu" "F.Mask" "F.Paste")
			(net "SMB_E1S_3V3AUX_ISO_SDA_R")
		)
		(pad "2" smd circle
			(at 0.40005 0)
			(size 0 0)
			(layers "F.Cu" "F.Mask" "F.Paste")
			(net "SMB_E1S_3V3AUX_ISO_SDA")
		)
	)
	(footprint ""
		(layer "F.Cu")
		(at 162.34283 -75.767438)
		(property "Reference" "R2208"
			(at 0 0 0)
			(layer "F.SilkS")
			(hide yes)
			(effects
				(font
					(size 1.27 1.27)
				)
			)
		)
		(property "Value" ""
			(at 0 0 0)
			(layer "F.Fab")
			(effects
				(font
					(size 1.27 1.27)
				)
			)
		)
		(duplicate_pad_numbers_are_jumpers no)
		(fp_line
			(start -0.7874 -0.4064)
			(end 0.7874 -0.4064)
			(stroke
				(width 0.1524)
				(type default)
			)
			(layer "F.SilkS")
		)
		(fp_line
			(start -0.7874 0.4064)
			(end -0.7874 -0.4064)
			(stroke
				(width 0.1524)
				(type default)
			)
			(layer "F.SilkS")
		)
		(fp_line
			(start 0.7874 -0.4064)
			(end 0.7874 0.4064)
			(stroke
				(width 0.1524)
				(type default)
			)
			(layer "F.SilkS")
		)
		(fp_line
			(start 0.7874 0.4064)
			(end -0.7874 0.4064)
			(stroke
				(width 0.1524)
				(type default)
			)
			(layer "F.SilkS")
		)
		(fp_line
			(start -0.67945 -0.305054)
			(end -0.12065 -0.305054)
			(stroke
				(width 0.1)
				(type default)
			)
			(layer "F.Fab")
		)
		(fp_line
			(start -0.67945 0.3048)
			(end -0.67945 -0.305054)
			(stroke
				(width 0.1)
				(type default)
			)
			(layer "F.Fab")
		)
		(fp_line
			(start -0.12065 -0.305054)
			(end -0.12065 -0.2794)
			(stroke
				(width 0.1)
				(type default)
			)
			(layer "F.Fab")
		)
		(fp_line
			(start -0.12065 -0.2794)
			(end 0.12065 -0.2794)
			(stroke
				(width 0.1)
				(type default)
			)
			(layer "F.Fab")
		)
		(fp_line
			(start -0.12065 0.2794)
			(end -0.12065 0.3048)
			(stroke
				(width 0.1)
				(type default)
			)
			(layer "F.Fab")
		)
		(fp_line
			(start -0.12065 0.3048)
			(end -0.67945 0.3048)
			(stroke
				(width 0.1)
				(type default)
			)
			(layer "F.Fab")
		)
		(fp_line
			(start 0.120396 0.2794)
			(end -0.12065 0.2794)
			(stroke
				(width 0.1)
				(type default)
			)
			(layer "F.Fab")
		)
		(fp_line
			(start 0.120396 0.3048)
			(end 0.120396 0.2794)
			(stroke
				(width 0.1)
				(type default)
			)
			(layer "F.Fab")
		)
		(fp_line
			(start 0.12065 -0.3048)
			(end 0.67945 -0.3048)
			(stroke
				(width 0.1)
				(type default)
			)
			(layer "F.Fab")
		)
		(fp_line
			(start 0.12065 -0.2794)
			(end 0.12065 -0.3048)
			(stroke
				(width 0.1)
				(type default)
			)
			(layer "F.Fab")
		)
		(fp_line
			(start 0.67945 -0.3048)
			(end 0.67945 0.3048)
			(stroke
				(width 0.1)
				(type default)
			)
			(layer "F.Fab")
		)
		(fp_line
			(start 0.67945 0.3048)
			(end 0.120396 0.3048)
			(stroke
				(width 0.1)
				(type default)
			)
			(layer "F.Fab")
		)
		(pad "1" smd circle
			(at -0.40005 0)
			(size 0 0)
			(layers "F.Cu" "F.Mask" "F.Paste")
			(net "SMB_S3M_CPU0_3V3AUX_SDA_R")
		)
		(pad "2" smd circle
			(at 0.40005 0)
			(size 0 0)
			(layers "F.Cu" "F.Mask" "F.Paste")
			(net "SMB_S3M_CPU0_3V3AUX_SDA")
		)
	)
	(footprint ""
		(layer "F.Cu")
		(at 117.904514 -336.192368 90)
		(property "Reference" "PC523"
			(at 0 0 90)
			(layer "F.SilkS")
			(hide yes)
			(effects
				(font
					(size 1.27 1.27)
				)
			)
		)
		(property "Value" ""
			(at 0 0 90)
			(layer "F.Fab")
			(effects
				(font
					(size 1.27 1.27)
				)
			)
		)
		(duplicate_pad_numbers_are_jumpers no)
		(fp_line
			(start 0.7874 -0.4064)
			(end 0.7874 0.4064)
			(stroke
				(width 0.1524)
				(type default)
			)
			(layer "F.SilkS")
		)
		(fp_line
			(start -0.7874 -0.4064)
			(end 0.7874 -0.4064)
			(stroke
				(width 0.1524)
				(type default)
			)
			(layer "F.SilkS")
		)
		(fp_line
			(start 0.7874 0.4064)
			(end -0.7874 0.4064)
			(stroke
				(width 0.1524)
				(type default)
			)
			(layer "F.SilkS")
		)
		(fp_line
			(start -0.7874 0.4064)
			(end -0.7874 -0.4064)
			(stroke
				(width 0.1524)
				(type default)
			)
			(layer "F.SilkS")
		)
		(fp_line
			(start -0.12065 -0.305054)
			(end -0.12065 -0.2794)
			(stroke
				(width 0.1)
				(type default)
			)
			(layer "F.Fab")
		)
		(fp_line
			(start -0.67945 -0.305054)
			(end -0.12065 -0.305054)
			(stroke
				(width 0.1)
				(type default)
			)
			(layer "F.Fab")
		)
		(fp_line
			(start 0.67945 -0.3048)
			(end 0.67945 0.3048)
			(stroke
				(width 0.1)
				(type default)
			)
			(layer "F.Fab")
		)
		(fp_line
			(start 0.12065 -0.3048)
			(end 0.67945 -0.3048)
			(stroke
				(width 0.1)
				(type default)
			)
			(layer "F.Fab")
		)
		(fp_line
			(start 0.12065 -0.2794)
			(end 0.12065 -0.3048)
			(stroke
				(width 0.1)
				(type default)
			)
			(layer "F.Fab")
		)
		(fp_line
			(start -0.12065 -0.2794)
			(end 0.12065 -0.2794)
			(stroke
				(width 0.1)
				(type default)
			)
			(layer "F.Fab")
		)
		(fp_line
			(start 0.120396 0.2794)
			(end -0.12065 0.2794)
			(stroke
				(width 0.1)
				(type default)
			)
			(layer "F.Fab")
		)
		(fp_line
			(start -0.12065 0.2794)
			(end -0.12065 0.3048)
			(stroke
				(width 0.1)
				(type default)
			)
			(layer "F.Fab")
		)
		(fp_line
			(start 0.67945 0.3048)
			(end 0.120396 0.3048)
			(stroke
				(width 0.1)
				(type default)
			)
			(layer "F.Fab")
		)
		(fp_line
			(start 0.120396 0.3048)
			(end 0.120396 0.2794)
			(stroke
				(width 0.1)
				(type default)
			)
			(layer "F.Fab")
		)
		(fp_line
			(start -0.12065 0.3048)
			(end -0.67945 0.3048)
			(stroke
				(width 0.1)
				(type default)
			)
			(layer "F.Fab")
		)
		(fp_line
			(start -0.67945 0.3048)
			(end -0.67945 -0.305054)
			(stroke
				(width 0.1)
				(type default)
			)
			(layer "F.Fab")
		)
		(pad "1" smd circle
			(at -0.40005 0 90)
			(size 0 0)
			(layers "F.Cu" "F.Mask" "F.Paste")
			(net "PVCCIN_CPU1_VDD4")
		)
		(pad "2" smd circle
			(at 0.40005 0 90)
			(size 0 0)
			(layers "F.Cu" "F.Mask" "F.Paste")
			(net "GND")
		)
	)
	(footprint ""
		(layer "F.Cu")
		(at 180.528468 -47.139098 180)
		(property "Reference" "C1101"
			(at 0 0 180)
			(layer "F.SilkS")
			(hide yes)
			(effects
				(font
					(size 1.27 1.27)
				)
			)
		)
		(property "Value" ""
			(at 0 0 180)
			(layer "F.Fab")
			(effects
				(font
					(size 1.27 1.27)
				)
			)
		)
		(duplicate_pad_numbers_are_jumpers no)
		(fp_line
			(start 0.299974 0.150114)
			(end -0.299974 0.150114)
			(stroke
				(width 0.1)
				(type default)
			)
			(layer "F.Fab")
		)
		(fp_line
			(start 0.299974 -0.150114)
			(end 0.299974 0.150114)
			(stroke
				(width 0.1)
				(type default)
			)
			(layer "F.Fab")
		)
		(fp_line
			(start -0.299974 0.150114)
			(end -0.299974 -0.150114)
			(stroke
				(width 0.1)
				(type default)
			)
			(layer "F.Fab")
		)
		(fp_line
			(start -0.299974 -0.150114)
			(end 0.299974 -0.150114)
			(stroke
				(width 0.1)
				(type default)
			)
			(layer "F.Fab")
		)
		(pad "1" smd rect
			(at -0.2667 0 180)
			(size 0.3048 0.381)
			(layers "F.Cu" "F.Mask" "F.Paste")
			(net "P3E_PCH_M2_TX_DN<2>")
		)
		(pad "2" smd rect
			(at 0.2667 0 180)
			(size 0.3048 0.381)
			(layers "F.Cu" "F.Mask" "F.Paste")
			(net "P3E_PCH_M2_TX_C_DN<2>")
		)
		(zone
			(layer "In1.Cu")
			(hatch none 0.5)
			(connect_pads
				(clearance 0)
			)
			(min_thickness 0.25)
			(keepout
				(tracks not_allowed)
				(vias allowed)
				(pads allowed)
				(copperpour not_allowed)
				(footprints allowed)
			)
			(placement
				(enabled no)
				(sheetname "")
			)
			(fill
				(thermal_gap 0.5)
				(thermal_bridge_width 0.5)
				(island_removal_mode 0)
			)
			(polygon
				(pts
					(arc
						(start 180.388768 -47.380398)
						(mid 180.44265 -47.35808)
						(end 180.464968 -47.304198)
					)
					(arc
						(start 180.464968 -46.973998)
						(mid 180.44265 -46.920116)
						(end 180.388768 -46.897798)
					)
					(arc
						(start 180.134768 -46.897798)
						(mid 180.080886 -46.920116)
						(end 180.058568 -46.973998)
					)
					(arc
						(start 180.058568 -47.304198)
						(mid 180.080886 -47.35808)
						(end 180.134768 -47.380398)
					)
				)
			)
		)
		(zone
			(layer "In1.Cu")
			(hatch none 0.5)
			(connect_pads
				(clearance 0)
			)
			(min_thickness 0.25)
			(keepout
				(tracks not_allowed)
				(vias allowed)
				(pads allowed)
				(copperpour not_allowed)
				(footprints allowed)
			)
			(placement
				(enabled no)
				(sheetname "")
			)
			(fill
				(thermal_gap 0.5)
				(thermal_bridge_width 0.5)
				(island_removal_mode 0)
			)
			(polygon
				(pts
					(arc
						(start 180.922168 -47.380398)
						(mid 180.97605 -47.35808)
						(end 180.998368 -47.304198)
					)
					(arc
						(start 180.998368 -46.973998)
						(mid 180.97605 -46.920116)
						(end 180.922168 -46.897798)
					)
					(arc
						(start 180.668168 -46.897798)
						(mid 180.614286 -46.920116)
						(end 180.591968 -46.973998)
					)
					(arc
						(start 180.591968 -47.304198)
						(mid 180.614286 -47.35808)
						(end 180.668168 -47.380398)
					)
				)
			)
		)
	)
	(footprint ""
		(layer "F.Cu")
		(at 161.29 -126.365 -90)
		(property "Reference" "R4641"
			(at 0 0 270)
			(layer "F.SilkS")
			(hide yes)
			(effects
				(font
					(size 1.27 1.27)
				)
			)
		)
		(property "Value" ""
			(at 0 0 270)
			(layer "F.Fab")
			(effects
				(font
					(size 1.27 1.27)
				)
			)
		)
		(duplicate_pad_numbers_are_jumpers no)
		(fp_line
			(start -2.234946 0.9271)
			(end -2.234946 -0.9271)
			(stroke
				(width 0.1524)
				(type default)
			)
			(layer "F.SilkS")
		)
		(fp_line
			(start 2.234946 0.9271)
			(end -2.234946 0.9271)
			(stroke
				(width 0.1524)
				(type default)
			)
			(layer "F.SilkS")
		)
		(fp_line
			(start -2.234946 -0.9271)
			(end 2.234946 -0.9271)
			(stroke
				(width 0.1524)
				(type default)
			)
			(layer "F.SilkS")
		)
		(fp_line
			(start 2.234946 -0.9271)
			(end 2.234946 0.9271)
			(stroke
				(width 0.1524)
				(type default)
			)
			(layer "F.SilkS")
		)
		(fp_line
			(start -1.575054 0.824992)
			(end 1.575054 0.824992)
			(stroke
				(width 0.1)
				(type default)
			)
			(layer "F.Fab")
		)
		(fp_line
			(start 1.575054 0.824992)
			(end 1.575054 -0.824992)
			(stroke
				(width 0.1)
				(type default)
			)
			(layer "F.Fab")
		)
		(fp_line
			(start -1.575054 -0.824992)
			(end -1.575054 0.824992)
			(stroke
				(width 0.1)
				(type default)
			)
			(layer "F.Fab")
		)
		(fp_line
			(start 1.575054 -0.824992)
			(end -1.575054 -0.824992)
			(stroke
				(width 0.1)
				(type default)
			)
			(layer "F.Fab")
		)
		(pad "1" smd rect
			(at -1.599946 0 270)
			(size 1.016 1.6002)
			(layers "F.Cu" "F.Mask" "F.Paste")
			(net "P5V")
		)
		(pad "2" smd rect
			(at 1.599946 0 270)
			(size 1.016 1.6002)
			(layers "F.Cu" "F.Mask" "F.Paste")
			(net "VR_P5V_EN_D")
		)
	)
	(footprint ""
		(layer "F.Cu")
		(at 27.628596 -395.374876 180)
		(property "Reference" "R3280"
			(at 0 0 180)
			(layer "F.SilkS")
			(hide yes)
			(effects
				(font
					(size 1.27 1.27)
				)
			)
		)
		(property "Value" ""
			(at 0 0 180)
			(layer "F.Fab")
			(effects
				(font
					(size 1.27 1.27)
				)
			)
		)
		(duplicate_pad_numbers_are_jumpers no)
		(fp_line
			(start 0.7874 0.4064)
			(end -0.7874 0.4064)
			(stroke
				(width 0.1524)
				(type default)
			)
			(layer "F.SilkS")
		)
		(fp_line
			(start 0.7874 -0.4064)
			(end 0.7874 0.4064)
			(stroke
				(width 0.1524)
				(type default)
			)
			(layer "F.SilkS")
		)
		(fp_line
			(start -0.7874 0.4064)
			(end -0.7874 -0.4064)
			(stroke
				(width 0.1524)
				(type default)
			)
			(layer "F.SilkS")
		)
		(fp_line
			(start -0.7874 -0.4064)
			(end 0.7874 -0.4064)
			(stroke
				(width 0.1524)
				(type default)
			)
			(layer "F.SilkS")
		)
		(fp_line
			(start 0.67945 0.3048)
			(end 0.120396 0.3048)
			(stroke
				(width 0.1)
				(type default)
			)
			(layer "F.Fab")
		)
		(fp_line
			(start 0.67945 -0.3048)
			(end 0.67945 0.3048)
			(stroke
				(width 0.1)
				(type default)
			)
			(layer "F.Fab")
		)
		(fp_line
			(start 0.12065 -0.2794)
			(end 0.12065 -0.3048)
			(stroke
				(width 0.1)
				(type default)
			)
			(layer "F.Fab")
		)
		(fp_line
			(start 0.12065 -0.3048)
			(end 0.67945 -0.3048)
			(stroke
				(width 0.1)
				(type default)
			)
			(layer "F.Fab")
		)
		(fp_line
			(start 0.120396 0.3048)
			(end 0.120396 0.2794)
			(stroke
				(width 0.1)
				(type default)
			)
			(layer "F.Fab")
		)
		(fp_line
			(start 0.120396 0.2794)
			(end -0.12065 0.2794)
			(stroke
				(width 0.1)
				(type default)
			)
			(layer "F.Fab")
		)
		(fp_line
			(start -0.12065 0.3048)
			(end -0.67945 0.3048)
			(stroke
				(width 0.1)
				(type default)
			)
			(layer "F.Fab")
		)
		(fp_line
			(start -0.12065 0.2794)
			(end -0.12065 0.3048)
			(stroke
				(width 0.1)
				(type default)
			)
			(layer "F.Fab")
		)
		(fp_line
			(start -0.12065 -0.2794)
			(end 0.12065 -0.2794)
			(stroke
				(width 0.1)
				(type default)
			)
			(layer "F.Fab")
		)
		(fp_line
			(start -0.12065 -0.305054)
			(end -0.12065 -0.2794)
			(stroke
				(width 0.1)
				(type default)
			)
			(layer "F.Fab")
		)
		(fp_line
			(start -0.67945 0.3048)
			(end -0.67945 -0.305054)
			(stroke
				(width 0.1)
				(type default)
			)
			(layer "F.Fab")
		)
		(fp_line
			(start -0.67945 -0.305054)
			(end -0.12065 -0.305054)
			(stroke
				(width 0.1)
				(type default)
			)
			(layer "F.Fab")
		)
		(pad "1" smd circle
			(at -0.40005 0 180)
			(size 0 0)
			(layers "F.Cu" "F.Mask" "F.Paste")
			(net "P3V3_AUX")
		)
		(pad "2" smd circle
			(at 0.40005 0 180)
			(size 0 0)
			(layers "F.Cu" "F.Mask" "F.Paste")
			(net "FM_P2E_EQB1")
		)
	)
	(footprint ""
		(layer "F.Cu")
		(at 432.757072 -177.903124 -90)
		(property "Reference" "PR1"
			(at 0 0 270)
			(layer "F.SilkS")
			(hide yes)
			(effects
				(font
					(size 1.27 1.27)
				)
			)
		)
		(property "Value" ""
			(at 0 0 270)
			(layer "F.Fab")
			(effects
				(font
					(size 1.27 1.27)
				)
			)
		)
		(duplicate_pad_numbers_are_jumpers no)
		(fp_line
			(start -0.7874 0.4064)
			(end -0.7874 -0.4064)
			(stroke
				(width 0.1524)
				(type default)
			)
			(layer "F.SilkS")
		)
		(fp_line
			(start 0.7874 0.4064)
			(end -0.7874 0.4064)
			(stroke
				(width 0.1524)
				(type default)
			)
			(layer "F.SilkS")
		)
		(fp_line
			(start -0.7874 -0.4064)
			(end 0.7874 -0.4064)
			(stroke
				(width 0.1524)
				(type default)
			)
			(layer "F.SilkS")
		)
		(fp_line
			(start 0.7874 -0.4064)
			(end 0.7874 0.4064)
			(stroke
				(width 0.1524)
				(type default)
			)
			(layer "F.SilkS")
		)
		(fp_line
			(start -0.67945 0.3048)
			(end -0.67945 -0.305054)
			(stroke
				(width 0.1)
				(type default)
			)
			(layer "F.Fab")
		)
		(fp_line
			(start -0.12065 0.3048)
			(end -0.67945 0.3048)
			(stroke
				(width 0.1)
				(type default)
			)
			(layer "F.Fab")
		)
		(fp_line
			(start 0.120396 0.3048)
			(end 0.120396 0.2794)
			(stroke
				(width 0.1)
				(type default)
			)
			(layer "F.Fab")
		)
		(fp_line
			(start 0.67945 0.3048)
			(end 0.120396 0.3048)
			(stroke
				(width 0.1)
				(type default)
			)
			(layer "F.Fab")
		)
		(fp_line
			(start -0.12065 0.2794)
			(end -0.12065 0.3048)
			(stroke
				(width 0.1)
				(type default)
			)
			(layer "F.Fab")
		)
		(fp_line
			(start 0.120396 0.2794)
			(end -0.12065 0.2794)
			(stroke
				(width 0.1)
				(type default)
			)
			(layer "F.Fab")
		)
		(fp_line
			(start -0.12065 -0.2794)
			(end 0.12065 -0.2794)
			(stroke
				(width 0.1)
				(type default)
			)
			(layer "F.Fab")
		)
		(fp_line
			(start 0.12065 -0.2794)
			(end 0.12065 -0.3048)
			(stroke
				(width 0.1)
				(type default)
			)
			(layer "F.Fab")
		)
		(fp_line
			(start 0.12065 -0.3048)
			(end 0.67945 -0.3048)
			(stroke
				(width 0.1)
				(type default)
			)
			(layer "F.Fab")
		)
		(fp_line
			(start 0.67945 -0.3048)
			(end 0.67945 0.3048)
			(stroke
				(width 0.1)
				(type default)
			)
			(layer "F.Fab")
		)
		(fp_line
			(start -0.67945 -0.305054)
			(end -0.12065 -0.305054)
			(stroke
				(width 0.1)
				(type default)
			)
			(layer "F.Fab")
		)
		(fp_line
			(start -0.12065 -0.305054)
			(end -0.12065 -0.2794)
			(stroke
				(width 0.1)
				(type default)
			)
			(layer "F.Fab")
		)
		(pad "1" smd circle
			(at -0.40005 0 270)
			(size 0 0)
			(layers "F.Cu" "F.Mask" "F.Paste")
			(net "GND")
		)
		(pad "2" smd circle
			(at 0.40005 0 270)
			(size 0 0)
			(layers "F.Cu" "F.Mask" "F.Paste")
			(net "GND")
		)
	)
	(footprint ""
		(layer "F.Cu")
		(at 249.034046 -540.634682 -90)
		(property "Reference" "ME27"
			(at 0.0254 -3.851148 270)
			(unlocked yes)
			(layer "F.SilkS")
			(effects
				(font
					(size 0.7874 0.5842)
					(thickness 0.1524)
				)
				(justify left)
			)
		)
		(property "Value" ""
			(at 0 0 270)
			(layer "F.Fab")
			(effects
				(font
					(size 1.27 1.27)
				)
			)
		)
		(duplicate_pad_numbers_are_jumpers no)
		(zone
			(layer "F.Cu")
			(hatch none 0.5)
			(connect_pads
				(clearance 0)
			)
			(min_thickness 0.25)
			(keepout
				(tracks allowed)
				(vias allowed)
				(pads allowed)
				(copperpour allowed)
				(footprints not_allowed)
			)
			(placement
				(enabled no)
				(sheetname "")
			)
			(fill
				(thermal_gap 0.5)
				(thermal_bridge_width 0.5)
				(island_removal_mode 0)
			)
			(polygon
				(pts
					(xy 249.034046 -540.634682) (xy 249.034046 18.165318) (xy 252.03404 18.165318) (xy 252.03404 -540.634682)
				)
			)
		)
	)
	(footprint ""
		(layer "F.Cu")
		(at 198.41464 -71.582788)
		(property "Reference" "PC2201"
			(at 0 0 0)
			(layer "F.SilkS")
			(hide yes)
			(effects
				(font
					(size 1.27 1.27)
				)
			)
		)
		(property "Value" ""
			(at 0 0 0)
			(layer "F.Fab")
			(effects
				(font
					(size 1.27 1.27)
				)
			)
		)
		(duplicate_pad_numbers_are_jumpers no)
		(fp_line
			(start -0.7874 -0.4064)
			(end 0.7874 -0.4064)
			(stroke
				(width 0.1524)
				(type default)
			)
			(layer "F.SilkS")
		)
		(fp_line
			(start -0.7874 0.4064)
			(end -0.7874 -0.4064)
			(stroke
				(width 0.1524)
				(type default)
			)
			(layer "F.SilkS")
		)
		(fp_line
			(start 0.7874 -0.4064)
			(end 0.7874 0.4064)
			(stroke
				(width 0.1524)
				(type default)
			)
			(layer "F.SilkS")
		)
		(fp_line
			(start 0.7874 0.4064)
			(end -0.7874 0.4064)
			(stroke
				(width 0.1524)
				(type default)
			)
			(layer "F.SilkS")
		)
		(fp_line
			(start -0.67945 -0.305054)
			(end -0.12065 -0.305054)
			(stroke
				(width 0.1)
				(type default)
			)
			(layer "F.Fab")
		)
		(fp_line
			(start -0.67945 0.3048)
			(end -0.67945 -0.305054)
			(stroke
				(width 0.1)
				(type default)
			)
			(layer "F.Fab")
		)
		(fp_line
			(start -0.12065 -0.305054)
			(end -0.12065 -0.2794)
			(stroke
				(width 0.1)
				(type default)
			)
			(layer "F.Fab")
		)
		(fp_line
			(start -0.12065 -0.2794)
			(end 0.12065 -0.2794)
			(stroke
				(width 0.1)
				(type default)
			)
			(layer "F.Fab")
		)
		(fp_line
			(start -0.12065 0.2794)
			(end -0.12065 0.3048)
			(stroke
				(width 0.1)
				(type default)
			)
			(layer "F.Fab")
		)
		(fp_line
			(start -0.12065 0.3048)
			(end -0.67945 0.3048)
			(stroke
				(width 0.1)
				(type default)
			)
			(layer "F.Fab")
		)
		(fp_line
			(start 0.120396 0.2794)
			(end -0.12065 0.2794)
			(stroke
				(width 0.1)
				(type default)
			)
			(layer "F.Fab")
		)
		(fp_line
			(start 0.120396 0.3048)
			(end 0.120396 0.2794)
			(stroke
				(width 0.1)
				(type default)
			)
			(layer "F.Fab")
		)
		(fp_line
			(start 0.12065 -0.3048)
			(end 0.67945 -0.3048)
			(stroke
				(width 0.1)
				(type default)
			)
			(layer "F.Fab")
		)
		(fp_line
			(start 0.12065 -0.2794)
			(end 0.12065 -0.3048)
			(stroke
				(width 0.1)
				(type default)
			)
			(layer "F.Fab")
		)
		(fp_line
			(start 0.67945 -0.3048)
			(end 0.67945 0.3048)
			(stroke
				(width 0.1)
				(type default)
			)
			(layer "F.Fab")
		)
		(fp_line
			(start 0.67945 0.3048)
			(end 0.120396 0.3048)
			(stroke
				(width 0.1)
				(type default)
			)
			(layer "F.Fab")
		)
		(pad "1" smd circle
			(at -0.40005 0)
			(size 0 0)
			(layers "F.Cu" "F.Mask" "F.Paste")
			(net "P3V3_E1S_DVDT_0")
		)
		(pad "2" smd circle
			(at 0.40005 0)
			(size 0 0)
			(layers "F.Cu" "F.Mask" "F.Paste")
			(net "GND")
		)
	)
	(footprint ""
		(layer "F.Cu")
		(at 128.348486 -342.270334)
		(property "Reference" "PR292"
			(at 0 0 0)
			(layer "F.SilkS")
			(hide yes)
			(effects
				(font
					(size 1.27 1.27)
				)
			)
		)
		(property "Value" ""
			(at 0 0 0)
			(layer "F.Fab")
			(effects
				(font
					(size 1.27 1.27)
				)
			)
		)
		(duplicate_pad_numbers_are_jumpers no)
		(fp_line
			(start -0.7874 -0.4064)
			(end 0.7874 -0.4064)
			(stroke
				(width 0.1524)
				(type default)
			)
			(layer "F.SilkS")
		)
		(fp_line
			(start -0.7874 0.4064)
			(end -0.7874 -0.4064)
			(stroke
				(width 0.1524)
				(type default)
			)
			(layer "F.SilkS")
		)
		(fp_line
			(start 0.7874 -0.4064)
			(end 0.7874 0.4064)
			(stroke
				(width 0.1524)
				(type default)
			)
			(layer "F.SilkS")
		)
		(fp_line
			(start 0.7874 0.4064)
			(end -0.7874 0.4064)
			(stroke
				(width 0.1524)
				(type default)
			)
			(layer "F.SilkS")
		)
		(fp_line
			(start -0.67945 -0.305054)
			(end -0.12065 -0.305054)
			(stroke
				(width 0.1)
				(type default)
			)
			(layer "F.Fab")
		)
		(fp_line
			(start -0.67945 0.3048)
			(end -0.67945 -0.305054)
			(stroke
				(width 0.1)
				(type default)
			)
			(layer "F.Fab")
		)
		(fp_line
			(start -0.12065 -0.305054)
			(end -0.12065 -0.2794)
			(stroke
				(width 0.1)
				(type default)
			)
			(layer "F.Fab")
		)
		(fp_line
			(start -0.12065 -0.2794)
			(end 0.12065 -0.2794)
			(stroke
				(width 0.1)
				(type default)
			)
			(layer "F.Fab")
		)
		(fp_line
			(start -0.12065 0.2794)
			(end -0.12065 0.3048)
			(stroke
				(width 0.1)
				(type default)
			)
			(layer "F.Fab")
		)
		(fp_line
			(start -0.12065 0.3048)
			(end -0.67945 0.3048)
			(stroke
				(width 0.1)
				(type default)
			)
			(layer "F.Fab")
		)
		(fp_line
			(start 0.120396 0.2794)
			(end -0.12065 0.2794)
			(stroke
				(width 0.1)
				(type default)
			)
			(layer "F.Fab")
		)
		(fp_line
			(start 0.120396 0.3048)
			(end 0.120396 0.2794)
			(stroke
				(width 0.1)
				(type default)
			)
			(layer "F.Fab")
		)
		(fp_line
			(start 0.12065 -0.3048)
			(end 0.67945 -0.3048)
			(stroke
				(width 0.1)
				(type default)
			)
			(layer "F.Fab")
		)
		(fp_line
			(start 0.12065 -0.2794)
			(end 0.12065 -0.3048)
			(stroke
				(width 0.1)
				(type default)
			)
			(layer "F.Fab")
		)
		(fp_line
			(start 0.67945 -0.3048)
			(end 0.67945 0.3048)
			(stroke
				(width 0.1)
				(type default)
			)
			(layer "F.Fab")
		)
		(fp_line
			(start 0.67945 0.3048)
			(end 0.120396 0.3048)
			(stroke
				(width 0.1)
				(type default)
			)
			(layer "F.Fab")
		)
		(pad "1" smd circle
			(at -0.40005 0)
			(size 0 0)
			(layers "F.Cu" "F.Mask" "F.Paste")
			(net "PVCCIN_CPU1_LSET5")
		)
		(pad "2" smd circle
			(at 0.40005 0)
			(size 0 0)
			(layers "F.Cu" "F.Mask" "F.Paste")
			(net "GND")
		)
	)
	(footprint ""
		(layer "F.Cu")
		(at 123.62688 -92.674948 -90)
		(property "Reference" "R4399"
			(at 0 0 270)
			(layer "F.SilkS")
			(hide yes)
			(effects
				(font
					(size 1.27 1.27)
				)
			)
		)
		(property "Value" ""
			(at 0 0 270)
			(layer "F.Fab")
			(effects
				(font
					(size 1.27 1.27)
				)
			)
		)
		(duplicate_pad_numbers_are_jumpers no)
		(fp_line
			(start -0.7874 0.4064)
			(end -0.7874 -0.4064)
			(stroke
				(width 0.1524)
				(type default)
			)
			(layer "F.SilkS")
		)
		(fp_line
			(start 0.7874 0.4064)
			(end -0.7874 0.4064)
			(stroke
				(width 0.1524)
				(type default)
			)
			(layer "F.SilkS")
		)
		(fp_line
			(start -0.7874 -0.4064)
			(end 0.7874 -0.4064)
			(stroke
				(width 0.1524)
				(type default)
			)
			(layer "F.SilkS")
		)
		(fp_line
			(start 0.7874 -0.4064)
			(end 0.7874 0.4064)
			(stroke
				(width 0.1524)
				(type default)
			)
			(layer "F.SilkS")
		)
		(fp_line
			(start -0.67945 0.3048)
			(end -0.67945 -0.305054)
			(stroke
				(width 0.1)
				(type default)
			)
			(layer "F.Fab")
		)
		(fp_line
			(start -0.12065 0.3048)
			(end -0.67945 0.3048)
			(stroke
				(width 0.1)
				(type default)
			)
			(layer "F.Fab")
		)
		(fp_line
			(start 0.120396 0.3048)
			(end 0.120396 0.2794)
			(stroke
				(width 0.1)
				(type default)
			)
			(layer "F.Fab")
		)
		(fp_line
			(start 0.67945 0.3048)
			(end 0.120396 0.3048)
			(stroke
				(width 0.1)
				(type default)
			)
			(layer "F.Fab")
		)
		(fp_line
			(start -0.12065 0.2794)
			(end -0.12065 0.3048)
			(stroke
				(width 0.1)
				(type default)
			)
			(layer "F.Fab")
		)
		(fp_line
			(start 0.120396 0.2794)
			(end -0.12065 0.2794)
			(stroke
				(width 0.1)
				(type default)
			)
			(layer "F.Fab")
		)
		(fp_line
			(start -0.12065 -0.2794)
			(end 0.12065 -0.2794)
			(stroke
				(width 0.1)
				(type default)
			)
			(layer "F.Fab")
		)
		(fp_line
			(start 0.12065 -0.2794)
			(end 0.12065 -0.3048)
			(stroke
				(width 0.1)
				(type default)
			)
			(layer "F.Fab")
		)
		(fp_line
			(start 0.12065 -0.3048)
			(end 0.67945 -0.3048)
			(stroke
				(width 0.1)
				(type default)
			)
			(layer "F.Fab")
		)
		(fp_line
			(start 0.67945 -0.3048)
			(end 0.67945 0.3048)
			(stroke
				(width 0.1)
				(type default)
			)
			(layer "F.Fab")
		)
		(fp_line
			(start -0.67945 -0.305054)
			(end -0.12065 -0.305054)
			(stroke
				(width 0.1)
				(type default)
			)
			(layer "F.Fab")
		)
		(fp_line
			(start -0.12065 -0.305054)
			(end -0.12065 -0.2794)
			(stroke
				(width 0.1)
				(type default)
			)
			(layer "F.Fab")
		)
		(pad "1" smd circle
			(at -0.40005 0 270)
			(size 0 0)
			(layers "F.Cu" "F.Mask" "F.Paste")
			(net "H_CPU0_THERMTRIP_VT_N")
		)
		(pad "2" smd circle
			(at 0.40005 0 270)
			(size 0 0)
			(layers "F.Cu" "F.Mask" "F.Paste")
			(net "H_CPU0_THERMTRIP_LVC1_N")
		)
	)
	(footprint ""
		(layer "F.Cu")
		(at 213.41588 -50.637948 90)
		(property "Reference" "R3756"
			(at 0 0 90)
			(layer "F.SilkS")
			(hide yes)
			(effects
				(font
					(size 1.27 1.27)
				)
			)
		)
		(property "Value" ""
			(at 0 0 90)
			(layer "F.Fab")
			(effects
				(font
					(size 1.27 1.27)
				)
			)
		)
		(duplicate_pad_numbers_are_jumpers no)
		(fp_line
			(start 0.7874 -0.4064)
			(end 0.7874 0.4064)
			(stroke
				(width 0.1524)
				(type default)
			)
			(layer "F.SilkS")
		)
		(fp_line
			(start -0.7874 -0.4064)
			(end 0.7874 -0.4064)
			(stroke
				(width 0.1524)
				(type default)
			)
			(layer "F.SilkS")
		)
		(fp_line
			(start 0.7874 0.4064)
			(end -0.7874 0.4064)
			(stroke
				(width 0.1524)
				(type default)
			)
			(layer "F.SilkS")
		)
		(fp_line
			(start -0.7874 0.4064)
			(end -0.7874 -0.4064)
			(stroke
				(width 0.1524)
				(type default)
			)
			(layer "F.SilkS")
		)
		(fp_line
			(start -0.12065 -0.305054)
			(end -0.12065 -0.2794)
			(stroke
				(width 0.1)
				(type default)
			)
			(layer "F.Fab")
		)
		(fp_line
			(start -0.67945 -0.305054)
			(end -0.12065 -0.305054)
			(stroke
				(width 0.1)
				(type default)
			)
			(layer "F.Fab")
		)
		(fp_line
			(start 0.67945 -0.3048)
			(end 0.67945 0.3048)
			(stroke
				(width 0.1)
				(type default)
			)
			(layer "F.Fab")
		)
		(fp_line
			(start 0.12065 -0.3048)
			(end 0.67945 -0.3048)
			(stroke
				(width 0.1)
				(type default)
			)
			(layer "F.Fab")
		)
		(fp_line
			(start 0.12065 -0.2794)
			(end 0.12065 -0.3048)
			(stroke
				(width 0.1)
				(type default)
			)
			(layer "F.Fab")
		)
		(fp_line
			(start -0.12065 -0.2794)
			(end 0.12065 -0.2794)
			(stroke
				(width 0.1)
				(type default)
			)
			(layer "F.Fab")
		)
		(fp_line
			(start 0.120396 0.2794)
			(end -0.12065 0.2794)
			(stroke
				(width 0.1)
				(type default)
			)
			(layer "F.Fab")
		)
		(fp_line
			(start -0.12065 0.2794)
			(end -0.12065 0.3048)
			(stroke
				(width 0.1)
				(type default)
			)
			(layer "F.Fab")
		)
		(fp_line
			(start 0.67945 0.3048)
			(end 0.120396 0.3048)
			(stroke
				(width 0.1)
				(type default)
			)
			(layer "F.Fab")
		)
		(fp_line
			(start 0.120396 0.3048)
			(end 0.120396 0.2794)
			(stroke
				(width 0.1)
				(type default)
			)
			(layer "F.Fab")
		)
		(fp_line
			(start -0.12065 0.3048)
			(end -0.67945 0.3048)
			(stroke
				(width 0.1)
				(type default)
			)
			(layer "F.Fab")
		)
		(fp_line
			(start -0.67945 0.3048)
			(end -0.67945 -0.305054)
			(stroke
				(width 0.1)
				(type default)
			)
			(layer "F.Fab")
		)
		(pad "1" smd circle
			(at -0.40005 0 90)
			(size 0 0)
			(layers "F.Cu" "F.Mask" "F.Paste")
			(net "SMB_INA230_2_3V3AUX_SDA_R")
		)
		(pad "2" smd circle
			(at 0.40005 0 90)
			(size 0 0)
			(layers "F.Cu" "F.Mask" "F.Paste")
			(net "SMB_INA230_2_3V3AUX_SDA_R1")
		)
	)
	(footprint ""
		(layer "F.Cu")
		(at 71.393558 -65.082674 -90)
		(property "Reference" "R3082"
			(at 0 0 270)
			(layer "F.SilkS")
			(hide yes)
			(effects
				(font
					(size 1.27 1.27)
				)
			)
		)
		(property "Value" ""
			(at 0 0 270)
			(layer "F.Fab")
			(effects
				(font
					(size 1.27 1.27)
				)
			)
		)
		(duplicate_pad_numbers_are_jumpers no)
		(fp_line
			(start -0.7874 0.4064)
			(end -0.7874 -0.4064)
			(stroke
				(width 0.1524)
				(type default)
			)
			(layer "F.SilkS")
		)
		(fp_line
			(start 0.7874 0.4064)
			(end -0.7874 0.4064)
			(stroke
				(width 0.1524)
				(type default)
			)
			(layer "F.SilkS")
		)
		(fp_line
			(start -0.7874 -0.4064)
			(end 0.7874 -0.4064)
			(stroke
				(width 0.1524)
				(type default)
			)
			(layer "F.SilkS")
		)
		(fp_line
			(start 0.7874 -0.4064)
			(end 0.7874 0.4064)
			(stroke
				(width 0.1524)
				(type default)
			)
			(layer "F.SilkS")
		)
		(fp_line
			(start -0.67945 0.3048)
			(end -0.67945 -0.305054)
			(stroke
				(width 0.1)
				(type default)
			)
			(layer "F.Fab")
		)
		(fp_line
			(start -0.12065 0.3048)
			(end -0.67945 0.3048)
			(stroke
				(width 0.1)
				(type default)
			)
			(layer "F.Fab")
		)
		(fp_line
			(start 0.120396 0.3048)
			(end 0.120396 0.2794)
			(stroke
				(width 0.1)
				(type default)
			)
			(layer "F.Fab")
		)
		(fp_line
			(start 0.67945 0.3048)
			(end 0.120396 0.3048)
			(stroke
				(width 0.1)
				(type default)
			)
			(layer "F.Fab")
		)
		(fp_line
			(start -0.12065 0.2794)
			(end -0.12065 0.3048)
			(stroke
				(width 0.1)
				(type default)
			)
			(layer "F.Fab")
		)
		(fp_line
			(start 0.120396 0.2794)
			(end -0.12065 0.2794)
			(stroke
				(width 0.1)
				(type default)
			)
			(layer "F.Fab")
		)
		(fp_line
			(start -0.12065 -0.2794)
			(end 0.12065 -0.2794)
			(stroke
				(width 0.1)
				(type default)
			)
			(layer "F.Fab")
		)
		(fp_line
			(start 0.12065 -0.2794)
			(end 0.12065 -0.3048)
			(stroke
				(width 0.1)
				(type default)
			)
			(layer "F.Fab")
		)
		(fp_line
			(start 0.12065 -0.3048)
			(end 0.67945 -0.3048)
			(stroke
				(width 0.1)
				(type default)
			)
			(layer "F.Fab")
		)
		(fp_line
			(start 0.67945 -0.3048)
			(end 0.67945 0.3048)
			(stroke
				(width 0.1)
				(type default)
			)
			(layer "F.Fab")
		)
		(fp_line
			(start -0.67945 -0.305054)
			(end -0.12065 -0.305054)
			(stroke
				(width 0.1)
				(type default)
			)
			(layer "F.Fab")
		)
		(fp_line
			(start -0.12065 -0.305054)
			(end -0.12065 -0.2794)
			(stroke
				(width 0.1)
				(type default)
			)
			(layer "F.Fab")
		)
		(pad "1" smd circle
			(at -0.40005 0 270)
			(size 0 0)
			(layers "F.Cu" "F.Mask" "F.Paste")
			(net "LED_RST_PLD_CPU1_DRAM_AB_N")
		)
		(pad "2" smd circle
			(at 0.40005 0 270)
			(size 0 0)
			(layers "F.Cu" "F.Mask" "F.Paste")
			(net "P3V3_AUX")
		)
	)
	(footprint ""
		(layer "F.Cu")
		(at 367.44783 -252.956314 -90)
		(property "Reference" "C1028"
			(at 0 0 270)
			(layer "F.SilkS")
			(hide yes)
			(effects
				(font
					(size 1.27 1.27)
				)
			)
		)
		(property "Value" ""
			(at 0 0 270)
			(layer "F.Fab")
			(effects
				(font
					(size 1.27 1.27)
				)
			)
		)
		(duplicate_pad_numbers_are_jumpers no)
		(fp_line
			(start -0.7874 0.4064)
			(end -0.7874 -0.4064)
			(stroke
				(width 0.1524)
				(type default)
			)
			(layer "F.SilkS")
		)
		(fp_line
			(start 0.7874 0.4064)
			(end -0.7874 0.4064)
			(stroke
				(width 0.1524)
				(type default)
			)
			(layer "F.SilkS")
		)
		(fp_line
			(start -0.7874 -0.4064)
			(end 0.7874 -0.4064)
			(stroke
				(width 0.1524)
				(type default)
			)
			(layer "F.SilkS")
		)
		(fp_line
			(start 0.7874 -0.4064)
			(end 0.7874 0.4064)
			(stroke
				(width 0.1524)
				(type default)
			)
			(layer "F.SilkS")
		)
		(fp_line
			(start -0.67945 0.3048)
			(end -0.67945 -0.305054)
			(stroke
				(width 0.1)
				(type default)
			)
			(layer "F.Fab")
		)
		(fp_line
			(start -0.12065 0.3048)
			(end -0.67945 0.3048)
			(stroke
				(width 0.1)
				(type default)
			)
			(layer "F.Fab")
		)
		(fp_line
			(start 0.120396 0.3048)
			(end 0.120396 0.2794)
			(stroke
				(width 0.1)
				(type default)
			)
			(layer "F.Fab")
		)
		(fp_line
			(start 0.67945 0.3048)
			(end 0.120396 0.3048)
			(stroke
				(width 0.1)
				(type default)
			)
			(layer "F.Fab")
		)
		(fp_line
			(start -0.12065 0.2794)
			(end -0.12065 0.3048)
			(stroke
				(width 0.1)
				(type default)
			)
			(layer "F.Fab")
		)
		(fp_line
			(start 0.120396 0.2794)
			(end -0.12065 0.2794)
			(stroke
				(width 0.1)
				(type default)
			)
			(layer "F.Fab")
		)
		(fp_line
			(start -0.12065 -0.2794)
			(end 0.12065 -0.2794)
			(stroke
				(width 0.1)
				(type default)
			)
			(layer "F.Fab")
		)
		(fp_line
			(start 0.12065 -0.2794)
			(end 0.12065 -0.3048)
			(stroke
				(width 0.1)
				(type default)
			)
			(layer "F.Fab")
		)
		(fp_line
			(start 0.12065 -0.3048)
			(end 0.67945 -0.3048)
			(stroke
				(width 0.1)
				(type default)
			)
			(layer "F.Fab")
		)
		(fp_line
			(start 0.67945 -0.3048)
			(end 0.67945 0.3048)
			(stroke
				(width 0.1)
				(type default)
			)
			(layer "F.Fab")
		)
		(fp_line
			(start -0.67945 -0.305054)
			(end -0.12065 -0.305054)
			(stroke
				(width 0.1)
				(type default)
			)
			(layer "F.Fab")
		)
		(fp_line
			(start -0.12065 -0.305054)
			(end -0.12065 -0.2794)
			(stroke
				(width 0.1)
				(type default)
			)
			(layer "F.Fab")
		)
		(pad "1" smd circle
			(at -0.40005 0 270)
			(size 0 0)
			(layers "F.Cu" "F.Mask" "F.Paste")
			(net "PVCCIN_CPU0")
		)
		(pad "2" smd circle
			(at 0.40005 0 270)
			(size 0 0)
			(layers "F.Cu" "F.Mask" "F.Paste")
			(net "GND")
		)
	)
	(footprint ""
		(layer "F.Cu")
		(at 404.2664 -385.84886)
		(property "Reference" "ME15"
			(at -9.652 -9.540748 0)
			(unlocked yes)
			(layer "F.SilkS")
			(effects
				(font
					(size 0.7874 0.5842)
					(thickness 0.1524)
				)
				(justify left)
			)
		)
		(property "Value" ""
			(at 0 0 0)
			(layer "F.Fab")
			(effects
				(font
					(size 1.27 1.27)
				)
			)
		)
		(duplicate_pad_numbers_are_jumpers no)
		(zone
			(layer "F.Cu")
			(hatch none 0.5)
			(connect_pads
				(clearance 0)
			)
			(min_thickness 0.25)
			(keepout
				(tracks allowed)
				(vias allowed)
				(pads allowed)
				(copperpour allowed)
				(footprints not_allowed)
			)
			(placement
				(enabled no)
				(sheetname "")
			)
			(fill
				(thermal_gap 0.5)
				(thermal_bridge_width 0.5)
				(island_removal_mode 0)
			)
			(polygon
				(pts
					(arc
						(start 414.26638 -385.84886)
						(mid 394.26642 -385.84886)
						(end 414.26638 -385.84886)
					)
				)
			)
		)
	)
	(footprint ""
		(layer "F.Cu")
		(at 288.9377 -406.81402 180)
		(property "Reference" "R4896"
			(at 0 0 180)
			(layer "F.SilkS")
			(hide yes)
			(effects
				(font
					(size 1.27 1.27)
				)
			)
		)
		(property "Value" ""
			(at 0 0 180)
			(layer "F.Fab")
			(effects
				(font
					(size 1.27 1.27)
				)
			)
		)
		(duplicate_pad_numbers_are_jumpers no)
		(fp_line
			(start 0.7874 0.4064)
			(end -0.7874 0.4064)
			(stroke
				(width 0.1524)
				(type default)
			)
			(layer "F.SilkS")
		)
		(fp_line
			(start 0.7874 -0.4064)
			(end 0.7874 0.4064)
			(stroke
				(width 0.1524)
				(type default)
			)
			(layer "F.SilkS")
		)
		(fp_line
			(start -0.7874 0.4064)
			(end -0.7874 -0.4064)
			(stroke
				(width 0.1524)
				(type default)
			)
			(layer "F.SilkS")
		)
		(fp_line
			(start -0.7874 -0.4064)
			(end 0.7874 -0.4064)
			(stroke
				(width 0.1524)
				(type default)
			)
			(layer "F.SilkS")
		)
		(fp_line
			(start 0.67945 0.3048)
			(end 0.120396 0.3048)
			(stroke
				(width 0.1)
				(type default)
			)
			(layer "F.Fab")
		)
		(fp_line
			(start 0.67945 -0.3048)
			(end 0.67945 0.3048)
			(stroke
				(width 0.1)
				(type default)
			)
			(layer "F.Fab")
		)
		(fp_line
			(start 0.12065 -0.2794)
			(end 0.12065 -0.3048)
			(stroke
				(width 0.1)
				(type default)
			)
			(layer "F.Fab")
		)
		(fp_line
			(start 0.12065 -0.3048)
			(end 0.67945 -0.3048)
			(stroke
				(width 0.1)
				(type default)
			)
			(layer "F.Fab")
		)
		(fp_line
			(start 0.120396 0.3048)
			(end 0.120396 0.2794)
			(stroke
				(width 0.1)
				(type default)
			)
			(layer "F.Fab")
		)
		(fp_line
			(start 0.120396 0.2794)
			(end -0.12065 0.2794)
			(stroke
				(width 0.1)
				(type default)
			)
			(layer "F.Fab")
		)
		(fp_line
			(start -0.12065 0.3048)
			(end -0.67945 0.3048)
			(stroke
				(width 0.1)
				(type default)
			)
			(layer "F.Fab")
		)
		(fp_line
			(start -0.12065 0.2794)
			(end -0.12065 0.3048)
			(stroke
				(width 0.1)
				(type default)
			)
			(layer "F.Fab")
		)
		(fp_line
			(start -0.12065 -0.2794)
			(end 0.12065 -0.2794)
			(stroke
				(width 0.1)
				(type default)
			)
			(layer "F.Fab")
		)
		(fp_line
			(start -0.12065 -0.305054)
			(end -0.12065 -0.2794)
			(stroke
				(width 0.1)
				(type default)
			)
			(layer "F.Fab")
		)
		(fp_line
			(start -0.67945 0.3048)
			(end -0.67945 -0.305054)
			(stroke
				(width 0.1)
				(type default)
			)
			(layer "F.Fab")
		)
		(fp_line
			(start -0.67945 -0.305054)
			(end -0.12065 -0.305054)
			(stroke
				(width 0.1)
				(type default)
			)
			(layer "F.Fab")
		)
		(pad "1" smd circle
			(at -0.40005 0 180)
			(size 0 0)
			(layers "F.Cu" "F.Mask" "F.Paste")
			(net "P12V_HSC_T_CRIT_N")
		)
		(pad "2" smd circle
			(at 0.40005 0 180)
			(size 0 0)
			(layers "F.Cu" "F.Mask" "F.Paste")
			(net "P12V_HSC_T_CRIT_R_N")
		)
	)
	(footprint ""
		(layer "F.Cu")
		(at 214.4268 -107.4166 -90)
		(property "Reference" "C2382"
			(at 0 0 270)
			(layer "F.SilkS")
			(hide yes)
			(effects
				(font
					(size 1.27 1.27)
				)
			)
		)
		(property "Value" ""
			(at 0 0 270)
			(layer "F.Fab")
			(effects
				(font
					(size 1.27 1.27)
				)
			)
		)
		(duplicate_pad_numbers_are_jumpers no)
		(fp_line
			(start -0.7874 0.4064)
			(end -0.7874 -0.4064)
			(stroke
				(width 0.1524)
				(type default)
			)
			(layer "F.SilkS")
		)
		(fp_line
			(start 0.7874 0.4064)
			(end -0.7874 0.4064)
			(stroke
				(width 0.1524)
				(type default)
			)
			(layer "F.SilkS")
		)
		(fp_line
			(start -0.7874 -0.4064)
			(end 0.7874 -0.4064)
			(stroke
				(width 0.1524)
				(type default)
			)
			(layer "F.SilkS")
		)
		(fp_line
			(start 0.7874 -0.4064)
			(end 0.7874 0.4064)
			(stroke
				(width 0.1524)
				(type default)
			)
			(layer "F.SilkS")
		)
		(fp_line
			(start -0.67945 0.3048)
			(end -0.67945 -0.305054)
			(stroke
				(width 0.1)
				(type default)
			)
			(layer "F.Fab")
		)
		(fp_line
			(start -0.12065 0.3048)
			(end -0.67945 0.3048)
			(stroke
				(width 0.1)
				(type default)
			)
			(layer "F.Fab")
		)
		(fp_line
			(start 0.120396 0.3048)
			(end 0.120396 0.2794)
			(stroke
				(width 0.1)
				(type default)
			)
			(layer "F.Fab")
		)
		(fp_line
			(start 0.67945 0.3048)
			(end 0.120396 0.3048)
			(stroke
				(width 0.1)
				(type default)
			)
			(layer "F.Fab")
		)
		(fp_line
			(start -0.12065 0.2794)
			(end -0.12065 0.3048)
			(stroke
				(width 0.1)
				(type default)
			)
			(layer "F.Fab")
		)
		(fp_line
			(start 0.120396 0.2794)
			(end -0.12065 0.2794)
			(stroke
				(width 0.1)
				(type default)
			)
			(layer "F.Fab")
		)
		(fp_line
			(start -0.12065 -0.2794)
			(end 0.12065 -0.2794)
			(stroke
				(width 0.1)
				(type default)
			)
			(layer "F.Fab")
		)
		(fp_line
			(start 0.12065 -0.2794)
			(end 0.12065 -0.3048)
			(stroke
				(width 0.1)
				(type default)
			)
			(layer "F.Fab")
		)
		(fp_line
			(start 0.12065 -0.3048)
			(end 0.67945 -0.3048)
			(stroke
				(width 0.1)
				(type default)
			)
			(layer "F.Fab")
		)
		(fp_line
			(start 0.67945 -0.3048)
			(end 0.67945 0.3048)
			(stroke
				(width 0.1)
				(type default)
			)
			(layer "F.Fab")
		)
		(fp_line
			(start -0.67945 -0.305054)
			(end -0.12065 -0.305054)
			(stroke
				(width 0.1)
				(type default)
			)
			(layer "F.Fab")
		)
		(fp_line
			(start -0.12065 -0.305054)
			(end -0.12065 -0.2794)
			(stroke
				(width 0.1)
				(type default)
			)
			(layer "F.Fab")
		)
		(pad "1" smd circle
			(at -0.40005 0 270)
			(size 0 0)
			(layers "F.Cu" "F.Mask" "F.Paste")
			(net "P12V_AUX_UV_TRIGGER")
		)
		(pad "2" smd circle
			(at 0.40005 0 270)
			(size 0 0)
			(layers "F.Cu" "F.Mask" "F.Paste")
			(net "GND")
		)
	)
	(footprint ""
		(layer "F.Cu")
		(at 411.21965 -402.371052 -90)
		(property "Reference" "C961"
			(at 0 0 270)
			(layer "F.SilkS")
			(hide yes)
			(effects
				(font
					(size 1.27 1.27)
				)
			)
		)
		(property "Value" ""
			(at 0 0 270)
			(layer "F.Fab")
			(effects
				(font
					(size 1.27 1.27)
				)
			)
		)
		(duplicate_pad_numbers_are_jumpers no)
		(fp_line
			(start -0.299974 0.150114)
			(end -0.299974 -0.150114)
			(stroke
				(width 0.1)
				(type default)
			)
			(layer "F.Fab")
		)
		(fp_line
			(start 0.299974 0.150114)
			(end -0.299974 0.150114)
			(stroke
				(width 0.1)
				(type default)
			)
			(layer "F.Fab")
		)
		(fp_line
			(start -0.299974 -0.150114)
			(end 0.299974 -0.150114)
			(stroke
				(width 0.1)
				(type default)
			)
			(layer "F.Fab")
		)
		(fp_line
			(start 0.299974 -0.150114)
			(end 0.299974 0.150114)
			(stroke
				(width 0.1)
				(type default)
			)
			(layer "F.Fab")
		)
		(pad "1" smd rect
			(at -0.2667 0 270)
			(size 0.3048 0.381)
			(layers "F.Cu" "F.Mask" "F.Paste")
			(net "P5E_CPU0_PE2_TX_C_DP<2>")
		)
		(pad "2" smd rect
			(at 0.2667 0 270)
			(size 0.3048 0.381)
			(layers "F.Cu" "F.Mask" "F.Paste")
			(net "P5E_CPU0_PE2_TX_DP<2>")
		)
	)
	(footprint ""
		(layer "F.Cu")
		(at 176.17948 -425.414948)
		(property "Reference" "R2917"
			(at 0 0 0)
			(layer "F.SilkS")
			(hide yes)
			(effects
				(font
					(size 1.27 1.27)
				)
			)
		)
		(property "Value" ""
			(at 0 0 0)
			(layer "F.Fab")
			(effects
				(font
					(size 1.27 1.27)
				)
			)
		)
		(duplicate_pad_numbers_are_jumpers no)
		(fp_line
			(start -0.7874 -0.4064)
			(end 0.7874 -0.4064)
			(stroke
				(width 0.1524)
				(type default)
			)
			(layer "F.SilkS")
		)
		(fp_line
			(start -0.7874 0.4064)
			(end -0.7874 -0.4064)
			(stroke
				(width 0.1524)
				(type default)
			)
			(layer "F.SilkS")
		)
		(fp_line
			(start 0.7874 -0.4064)
			(end 0.7874 0.4064)
			(stroke
				(width 0.1524)
				(type default)
			)
			(layer "F.SilkS")
		)
		(fp_line
			(start 0.7874 0.4064)
			(end -0.7874 0.4064)
			(stroke
				(width 0.1524)
				(type default)
			)
			(layer "F.SilkS")
		)
		(fp_line
			(start -0.67945 -0.305054)
			(end -0.12065 -0.305054)
			(stroke
				(width 0.1)
				(type default)
			)
			(layer "F.Fab")
		)
		(fp_line
			(start -0.67945 0.3048)
			(end -0.67945 -0.305054)
			(stroke
				(width 0.1)
				(type default)
			)
			(layer "F.Fab")
		)
		(fp_line
			(start -0.12065 -0.305054)
			(end -0.12065 -0.2794)
			(stroke
				(width 0.1)
				(type default)
			)
			(layer "F.Fab")
		)
		(fp_line
			(start -0.12065 -0.2794)
			(end 0.12065 -0.2794)
			(stroke
				(width 0.1)
				(type default)
			)
			(layer "F.Fab")
		)
		(fp_line
			(start -0.12065 0.2794)
			(end -0.12065 0.3048)
			(stroke
				(width 0.1)
				(type default)
			)
			(layer "F.Fab")
		)
		(fp_line
			(start -0.12065 0.3048)
			(end -0.67945 0.3048)
			(stroke
				(width 0.1)
				(type default)
			)
			(layer "F.Fab")
		)
		(fp_line
			(start 0.120396 0.2794)
			(end -0.12065 0.2794)
			(stroke
				(width 0.1)
				(type default)
			)
			(layer "F.Fab")
		)
		(fp_line
			(start 0.120396 0.3048)
			(end 0.120396 0.2794)
			(stroke
				(width 0.1)
				(type default)
			)
			(layer "F.Fab")
		)
		(fp_line
			(start 0.12065 -0.3048)
			(end 0.67945 -0.3048)
			(stroke
				(width 0.1)
				(type default)
			)
			(layer "F.Fab")
		)
		(fp_line
			(start 0.12065 -0.2794)
			(end 0.12065 -0.3048)
			(stroke
				(width 0.1)
				(type default)
			)
			(layer "F.Fab")
		)
		(fp_line
			(start 0.67945 -0.3048)
			(end 0.67945 0.3048)
			(stroke
				(width 0.1)
				(type default)
			)
			(layer "F.Fab")
		)
		(fp_line
			(start 0.67945 0.3048)
			(end 0.120396 0.3048)
			(stroke
				(width 0.1)
				(type default)
			)
			(layer "F.Fab")
		)
		(pad "1" smd circle
			(at -0.40005 0)
			(size 0 0)
			(layers "F.Cu" "F.Mask" "F.Paste")
			(net "BMC_MONITER_BUF_R")
		)
		(pad "2" smd circle
			(at 0.40005 0)
			(size 0 0)
			(layers "F.Cu" "F.Mask" "F.Paste")
			(net "BMC_MONITER_BUF")
		)
	)
	(footprint ""
		(layer "F.Cu")
		(at 319.270888 -402.371052 -90)
		(property "Reference" "C1568"
			(at 0 0 270)
			(layer "F.SilkS")
			(hide yes)
			(effects
				(font
					(size 1.27 1.27)
				)
			)
		)
		(property "Value" ""
			(at 0 0 270)
			(layer "F.Fab")
			(effects
				(font
					(size 1.27 1.27)
				)
			)
		)
		(duplicate_pad_numbers_are_jumpers no)
		(fp_line
			(start -0.299974 0.150114)
			(end -0.299974 -0.150114)
			(stroke
				(width 0.1)
				(type default)
			)
			(layer "F.Fab")
		)
		(fp_line
			(start 0.299974 0.150114)
			(end -0.299974 0.150114)
			(stroke
				(width 0.1)
				(type default)
			)
			(layer "F.Fab")
		)
		(fp_line
			(start -0.299974 -0.150114)
			(end 0.299974 -0.150114)
			(stroke
				(width 0.1)
				(type default)
			)
			(layer "F.Fab")
		)
		(fp_line
			(start 0.299974 -0.150114)
			(end 0.299974 0.150114)
			(stroke
				(width 0.1)
				(type default)
			)
			(layer "F.Fab")
		)
		(pad "1" smd rect
			(at -0.2667 0 270)
			(size 0.3048 0.381)
			(layers "F.Cu" "F.Mask" "F.Paste")
			(net "P5E_CPU0_PE4_TX_C_DN<5>")
		)
		(pad "2" smd rect
			(at 0.2667 0 270)
			(size 0.3048 0.381)
			(layers "F.Cu" "F.Mask" "F.Paste")
			(net "P5E_CPU0_PE4_TX_DN<5>")
		)
	)
	(footprint ""
		(layer "F.Cu")
		(at 358.76865 -412.0388)
		(property "Reference" "R4800"
			(at 0 0 0)
			(layer "F.SilkS")
			(hide yes)
			(effects
				(font
					(size 1.27 1.27)
				)
			)
		)
		(property "Value" ""
			(at 0 0 0)
			(layer "F.Fab")
			(effects
				(font
					(size 1.27 1.27)
				)
			)
		)
		(duplicate_pad_numbers_are_jumpers no)
		(fp_line
			(start -0.7874 -0.4064)
			(end 0.7874 -0.4064)
			(stroke
				(width 0.1524)
				(type default)
			)
			(layer "F.SilkS")
		)
		(fp_line
			(start -0.7874 0.4064)
			(end -0.7874 -0.4064)
			(stroke
				(width 0.1524)
				(type default)
			)
			(layer "F.SilkS")
		)
		(fp_line
			(start 0.7874 -0.4064)
			(end 0.7874 0.4064)
			(stroke
				(width 0.1524)
				(type default)
			)
			(layer "F.SilkS")
		)
		(fp_line
			(start 0.7874 0.4064)
			(end -0.7874 0.4064)
			(stroke
				(width 0.1524)
				(type default)
			)
			(layer "F.SilkS")
		)
		(fp_line
			(start -0.67945 -0.305054)
			(end -0.12065 -0.305054)
			(stroke
				(width 0.1)
				(type default)
			)
			(layer "F.Fab")
		)
		(fp_line
			(start -0.67945 0.3048)
			(end -0.67945 -0.305054)
			(stroke
				(width 0.1)
				(type default)
			)
			(layer "F.Fab")
		)
		(fp_line
			(start -0.12065 -0.305054)
			(end -0.12065 -0.2794)
			(stroke
				(width 0.1)
				(type default)
			)
			(layer "F.Fab")
		)
		(fp_line
			(start -0.12065 -0.2794)
			(end 0.12065 -0.2794)
			(stroke
				(width 0.1)
				(type default)
			)
			(layer "F.Fab")
		)
		(fp_line
			(start -0.12065 0.2794)
			(end -0.12065 0.3048)
			(stroke
				(width 0.1)
				(type default)
			)
			(layer "F.Fab")
		)
		(fp_line
			(start -0.12065 0.3048)
			(end -0.67945 0.3048)
			(stroke
				(width 0.1)
				(type default)
			)
			(layer "F.Fab")
		)
		(fp_line
			(start 0.120396 0.2794)
			(end -0.12065 0.2794)
			(stroke
				(width 0.1)
				(type default)
			)
			(layer "F.Fab")
		)
		(fp_line
			(start 0.120396 0.3048)
			(end 0.120396 0.2794)
			(stroke
				(width 0.1)
				(type default)
			)
			(layer "F.Fab")
		)
		(fp_line
			(start 0.12065 -0.3048)
			(end 0.67945 -0.3048)
			(stroke
				(width 0.1)
				(type default)
			)
			(layer "F.Fab")
		)
		(fp_line
			(start 0.12065 -0.2794)
			(end 0.12065 -0.3048)
			(stroke
				(width 0.1)
				(type default)
			)
			(layer "F.Fab")
		)
		(fp_line
			(start 0.67945 -0.3048)
			(end 0.67945 0.3048)
			(stroke
				(width 0.1)
				(type default)
			)
			(layer "F.Fab")
		)
		(fp_line
			(start 0.67945 0.3048)
			(end 0.120396 0.3048)
			(stroke
				(width 0.1)
				(type default)
			)
			(layer "F.Fab")
		)
		(pad "1" smd circle
			(at -0.40005 0)
			(size 0 0)
			(layers "F.Cu" "F.Mask" "F.Paste")
			(net "P3V3_AUX")
		)
		(pad "2" smd circle
			(at 0.40005 0)
			(size 0 0)
			(layers "F.Cu" "F.Mask" "F.Paste")
			(net "PRSNT_CABLE_GPU_A3")
		)
	)
	(footprint ""
		(layer "F.Cu")
		(at 117.581934 -108.331762 -90)
		(property "Reference" "C2246"
			(at 0 0 270)
			(layer "F.SilkS")
			(hide yes)
			(effects
				(font
					(size 1.27 1.27)
				)
			)
		)
		(property "Value" ""
			(at 0 0 270)
			(layer "F.Fab")
			(effects
				(font
					(size 1.27 1.27)
				)
			)
		)
		(duplicate_pad_numbers_are_jumpers no)
		(fp_line
			(start -0.7874 0.4064)
			(end -0.7874 -0.4064)
			(stroke
				(width 0.1524)
				(type default)
			)
			(layer "F.SilkS")
		)
		(fp_line
			(start 0.7874 0.4064)
			(end -0.7874 0.4064)
			(stroke
				(width 0.1524)
				(type default)
			)
			(layer "F.SilkS")
		)
		(fp_line
			(start -0.7874 -0.4064)
			(end 0.7874 -0.4064)
			(stroke
				(width 0.1524)
				(type default)
			)
			(layer "F.SilkS")
		)
		(fp_line
			(start 0.7874 -0.4064)
			(end 0.7874 0.4064)
			(stroke
				(width 0.1524)
				(type default)
			)
			(layer "F.SilkS")
		)
		(fp_line
			(start -0.67945 0.3048)
			(end -0.67945 -0.305054)
			(stroke
				(width 0.1)
				(type default)
			)
			(layer "F.Fab")
		)
		(fp_line
			(start -0.12065 0.3048)
			(end -0.67945 0.3048)
			(stroke
				(width 0.1)
				(type default)
			)
			(layer "F.Fab")
		)
		(fp_line
			(start 0.120396 0.3048)
			(end 0.120396 0.2794)
			(stroke
				(width 0.1)
				(type default)
			)
			(layer "F.Fab")
		)
		(fp_line
			(start 0.67945 0.3048)
			(end 0.120396 0.3048)
			(stroke
				(width 0.1)
				(type default)
			)
			(layer "F.Fab")
		)
		(fp_line
			(start -0.12065 0.2794)
			(end -0.12065 0.3048)
			(stroke
				(width 0.1)
				(type default)
			)
			(layer "F.Fab")
		)
		(fp_line
			(start 0.120396 0.2794)
			(end -0.12065 0.2794)
			(stroke
				(width 0.1)
				(type default)
			)
			(layer "F.Fab")
		)
		(fp_line
			(start -0.12065 -0.2794)
			(end 0.12065 -0.2794)
			(stroke
				(width 0.1)
				(type default)
			)
			(layer "F.Fab")
		)
		(fp_line
			(start 0.12065 -0.2794)
			(end 0.12065 -0.3048)
			(stroke
				(width 0.1)
				(type default)
			)
			(layer "F.Fab")
		)
		(fp_line
			(start 0.12065 -0.3048)
			(end 0.67945 -0.3048)
			(stroke
				(width 0.1)
				(type default)
			)
			(layer "F.Fab")
		)
		(fp_line
			(start 0.67945 -0.3048)
			(end 0.67945 0.3048)
			(stroke
				(width 0.1)
				(type default)
			)
			(layer "F.Fab")
		)
		(fp_line
			(start -0.67945 -0.305054)
			(end -0.12065 -0.305054)
			(stroke
				(width 0.1)
				(type default)
			)
			(layer "F.Fab")
		)
		(fp_line
			(start -0.12065 -0.305054)
			(end -0.12065 -0.2794)
			(stroke
				(width 0.1)
				(type default)
			)
			(layer "F.Fab")
		)
		(pad "1" smd circle
			(at -0.40005 0 270)
			(size 0 0)
			(layers "F.Cu" "F.Mask" "F.Paste")
			(net "P3V3_AUX")
		)
		(pad "2" smd circle
			(at 0.40005 0 270)
			(size 0 0)
			(layers "F.Cu" "F.Mask" "F.Paste")
			(net "GND")
		)
	)
	(footprint ""
		(layer "F.Cu")
		(at 310.007 -53.050948 -90)
		(property "Reference" "R315"
			(at 0 0 270)
			(layer "F.SilkS")
			(hide yes)
			(effects
				(font
					(size 1.27 1.27)
				)
			)
		)
		(property "Value" ""
			(at 0 0 270)
			(layer "F.Fab")
			(effects
				(font
					(size 1.27 1.27)
				)
			)
		)
		(duplicate_pad_numbers_are_jumpers no)
		(fp_line
			(start -0.7874 0.4064)
			(end -0.7874 -0.4064)
			(stroke
				(width 0.1524)
				(type default)
			)
			(layer "F.SilkS")
		)
		(fp_line
			(start 0.7874 0.4064)
			(end -0.7874 0.4064)
			(stroke
				(width 0.1524)
				(type default)
			)
			(layer "F.SilkS")
		)
		(fp_line
			(start -0.7874 -0.4064)
			(end 0.7874 -0.4064)
			(stroke
				(width 0.1524)
				(type default)
			)
			(layer "F.SilkS")
		)
		(fp_line
			(start 0.7874 -0.4064)
			(end 0.7874 0.4064)
			(stroke
				(width 0.1524)
				(type default)
			)
			(layer "F.SilkS")
		)
		(fp_line
			(start -0.67945 0.3048)
			(end -0.67945 -0.305054)
			(stroke
				(width 0.1)
				(type default)
			)
			(layer "F.Fab")
		)
		(fp_line
			(start -0.12065 0.3048)
			(end -0.67945 0.3048)
			(stroke
				(width 0.1)
				(type default)
			)
			(layer "F.Fab")
		)
		(fp_line
			(start 0.120396 0.3048)
			(end 0.120396 0.2794)
			(stroke
				(width 0.1)
				(type default)
			)
			(layer "F.Fab")
		)
		(fp_line
			(start 0.67945 0.3048)
			(end 0.120396 0.3048)
			(stroke
				(width 0.1)
				(type default)
			)
			(layer "F.Fab")
		)
		(fp_line
			(start -0.12065 0.2794)
			(end -0.12065 0.3048)
			(stroke
				(width 0.1)
				(type default)
			)
			(layer "F.Fab")
		)
		(fp_line
			(start 0.120396 0.2794)
			(end -0.12065 0.2794)
			(stroke
				(width 0.1)
				(type default)
			)
			(layer "F.Fab")
		)
		(fp_line
			(start -0.12065 -0.2794)
			(end 0.12065 -0.2794)
			(stroke
				(width 0.1)
				(type default)
			)
			(layer "F.Fab")
		)
		(fp_line
			(start 0.12065 -0.2794)
			(end 0.12065 -0.3048)
			(stroke
				(width 0.1)
				(type default)
			)
			(layer "F.Fab")
		)
		(fp_line
			(start 0.12065 -0.3048)
			(end 0.67945 -0.3048)
			(stroke
				(width 0.1)
				(type default)
			)
			(layer "F.Fab")
		)
		(fp_line
			(start 0.67945 -0.3048)
			(end 0.67945 0.3048)
			(stroke
				(width 0.1)
				(type default)
			)
			(layer "F.Fab")
		)
		(fp_line
			(start -0.67945 -0.305054)
			(end -0.12065 -0.305054)
			(stroke
				(width 0.1)
				(type default)
			)
			(layer "F.Fab")
		)
		(fp_line
			(start -0.12065 -0.305054)
			(end -0.12065 -0.2794)
			(stroke
				(width 0.1)
				(type default)
			)
			(layer "F.Fab")
		)
		(pad "1" smd circle
			(at -0.40005 0 270)
			(size 0 0)
			(layers "F.Cu" "F.Mask" "F.Paste")
			(net "PWRGD_CPUPWRGD_GTL")
		)
		(pad "2" smd circle
			(at 0.40005 0 270)
			(size 0 0)
			(layers "F.Cu" "F.Mask" "F.Paste")
			(net "PWRGD_CPUPWRGD_LVC1_R")
		)
	)
	(footprint ""
		(layer "F.Cu")
		(at 173.5836 -366.33023)
		(property "Reference" "PC1658"
			(at 0 0 0)
			(layer "F.SilkS")
			(hide yes)
			(effects
				(font
					(size 1.27 1.27)
				)
			)
		)
		(property "Value" ""
			(at 0 0 0)
			(layer "F.Fab")
			(effects
				(font
					(size 1.27 1.27)
				)
			)
		)
		(duplicate_pad_numbers_are_jumpers no)
		(fp_line
			(start -0.7874 -0.4064)
			(end 0.7874 -0.4064)
			(stroke
				(width 0.1524)
				(type default)
			)
			(layer "F.SilkS")
		)
		(fp_line
			(start -0.7874 0.4064)
			(end -0.7874 -0.4064)
			(stroke
				(width 0.1524)
				(type default)
			)
			(layer "F.SilkS")
		)
		(fp_line
			(start 0.7874 -0.4064)
			(end 0.7874 0.4064)
			(stroke
				(width 0.1524)
				(type default)
			)
			(layer "F.SilkS")
		)
		(fp_line
			(start 0.7874 0.4064)
			(end -0.7874 0.4064)
			(stroke
				(width 0.1524)
				(type default)
			)
			(layer "F.SilkS")
		)
		(fp_line
			(start -0.67945 -0.305054)
			(end -0.12065 -0.305054)
			(stroke
				(width 0.1)
				(type default)
			)
			(layer "F.Fab")
		)
		(fp_line
			(start -0.67945 0.3048)
			(end -0.67945 -0.305054)
			(stroke
				(width 0.1)
				(type default)
			)
			(layer "F.Fab")
		)
		(fp_line
			(start -0.12065 -0.305054)
			(end -0.12065 -0.2794)
			(stroke
				(width 0.1)
				(type default)
			)
			(layer "F.Fab")
		)
		(fp_line
			(start -0.12065 -0.2794)
			(end 0.12065 -0.2794)
			(stroke
				(width 0.1)
				(type default)
			)
			(layer "F.Fab")
		)
		(fp_line
			(start -0.12065 0.2794)
			(end -0.12065 0.3048)
			(stroke
				(width 0.1)
				(type default)
			)
			(layer "F.Fab")
		)
		(fp_line
			(start -0.12065 0.3048)
			(end -0.67945 0.3048)
			(stroke
				(width 0.1)
				(type default)
			)
			(layer "F.Fab")
		)
		(fp_line
			(start 0.120396 0.2794)
			(end -0.12065 0.2794)
			(stroke
				(width 0.1)
				(type default)
			)
			(layer "F.Fab")
		)
		(fp_line
			(start 0.120396 0.3048)
			(end 0.120396 0.2794)
			(stroke
				(width 0.1)
				(type default)
			)
			(layer "F.Fab")
		)
		(fp_line
			(start 0.12065 -0.3048)
			(end 0.67945 -0.3048)
			(stroke
				(width 0.1)
				(type default)
			)
			(layer "F.Fab")
		)
		(fp_line
			(start 0.12065 -0.2794)
			(end 0.12065 -0.3048)
			(stroke
				(width 0.1)
				(type default)
			)
			(layer "F.Fab")
		)
		(fp_line
			(start 0.67945 -0.3048)
			(end 0.67945 0.3048)
			(stroke
				(width 0.1)
				(type default)
			)
			(layer "F.Fab")
		)
		(fp_line
			(start 0.67945 0.3048)
			(end 0.120396 0.3048)
			(stroke
				(width 0.1)
				(type default)
			)
			(layer "F.Fab")
		)
		(pad "1" smd circle
			(at -0.40005 0)
			(size 0 0)
			(layers "F.Cu" "F.Mask" "F.Paste")
			(net "P12V_AUX")
		)
		(pad "2" smd circle
			(at 0.40005 0)
			(size 0 0)
			(layers "F.Cu" "F.Mask" "F.Paste")
			(net "GND")
		)
	)
	(footprint ""
		(layer "F.Cu")
		(at 220.345 -49.911 180)
		(property "Reference" "C2378"
			(at 0 0 180)
			(layer "F.SilkS")
			(hide yes)
			(effects
				(font
					(size 1.27 1.27)
				)
			)
		)
		(property "Value" ""
			(at 0 0 180)
			(layer "F.Fab")
			(effects
				(font
					(size 1.27 1.27)
				)
			)
		)
		(duplicate_pad_numbers_are_jumpers no)
		(fp_line
			(start 0.7874 0.4064)
			(end -0.7874 0.4064)
			(stroke
				(width 0.1524)
				(type default)
			)
			(layer "F.SilkS")
		)
		(fp_line
			(start 0.7874 -0.4064)
			(end 0.7874 0.4064)
			(stroke
				(width 0.1524)
				(type default)
			)
			(layer "F.SilkS")
		)
		(fp_line
			(start -0.7874 0.4064)
			(end -0.7874 -0.4064)
			(stroke
				(width 0.1524)
				(type default)
			)
			(layer "F.SilkS")
		)
		(fp_line
			(start -0.7874 -0.4064)
			(end 0.7874 -0.4064)
			(stroke
				(width 0.1524)
				(type default)
			)
			(layer "F.SilkS")
		)
		(fp_line
			(start 0.67945 0.3048)
			(end 0.120396 0.3048)
			(stroke
				(width 0.1)
				(type default)
			)
			(layer "F.Fab")
		)
		(fp_line
			(start 0.67945 -0.3048)
			(end 0.67945 0.3048)
			(stroke
				(width 0.1)
				(type default)
			)
			(layer "F.Fab")
		)
		(fp_line
			(start 0.12065 -0.2794)
			(end 0.12065 -0.3048)
			(stroke
				(width 0.1)
				(type default)
			)
			(layer "F.Fab")
		)
		(fp_line
			(start 0.12065 -0.3048)
			(end 0.67945 -0.3048)
			(stroke
				(width 0.1)
				(type default)
			)
			(layer "F.Fab")
		)
		(fp_line
			(start 0.120396 0.3048)
			(end 0.120396 0.2794)
			(stroke
				(width 0.1)
				(type default)
			)
			(layer "F.Fab")
		)
		(fp_line
			(start 0.120396 0.2794)
			(end -0.12065 0.2794)
			(stroke
				(width 0.1)
				(type default)
			)
			(layer "F.Fab")
		)
		(fp_line
			(start -0.12065 0.3048)
			(end -0.67945 0.3048)
			(stroke
				(width 0.1)
				(type default)
			)
			(layer "F.Fab")
		)
		(fp_line
			(start -0.12065 0.2794)
			(end -0.12065 0.3048)
			(stroke
				(width 0.1)
				(type default)
			)
			(layer "F.Fab")
		)
		(fp_line
			(start -0.12065 -0.2794)
			(end 0.12065 -0.2794)
			(stroke
				(width 0.1)
				(type default)
			)
			(layer "F.Fab")
		)
		(fp_line
			(start -0.12065 -0.305054)
			(end -0.12065 -0.2794)
			(stroke
				(width 0.1)
				(type default)
			)
			(layer "F.Fab")
		)
		(fp_line
			(start -0.67945 0.3048)
			(end -0.67945 -0.305054)
			(stroke
				(width 0.1)
				(type default)
			)
			(layer "F.Fab")
		)
		(fp_line
			(start -0.67945 -0.305054)
			(end -0.12065 -0.305054)
			(stroke
				(width 0.1)
				(type default)
			)
			(layer "F.Fab")
		)
		(pad "1" smd circle
			(at -0.40005 0 180)
			(size 0 0)
			(layers "F.Cu" "F.Mask" "F.Paste")
			(net "P3V3_E1S_0")
		)
		(pad "2" smd circle
			(at 0.40005 0 180)
			(size 0 0)
			(layers "F.Cu" "F.Mask" "F.Paste")
			(net "GND")
		)
	)
	(footprint ""
		(layer "F.Cu")
		(at 375.37517 -402.371052 -90)
		(property "Reference" "C936"
			(at 0 0 270)
			(layer "F.SilkS")
			(hide yes)
			(effects
				(font
					(size 1.27 1.27)
				)
			)
		)
		(property "Value" ""
			(at 0 0 270)
			(layer "F.Fab")
			(effects
				(font
					(size 1.27 1.27)
				)
			)
		)
		(duplicate_pad_numbers_are_jumpers no)
		(fp_line
			(start -0.299974 0.150114)
			(end -0.299974 -0.150114)
			(stroke
				(width 0.1)
				(type default)
			)
			(layer "F.Fab")
		)
		(fp_line
			(start 0.299974 0.150114)
			(end -0.299974 0.150114)
			(stroke
				(width 0.1)
				(type default)
			)
			(layer "F.Fab")
		)
		(fp_line
			(start -0.299974 -0.150114)
			(end 0.299974 -0.150114)
			(stroke
				(width 0.1)
				(type default)
			)
			(layer "F.Fab")
		)
		(fp_line
			(start 0.299974 -0.150114)
			(end 0.299974 0.150114)
			(stroke
				(width 0.1)
				(type default)
			)
			(layer "F.Fab")
		)
		(pad "1" smd rect
			(at -0.2667 0 270)
			(size 0.3048 0.381)
			(layers "F.Cu" "F.Mask" "F.Paste")
			(net "P5E_CPU0_PE2_TX_C_DN<14>")
		)
		(pad "2" smd rect
			(at 0.2667 0 270)
			(size 0.3048 0.381)
			(layers "F.Cu" "F.Mask" "F.Paste")
			(net "P5E_CPU0_PE2_TX_DN<14>")
		)
	)
	(footprint ""
		(layer "F.Cu")
		(at 394.141198 -161.07791 180)
		(property "Reference" "R969"
			(at 0 0 180)
			(layer "F.SilkS")
			(hide yes)
			(effects
				(font
					(size 1.27 1.27)
				)
			)
		)
		(property "Value" ""
			(at 0 0 180)
			(layer "F.Fab")
			(effects
				(font
					(size 1.27 1.27)
				)
			)
		)
		(duplicate_pad_numbers_are_jumpers no)
		(fp_line
			(start 0.7874 0.4064)
			(end -0.7874 0.4064)
			(stroke
				(width 0.1524)
				(type default)
			)
			(layer "F.SilkS")
		)
		(fp_line
			(start 0.7874 -0.4064)
			(end 0.7874 0.4064)
			(stroke
				(width 0.1524)
				(type default)
			)
			(layer "F.SilkS")
		)
		(fp_line
			(start -0.7874 0.4064)
			(end -0.7874 -0.4064)
			(stroke
				(width 0.1524)
				(type default)
			)
			(layer "F.SilkS")
		)
		(fp_line
			(start -0.7874 -0.4064)
			(end 0.7874 -0.4064)
			(stroke
				(width 0.1524)
				(type default)
			)
			(layer "F.SilkS")
		)
		(fp_line
			(start 0.67945 0.3048)
			(end 0.120396 0.3048)
			(stroke
				(width 0.1)
				(type default)
			)
			(layer "F.Fab")
		)
		(fp_line
			(start 0.67945 -0.3048)
			(end 0.67945 0.3048)
			(stroke
				(width 0.1)
				(type default)
			)
			(layer "F.Fab")
		)
		(fp_line
			(start 0.12065 -0.2794)
			(end 0.12065 -0.3048)
			(stroke
				(width 0.1)
				(type default)
			)
			(layer "F.Fab")
		)
		(fp_line
			(start 0.12065 -0.3048)
			(end 0.67945 -0.3048)
			(stroke
				(width 0.1)
				(type default)
			)
			(layer "F.Fab")
		)
		(fp_line
			(start 0.120396 0.3048)
			(end 0.120396 0.2794)
			(stroke
				(width 0.1)
				(type default)
			)
			(layer "F.Fab")
		)
		(fp_line
			(start 0.120396 0.2794)
			(end -0.12065 0.2794)
			(stroke
				(width 0.1)
				(type default)
			)
			(layer "F.Fab")
		)
		(fp_line
			(start -0.12065 0.3048)
			(end -0.67945 0.3048)
			(stroke
				(width 0.1)
				(type default)
			)
			(layer "F.Fab")
		)
		(fp_line
			(start -0.12065 0.2794)
			(end -0.12065 0.3048)
			(stroke
				(width 0.1)
				(type default)
			)
			(layer "F.Fab")
		)
		(fp_line
			(start -0.12065 -0.2794)
			(end 0.12065 -0.2794)
			(stroke
				(width 0.1)
				(type default)
			)
			(layer "F.Fab")
		)
		(fp_line
			(start -0.12065 -0.305054)
			(end -0.12065 -0.2794)
			(stroke
				(width 0.1)
				(type default)
			)
			(layer "F.Fab")
		)
		(fp_line
			(start -0.67945 0.3048)
			(end -0.67945 -0.305054)
			(stroke
				(width 0.1)
				(type default)
			)
			(layer "F.Fab")
		)
		(fp_line
			(start -0.67945 -0.305054)
			(end -0.12065 -0.305054)
			(stroke
				(width 0.1)
				(type default)
			)
			(layer "F.Fab")
		)
		(pad "1" smd circle
			(at -0.40005 0 180)
			(size 0 0)
			(layers "F.Cu" "F.Mask" "F.Paste")
			(net "PVNN_TERM_CPU0")
		)
		(pad "2" smd circle
			(at 0.40005 0 180)
			(size 0 0)
			(layers "F.Cu" "F.Mask" "F.Paste")
			(net "SMB_S3M_CPU0_R_SCL")
		)
	)
	(footprint ""
		(layer "F.Cu")
		(at 355.227128 -260.364986 -90)
		(property "Reference" "C413"
			(at 0 0 270)
			(layer "F.SilkS")
			(hide yes)
			(effects
				(font
					(size 1.27 1.27)
				)
			)
		)
		(property "Value" ""
			(at 0 0 270)
			(layer "F.Fab")
			(effects
				(font
					(size 1.27 1.27)
				)
			)
		)
		(duplicate_pad_numbers_are_jumpers no)
		(fp_line
			(start -0.7874 0.4064)
			(end -0.7874 -0.4064)
			(stroke
				(width 0.1524)
				(type default)
			)
			(layer "F.SilkS")
		)
		(fp_line
			(start 0.7874 0.4064)
			(end -0.7874 0.4064)
			(stroke
				(width 0.1524)
				(type default)
			)
			(layer "F.SilkS")
		)
		(fp_line
			(start -0.7874 -0.4064)
			(end 0.7874 -0.4064)
			(stroke
				(width 0.1524)
				(type default)
			)
			(layer "F.SilkS")
		)
		(fp_line
			(start 0.7874 -0.4064)
			(end 0.7874 0.4064)
			(stroke
				(width 0.1524)
				(type default)
			)
			(layer "F.SilkS")
		)
		(fp_line
			(start -0.67945 0.3048)
			(end -0.67945 -0.305054)
			(stroke
				(width 0.1)
				(type default)
			)
			(layer "F.Fab")
		)
		(fp_line
			(start -0.12065 0.3048)
			(end -0.67945 0.3048)
			(stroke
				(width 0.1)
				(type default)
			)
			(layer "F.Fab")
		)
		(fp_line
			(start 0.120396 0.3048)
			(end 0.120396 0.2794)
			(stroke
				(width 0.1)
				(type default)
			)
			(layer "F.Fab")
		)
		(fp_line
			(start 0.67945 0.3048)
			(end 0.120396 0.3048)
			(stroke
				(width 0.1)
				(type default)
			)
			(layer "F.Fab")
		)
		(fp_line
			(start -0.12065 0.2794)
			(end -0.12065 0.3048)
			(stroke
				(width 0.1)
				(type default)
			)
			(layer "F.Fab")
		)
		(fp_line
			(start 0.120396 0.2794)
			(end -0.12065 0.2794)
			(stroke
				(width 0.1)
				(type default)
			)
			(layer "F.Fab")
		)
		(fp_line
			(start -0.12065 -0.2794)
			(end 0.12065 -0.2794)
			(stroke
				(width 0.1)
				(type default)
			)
			(layer "F.Fab")
		)
		(fp_line
			(start 0.12065 -0.2794)
			(end 0.12065 -0.3048)
			(stroke
				(width 0.1)
				(type default)
			)
			(layer "F.Fab")
		)
		(fp_line
			(start 0.12065 -0.3048)
			(end 0.67945 -0.3048)
			(stroke
				(width 0.1)
				(type default)
			)
			(layer "F.Fab")
		)
		(fp_line
			(start 0.67945 -0.3048)
			(end 0.67945 0.3048)
			(stroke
				(width 0.1)
				(type default)
			)
			(layer "F.Fab")
		)
		(fp_line
			(start -0.67945 -0.305054)
			(end -0.12065 -0.305054)
			(stroke
				(width 0.1)
				(type default)
			)
			(layer "F.Fab")
		)
		(fp_line
			(start -0.12065 -0.305054)
			(end -0.12065 -0.2794)
			(stroke
				(width 0.1)
				(type default)
			)
			(layer "F.Fab")
		)
		(pad "1" smd circle
			(at -0.40005 0 270)
			(size 0 0)
			(layers "F.Cu" "F.Mask" "F.Paste")
			(net "PVCCFA_EHV_FIVRA_CPU0")
		)
		(pad "2" smd circle
			(at 0.40005 0 270)
			(size 0 0)
			(layers "F.Cu" "F.Mask" "F.Paste")
			(net "GND")
		)
	)
	(footprint ""
		(layer "F.Cu")
		(at 419.731698 -362.155994 -90)
		(property "Reference" "PC604_P0_1"
			(at 0 0 270)
			(layer "F.SilkS")
			(hide yes)
			(effects
				(font
					(size 1.27 1.27)
				)
			)
		)
		(property "Value" ""
			(at 0 0 270)
			(layer "F.Fab")
			(effects
				(font
					(size 1.27 1.27)
				)
			)
		)
		(duplicate_pad_numbers_are_jumpers no)
		(fp_line
			(start -0.7874 0.4064)
			(end -0.7874 -0.4064)
			(stroke
				(width 0.1524)
				(type default)
			)
			(layer "F.SilkS")
		)
		(fp_line
			(start 0.7874 0.4064)
			(end -0.7874 0.4064)
			(stroke
				(width 0.1524)
				(type default)
			)
			(layer "F.SilkS")
		)
		(fp_line
			(start -0.7874 -0.4064)
			(end 0.7874 -0.4064)
			(stroke
				(width 0.1524)
				(type default)
			)
			(layer "F.SilkS")
		)
		(fp_line
			(start 0.7874 -0.4064)
			(end 0.7874 0.4064)
			(stroke
				(width 0.1524)
				(type default)
			)
			(layer "F.SilkS")
		)
		(fp_line
			(start -0.67945 0.3048)
			(end -0.67945 -0.305054)
			(stroke
				(width 0.1)
				(type default)
			)
			(layer "F.Fab")
		)
		(fp_line
			(start -0.12065 0.3048)
			(end -0.67945 0.3048)
			(stroke
				(width 0.1)
				(type default)
			)
			(layer "F.Fab")
		)
		(fp_line
			(start 0.120396 0.3048)
			(end 0.120396 0.2794)
			(stroke
				(width 0.1)
				(type default)
			)
			(layer "F.Fab")
		)
		(fp_line
			(start 0.67945 0.3048)
			(end 0.120396 0.3048)
			(stroke
				(width 0.1)
				(type default)
			)
			(layer "F.Fab")
		)
		(fp_line
			(start -0.12065 0.2794)
			(end -0.12065 0.3048)
			(stroke
				(width 0.1)
				(type default)
			)
			(layer "F.Fab")
		)
		(fp_line
			(start 0.120396 0.2794)
			(end -0.12065 0.2794)
			(stroke
				(width 0.1)
				(type default)
			)
			(layer "F.Fab")
		)
		(fp_line
			(start -0.12065 -0.2794)
			(end 0.12065 -0.2794)
			(stroke
				(width 0.1)
				(type default)
			)
			(layer "F.Fab")
		)
		(fp_line
			(start 0.12065 -0.2794)
			(end 0.12065 -0.3048)
			(stroke
				(width 0.1)
				(type default)
			)
			(layer "F.Fab")
		)
		(fp_line
			(start 0.12065 -0.3048)
			(end 0.67945 -0.3048)
			(stroke
				(width 0.1)
				(type default)
			)
			(layer "F.Fab")
		)
		(fp_line
			(start 0.67945 -0.3048)
			(end 0.67945 0.3048)
			(stroke
				(width 0.1)
				(type default)
			)
			(layer "F.Fab")
		)
		(fp_line
			(start -0.67945 -0.305054)
			(end -0.12065 -0.305054)
			(stroke
				(width 0.1)
				(type default)
			)
			(layer "F.Fab")
		)
		(fp_line
			(start -0.12065 -0.305054)
			(end -0.12065 -0.2794)
			(stroke
				(width 0.1)
				(type default)
			)
			(layer "F.Fab")
		)
		(pad "1" smd circle
			(at -0.40005 0 270)
			(size 0 0)
			(layers "F.Cu" "F.Mask" "F.Paste")
			(net "SW_P12V_PVCCFA_EHV_FIVRA_CPU0_R")
		)
		(pad "2" smd circle
			(at 0.40005 0 270)
			(size 0 0)
			(layers "F.Cu" "F.Mask" "F.Paste")
			(net "GND")
		)
	)
	(footprint ""
		(layer "F.Cu")
		(at 21.801582 -423.629836 -90)
		(property "Reference" "R3067"
			(at 0 0 270)
			(layer "F.SilkS")
			(hide yes)
			(effects
				(font
					(size 1.27 1.27)
				)
			)
		)
		(property "Value" ""
			(at 0 0 270)
			(layer "F.Fab")
			(effects
				(font
					(size 1.27 1.27)
				)
			)
		)
		(duplicate_pad_numbers_are_jumpers no)
		(fp_line
			(start -0.7874 0.4064)
			(end -0.7874 -0.4064)
			(stroke
				(width 0.1524)
				(type default)
			)
			(layer "F.SilkS")
		)
		(fp_line
			(start 0.7874 0.4064)
			(end -0.7874 0.4064)
			(stroke
				(width 0.1524)
				(type default)
			)
			(layer "F.SilkS")
		)
		(fp_line
			(start -0.7874 -0.4064)
			(end 0.7874 -0.4064)
			(stroke
				(width 0.1524)
				(type default)
			)
			(layer "F.SilkS")
		)
		(fp_line
			(start 0.7874 -0.4064)
			(end 0.7874 0.4064)
			(stroke
				(width 0.1524)
				(type default)
			)
			(layer "F.SilkS")
		)
		(fp_line
			(start -0.67945 0.3048)
			(end -0.67945 -0.305054)
			(stroke
				(width 0.1)
				(type default)
			)
			(layer "F.Fab")
		)
		(fp_line
			(start -0.12065 0.3048)
			(end -0.67945 0.3048)
			(stroke
				(width 0.1)
				(type default)
			)
			(layer "F.Fab")
		)
		(fp_line
			(start 0.120396 0.3048)
			(end 0.120396 0.2794)
			(stroke
				(width 0.1)
				(type default)
			)
			(layer "F.Fab")
		)
		(fp_line
			(start 0.67945 0.3048)
			(end 0.120396 0.3048)
			(stroke
				(width 0.1)
				(type default)
			)
			(layer "F.Fab")
		)
		(fp_line
			(start -0.12065 0.2794)
			(end -0.12065 0.3048)
			(stroke
				(width 0.1)
				(type default)
			)
			(layer "F.Fab")
		)
		(fp_line
			(start 0.120396 0.2794)
			(end -0.12065 0.2794)
			(stroke
				(width 0.1)
				(type default)
			)
			(layer "F.Fab")
		)
		(fp_line
			(start -0.12065 -0.2794)
			(end 0.12065 -0.2794)
			(stroke
				(width 0.1)
				(type default)
			)
			(layer "F.Fab")
		)
		(fp_line
			(start 0.12065 -0.2794)
			(end 0.12065 -0.3048)
			(stroke
				(width 0.1)
				(type default)
			)
			(layer "F.Fab")
		)
		(fp_line
			(start 0.12065 -0.3048)
			(end 0.67945 -0.3048)
			(stroke
				(width 0.1)
				(type default)
			)
			(layer "F.Fab")
		)
		(fp_line
			(start 0.67945 -0.3048)
			(end 0.67945 0.3048)
			(stroke
				(width 0.1)
				(type default)
			)
			(layer "F.Fab")
		)
		(fp_line
			(start -0.67945 -0.305054)
			(end -0.12065 -0.305054)
			(stroke
				(width 0.1)
				(type default)
			)
			(layer "F.Fab")
		)
		(fp_line
			(start -0.12065 -0.305054)
			(end -0.12065 -0.2794)
			(stroke
				(width 0.1)
				(type default)
			)
			(layer "F.Fab")
		)
		(pad "1" smd circle
			(at -0.40005 0 270)
			(size 0 0)
			(layers "F.Cu" "F.Mask" "F.Paste")
			(net "FM_SMB_2_ALERT_GPU_ISO_N")
		)
		(pad "2" smd circle
			(at 0.40005 0 270)
			(size 0 0)
			(layers "F.Cu" "F.Mask" "F.Paste")
			(net "FM_SMB_2_ALERT_GPU_ISO_R_N")
		)
	)
	(footprint ""
		(layer "F.Cu")
		(at 101.58349 -333.525368 -90)
		(property "Reference" "PC558_P1_2"
			(at 0 0 270)
			(layer "F.SilkS")
			(hide yes)
			(effects
				(font
					(size 1.27 1.27)
				)
			)
		)
		(property "Value" ""
			(at 0 0 270)
			(layer "F.Fab")
			(effects
				(font
					(size 1.27 1.27)
				)
			)
		)
		(duplicate_pad_numbers_are_jumpers no)
		(fp_line
			(start -0.7874 0.4064)
			(end -0.7874 -0.4064)
			(stroke
				(width 0.1524)
				(type default)
			)
			(layer "F.SilkS")
		)
		(fp_line
			(start 0.7874 0.4064)
			(end -0.7874 0.4064)
			(stroke
				(width 0.1524)
				(type default)
			)
			(layer "F.SilkS")
		)
		(fp_line
			(start -0.7874 -0.4064)
			(end 0.7874 -0.4064)
			(stroke
				(width 0.1524)
				(type default)
			)
			(layer "F.SilkS")
		)
		(fp_line
			(start 0.7874 -0.4064)
			(end 0.7874 0.4064)
			(stroke
				(width 0.1524)
				(type default)
			)
			(layer "F.SilkS")
		)
		(fp_line
			(start -0.67945 0.3048)
			(end -0.67945 -0.305054)
			(stroke
				(width 0.1)
				(type default)
			)
			(layer "F.Fab")
		)
		(fp_line
			(start -0.12065 0.3048)
			(end -0.67945 0.3048)
			(stroke
				(width 0.1)
				(type default)
			)
			(layer "F.Fab")
		)
		(fp_line
			(start 0.120396 0.3048)
			(end 0.120396 0.2794)
			(stroke
				(width 0.1)
				(type default)
			)
			(layer "F.Fab")
		)
		(fp_line
			(start 0.67945 0.3048)
			(end 0.120396 0.3048)
			(stroke
				(width 0.1)
				(type default)
			)
			(layer "F.Fab")
		)
		(fp_line
			(start -0.12065 0.2794)
			(end -0.12065 0.3048)
			(stroke
				(width 0.1)
				(type default)
			)
			(layer "F.Fab")
		)
		(fp_line
			(start 0.120396 0.2794)
			(end -0.12065 0.2794)
			(stroke
				(width 0.1)
				(type default)
			)
			(layer "F.Fab")
		)
		(fp_line
			(start -0.12065 -0.2794)
			(end 0.12065 -0.2794)
			(stroke
				(width 0.1)
				(type default)
			)
			(layer "F.Fab")
		)
		(fp_line
			(start 0.12065 -0.2794)
			(end 0.12065 -0.3048)
			(stroke
				(width 0.1)
				(type default)
			)
			(layer "F.Fab")
		)
		(fp_line
			(start 0.12065 -0.3048)
			(end 0.67945 -0.3048)
			(stroke
				(width 0.1)
				(type default)
			)
			(layer "F.Fab")
		)
		(fp_line
			(start 0.67945 -0.3048)
			(end 0.67945 0.3048)
			(stroke
				(width 0.1)
				(type default)
			)
			(layer "F.Fab")
		)
		(fp_line
			(start -0.67945 -0.305054)
			(end -0.12065 -0.305054)
			(stroke
				(width 0.1)
				(type default)
			)
			(layer "F.Fab")
		)
		(fp_line
			(start -0.12065 -0.305054)
			(end -0.12065 -0.2794)
			(stroke
				(width 0.1)
				(type default)
			)
			(layer "F.Fab")
		)
		(pad "1" smd circle
			(at -0.40005 0 270)
			(size 0 0)
			(layers "F.Cu" "F.Mask" "F.Paste")
			(net "PVCCIN_CPU1_PVCC")
		)
		(pad "2" smd circle
			(at 0.40005 0 270)
			(size 0 0)
			(layers "F.Cu" "F.Mask" "F.Paste")
			(net "GND")
		)
	)
	(footprint ""
		(layer "F.Cu")
		(at 424.204892 -382.361948 180)
		(property "Reference" "R2829"
			(at 0 0 180)
			(layer "F.SilkS")
			(hide yes)
			(effects
				(font
					(size 1.27 1.27)
				)
			)
		)
		(property "Value" ""
			(at 0 0 180)
			(layer "F.Fab")
			(effects
				(font
					(size 1.27 1.27)
				)
			)
		)
		(duplicate_pad_numbers_are_jumpers no)
		(fp_line
			(start 0.7874 0.4064)
			(end -0.7874 0.4064)
			(stroke
				(width 0.1524)
				(type default)
			)
			(layer "F.SilkS")
		)
		(fp_line
			(start 0.7874 -0.4064)
			(end 0.7874 0.4064)
			(stroke
				(width 0.1524)
				(type default)
			)
			(layer "F.SilkS")
		)
		(fp_line
			(start -0.7874 0.4064)
			(end -0.7874 -0.4064)
			(stroke
				(width 0.1524)
				(type default)
			)
			(layer "F.SilkS")
		)
		(fp_line
			(start -0.7874 -0.4064)
			(end 0.7874 -0.4064)
			(stroke
				(width 0.1524)
				(type default)
			)
			(layer "F.SilkS")
		)
		(fp_line
			(start 0.67945 0.3048)
			(end 0.120396 0.3048)
			(stroke
				(width 0.1)
				(type default)
			)
			(layer "F.Fab")
		)
		(fp_line
			(start 0.67945 -0.3048)
			(end 0.67945 0.3048)
			(stroke
				(width 0.1)
				(type default)
			)
			(layer "F.Fab")
		)
		(fp_line
			(start 0.12065 -0.2794)
			(end 0.12065 -0.3048)
			(stroke
				(width 0.1)
				(type default)
			)
			(layer "F.Fab")
		)
		(fp_line
			(start 0.12065 -0.3048)
			(end 0.67945 -0.3048)
			(stroke
				(width 0.1)
				(type default)
			)
			(layer "F.Fab")
		)
		(fp_line
			(start 0.120396 0.3048)
			(end 0.120396 0.2794)
			(stroke
				(width 0.1)
				(type default)
			)
			(layer "F.Fab")
		)
		(fp_line
			(start 0.120396 0.2794)
			(end -0.12065 0.2794)
			(stroke
				(width 0.1)
				(type default)
			)
			(layer "F.Fab")
		)
		(fp_line
			(start -0.12065 0.3048)
			(end -0.67945 0.3048)
			(stroke
				(width 0.1)
				(type default)
			)
			(layer "F.Fab")
		)
		(fp_line
			(start -0.12065 0.2794)
			(end -0.12065 0.3048)
			(stroke
				(width 0.1)
				(type default)
			)
			(layer "F.Fab")
		)
		(fp_line
			(start -0.12065 -0.2794)
			(end 0.12065 -0.2794)
			(stroke
				(width 0.1)
				(type default)
			)
			(layer "F.Fab")
		)
		(fp_line
			(start -0.12065 -0.305054)
			(end -0.12065 -0.2794)
			(stroke
				(width 0.1)
				(type default)
			)
			(layer "F.Fab")
		)
		(fp_line
			(start -0.67945 0.3048)
			(end -0.67945 -0.305054)
			(stroke
				(width 0.1)
				(type default)
			)
			(layer "F.Fab")
		)
		(fp_line
			(start -0.67945 -0.305054)
			(end -0.12065 -0.305054)
			(stroke
				(width 0.1)
				(type default)
			)
			(layer "F.Fab")
		)
		(pad "1" smd circle
			(at -0.40005 0 180)
			(size 0 0)
			(layers "F.Cu" "F.Mask" "F.Paste")
			(net "RST_BMC_FROM_SWB_N")
		)
		(pad "2" smd circle
			(at 0.40005 0 180)
			(size 0 0)
			(layers "F.Cu" "F.Mask" "F.Paste")
			(net "GND")
		)
	)
	(footprint ""
		(layer "F.Cu")
		(at 51.593496 -108.14177)
		(property "Reference" "R3727"
			(at 0 0 0)
			(layer "F.SilkS")
			(hide yes)
			(effects
				(font
					(size 1.27 1.27)
				)
			)
		)
		(property "Value" ""
			(at 0 0 0)
			(layer "F.Fab")
			(effects
				(font
					(size 1.27 1.27)
				)
			)
		)
		(duplicate_pad_numbers_are_jumpers no)
		(fp_line
			(start -0.7874 -0.4064)
			(end 0.7874 -0.4064)
			(stroke
				(width 0.1524)
				(type default)
			)
			(layer "F.SilkS")
		)
		(fp_line
			(start -0.7874 0.4064)
			(end -0.7874 -0.4064)
			(stroke
				(width 0.1524)
				(type default)
			)
			(layer "F.SilkS")
		)
		(fp_line
			(start 0.7874 -0.4064)
			(end 0.7874 0.4064)
			(stroke
				(width 0.1524)
				(type default)
			)
			(layer "F.SilkS")
		)
		(fp_line
			(start 0.7874 0.4064)
			(end -0.7874 0.4064)
			(stroke
				(width 0.1524)
				(type default)
			)
			(layer "F.SilkS")
		)
		(fp_line
			(start -0.67945 -0.305054)
			(end -0.12065 -0.305054)
			(stroke
				(width 0.1)
				(type default)
			)
			(layer "F.Fab")
		)
		(fp_line
			(start -0.67945 0.3048)
			(end -0.67945 -0.305054)
			(stroke
				(width 0.1)
				(type default)
			)
			(layer "F.Fab")
		)
		(fp_line
			(start -0.12065 -0.305054)
			(end -0.12065 -0.2794)
			(stroke
				(width 0.1)
				(type default)
			)
			(layer "F.Fab")
		)
		(fp_line
			(start -0.12065 -0.2794)
			(end 0.12065 -0.2794)
			(stroke
				(width 0.1)
				(type default)
			)
			(layer "F.Fab")
		)
		(fp_line
			(start -0.12065 0.2794)
			(end -0.12065 0.3048)
			(stroke
				(width 0.1)
				(type default)
			)
			(layer "F.Fab")
		)
		(fp_line
			(start -0.12065 0.3048)
			(end -0.67945 0.3048)
			(stroke
				(width 0.1)
				(type default)
			)
			(layer "F.Fab")
		)
		(fp_line
			(start 0.120396 0.2794)
			(end -0.12065 0.2794)
			(stroke
				(width 0.1)
				(type default)
			)
			(layer "F.Fab")
		)
		(fp_line
			(start 0.120396 0.3048)
			(end 0.120396 0.2794)
			(stroke
				(width 0.1)
				(type default)
			)
			(layer "F.Fab")
		)
		(fp_line
			(start 0.12065 -0.3048)
			(end 0.67945 -0.3048)
			(stroke
				(width 0.1)
				(type default)
			)
			(layer "F.Fab")
		)
		(fp_line
			(start 0.12065 -0.2794)
			(end 0.12065 -0.3048)
			(stroke
				(width 0.1)
				(type default)
			)
			(layer "F.Fab")
		)
		(fp_line
			(start 0.67945 -0.3048)
			(end 0.67945 0.3048)
			(stroke
				(width 0.1)
				(type default)
			)
			(layer "F.Fab")
		)
		(fp_line
			(start 0.67945 0.3048)
			(end 0.120396 0.3048)
			(stroke
				(width 0.1)
				(type default)
			)
			(layer "F.Fab")
		)
		(pad "1" smd circle
			(at -0.40005 0)
			(size 0 0)
			(layers "F.Cu" "F.Mask" "F.Paste")
			(net "P3V3_AUX")
		)
		(pad "2" smd circle
			(at 0.40005 0)
			(size 0 0)
			(layers "F.Cu" "F.Mask" "F.Paste")
			(net "SMB_LM75_1_3V3AUX_SCL")
		)
	)
	(footprint ""
		(layer "F.Cu")
		(at 49.496472 -436.803038)
		(property "Reference" "C1766"
			(at 0 0 0)
			(layer "F.SilkS")
			(hide yes)
			(effects
				(font
					(size 1.27 1.27)
				)
			)
		)
		(property "Value" ""
			(at 0 0 0)
			(layer "F.Fab")
			(effects
				(font
					(size 1.27 1.27)
				)
			)
		)
		(duplicate_pad_numbers_are_jumpers no)
		(fp_line
			(start -0.7874 -0.4064)
			(end 0.7874 -0.4064)
			(stroke
				(width 0.1524)
				(type default)
			)
			(layer "F.SilkS")
		)
		(fp_line
			(start -0.7874 0.4064)
			(end -0.7874 -0.4064)
			(stroke
				(width 0.1524)
				(type default)
			)
			(layer "F.SilkS")
		)
		(fp_line
			(start 0.7874 -0.4064)
			(end 0.7874 0.4064)
			(stroke
				(width 0.1524)
				(type default)
			)
			(layer "F.SilkS")
		)
		(fp_line
			(start 0.7874 0.4064)
			(end -0.7874 0.4064)
			(stroke
				(width 0.1524)
				(type default)
			)
			(layer "F.SilkS")
		)
		(fp_line
			(start -0.67945 -0.305054)
			(end -0.12065 -0.305054)
			(stroke
				(width 0.1)
				(type default)
			)
			(layer "F.Fab")
		)
		(fp_line
			(start -0.67945 0.3048)
			(end -0.67945 -0.305054)
			(stroke
				(width 0.1)
				(type default)
			)
			(layer "F.Fab")
		)
		(fp_line
			(start -0.12065 -0.305054)
			(end -0.12065 -0.2794)
			(stroke
				(width 0.1)
				(type default)
			)
			(layer "F.Fab")
		)
		(fp_line
			(start -0.12065 -0.2794)
			(end 0.12065 -0.2794)
			(stroke
				(width 0.1)
				(type default)
			)
			(layer "F.Fab")
		)
		(fp_line
			(start -0.12065 0.2794)
			(end -0.12065 0.3048)
			(stroke
				(width 0.1)
				(type default)
			)
			(layer "F.Fab")
		)
		(fp_line
			(start -0.12065 0.3048)
			(end -0.67945 0.3048)
			(stroke
				(width 0.1)
				(type default)
			)
			(layer "F.Fab")
		)
		(fp_line
			(start 0.120396 0.2794)
			(end -0.12065 0.2794)
			(stroke
				(width 0.1)
				(type default)
			)
			(layer "F.Fab")
		)
		(fp_line
			(start 0.120396 0.3048)
			(end 0.120396 0.2794)
			(stroke
				(width 0.1)
				(type default)
			)
			(layer "F.Fab")
		)
		(fp_line
			(start 0.12065 -0.3048)
			(end 0.67945 -0.3048)
			(stroke
				(width 0.1)
				(type default)
			)
			(layer "F.Fab")
		)
		(fp_line
			(start 0.12065 -0.2794)
			(end 0.12065 -0.3048)
			(stroke
				(width 0.1)
				(type default)
			)
			(layer "F.Fab")
		)
		(fp_line
			(start 0.67945 -0.3048)
			(end 0.67945 0.3048)
			(stroke
				(width 0.1)
				(type default)
			)
			(layer "F.Fab")
		)
		(fp_line
			(start 0.67945 0.3048)
			(end 0.120396 0.3048)
			(stroke
				(width 0.1)
				(type default)
			)
			(layer "F.Fab")
		)
		(pad "1" smd circle
			(at -0.40005 0)
			(size 0 0)
			(layers "F.Cu" "F.Mask" "F.Paste")
			(net "P3V3_AUX")
		)
		(pad "2" smd circle
			(at 0.40005 0)
			(size 0 0)
			(layers "F.Cu" "F.Mask" "F.Paste")
			(net "GND")
		)
	)
	(footprint ""
		(layer "F.Cu")
		(at 112.26546 -418.027358 90)
		(property "Reference" "R2659"
			(at 0 0 90)
			(layer "F.SilkS")
			(hide yes)
			(effects
				(font
					(size 1.27 1.27)
				)
			)
		)
		(property "Value" ""
			(at 0 0 90)
			(layer "F.Fab")
			(effects
				(font
					(size 1.27 1.27)
				)
			)
		)
		(duplicate_pad_numbers_are_jumpers no)
		(fp_line
			(start -0.33147 -0.4064)
			(end 0.31877 -0.4064)
			(stroke
				(width 0.1524)
				(type default)
			)
			(layer "F.SilkS")
		)
		(fp_line
			(start 0.7874 -0.01524)
			(end 0.7874 0.4064)
			(stroke
				(width 0.1524)
				(type default)
			)
			(layer "F.SilkS")
		)
		(fp_line
			(start 0.7874 0.4064)
			(end -0.7874 0.4064)
			(stroke
				(width 0.1524)
				(type default)
			)
			(layer "F.SilkS")
		)
		(fp_line
			(start -0.7874 0.4064)
			(end -0.7874 -0.0254)
			(stroke
				(width 0.1524)
				(type default)
			)
			(layer "F.SilkS")
		)
		(fp_line
			(start -0.12065 -0.305054)
			(end -0.12065 -0.2794)
			(stroke
				(width 0.1)
				(type default)
			)
			(layer "F.Fab")
		)
		(fp_line
			(start -0.67945 -0.305054)
			(end -0.12065 -0.305054)
			(stroke
				(width 0.1)
				(type default)
			)
			(layer "F.Fab")
		)
		(fp_line
			(start 0.67945 -0.3048)
			(end 0.67945 0.3048)
			(stroke
				(width 0.1)
				(type default)
			)
			(layer "F.Fab")
		)
		(fp_line
			(start 0.12065 -0.3048)
			(end 0.67945 -0.3048)
			(stroke
				(width 0.1)
				(type default)
			)
			(layer "F.Fab")
		)
		(fp_line
			(start 0.12065 -0.2794)
			(end 0.12065 -0.3048)
			(stroke
				(width 0.1)
				(type default)
			)
			(layer "F.Fab")
		)
		(fp_line
			(start -0.12065 -0.2794)
			(end 0.12065 -0.2794)
			(stroke
				(width 0.1)
				(type default)
			)
			(layer "F.Fab")
		)
		(fp_line
			(start 0.120396 0.2794)
			(end -0.12065 0.2794)
			(stroke
				(width 0.1)
				(type default)
			)
			(layer "F.Fab")
		)
		(fp_line
			(start -0.12065 0.2794)
			(end -0.12065 0.3048)
			(stroke
				(width 0.1)
				(type default)
			)
			(layer "F.Fab")
		)
		(fp_line
			(start 0.67945 0.3048)
			(end 0.120396 0.3048)
			(stroke
				(width 0.1)
				(type default)
			)
			(layer "F.Fab")
		)
		(fp_line
			(start 0.120396 0.3048)
			(end 0.120396 0.2794)
			(stroke
				(width 0.1)
				(type default)
			)
			(layer "F.Fab")
		)
		(fp_line
			(start -0.12065 0.3048)
			(end -0.67945 0.3048)
			(stroke
				(width 0.1)
				(type default)
			)
			(layer "F.Fab")
		)
		(fp_line
			(start -0.67945 0.3048)
			(end -0.67945 -0.305054)
			(stroke
				(width 0.1)
				(type default)
			)
			(layer "F.Fab")
		)
		(pad "1" smd circle
			(at -0.40005 0 90)
			(size 0 0)
			(layers "F.Cu" "F.Mask" "F.Paste")
			(net "CLK_100M_SWB_R_DP")
		)
		(pad "2" smd circle
			(at 0.40005 0 90)
			(size 0 0)
			(layers "F.Cu" "F.Mask" "F.Paste")
			(net "CLK_100M_SWB_DP")
		)
	)
	(footprint ""
		(layer "F.Cu")
		(at 403.37613 -408.517344 -90)
		(property "Reference" "C890"
			(at 0 0 270)
			(layer "F.SilkS")
			(hide yes)
			(effects
				(font
					(size 1.27 1.27)
				)
			)
		)
		(property "Value" ""
			(at 0 0 270)
			(layer "F.Fab")
			(effects
				(font
					(size 1.27 1.27)
				)
			)
		)
		(duplicate_pad_numbers_are_jumpers no)
		(fp_line
			(start -0.299974 0.150114)
			(end -0.299974 -0.150114)
			(stroke
				(width 0.1)
				(type default)
			)
			(layer "F.Fab")
		)
		(fp_line
			(start 0.299974 0.150114)
			(end -0.299974 0.150114)
			(stroke
				(width 0.1)
				(type default)
			)
			(layer "F.Fab")
		)
		(fp_line
			(start -0.299974 -0.150114)
			(end 0.299974 -0.150114)
			(stroke
				(width 0.1)
				(type default)
			)
			(layer "F.Fab")
		)
		(fp_line
			(start 0.299974 -0.150114)
			(end 0.299974 0.150114)
			(stroke
				(width 0.1)
				(type default)
			)
			(layer "F.Fab")
		)
		(pad "1" smd rect
			(at -0.2667 0 270)
			(size 0.3048 0.381)
			(layers "F.Cu" "F.Mask" "F.Paste")
			(net "P5E_CPU0_PE3_TX_C_DN<5>")
		)
		(pad "2" smd rect
			(at 0.2667 0 270)
			(size 0.3048 0.381)
			(layers "F.Cu" "F.Mask" "F.Paste")
			(net "P5E_CPU0_PE3_TX_DN<5>")
		)
	)
	(footprint ""
		(layer "F.Cu")
		(at 159.317944 -81.902554 90)
		(property "Reference" "R3125"
			(at 0 0 90)
			(layer "F.SilkS")
			(hide yes)
			(effects
				(font
					(size 1.27 1.27)
				)
			)
		)
		(property "Value" ""
			(at 0 0 90)
			(layer "F.Fab")
			(effects
				(font
					(size 1.27 1.27)
				)
			)
		)
		(duplicate_pad_numbers_are_jumpers no)
		(fp_line
			(start 0.7874 -0.4064)
			(end 0.7874 0.4064)
			(stroke
				(width 0.1524)
				(type default)
			)
			(layer "F.SilkS")
		)
		(fp_line
			(start -0.7874 -0.4064)
			(end 0.7874 -0.4064)
			(stroke
				(width 0.1524)
				(type default)
			)
			(layer "F.SilkS")
		)
		(fp_line
			(start 0.7874 0.4064)
			(end -0.7874 0.4064)
			(stroke
				(width 0.1524)
				(type default)
			)
			(layer "F.SilkS")
		)
		(fp_line
			(start -0.7874 0.4064)
			(end -0.7874 -0.4064)
			(stroke
				(width 0.1524)
				(type default)
			)
			(layer "F.SilkS")
		)
		(fp_line
			(start -0.12065 -0.305054)
			(end -0.12065 -0.2794)
			(stroke
				(width 0.1)
				(type default)
			)
			(layer "F.Fab")
		)
		(fp_line
			(start -0.67945 -0.305054)
			(end -0.12065 -0.305054)
			(stroke
				(width 0.1)
				(type default)
			)
			(layer "F.Fab")
		)
		(fp_line
			(start 0.67945 -0.3048)
			(end 0.67945 0.3048)
			(stroke
				(width 0.1)
				(type default)
			)
			(layer "F.Fab")
		)
		(fp_line
			(start 0.12065 -0.3048)
			(end 0.67945 -0.3048)
			(stroke
				(width 0.1)
				(type default)
			)
			(layer "F.Fab")
		)
		(fp_line
			(start 0.12065 -0.2794)
			(end 0.12065 -0.3048)
			(stroke
				(width 0.1)
				(type default)
			)
			(layer "F.Fab")
		)
		(fp_line
			(start -0.12065 -0.2794)
			(end 0.12065 -0.2794)
			(stroke
				(width 0.1)
				(type default)
			)
			(layer "F.Fab")
		)
		(fp_line
			(start 0.120396 0.2794)
			(end -0.12065 0.2794)
			(stroke
				(width 0.1)
				(type default)
			)
			(layer "F.Fab")
		)
		(fp_line
			(start -0.12065 0.2794)
			(end -0.12065 0.3048)
			(stroke
				(width 0.1)
				(type default)
			)
			(layer "F.Fab")
		)
		(fp_line
			(start 0.67945 0.3048)
			(end 0.120396 0.3048)
			(stroke
				(width 0.1)
				(type default)
			)
			(layer "F.Fab")
		)
		(fp_line
			(start 0.120396 0.3048)
			(end 0.120396 0.2794)
			(stroke
				(width 0.1)
				(type default)
			)
			(layer "F.Fab")
		)
		(fp_line
			(start -0.12065 0.3048)
			(end -0.67945 0.3048)
			(stroke
				(width 0.1)
				(type default)
			)
			(layer "F.Fab")
		)
		(fp_line
			(start -0.67945 0.3048)
			(end -0.67945 -0.305054)
			(stroke
				(width 0.1)
				(type default)
			)
			(layer "F.Fab")
		)
		(pad "1" smd circle
			(at -0.40005 0 90)
			(size 0 0)
			(layers "F.Cu" "F.Mask" "F.Paste")
			(net "SMB_S3M_CPU1_PIROM_3V3AUX_SCL_R")
		)
		(pad "2" smd circle
			(at 0.40005 0 90)
			(size 0 0)
			(layers "F.Cu" "F.Mask" "F.Paste")
			(net "SMB_S3M_CPU1_PIROM_3V3AUX_SCL")
		)
	)
	(footprint ""
		(layer "F.Cu")
		(at 114.73688 -104.079548 90)
		(property "Reference" "R4019"
			(at 0 0 90)
			(layer "F.SilkS")
			(hide yes)
			(effects
				(font
					(size 1.27 1.27)
				)
			)
		)
		(property "Value" ""
			(at 0 0 90)
			(layer "F.Fab")
			(effects
				(font
					(size 1.27 1.27)
				)
			)
		)
		(duplicate_pad_numbers_are_jumpers no)
		(fp_line
			(start 0.7874 -0.4064)
			(end 0.7874 0.4064)
			(stroke
				(width 0.1524)
				(type default)
			)
			(layer "F.SilkS")
		)
		(fp_line
			(start -0.7874 -0.4064)
			(end 0.7874 -0.4064)
			(stroke
				(width 0.1524)
				(type default)
			)
			(layer "F.SilkS")
		)
		(fp_line
			(start 0.7874 0.4064)
			(end -0.7874 0.4064)
			(stroke
				(width 0.1524)
				(type default)
			)
			(layer "F.SilkS")
		)
		(fp_line
			(start -0.7874 0.4064)
			(end -0.7874 -0.4064)
			(stroke
				(width 0.1524)
				(type default)
			)
			(layer "F.SilkS")
		)
		(fp_line
			(start -0.12065 -0.305054)
			(end -0.12065 -0.2794)
			(stroke
				(width 0.1)
				(type default)
			)
			(layer "F.Fab")
		)
		(fp_line
			(start -0.67945 -0.305054)
			(end -0.12065 -0.305054)
			(stroke
				(width 0.1)
				(type default)
			)
			(layer "F.Fab")
		)
		(fp_line
			(start 0.67945 -0.3048)
			(end 0.67945 0.3048)
			(stroke
				(width 0.1)
				(type default)
			)
			(layer "F.Fab")
		)
		(fp_line
			(start 0.12065 -0.3048)
			(end 0.67945 -0.3048)
			(stroke
				(width 0.1)
				(type default)
			)
			(layer "F.Fab")
		)
		(fp_line
			(start 0.12065 -0.2794)
			(end 0.12065 -0.3048)
			(stroke
				(width 0.1)
				(type default)
			)
			(layer "F.Fab")
		)
		(fp_line
			(start -0.12065 -0.2794)
			(end 0.12065 -0.2794)
			(stroke
				(width 0.1)
				(type default)
			)
			(layer "F.Fab")
		)
		(fp_line
			(start 0.120396 0.2794)
			(end -0.12065 0.2794)
			(stroke
				(width 0.1)
				(type default)
			)
			(layer "F.Fab")
		)
		(fp_line
			(start -0.12065 0.2794)
			(end -0.12065 0.3048)
			(stroke
				(width 0.1)
				(type default)
			)
			(layer "F.Fab")
		)
		(fp_line
			(start 0.67945 0.3048)
			(end 0.120396 0.3048)
			(stroke
				(width 0.1)
				(type default)
			)
			(layer "F.Fab")
		)
		(fp_line
			(start 0.120396 0.3048)
			(end 0.120396 0.2794)
			(stroke
				(width 0.1)
				(type default)
			)
			(layer "F.Fab")
		)
		(fp_line
			(start -0.12065 0.3048)
			(end -0.67945 0.3048)
			(stroke
				(width 0.1)
				(type default)
			)
			(layer "F.Fab")
		)
		(fp_line
			(start -0.67945 0.3048)
			(end -0.67945 -0.305054)
			(stroke
				(width 0.1)
				(type default)
			)
			(layer "F.Fab")
		)
		(pad "1" smd circle
			(at -0.40005 0 90)
			(size 0 0)
			(layers "F.Cu" "F.Mask" "F.Paste")
			(net "P0V62_CPU0_ERRS_VREF")
		)
		(pad "2" smd circle
			(at 0.40005 0 90)
			(size 0 0)
			(layers "F.Cu" "F.Mask" "F.Paste")
			(net "GND")
		)
	)
	(footprint ""
		(layer "F.Cu")
		(at 185.91403 -402.722334 -90)
		(property "Reference" "PU289"
			(at -8.205978 -4.056126 0)
			(unlocked yes)
			(layer "F.SilkS")
			(effects
				(font
					(size 0.7874 0.5842)
					(thickness 0.1524)
				)
			)
		)
		(property "Value" ""
			(at 0 0 270)
			(layer "F.Fab")
			(effects
				(font
					(size 1.27 1.27)
				)
			)
		)
		(duplicate_pad_numbers_are_jumpers no)
		(fp_line
			(start -2.567686 3.567684)
			(end 2.567686 3.567684)
			(stroke
				(width 0.1524)
				(type default)
			)
			(layer "F.SilkS")
		)
		(fp_line
			(start 2.567686 3.567684)
			(end 2.567686 -3.567684)
			(stroke
				(width 0.1524)
				(type default)
			)
			(layer "F.SilkS")
		)
		(fp_line
			(start -2.567686 -3.567684)
			(end -2.567686 3.567684)
			(stroke
				(width 0.1524)
				(type default)
			)
			(layer "F.SilkS")
		)
		(fp_line
			(start 2.567686 -3.567684)
			(end -2.567686 -3.567684)
			(stroke
				(width 0.1524)
				(type default)
			)
			(layer "F.SilkS")
		)
		(fp_poly
			(pts
				(xy -2.7432 -2.70002) (xy -3.7592 -2.19202) (xy -3.7592 -3.20802)
			)
			(stroke
				(width 0)
				(type default)
			)
			(fill yes)
			(layer "F.SilkS")
		)
		(fp_line
			(start -2.549906 3.549904)
			(end 2.549906 3.549904)
			(stroke
				(width 0.1)
				(type default)
			)
			(layer "F.Fab")
		)
		(fp_line
			(start 2.549906 3.549904)
			(end 2.549906 -3.549904)
			(stroke
				(width 0.1)
				(type default)
			)
			(layer "F.Fab")
		)
		(fp_line
			(start -2.549906 -3.549904)
			(end -2.549906 3.549904)
			(stroke
				(width 0.1)
				(type default)
			)
			(layer "F.Fab")
		)
		(fp_line
			(start 2.549906 -3.549904)
			(end -2.549906 -3.549904)
			(stroke
				(width 0.1)
				(type default)
			)
			(layer "F.Fab")
		)
		(fp_poly
			(pts
				(xy -3.7592 -3.20802) (xy -3.7592 -2.19202) (xy -2.7432 -2.70002)
			)
			(stroke
				(width 0)
				(type default)
			)
			(fill yes)
			(layer "F.Fab")
		)
		(pad "1" smd rect
			(at -2.237486 -2.70002)
			(size 0.2286 0.381)
			(layers "F.Cu" "F.Mask" "F.Paste")
			(net "P12V_PSU")
		)
		(pad "2" smd rect
			(at -2.237486 -2.249932)
			(size 0.2286 0.381)
			(layers "F.Cu" "F.Mask" "F.Paste")
			(net "P12V_PSU")
		)
		(pad "3" smd rect
			(at -2.237486 -1.800098)
			(size 0.2286 0.381)
			(layers "F.Cu" "F.Mask" "F.Paste")
			(net "P12V_PSU")
		)
		(pad "4" smd rect
			(at -2.237486 -1.35001)
			(size 0.2286 0.381)
			(layers "F.Cu" "F.Mask" "F.Paste")
			(net "P12V_PSU")
		)
		(pad "5" smd rect
			(at -2.237486 -0.899922)
			(size 0.2286 0.381)
			(layers "F.Cu" "F.Mask" "F.Paste")
			(net "P12V_PSU")
		)
		(pad "6" smd rect
			(at -2.237486 -0.450088)
			(size 0.2286 0.381)
			(layers "F.Cu" "F.Mask" "F.Paste")
			(net "P12V_PSU")
		)
		(pad "7" smd rect
			(at -2.237486 0)
			(size 0.2286 0.381)
			(layers "F.Cu" "F.Mask" "F.Paste")
			(net "P12V_PSU")
		)
		(pad "8" smd rect
			(at -2.237486 0.450088)
			(size 0.2286 0.381)
			(layers "F.Cu" "F.Mask" "F.Paste")
			(net "P12V_PSU")
		)
		(pad "9" smd rect
			(at -2.237486 0.899922)
			(size 0.2286 0.381)
			(layers "F.Cu" "F.Mask" "F.Paste")
			(net "HSC_VSENSE")
		)
		(pad "10" smd rect
			(at -2.237486 1.35001)
			(size 0.2286 0.381)
			(layers "F.Cu" "F.Mask" "F.Paste")
			(net "IRQ_SML1_PMBUS_ALERT")
		)
		(pad "11" smd rect
			(at -2.237486 1.800098)
			(size 0.2286 0.381)
			(layers "F.Cu" "F.Mask" "F.Paste")
			(net "SMB_SML1_PMBUS_HSC_L_SCL")
		)
		(pad "12" smd rect
			(at -2.237486 2.249932)
			(size 0.2286 0.381)
			(layers "F.Cu" "F.Mask" "F.Paste")
			(net "SMB_SML1_PMBUS_HSC_R_SDA")
		)
		(pad "13" smd rect
			(at -2.237486 2.70002)
			(size 0.2286 0.381)
			(layers "F.Cu" "F.Mask" "F.Paste")
			(net "MB0_P12V_STBY_PWRGD")
		)
		(pad "14" smd rect
			(at -1.575054 3.237484 270)
			(size 0.2286 0.381)
			(layers "F.Cu" "F.Mask" "F.Paste")
			(net "HSC_VIN_UVW_N")
		)
		(pad "15" smd rect
			(at -1.124966 3.237484 270)
			(size 0.2286 0.381)
			(layers "F.Cu" "F.Mask" "F.Paste")
			(net "HSC_VTEMP")
		)
		(pad "16" smd rect
			(at -0.674878 3.237484 270)
			(size 0.2286 0.381)
			(layers "F.Cu" "F.Mask" "F.Paste")
			(net "HSC_SS")
		)
		(pad "17" smd rect
			(at -0.225044 3.237484 270)
			(size 0.2286 0.381)
			(layers "F.Cu" "F.Mask" "F.Paste")
			(net "HSC_VDD_R")
		)
		(pad "18" smd rect
			(at 0.225044 3.237484 270)
			(size 0.2286 0.381)
			(layers "F.Cu" "F.Mask" "F.Paste")
			(net "AGND_HSC")
		)
		(pad "19" smd rect
			(at 0.674878 3.237484 270)
			(size 0.2286 0.381)
			(layers "F.Cu" "F.Mask" "F.Paste")
			(net "HSC_VDD18")
		)
		(pad "20" smd rect
			(at 1.124966 3.237484 270)
			(size 0.2286 0.381)
			(layers "F.Cu" "F.Mask" "F.Paste")
			(net "HSC_CS")
		)
		(pad "21" smd rect
			(at 1.575054 3.237484 270)
			(size 0.2286 0.381)
			(layers "F.Cu" "F.Mask" "F.Paste")
			(net "HSC_IMON")
		)
		(pad "22" smd rect
			(at 2.237486 2.70002)
			(size 0.2286 0.381)
			(layers "F.Cu" "F.Mask" "F.Paste")
			(net "HSC_OCREF")
		)
		(pad "23" smd rect
			(at 2.237486 2.249932)
			(size 0.2286 0.381)
			(layers "F.Cu" "F.Mask" "F.Paste")
			(net "HSC_ADDR")
		)
		(pad "24" smd rect
			(at 2.237486 1.800098)
			(size 0.2286 0.381)
			(layers "F.Cu" "F.Mask" "F.Paste")
			(net "HSC_VOSEN")
		)
		(pad "25" smd rect
			(at 2.237486 1.35001)
			(size 0.2286 0.381)
			(layers "F.Cu" "F.Mask" "F.Paste")
			(net "HSC_SCREF")
		)
		(pad "26" smd rect
			(at 2.237486 0.899922)
			(size 0.2286 0.381)
			(layers "F.Cu" "F.Mask" "F.Paste")
			(net "HSC_EN_R")
		)
		(pad "27" smd rect
			(at 2.237486 0.450088)
			(size 0.2286 0.381)
			(layers "F.Cu" "F.Mask" "F.Paste")
			(net "P12V_AUX")
		)
		(pad "28" smd rect
			(at 2.237486 0)
			(size 0.2286 0.381)
			(layers "F.Cu" "F.Mask" "F.Paste")
			(net "P12V_AUX")
		)
		(pad "29" smd rect
			(at 2.237486 -0.450088)
			(size 0.2286 0.381)
			(layers "F.Cu" "F.Mask" "F.Paste")
			(net "P12V_AUX")
		)
		(pad "30" smd rect
			(at 2.237486 -0.899922)
			(size 0.2286 0.381)
			(layers "F.Cu" "F.Mask" "F.Paste")
			(net "P12V_AUX")
		)
		(pad "31" smd rect
			(at 2.237486 -1.35001)
			(size 0.2286 0.381)
			(layers "F.Cu" "F.Mask" "F.Paste")
			(net "P12V_AUX")
		)
		(pad "32" smd rect
			(at 2.237486 -1.800098)
			(size 0.2286 0.381)
			(layers "F.Cu" "F.Mask" "F.Paste")
			(net "P12V_AUX")
		)
		(pad "33" smd rect
			(at 2.237486 -2.249932)
			(size 0.2286 0.381)
			(layers "F.Cu" "F.Mask" "F.Paste")
			(net "P12V_AUX")
		)
		(pad "34" smd rect
			(at 2.237486 -2.70002)
			(size 0.2286 0.381)
			(layers "F.Cu" "F.Mask" "F.Paste")
			(net "P12V_AUX")
		)
		(pad "35" smd rect
			(at 1.575054 -3.237484 270)
			(size 0.2286 0.381)
			(layers "F.Cu" "F.Mask" "F.Paste")
			(net "P12V_AUX")
		)
		(pad "36" smd rect
			(at 1.124966 -3.237484 270)
			(size 0.2286 0.381)
			(layers "F.Cu" "F.Mask" "F.Paste")
			(net "P12V_AUX")
		)
		(pad "37" smd rect
			(at 0.674878 -3.237484 270)
			(size 0.2286 0.381)
			(layers "F.Cu" "F.Mask" "F.Paste")
			(net "HSC_D_OC_R")
		)
		(pad "38" smd rect
			(at 0.225044 -3.237484 270)
			(size 0.2286 0.381)
			(layers "F.Cu" "F.Mask" "F.Paste")
			(net "HSC_ON_R")
		)
		(pad "39" smd rect
			(at -0.225044 -3.237484 270)
			(size 0.2286 0.381)
			(layers "F.Cu" "F.Mask" "F.Paste")
			(net "HSC_FAULT")
		)
		(pad "40" smd rect
			(at -0.674878 -3.237484 270)
			(size 0.2286 0.381)
			(layers "F.Cu" "F.Mask" "F.Paste")
			(net "HSC_FLT_TYPE")
		)
		(pad "41" smd rect
			(at -1.124966 -3.237484 270)
			(size 0.2286 0.381)
			(layers "F.Cu" "F.Mask" "F.Paste")
			(net "HSC_MODE")
		)
		(pad "42" smd rect
			(at -1.575054 -3.237484 270)
			(size 0.2286 0.381)
			(layers "F.Cu" "F.Mask" "F.Paste")
			(net "P12V_PSU")
		)
		(pad "43" smd rect
			(at 0 -0.999998 270)
			(size 3.4036 3.4036)
			(layers "F.Cu" "F.Mask" "F.Paste")
			(net "P12V_PSU")
		)
		(pad "44" smd rect
			(at -1.124966 1.89992 270)
			(size 1.1684 1.6002)
			(layers "F.Cu" "F.Mask" "F.Paste")
			(net "AGND_HSC")
		)
		(pad "45" smd rect
			(at 1.124966 1.89992 270)
			(size 1.1684 1.6002)
			(layers "F.Cu" "F.Mask" "F.Paste")
			(net "HSC_VDD_R")
		)
	)
	(footprint ""
		(layer "F.Cu")
		(at 382.086612 -72.75957 90)
		(property "Reference" "PR1329"
			(at 0 0 90)
			(layer "F.SilkS")
			(hide yes)
			(effects
				(font
					(size 1.27 1.27)
				)
			)
		)
		(property "Value" ""
			(at 0 0 90)
			(layer "F.Fab")
			(effects
				(font
					(size 1.27 1.27)
				)
			)
		)
		(duplicate_pad_numbers_are_jumpers no)
		(fp_line
			(start 0.7874 -0.4064)
			(end 0.7874 0.4064)
			(stroke
				(width 0.1524)
				(type default)
			)
			(layer "F.SilkS")
		)
		(fp_line
			(start -0.7874 -0.4064)
			(end 0.7874 -0.4064)
			(stroke
				(width 0.1524)
				(type default)
			)
			(layer "F.SilkS")
		)
		(fp_line
			(start 0.7874 0.4064)
			(end -0.7874 0.4064)
			(stroke
				(width 0.1524)
				(type default)
			)
			(layer "F.SilkS")
		)
		(fp_line
			(start -0.7874 0.4064)
			(end -0.7874 -0.4064)
			(stroke
				(width 0.1524)
				(type default)
			)
			(layer "F.SilkS")
		)
		(fp_line
			(start -0.12065 -0.305054)
			(end -0.12065 -0.2794)
			(stroke
				(width 0.1)
				(type default)
			)
			(layer "F.Fab")
		)
		(fp_line
			(start -0.67945 -0.305054)
			(end -0.12065 -0.305054)
			(stroke
				(width 0.1)
				(type default)
			)
			(layer "F.Fab")
		)
		(fp_line
			(start 0.67945 -0.3048)
			(end 0.67945 0.3048)
			(stroke
				(width 0.1)
				(type default)
			)
			(layer "F.Fab")
		)
		(fp_line
			(start 0.12065 -0.3048)
			(end 0.67945 -0.3048)
			(stroke
				(width 0.1)
				(type default)
			)
			(layer "F.Fab")
		)
		(fp_line
			(start 0.12065 -0.2794)
			(end 0.12065 -0.3048)
			(stroke
				(width 0.1)
				(type default)
			)
			(layer "F.Fab")
		)
		(fp_line
			(start -0.12065 -0.2794)
			(end 0.12065 -0.2794)
			(stroke
				(width 0.1)
				(type default)
			)
			(layer "F.Fab")
		)
		(fp_line
			(start 0.120396 0.2794)
			(end -0.12065 0.2794)
			(stroke
				(width 0.1)
				(type default)
			)
			(layer "F.Fab")
		)
		(fp_line
			(start -0.12065 0.2794)
			(end -0.12065 0.3048)
			(stroke
				(width 0.1)
				(type default)
			)
			(layer "F.Fab")
		)
		(fp_line
			(start 0.67945 0.3048)
			(end 0.120396 0.3048)
			(stroke
				(width 0.1)
				(type default)
			)
			(layer "F.Fab")
		)
		(fp_line
			(start 0.120396 0.3048)
			(end 0.120396 0.2794)
			(stroke
				(width 0.1)
				(type default)
			)
			(layer "F.Fab")
		)
		(fp_line
			(start -0.12065 0.3048)
			(end -0.67945 0.3048)
			(stroke
				(width 0.1)
				(type default)
			)
			(layer "F.Fab")
		)
		(fp_line
			(start -0.67945 0.3048)
			(end -0.67945 -0.305054)
			(stroke
				(width 0.1)
				(type default)
			)
			(layer "F.Fab")
		)
		(pad "1" smd circle
			(at -0.40005 0 90)
			(size 0 0)
			(layers "F.Cu" "F.Mask" "F.Paste")
			(net "PVCC1_AUX")
		)
		(pad "2" smd circle
			(at 0.40005 0 90)
			(size 0 0)
			(layers "F.Cu" "F.Mask" "F.Paste")
			(net "P1V8_PCH_AUX_VCC")
		)
	)
	(footprint ""
		(layer "F.Cu")
		(at 62.467998 -408.517344 -90)
		(property "Reference" "C701"
			(at 0 0 270)
			(layer "F.SilkS")
			(hide yes)
			(effects
				(font
					(size 1.27 1.27)
				)
			)
		)
		(property "Value" ""
			(at 0 0 270)
			(layer "F.Fab")
			(effects
				(font
					(size 1.27 1.27)
				)
			)
		)
		(duplicate_pad_numbers_are_jumpers no)
		(fp_line
			(start -0.299974 0.150114)
			(end -0.299974 -0.150114)
			(stroke
				(width 0.1)
				(type default)
			)
			(layer "F.Fab")
		)
		(fp_line
			(start 0.299974 0.150114)
			(end -0.299974 0.150114)
			(stroke
				(width 0.1)
				(type default)
			)
			(layer "F.Fab")
		)
		(fp_line
			(start -0.299974 -0.150114)
			(end 0.299974 -0.150114)
			(stroke
				(width 0.1)
				(type default)
			)
			(layer "F.Fab")
		)
		(fp_line
			(start 0.299974 -0.150114)
			(end 0.299974 0.150114)
			(stroke
				(width 0.1)
				(type default)
			)
			(layer "F.Fab")
		)
		(pad "1" smd rect
			(at -0.2667 0 270)
			(size 0.3048 0.381)
			(layers "F.Cu" "F.Mask" "F.Paste")
			(net "P5E_CPU1_PE4_TX_C_DP<4>")
		)
		(pad "2" smd rect
			(at 0.2667 0 270)
			(size 0.3048 0.381)
			(layers "F.Cu" "F.Mask" "F.Paste")
			(net "P5E_CPU1_PE4_TX_DP<4>")
		)
	)
	(footprint ""
		(layer "F.Cu")
		(at 118.83898 -412.17469 180)
		(property "Reference" "R4491"
			(at 0 0 180)
			(layer "F.SilkS")
			(hide yes)
			(effects
				(font
					(size 1.27 1.27)
				)
			)
		)
		(property "Value" ""
			(at 0 0 180)
			(layer "F.Fab")
			(effects
				(font
					(size 1.27 1.27)
				)
			)
		)
		(duplicate_pad_numbers_are_jumpers no)
		(fp_line
			(start 0.7874 0.4064)
			(end -0.7874 0.4064)
			(stroke
				(width 0.1524)
				(type default)
			)
			(layer "F.SilkS")
		)
		(fp_line
			(start 0.7874 -0.4064)
			(end 0.7874 0.4064)
			(stroke
				(width 0.1524)
				(type default)
			)
			(layer "F.SilkS")
		)
		(fp_line
			(start -0.7874 0.4064)
			(end -0.7874 -0.4064)
			(stroke
				(width 0.1524)
				(type default)
			)
			(layer "F.SilkS")
		)
		(fp_line
			(start -0.7874 -0.4064)
			(end 0.7874 -0.4064)
			(stroke
				(width 0.1524)
				(type default)
			)
			(layer "F.SilkS")
		)
		(fp_line
			(start 0.67945 0.3048)
			(end 0.120396 0.3048)
			(stroke
				(width 0.1)
				(type default)
			)
			(layer "F.Fab")
		)
		(fp_line
			(start 0.67945 -0.3048)
			(end 0.67945 0.3048)
			(stroke
				(width 0.1)
				(type default)
			)
			(layer "F.Fab")
		)
		(fp_line
			(start 0.12065 -0.2794)
			(end 0.12065 -0.3048)
			(stroke
				(width 0.1)
				(type default)
			)
			(layer "F.Fab")
		)
		(fp_line
			(start 0.12065 -0.3048)
			(end 0.67945 -0.3048)
			(stroke
				(width 0.1)
				(type default)
			)
			(layer "F.Fab")
		)
		(fp_line
			(start 0.120396 0.3048)
			(end 0.120396 0.2794)
			(stroke
				(width 0.1)
				(type default)
			)
			(layer "F.Fab")
		)
		(fp_line
			(start 0.120396 0.2794)
			(end -0.12065 0.2794)
			(stroke
				(width 0.1)
				(type default)
			)
			(layer "F.Fab")
		)
		(fp_line
			(start -0.12065 0.3048)
			(end -0.67945 0.3048)
			(stroke
				(width 0.1)
				(type default)
			)
			(layer "F.Fab")
		)
		(fp_line
			(start -0.12065 0.2794)
			(end -0.12065 0.3048)
			(stroke
				(width 0.1)
				(type default)
			)
			(layer "F.Fab")
		)
		(fp_line
			(start -0.12065 -0.2794)
			(end 0.12065 -0.2794)
			(stroke
				(width 0.1)
				(type default)
			)
			(layer "F.Fab")
		)
		(fp_line
			(start -0.12065 -0.305054)
			(end -0.12065 -0.2794)
			(stroke
				(width 0.1)
				(type default)
			)
			(layer "F.Fab")
		)
		(fp_line
			(start -0.67945 0.3048)
			(end -0.67945 -0.305054)
			(stroke
				(width 0.1)
				(type default)
			)
			(layer "F.Fab")
		)
		(fp_line
			(start -0.67945 -0.305054)
			(end -0.12065 -0.305054)
			(stroke
				(width 0.1)
				(type default)
			)
			(layer "F.Fab")
		)
		(pad "1" smd circle
			(at -0.40005 0 180)
			(size 0 0)
			(layers "F.Cu" "F.Mask" "F.Paste")
			(net "P3V3")
		)
		(pad "2" smd circle
			(at 0.40005 0 180)
			(size 0 0)
			(layers "F.Cu" "F.Mask" "F.Paste")
			(net "CLK_9ZXL045_HIBW")
		)
	)
	(footprint ""
		(layer "F.Cu")
		(at 16.333724 -76.943204)
		(property "Reference" "C1876"
			(at 0 0 0)
			(layer "F.SilkS")
			(hide yes)
			(effects
				(font
					(size 1.27 1.27)
				)
			)
		)
		(property "Value" ""
			(at 0 0 0)
			(layer "F.Fab")
			(effects
				(font
					(size 1.27 1.27)
				)
			)
		)
		(duplicate_pad_numbers_are_jumpers no)
		(fp_line
			(start -0.7874 -0.4064)
			(end 0.7874 -0.4064)
			(stroke
				(width 0.1524)
				(type default)
			)
			(layer "F.SilkS")
		)
		(fp_line
			(start -0.7874 0.4064)
			(end -0.7874 -0.4064)
			(stroke
				(width 0.1524)
				(type default)
			)
			(layer "F.SilkS")
		)
		(fp_line
			(start 0.7874 -0.4064)
			(end 0.7874 0.4064)
			(stroke
				(width 0.1524)
				(type default)
			)
			(layer "F.SilkS")
		)
		(fp_line
			(start 0.7874 0.4064)
			(end -0.7874 0.4064)
			(stroke
				(width 0.1524)
				(type default)
			)
			(layer "F.SilkS")
		)
		(fp_line
			(start -0.67945 -0.305054)
			(end -0.12065 -0.305054)
			(stroke
				(width 0.1)
				(type default)
			)
			(layer "F.Fab")
		)
		(fp_line
			(start -0.67945 0.3048)
			(end -0.67945 -0.305054)
			(stroke
				(width 0.1)
				(type default)
			)
			(layer "F.Fab")
		)
		(fp_line
			(start -0.12065 -0.305054)
			(end -0.12065 -0.2794)
			(stroke
				(width 0.1)
				(type default)
			)
			(layer "F.Fab")
		)
		(fp_line
			(start -0.12065 -0.2794)
			(end 0.12065 -0.2794)
			(stroke
				(width 0.1)
				(type default)
			)
			(layer "F.Fab")
		)
		(fp_line
			(start -0.12065 0.2794)
			(end -0.12065 0.3048)
			(stroke
				(width 0.1)
				(type default)
			)
			(layer "F.Fab")
		)
		(fp_line
			(start -0.12065 0.3048)
			(end -0.67945 0.3048)
			(stroke
				(width 0.1)
				(type default)
			)
			(layer "F.Fab")
		)
		(fp_line
			(start 0.120396 0.2794)
			(end -0.12065 0.2794)
			(stroke
				(width 0.1)
				(type default)
			)
			(layer "F.Fab")
		)
		(fp_line
			(start 0.120396 0.3048)
			(end 0.120396 0.2794)
			(stroke
				(width 0.1)
				(type default)
			)
			(layer "F.Fab")
		)
		(fp_line
			(start 0.12065 -0.3048)
			(end 0.67945 -0.3048)
			(stroke
				(width 0.1)
				(type default)
			)
			(layer "F.Fab")
		)
		(fp_line
			(start 0.12065 -0.2794)
			(end 0.12065 -0.3048)
			(stroke
				(width 0.1)
				(type default)
			)
			(layer "F.Fab")
		)
		(fp_line
			(start 0.67945 -0.3048)
			(end 0.67945 0.3048)
			(stroke
				(width 0.1)
				(type default)
			)
			(layer "F.Fab")
		)
		(fp_line
			(start 0.67945 0.3048)
			(end 0.120396 0.3048)
			(stroke
				(width 0.1)
				(type default)
			)
			(layer "F.Fab")
		)
		(pad "1" smd circle
			(at -0.40005 0)
			(size 0 0)
			(layers "F.Cu" "F.Mask" "F.Paste")
			(net "P3V3_AUX")
		)
		(pad "2" smd circle
			(at 0.40005 0)
			(size 0 0)
			(layers "F.Cu" "F.Mask" "F.Paste")
			(net "GND")
		)
	)
	(footprint ""
		(layer "F.Cu")
		(at 65.861438 -22.235922 180)
		(property "Reference" "PR3850"
			(at 0 0 180)
			(layer "F.SilkS")
			(hide yes)
			(effects
				(font
					(size 1.27 1.27)
				)
			)
		)
		(property "Value" ""
			(at 0 0 180)
			(layer "F.Fab")
			(effects
				(font
					(size 1.27 1.27)
				)
			)
		)
		(duplicate_pad_numbers_are_jumpers no)
		(fp_line
			(start 0.7874 0.4064)
			(end -0.7874 0.4064)
			(stroke
				(width 0.1524)
				(type default)
			)
			(layer "F.SilkS")
		)
		(fp_line
			(start 0.7874 -0.4064)
			(end 0.7874 0.4064)
			(stroke
				(width 0.1524)
				(type default)
			)
			(layer "F.SilkS")
		)
		(fp_line
			(start -0.7874 0.4064)
			(end -0.7874 -0.4064)
			(stroke
				(width 0.1524)
				(type default)
			)
			(layer "F.SilkS")
		)
		(fp_line
			(start -0.7874 -0.4064)
			(end 0.7874 -0.4064)
			(stroke
				(width 0.1524)
				(type default)
			)
			(layer "F.SilkS")
		)
		(fp_line
			(start 0.67945 0.3048)
			(end 0.120396 0.3048)
			(stroke
				(width 0.1)
				(type default)
			)
			(layer "F.Fab")
		)
		(fp_line
			(start 0.67945 -0.3048)
			(end 0.67945 0.3048)
			(stroke
				(width 0.1)
				(type default)
			)
			(layer "F.Fab")
		)
		(fp_line
			(start 0.12065 -0.2794)
			(end 0.12065 -0.3048)
			(stroke
				(width 0.1)
				(type default)
			)
			(layer "F.Fab")
		)
		(fp_line
			(start 0.12065 -0.3048)
			(end 0.67945 -0.3048)
			(stroke
				(width 0.1)
				(type default)
			)
			(layer "F.Fab")
		)
		(fp_line
			(start 0.120396 0.3048)
			(end 0.120396 0.2794)
			(stroke
				(width 0.1)
				(type default)
			)
			(layer "F.Fab")
		)
		(fp_line
			(start 0.120396 0.2794)
			(end -0.12065 0.2794)
			(stroke
				(width 0.1)
				(type default)
			)
			(layer "F.Fab")
		)
		(fp_line
			(start -0.12065 0.3048)
			(end -0.67945 0.3048)
			(stroke
				(width 0.1)
				(type default)
			)
			(layer "F.Fab")
		)
		(fp_line
			(start -0.12065 0.2794)
			(end -0.12065 0.3048)
			(stroke
				(width 0.1)
				(type default)
			)
			(layer "F.Fab")
		)
		(fp_line
			(start -0.12065 -0.2794)
			(end 0.12065 -0.2794)
			(stroke
				(width 0.1)
				(type default)
			)
			(layer "F.Fab")
		)
		(fp_line
			(start -0.12065 -0.305054)
			(end -0.12065 -0.2794)
			(stroke
				(width 0.1)
				(type default)
			)
			(layer "F.Fab")
		)
		(fp_line
			(start -0.67945 0.3048)
			(end -0.67945 -0.305054)
			(stroke
				(width 0.1)
				(type default)
			)
			(layer "F.Fab")
		)
		(fp_line
			(start -0.67945 -0.305054)
			(end -0.12065 -0.305054)
			(stroke
				(width 0.1)
				(type default)
			)
			(layer "F.Fab")
		)
		(pad "1" smd circle
			(at -0.40005 0 180)
			(size 0 0)
			(layers "F.Cu" "F.Mask" "F.Paste")
			(net "P12V_OCP_V3_2")
		)
		(pad "2" smd circle
			(at 0.40005 0 180)
			(size 0 0)
			(layers "F.Cu" "F.Mask" "F.Paste")
			(net "P12V_OCP_AVIN_PD_2")
		)
	)
	(footprint ""
		(layer "F.Cu")
		(at 287.494726 -367.919508)
		(property "Reference" "PR1297"
			(at 0 0 0)
			(layer "F.SilkS")
			(hide yes)
			(effects
				(font
					(size 1.27 1.27)
				)
			)
		)
		(property "Value" ""
			(at 0 0 0)
			(layer "F.Fab")
			(effects
				(font
					(size 1.27 1.27)
				)
			)
		)
		(duplicate_pad_numbers_are_jumpers no)
		(fp_line
			(start -0.7874 -0.4064)
			(end 0.7874 -0.4064)
			(stroke
				(width 0.1524)
				(type default)
			)
			(layer "F.SilkS")
		)
		(fp_line
			(start -0.7874 0.4064)
			(end -0.7874 -0.4064)
			(stroke
				(width 0.1524)
				(type default)
			)
			(layer "F.SilkS")
		)
		(fp_line
			(start 0.7874 -0.4064)
			(end 0.7874 0.4064)
			(stroke
				(width 0.1524)
				(type default)
			)
			(layer "F.SilkS")
		)
		(fp_line
			(start 0.7874 0.4064)
			(end -0.7874 0.4064)
			(stroke
				(width 0.1524)
				(type default)
			)
			(layer "F.SilkS")
		)
		(fp_line
			(start -0.67945 -0.305054)
			(end -0.12065 -0.305054)
			(stroke
				(width 0.1)
				(type default)
			)
			(layer "F.Fab")
		)
		(fp_line
			(start -0.67945 0.3048)
			(end -0.67945 -0.305054)
			(stroke
				(width 0.1)
				(type default)
			)
			(layer "F.Fab")
		)
		(fp_line
			(start -0.12065 -0.305054)
			(end -0.12065 -0.2794)
			(stroke
				(width 0.1)
				(type default)
			)
			(layer "F.Fab")
		)
		(fp_line
			(start -0.12065 -0.2794)
			(end 0.12065 -0.2794)
			(stroke
				(width 0.1)
				(type default)
			)
			(layer "F.Fab")
		)
		(fp_line
			(start -0.12065 0.2794)
			(end -0.12065 0.3048)
			(stroke
				(width 0.1)
				(type default)
			)
			(layer "F.Fab")
		)
		(fp_line
			(start -0.12065 0.3048)
			(end -0.67945 0.3048)
			(stroke
				(width 0.1)
				(type default)
			)
			(layer "F.Fab")
		)
		(fp_line
			(start 0.120396 0.2794)
			(end -0.12065 0.2794)
			(stroke
				(width 0.1)
				(type default)
			)
			(layer "F.Fab")
		)
		(fp_line
			(start 0.120396 0.3048)
			(end 0.120396 0.2794)
			(stroke
				(width 0.1)
				(type default)
			)
			(layer "F.Fab")
		)
		(fp_line
			(start 0.12065 -0.3048)
			(end 0.67945 -0.3048)
			(stroke
				(width 0.1)
				(type default)
			)
			(layer "F.Fab")
		)
		(fp_line
			(start 0.12065 -0.2794)
			(end 0.12065 -0.3048)
			(stroke
				(width 0.1)
				(type default)
			)
			(layer "F.Fab")
		)
		(fp_line
			(start 0.67945 -0.3048)
			(end 0.67945 0.3048)
			(stroke
				(width 0.1)
				(type default)
			)
			(layer "F.Fab")
		)
		(fp_line
			(start 0.67945 0.3048)
			(end 0.120396 0.3048)
			(stroke
				(width 0.1)
				(type default)
			)
			(layer "F.Fab")
		)
		(pad "1" smd circle
			(at -0.40005 0)
			(size 0 0)
			(layers "F.Cu" "F.Mask" "F.Paste")
			(net "PVCCFA_EHV_FIVRA_CPU0_LSET4")
		)
		(pad "2" smd circle
			(at 0.40005 0)
			(size 0 0)
			(layers "F.Cu" "F.Mask" "F.Paste")
			(net "GND")
		)
	)
	(footprint ""
		(layer "F.Cu")
		(at 68.212462 -38.405562 180)
		(property "Reference" "R3620"
			(at 0 0 180)
			(layer "F.SilkS")
			(hide yes)
			(effects
				(font
					(size 1.27 1.27)
				)
			)
		)
		(property "Value" ""
			(at 0 0 180)
			(layer "F.Fab")
			(effects
				(font
					(size 1.27 1.27)
				)
			)
		)
		(duplicate_pad_numbers_are_jumpers no)
		(fp_line
			(start 0.7874 0.4064)
			(end -0.7874 0.4064)
			(stroke
				(width 0.1524)
				(type default)
			)
			(layer "F.SilkS")
		)
		(fp_line
			(start 0.7874 -0.4064)
			(end 0.7874 0.4064)
			(stroke
				(width 0.1524)
				(type default)
			)
			(layer "F.SilkS")
		)
		(fp_line
			(start -0.7874 0.4064)
			(end -0.7874 -0.4064)
			(stroke
				(width 0.1524)
				(type default)
			)
			(layer "F.SilkS")
		)
		(fp_line
			(start -0.7874 -0.4064)
			(end 0.7874 -0.4064)
			(stroke
				(width 0.1524)
				(type default)
			)
			(layer "F.SilkS")
		)
		(fp_line
			(start 0.67945 0.3048)
			(end 0.120396 0.3048)
			(stroke
				(width 0.1)
				(type default)
			)
			(layer "F.Fab")
		)
		(fp_line
			(start 0.67945 -0.3048)
			(end 0.67945 0.3048)
			(stroke
				(width 0.1)
				(type default)
			)
			(layer "F.Fab")
		)
		(fp_line
			(start 0.12065 -0.2794)
			(end 0.12065 -0.3048)
			(stroke
				(width 0.1)
				(type default)
			)
			(layer "F.Fab")
		)
		(fp_line
			(start 0.12065 -0.3048)
			(end 0.67945 -0.3048)
			(stroke
				(width 0.1)
				(type default)
			)
			(layer "F.Fab")
		)
		(fp_line
			(start 0.120396 0.3048)
			(end 0.120396 0.2794)
			(stroke
				(width 0.1)
				(type default)
			)
			(layer "F.Fab")
		)
		(fp_line
			(start 0.120396 0.2794)
			(end -0.12065 0.2794)
			(stroke
				(width 0.1)
				(type default)
			)
			(layer "F.Fab")
		)
		(fp_line
			(start -0.12065 0.3048)
			(end -0.67945 0.3048)
			(stroke
				(width 0.1)
				(type default)
			)
			(layer "F.Fab")
		)
		(fp_line
			(start -0.12065 0.2794)
			(end -0.12065 0.3048)
			(stroke
				(width 0.1)
				(type default)
			)
			(layer "F.Fab")
		)
		(fp_line
			(start -0.12065 -0.2794)
			(end 0.12065 -0.2794)
			(stroke
				(width 0.1)
				(type default)
			)
			(layer "F.Fab")
		)
		(fp_line
			(start -0.12065 -0.305054)
			(end -0.12065 -0.2794)
			(stroke
				(width 0.1)
				(type default)
			)
			(layer "F.Fab")
		)
		(fp_line
			(start -0.67945 0.3048)
			(end -0.67945 -0.305054)
			(stroke
				(width 0.1)
				(type default)
			)
			(layer "F.Fab")
		)
		(fp_line
			(start -0.67945 -0.305054)
			(end -0.12065 -0.305054)
			(stroke
				(width 0.1)
				(type default)
			)
			(layer "F.Fab")
		)
		(pad "1" smd circle
			(at -0.40005 0 180)
			(size 0 0)
			(layers "F.Cu" "F.Mask" "F.Paste")
			(net "INA230_3_A0")
		)
		(pad "2" smd circle
			(at 0.40005 0 180)
			(size 0 0)
			(layers "F.Cu" "F.Mask" "F.Paste")
			(net "SMB_INA230_3_3V3AUX_SCL_R1")
		)
	)
	(footprint ""
		(layer "F.Cu")
		(at 49.610264 -363.228636 90)
		(property "Reference" "PC417"
			(at 0 0 90)
			(layer "F.SilkS")
			(hide yes)
			(effects
				(font
					(size 1.27 1.27)
				)
			)
		)
		(property "Value" ""
			(at 0 0 90)
			(layer "F.Fab")
			(effects
				(font
					(size 1.27 1.27)
				)
			)
		)
		(duplicate_pad_numbers_are_jumpers no)
		(fp_line
			(start -3.400044 1.249934)
			(end 3.400044 1.249934)
			(stroke
				(width 0.1524)
				(type default)
			)
			(layer "F.SilkS")
		)
		(fp_circle
			(center 0 1.249934)
			(end 0 4.649978)
			(stroke
				(width 0.1524)
				(type default)
			)
			(fill no)
			(layer "F.SilkS")
		)
		(fp_poly
			(pts
				(arc
					(start -3.400044 1.249934)
					(mid 0 4.649978)
					(end 3.400044 1.249934)
				)
			)
			(stroke
				(width 0)
				(type default)
			)
			(fill yes)
			(layer "F.SilkS")
		)
		(fp_circle
			(center 0 1.249934)
			(end 0 4.649978)
			(stroke
				(width 0.1)
				(type default)
			)
			(fill no)
			(layer "F.Fab")
		)
		(pad "1" thru_hole rect
			(at 0 0 90)
			(size 1.524 1.524)
			(drill 1.016)
			(layers "*.Cu" "*.Mask")
			(remove_unused_layers no)
			(net "SW_P12V_PVCCFA_EHV_FIVRA_CPU1_L")
			(clearance 0)
			(padstack
				(mode front_inner_back)
				(layer "Inner"
					(shape circle)
					(size 1.524 1.524)
					(clearance 0)
				)
				(layer "B.Cu"
					(shape rect)
					(size 1.524 1.524)
					(clearance 0)
				)
			)
		)
		(pad "2" thru_hole circle
			(at 0 2.500122 90)
			(size 1.524 1.524)
			(drill 1.016)
			(layers "*.Cu" "*.Mask")
			(remove_unused_layers no)
			(net "GND")
			(clearance 0)
		)
	)
	(footprint ""
		(layer "F.Cu")
		(at 180.528468 -53.980334 180)
		(property "Reference" "C1104"
			(at 0 0 180)
			(layer "F.SilkS")
			(hide yes)
			(effects
				(font
					(size 1.27 1.27)
				)
			)
		)
		(property "Value" ""
			(at 0 0 180)
			(layer "F.Fab")
			(effects
				(font
					(size 1.27 1.27)
				)
			)
		)
		(duplicate_pad_numbers_are_jumpers no)
		(fp_line
			(start 0.299974 0.150114)
			(end -0.299974 0.150114)
			(stroke
				(width 0.1)
				(type default)
			)
			(layer "F.Fab")
		)
		(fp_line
			(start 0.299974 -0.150114)
			(end 0.299974 0.150114)
			(stroke
				(width 0.1)
				(type default)
			)
			(layer "F.Fab")
		)
		(fp_line
			(start -0.299974 0.150114)
			(end -0.299974 -0.150114)
			(stroke
				(width 0.1)
				(type default)
			)
			(layer "F.Fab")
		)
		(fp_line
			(start -0.299974 -0.150114)
			(end 0.299974 -0.150114)
			(stroke
				(width 0.1)
				(type default)
			)
			(layer "F.Fab")
		)
		(pad "1" smd rect
			(at -0.2667 0 180)
			(size 0.3048 0.381)
			(layers "F.Cu" "F.Mask" "F.Paste")
			(net "P3E_PCH_M2_TX_DP<0>")
		)
		(pad "2" smd rect
			(at 0.2667 0 180)
			(size 0.3048 0.381)
			(layers "F.Cu" "F.Mask" "F.Paste")
			(net "P3E_PCH_M2_TX_C_DP<0>")
		)
		(zone
			(layer "In1.Cu")
			(hatch none 0.5)
			(connect_pads
				(clearance 0)
			)
			(min_thickness 0.25)
			(keepout
				(tracks not_allowed)
				(vias allowed)
				(pads allowed)
				(copperpour not_allowed)
				(footprints allowed)
			)
			(placement
				(enabled no)
				(sheetname "")
			)
			(fill
				(thermal_gap 0.5)
				(thermal_bridge_width 0.5)
				(island_removal_mode 0)
			)
			(polygon
				(pts
					(arc
						(start 180.388768 -54.221634)
						(mid 180.44265 -54.199316)
						(end 180.464968 -54.145434)
					)
					(arc
						(start 180.464968 -53.815234)
						(mid 180.44265 -53.761352)
						(end 180.388768 -53.739034)
					)
					(arc
						(start 180.134768 -53.739034)
						(mid 180.080886 -53.761352)
						(end 180.058568 -53.815234)
					)
					(arc
						(start 180.058568 -54.145434)
						(mid 180.080886 -54.199316)
						(end 180.134768 -54.221634)
					)
				)
			)
		)
		(zone
			(layer "In1.Cu")
			(hatch none 0.5)
			(connect_pads
				(clearance 0)
			)
			(min_thickness 0.25)
			(keepout
				(tracks not_allowed)
				(vias allowed)
				(pads allowed)
				(copperpour not_allowed)
				(footprints allowed)
			)
			(placement
				(enabled no)
				(sheetname "")
			)
			(fill
				(thermal_gap 0.5)
				(thermal_bridge_width 0.5)
				(island_removal_mode 0)
			)
			(polygon
				(pts
					(arc
						(start 180.922168 -54.221634)
						(mid 180.97605 -54.199316)
						(end 180.998368 -54.145434)
					)
					(arc
						(start 180.998368 -53.815234)
						(mid 180.97605 -53.761352)
						(end 180.922168 -53.739034)
					)
					(arc
						(start 180.668168 -53.739034)
						(mid 180.614286 -53.761352)
						(end 180.591968 -53.815234)
					)
					(arc
						(start 180.591968 -54.145434)
						(mid 180.614286 -54.199316)
						(end 180.668168 -54.221634)
					)
				)
			)
		)
	)
	(footprint ""
		(layer "F.Cu")
		(at 179.352448 -404.287482 180)
		(property "Reference" "PR3935"
			(at 0 0 180)
			(layer "F.SilkS")
			(hide yes)
			(effects
				(font
					(size 1.27 1.27)
				)
			)
		)
		(property "Value" ""
			(at 0 0 180)
			(layer "F.Fab")
			(effects
				(font
					(size 1.27 1.27)
				)
			)
		)
		(duplicate_pad_numbers_are_jumpers no)
		(fp_line
			(start 0.7874 0.4064)
			(end -0.7874 0.4064)
			(stroke
				(width 0.1524)
				(type default)
			)
			(layer "F.SilkS")
		)
		(fp_line
			(start 0.7874 -0.4064)
			(end 0.7874 0.4064)
			(stroke
				(width 0.1524)
				(type default)
			)
			(layer "F.SilkS")
		)
		(fp_line
			(start -0.7874 0.4064)
			(end -0.7874 -0.4064)
			(stroke
				(width 0.1524)
				(type default)
			)
			(layer "F.SilkS")
		)
		(fp_line
			(start -0.7874 -0.4064)
			(end 0.7874 -0.4064)
			(stroke
				(width 0.1524)
				(type default)
			)
			(layer "F.SilkS")
		)
		(fp_line
			(start 0.67945 0.3048)
			(end 0.120396 0.3048)
			(stroke
				(width 0.1)
				(type default)
			)
			(layer "F.Fab")
		)
		(fp_line
			(start 0.67945 -0.3048)
			(end 0.67945 0.3048)
			(stroke
				(width 0.1)
				(type default)
			)
			(layer "F.Fab")
		)
		(fp_line
			(start 0.12065 -0.2794)
			(end 0.12065 -0.3048)
			(stroke
				(width 0.1)
				(type default)
			)
			(layer "F.Fab")
		)
		(fp_line
			(start 0.12065 -0.3048)
			(end 0.67945 -0.3048)
			(stroke
				(width 0.1)
				(type default)
			)
			(layer "F.Fab")
		)
		(fp_line
			(start 0.120396 0.3048)
			(end 0.120396 0.2794)
			(stroke
				(width 0.1)
				(type default)
			)
			(layer "F.Fab")
		)
		(fp_line
			(start 0.120396 0.2794)
			(end -0.12065 0.2794)
			(stroke
				(width 0.1)
				(type default)
			)
			(layer "F.Fab")
		)
		(fp_line
			(start -0.12065 0.3048)
			(end -0.67945 0.3048)
			(stroke
				(width 0.1)
				(type default)
			)
			(layer "F.Fab")
		)
		(fp_line
			(start -0.12065 0.2794)
			(end -0.12065 0.3048)
			(stroke
				(width 0.1)
				(type default)
			)
			(layer "F.Fab")
		)
		(fp_line
			(start -0.12065 -0.2794)
			(end 0.12065 -0.2794)
			(stroke
				(width 0.1)
				(type default)
			)
			(layer "F.Fab")
		)
		(fp_line
			(start -0.12065 -0.305054)
			(end -0.12065 -0.2794)
			(stroke
				(width 0.1)
				(type default)
			)
			(layer "F.Fab")
		)
		(fp_line
			(start -0.67945 0.3048)
			(end -0.67945 -0.305054)
			(stroke
				(width 0.1)
				(type default)
			)
			(layer "F.Fab")
		)
		(fp_line
			(start -0.67945 -0.305054)
			(end -0.12065 -0.305054)
			(stroke
				(width 0.1)
				(type default)
			)
			(layer "F.Fab")
		)
		(pad "1" smd circle
			(at -0.40005 0 180)
			(size 0 0)
			(layers "F.Cu" "F.Mask" "F.Paste")
			(net "HSC_VTEMP")
		)
		(pad "2" smd circle
			(at 0.40005 0 180)
			(size 0 0)
			(layers "F.Cu" "F.Mask" "F.Paste")
			(net "AGND_HSC")
		)
	)
	(footprint ""
		(layer "F.Cu")
		(at 333.784448 -408.517344 -90)
		(property "Reference" "C921"
			(at 0 0 270)
			(layer "F.SilkS")
			(hide yes)
			(effects
				(font
					(size 1.27 1.27)
				)
			)
		)
		(property "Value" ""
			(at 0 0 270)
			(layer "F.Fab")
			(effects
				(font
					(size 1.27 1.27)
				)
			)
		)
		(duplicate_pad_numbers_are_jumpers no)
		(fp_line
			(start -0.299974 0.150114)
			(end -0.299974 -0.150114)
			(stroke
				(width 0.1)
				(type default)
			)
			(layer "F.Fab")
		)
		(fp_line
			(start 0.299974 0.150114)
			(end -0.299974 0.150114)
			(stroke
				(width 0.1)
				(type default)
			)
			(layer "F.Fab")
		)
		(fp_line
			(start -0.299974 -0.150114)
			(end 0.299974 -0.150114)
			(stroke
				(width 0.1)
				(type default)
			)
			(layer "F.Fab")
		)
		(fp_line
			(start 0.299974 -0.150114)
			(end 0.299974 0.150114)
			(stroke
				(width 0.1)
				(type default)
			)
			(layer "F.Fab")
		)
		(pad "1" smd rect
			(at -0.2667 0 270)
			(size 0.3048 0.381)
			(layers "F.Cu" "F.Mask" "F.Paste")
			(net "P5E_CPU0_PE0_TX_C_DP<6>")
		)
		(pad "2" smd rect
			(at 0.2667 0 270)
			(size 0.3048 0.381)
			(layers "F.Cu" "F.Mask" "F.Paste")
			(net "P5E_CPU0_PE0_TX_DP<6>")
		)
	)
	(footprint ""
		(layer "F.Cu")
		(at 153.022554 -408.517344 -90)
		(property "Reference" "C1537"
			(at 0 0 270)
			(layer "F.SilkS")
			(hide yes)
			(effects
				(font
					(size 1.27 1.27)
				)
			)
		)
		(property "Value" ""
			(at 0 0 270)
			(layer "F.Fab")
			(effects
				(font
					(size 1.27 1.27)
				)
			)
		)
		(duplicate_pad_numbers_are_jumpers no)
		(fp_line
			(start -0.299974 0.150114)
			(end -0.299974 -0.150114)
			(stroke
				(width 0.1)
				(type default)
			)
			(layer "F.Fab")
		)
		(fp_line
			(start 0.299974 0.150114)
			(end -0.299974 0.150114)
			(stroke
				(width 0.1)
				(type default)
			)
			(layer "F.Fab")
		)
		(fp_line
			(start -0.299974 -0.150114)
			(end 0.299974 -0.150114)
			(stroke
				(width 0.1)
				(type default)
			)
			(layer "F.Fab")
		)
		(fp_line
			(start 0.299974 -0.150114)
			(end 0.299974 0.150114)
			(stroke
				(width 0.1)
				(type default)
			)
			(layer "F.Fab")
		)
		(pad "1" smd rect
			(at -0.2667 0 270)
			(size 0.3048 0.381)
			(layers "F.Cu" "F.Mask" "F.Paste")
			(net "P5E_CPU1_PE3_TX_C_DP<5>")
		)
		(pad "2" smd rect
			(at 0.2667 0 270)
			(size 0.3048 0.381)
			(layers "F.Cu" "F.Mask" "F.Paste")
			(net "P5E_CPU1_PE3_TX_DP<5>")
		)
	)
	(footprint ""
		(layer "F.Cu")
		(at 24.069802 -406.874218)
		(property "Reference" "R3498"
			(at 0 0 0)
			(layer "F.SilkS")
			(hide yes)
			(effects
				(font
					(size 1.27 1.27)
				)
			)
		)
		(property "Value" ""
			(at 0 0 0)
			(layer "F.Fab")
			(effects
				(font
					(size 1.27 1.27)
				)
			)
		)
		(duplicate_pad_numbers_are_jumpers no)
		(fp_line
			(start -0.7874 -0.4064)
			(end 0.7874 -0.4064)
			(stroke
				(width 0.1524)
				(type default)
			)
			(layer "F.SilkS")
		)
		(fp_line
			(start -0.7874 0.4064)
			(end -0.7874 -0.4064)
			(stroke
				(width 0.1524)
				(type default)
			)
			(layer "F.SilkS")
		)
		(fp_line
			(start 0.7874 -0.4064)
			(end 0.7874 0.4064)
			(stroke
				(width 0.1524)
				(type default)
			)
			(layer "F.SilkS")
		)
		(fp_line
			(start 0.7874 0.4064)
			(end -0.7874 0.4064)
			(stroke
				(width 0.1524)
				(type default)
			)
			(layer "F.SilkS")
		)
		(fp_line
			(start -0.67945 -0.305054)
			(end -0.12065 -0.305054)
			(stroke
				(width 0.1)
				(type default)
			)
			(layer "F.Fab")
		)
		(fp_line
			(start -0.67945 0.3048)
			(end -0.67945 -0.305054)
			(stroke
				(width 0.1)
				(type default)
			)
			(layer "F.Fab")
		)
		(fp_line
			(start -0.12065 -0.305054)
			(end -0.12065 -0.2794)
			(stroke
				(width 0.1)
				(type default)
			)
			(layer "F.Fab")
		)
		(fp_line
			(start -0.12065 -0.2794)
			(end 0.12065 -0.2794)
			(stroke
				(width 0.1)
				(type default)
			)
			(layer "F.Fab")
		)
		(fp_line
			(start -0.12065 0.2794)
			(end -0.12065 0.3048)
			(stroke
				(width 0.1)
				(type default)
			)
			(layer "F.Fab")
		)
		(fp_line
			(start -0.12065 0.3048)
			(end -0.67945 0.3048)
			(stroke
				(width 0.1)
				(type default)
			)
			(layer "F.Fab")
		)
		(fp_line
			(start 0.120396 0.2794)
			(end -0.12065 0.2794)
			(stroke
				(width 0.1)
				(type default)
			)
			(layer "F.Fab")
		)
		(fp_line
			(start 0.120396 0.3048)
			(end 0.120396 0.2794)
			(stroke
				(width 0.1)
				(type default)
			)
			(layer "F.Fab")
		)
		(fp_line
			(start 0.12065 -0.3048)
			(end 0.67945 -0.3048)
			(stroke
				(width 0.1)
				(type default)
			)
			(layer "F.Fab")
		)
		(fp_line
			(start 0.12065 -0.2794)
			(end 0.12065 -0.3048)
			(stroke
				(width 0.1)
				(type default)
			)
			(layer "F.Fab")
		)
		(fp_line
			(start 0.67945 -0.3048)
			(end 0.67945 0.3048)
			(stroke
				(width 0.1)
				(type default)
			)
			(layer "F.Fab")
		)
		(fp_line
			(start 0.67945 0.3048)
			(end 0.120396 0.3048)
			(stroke
				(width 0.1)
				(type default)
			)
			(layer "F.Fab")
		)
		(pad "1" smd circle
			(at -0.40005 0)
			(size 0 0)
			(layers "F.Cu" "F.Mask" "F.Paste")
			(net "P3V3_AUX")
		)
		(pad "2" smd circle
			(at 0.40005 0)
			(size 0 0)
			(layers "F.Cu" "F.Mask" "F.Paste")
			(net "GPU_FPGA_THERM_OVERT_N")
		)
	)
	(footprint ""
		(layer "F.Cu")
		(at 301.45482 -419.02761 -90)
		(property "Reference" "C2265"
			(at 0 0 270)
			(layer "F.SilkS")
			(hide yes)
			(effects
				(font
					(size 1.27 1.27)
				)
			)
		)
		(property "Value" ""
			(at 0 0 270)
			(layer "F.Fab")
			(effects
				(font
					(size 1.27 1.27)
				)
			)
		)
		(duplicate_pad_numbers_are_jumpers no)
		(fp_line
			(start -0.7874 0.4064)
			(end -0.7874 -0.4064)
			(stroke
				(width 0.1524)
				(type default)
			)
			(layer "F.SilkS")
		)
		(fp_line
			(start 0.7874 0.4064)
			(end -0.7874 0.4064)
			(stroke
				(width 0.1524)
				(type default)
			)
			(layer "F.SilkS")
		)
		(fp_line
			(start -0.7874 -0.4064)
			(end 0.7874 -0.4064)
			(stroke
				(width 0.1524)
				(type default)
			)
			(layer "F.SilkS")
		)
		(fp_line
			(start 0.7874 -0.4064)
			(end 0.7874 0.4064)
			(stroke
				(width 0.1524)
				(type default)
			)
			(layer "F.SilkS")
		)
		(fp_line
			(start -0.67945 0.3048)
			(end -0.67945 -0.305054)
			(stroke
				(width 0.1)
				(type default)
			)
			(layer "F.Fab")
		)
		(fp_line
			(start -0.12065 0.3048)
			(end -0.67945 0.3048)
			(stroke
				(width 0.1)
				(type default)
			)
			(layer "F.Fab")
		)
		(fp_line
			(start 0.120396 0.3048)
			(end 0.120396 0.2794)
			(stroke
				(width 0.1)
				(type default)
			)
			(layer "F.Fab")
		)
		(fp_line
			(start 0.67945 0.3048)
			(end 0.120396 0.3048)
			(stroke
				(width 0.1)
				(type default)
			)
			(layer "F.Fab")
		)
		(fp_line
			(start -0.12065 0.2794)
			(end -0.12065 0.3048)
			(stroke
				(width 0.1)
				(type default)
			)
			(layer "F.Fab")
		)
		(fp_line
			(start 0.120396 0.2794)
			(end -0.12065 0.2794)
			(stroke
				(width 0.1)
				(type default)
			)
			(layer "F.Fab")
		)
		(fp_line
			(start -0.12065 -0.2794)
			(end 0.12065 -0.2794)
			(stroke
				(width 0.1)
				(type default)
			)
			(layer "F.Fab")
		)
		(fp_line
			(start 0.12065 -0.2794)
			(end 0.12065 -0.3048)
			(stroke
				(width 0.1)
				(type default)
			)
			(layer "F.Fab")
		)
		(fp_line
			(start 0.12065 -0.3048)
			(end 0.67945 -0.3048)
			(stroke
				(width 0.1)
				(type default)
			)
			(layer "F.Fab")
		)
		(fp_line
			(start 0.67945 -0.3048)
			(end 0.67945 0.3048)
			(stroke
				(width 0.1)
				(type default)
			)
			(layer "F.Fab")
		)
		(fp_line
			(start -0.67945 -0.305054)
			(end -0.12065 -0.305054)
			(stroke
				(width 0.1)
				(type default)
			)
			(layer "F.Fab")
		)
		(fp_line
			(start -0.12065 -0.305054)
			(end -0.12065 -0.2794)
			(stroke
				(width 0.1)
				(type default)
			)
			(layer "F.Fab")
		)
		(pad "1" smd circle
			(at -0.40005 0 270)
			(size 0 0)
			(layers "F.Cu" "F.Mask" "F.Paste")
			(net "PRSNT_CABLE_GPU_B3_ISO_N")
		)
		(pad "2" smd circle
			(at 0.40005 0 270)
			(size 0 0)
			(layers "F.Cu" "F.Mask" "F.Paste")
			(net "GND")
		)
	)
	(footprint ""
		(layer "F.Cu")
		(at 304.53965 -61.130688 180)
		(property "Reference" "R2252"
			(at 0 0 180)
			(layer "F.SilkS")
			(hide yes)
			(effects
				(font
					(size 1.27 1.27)
				)
			)
		)
		(property "Value" ""
			(at 0 0 180)
			(layer "F.Fab")
			(effects
				(font
					(size 1.27 1.27)
				)
			)
		)
		(duplicate_pad_numbers_are_jumpers no)
		(fp_line
			(start 0.7874 0.4064)
			(end -0.7874 0.4064)
			(stroke
				(width 0.1524)
				(type default)
			)
			(layer "F.SilkS")
		)
		(fp_line
			(start 0.7874 -0.4064)
			(end 0.7874 0.4064)
			(stroke
				(width 0.1524)
				(type default)
			)
			(layer "F.SilkS")
		)
		(fp_line
			(start -0.7874 0.4064)
			(end -0.7874 -0.4064)
			(stroke
				(width 0.1524)
				(type default)
			)
			(layer "F.SilkS")
		)
		(fp_line
			(start -0.7874 -0.4064)
			(end 0.7874 -0.4064)
			(stroke
				(width 0.1524)
				(type default)
			)
			(layer "F.SilkS")
		)
		(fp_line
			(start 0.67945 0.3048)
			(end 0.120396 0.3048)
			(stroke
				(width 0.1)
				(type default)
			)
			(layer "F.Fab")
		)
		(fp_line
			(start 0.67945 -0.3048)
			(end 0.67945 0.3048)
			(stroke
				(width 0.1)
				(type default)
			)
			(layer "F.Fab")
		)
		(fp_line
			(start 0.12065 -0.2794)
			(end 0.12065 -0.3048)
			(stroke
				(width 0.1)
				(type default)
			)
			(layer "F.Fab")
		)
		(fp_line
			(start 0.12065 -0.3048)
			(end 0.67945 -0.3048)
			(stroke
				(width 0.1)
				(type default)
			)
			(layer "F.Fab")
		)
		(fp_line
			(start 0.120396 0.3048)
			(end 0.120396 0.2794)
			(stroke
				(width 0.1)
				(type default)
			)
			(layer "F.Fab")
		)
		(fp_line
			(start 0.120396 0.2794)
			(end -0.12065 0.2794)
			(stroke
				(width 0.1)
				(type default)
			)
			(layer "F.Fab")
		)
		(fp_line
			(start -0.12065 0.3048)
			(end -0.67945 0.3048)
			(stroke
				(width 0.1)
				(type default)
			)
			(layer "F.Fab")
		)
		(fp_line
			(start -0.12065 0.2794)
			(end -0.12065 0.3048)
			(stroke
				(width 0.1)
				(type default)
			)
			(layer "F.Fab")
		)
		(fp_line
			(start -0.12065 -0.2794)
			(end 0.12065 -0.2794)
			(stroke
				(width 0.1)
				(type default)
			)
			(layer "F.Fab")
		)
		(fp_line
			(start -0.12065 -0.305054)
			(end -0.12065 -0.2794)
			(stroke
				(width 0.1)
				(type default)
			)
			(layer "F.Fab")
		)
		(fp_line
			(start -0.67945 0.3048)
			(end -0.67945 -0.305054)
			(stroke
				(width 0.1)
				(type default)
			)
			(layer "F.Fab")
		)
		(fp_line
			(start -0.67945 -0.305054)
			(end -0.12065 -0.305054)
			(stroke
				(width 0.1)
				(type default)
			)
			(layer "F.Fab")
		)
		(pad "1" smd circle
			(at -0.40005 0 180)
			(size 0 0)
			(layers "F.Cu" "F.Mask" "F.Paste")
			(net "PECI_MUX_SEL_R")
		)
		(pad "2" smd circle
			(at 0.40005 0 180)
			(size 0 0)
			(layers "F.Cu" "F.Mask" "F.Paste")
			(net "GND")
		)
	)
	(footprint ""
		(layer "F.Cu")
		(at 31.29788 -432.907948)
		(property "Reference" "R3468"
			(at 0 0 0)
			(layer "F.SilkS")
			(hide yes)
			(effects
				(font
					(size 1.27 1.27)
				)
			)
		)
		(property "Value" ""
			(at 0 0 0)
			(layer "F.Fab")
			(effects
				(font
					(size 1.27 1.27)
				)
			)
		)
		(duplicate_pad_numbers_are_jumpers no)
		(fp_line
			(start -0.7874 -0.4064)
			(end 0.7874 -0.4064)
			(stroke
				(width 0.1524)
				(type default)
			)
			(layer "F.SilkS")
		)
		(fp_line
			(start -0.7874 0.4064)
			(end -0.7874 -0.4064)
			(stroke
				(width 0.1524)
				(type default)
			)
			(layer "F.SilkS")
		)
		(fp_line
			(start 0.7874 -0.4064)
			(end 0.7874 0.4064)
			(stroke
				(width 0.1524)
				(type default)
			)
			(layer "F.SilkS")
		)
		(fp_line
			(start 0.7874 0.4064)
			(end -0.7874 0.4064)
			(stroke
				(width 0.1524)
				(type default)
			)
			(layer "F.SilkS")
		)
		(fp_line
			(start -0.67945 -0.305054)
			(end -0.12065 -0.305054)
			(stroke
				(width 0.1)
				(type default)
			)
			(layer "F.Fab")
		)
		(fp_line
			(start -0.67945 0.3048)
			(end -0.67945 -0.305054)
			(stroke
				(width 0.1)
				(type default)
			)
			(layer "F.Fab")
		)
		(fp_line
			(start -0.12065 -0.305054)
			(end -0.12065 -0.2794)
			(stroke
				(width 0.1)
				(type default)
			)
			(layer "F.Fab")
		)
		(fp_line
			(start -0.12065 -0.2794)
			(end 0.12065 -0.2794)
			(stroke
				(width 0.1)
				(type default)
			)
			(layer "F.Fab")
		)
		(fp_line
			(start -0.12065 0.2794)
			(end -0.12065 0.3048)
			(stroke
				(width 0.1)
				(type default)
			)
			(layer "F.Fab")
		)
		(fp_line
			(start -0.12065 0.3048)
			(end -0.67945 0.3048)
			(stroke
				(width 0.1)
				(type default)
			)
			(layer "F.Fab")
		)
		(fp_line
			(start 0.120396 0.2794)
			(end -0.12065 0.2794)
			(stroke
				(width 0.1)
				(type default)
			)
			(layer "F.Fab")
		)
		(fp_line
			(start 0.120396 0.3048)
			(end 0.120396 0.2794)
			(stroke
				(width 0.1)
				(type default)
			)
			(layer "F.Fab")
		)
		(fp_line
			(start 0.12065 -0.3048)
			(end 0.67945 -0.3048)
			(stroke
				(width 0.1)
				(type default)
			)
			(layer "F.Fab")
		)
		(fp_line
			(start 0.12065 -0.2794)
			(end 0.12065 -0.3048)
			(stroke
				(width 0.1)
				(type default)
			)
			(layer "F.Fab")
		)
		(fp_line
			(start 0.67945 -0.3048)
			(end 0.67945 0.3048)
			(stroke
				(width 0.1)
				(type default)
			)
			(layer "F.Fab")
		)
		(fp_line
			(start 0.67945 0.3048)
			(end 0.120396 0.3048)
			(stroke
				(width 0.1)
				(type default)
			)
			(layer "F.Fab")
		)
		(pad "1" smd circle
			(at -0.40005 0)
			(size 0 0)
			(layers "F.Cu" "F.Mask" "F.Paste")
			(net "RST_PERST_2_SWB_BUF_R_N")
		)
		(pad "2" smd circle
			(at 0.40005 0)
			(size 0 0)
			(layers "F.Cu" "F.Mask" "F.Paste")
			(net "RST_PERST_2_SWB_BUF_N")
		)
	)
	(footprint ""
		(layer "F.Cu")
		(at 197.876668 -76.016866)
		(property "Reference" "R1350"
			(at 0 0 0)
			(layer "F.SilkS")
			(hide yes)
			(effects
				(font
					(size 1.27 1.27)
				)
			)
		)
		(property "Value" ""
			(at 0 0 0)
			(layer "F.Fab")
			(effects
				(font
					(size 1.27 1.27)
				)
			)
		)
		(duplicate_pad_numbers_are_jumpers no)
		(fp_line
			(start -0.7874 -0.4064)
			(end 0.7874 -0.4064)
			(stroke
				(width 0.1524)
				(type default)
			)
			(layer "F.SilkS")
		)
		(fp_line
			(start -0.7874 0.4064)
			(end -0.7874 -0.4064)
			(stroke
				(width 0.1524)
				(type default)
			)
			(layer "F.SilkS")
		)
		(fp_line
			(start 0.7874 -0.4064)
			(end 0.7874 0.4064)
			(stroke
				(width 0.1524)
				(type default)
			)
			(layer "F.SilkS")
		)
		(fp_line
			(start 0.7874 0.4064)
			(end -0.7874 0.4064)
			(stroke
				(width 0.1524)
				(type default)
			)
			(layer "F.SilkS")
		)
		(fp_line
			(start -0.67945 -0.305054)
			(end -0.12065 -0.305054)
			(stroke
				(width 0.1)
				(type default)
			)
			(layer "F.Fab")
		)
		(fp_line
			(start -0.67945 0.3048)
			(end -0.67945 -0.305054)
			(stroke
				(width 0.1)
				(type default)
			)
			(layer "F.Fab")
		)
		(fp_line
			(start -0.12065 -0.305054)
			(end -0.12065 -0.2794)
			(stroke
				(width 0.1)
				(type default)
			)
			(layer "F.Fab")
		)
		(fp_line
			(start -0.12065 -0.2794)
			(end 0.12065 -0.2794)
			(stroke
				(width 0.1)
				(type default)
			)
			(layer "F.Fab")
		)
		(fp_line
			(start -0.12065 0.2794)
			(end -0.12065 0.3048)
			(stroke
				(width 0.1)
				(type default)
			)
			(layer "F.Fab")
		)
		(fp_line
			(start -0.12065 0.3048)
			(end -0.67945 0.3048)
			(stroke
				(width 0.1)
				(type default)
			)
			(layer "F.Fab")
		)
		(fp_line
			(start 0.120396 0.2794)
			(end -0.12065 0.2794)
			(stroke
				(width 0.1)
				(type default)
			)
			(layer "F.Fab")
		)
		(fp_line
			(start 0.120396 0.3048)
			(end 0.120396 0.2794)
			(stroke
				(width 0.1)
				(type default)
			)
			(layer "F.Fab")
		)
		(fp_line
			(start 0.12065 -0.3048)
			(end 0.67945 -0.3048)
			(stroke
				(width 0.1)
				(type default)
			)
			(layer "F.Fab")
		)
		(fp_line
			(start 0.12065 -0.2794)
			(end 0.12065 -0.3048)
			(stroke
				(width 0.1)
				(type default)
			)
			(layer "F.Fab")
		)
		(fp_line
			(start 0.67945 -0.3048)
			(end 0.67945 0.3048)
			(stroke
				(width 0.1)
				(type default)
			)
			(layer "F.Fab")
		)
		(fp_line
			(start 0.67945 0.3048)
			(end 0.120396 0.3048)
			(stroke
				(width 0.1)
				(type default)
			)
			(layer "F.Fab")
		)
		(pad "1" smd circle
			(at -0.40005 0)
			(size 0 0)
			(layers "F.Cu" "F.Mask" "F.Paste")
			(net "RMII_OCP_BMC_CRSDV")
		)
		(pad "2" smd circle
			(at 0.40005 0)
			(size 0 0)
			(layers "F.Cu" "F.Mask" "F.Paste")
			(net "GND")
		)
	)
	(footprint ""
		(layer "F.Cu")
		(at 366.637824 -354.652326 180)
		(property "Reference" "R2408"
			(at 0 0 180)
			(layer "F.SilkS")
			(hide yes)
			(effects
				(font
					(size 1.27 1.27)
				)
			)
		)
		(property "Value" ""
			(at 0 0 180)
			(layer "F.Fab")
			(effects
				(font
					(size 1.27 1.27)
				)
			)
		)
		(duplicate_pad_numbers_are_jumpers no)
		(fp_line
			(start 0.7874 0.4064)
			(end -0.7874 0.4064)
			(stroke
				(width 0.1524)
				(type default)
			)
			(layer "F.SilkS")
		)
		(fp_line
			(start 0.7874 -0.4064)
			(end 0.7874 0.4064)
			(stroke
				(width 0.1524)
				(type default)
			)
			(layer "F.SilkS")
		)
		(fp_line
			(start -0.7874 0.4064)
			(end -0.7874 -0.4064)
			(stroke
				(width 0.1524)
				(type default)
			)
			(layer "F.SilkS")
		)
		(fp_line
			(start -0.7874 -0.4064)
			(end 0.7874 -0.4064)
			(stroke
				(width 0.1524)
				(type default)
			)
			(layer "F.SilkS")
		)
		(fp_line
			(start 0.67945 0.3048)
			(end 0.120396 0.3048)
			(stroke
				(width 0.1)
				(type default)
			)
			(layer "F.Fab")
		)
		(fp_line
			(start 0.67945 -0.3048)
			(end 0.67945 0.3048)
			(stroke
				(width 0.1)
				(type default)
			)
			(layer "F.Fab")
		)
		(fp_line
			(start 0.12065 -0.2794)
			(end 0.12065 -0.3048)
			(stroke
				(width 0.1)
				(type default)
			)
			(layer "F.Fab")
		)
		(fp_line
			(start 0.12065 -0.3048)
			(end 0.67945 -0.3048)
			(stroke
				(width 0.1)
				(type default)
			)
			(layer "F.Fab")
		)
		(fp_line
			(start 0.120396 0.3048)
			(end 0.120396 0.2794)
			(stroke
				(width 0.1)
				(type default)
			)
			(layer "F.Fab")
		)
		(fp_line
			(start 0.120396 0.2794)
			(end -0.12065 0.2794)
			(stroke
				(width 0.1)
				(type default)
			)
			(layer "F.Fab")
		)
		(fp_line
			(start -0.12065 0.3048)
			(end -0.67945 0.3048)
			(stroke
				(width 0.1)
				(type default)
			)
			(layer "F.Fab")
		)
		(fp_line
			(start -0.12065 0.2794)
			(end -0.12065 0.3048)
			(stroke
				(width 0.1)
				(type default)
			)
			(layer "F.Fab")
		)
		(fp_line
			(start -0.12065 -0.2794)
			(end 0.12065 -0.2794)
			(stroke
				(width 0.1)
				(type default)
			)
			(layer "F.Fab")
		)
		(fp_line
			(start -0.12065 -0.305054)
			(end -0.12065 -0.2794)
			(stroke
				(width 0.1)
				(type default)
			)
			(layer "F.Fab")
		)
		(fp_line
			(start -0.67945 0.3048)
			(end -0.67945 -0.305054)
			(stroke
				(width 0.1)
				(type default)
			)
			(layer "F.Fab")
		)
		(fp_line
			(start -0.67945 -0.305054)
			(end -0.12065 -0.305054)
			(stroke
				(width 0.1)
				(type default)
			)
			(layer "F.Fab")
		)
		(pad "1" smd circle
			(at -0.40005 0 180)
			(size 0 0)
			(layers "F.Cu" "F.Mask" "F.Paste")
			(net "PWRGD_PVPP_HBM_CPU0_R")
		)
		(pad "2" smd circle
			(at 0.40005 0 180)
			(size 0 0)
			(layers "F.Cu" "F.Mask" "F.Paste")
			(net "PWRGD_PVPP_HBM_CPU0")
		)
	)
	(footprint ""
		(layer "F.Cu")
		(at 355.8286 -403.9108)
		(property "Reference" "R4730"
			(at 0 0 0)
			(layer "F.SilkS")
			(hide yes)
			(effects
				(font
					(size 1.27 1.27)
				)
			)
		)
		(property "Value" ""
			(at 0 0 0)
			(layer "F.Fab")
			(effects
				(font
					(size 1.27 1.27)
				)
			)
		)
		(duplicate_pad_numbers_are_jumpers no)
		(fp_line
			(start -0.7874 -0.4064)
			(end 0.7874 -0.4064)
			(stroke
				(width 0.1524)
				(type default)
			)
			(layer "F.SilkS")
		)
		(fp_line
			(start -0.7874 0.4064)
			(end -0.7874 -0.4064)
			(stroke
				(width 0.1524)
				(type default)
			)
			(layer "F.SilkS")
		)
		(fp_line
			(start 0.7874 -0.4064)
			(end 0.7874 0.4064)
			(stroke
				(width 0.1524)
				(type default)
			)
			(layer "F.SilkS")
		)
		(fp_line
			(start 0.7874 0.4064)
			(end -0.7874 0.4064)
			(stroke
				(width 0.1524)
				(type default)
			)
			(layer "F.SilkS")
		)
		(fp_line
			(start -0.67945 -0.305054)
			(end -0.12065 -0.305054)
			(stroke
				(width 0.1)
				(type default)
			)
			(layer "F.Fab")
		)
		(fp_line
			(start -0.67945 0.3048)
			(end -0.67945 -0.305054)
			(stroke
				(width 0.1)
				(type default)
			)
			(layer "F.Fab")
		)
		(fp_line
			(start -0.12065 -0.305054)
			(end -0.12065 -0.2794)
			(stroke
				(width 0.1)
				(type default)
			)
			(layer "F.Fab")
		)
		(fp_line
			(start -0.12065 -0.2794)
			(end 0.12065 -0.2794)
			(stroke
				(width 0.1)
				(type default)
			)
			(layer "F.Fab")
		)
		(fp_line
			(start -0.12065 0.2794)
			(end -0.12065 0.3048)
			(stroke
				(width 0.1)
				(type default)
			)
			(layer "F.Fab")
		)
		(fp_line
			(start -0.12065 0.3048)
			(end -0.67945 0.3048)
			(stroke
				(width 0.1)
				(type default)
			)
			(layer "F.Fab")
		)
		(fp_line
			(start 0.120396 0.2794)
			(end -0.12065 0.2794)
			(stroke
				(width 0.1)
				(type default)
			)
			(layer "F.Fab")
		)
		(fp_line
			(start 0.120396 0.3048)
			(end 0.120396 0.2794)
			(stroke
				(width 0.1)
				(type default)
			)
			(layer "F.Fab")
		)
		(fp_line
			(start 0.12065 -0.3048)
			(end 0.67945 -0.3048)
			(stroke
				(width 0.1)
				(type default)
			)
			(layer "F.Fab")
		)
		(fp_line
			(start 0.12065 -0.2794)
			(end 0.12065 -0.3048)
			(stroke
				(width 0.1)
				(type default)
			)
			(layer "F.Fab")
		)
		(fp_line
			(start 0.67945 -0.3048)
			(end 0.67945 0.3048)
			(stroke
				(width 0.1)
				(type default)
			)
			(layer "F.Fab")
		)
		(fp_line
			(start 0.67945 0.3048)
			(end 0.120396 0.3048)
			(stroke
				(width 0.1)
				(type default)
			)
			(layer "F.Fab")
		)
		(pad "1" smd circle
			(at -0.40005 0)
			(size 0 0)
			(layers "F.Cu" "F.Mask" "F.Paste")
			(net "P3V3_AUX")
		)
		(pad "2" smd circle
			(at 0.40005 0)
			(size 0 0)
			(layers "F.Cu" "F.Mask" "F.Paste")
			(net "PRSNT_CABLE_SWB_B2_N")
		)
	)
	(footprint ""
		(layer "F.Cu")
		(at 134.225538 -342.726264 -90)
		(property "Reference" "PC481_P1_8"
			(at 0 0 270)
			(layer "F.SilkS")
			(hide yes)
			(effects
				(font
					(size 1.27 1.27)
				)
			)
		)
		(property "Value" ""
			(at 0 0 270)
			(layer "F.Fab")
			(effects
				(font
					(size 1.27 1.27)
				)
			)
		)
		(duplicate_pad_numbers_are_jumpers no)
		(fp_line
			(start -0.7874 0.4064)
			(end -0.7874 -0.4064)
			(stroke
				(width 0.1524)
				(type default)
			)
			(layer "F.SilkS")
		)
		(fp_line
			(start 0.7874 0.4064)
			(end -0.7874 0.4064)
			(stroke
				(width 0.1524)
				(type default)
			)
			(layer "F.SilkS")
		)
		(fp_line
			(start -0.7874 -0.4064)
			(end 0.7874 -0.4064)
			(stroke
				(width 0.1524)
				(type default)
			)
			(layer "F.SilkS")
		)
		(fp_line
			(start 0.7874 -0.4064)
			(end 0.7874 0.4064)
			(stroke
				(width 0.1524)
				(type default)
			)
			(layer "F.SilkS")
		)
		(fp_line
			(start -0.67945 0.3048)
			(end -0.67945 -0.305054)
			(stroke
				(width 0.1)
				(type default)
			)
			(layer "F.Fab")
		)
		(fp_line
			(start -0.12065 0.3048)
			(end -0.67945 0.3048)
			(stroke
				(width 0.1)
				(type default)
			)
			(layer "F.Fab")
		)
		(fp_line
			(start 0.120396 0.3048)
			(end 0.120396 0.2794)
			(stroke
				(width 0.1)
				(type default)
			)
			(layer "F.Fab")
		)
		(fp_line
			(start 0.67945 0.3048)
			(end 0.120396 0.3048)
			(stroke
				(width 0.1)
				(type default)
			)
			(layer "F.Fab")
		)
		(fp_line
			(start -0.12065 0.2794)
			(end -0.12065 0.3048)
			(stroke
				(width 0.1)
				(type default)
			)
			(layer "F.Fab")
		)
		(fp_line
			(start 0.120396 0.2794)
			(end -0.12065 0.2794)
			(stroke
				(width 0.1)
				(type default)
			)
			(layer "F.Fab")
		)
		(fp_line
			(start -0.12065 -0.2794)
			(end 0.12065 -0.2794)
			(stroke
				(width 0.1)
				(type default)
			)
			(layer "F.Fab")
		)
		(fp_line
			(start 0.12065 -0.2794)
			(end 0.12065 -0.3048)
			(stroke
				(width 0.1)
				(type default)
			)
			(layer "F.Fab")
		)
		(fp_line
			(start 0.12065 -0.3048)
			(end 0.67945 -0.3048)
			(stroke
				(width 0.1)
				(type default)
			)
			(layer "F.Fab")
		)
		(fp_line
			(start 0.67945 -0.3048)
			(end 0.67945 0.3048)
			(stroke
				(width 0.1)
				(type default)
			)
			(layer "F.Fab")
		)
		(fp_line
			(start -0.67945 -0.305054)
			(end -0.12065 -0.305054)
			(stroke
				(width 0.1)
				(type default)
			)
			(layer "F.Fab")
		)
		(fp_line
			(start -0.12065 -0.305054)
			(end -0.12065 -0.2794)
			(stroke
				(width 0.1)
				(type default)
			)
			(layer "F.Fab")
		)
		(pad "1" smd circle
			(at -0.40005 0 270)
			(size 0 0)
			(layers "F.Cu" "F.Mask" "F.Paste")
			(net "PVCCIN_CPU1_PVCC")
		)
		(pad "2" smd circle
			(at 0.40005 0 270)
			(size 0 0)
			(layers "F.Cu" "F.Mask" "F.Paste")
			(net "GND")
		)
	)
	(footprint ""
		(layer "F.Cu")
		(at 75.416918 -18.164302)
		(property "Reference" "PR3805"
			(at 0 0 0)
			(layer "F.SilkS")
			(hide yes)
			(effects
				(font
					(size 1.27 1.27)
				)
			)
		)
		(property "Value" ""
			(at 0 0 0)
			(layer "F.Fab")
			(effects
				(font
					(size 1.27 1.27)
				)
			)
		)
		(duplicate_pad_numbers_are_jumpers no)
		(fp_line
			(start -0.7874 -0.4064)
			(end 0.7874 -0.4064)
			(stroke
				(width 0.1524)
				(type default)
			)
			(layer "F.SilkS")
		)
		(fp_line
			(start -0.7874 0.4064)
			(end -0.7874 -0.4064)
			(stroke
				(width 0.1524)
				(type default)
			)
			(layer "F.SilkS")
		)
		(fp_line
			(start 0.7874 -0.4064)
			(end 0.7874 0.4064)
			(stroke
				(width 0.1524)
				(type default)
			)
			(layer "F.SilkS")
		)
		(fp_line
			(start 0.7874 0.4064)
			(end -0.7874 0.4064)
			(stroke
				(width 0.1524)
				(type default)
			)
			(layer "F.SilkS")
		)
		(fp_line
			(start -0.67945 -0.305054)
			(end -0.12065 -0.305054)
			(stroke
				(width 0.1)
				(type default)
			)
			(layer "F.Fab")
		)
		(fp_line
			(start -0.67945 0.3048)
			(end -0.67945 -0.305054)
			(stroke
				(width 0.1)
				(type default)
			)
			(layer "F.Fab")
		)
		(fp_line
			(start -0.12065 -0.305054)
			(end -0.12065 -0.2794)
			(stroke
				(width 0.1)
				(type default)
			)
			(layer "F.Fab")
		)
		(fp_line
			(start -0.12065 -0.2794)
			(end 0.12065 -0.2794)
			(stroke
				(width 0.1)
				(type default)
			)
			(layer "F.Fab")
		)
		(fp_line
			(start -0.12065 0.2794)
			(end -0.12065 0.3048)
			(stroke
				(width 0.1)
				(type default)
			)
			(layer "F.Fab")
		)
		(fp_line
			(start -0.12065 0.3048)
			(end -0.67945 0.3048)
			(stroke
				(width 0.1)
				(type default)
			)
			(layer "F.Fab")
		)
		(fp_line
			(start 0.120396 0.2794)
			(end -0.12065 0.2794)
			(stroke
				(width 0.1)
				(type default)
			)
			(layer "F.Fab")
		)
		(fp_line
			(start 0.120396 0.3048)
			(end 0.120396 0.2794)
			(stroke
				(width 0.1)
				(type default)
			)
			(layer "F.Fab")
		)
		(fp_line
			(start 0.12065 -0.3048)
			(end 0.67945 -0.3048)
			(stroke
				(width 0.1)
				(type default)
			)
			(layer "F.Fab")
		)
		(fp_line
			(start 0.12065 -0.2794)
			(end 0.12065 -0.3048)
			(stroke
				(width 0.1)
				(type default)
			)
			(layer "F.Fab")
		)
		(fp_line
			(start 0.67945 -0.3048)
			(end 0.67945 0.3048)
			(stroke
				(width 0.1)
				(type default)
			)
			(layer "F.Fab")
		)
		(fp_line
			(start 0.67945 0.3048)
			(end 0.120396 0.3048)
			(stroke
				(width 0.1)
				(type default)
			)
			(layer "F.Fab")
		)
		(pad "1" smd circle
			(at -0.40005 0)
			(size 0 0)
			(layers "F.Cu" "F.Mask" "F.Paste")
			(net "P12V_AUX")
		)
		(pad "2" smd circle
			(at 0.40005 0)
			(size 0 0)
			(layers "F.Cu" "F.Mask" "F.Paste")
			(net "P12V_OCP_UV_2")
		)
	)
	(footprint ""
		(layer "F.Cu")
		(at 29.22524 -137.978388 90)
		(property "Reference" "PR4245"
			(at 0 0 90)
			(layer "F.SilkS")
			(hide yes)
			(effects
				(font
					(size 1.27 1.27)
				)
			)
		)
		(property "Value" ""
			(at 0 0 90)
			(layer "F.Fab")
			(effects
				(font
					(size 1.27 1.27)
				)
			)
		)
		(duplicate_pad_numbers_are_jumpers no)
		(fp_line
			(start 0.7874 -0.4064)
			(end 0.7874 0.4064)
			(stroke
				(width 0.1524)
				(type default)
			)
			(layer "F.SilkS")
		)
		(fp_line
			(start -0.7874 -0.4064)
			(end 0.7874 -0.4064)
			(stroke
				(width 0.1524)
				(type default)
			)
			(layer "F.SilkS")
		)
		(fp_line
			(start 0.7874 0.4064)
			(end -0.7874 0.4064)
			(stroke
				(width 0.1524)
				(type default)
			)
			(layer "F.SilkS")
		)
		(fp_line
			(start -0.7874 0.4064)
			(end -0.7874 -0.4064)
			(stroke
				(width 0.1524)
				(type default)
			)
			(layer "F.SilkS")
		)
		(fp_line
			(start -0.12065 -0.305054)
			(end -0.12065 -0.2794)
			(stroke
				(width 0.1)
				(type default)
			)
			(layer "F.Fab")
		)
		(fp_line
			(start -0.67945 -0.305054)
			(end -0.12065 -0.305054)
			(stroke
				(width 0.1)
				(type default)
			)
			(layer "F.Fab")
		)
		(fp_line
			(start 0.67945 -0.3048)
			(end 0.67945 0.3048)
			(stroke
				(width 0.1)
				(type default)
			)
			(layer "F.Fab")
		)
		(fp_line
			(start 0.12065 -0.3048)
			(end 0.67945 -0.3048)
			(stroke
				(width 0.1)
				(type default)
			)
			(layer "F.Fab")
		)
		(fp_line
			(start 0.12065 -0.2794)
			(end 0.12065 -0.3048)
			(stroke
				(width 0.1)
				(type default)
			)
			(layer "F.Fab")
		)
		(fp_line
			(start -0.12065 -0.2794)
			(end 0.12065 -0.2794)
			(stroke
				(width 0.1)
				(type default)
			)
			(layer "F.Fab")
		)
		(fp_line
			(start 0.120396 0.2794)
			(end -0.12065 0.2794)
			(stroke
				(width 0.1)
				(type default)
			)
			(layer "F.Fab")
		)
		(fp_line
			(start -0.12065 0.2794)
			(end -0.12065 0.3048)
			(stroke
				(width 0.1)
				(type default)
			)
			(layer "F.Fab")
		)
		(fp_line
			(start 0.67945 0.3048)
			(end 0.120396 0.3048)
			(stroke
				(width 0.1)
				(type default)
			)
			(layer "F.Fab")
		)
		(fp_line
			(start 0.120396 0.3048)
			(end 0.120396 0.2794)
			(stroke
				(width 0.1)
				(type default)
			)
			(layer "F.Fab")
		)
		(fp_line
			(start -0.12065 0.3048)
			(end -0.67945 0.3048)
			(stroke
				(width 0.1)
				(type default)
			)
			(layer "F.Fab")
		)
		(fp_line
			(start -0.67945 0.3048)
			(end -0.67945 -0.305054)
			(stroke
				(width 0.1)
				(type default)
			)
			(layer "F.Fab")
		)
		(pad "1" smd circle
			(at -0.40005 0 90)
			(size 0 0)
			(layers "F.Cu" "F.Mask" "F.Paste")
			(net "NC_PVCCINFAON_CPU1_ACSP6")
		)
		(pad "2" smd circle
			(at 0.40005 0 90)
			(size 0 0)
			(layers "F.Cu" "F.Mask" "F.Paste")
			(net "GND")
		)
	)
	(footprint ""
		(layer "F.Cu")
		(at 114.68608 -119.846598 -90)
		(property "Reference" "R4036"
			(at 0 0 270)
			(layer "F.SilkS")
			(hide yes)
			(effects
				(font
					(size 1.27 1.27)
				)
			)
		)
		(property "Value" ""
			(at 0 0 270)
			(layer "F.Fab")
			(effects
				(font
					(size 1.27 1.27)
				)
			)
		)
		(duplicate_pad_numbers_are_jumpers no)
		(fp_line
			(start -0.7874 0.4064)
			(end -0.7874 -0.4064)
			(stroke
				(width 0.1524)
				(type default)
			)
			(layer "F.SilkS")
		)
		(fp_line
			(start 0.7874 0.4064)
			(end -0.7874 0.4064)
			(stroke
				(width 0.1524)
				(type default)
			)
			(layer "F.SilkS")
		)
		(fp_line
			(start -0.7874 -0.4064)
			(end 0.7874 -0.4064)
			(stroke
				(width 0.1524)
				(type default)
			)
			(layer "F.SilkS")
		)
		(fp_line
			(start 0.7874 -0.4064)
			(end 0.7874 0.4064)
			(stroke
				(width 0.1524)
				(type default)
			)
			(layer "F.SilkS")
		)
		(fp_line
			(start -0.67945 0.3048)
			(end -0.67945 -0.305054)
			(stroke
				(width 0.1)
				(type default)
			)
			(layer "F.Fab")
		)
		(fp_line
			(start -0.12065 0.3048)
			(end -0.67945 0.3048)
			(stroke
				(width 0.1)
				(type default)
			)
			(layer "F.Fab")
		)
		(fp_line
			(start 0.120396 0.3048)
			(end 0.120396 0.2794)
			(stroke
				(width 0.1)
				(type default)
			)
			(layer "F.Fab")
		)
		(fp_line
			(start 0.67945 0.3048)
			(end 0.120396 0.3048)
			(stroke
				(width 0.1)
				(type default)
			)
			(layer "F.Fab")
		)
		(fp_line
			(start -0.12065 0.2794)
			(end -0.12065 0.3048)
			(stroke
				(width 0.1)
				(type default)
			)
			(layer "F.Fab")
		)
		(fp_line
			(start 0.120396 0.2794)
			(end -0.12065 0.2794)
			(stroke
				(width 0.1)
				(type default)
			)
			(layer "F.Fab")
		)
		(fp_line
			(start -0.12065 -0.2794)
			(end 0.12065 -0.2794)
			(stroke
				(width 0.1)
				(type default)
			)
			(layer "F.Fab")
		)
		(fp_line
			(start 0.12065 -0.2794)
			(end 0.12065 -0.3048)
			(stroke
				(width 0.1)
				(type default)
			)
			(layer "F.Fab")
		)
		(fp_line
			(start 0.12065 -0.3048)
			(end 0.67945 -0.3048)
			(stroke
				(width 0.1)
				(type default)
			)
			(layer "F.Fab")
		)
		(fp_line
			(start 0.67945 -0.3048)
			(end 0.67945 0.3048)
			(stroke
				(width 0.1)
				(type default)
			)
			(layer "F.Fab")
		)
		(fp_line
			(start -0.67945 -0.305054)
			(end -0.12065 -0.305054)
			(stroke
				(width 0.1)
				(type default)
			)
			(layer "F.Fab")
		)
		(fp_line
			(start -0.12065 -0.305054)
			(end -0.12065 -0.2794)
			(stroke
				(width 0.1)
				(type default)
			)
			(layer "F.Fab")
		)
		(pad "1" smd circle
			(at -0.40005 0 270)
			(size 0 0)
			(layers "F.Cu" "F.Mask" "F.Paste")
			(net "P3V3_AUX")
		)
		(pad "2" smd circle
			(at 0.40005 0 270)
			(size 0 0)
			(layers "F.Cu" "F.Mask" "F.Paste")
			(net "P0V62_CPU0_RST_DDR_VREF")
		)
	)
	(footprint ""
		(layer "F.Cu")
		(at 434.443632 -107.17403 90)
		(property "Reference" "PC2086"
			(at 0 0 90)
			(layer "F.SilkS")
			(hide yes)
			(effects
				(font
					(size 1.27 1.27)
				)
			)
		)
		(property "Value" ""
			(at 0 0 90)
			(layer "F.Fab")
			(effects
				(font
					(size 1.27 1.27)
				)
			)
		)
		(duplicate_pad_numbers_are_jumpers no)
		(fp_line
			(start 0.7874 -0.4064)
			(end 0.7874 0.4064)
			(stroke
				(width 0.1524)
				(type default)
			)
			(layer "F.SilkS")
		)
		(fp_line
			(start -0.7874 -0.4064)
			(end 0.7874 -0.4064)
			(stroke
				(width 0.1524)
				(type default)
			)
			(layer "F.SilkS")
		)
		(fp_line
			(start 0.7874 0.4064)
			(end -0.7874 0.4064)
			(stroke
				(width 0.1524)
				(type default)
			)
			(layer "F.SilkS")
		)
		(fp_line
			(start -0.7874 0.4064)
			(end -0.7874 -0.4064)
			(stroke
				(width 0.1524)
				(type default)
			)
			(layer "F.SilkS")
		)
		(fp_line
			(start -0.12065 -0.305054)
			(end -0.12065 -0.2794)
			(stroke
				(width 0.1)
				(type default)
			)
			(layer "F.Fab")
		)
		(fp_line
			(start -0.67945 -0.305054)
			(end -0.12065 -0.305054)
			(stroke
				(width 0.1)
				(type default)
			)
			(layer "F.Fab")
		)
		(fp_line
			(start 0.67945 -0.3048)
			(end 0.67945 0.3048)
			(stroke
				(width 0.1)
				(type default)
			)
			(layer "F.Fab")
		)
		(fp_line
			(start 0.12065 -0.3048)
			(end 0.67945 -0.3048)
			(stroke
				(width 0.1)
				(type default)
			)
			(layer "F.Fab")
		)
		(fp_line
			(start 0.12065 -0.2794)
			(end 0.12065 -0.3048)
			(stroke
				(width 0.1)
				(type default)
			)
			(layer "F.Fab")
		)
		(fp_line
			(start -0.12065 -0.2794)
			(end 0.12065 -0.2794)
			(stroke
				(width 0.1)
				(type default)
			)
			(layer "F.Fab")
		)
		(fp_line
			(start 0.120396 0.2794)
			(end -0.12065 0.2794)
			(stroke
				(width 0.1)
				(type default)
			)
			(layer "F.Fab")
		)
		(fp_line
			(start -0.12065 0.2794)
			(end -0.12065 0.3048)
			(stroke
				(width 0.1)
				(type default)
			)
			(layer "F.Fab")
		)
		(fp_line
			(start 0.67945 0.3048)
			(end 0.120396 0.3048)
			(stroke
				(width 0.1)
				(type default)
			)
			(layer "F.Fab")
		)
		(fp_line
			(start 0.120396 0.3048)
			(end 0.120396 0.2794)
			(stroke
				(width 0.1)
				(type default)
			)
			(layer "F.Fab")
		)
		(fp_line
			(start -0.12065 0.3048)
			(end -0.67945 0.3048)
			(stroke
				(width 0.1)
				(type default)
			)
			(layer "F.Fab")
		)
		(fp_line
			(start -0.67945 0.3048)
			(end -0.67945 -0.305054)
			(stroke
				(width 0.1)
				(type default)
			)
			(layer "F.Fab")
		)
		(pad "1" smd circle
			(at -0.40005 0 90)
			(size 0 0)
			(layers "F.Cu" "F.Mask" "F.Paste")
			(net "P3V3_OCP_VCC_1")
		)
		(pad "2" smd circle
			(at 0.40005 0 90)
			(size 0 0)
			(layers "F.Cu" "F.Mask" "F.Paste")
			(net "GND")
		)
	)
	(footprint ""
		(layer "F.Cu")
		(at 164.52088 -46.954948 180)
		(property "Reference" "R1605"
			(at 0 0 180)
			(layer "F.SilkS")
			(hide yes)
			(effects
				(font
					(size 1.27 1.27)
				)
			)
		)
		(property "Value" ""
			(at 0 0 180)
			(layer "F.Fab")
			(effects
				(font
					(size 1.27 1.27)
				)
			)
		)
		(duplicate_pad_numbers_are_jumpers no)
		(fp_line
			(start 0.7874 0.4064)
			(end -0.7874 0.4064)
			(stroke
				(width 0.1524)
				(type default)
			)
			(layer "F.SilkS")
		)
		(fp_line
			(start 0.7874 -0.4064)
			(end 0.7874 0.4064)
			(stroke
				(width 0.1524)
				(type default)
			)
			(layer "F.SilkS")
		)
		(fp_line
			(start -0.7874 0.4064)
			(end -0.7874 -0.4064)
			(stroke
				(width 0.1524)
				(type default)
			)
			(layer "F.SilkS")
		)
		(fp_line
			(start -0.7874 -0.4064)
			(end 0.7874 -0.4064)
			(stroke
				(width 0.1524)
				(type default)
			)
			(layer "F.SilkS")
		)
		(fp_line
			(start 0.67945 0.3048)
			(end 0.120396 0.3048)
			(stroke
				(width 0.1)
				(type default)
			)
			(layer "F.Fab")
		)
		(fp_line
			(start 0.67945 -0.3048)
			(end 0.67945 0.3048)
			(stroke
				(width 0.1)
				(type default)
			)
			(layer "F.Fab")
		)
		(fp_line
			(start 0.12065 -0.2794)
			(end 0.12065 -0.3048)
			(stroke
				(width 0.1)
				(type default)
			)
			(layer "F.Fab")
		)
		(fp_line
			(start 0.12065 -0.3048)
			(end 0.67945 -0.3048)
			(stroke
				(width 0.1)
				(type default)
			)
			(layer "F.Fab")
		)
		(fp_line
			(start 0.120396 0.3048)
			(end 0.120396 0.2794)
			(stroke
				(width 0.1)
				(type default)
			)
			(layer "F.Fab")
		)
		(fp_line
			(start 0.120396 0.2794)
			(end -0.12065 0.2794)
			(stroke
				(width 0.1)
				(type default)
			)
			(layer "F.Fab")
		)
		(fp_line
			(start -0.12065 0.3048)
			(end -0.67945 0.3048)
			(stroke
				(width 0.1)
				(type default)
			)
			(layer "F.Fab")
		)
		(fp_line
			(start -0.12065 0.2794)
			(end -0.12065 0.3048)
			(stroke
				(width 0.1)
				(type default)
			)
			(layer "F.Fab")
		)
		(fp_line
			(start -0.12065 -0.2794)
			(end 0.12065 -0.2794)
			(stroke
				(width 0.1)
				(type default)
			)
			(layer "F.Fab")
		)
		(fp_line
			(start -0.12065 -0.305054)
			(end -0.12065 -0.2794)
			(stroke
				(width 0.1)
				(type default)
			)
			(layer "F.Fab")
		)
		(fp_line
			(start -0.67945 0.3048)
			(end -0.67945 -0.305054)
			(stroke
				(width 0.1)
				(type default)
			)
			(layer "F.Fab")
		)
		(fp_line
			(start -0.67945 -0.305054)
			(end -0.12065 -0.305054)
			(stroke
				(width 0.1)
				(type default)
			)
			(layer "F.Fab")
		)
		(pad "1" smd circle
			(at -0.40005 0 180)
			(size 0 0)
			(layers "F.Cu" "F.Mask" "F.Paste")
			(net "PD_M2_0_DEVSLP")
		)
		(pad "2" smd circle
			(at 0.40005 0 180)
			(size 0 0)
			(layers "F.Cu" "F.Mask" "F.Paste")
			(net "GND")
		)
	)
	(footprint ""
		(layer "F.Cu")
		(at 358.84104 -315.66739 90)
		(property "Reference" "PC319"
			(at 0 0 90)
			(layer "F.SilkS")
			(hide yes)
			(effects
				(font
					(size 1.27 1.27)
				)
			)
		)
		(property "Value" ""
			(at 0 0 90)
			(layer "F.Fab")
			(effects
				(font
					(size 1.27 1.27)
				)
			)
		)
		(duplicate_pad_numbers_are_jumpers no)
		(fp_line
			(start 2.750058 0.999998)
			(end -2.750058 0.999998)
			(stroke
				(width 0.1524)
				(type default)
			)
			(layer "F.SilkS")
		)
		(fp_circle
			(center 0 0.999998)
			(end 0 3.750056)
			(stroke
				(width 0.1524)
				(type default)
			)
			(fill no)
			(layer "F.SilkS")
		)
		(fp_poly
			(pts
				(arc
					(start 2.750058 0.999998)
					(mid 0 3.750056)
					(end -2.750058 0.999998)
				)
			)
			(stroke
				(width 0)
				(type default)
			)
			(fill yes)
			(layer "F.SilkS")
		)
		(fp_circle
			(center 0 0.999998)
			(end 0 3.750056)
			(stroke
				(width 0.1)
				(type default)
			)
			(fill no)
			(layer "F.Fab")
		)
		(pad "1" thru_hole rect
			(at 0 0 90)
			(size 1.5748 1.5748)
			(drill 1.0668)
			(layers "*.Cu" "*.Mask")
			(remove_unused_layers no)
			(net "PVCCIN_CPU0")
			(clearance 0)
			(padstack
				(mode front_inner_back)
				(layer "Inner"
					(shape circle)
					(size 1.5748 1.5748)
					(clearance 0)
				)
				(layer "B.Cu"
					(shape rect)
					(size 1.5748 1.5748)
					(clearance 0)
				)
			)
		)
		(pad "2" thru_hole circle
			(at 0 1.999996 90)
			(size 1.5748 1.5748)
			(drill 1.0668)
			(layers "*.Cu" "*.Mask")
			(remove_unused_layers no)
			(net "GND")
			(clearance 0)
		)
	)
	(footprint ""
		(layer "F.Cu")
		(at 105.3084 -249.320558 -90)
		(property "Reference" "C236"
			(at 0 0 270)
			(layer "F.SilkS")
			(hide yes)
			(effects
				(font
					(size 1.27 1.27)
				)
			)
		)
		(property "Value" ""
			(at 0 0 270)
			(layer "F.Fab")
			(effects
				(font
					(size 1.27 1.27)
				)
			)
		)
		(duplicate_pad_numbers_are_jumpers no)
		(fp_line
			(start -0.7874 0.4064)
			(end -0.7874 -0.4064)
			(stroke
				(width 0.1524)
				(type default)
			)
			(layer "F.SilkS")
		)
		(fp_line
			(start 0.7874 0.4064)
			(end -0.7874 0.4064)
			(stroke
				(width 0.1524)
				(type default)
			)
			(layer "F.SilkS")
		)
		(fp_line
			(start -0.7874 -0.4064)
			(end 0.7874 -0.4064)
			(stroke
				(width 0.1524)
				(type default)
			)
			(layer "F.SilkS")
		)
		(fp_line
			(start 0.7874 -0.4064)
			(end 0.7874 0.4064)
			(stroke
				(width 0.1524)
				(type default)
			)
			(layer "F.SilkS")
		)
		(fp_line
			(start -0.67945 0.3048)
			(end -0.67945 -0.305054)
			(stroke
				(width 0.1)
				(type default)
			)
			(layer "F.Fab")
		)
		(fp_line
			(start -0.12065 0.3048)
			(end -0.67945 0.3048)
			(stroke
				(width 0.1)
				(type default)
			)
			(layer "F.Fab")
		)
		(fp_line
			(start 0.120396 0.3048)
			(end 0.120396 0.2794)
			(stroke
				(width 0.1)
				(type default)
			)
			(layer "F.Fab")
		)
		(fp_line
			(start 0.67945 0.3048)
			(end 0.120396 0.3048)
			(stroke
				(width 0.1)
				(type default)
			)
			(layer "F.Fab")
		)
		(fp_line
			(start -0.12065 0.2794)
			(end -0.12065 0.3048)
			(stroke
				(width 0.1)
				(type default)
			)
			(layer "F.Fab")
		)
		(fp_line
			(start 0.120396 0.2794)
			(end -0.12065 0.2794)
			(stroke
				(width 0.1)
				(type default)
			)
			(layer "F.Fab")
		)
		(fp_line
			(start -0.12065 -0.2794)
			(end 0.12065 -0.2794)
			(stroke
				(width 0.1)
				(type default)
			)
			(layer "F.Fab")
		)
		(fp_line
			(start 0.12065 -0.2794)
			(end 0.12065 -0.3048)
			(stroke
				(width 0.1)
				(type default)
			)
			(layer "F.Fab")
		)
		(fp_line
			(start 0.12065 -0.3048)
			(end 0.67945 -0.3048)
			(stroke
				(width 0.1)
				(type default)
			)
			(layer "F.Fab")
		)
		(fp_line
			(start 0.67945 -0.3048)
			(end 0.67945 0.3048)
			(stroke
				(width 0.1)
				(type default)
			)
			(layer "F.Fab")
		)
		(fp_line
			(start -0.67945 -0.305054)
			(end -0.12065 -0.305054)
			(stroke
				(width 0.1)
				(type default)
			)
			(layer "F.Fab")
		)
		(fp_line
			(start -0.12065 -0.305054)
			(end -0.12065 -0.2794)
			(stroke
				(width 0.1)
				(type default)
			)
			(layer "F.Fab")
		)
		(pad "1" smd circle
			(at -0.40005 0 270)
			(size 0 0)
			(layers "F.Cu" "F.Mask" "F.Paste")
			(net "PVCCIN_CPU1")
		)
		(pad "2" smd circle
			(at 0.40005 0 270)
			(size 0 0)
			(layers "F.Cu" "F.Mask" "F.Paste")
			(net "GND")
		)
	)
	(footprint ""
		(layer "F.Cu")
		(at 321.531488 -408.517344 -90)
		(property "Reference" "C913"
			(at 0 0 270)
			(layer "F.SilkS")
			(hide yes)
			(effects
				(font
					(size 1.27 1.27)
				)
			)
		)
		(property "Value" ""
			(at 0 0 270)
			(layer "F.Fab")
			(effects
				(font
					(size 1.27 1.27)
				)
			)
		)
		(duplicate_pad_numbers_are_jumpers no)
		(fp_line
			(start -0.299974 0.150114)
			(end -0.299974 -0.150114)
			(stroke
				(width 0.1)
				(type default)
			)
			(layer "F.Fab")
		)
		(fp_line
			(start 0.299974 0.150114)
			(end -0.299974 0.150114)
			(stroke
				(width 0.1)
				(type default)
			)
			(layer "F.Fab")
		)
		(fp_line
			(start -0.299974 -0.150114)
			(end 0.299974 -0.150114)
			(stroke
				(width 0.1)
				(type default)
			)
			(layer "F.Fab")
		)
		(fp_line
			(start 0.299974 -0.150114)
			(end 0.299974 0.150114)
			(stroke
				(width 0.1)
				(type default)
			)
			(layer "F.Fab")
		)
		(pad "1" smd rect
			(at -0.2667 0 270)
			(size 0.3048 0.381)
			(layers "F.Cu" "F.Mask" "F.Paste")
			(net "P5E_CPU0_PE0_TX_C_DP<10>")
		)
		(pad "2" smd rect
			(at 0.2667 0 270)
			(size 0.3048 0.381)
			(layers "F.Cu" "F.Mask" "F.Paste")
			(net "P5E_CPU0_PE0_TX_DP<10>")
		)
	)
	(footprint ""
		(layer "F.Cu")
		(at 128.70688 -92.674948 -90)
		(property "Reference" "R4401"
			(at 0 0 270)
			(layer "F.SilkS")
			(hide yes)
			(effects
				(font
					(size 1.27 1.27)
				)
			)
		)
		(property "Value" ""
			(at 0 0 270)
			(layer "F.Fab")
			(effects
				(font
					(size 1.27 1.27)
				)
			)
		)
		(duplicate_pad_numbers_are_jumpers no)
		(fp_line
			(start -0.7874 0.4064)
			(end -0.7874 -0.4064)
			(stroke
				(width 0.1524)
				(type default)
			)
			(layer "F.SilkS")
		)
		(fp_line
			(start 0.7874 0.4064)
			(end -0.7874 0.4064)
			(stroke
				(width 0.1524)
				(type default)
			)
			(layer "F.SilkS")
		)
		(fp_line
			(start -0.7874 -0.4064)
			(end 0.7874 -0.4064)
			(stroke
				(width 0.1524)
				(type default)
			)
			(layer "F.SilkS")
		)
		(fp_line
			(start 0.7874 -0.4064)
			(end 0.7874 0.4064)
			(stroke
				(width 0.1524)
				(type default)
			)
			(layer "F.SilkS")
		)
		(fp_line
			(start -0.67945 0.3048)
			(end -0.67945 -0.305054)
			(stroke
				(width 0.1)
				(type default)
			)
			(layer "F.Fab")
		)
		(fp_line
			(start -0.12065 0.3048)
			(end -0.67945 0.3048)
			(stroke
				(width 0.1)
				(type default)
			)
			(layer "F.Fab")
		)
		(fp_line
			(start 0.120396 0.3048)
			(end 0.120396 0.2794)
			(stroke
				(width 0.1)
				(type default)
			)
			(layer "F.Fab")
		)
		(fp_line
			(start 0.67945 0.3048)
			(end 0.120396 0.3048)
			(stroke
				(width 0.1)
				(type default)
			)
			(layer "F.Fab")
		)
		(fp_line
			(start -0.12065 0.2794)
			(end -0.12065 0.3048)
			(stroke
				(width 0.1)
				(type default)
			)
			(layer "F.Fab")
		)
		(fp_line
			(start 0.120396 0.2794)
			(end -0.12065 0.2794)
			(stroke
				(width 0.1)
				(type default)
			)
			(layer "F.Fab")
		)
		(fp_line
			(start -0.12065 -0.2794)
			(end 0.12065 -0.2794)
			(stroke
				(width 0.1)
				(type default)
			)
			(layer "F.Fab")
		)
		(fp_line
			(start 0.12065 -0.2794)
			(end 0.12065 -0.3048)
			(stroke
				(width 0.1)
				(type default)
			)
			(layer "F.Fab")
		)
		(fp_line
			(start 0.12065 -0.3048)
			(end 0.67945 -0.3048)
			(stroke
				(width 0.1)
				(type default)
			)
			(layer "F.Fab")
		)
		(fp_line
			(start 0.67945 -0.3048)
			(end 0.67945 0.3048)
			(stroke
				(width 0.1)
				(type default)
			)
			(layer "F.Fab")
		)
		(fp_line
			(start -0.67945 -0.305054)
			(end -0.12065 -0.305054)
			(stroke
				(width 0.1)
				(type default)
			)
			(layer "F.Fab")
		)
		(fp_line
			(start -0.12065 -0.305054)
			(end -0.12065 -0.2794)
			(stroke
				(width 0.1)
				(type default)
			)
			(layer "F.Fab")
		)
		(pad "1" smd circle
			(at -0.40005 0 270)
			(size 0 0)
			(layers "F.Cu" "F.Mask" "F.Paste")
			(net "PVNN_TERM_CPU0")
		)
		(pad "2" smd circle
			(at 0.40005 0 270)
			(size 0 0)
			(layers "F.Cu" "F.Mask" "F.Paste")
			(net "H_CPU0_MEMHOT_OUT_LVC1_R_N")
		)
	)
	(footprint ""
		(layer "F.Cu")
		(at 33.410398 -390.10717 180)
		(property "Reference" "R3381"
			(at 0 0 180)
			(layer "F.SilkS")
			(hide yes)
			(effects
				(font
					(size 1.27 1.27)
				)
			)
		)
		(property "Value" ""
			(at 0 0 180)
			(layer "F.Fab")
			(effects
				(font
					(size 1.27 1.27)
				)
			)
		)
		(duplicate_pad_numbers_are_jumpers no)
		(fp_line
			(start 0.7874 0.4064)
			(end -0.7874 0.4064)
			(stroke
				(width 0.1524)
				(type default)
			)
			(layer "F.SilkS")
		)
		(fp_line
			(start 0.7874 -0.4064)
			(end 0.7874 0.4064)
			(stroke
				(width 0.1524)
				(type default)
			)
			(layer "F.SilkS")
		)
		(fp_line
			(start -0.7874 0.4064)
			(end -0.7874 -0.4064)
			(stroke
				(width 0.1524)
				(type default)
			)
			(layer "F.SilkS")
		)
		(fp_line
			(start -0.7874 -0.4064)
			(end 0.7874 -0.4064)
			(stroke
				(width 0.1524)
				(type default)
			)
			(layer "F.SilkS")
		)
		(fp_line
			(start 0.67945 0.3048)
			(end 0.120396 0.3048)
			(stroke
				(width 0.1)
				(type default)
			)
			(layer "F.Fab")
		)
		(fp_line
			(start 0.67945 -0.3048)
			(end 0.67945 0.3048)
			(stroke
				(width 0.1)
				(type default)
			)
			(layer "F.Fab")
		)
		(fp_line
			(start 0.12065 -0.2794)
			(end 0.12065 -0.3048)
			(stroke
				(width 0.1)
				(type default)
			)
			(layer "F.Fab")
		)
		(fp_line
			(start 0.12065 -0.3048)
			(end 0.67945 -0.3048)
			(stroke
				(width 0.1)
				(type default)
			)
			(layer "F.Fab")
		)
		(fp_line
			(start 0.120396 0.3048)
			(end 0.120396 0.2794)
			(stroke
				(width 0.1)
				(type default)
			)
			(layer "F.Fab")
		)
		(fp_line
			(start 0.120396 0.2794)
			(end -0.12065 0.2794)
			(stroke
				(width 0.1)
				(type default)
			)
			(layer "F.Fab")
		)
		(fp_line
			(start -0.12065 0.3048)
			(end -0.67945 0.3048)
			(stroke
				(width 0.1)
				(type default)
			)
			(layer "F.Fab")
		)
		(fp_line
			(start -0.12065 0.2794)
			(end -0.12065 0.3048)
			(stroke
				(width 0.1)
				(type default)
			)
			(layer "F.Fab")
		)
		(fp_line
			(start -0.12065 -0.2794)
			(end 0.12065 -0.2794)
			(stroke
				(width 0.1)
				(type default)
			)
			(layer "F.Fab")
		)
		(fp_line
			(start -0.12065 -0.305054)
			(end -0.12065 -0.2794)
			(stroke
				(width 0.1)
				(type default)
			)
			(layer "F.Fab")
		)
		(fp_line
			(start -0.67945 0.3048)
			(end -0.67945 -0.305054)
			(stroke
				(width 0.1)
				(type default)
			)
			(layer "F.Fab")
		)
		(fp_line
			(start -0.67945 -0.305054)
			(end -0.12065 -0.305054)
			(stroke
				(width 0.1)
				(type default)
			)
			(layer "F.Fab")
		)
		(pad "1" smd circle
			(at -0.40005 0 180)
			(size 0 0)
			(layers "F.Cu" "F.Mask" "F.Paste")
			(net "FM_P2E_BUF2_RXDET")
		)
		(pad "2" smd circle
			(at 0.40005 0 180)
			(size 0 0)
			(layers "F.Cu" "F.Mask" "F.Paste")
			(net "GND")
		)
	)
	(footprint ""
		(layer "F.Cu")
		(at 133.816852 -340.064598)
		(property "Reference" "PC506_P1_5"
			(at 0 0 0)
			(layer "F.SilkS")
			(hide yes)
			(effects
				(font
					(size 1.27 1.27)
				)
			)
		)
		(property "Value" ""
			(at 0 0 0)
			(layer "F.Fab")
			(effects
				(font
					(size 1.27 1.27)
				)
			)
		)
		(duplicate_pad_numbers_are_jumpers no)
		(fp_line
			(start -0.7874 -0.4064)
			(end 0.7874 -0.4064)
			(stroke
				(width 0.1524)
				(type default)
			)
			(layer "F.SilkS")
		)
		(fp_line
			(start -0.7874 0.4064)
			(end -0.7874 -0.4064)
			(stroke
				(width 0.1524)
				(type default)
			)
			(layer "F.SilkS")
		)
		(fp_line
			(start 0.7874 -0.4064)
			(end 0.7874 0.4064)
			(stroke
				(width 0.1524)
				(type default)
			)
			(layer "F.SilkS")
		)
		(fp_line
			(start 0.7874 0.4064)
			(end -0.7874 0.4064)
			(stroke
				(width 0.1524)
				(type default)
			)
			(layer "F.SilkS")
		)
		(fp_line
			(start -0.67945 -0.305054)
			(end -0.12065 -0.305054)
			(stroke
				(width 0.1)
				(type default)
			)
			(layer "F.Fab")
		)
		(fp_line
			(start -0.67945 0.3048)
			(end -0.67945 -0.305054)
			(stroke
				(width 0.1)
				(type default)
			)
			(layer "F.Fab")
		)
		(fp_line
			(start -0.12065 -0.305054)
			(end -0.12065 -0.2794)
			(stroke
				(width 0.1)
				(type default)
			)
			(layer "F.Fab")
		)
		(fp_line
			(start -0.12065 -0.2794)
			(end 0.12065 -0.2794)
			(stroke
				(width 0.1)
				(type default)
			)
			(layer "F.Fab")
		)
		(fp_line
			(start -0.12065 0.2794)
			(end -0.12065 0.3048)
			(stroke
				(width 0.1)
				(type default)
			)
			(layer "F.Fab")
		)
		(fp_line
			(start -0.12065 0.3048)
			(end -0.67945 0.3048)
			(stroke
				(width 0.1)
				(type default)
			)
			(layer "F.Fab")
		)
		(fp_line
			(start 0.120396 0.2794)
			(end -0.12065 0.2794)
			(stroke
				(width 0.1)
				(type default)
			)
			(layer "F.Fab")
		)
		(fp_line
			(start 0.120396 0.3048)
			(end 0.120396 0.2794)
			(stroke
				(width 0.1)
				(type default)
			)
			(layer "F.Fab")
		)
		(fp_line
			(start 0.12065 -0.3048)
			(end 0.67945 -0.3048)
			(stroke
				(width 0.1)
				(type default)
			)
			(layer "F.Fab")
		)
		(fp_line
			(start 0.12065 -0.2794)
			(end 0.12065 -0.3048)
			(stroke
				(width 0.1)
				(type default)
			)
			(layer "F.Fab")
		)
		(fp_line
			(start 0.67945 -0.3048)
			(end 0.67945 0.3048)
			(stroke
				(width 0.1)
				(type default)
			)
			(layer "F.Fab")
		)
		(fp_line
			(start 0.67945 0.3048)
			(end 0.120396 0.3048)
			(stroke
				(width 0.1)
				(type default)
			)
			(layer "F.Fab")
		)
		(pad "1" smd circle
			(at -0.40005 0)
			(size 0 0)
			(layers "F.Cu" "F.Mask" "F.Paste")
			(net "SW_P12V_PVCCIN_CPU1_FLT")
		)
		(pad "2" smd circle
			(at 0.40005 0)
			(size 0 0)
			(layers "F.Cu" "F.Mask" "F.Paste")
			(net "GND")
		)
	)
	(footprint ""
		(layer "F.Cu")
		(at 455.228452 -15.503398 180)
		(property "Reference" "PD102"
			(at -2.299716 -2.168652 0)
			(unlocked yes)
			(layer "F.SilkS")
			(effects
				(font
					(size 0.7874 0.5842)
					(thickness 0.1524)
				)
				(justify left)
			)
		)
		(property "Value" ""
			(at 0 0 180)
			(layer "F.Fab")
			(effects
				(font
					(size 1.27 1.27)
				)
			)
		)
		(duplicate_pad_numbers_are_jumpers no)
		(fp_line
			(start 4.107942 1.459992)
			(end -3.400044 1.459992)
			(stroke
				(width 0.1524)
				(type default)
			)
			(layer "F.SilkS")
		)
		(fp_line
			(start 4.107942 -1.459992)
			(end 4.107942 1.459992)
			(stroke
				(width 0.1524)
				(type default)
			)
			(layer "F.SilkS")
		)
		(fp_line
			(start -3.400044 1.459992)
			(end -3.400044 -1.459992)
			(stroke
				(width 0.1524)
				(type default)
			)
			(layer "F.SilkS")
		)
		(fp_line
			(start -3.400044 -1.459992)
			(end 4.107942 -1.459992)
			(stroke
				(width 0.1524)
				(type default)
			)
			(layer "F.SilkS")
		)
		(fp_rect
			(start 4.107942 -1.459992)
			(end 3.308096 1.459992)
			(stroke
				(width 0)
				(type default)
			)
			(fill yes)
			(layer "F.SilkS")
		)
		(fp_line
			(start 2.29997 1.459992)
			(end -2.29997 1.459992)
			(stroke
				(width 0.1)
				(type default)
			)
			(layer "F.Fab")
		)
		(fp_line
			(start 2.29997 -1.459992)
			(end 2.29997 1.459992)
			(stroke
				(width 0.1)
				(type default)
			)
			(layer "F.Fab")
		)
		(fp_line
			(start -2.29997 1.459992)
			(end -2.29997 -1.459992)
			(stroke
				(width 0.1)
				(type default)
			)
			(layer "F.Fab")
		)
		(fp_line
			(start -2.29997 -1.459992)
			(end 2.29997 -1.459992)
			(stroke
				(width 0.1)
				(type default)
			)
			(layer "F.Fab")
		)
		(fp_text user "-"
			(at 5.4102 0.29845 0)
			(unlocked yes)
			(layer "F.SilkS")
			(effects
				(font
					(size 1.905 1.4224)
					(thickness 0.1524)
				)
				(justify left)
			)
		)
		(fp_text user "+"
			(at -4.7752 -0.12065 180)
			(unlocked yes)
			(layer "F.SilkS")
			(effects
				(font
					(size 1.905 1.4224)
					(thickness 0.1524)
				)
				(justify left)
			)
		)
		(fp_text user "-"
			(at 5.4102 0.29845 0)
			(unlocked yes)
			(layer "F.Fab")
			(effects
				(font
					(size 1.905 1.4224)
					(thickness 0.1524)
				)
				(justify left)
			)
		)
		(fp_text user "+"
			(at -4.7752 -0.12065 180)
			(unlocked yes)
			(layer "F.Fab")
			(effects
				(font
					(size 1.905 1.4224)
					(thickness 0.1524)
				)
				(justify left)
			)
		)
		(pad "A" smd rect
			(at -1.999996 0 270)
			(size 1.7018 2.5146)
			(layers "F.Cu" "F.Mask" "F.Paste")
			(net "GND")
		)
		(pad "C" smd rect
			(at 1.999996 0 270)
			(size 1.7018 2.5146)
			(layers "F.Cu" "F.Mask" "F.Paste")
			(net "P12V_OCP_SFF")
		)
	)
	(footprint ""
		(layer "F.Cu")
		(at 389.902192 -76.171044 90)
		(property "Reference" "PC1232"
			(at 0 0 90)
			(layer "F.SilkS")
			(hide yes)
			(effects
				(font
					(size 1.27 1.27)
				)
			)
		)
		(property "Value" ""
			(at 0 0 90)
			(layer "F.Fab")
			(effects
				(font
					(size 1.27 1.27)
				)
			)
		)
		(duplicate_pad_numbers_are_jumpers no)
		(fp_line
			(start 1.524 -0.762)
			(end 1.524 0.762)
			(stroke
				(width 0.1524)
				(type default)
			)
			(layer "F.SilkS")
		)
		(fp_line
			(start -1.524 -0.762)
			(end 1.524 -0.762)
			(stroke
				(width 0.1524)
				(type default)
			)
			(layer "F.SilkS")
		)
		(fp_line
			(start 1.524 0.762)
			(end -1.524 0.762)
			(stroke
				(width 0.1524)
				(type default)
			)
			(layer "F.SilkS")
		)
		(fp_line
			(start -1.524 0.762)
			(end -1.524 -0.762)
			(stroke
				(width 0.1524)
				(type default)
			)
			(layer "F.SilkS")
		)
		(fp_line
			(start 1.1049 -0.724916)
			(end -1.1049 -0.724916)
			(stroke
				(width 0.1)
				(type default)
			)
			(layer "F.Fab")
		)
		(fp_line
			(start -1.1049 -0.724916)
			(end -1.1049 0.724916)
			(stroke
				(width 0.1)
				(type default)
			)
			(layer "F.Fab")
		)
		(fp_line
			(start 1.1049 0.724916)
			(end 1.1049 -0.724916)
			(stroke
				(width 0.1)
				(type default)
			)
			(layer "F.Fab")
		)
		(fp_line
			(start -1.1049 0.724916)
			(end 1.1049 0.724916)
			(stroke
				(width 0.1)
				(type default)
			)
			(layer "F.Fab")
		)
		(pad "1" smd rect
			(at -0.889 0 270)
			(size 1.016 1.27)
			(layers "F.Cu" "F.Mask" "F.Paste")
			(net "SW_P1V8_PCH_AUX_FLT")
		)
		(pad "2" smd rect
			(at 0.889 0 270)
			(size 1.016 1.27)
			(layers "F.Cu" "F.Mask" "F.Paste")
			(net "GND")
		)
	)
	(footprint ""
		(layer "F.Cu")
		(at 141.66088 -368.645948 -90)
		(property "Reference" "R1712"
			(at 0 0 270)
			(layer "F.SilkS")
			(hide yes)
			(effects
				(font
					(size 1.27 1.27)
				)
			)
		)
		(property "Value" ""
			(at 0 0 270)
			(layer "F.Fab")
			(effects
				(font
					(size 1.27 1.27)
				)
			)
		)
		(duplicate_pad_numbers_are_jumpers no)
		(fp_line
			(start -0.7874 0.4064)
			(end -0.7874 -0.4064)
			(stroke
				(width 0.1524)
				(type default)
			)
			(layer "F.SilkS")
		)
		(fp_line
			(start 0.7874 0.4064)
			(end -0.7874 0.4064)
			(stroke
				(width 0.1524)
				(type default)
			)
			(layer "F.SilkS")
		)
		(fp_line
			(start -0.7874 -0.4064)
			(end 0.7874 -0.4064)
			(stroke
				(width 0.1524)
				(type default)
			)
			(layer "F.SilkS")
		)
		(fp_line
			(start 0.7874 -0.4064)
			(end 0.7874 0.4064)
			(stroke
				(width 0.1524)
				(type default)
			)
			(layer "F.SilkS")
		)
		(fp_line
			(start -0.67945 0.3048)
			(end -0.67945 -0.305054)
			(stroke
				(width 0.1)
				(type default)
			)
			(layer "F.Fab")
		)
		(fp_line
			(start -0.12065 0.3048)
			(end -0.67945 0.3048)
			(stroke
				(width 0.1)
				(type default)
			)
			(layer "F.Fab")
		)
		(fp_line
			(start 0.120396 0.3048)
			(end 0.120396 0.2794)
			(stroke
				(width 0.1)
				(type default)
			)
			(layer "F.Fab")
		)
		(fp_line
			(start 0.67945 0.3048)
			(end 0.120396 0.3048)
			(stroke
				(width 0.1)
				(type default)
			)
			(layer "F.Fab")
		)
		(fp_line
			(start -0.12065 0.2794)
			(end -0.12065 0.3048)
			(stroke
				(width 0.1)
				(type default)
			)
			(layer "F.Fab")
		)
		(fp_line
			(start 0.120396 0.2794)
			(end -0.12065 0.2794)
			(stroke
				(width 0.1)
				(type default)
			)
			(layer "F.Fab")
		)
		(fp_line
			(start -0.12065 -0.2794)
			(end 0.12065 -0.2794)
			(stroke
				(width 0.1)
				(type default)
			)
			(layer "F.Fab")
		)
		(fp_line
			(start 0.12065 -0.2794)
			(end 0.12065 -0.3048)
			(stroke
				(width 0.1)
				(type default)
			)
			(layer "F.Fab")
		)
		(fp_line
			(start 0.12065 -0.3048)
			(end 0.67945 -0.3048)
			(stroke
				(width 0.1)
				(type default)
			)
			(layer "F.Fab")
		)
		(fp_line
			(start 0.67945 -0.3048)
			(end 0.67945 0.3048)
			(stroke
				(width 0.1)
				(type default)
			)
			(layer "F.Fab")
		)
		(fp_line
			(start -0.67945 -0.305054)
			(end -0.12065 -0.305054)
			(stroke
				(width 0.1)
				(type default)
			)
			(layer "F.Fab")
		)
		(fp_line
			(start -0.12065 -0.305054)
			(end -0.12065 -0.2794)
			(stroke
				(width 0.1)
				(type default)
			)
			(layer "F.Fab")
		)
		(pad "1" smd circle
			(at -0.40005 0 270)
			(size 0 0)
			(layers "F.Cu" "F.Mask" "F.Paste")
			(net "SMB_VR_3V3AUX_SDA_R3")
		)
		(pad "2" smd circle
			(at 0.40005 0 270)
			(size 0 0)
			(layers "F.Cu" "F.Mask" "F.Paste")
			(net "P3V3_AUX")
		)
	)
	(footprint ""
		(layer "F.Cu")
		(at 108.56722 -294.01008)
		(property "Reference" "C265"
			(at 0 0 0)
			(layer "F.SilkS")
			(hide yes)
			(effects
				(font
					(size 1.27 1.27)
				)
			)
		)
		(property "Value" ""
			(at 0 0 0)
			(layer "F.Fab")
			(effects
				(font
					(size 1.27 1.27)
				)
			)
		)
		(duplicate_pad_numbers_are_jumpers no)
		(fp_line
			(start -1.524 -0.762)
			(end 1.524 -0.762)
			(stroke
				(width 0.1524)
				(type default)
			)
			(layer "F.SilkS")
		)
		(fp_line
			(start -1.524 0.762)
			(end -1.524 -0.762)
			(stroke
				(width 0.1524)
				(type default)
			)
			(layer "F.SilkS")
		)
		(fp_line
			(start 1.524 -0.762)
			(end 1.524 0.762)
			(stroke
				(width 0.1524)
				(type default)
			)
			(layer "F.SilkS")
		)
		(fp_line
			(start 1.524 0.762)
			(end -1.524 0.762)
			(stroke
				(width 0.1524)
				(type default)
			)
			(layer "F.SilkS")
		)
		(fp_line
			(start -1.1049 -0.724916)
			(end -1.1049 0.724916)
			(stroke
				(width 0.1)
				(type default)
			)
			(layer "F.Fab")
		)
		(fp_line
			(start -1.1049 0.724916)
			(end 1.1049 0.724916)
			(stroke
				(width 0.1)
				(type default)
			)
			(layer "F.Fab")
		)
		(fp_line
			(start 1.1049 -0.724916)
			(end -1.1049 -0.724916)
			(stroke
				(width 0.1)
				(type default)
			)
			(layer "F.Fab")
		)
		(fp_line
			(start 1.1049 0.724916)
			(end 1.1049 -0.724916)
			(stroke
				(width 0.1)
				(type default)
			)
			(layer "F.Fab")
		)
		(pad "1" smd rect
			(at -0.889 0 180)
			(size 1.016 1.27)
			(layers "F.Cu" "F.Mask" "F.Paste")
			(net "PVCCIN_CPU1")
		)
		(pad "2" smd rect
			(at 0.889 0 180)
			(size 1.016 1.27)
			(layers "F.Cu" "F.Mask" "F.Paste")
			(net "GND")
		)
	)
	(footprint ""
		(layer "F.Cu")
		(at 70.382892 -47.049944)
		(property "Reference" "H31"
			(at -1.7272 -4.511548 0)
			(unlocked yes)
			(layer "B.SilkS")
			(effects
				(font
					(size 0.7874 0.5842)
					(thickness 0.1524)
				)
				(justify left mirror)
			)
		)
		(property "Value" ""
			(at 0 0 0)
			(layer "F.Fab")
			(effects
				(font
					(size 1.27 1.27)
				)
			)
		)
		(duplicate_pad_numbers_are_jumpers no)
		(pad "1" thru_hole circle
			(at 0 0)
			(size 4.5212 4.5212)
			(drill 3.81)
			(layers "*.Cu" "*.Mask")
			(remove_unused_layers no)
			(net "GND")
			(clearance -0.1016)
			(padstack
				(mode front_inner_back)
				(layer "Inner"
					(shape circle)
					(size 5.6134 5.6134)
					(clearance -0.6477)
				)
				(layer "B.Cu"
					(shape circle)
					(size 8.001 8.001)
					(clearance -1.8415)
				)
			)
		)
	)
	(footprint ""
		(layer "F.Cu")
		(at 55.090314 -144.267174)
		(property "Reference" "PC2949"
			(at 0 0 0)
			(layer "F.SilkS")
			(hide yes)
			(effects
				(font
					(size 1.27 1.27)
				)
			)
		)
		(property "Value" ""
			(at 0 0 0)
			(layer "F.Fab")
			(effects
				(font
					(size 1.27 1.27)
				)
			)
		)
		(duplicate_pad_numbers_are_jumpers no)
		(fp_line
			(start -0.7874 -0.4064)
			(end 0.7874 -0.4064)
			(stroke
				(width 0.1524)
				(type default)
			)
			(layer "F.SilkS")
		)
		(fp_line
			(start -0.7874 0.4064)
			(end -0.7874 -0.4064)
			(stroke
				(width 0.1524)
				(type default)
			)
			(layer "F.SilkS")
		)
		(fp_line
			(start 0.7874 -0.4064)
			(end 0.7874 0.4064)
			(stroke
				(width 0.1524)
				(type default)
			)
			(layer "F.SilkS")
		)
		(fp_line
			(start 0.7874 0.4064)
			(end -0.7874 0.4064)
			(stroke
				(width 0.1524)
				(type default)
			)
			(layer "F.SilkS")
		)
		(fp_line
			(start -0.67945 -0.305054)
			(end -0.12065 -0.305054)
			(stroke
				(width 0.1)
				(type default)
			)
			(layer "F.Fab")
		)
		(fp_line
			(start -0.67945 0.3048)
			(end -0.67945 -0.305054)
			(stroke
				(width 0.1)
				(type default)
			)
			(layer "F.Fab")
		)
		(fp_line
			(start -0.12065 -0.305054)
			(end -0.12065 -0.2794)
			(stroke
				(width 0.1)
				(type default)
			)
			(layer "F.Fab")
		)
		(fp_line
			(start -0.12065 -0.2794)
			(end 0.12065 -0.2794)
			(stroke
				(width 0.1)
				(type default)
			)
			(layer "F.Fab")
		)
		(fp_line
			(start -0.12065 0.2794)
			(end -0.12065 0.3048)
			(stroke
				(width 0.1)
				(type default)
			)
			(layer "F.Fab")
		)
		(fp_line
			(start -0.12065 0.3048)
			(end -0.67945 0.3048)
			(stroke
				(width 0.1)
				(type default)
			)
			(layer "F.Fab")
		)
		(fp_line
			(start 0.120396 0.2794)
			(end -0.12065 0.2794)
			(stroke
				(width 0.1)
				(type default)
			)
			(layer "F.Fab")
		)
		(fp_line
			(start 0.120396 0.3048)
			(end 0.120396 0.2794)
			(stroke
				(width 0.1)
				(type default)
			)
			(layer "F.Fab")
		)
		(fp_line
			(start 0.12065 -0.3048)
			(end 0.67945 -0.3048)
			(stroke
				(width 0.1)
				(type default)
			)
			(layer "F.Fab")
		)
		(fp_line
			(start 0.12065 -0.2794)
			(end 0.12065 -0.3048)
			(stroke
				(width 0.1)
				(type default)
			)
			(layer "F.Fab")
		)
		(fp_line
			(start 0.67945 -0.3048)
			(end 0.67945 0.3048)
			(stroke
				(width 0.1)
				(type default)
			)
			(layer "F.Fab")
		)
		(fp_line
			(start 0.67945 0.3048)
			(end 0.120396 0.3048)
			(stroke
				(width 0.1)
				(type default)
			)
			(layer "F.Fab")
		)
		(pad "1" smd circle
			(at -0.40005 0)
			(size 0 0)
			(layers "F.Cu" "F.Mask" "F.Paste")
			(net "PVCCFA_EHV_CPU1_PVCC")
		)
		(pad "2" smd circle
			(at 0.40005 0)
			(size 0 0)
			(layers "F.Cu" "F.Mask" "F.Paste")
			(net "GND")
		)
	)
	(footprint ""
		(layer "F.Cu")
		(at 314.03544 -62.060328 180)
		(property "Reference" "R4564"
			(at 0 0 180)
			(layer "F.SilkS")
			(hide yes)
			(effects
				(font
					(size 1.27 1.27)
				)
			)
		)
		(property "Value" ""
			(at 0 0 180)
			(layer "F.Fab")
			(effects
				(font
					(size 1.27 1.27)
				)
			)
		)
		(duplicate_pad_numbers_are_jumpers no)
		(fp_line
			(start 0.7874 0.4064)
			(end -0.7874 0.4064)
			(stroke
				(width 0.1524)
				(type default)
			)
			(layer "F.SilkS")
		)
		(fp_line
			(start 0.7874 -0.4064)
			(end 0.7874 0.4064)
			(stroke
				(width 0.1524)
				(type default)
			)
			(layer "F.SilkS")
		)
		(fp_line
			(start -0.7874 0.4064)
			(end -0.7874 -0.4064)
			(stroke
				(width 0.1524)
				(type default)
			)
			(layer "F.SilkS")
		)
		(fp_line
			(start -0.7874 -0.4064)
			(end 0.7874 -0.4064)
			(stroke
				(width 0.1524)
				(type default)
			)
			(layer "F.SilkS")
		)
		(fp_line
			(start 0.67945 0.3048)
			(end 0.120396 0.3048)
			(stroke
				(width 0.1)
				(type default)
			)
			(layer "F.Fab")
		)
		(fp_line
			(start 0.67945 -0.3048)
			(end 0.67945 0.3048)
			(stroke
				(width 0.1)
				(type default)
			)
			(layer "F.Fab")
		)
		(fp_line
			(start 0.12065 -0.2794)
			(end 0.12065 -0.3048)
			(stroke
				(width 0.1)
				(type default)
			)
			(layer "F.Fab")
		)
		(fp_line
			(start 0.12065 -0.3048)
			(end 0.67945 -0.3048)
			(stroke
				(width 0.1)
				(type default)
			)
			(layer "F.Fab")
		)
		(fp_line
			(start 0.120396 0.3048)
			(end 0.120396 0.2794)
			(stroke
				(width 0.1)
				(type default)
			)
			(layer "F.Fab")
		)
		(fp_line
			(start 0.120396 0.2794)
			(end -0.12065 0.2794)
			(stroke
				(width 0.1)
				(type default)
			)
			(layer "F.Fab")
		)
		(fp_line
			(start -0.12065 0.3048)
			(end -0.67945 0.3048)
			(stroke
				(width 0.1)
				(type default)
			)
			(layer "F.Fab")
		)
		(fp_line
			(start -0.12065 0.2794)
			(end -0.12065 0.3048)
			(stroke
				(width 0.1)
				(type default)
			)
			(layer "F.Fab")
		)
		(fp_line
			(start -0.12065 -0.2794)
			(end 0.12065 -0.2794)
			(stroke
				(width 0.1)
				(type default)
			)
			(layer "F.Fab")
		)
		(fp_line
			(start -0.12065 -0.305054)
			(end -0.12065 -0.2794)
			(stroke
				(width 0.1)
				(type default)
			)
			(layer "F.Fab")
		)
		(fp_line
			(start -0.67945 0.3048)
			(end -0.67945 -0.305054)
			(stroke
				(width 0.1)
				(type default)
			)
			(layer "F.Fab")
		)
		(fp_line
			(start -0.67945 -0.305054)
			(end -0.12065 -0.305054)
			(stroke
				(width 0.1)
				(type default)
			)
			(layer "F.Fab")
		)
		(pad "1" smd circle
			(at -0.40005 0 180)
			(size 0 0)
			(layers "F.Cu" "F.Mask" "F.Paste")
			(net "PD_GPP_I_14")
		)
		(pad "2" smd circle
			(at 0.40005 0 180)
			(size 0 0)
			(layers "F.Cu" "F.Mask" "F.Paste")
			(net "GND")
		)
	)
	(footprint ""
		(layer "F.Cu")
		(at 288.305748 -258.091686)
		(property "Reference" "J3"
			(at -3.683 -81.702148 0)
			(unlocked yes)
			(layer "F.SilkS")
			(effects
				(font
					(size 0.7874 0.5842)
					(thickness 0.1524)
				)
				(justify left)
			)
		)
		(property "Value" ""
			(at 0 0 0)
			(layer "F.Fab")
			(effects
				(font
					(size 1.27 1.27)
				)
			)
		)
		(duplicate_pad_numbers_are_jumpers no)
		(fp_line
			(start -3.24993 -81.000092)
			(end -3.24993 81.000092)
			(stroke
				(width 0.1524)
				(type default)
			)
			(layer "F.SilkS")
		)
		(fp_line
			(start -3.24993 81.000092)
			(end 3.24993 81.000092)
			(stroke
				(width 0.1524)
				(type default)
			)
			(layer "F.SilkS")
		)
		(fp_line
			(start 3.24993 -81.000092)
			(end -3.24993 -81.000092)
			(stroke
				(width 0.1524)
				(type default)
			)
			(layer "F.SilkS")
		)
		(fp_line
			(start 3.24993 -72.00011)
			(end -3.24993 -72.00011)
			(stroke
				(width 0.1524)
				(type default)
			)
			(layer "F.SilkS")
		)
		(fp_line
			(start 3.24993 72.00011)
			(end -3.24993 72.00011)
			(stroke
				(width 0.1524)
				(type default)
			)
			(layer "F.SilkS")
		)
		(fp_line
			(start 3.24993 81.000092)
			(end 3.24993 -81.000092)
			(stroke
				(width 0.1524)
				(type default)
			)
			(layer "F.SilkS")
		)
		(fp_poly
			(pts
				(xy -4.195064 -63.828422) (xy -3.323336 -63.392558) (xy -4.195064 -62.956694)
			)
			(stroke
				(width 0)
				(type default)
			)
			(fill yes)
			(layer "F.SilkS")
		)
		(fp_line
			(start -3.24993 -81.000092)
			(end -3.24993 81.000092)
			(stroke
				(width 0.1)
				(type default)
			)
			(layer "F.Fab")
		)
		(fp_line
			(start -3.24993 81.000092)
			(end 3.24993 81.000092)
			(stroke
				(width 0.1)
				(type default)
			)
			(layer "F.Fab")
		)
		(fp_line
			(start 3.24993 -81.000092)
			(end -3.24993 -81.000092)
			(stroke
				(width 0.1)
				(type default)
			)
			(layer "F.Fab")
		)
		(fp_line
			(start 3.24993 -72.00011)
			(end -3.24993 -72.00011)
			(stroke
				(width 0.1)
				(type default)
			)
			(layer "F.Fab")
		)
		(fp_line
			(start 3.24993 -71.000112)
			(end -3.24993 -71.000112)
			(stroke
				(width 0.1)
				(type default)
			)
			(layer "F.Fab")
		)
		(fp_line
			(start 3.24993 71.000112)
			(end -3.24993 71.000112)
			(stroke
				(width 0.1)
				(type default)
			)
			(layer "F.Fab")
		)
		(fp_line
			(start 3.24993 72.00011)
			(end -3.24993 72.00011)
			(stroke
				(width 0.1)
				(type default)
			)
			(layer "F.Fab")
		)
		(fp_line
			(start 3.24993 81.000092)
			(end 3.24993 -81.000092)
			(stroke
				(width 0.1)
				(type default)
			)
			(layer "F.Fab")
		)
		(fp_poly
			(pts
				(xy -4.445 -63.832994) (xy -4.445 -62.816994) (xy -3.429 -63.324994)
			)
			(stroke
				(width 0)
				(type default)
			)
			(fill yes)
			(layer "F.Fab")
		)
		(pad "1" smd rect
			(at -2.050034 -63.324994 270)
			(size 0.519938 1.4986)
			(layers "F.Cu" "F.Mask" "F.Paste")
			(net "P12V_S3_AUX_CPU0_NVDIMM")
		)
		(pad "2" smd rect
			(at -2.050034 -62.47511 270)
			(size 0.519938 1.4986)
			(layers "F.Cu" "F.Mask" "F.Paste")
			(net "TP_CHB_CPU0_DIMM1_FRU_0")
		)
		(pad "3" smd rect
			(at -2.050034 -61.624972 270)
			(size 0.519938 1.4986)
			(layers "F.Cu" "F.Mask" "F.Paste")
			(net "P3V3_AUX")
		)
		(pad "4" smd rect
			(at -2.050034 -60.775088 270)
			(size 0.519938 1.4986)
			(layers "F.Cu" "F.Mask" "F.Paste")
			(net "I3C_SPD_DDRABCD_CPU0_LVC1_SCL_2")
		)
		(pad "5" smd rect
			(at -2.050034 -59.92495 270)
			(size 0.519938 1.4986)
			(layers "F.Cu" "F.Mask" "F.Paste")
			(net "I3C_SPD_DDRABCD_CPU0_LVC1_SDA")
		)
		(pad "6" smd rect
			(at -2.050034 -59.075066 270)
			(size 0.519938 1.4986)
			(layers "F.Cu" "F.Mask" "F.Paste")
			(net "GND")
		)
		(pad "7" smd rect
			(at -2.050034 -58.224928 270)
			(size 0.519938 1.4986)
			(layers "F.Cu" "F.Mask" "F.Paste")
			(net "M_B_CPU0_SA_DQ<0>")
		)
		(pad "8" smd rect
			(at -2.050034 -57.375044 270)
			(size 0.519938 1.4986)
			(layers "F.Cu" "F.Mask" "F.Paste")
			(net "GND")
		)
		(pad "9" smd rect
			(at -2.050034 -56.524906 270)
			(size 0.519938 1.4986)
			(layers "F.Cu" "F.Mask" "F.Paste")
			(net "M_B_CPU0_SA_DQ<1>")
		)
		(pad "10" smd rect
			(at -2.050034 -55.675022 270)
			(size 0.519938 1.4986)
			(layers "F.Cu" "F.Mask" "F.Paste")
			(net "GND")
		)
		(pad "11" smd rect
			(at -2.050034 -54.824884 270)
			(size 0.519938 1.4986)
			(layers "F.Cu" "F.Mask" "F.Paste")
			(net "M_B_CPU0_SA_DQS_DP<0>")
		)
		(pad "12" smd rect
			(at -2.050034 -53.975 270)
			(size 0.519938 1.4986)
			(layers "F.Cu" "F.Mask" "F.Paste")
			(net "M_B_CPU0_SA_DQS_DN<0>")
		)
		(pad "13" smd rect
			(at -2.050034 -53.125116 270)
			(size 0.519938 1.4986)
			(layers "F.Cu" "F.Mask" "F.Paste")
			(net "GND")
		)
		(pad "14" smd rect
			(at -2.050034 -52.274978 270)
			(size 0.519938 1.4986)
			(layers "F.Cu" "F.Mask" "F.Paste")
			(net "M_B_CPU0_SA_DQ<4>")
		)
		(pad "15" smd rect
			(at -2.050034 -51.425094 270)
			(size 0.519938 1.4986)
			(layers "F.Cu" "F.Mask" "F.Paste")
			(net "GND")
		)
		(pad "16" smd rect
			(at -2.050034 -50.574956 270)
			(size 0.519938 1.4986)
			(layers "F.Cu" "F.Mask" "F.Paste")
			(net "M_B_CPU0_SA_DQ<5>")
		)
		(pad "17" smd rect
			(at -2.050034 -49.725072 270)
			(size 0.519938 1.4986)
			(layers "F.Cu" "F.Mask" "F.Paste")
			(net "GND")
		)
		(pad "18" smd rect
			(at -2.050034 -48.874934 270)
			(size 0.519938 1.4986)
			(layers "F.Cu" "F.Mask" "F.Paste")
			(net "M_B_CPU0_SA_DQ<8>")
		)
		(pad "19" smd rect
			(at -2.050034 -48.02505 270)
			(size 0.519938 1.4986)
			(layers "F.Cu" "F.Mask" "F.Paste")
			(net "GND")
		)
		(pad "20" smd rect
			(at -2.050034 -47.174912 270)
			(size 0.519938 1.4986)
			(layers "F.Cu" "F.Mask" "F.Paste")
			(net "M_B_CPU0_SA_DQ<9>")
		)
		(pad "21" smd rect
			(at -2.050034 -46.325028 270)
			(size 0.519938 1.4986)
			(layers "F.Cu" "F.Mask" "F.Paste")
			(net "GND")
		)
		(pad "22" smd rect
			(at -2.050034 -45.47489 270)
			(size 0.519938 1.4986)
			(layers "F.Cu" "F.Mask" "F.Paste")
			(net "M_B_CPU0_SA_DQS_DP<1>")
		)
		(pad "23" smd rect
			(at -2.050034 -44.625006 270)
			(size 0.519938 1.4986)
			(layers "F.Cu" "F.Mask" "F.Paste")
			(net "M_B_CPU0_SA_DQS_DN<1>")
		)
		(pad "24" smd rect
			(at -2.050034 -43.775122 270)
			(size 0.519938 1.4986)
			(layers "F.Cu" "F.Mask" "F.Paste")
			(net "GND")
		)
		(pad "25" smd rect
			(at -2.050034 -42.924984 270)
			(size 0.519938 1.4986)
			(layers "F.Cu" "F.Mask" "F.Paste")
			(net "M_B_CPU0_SA_DQ<12>")
		)
		(pad "26" smd rect
			(at -2.050034 -42.0751 270)
			(size 0.519938 1.4986)
			(layers "F.Cu" "F.Mask" "F.Paste")
			(net "GND")
		)
		(pad "27" smd rect
			(at -2.050034 -41.224962 270)
			(size 0.519938 1.4986)
			(layers "F.Cu" "F.Mask" "F.Paste")
			(net "M_B_CPU0_SA_DQ<13>")
		)
		(pad "28" smd rect
			(at -2.050034 -40.375078 270)
			(size 0.519938 1.4986)
			(layers "F.Cu" "F.Mask" "F.Paste")
			(net "GND")
		)
		(pad "29" smd rect
			(at -2.050034 -39.52494 270)
			(size 0.519938 1.4986)
			(layers "F.Cu" "F.Mask" "F.Paste")
			(net "M_B_CPU0_SA_DQ<16>")
		)
		(pad "30" smd rect
			(at -2.050034 -38.675056 270)
			(size 0.519938 1.4986)
			(layers "F.Cu" "F.Mask" "F.Paste")
			(net "GND")
		)
		(pad "31" smd rect
			(at -2.050034 -37.824918 270)
			(size 0.519938 1.4986)
			(layers "F.Cu" "F.Mask" "F.Paste")
			(net "M_B_CPU0_SA_DQ<17>")
		)
		(pad "32" smd rect
			(at -2.050034 -36.975034 270)
			(size 0.519938 1.4986)
			(layers "F.Cu" "F.Mask" "F.Paste")
			(net "GND")
		)
		(pad "33" smd rect
			(at -2.050034 -36.124896 270)
			(size 0.519938 1.4986)
			(layers "F.Cu" "F.Mask" "F.Paste")
			(net "M_B_CPU0_SA_DQS_DP<2>")
		)
		(pad "34" smd rect
			(at -2.050034 -35.275012 270)
			(size 0.519938 1.4986)
			(layers "F.Cu" "F.Mask" "F.Paste")
			(net "M_B_CPU0_SA_DQS_DN<2>")
		)
		(pad "35" smd rect
			(at -2.050034 -34.425128 270)
			(size 0.519938 1.4986)
			(layers "F.Cu" "F.Mask" "F.Paste")
			(net "GND")
		)
		(pad "36" smd rect
			(at -2.050034 -33.57499 270)
			(size 0.519938 1.4986)
			(layers "F.Cu" "F.Mask" "F.Paste")
			(net "M_B_CPU0_SA_DQ<20>")
		)
		(pad "37" smd rect
			(at -2.050034 -32.725106 270)
			(size 0.519938 1.4986)
			(layers "F.Cu" "F.Mask" "F.Paste")
			(net "GND")
		)
		(pad "38" smd rect
			(at -2.050034 -31.874968 270)
			(size 0.519938 1.4986)
			(layers "F.Cu" "F.Mask" "F.Paste")
			(net "M_B_CPU0_SA_DQ<21>")
		)
		(pad "39" smd rect
			(at -2.050034 -31.025084 270)
			(size 0.519938 1.4986)
			(layers "F.Cu" "F.Mask" "F.Paste")
			(net "GND")
		)
		(pad "40" smd rect
			(at -2.050034 -30.174946 270)
			(size 0.519938 1.4986)
			(layers "F.Cu" "F.Mask" "F.Paste")
			(net "M_B_CPU0_SA_DQ<24>")
		)
		(pad "41" smd rect
			(at -2.050034 -29.325062 270)
			(size 0.519938 1.4986)
			(layers "F.Cu" "F.Mask" "F.Paste")
			(net "GND")
		)
		(pad "42" smd rect
			(at -2.050034 -28.474924 270)
			(size 0.519938 1.4986)
			(layers "F.Cu" "F.Mask" "F.Paste")
			(net "M_B_CPU0_SA_DQ<25>")
		)
		(pad "43" smd rect
			(at -2.050034 -27.62504 270)
			(size 0.519938 1.4986)
			(layers "F.Cu" "F.Mask" "F.Paste")
			(net "GND")
		)
		(pad "44" smd rect
			(at -2.050034 -26.774902 270)
			(size 0.519938 1.4986)
			(layers "F.Cu" "F.Mask" "F.Paste")
			(net "M_B_CPU0_SA_DQS_DP<3>")
		)
		(pad "45" smd rect
			(at -2.050034 -25.925018 270)
			(size 0.519938 1.4986)
			(layers "F.Cu" "F.Mask" "F.Paste")
			(net "M_B_CPU0_SA_DQS_DN<3>")
		)
		(pad "46" smd rect
			(at -2.050034 -25.07488 270)
			(size 0.519938 1.4986)
			(layers "F.Cu" "F.Mask" "F.Paste")
			(net "GND")
		)
		(pad "47" smd rect
			(at -2.050034 -24.224996 270)
			(size 0.519938 1.4986)
			(layers "F.Cu" "F.Mask" "F.Paste")
			(net "M_B_CPU0_SA_DQ<28>")
		)
		(pad "48" smd rect
			(at -2.050034 -23.375112 270)
			(size 0.519938 1.4986)
			(layers "F.Cu" "F.Mask" "F.Paste")
			(net "GND")
		)
		(pad "49" smd rect
			(at -2.050034 -22.524974 270)
			(size 0.519938 1.4986)
			(layers "F.Cu" "F.Mask" "F.Paste")
			(net "M_B_CPU0_SA_DQ<29>")
		)
		(pad "50" smd rect
			(at -2.050034 -21.67509 270)
			(size 0.519938 1.4986)
			(layers "F.Cu" "F.Mask" "F.Paste")
			(net "GND")
		)
		(pad "51" smd rect
			(at -2.050034 -20.824952 270)
			(size 0.519938 1.4986)
			(layers "F.Cu" "F.Mask" "F.Paste")
			(net "M_B_CPU0_SA_CB<0>")
		)
		(pad "52" smd rect
			(at -2.050034 -19.975068 270)
			(size 0.519938 1.4986)
			(layers "F.Cu" "F.Mask" "F.Paste")
			(net "GND")
		)
		(pad "53" smd rect
			(at -2.050034 -19.12493 270)
			(size 0.519938 1.4986)
			(layers "F.Cu" "F.Mask" "F.Paste")
			(net "M_B_CPU0_SA_CB<1>")
		)
		(pad "54" smd rect
			(at -2.050034 -18.275046 270)
			(size 0.519938 1.4986)
			(layers "F.Cu" "F.Mask" "F.Paste")
			(net "GND")
		)
		(pad "55" smd rect
			(at -2.050034 -17.424908 270)
			(size 0.519938 1.4986)
			(layers "F.Cu" "F.Mask" "F.Paste")
			(net "M_B_CPU0_SA_DQS_DP<4>")
		)
		(pad "56" smd rect
			(at -2.050034 -16.575024 270)
			(size 0.519938 1.4986)
			(layers "F.Cu" "F.Mask" "F.Paste")
			(net "M_B_CPU0_SA_DQS_DN<4>")
		)
		(pad "57" smd rect
			(at -2.050034 -15.724886 270)
			(size 0.519938 1.4986)
			(layers "F.Cu" "F.Mask" "F.Paste")
			(net "GND")
		)
		(pad "58" smd rect
			(at -2.050034 -14.875002 270)
			(size 0.519938 1.4986)
			(layers "F.Cu" "F.Mask" "F.Paste")
			(net "M_B_CPU0_SA_CB<4>")
		)
		(pad "59" smd rect
			(at -2.050034 -14.025118 270)
			(size 0.519938 1.4986)
			(layers "F.Cu" "F.Mask" "F.Paste")
			(net "GND")
		)
		(pad "60" smd rect
			(at -2.050034 -13.17498 270)
			(size 0.519938 1.4986)
			(layers "F.Cu" "F.Mask" "F.Paste")
			(net "M_B_CPU0_SA_CB<5>")
		)
		(pad "61" smd rect
			(at -2.050034 -12.325096 270)
			(size 0.519938 1.4986)
			(layers "F.Cu" "F.Mask" "F.Paste")
			(net "GND")
		)
		(pad "62" smd rect
			(at -2.050034 -11.474958 270)
			(size 0.519938 1.4986)
			(layers "F.Cu" "F.Mask" "F.Paste")
			(net "M_B_CPU0_ALERT_N")
		)
		(pad "63" smd rect
			(at -2.050034 -10.625074 270)
			(size 0.519938 1.4986)
			(layers "F.Cu" "F.Mask" "F.Paste")
			(net "GND")
		)
		(pad "64" smd rect
			(at -2.050034 -9.774936 270)
			(size 0.519938 1.4986)
			(layers "F.Cu" "F.Mask" "F.Paste")
			(net "M_B_CPU0_SA_CS_N<0>")
		)
		(pad "65" smd rect
			(at -2.050034 -8.925052 270)
			(size 0.519938 1.4986)
			(layers "F.Cu" "F.Mask" "F.Paste")
			(net "GND")
		)
		(pad "66" smd rect
			(at -2.050034 -8.074914 270)
			(size 0.519938 1.4986)
			(layers "F.Cu" "F.Mask" "F.Paste")
			(net "M_B_CPU0_SA_CA<0>")
		)
		(pad "67" smd rect
			(at -2.050034 -7.22503 270)
			(size 0.519938 1.4986)
			(layers "F.Cu" "F.Mask" "F.Paste")
			(net "GND")
		)
		(pad "68" smd rect
			(at -2.050034 -6.374892 270)
			(size 0.519938 1.4986)
			(layers "F.Cu" "F.Mask" "F.Paste")
			(net "M_B_CPU0_SA_CA<2>")
		)
		(pad "69" smd rect
			(at -2.050034 -5.525008 270)
			(size 0.519938 1.4986)
			(layers "F.Cu" "F.Mask" "F.Paste")
			(net "GND")
		)
		(pad "70" smd rect
			(at -2.050034 -4.675124 270)
			(size 0.519938 1.4986)
			(layers "F.Cu" "F.Mask" "F.Paste")
			(net "M_B_CPU0_SA_CA<4>")
		)
		(pad "71" smd rect
			(at -2.050034 -3.824986 270)
			(size 0.519938 1.4986)
			(layers "F.Cu" "F.Mask" "F.Paste")
			(net "GND")
		)
		(pad "72" smd rect
			(at -2.050034 -2.975102 270)
			(size 0.519938 1.4986)
			(layers "F.Cu" "F.Mask" "F.Paste")
			(net "M_B_CPU0_SA_CA<6>")
		)
		(pad "73" smd rect
			(at -2.050034 -2.124964 270)
			(size 0.519938 1.4986)
			(layers "F.Cu" "F.Mask" "F.Paste")
			(net "GND")
		)
		(pad "74" smd rect
			(at -2.050034 -1.27508 270)
			(size 0.519938 1.4986)
			(layers "F.Cu" "F.Mask" "F.Paste")
			(net "M_B_CPU0_SA_PAR")
		)
		(pad "75" smd rect
			(at -2.050034 -0.424942 270)
			(size 0.519938 1.4986)
			(layers "F.Cu" "F.Mask" "F.Paste")
			(net "GND")
		)
		(pad "76" smd rect
			(at -2.050034 5.525008 270)
			(size 0.519938 1.4986)
			(layers "F.Cu" "F.Mask" "F.Paste")
			(net "M_B_CPU0_SB_CA<0>")
		)
		(pad "77" smd rect
			(at -2.050034 6.374892 270)
			(size 0.519938 1.4986)
			(layers "F.Cu" "F.Mask" "F.Paste")
			(net "GND")
		)
		(pad "78" smd rect
			(at -2.050034 7.22503 270)
			(size 0.519938 1.4986)
			(layers "F.Cu" "F.Mask" "F.Paste")
			(net "M_B_CPU0_SB_CA<2>")
		)
		(pad "79" smd rect
			(at -2.050034 8.074914 270)
			(size 0.519938 1.4986)
			(layers "F.Cu" "F.Mask" "F.Paste")
			(net "GND")
		)
		(pad "80" smd rect
			(at -2.050034 8.925052 270)
			(size 0.519938 1.4986)
			(layers "F.Cu" "F.Mask" "F.Paste")
			(net "M_B_CPU0_SB_CA<4>")
		)
		(pad "81" smd rect
			(at -2.050034 9.774936 270)
			(size 0.519938 1.4986)
			(layers "F.Cu" "F.Mask" "F.Paste")
			(net "GND")
		)
		(pad "82" smd rect
			(at -2.050034 10.625074 270)
			(size 0.519938 1.4986)
			(layers "F.Cu" "F.Mask" "F.Paste")
			(net "M_B_CPU0_SB_CA<6>")
		)
		(pad "83" smd rect
			(at -2.050034 11.474958 270)
			(size 0.519938 1.4986)
			(layers "F.Cu" "F.Mask" "F.Paste")
			(net "GND")
		)
		(pad "84" smd rect
			(at -2.050034 12.325096 270)
			(size 0.519938 1.4986)
			(layers "F.Cu" "F.Mask" "F.Paste")
			(net "M_B_CPU0_SB_CS_N<0>")
		)
		(pad "85" smd rect
			(at -2.050034 13.17498 270)
			(size 0.519938 1.4986)
			(layers "F.Cu" "F.Mask" "F.Paste")
			(net "GND")
		)
		(pad "86" smd rect
			(at -2.050034 14.025118 270)
			(size 0.519938 1.4986)
			(layers "F.Cu" "F.Mask" "F.Paste")
			(net "M_B_CPU0_SA_RSP<0>")
		)
		(pad "87" smd rect
			(at -2.050034 14.875002 270)
			(size 0.519938 1.4986)
			(layers "F.Cu" "F.Mask" "F.Paste")
			(net "M_B_CPU0_SB_RSP<0>")
		)
		(pad "88" smd rect
			(at -2.050034 15.724886 270)
			(size 0.519938 1.4986)
			(layers "F.Cu" "F.Mask" "F.Paste")
			(net "GND")
		)
		(pad "89" smd rect
			(at -2.050034 16.575024 270)
			(size 0.519938 1.4986)
			(layers "F.Cu" "F.Mask" "F.Paste")
			(net "M_B_CPU0_SB_CB<4>")
		)
		(pad "90" smd rect
			(at -2.050034 17.424908 270)
			(size 0.519938 1.4986)
			(layers "F.Cu" "F.Mask" "F.Paste")
			(net "GND")
		)
		(pad "91" smd rect
			(at -2.050034 18.275046 270)
			(size 0.519938 1.4986)
			(layers "F.Cu" "F.Mask" "F.Paste")
			(net "M_B_CPU0_SB_CB<5>")
		)
		(pad "92" smd rect
			(at -2.050034 19.12493 270)
			(size 0.519938 1.4986)
			(layers "F.Cu" "F.Mask" "F.Paste")
			(net "GND")
		)
		(pad "93" smd rect
			(at -2.050034 19.975068 270)
			(size 0.519938 1.4986)
			(layers "F.Cu" "F.Mask" "F.Paste")
			(net "M_B_CPU0_SB_DQS_DP<9>")
		)
		(pad "94" smd rect
			(at -2.050034 20.824952 270)
			(size 0.519938 1.4986)
			(layers "F.Cu" "F.Mask" "F.Paste")
			(net "M_B_CPU0_SB_DQS_DN<9>")
		)
		(pad "95" smd rect
			(at -2.050034 21.67509 270)
			(size 0.519938 1.4986)
			(layers "F.Cu" "F.Mask" "F.Paste")
			(net "GND")
		)
		(pad "96" smd rect
			(at -2.050034 22.524974 270)
			(size 0.519938 1.4986)
			(layers "F.Cu" "F.Mask" "F.Paste")
			(net "M_B_CPU0_SB_CB<0>")
		)
		(pad "97" smd rect
			(at -2.050034 23.375112 270)
			(size 0.519938 1.4986)
			(layers "F.Cu" "F.Mask" "F.Paste")
			(net "GND")
		)
		(pad "98" smd rect
			(at -2.050034 24.224996 270)
			(size 0.519938 1.4986)
			(layers "F.Cu" "F.Mask" "F.Paste")
			(net "M_B_CPU0_SB_CB<1>")
		)
		(pad "99" smd rect
			(at -2.050034 25.07488 270)
			(size 0.519938 1.4986)
			(layers "F.Cu" "F.Mask" "F.Paste")
			(net "GND")
		)
		(pad "100" smd rect
			(at -2.050034 25.925018 270)
			(size 0.519938 1.4986)
			(layers "F.Cu" "F.Mask" "F.Paste")
			(net "M_B_CPU0_SB_DQ<0>")
		)
		(pad "101" smd rect
			(at -2.050034 26.774902 270)
			(size 0.519938 1.4986)
			(layers "F.Cu" "F.Mask" "F.Paste")
			(net "GND")
		)
		(pad "102" smd rect
			(at -2.050034 27.62504 270)
			(size 0.519938 1.4986)
			(layers "F.Cu" "F.Mask" "F.Paste")
			(net "M_B_CPU0_SB_DQ<1>")
		)
		(pad "103" smd rect
			(at -2.050034 28.474924 270)
			(size 0.519938 1.4986)
			(layers "F.Cu" "F.Mask" "F.Paste")
			(net "GND")
		)
		(pad "104" smd rect
			(at -2.050034 29.325062 270)
			(size 0.519938 1.4986)
			(layers "F.Cu" "F.Mask" "F.Paste")
			(net "M_B_CPU0_SB_DQS_DP<0>")
		)
		(pad "105" smd rect
			(at -2.050034 30.174946 270)
			(size 0.519938 1.4986)
			(layers "F.Cu" "F.Mask" "F.Paste")
			(net "M_B_CPU0_SB_DQS_DN<0>")
		)
		(pad "106" smd rect
			(at -2.050034 31.025084 270)
			(size 0.519938 1.4986)
			(layers "F.Cu" "F.Mask" "F.Paste")
			(net "GND")
		)
		(pad "107" smd rect
			(at -2.050034 31.874968 270)
			(size 0.519938 1.4986)
			(layers "F.Cu" "F.Mask" "F.Paste")
			(net "M_B_CPU0_SB_DQ<4>")
		)
		(pad "108" smd rect
			(at -2.050034 32.725106 270)
			(size 0.519938 1.4986)
			(layers "F.Cu" "F.Mask" "F.Paste")
			(net "GND")
		)
		(pad "109" smd rect
			(at -2.050034 33.57499 270)
			(size 0.519938 1.4986)
			(layers "F.Cu" "F.Mask" "F.Paste")
			(net "M_B_CPU0_SB_DQ<5>")
		)
		(pad "110" smd rect
			(at -2.050034 34.425128 270)
			(size 0.519938 1.4986)
			(layers "F.Cu" "F.Mask" "F.Paste")
			(net "GND")
		)
		(pad "111" smd rect
			(at -2.050034 35.275012 270)
			(size 0.519938 1.4986)
			(layers "F.Cu" "F.Mask" "F.Paste")
			(net "M_B_CPU0_SB_DQ<8>")
		)
		(pad "112" smd rect
			(at -2.050034 36.124896 270)
			(size 0.519938 1.4986)
			(layers "F.Cu" "F.Mask" "F.Paste")
			(net "GND")
		)
		(pad "113" smd rect
			(at -2.050034 36.975034 270)
			(size 0.519938 1.4986)
			(layers "F.Cu" "F.Mask" "F.Paste")
			(net "M_B_CPU0_SB_DQ<9>")
		)
		(pad "114" smd rect
			(at -2.050034 37.824918 270)
			(size 0.519938 1.4986)
			(layers "F.Cu" "F.Mask" "F.Paste")
			(net "GND")
		)
		(pad "115" smd rect
			(at -2.050034 38.675056 270)
			(size 0.519938 1.4986)
			(layers "F.Cu" "F.Mask" "F.Paste")
			(net "M_B_CPU0_SB_DQS_DP<1>")
		)
		(pad "116" smd rect
			(at -2.050034 39.52494 270)
			(size 0.519938 1.4986)
			(layers "F.Cu" "F.Mask" "F.Paste")
			(net "M_B_CPU0_SB_DQS_DN<1>")
		)
		(pad "117" smd rect
			(at -2.050034 40.375078 270)
			(size 0.519938 1.4986)
			(layers "F.Cu" "F.Mask" "F.Paste")
			(net "GND")
		)
		(pad "118" smd rect
			(at -2.050034 41.224962 270)
			(size 0.519938 1.4986)
			(layers "F.Cu" "F.Mask" "F.Paste")
			(net "M_B_CPU0_SB_DQ<12>")
		)
		(pad "119" smd rect
			(at -2.050034 42.0751 270)
			(size 0.519938 1.4986)
			(layers "F.Cu" "F.Mask" "F.Paste")
			(net "GND")
		)
		(pad "120" smd rect
			(at -2.050034 42.924984 270)
			(size 0.519938 1.4986)
			(layers "F.Cu" "F.Mask" "F.Paste")
			(net "M_B_CPU0_SB_DQ<13>")
		)
		(pad "121" smd rect
			(at -2.050034 43.775122 270)
			(size 0.519938 1.4986)
			(layers "F.Cu" "F.Mask" "F.Paste")
			(net "GND")
		)
		(pad "122" smd rect
			(at -2.050034 44.625006 270)
			(size 0.519938 1.4986)
			(layers "F.Cu" "F.Mask" "F.Paste")
			(net "M_B_CPU0_SB_DQ<16>")
		)
		(pad "123" smd rect
			(at -2.050034 45.47489 270)
			(size 0.519938 1.4986)
			(layers "F.Cu" "F.Mask" "F.Paste")
			(net "GND")
		)
		(pad "124" smd rect
			(at -2.050034 46.325028 270)
			(size 0.519938 1.4986)
			(layers "F.Cu" "F.Mask" "F.Paste")
			(net "M_B_CPU0_SB_DQ<17>")
		)
		(pad "125" smd rect
			(at -2.050034 47.174912 270)
			(size 0.519938 1.4986)
			(layers "F.Cu" "F.Mask" "F.Paste")
			(net "GND")
		)
		(pad "126" smd rect
			(at -2.050034 48.02505 270)
			(size 0.519938 1.4986)
			(layers "F.Cu" "F.Mask" "F.Paste")
			(net "M_B_CPU0_SB_DQS_DP<2>")
		)
		(pad "127" smd rect
			(at -2.050034 48.874934 270)
			(size 0.519938 1.4986)
			(layers "F.Cu" "F.Mask" "F.Paste")
			(net "M_B_CPU0_SB_DQS_DN<2>")
		)
		(pad "128" smd rect
			(at -2.050034 49.725072 270)
			(size 0.519938 1.4986)
			(layers "F.Cu" "F.Mask" "F.Paste")
			(net "GND")
		)
		(pad "129" smd rect
			(at -2.050034 50.574956 270)
			(size 0.519938 1.4986)
			(layers "F.Cu" "F.Mask" "F.Paste")
			(net "M_B_CPU0_SB_DQ<20>")
		)
		(pad "130" smd rect
			(at -2.050034 51.425094 270)
			(size 0.519938 1.4986)
			(layers "F.Cu" "F.Mask" "F.Paste")
			(net "GND")
		)
		(pad "131" smd rect
			(at -2.050034 52.274978 270)
			(size 0.519938 1.4986)
			(layers "F.Cu" "F.Mask" "F.Paste")
			(net "M_B_CPU0_SB_DQ<21>")
		)
		(pad "132" smd rect
			(at -2.050034 53.125116 270)
			(size 0.519938 1.4986)
			(layers "F.Cu" "F.Mask" "F.Paste")
			(net "GND")
		)
		(pad "133" smd rect
			(at -2.050034 53.975 270)
			(size 0.519938 1.4986)
			(layers "F.Cu" "F.Mask" "F.Paste")
			(net "M_B_CPU0_SB_DQ<24>")
		)
		(pad "134" smd rect
			(at -2.050034 54.824884 270)
			(size 0.519938 1.4986)
			(layers "F.Cu" "F.Mask" "F.Paste")
			(net "GND")
		)
		(pad "135" smd rect
			(at -2.050034 55.675022 270)
			(size 0.519938 1.4986)
			(layers "F.Cu" "F.Mask" "F.Paste")
			(net "M_B_CPU0_SB_DQ<25>")
		)
		(pad "136" smd rect
			(at -2.050034 56.524906 270)
			(size 0.519938 1.4986)
			(layers "F.Cu" "F.Mask" "F.Paste")
			(net "GND")
		)
		(pad "137" smd rect
			(at -2.050034 57.375044 270)
			(size 0.519938 1.4986)
			(layers "F.Cu" "F.Mask" "F.Paste")
			(net "M_B_CPU0_SB_DQS_DP<3>")
		)
		(pad "138" smd rect
			(at -2.050034 58.224928 270)
			(size 0.519938 1.4986)
			(layers "F.Cu" "F.Mask" "F.Paste")
			(net "M_B_CPU0_SB_DQS_DN<3>")
		)
		(pad "139" smd rect
			(at -2.050034 59.075066 270)
			(size 0.519938 1.4986)
			(layers "F.Cu" "F.Mask" "F.Paste")
			(net "GND")
		)
		(pad "140" smd rect
			(at -2.050034 59.92495 270)
			(size 0.519938 1.4986)
			(layers "F.Cu" "F.Mask" "F.Paste")
			(net "M_B_CPU0_SB_DQ<28>")
		)
		(pad "141" smd rect
			(at -2.050034 60.775088 270)
			(size 0.519938 1.4986)
			(layers "F.Cu" "F.Mask" "F.Paste")
			(net "GND")
		)
		(pad "142" smd rect
			(at -2.050034 61.624972 270)
			(size 0.519938 1.4986)
			(layers "F.Cu" "F.Mask" "F.Paste")
			(net "M_B_CPU0_SB_DQ<29>")
		)
		(pad "143" smd rect
			(at -2.050034 62.47511 270)
			(size 0.519938 1.4986)
			(layers "F.Cu" "F.Mask" "F.Paste")
			(net "GND")
		)
		(pad "144" smd rect
			(at -2.050034 63.324994 270)
			(size 0.519938 1.4986)
			(layers "F.Cu" "F.Mask" "F.Paste")
			(net "TP_CHB_CPU0_DIMM1_FRU_1")
		)
		(pad "145" smd rect
			(at 2.050034 -63.324994 270)
			(size 0.519938 1.4986)
			(layers "F.Cu" "F.Mask" "F.Paste")
			(net "P12V_S3_AUX_CPU0_NVDIMM")
		)
		(pad "146" smd rect
			(at 2.050034 -62.47511 270)
			(size 0.519938 1.4986)
			(layers "F.Cu" "F.Mask" "F.Paste")
			(net "P12V_S3_AUX_CPU0_NVDIMM")
		)
		(pad "147" smd rect
			(at 2.050034 -61.624972 270)
			(size 0.519938 1.4986)
			(layers "F.Cu" "F.Mask" "F.Paste")
			(net "PWRGD_CHB_CPU0_DIMM1")
		)
		(pad "148" smd rect
			(at 2.050034 -60.775088 270)
			(size 0.519938 1.4986)
			(layers "F.Cu" "F.Mask" "F.Paste")
			(net "PD_CHB_CPU0_DIMM1_SAA")
		)
		(pad "149" smd rect
			(at 2.050034 -59.92495 270)
			(size 0.519938 1.4986)
			(layers "F.Cu" "F.Mask" "F.Paste")
			(net "TP_CHB_CPU0_DIMM1_FRU_2")
		)
		(pad "150" smd rect
			(at 2.050034 -59.075066 270)
			(size 0.519938 1.4986)
			(layers "F.Cu" "F.Mask" "F.Paste")
			(net "TP_CHB_CPU0_DIMM1_FRU_3")
		)
		(pad "151" smd rect
			(at 2.050034 -58.224928 270)
			(size 0.519938 1.4986)
			(layers "F.Cu" "F.Mask" "F.Paste")
			(net "GND")
		)
		(pad "152" smd rect
			(at 2.050034 -57.375044 270)
			(size 0.519938 1.4986)
			(layers "F.Cu" "F.Mask" "F.Paste")
			(net "M_B_CPU0_SA_DQ<2>")
		)
		(pad "153" smd rect
			(at 2.050034 -56.524906 270)
			(size 0.519938 1.4986)
			(layers "F.Cu" "F.Mask" "F.Paste")
			(net "GND")
		)
		(pad "154" smd rect
			(at 2.050034 -55.675022 270)
			(size 0.519938 1.4986)
			(layers "F.Cu" "F.Mask" "F.Paste")
			(net "M_B_CPU0_SA_DQ<3>")
		)
		(pad "155" smd rect
			(at 2.050034 -54.824884 270)
			(size 0.519938 1.4986)
			(layers "F.Cu" "F.Mask" "F.Paste")
			(net "GND")
		)
		(pad "156" smd rect
			(at 2.050034 -53.975 270)
			(size 0.519938 1.4986)
			(layers "F.Cu" "F.Mask" "F.Paste")
			(net "M_B_CPU0_SA_DQS_DN<5>")
		)
		(pad "157" smd rect
			(at 2.050034 -53.125116 270)
			(size 0.519938 1.4986)
			(layers "F.Cu" "F.Mask" "F.Paste")
			(net "M_B_CPU0_SA_DQS_DP<5>")
		)
		(pad "158" smd rect
			(at 2.050034 -52.274978 270)
			(size 0.519938 1.4986)
			(layers "F.Cu" "F.Mask" "F.Paste")
			(net "GND")
		)
		(pad "159" smd rect
			(at 2.050034 -51.425094 270)
			(size 0.519938 1.4986)
			(layers "F.Cu" "F.Mask" "F.Paste")
			(net "M_B_CPU0_SA_DQ<6>")
		)
		(pad "160" smd rect
			(at 2.050034 -50.574956 270)
			(size 0.519938 1.4986)
			(layers "F.Cu" "F.Mask" "F.Paste")
			(net "GND")
		)
		(pad "161" smd rect
			(at 2.050034 -49.725072 270)
			(size 0.519938 1.4986)
			(layers "F.Cu" "F.Mask" "F.Paste")
			(net "M_B_CPU0_SA_DQ<7>")
		)
		(pad "162" smd rect
			(at 2.050034 -48.874934 270)
			(size 0.519938 1.4986)
			(layers "F.Cu" "F.Mask" "F.Paste")
			(net "GND")
		)
		(pad "163" smd rect
			(at 2.050034 -48.02505 270)
			(size 0.519938 1.4986)
			(layers "F.Cu" "F.Mask" "F.Paste")
			(net "M_B_CPU0_SA_DQ<10>")
		)
		(pad "164" smd rect
			(at 2.050034 -47.174912 270)
			(size 0.519938 1.4986)
			(layers "F.Cu" "F.Mask" "F.Paste")
			(net "GND")
		)
		(pad "165" smd rect
			(at 2.050034 -46.325028 270)
			(size 0.519938 1.4986)
			(layers "F.Cu" "F.Mask" "F.Paste")
			(net "M_B_CPU0_SA_DQ<11>")
		)
		(pad "166" smd rect
			(at 2.050034 -45.47489 270)
			(size 0.519938 1.4986)
			(layers "F.Cu" "F.Mask" "F.Paste")
			(net "GND")
		)
		(pad "167" smd rect
			(at 2.050034 -44.625006 270)
			(size 0.519938 1.4986)
			(layers "F.Cu" "F.Mask" "F.Paste")
			(net "M_B_CPU0_SA_DQS_DN<6>")
		)
		(pad "168" smd rect
			(at 2.050034 -43.775122 270)
			(size 0.519938 1.4986)
			(layers "F.Cu" "F.Mask" "F.Paste")
			(net "M_B_CPU0_SA_DQS_DP<6>")
		)
		(pad "169" smd rect
			(at 2.050034 -42.924984 270)
			(size 0.519938 1.4986)
			(layers "F.Cu" "F.Mask" "F.Paste")
			(net "GND")
		)
		(pad "170" smd rect
			(at 2.050034 -42.0751 270)
			(size 0.519938 1.4986)
			(layers "F.Cu" "F.Mask" "F.Paste")
			(net "M_B_CPU0_SA_DQ<14>")
		)
		(pad "171" smd rect
			(at 2.050034 -41.224962 270)
			(size 0.519938 1.4986)
			(layers "F.Cu" "F.Mask" "F.Paste")
			(net "GND")
		)
		(pad "172" smd rect
			(at 2.050034 -40.375078 270)
			(size 0.519938 1.4986)
			(layers "F.Cu" "F.Mask" "F.Paste")
			(net "M_B_CPU0_SA_DQ<15>")
		)
		(pad "173" smd rect
			(at 2.050034 -39.52494 270)
			(size 0.519938 1.4986)
			(layers "F.Cu" "F.Mask" "F.Paste")
			(net "GND")
		)
		(pad "174" smd rect
			(at 2.050034 -38.675056 270)
			(size 0.519938 1.4986)
			(layers "F.Cu" "F.Mask" "F.Paste")
			(net "M_B_CPU0_SA_DQ<18>")
		)
		(pad "175" smd rect
			(at 2.050034 -37.824918 270)
			(size 0.519938 1.4986)
			(layers "F.Cu" "F.Mask" "F.Paste")
			(net "GND")
		)
		(pad "176" smd rect
			(at 2.050034 -36.975034 270)
			(size 0.519938 1.4986)
			(layers "F.Cu" "F.Mask" "F.Paste")
			(net "M_B_CPU0_SA_DQ<19>")
		)
		(pad "177" smd rect
			(at 2.050034 -36.124896 270)
			(size 0.519938 1.4986)
			(layers "F.Cu" "F.Mask" "F.Paste")
			(net "GND")
		)
		(pad "178" smd rect
			(at 2.050034 -35.275012 270)
			(size 0.519938 1.4986)
			(layers "F.Cu" "F.Mask" "F.Paste")
			(net "M_B_CPU0_SA_DQS_DN<7>")
		)
		(pad "179" smd rect
			(at 2.050034 -34.425128 270)
			(size 0.519938 1.4986)
			(layers "F.Cu" "F.Mask" "F.Paste")
			(net "M_B_CPU0_SA_DQS_DP<7>")
		)
		(pad "180" smd rect
			(at 2.050034 -33.57499 270)
			(size 0.519938 1.4986)
			(layers "F.Cu" "F.Mask" "F.Paste")
			(net "GND")
		)
		(pad "181" smd rect
			(at 2.050034 -32.725106 270)
			(size 0.519938 1.4986)
			(layers "F.Cu" "F.Mask" "F.Paste")
			(net "M_B_CPU0_SA_DQ<22>")
		)
		(pad "182" smd rect
			(at 2.050034 -31.874968 270)
			(size 0.519938 1.4986)
			(layers "F.Cu" "F.Mask" "F.Paste")
			(net "GND")
		)
		(pad "183" smd rect
			(at 2.050034 -31.025084 270)
			(size 0.519938 1.4986)
			(layers "F.Cu" "F.Mask" "F.Paste")
			(net "M_B_CPU0_SA_DQ<23>")
		)
		(pad "184" smd rect
			(at 2.050034 -30.174946 270)
			(size 0.519938 1.4986)
			(layers "F.Cu" "F.Mask" "F.Paste")
			(net "GND")
		)
		(pad "185" smd rect
			(at 2.050034 -29.325062 270)
			(size 0.519938 1.4986)
			(layers "F.Cu" "F.Mask" "F.Paste")
			(net "M_B_CPU0_SA_DQ<26>")
		)
		(pad "186" smd rect
			(at 2.050034 -28.474924 270)
			(size 0.519938 1.4986)
			(layers "F.Cu" "F.Mask" "F.Paste")
			(net "GND")
		)
		(pad "187" smd rect
			(at 2.050034 -27.62504 270)
			(size 0.519938 1.4986)
			(layers "F.Cu" "F.Mask" "F.Paste")
			(net "M_B_CPU0_SA_DQ<27>")
		)
		(pad "188" smd rect
			(at 2.050034 -26.774902 270)
			(size 0.519938 1.4986)
			(layers "F.Cu" "F.Mask" "F.Paste")
			(net "GND")
		)
		(pad "189" smd rect
			(at 2.050034 -25.925018 270)
			(size 0.519938 1.4986)
			(layers "F.Cu" "F.Mask" "F.Paste")
			(net "M_B_CPU0_SA_DQS_DN<8>")
		)
		(pad "190" smd rect
			(at 2.050034 -25.07488 270)
			(size 0.519938 1.4986)
			(layers "F.Cu" "F.Mask" "F.Paste")
			(net "M_B_CPU0_SA_DQS_DP<8>")
		)
		(pad "191" smd rect
			(at 2.050034 -24.224996 270)
			(size 0.519938 1.4986)
			(layers "F.Cu" "F.Mask" "F.Paste")
			(net "GND")
		)
		(pad "192" smd rect
			(at 2.050034 -23.375112 270)
			(size 0.519938 1.4986)
			(layers "F.Cu" "F.Mask" "F.Paste")
			(net "M_B_CPU0_SA_DQ<30>")
		)
		(pad "193" smd rect
			(at 2.050034 -22.524974 270)
			(size 0.519938 1.4986)
			(layers "F.Cu" "F.Mask" "F.Paste")
			(net "GND")
		)
		(pad "194" smd rect
			(at 2.050034 -21.67509 270)
			(size 0.519938 1.4986)
			(layers "F.Cu" "F.Mask" "F.Paste")
			(net "M_B_CPU0_SA_DQ<31>")
		)
		(pad "195" smd rect
			(at 2.050034 -20.824952 270)
			(size 0.519938 1.4986)
			(layers "F.Cu" "F.Mask" "F.Paste")
			(net "GND")
		)
		(pad "196" smd rect
			(at 2.050034 -19.975068 270)
			(size 0.519938 1.4986)
			(layers "F.Cu" "F.Mask" "F.Paste")
			(net "M_B_CPU0_SA_CB<2>")
		)
		(pad "197" smd rect
			(at 2.050034 -19.12493 270)
			(size 0.519938 1.4986)
			(layers "F.Cu" "F.Mask" "F.Paste")
			(net "GND")
		)
		(pad "198" smd rect
			(at 2.050034 -18.275046 270)
			(size 0.519938 1.4986)
			(layers "F.Cu" "F.Mask" "F.Paste")
			(net "M_B_CPU0_SA_CB<3>")
		)
		(pad "199" smd rect
			(at 2.050034 -17.424908 270)
			(size 0.519938 1.4986)
			(layers "F.Cu" "F.Mask" "F.Paste")
			(net "GND")
		)
		(pad "200" smd rect
			(at 2.050034 -16.575024 270)
			(size 0.519938 1.4986)
			(layers "F.Cu" "F.Mask" "F.Paste")
			(net "M_B_CPU0_SA_DQS_DN<9>")
		)
		(pad "201" smd rect
			(at 2.050034 -15.724886 270)
			(size 0.519938 1.4986)
			(layers "F.Cu" "F.Mask" "F.Paste")
			(net "M_B_CPU0_SA_DQS_DP<9>")
		)
		(pad "202" smd rect
			(at 2.050034 -14.875002 270)
			(size 0.519938 1.4986)
			(layers "F.Cu" "F.Mask" "F.Paste")
			(net "GND")
		)
		(pad "203" smd rect
			(at 2.050034 -14.025118 270)
			(size 0.519938 1.4986)
			(layers "F.Cu" "F.Mask" "F.Paste")
			(net "M_B_CPU0_SA_CB<6>")
		)
		(pad "204" smd rect
			(at 2.050034 -13.17498 270)
			(size 0.519938 1.4986)
			(layers "F.Cu" "F.Mask" "F.Paste")
			(net "GND")
		)
		(pad "205" smd rect
			(at 2.050034 -12.325096 270)
			(size 0.519938 1.4986)
			(layers "F.Cu" "F.Mask" "F.Paste")
			(net "M_B_CPU0_SA_CB<7>")
		)
		(pad "206" smd rect
			(at 2.050034 -11.474958 270)
			(size 0.519938 1.4986)
			(layers "F.Cu" "F.Mask" "F.Paste")
			(net "GND")
		)
		(pad "207" smd rect
			(at 2.050034 -10.625074 270)
			(size 0.519938 1.4986)
			(layers "F.Cu" "F.Mask" "F.Paste")
			(net "RST_M_AB_CPU0_FPGA_N")
		)
		(pad "208" smd rect
			(at 2.050034 -9.774936 270)
			(size 0.519938 1.4986)
			(layers "F.Cu" "F.Mask" "F.Paste")
			(net "GND")
		)
		(pad "209" smd rect
			(at 2.050034 -8.925052 270)
			(size 0.519938 1.4986)
			(layers "F.Cu" "F.Mask" "F.Paste")
			(net "M_B_CPU0_SA_CS_N<1>")
		)
		(pad "210" smd rect
			(at 2.050034 -8.074914 270)
			(size 0.519938 1.4986)
			(layers "F.Cu" "F.Mask" "F.Paste")
			(net "GND")
		)
		(pad "211" smd rect
			(at 2.050034 -7.22503 270)
			(size 0.519938 1.4986)
			(layers "F.Cu" "F.Mask" "F.Paste")
			(net "M_B_CPU0_SA_CA<1>")
		)
		(pad "212" smd rect
			(at 2.050034 -6.374892 270)
			(size 0.519938 1.4986)
			(layers "F.Cu" "F.Mask" "F.Paste")
			(net "GND")
		)
		(pad "213" smd rect
			(at 2.050034 -5.525008 270)
			(size 0.519938 1.4986)
			(layers "F.Cu" "F.Mask" "F.Paste")
			(net "M_B_CPU0_SA_CA<3>")
		)
		(pad "214" smd rect
			(at 2.050034 -4.675124 270)
			(size 0.519938 1.4986)
			(layers "F.Cu" "F.Mask" "F.Paste")
			(net "GND")
		)
		(pad "215" smd rect
			(at 2.050034 -3.824986 270)
			(size 0.519938 1.4986)
			(layers "F.Cu" "F.Mask" "F.Paste")
			(net "M_B_CPU0_SA_CA<5>")
		)
		(pad "216" smd rect
			(at 2.050034 -2.975102 270)
			(size 0.519938 1.4986)
			(layers "F.Cu" "F.Mask" "F.Paste")
			(net "GND")
		)
		(pad "217" smd rect
			(at 2.050034 -2.124964 270)
			(size 0.519938 1.4986)
			(layers "F.Cu" "F.Mask" "F.Paste")
			(net "M_B_CPU0_CLK_DP<0>")
		)
		(pad "218" smd rect
			(at 2.050034 -1.27508 270)
			(size 0.519938 1.4986)
			(layers "F.Cu" "F.Mask" "F.Paste")
			(net "M_B_CPU0_CLK_DN<0>")
		)
		(pad "219" smd rect
			(at 2.050034 -0.424942 270)
			(size 0.519938 1.4986)
			(layers "F.Cu" "F.Mask" "F.Paste")
			(net "GND")
		)
		(pad "220" smd rect
			(at 2.050034 5.525008 270)
			(size 0.519938 1.4986)
			(layers "F.Cu" "F.Mask" "F.Paste")
			(net "TP_CHB_CPU0_DIMM1_FRU_4")
		)
		(pad "221" smd rect
			(at 2.050034 6.374892 270)
			(size 0.519938 1.4986)
			(layers "F.Cu" "F.Mask" "F.Paste")
			(net "M_B_CPU0_SB_CA<1>")
		)
		(pad "222" smd rect
			(at 2.050034 7.22503 270)
			(size 0.519938 1.4986)
			(layers "F.Cu" "F.Mask" "F.Paste")
			(net "GND")
		)
		(pad "223" smd rect
			(at 2.050034 8.074914 270)
			(size 0.519938 1.4986)
			(layers "F.Cu" "F.Mask" "F.Paste")
			(net "M_B_CPU0_SB_CA<3>")
		)
		(pad "224" smd rect
			(at 2.050034 8.925052 270)
			(size 0.519938 1.4986)
			(layers "F.Cu" "F.Mask" "F.Paste")
			(net "GND")
		)
		(pad "225" smd rect
			(at 2.050034 9.774936 270)
			(size 0.519938 1.4986)
			(layers "F.Cu" "F.Mask" "F.Paste")
			(net "M_B_CPU0_SB_CA<5>")
		)
		(pad "226" smd rect
			(at 2.050034 10.625074 270)
			(size 0.519938 1.4986)
			(layers "F.Cu" "F.Mask" "F.Paste")
			(net "GND")
		)
		(pad "227" smd rect
			(at 2.050034 11.474958 270)
			(size 0.519938 1.4986)
			(layers "F.Cu" "F.Mask" "F.Paste")
			(net "M_B_CPU0_SB_PAR")
		)
		(pad "228" smd rect
			(at 2.050034 12.325096 270)
			(size 0.519938 1.4986)
			(layers "F.Cu" "F.Mask" "F.Paste")
			(net "GND")
		)
		(pad "229" smd rect
			(at 2.050034 13.17498 270)
			(size 0.519938 1.4986)
			(layers "F.Cu" "F.Mask" "F.Paste")
			(net "M_B_CPU0_SB_CS_N<1>")
		)
		(pad "230" smd rect
			(at 2.050034 14.025118 270)
			(size 0.519938 1.4986)
			(layers "F.Cu" "F.Mask" "F.Paste")
			(net "GND")
		)
		(pad "231" smd rect
			(at 2.050034 14.875002 270)
			(size 0.519938 1.4986)
			(layers "F.Cu" "F.Mask" "F.Paste")
			(net "TP_CHB_CPU0_DIMM1_FRU_5")
		)
		(pad "232" smd rect
			(at 2.050034 15.724886 270)
			(size 0.519938 1.4986)
			(layers "F.Cu" "F.Mask" "F.Paste")
			(net "TP_CHB_CPU0_DIMM1_FRU_6")
		)
		(pad "233" smd rect
			(at 2.050034 16.575024 270)
			(size 0.519938 1.4986)
			(layers "F.Cu" "F.Mask" "F.Paste")
			(net "GND")
		)
		(pad "234" smd rect
			(at 2.050034 17.424908 270)
			(size 0.519938 1.4986)
			(layers "F.Cu" "F.Mask" "F.Paste")
			(net "M_B_CPU0_SB_CB<6>")
		)
		(pad "235" smd rect
			(at 2.050034 18.275046 270)
			(size 0.519938 1.4986)
			(layers "F.Cu" "F.Mask" "F.Paste")
			(net "GND")
		)
		(pad "236" smd rect
			(at 2.050034 19.12493 270)
			(size 0.519938 1.4986)
			(layers "F.Cu" "F.Mask" "F.Paste")
			(net "M_B_CPU0_SB_CB<7>")
		)
		(pad "237" smd rect
			(at 2.050034 19.975068 270)
			(size 0.519938 1.4986)
			(layers "F.Cu" "F.Mask" "F.Paste")
			(net "GND")
		)
		(pad "238" smd rect
			(at 2.050034 20.824952 270)
			(size 0.519938 1.4986)
			(layers "F.Cu" "F.Mask" "F.Paste")
			(net "M_B_CPU0_SB_DQS_DN<4>")
		)
		(pad "239" smd rect
			(at 2.050034 21.67509 270)
			(size 0.519938 1.4986)
			(layers "F.Cu" "F.Mask" "F.Paste")
			(net "M_B_CPU0_SB_DQS_DP<4>")
		)
		(pad "240" smd rect
			(at 2.050034 22.524974 270)
			(size 0.519938 1.4986)
			(layers "F.Cu" "F.Mask" "F.Paste")
			(net "GND")
		)
		(pad "241" smd rect
			(at 2.050034 23.375112 270)
			(size 0.519938 1.4986)
			(layers "F.Cu" "F.Mask" "F.Paste")
			(net "M_B_CPU0_SB_CB<2>")
		)
		(pad "242" smd rect
			(at 2.050034 24.224996 270)
			(size 0.519938 1.4986)
			(layers "F.Cu" "F.Mask" "F.Paste")
			(net "GND")
		)
		(pad "243" smd rect
			(at 2.050034 25.07488 270)
			(size 0.519938 1.4986)
			(layers "F.Cu" "F.Mask" "F.Paste")
			(net "M_B_CPU0_SB_CB<3>")
		)
		(pad "244" smd rect
			(at 2.050034 25.925018 270)
			(size 0.519938 1.4986)
			(layers "F.Cu" "F.Mask" "F.Paste")
			(net "GND")
		)
		(pad "245" smd rect
			(at 2.050034 26.774902 270)
			(size 0.519938 1.4986)
			(layers "F.Cu" "F.Mask" "F.Paste")
			(net "M_B_CPU0_SB_DQ<2>")
		)
		(pad "246" smd rect
			(at 2.050034 27.62504 270)
			(size 0.519938 1.4986)
			(layers "F.Cu" "F.Mask" "F.Paste")
			(net "GND")
		)
		(pad "247" smd rect
			(at 2.050034 28.474924 270)
			(size 0.519938 1.4986)
			(layers "F.Cu" "F.Mask" "F.Paste")
			(net "M_B_CPU0_SB_DQ<3>")
		)
		(pad "248" smd rect
			(at 2.050034 29.325062 270)
			(size 0.519938 1.4986)
			(layers "F.Cu" "F.Mask" "F.Paste")
			(net "GND")
		)
		(pad "249" smd rect
			(at 2.050034 30.174946 270)
			(size 0.519938 1.4986)
			(layers "F.Cu" "F.Mask" "F.Paste")
			(net "M_B_CPU0_SB_DQS_DN<5>")
		)
		(pad "250" smd rect
			(at 2.050034 31.025084 270)
			(size 0.519938 1.4986)
			(layers "F.Cu" "F.Mask" "F.Paste")
			(net "M_B_CPU0_SB_DQS_DP<5>")
		)
		(pad "251" smd rect
			(at 2.050034 31.874968 270)
			(size 0.519938 1.4986)
			(layers "F.Cu" "F.Mask" "F.Paste")
			(net "GND")
		)
		(pad "252" smd rect
			(at 2.050034 32.725106 270)
			(size 0.519938 1.4986)
			(layers "F.Cu" "F.Mask" "F.Paste")
			(net "M_B_CPU0_SB_DQ<6>")
		)
		(pad "253" smd rect
			(at 2.050034 33.57499 270)
			(size 0.519938 1.4986)
			(layers "F.Cu" "F.Mask" "F.Paste")
			(net "GND")
		)
		(pad "254" smd rect
			(at 2.050034 34.425128 270)
			(size 0.519938 1.4986)
			(layers "F.Cu" "F.Mask" "F.Paste")
			(net "M_B_CPU0_SB_DQ<7>")
		)
		(pad "255" smd rect
			(at 2.050034 35.275012 270)
			(size 0.519938 1.4986)
			(layers "F.Cu" "F.Mask" "F.Paste")
			(net "GND")
		)
		(pad "256" smd rect
			(at 2.050034 36.124896 270)
			(size 0.519938 1.4986)
			(layers "F.Cu" "F.Mask" "F.Paste")
			(net "M_B_CPU0_SB_DQ<10>")
		)
		(pad "257" smd rect
			(at 2.050034 36.975034 270)
			(size 0.519938 1.4986)
			(layers "F.Cu" "F.Mask" "F.Paste")
			(net "GND")
		)
		(pad "258" smd rect
			(at 2.050034 37.824918 270)
			(size 0.519938 1.4986)
			(layers "F.Cu" "F.Mask" "F.Paste")
			(net "M_B_CPU0_SB_DQ<11>")
		)
		(pad "259" smd rect
			(at 2.050034 38.675056 270)
			(size 0.519938 1.4986)
			(layers "F.Cu" "F.Mask" "F.Paste")
			(net "GND")
		)
		(pad "260" smd rect
			(at 2.050034 39.52494 270)
			(size 0.519938 1.4986)
			(layers "F.Cu" "F.Mask" "F.Paste")
			(net "M_B_CPU0_SB_DQS_DN<6>")
		)
		(pad "261" smd rect
			(at 2.050034 40.375078 270)
			(size 0.519938 1.4986)
			(layers "F.Cu" "F.Mask" "F.Paste")
			(net "M_B_CPU0_SB_DQS_DP<6>")
		)
		(pad "262" smd rect
			(at 2.050034 41.224962 270)
			(size 0.519938 1.4986)
			(layers "F.Cu" "F.Mask" "F.Paste")
			(net "GND")
		)
		(pad "263" smd rect
			(at 2.050034 42.0751 270)
			(size 0.519938 1.4986)
			(layers "F.Cu" "F.Mask" "F.Paste")
			(net "M_B_CPU0_SB_DQ<14>")
		)
		(pad "264" smd rect
			(at 2.050034 42.924984 270)
			(size 0.519938 1.4986)
			(layers "F.Cu" "F.Mask" "F.Paste")
			(net "GND")
		)
		(pad "265" smd rect
			(at 2.050034 43.775122 270)
			(size 0.519938 1.4986)
			(layers "F.Cu" "F.Mask" "F.Paste")
			(net "M_B_CPU0_SB_DQ<15>")
		)
		(pad "266" smd rect
			(at 2.050034 44.625006 270)
			(size 0.519938 1.4986)
			(layers "F.Cu" "F.Mask" "F.Paste")
			(net "GND")
		)
		(pad "267" smd rect
			(at 2.050034 45.47489 270)
			(size 0.519938 1.4986)
			(layers "F.Cu" "F.Mask" "F.Paste")
			(net "M_B_CPU0_SB_DQ<18>")
		)
		(pad "268" smd rect
			(at 2.050034 46.325028 270)
			(size 0.519938 1.4986)
			(layers "F.Cu" "F.Mask" "F.Paste")
			(net "GND")
		)
		(pad "269" smd rect
			(at 2.050034 47.174912 270)
			(size 0.519938 1.4986)
			(layers "F.Cu" "F.Mask" "F.Paste")
			(net "M_B_CPU0_SB_DQ<19>")
		)
		(pad "270" smd rect
			(at 2.050034 48.02505 270)
			(size 0.519938 1.4986)
			(layers "F.Cu" "F.Mask" "F.Paste")
			(net "GND")
		)
		(pad "271" smd rect
			(at 2.050034 48.874934 270)
			(size 0.519938 1.4986)
			(layers "F.Cu" "F.Mask" "F.Paste")
			(net "M_B_CPU0_SB_DQS_DN<7>")
		)
		(pad "272" smd rect
			(at 2.050034 49.725072 270)
			(size 0.519938 1.4986)
			(layers "F.Cu" "F.Mask" "F.Paste")
			(net "M_B_CPU0_SB_DQS_DP<7>")
		)
		(pad "273" smd rect
			(at 2.050034 50.574956 270)
			(size 0.519938 1.4986)
			(layers "F.Cu" "F.Mask" "F.Paste")
			(net "GND")
		)
		(pad "274" smd rect
			(at 2.050034 51.425094 270)
			(size 0.519938 1.4986)
			(layers "F.Cu" "F.Mask" "F.Paste")
			(net "M_B_CPU0_SB_DQ<22>")
		)
		(pad "275" smd rect
			(at 2.050034 52.274978 270)
			(size 0.519938 1.4986)
			(layers "F.Cu" "F.Mask" "F.Paste")
			(net "GND")
		)
		(pad "276" smd rect
			(at 2.050034 53.125116 270)
			(size 0.519938 1.4986)
			(layers "F.Cu" "F.Mask" "F.Paste")
			(net "M_B_CPU0_SB_DQ<23>")
		)
		(pad "277" smd rect
			(at 2.050034 53.975 270)
			(size 0.519938 1.4986)
			(layers "F.Cu" "F.Mask" "F.Paste")
			(net "GND")
		)
		(pad "278" smd rect
			(at 2.050034 54.824884 270)
			(size 0.519938 1.4986)
			(layers "F.Cu" "F.Mask" "F.Paste")
			(net "M_B_CPU0_SB_DQ<26>")
		)
		(pad "279" smd rect
			(at 2.050034 55.675022 270)
			(size 0.519938 1.4986)
			(layers "F.Cu" "F.Mask" "F.Paste")
			(net "GND")
		)
		(pad "280" smd rect
			(at 2.050034 56.524906 270)
			(size 0.519938 1.4986)
			(layers "F.Cu" "F.Mask" "F.Paste")
			(net "M_B_CPU0_SB_DQ<27>")
		)
		(pad "281" smd rect
			(at 2.050034 57.375044 270)
			(size 0.519938 1.4986)
			(layers "F.Cu" "F.Mask" "F.Paste")
			(net "GND")
		)
		(pad "282" smd rect
			(at 2.050034 58.224928 270)
			(size 0.519938 1.4986)
			(layers "F.Cu" "F.Mask" "F.Paste")
			(net "M_B_CPU0_SB_DQS_DN<8>")
		)
		(pad "283" smd rect
			(at 2.050034 59.075066 270)
			(size 0.519938 1.4986)
			(layers "F.Cu" "F.Mask" "F.Paste")
			(net "M_B_CPU0_SB_DQS_DP<8>")
		)
		(pad "284" smd rect
			(at 2.050034 59.92495 270)
			(size 0.519938 1.4986)
			(layers "F.Cu" "F.Mask" "F.Paste")
			(net "GND")
		)
		(pad "285" smd rect
			(at 2.050034 60.775088 270)
			(size 0.519938 1.4986)
			(layers "F.Cu" "F.Mask" "F.Paste")
			(net "M_B_CPU0_SB_DQ<30>")
		)
		(pad "286" smd rect
			(at 2.050034 61.624972 270)
			(size 0.519938 1.4986)
			(layers "F.Cu" "F.Mask" "F.Paste")
			(net "GND")
		)
		(pad "287" smd rect
			(at 2.050034 62.47511 270)
			(size 0.519938 1.4986)
			(layers "F.Cu" "F.Mask" "F.Paste")
			(net "M_B_CPU0_SB_DQ<31>")
		)
		(pad "288" smd rect
			(at 2.050034 63.324994 270)
			(size 0.519938 1.4986)
			(layers "F.Cu" "F.Mask" "F.Paste")
			(net "GND")
		)
		(pad "G1" thru_hole oval
			(at 0 -68.97497)
			(size 2.8194 1.5748)
			(drill oval 2.4384 1.1938)
			(layers "*.Cu" "*.Mask")
			(remove_unused_layers no)
			(net "GND")
			(clearance 0.127)
			(thermal_gap 0.127)
		)
		(pad "G2" thru_hole oval
			(at 0 3.875024)
			(size 2.8194 1.5748)
			(drill oval 2.4384 1.1938)
			(layers "*.Cu" "*.Mask")
			(remove_unused_layers no)
			(net "GND")
			(clearance 0.127)
			(thermal_gap 0.127)
		)
		(pad "G3" thru_hole oval
			(at 0 68.97497)
			(size 2.8194 1.5748)
			(drill oval 2.4384 1.1938)
			(layers "*.Cu" "*.Mask")
			(remove_unused_layers no)
			(net "GND")
			(clearance 0.127)
			(thermal_gap 0.127)
		)
	)
	(footprint ""
		(layer "F.Cu")
		(at 360.482642 -393.28725)
		(property "Reference" "R4160"
			(at 0 0 0)
			(layer "F.SilkS")
			(hide yes)
			(effects
				(font
					(size 1.27 1.27)
				)
			)
		)
		(property "Value" ""
			(at 0 0 0)
			(layer "F.Fab")
			(effects
				(font
					(size 1.27 1.27)
				)
			)
		)
		(duplicate_pad_numbers_are_jumpers no)
		(fp_line
			(start -0.7874 -0.4064)
			(end 0.7874 -0.4064)
			(stroke
				(width 0.1524)
				(type default)
			)
			(layer "F.SilkS")
		)
		(fp_line
			(start -0.7874 0.4064)
			(end -0.7874 -0.4064)
			(stroke
				(width 0.1524)
				(type default)
			)
			(layer "F.SilkS")
		)
		(fp_line
			(start 0.7874 -0.4064)
			(end 0.7874 0.4064)
			(stroke
				(width 0.1524)
				(type default)
			)
			(layer "F.SilkS")
		)
		(fp_line
			(start 0.7874 0.4064)
			(end -0.7874 0.4064)
			(stroke
				(width 0.1524)
				(type default)
			)
			(layer "F.SilkS")
		)
		(fp_line
			(start -0.67945 -0.305054)
			(end -0.12065 -0.305054)
			(stroke
				(width 0.1)
				(type default)
			)
			(layer "F.Fab")
		)
		(fp_line
			(start -0.67945 0.3048)
			(end -0.67945 -0.305054)
			(stroke
				(width 0.1)
				(type default)
			)
			(layer "F.Fab")
		)
		(fp_line
			(start -0.12065 -0.305054)
			(end -0.12065 -0.2794)
			(stroke
				(width 0.1)
				(type default)
			)
			(layer "F.Fab")
		)
		(fp_line
			(start -0.12065 -0.2794)
			(end 0.12065 -0.2794)
			(stroke
				(width 0.1)
				(type default)
			)
			(layer "F.Fab")
		)
		(fp_line
			(start -0.12065 0.2794)
			(end -0.12065 0.3048)
			(stroke
				(width 0.1)
				(type default)
			)
			(layer "F.Fab")
		)
		(fp_line
			(start -0.12065 0.3048)
			(end -0.67945 0.3048)
			(stroke
				(width 0.1)
				(type default)
			)
			(layer "F.Fab")
		)
		(fp_line
			(start 0.120396 0.2794)
			(end -0.12065 0.2794)
			(stroke
				(width 0.1)
				(type default)
			)
			(layer "F.Fab")
		)
		(fp_line
			(start 0.120396 0.3048)
			(end 0.120396 0.2794)
			(stroke
				(width 0.1)
				(type default)
			)
			(layer "F.Fab")
		)
		(fp_line
			(start 0.12065 -0.3048)
			(end 0.67945 -0.3048)
			(stroke
				(width 0.1)
				(type default)
			)
			(layer "F.Fab")
		)
		(fp_line
			(start 0.12065 -0.2794)
			(end 0.12065 -0.3048)
			(stroke
				(width 0.1)
				(type default)
			)
			(layer "F.Fab")
		)
		(fp_line
			(start 0.67945 -0.3048)
			(end 0.67945 0.3048)
			(stroke
				(width 0.1)
				(type default)
			)
			(layer "F.Fab")
		)
		(fp_line
			(start 0.67945 0.3048)
			(end 0.120396 0.3048)
			(stroke
				(width 0.1)
				(type default)
			)
			(layer "F.Fab")
		)
		(pad "1" smd circle
			(at -0.40005 0)
			(size 0 0)
			(layers "F.Cu" "F.Mask" "F.Paste")
			(net "P3V3_AUX")
		)
		(pad "2" smd circle
			(at 0.40005 0)
			(size 0 0)
			(layers "F.Cu" "F.Mask" "F.Paste")
			(net "GPU_3V3IO_RSVD4")
		)
	)
	(footprint ""
		(layer "F.Cu")
		(at 204.64526 -51.999896)
		(property "Reference" "H112"
			(at -0.64008 -8.82777 0)
			(unlocked yes)
			(layer "F.SilkS")
			(effects
				(font
					(size 0.7874 0.5842)
					(thickness 0.1524)
				)
				(justify left)
			)
		)
		(property "Value" ""
			(at 0 0 0)
			(layer "F.Fab")
			(effects
				(font
					(size 1.27 1.27)
				)
			)
		)
		(duplicate_pad_numbers_are_jumpers no)
		(fp_arc
			(start -5.618226 -5.695188)
			(mid 3.086589 -7.380568)
			(end 7.999984 0)
			(stroke
				(width 0.1524)
				(type default)
			)
			(layer "F.SilkS")
		)
		(fp_arc
			(start 7.999984 0)
			(mid 3.083611 7.381777)
			(end -5.622798 5.690616)
			(stroke
				(width 0.1524)
				(type default)
			)
			(layer "F.SilkS")
		)
		(fp_arc
			(start -3.527044 -7.18058)
			(mid -2.158979 -7.703219)
			(end -0.718566 -7.967726)
			(stroke
				(width 0.1524)
				(type default)
			)
			(layer "B.SilkS")
		)
		(fp_arc
			(start 7.999984 0)
			(mid 3.091799 7.378252)
			(end -5.610098 5.703062)
			(stroke
				(width 0.1524)
				(type default)
			)
			(layer "B.SilkS")
		)
		(fp_circle
			(center 0 0)
			(end 7.999984 0)
			(stroke
				(width 0.1)
				(type default)
			)
			(fill no)
			(layer "B.Fab")
		)
		(fp_circle
			(center 0 0)
			(end 7.999984 0)
			(stroke
				(width 0.1)
				(type default)
			)
			(fill no)
			(layer "F.Fab")
		)
		(pad "" np_thru_hole circle
			(at 0 0)
			(size 5.5118 5.5118)
			(drill 5.5118)
			(layers "*.Cu" "*.Mask")
			(clearance 0.381)
			(thermal_gap 0.381)
		)
		(pad "2" thru_hole circle
			(at 0 -3.999992)
			(size 0.762 0.762)
			(drill 0.5588)
			(layers "*.Cu" "*.Mask")
			(remove_unused_layers no)
			(net "GND")
			(clearance 0.1524)
			(thermal_gap 0.1524)
		)
		(pad "3" thru_hole circle
			(at -2.999994 -2.500122)
			(size 0.762 0.762)
			(drill 0.5588)
			(layers "*.Cu" "*.Mask")
			(remove_unused_layers no)
			(net "GND")
			(clearance 0.1524)
			(thermal_gap 0.1524)
		)
		(pad "4" thru_hole circle
			(at -3.999992 0)
			(size 0.762 0.762)
			(drill 0.5588)
			(layers "*.Cu" "*.Mask")
			(remove_unused_layers no)
			(net "GND")
			(clearance 0.1524)
			(thermal_gap 0.1524)
		)
		(pad "5" thru_hole circle
			(at -2.999994 2.500122)
			(size 0.762 0.762)
			(drill 0.5588)
			(layers "*.Cu" "*.Mask")
			(remove_unused_layers no)
			(net "GND")
			(clearance 0.1524)
			(thermal_gap 0.1524)
		)
		(pad "6" thru_hole circle
			(at 0 3.999992)
			(size 0.762 0.762)
			(drill 0.5588)
			(layers "*.Cu" "*.Mask")
			(remove_unused_layers no)
			(net "GND")
			(clearance 0.1524)
			(thermal_gap 0.1524)
		)
		(pad "7" thru_hole circle
			(at 2.999994 2.500122)
			(size 0.762 0.762)
			(drill 0.5588)
			(layers "*.Cu" "*.Mask")
			(remove_unused_layers no)
			(net "GND")
			(clearance 0.1524)
			(thermal_gap 0.1524)
		)
		(pad "8" thru_hole circle
			(at 3.999992 0)
			(size 0.762 0.762)
			(drill 0.5588)
			(layers "*.Cu" "*.Mask")
			(remove_unused_layers no)
			(net "GND")
			(clearance 0.1524)
			(thermal_gap 0.1524)
		)
		(pad "9" thru_hole circle
			(at 2.999994 -2.500122)
			(size 0.762 0.762)
			(drill 0.5588)
			(layers "*.Cu" "*.Mask")
			(remove_unused_layers no)
			(net "GND")
			(clearance 0.1524)
			(thermal_gap 0.1524)
		)
		(zone
			(layer "F.Cu")
			(hatch none 0.5)
			(connect_pads
				(clearance 0)
			)
			(min_thickness 0.25)
			(keepout
				(tracks not_allowed)
				(vias allowed)
				(pads allowed)
				(copperpour not_allowed)
				(footprints allowed)
			)
			(placement
				(enabled no)
				(sheetname "")
			)
			(fill
				(thermal_gap 0.5)
				(thermal_bridge_width 0.5)
				(island_removal_mode 0)
			)
			(polygon
				(pts
					(arc
						(start 204.64526 -59.99988)
						(mid 198.988417 -57.656739)
						(end 196.645276 -51.999896)
					)
					(arc
						(start 196.645276 -51.999896)
						(mid 198.988417 -46.343053)
						(end 204.64526 -43.999912)
					)
					(xy 204.64526 -46.74616) (xy 204.594206 -46.74616)
					(arc
						(start 204.593952 -46.74616)
						(mid 199.391273 -51.999896)
						(end 204.593952 -57.253632)
					)
					(xy 204.594206 -57.253632) (xy 204.64526 -57.253632)
				)
			)
		)
		(zone
			(layer "F.Cu")
			(hatch none 0.5)
			(connect_pads
				(clearance 0)
			)
			(min_thickness 0.25)
			(keepout
				(tracks not_allowed)
				(vias allowed)
				(pads allowed)
				(copperpour not_allowed)
				(footprints allowed)
			)
			(placement
				(enabled no)
				(sheetname "")
			)
			(fill
				(thermal_gap 0.5)
				(thermal_bridge_width 0.5)
				(island_removal_mode 0)
			)
			(polygon
				(pts
					(arc
						(start 204.64526 -59.99988)
						(mid 210.302103 -57.656739)
						(end 212.645244 -51.999896)
					)
					(arc
						(start 212.645244 -51.999896)
						(mid 210.302103 -46.343053)
						(end 204.64526 -43.999912)
					)
					(xy 204.64526 -46.74616) (xy 204.696314 -46.74616)
					(arc
						(start 204.696568 -46.74616)
						(mid 209.899247 -51.999896)
						(end 204.696568 -57.253632)
					)
					(xy 204.696314 -57.253632) (xy 204.64526 -57.253632)
				)
			)
		)
		(zone
			(layers "F.Cu" "B.Cu" "In1.Cu" "In2.Cu" "In3.Cu" "In4.Cu" "In5.Cu" "In6.Cu"
				"In7.Cu" "In8.Cu" "In9.Cu" "In10.Cu" "In11.Cu" "In12.Cu" "In13.Cu" "In14.Cu"
				"In15.Cu" "In16.Cu"
			)
			(hatch none 0.5)
			(connect_pads
				(clearance 0)
			)
			(min_thickness 0.25)
			(keepout
				(tracks not_allowed)
				(vias allowed)
				(pads allowed)
				(copperpour not_allowed)
				(footprints allowed)
			)
			(placement
				(enabled no)
				(sheetname "")
			)
			(fill
				(thermal_gap 0.5)
				(thermal_bridge_width 0.5)
				(island_removal_mode 0)
			)
			(polygon
				(pts
					(arc
						(start 207.92186 -51.999896)
						(mid 201.36866 -51.999896)
						(end 207.92186 -51.999896)
					)
				)
			)
		)
		(zone
			(layer "B.Cu")
			(hatch none 0.5)
			(connect_pads
				(clearance 0)
			)
			(min_thickness 0.25)
			(keepout
				(tracks not_allowed)
				(vias allowed)
				(pads allowed)
				(copperpour not_allowed)
				(footprints allowed)
			)
			(placement
				(enabled no)
				(sheetname "")
			)
			(fill
				(thermal_gap 0.5)
				(thermal_bridge_width 0.5)
				(island_removal_mode 0)
			)
			(polygon
				(pts
					(arc
						(start 204.64526 -57.507886)
						(mid 199.13727 -51.999896)
						(end 204.64526 -46.491906)
					)
					(arc
						(start 204.64526 -46.974506)
						(mid 199.61987 -51.999896)
						(end 204.64526 -57.025286)
					)
				)
			)
		)
		(zone
			(layer "B.Cu")
			(hatch none 0.5)
			(connect_pads
				(clearance 0)
			)
			(min_thickness 0.25)
			(keepout
				(tracks not_allowed)
				(vias allowed)
				(pads allowed)
				(copperpour not_allowed)
				(footprints allowed)
			)
			(placement
				(enabled no)
				(sheetname "")
			)
			(fill
				(thermal_gap 0.5)
				(thermal_bridge_width 0.5)
				(island_removal_mode 0)
			)
			(polygon
				(pts
					(arc
						(start 204.64526 -57.507886)
						(mid 210.15325 -51.999896)
						(end 204.64526 -46.491906)
					)
					(arc
						(start 204.64526 -46.974506)
						(mid 209.67065 -51.999896)
						(end 204.64526 -57.025286)
					)
				)
			)
		)
	)
	(footprint ""
		(layer "F.Cu")
		(at 133.19252 -121.536968)
		(property "Reference" "R4763"
			(at 0 0 0)
			(layer "F.SilkS")
			(hide yes)
			(effects
				(font
					(size 1.27 1.27)
				)
			)
		)
		(property "Value" ""
			(at 0 0 0)
			(layer "F.Fab")
			(effects
				(font
					(size 1.27 1.27)
				)
			)
		)
		(duplicate_pad_numbers_are_jumpers no)
		(fp_line
			(start -0.7874 -0.4064)
			(end 0.7874 -0.4064)
			(stroke
				(width 0.1524)
				(type default)
			)
			(layer "F.SilkS")
		)
		(fp_line
			(start -0.7874 0.4064)
			(end -0.7874 -0.4064)
			(stroke
				(width 0.1524)
				(type default)
			)
			(layer "F.SilkS")
		)
		(fp_line
			(start 0.7874 -0.4064)
			(end 0.7874 0.4064)
			(stroke
				(width 0.1524)
				(type default)
			)
			(layer "F.SilkS")
		)
		(fp_line
			(start 0.7874 0.4064)
			(end -0.7874 0.4064)
			(stroke
				(width 0.1524)
				(type default)
			)
			(layer "F.SilkS")
		)
		(fp_line
			(start -0.67945 -0.305054)
			(end -0.12065 -0.305054)
			(stroke
				(width 0.1)
				(type default)
			)
			(layer "F.Fab")
		)
		(fp_line
			(start -0.67945 0.3048)
			(end -0.67945 -0.305054)
			(stroke
				(width 0.1)
				(type default)
			)
			(layer "F.Fab")
		)
		(fp_line
			(start -0.12065 -0.305054)
			(end -0.12065 -0.2794)
			(stroke
				(width 0.1)
				(type default)
			)
			(layer "F.Fab")
		)
		(fp_line
			(start -0.12065 -0.2794)
			(end 0.12065 -0.2794)
			(stroke
				(width 0.1)
				(type default)
			)
			(layer "F.Fab")
		)
		(fp_line
			(start -0.12065 0.2794)
			(end -0.12065 0.3048)
			(stroke
				(width 0.1)
				(type default)
			)
			(layer "F.Fab")
		)
		(fp_line
			(start -0.12065 0.3048)
			(end -0.67945 0.3048)
			(stroke
				(width 0.1)
				(type default)
			)
			(layer "F.Fab")
		)
		(fp_line
			(start 0.120396 0.2794)
			(end -0.12065 0.2794)
			(stroke
				(width 0.1)
				(type default)
			)
			(layer "F.Fab")
		)
		(fp_line
			(start 0.120396 0.3048)
			(end 0.120396 0.2794)
			(stroke
				(width 0.1)
				(type default)
			)
			(layer "F.Fab")
		)
		(fp_line
			(start 0.12065 -0.3048)
			(end 0.67945 -0.3048)
			(stroke
				(width 0.1)
				(type default)
			)
			(layer "F.Fab")
		)
		(fp_line
			(start 0.12065 -0.2794)
			(end 0.12065 -0.3048)
			(stroke
				(width 0.1)
				(type default)
			)
			(layer "F.Fab")
		)
		(fp_line
			(start 0.67945 -0.3048)
			(end 0.67945 0.3048)
			(stroke
				(width 0.1)
				(type default)
			)
			(layer "F.Fab")
		)
		(fp_line
			(start 0.67945 0.3048)
			(end 0.120396 0.3048)
			(stroke
				(width 0.1)
				(type default)
			)
			(layer "F.Fab")
		)
		(pad "1" smd circle
			(at -0.40005 0)
			(size 0 0)
			(layers "F.Cu" "F.Mask" "F.Paste")
			(net "P3V3_AUX")
		)
		(pad "2" smd circle
			(at 0.40005 0)
			(size 0 0)
			(layers "F.Cu" "F.Mask" "F.Paste")
			(net "HP_OCP_V3_2_EN")
		)
	)
	(footprint ""
		(layer "F.Cu")
		(at 111.21136 -31.437834 90)
		(property "Reference" "C1823"
			(at 0 0 90)
			(layer "F.SilkS")
			(hide yes)
			(effects
				(font
					(size 1.27 1.27)
				)
			)
		)
		(property "Value" ""
			(at 0 0 90)
			(layer "F.Fab")
			(effects
				(font
					(size 1.27 1.27)
				)
			)
		)
		(duplicate_pad_numbers_are_jumpers no)
		(fp_line
			(start 0.7874 -0.4064)
			(end 0.7874 0.4064)
			(stroke
				(width 0.1524)
				(type default)
			)
			(layer "F.SilkS")
		)
		(fp_line
			(start -0.7874 -0.4064)
			(end 0.7874 -0.4064)
			(stroke
				(width 0.1524)
				(type default)
			)
			(layer "F.SilkS")
		)
		(fp_line
			(start 0.7874 0.4064)
			(end -0.7874 0.4064)
			(stroke
				(width 0.1524)
				(type default)
			)
			(layer "F.SilkS")
		)
		(fp_line
			(start -0.7874 0.4064)
			(end -0.7874 -0.4064)
			(stroke
				(width 0.1524)
				(type default)
			)
			(layer "F.SilkS")
		)
		(fp_line
			(start -0.12065 -0.305054)
			(end -0.12065 -0.2794)
			(stroke
				(width 0.1)
				(type default)
			)
			(layer "F.Fab")
		)
		(fp_line
			(start -0.67945 -0.305054)
			(end -0.12065 -0.305054)
			(stroke
				(width 0.1)
				(type default)
			)
			(layer "F.Fab")
		)
		(fp_line
			(start 0.67945 -0.3048)
			(end 0.67945 0.3048)
			(stroke
				(width 0.1)
				(type default)
			)
			(layer "F.Fab")
		)
		(fp_line
			(start 0.12065 -0.3048)
			(end 0.67945 -0.3048)
			(stroke
				(width 0.1)
				(type default)
			)
			(layer "F.Fab")
		)
		(fp_line
			(start 0.12065 -0.2794)
			(end 0.12065 -0.3048)
			(stroke
				(width 0.1)
				(type default)
			)
			(layer "F.Fab")
		)
		(fp_line
			(start -0.12065 -0.2794)
			(end 0.12065 -0.2794)
			(stroke
				(width 0.1)
				(type default)
			)
			(layer "F.Fab")
		)
		(fp_line
			(start 0.120396 0.2794)
			(end -0.12065 0.2794)
			(stroke
				(width 0.1)
				(type default)
			)
			(layer "F.Fab")
		)
		(fp_line
			(start -0.12065 0.2794)
			(end -0.12065 0.3048)
			(stroke
				(width 0.1)
				(type default)
			)
			(layer "F.Fab")
		)
		(fp_line
			(start 0.67945 0.3048)
			(end 0.120396 0.3048)
			(stroke
				(width 0.1)
				(type default)
			)
			(layer "F.Fab")
		)
		(fp_line
			(start 0.120396 0.3048)
			(end 0.120396 0.2794)
			(stroke
				(width 0.1)
				(type default)
			)
			(layer "F.Fab")
		)
		(fp_line
			(start -0.12065 0.3048)
			(end -0.67945 0.3048)
			(stroke
				(width 0.1)
				(type default)
			)
			(layer "F.Fab")
		)
		(fp_line
			(start -0.67945 0.3048)
			(end -0.67945 -0.305054)
			(stroke
				(width 0.1)
				(type default)
			)
			(layer "F.Fab")
		)
		(pad "1" smd circle
			(at -0.40005 0 90)
			(size 0 0)
			(layers "F.Cu" "F.Mask" "F.Paste")
			(net "P3V3_AUX")
		)
		(pad "2" smd circle
			(at 0.40005 0 90)
			(size 0 0)
			(layers "F.Cu" "F.Mask" "F.Paste")
			(net "GND")
		)
	)
	(footprint ""
		(layer "F.Cu")
		(at 142.486634 -402.371052 -90)
		(property "Reference" "C756"
			(at 0 0 270)
			(layer "F.SilkS")
			(hide yes)
			(effects
				(font
					(size 1.27 1.27)
				)
			)
		)
		(property "Value" ""
			(at 0 0 270)
			(layer "F.Fab")
			(effects
				(font
					(size 1.27 1.27)
				)
			)
		)
		(duplicate_pad_numbers_are_jumpers no)
		(fp_line
			(start -0.299974 0.150114)
			(end -0.299974 -0.150114)
			(stroke
				(width 0.1)
				(type default)
			)
			(layer "F.Fab")
		)
		(fp_line
			(start 0.299974 0.150114)
			(end -0.299974 0.150114)
			(stroke
				(width 0.1)
				(type default)
			)
			(layer "F.Fab")
		)
		(fp_line
			(start -0.299974 -0.150114)
			(end 0.299974 -0.150114)
			(stroke
				(width 0.1)
				(type default)
			)
			(layer "F.Fab")
		)
		(fp_line
			(start 0.299974 -0.150114)
			(end 0.299974 0.150114)
			(stroke
				(width 0.1)
				(type default)
			)
			(layer "F.Fab")
		)
		(pad "1" smd rect
			(at -0.2667 0 270)
			(size 0.3048 0.381)
			(layers "F.Cu" "F.Mask" "F.Paste")
			(net "P5E_CPU1_PE2_TX_C_DN<8>")
		)
		(pad "2" smd rect
			(at 0.2667 0 270)
			(size 0.3048 0.381)
			(layers "F.Cu" "F.Mask" "F.Paste")
			(net "P5E_CPU1_PE2_TX_DN<8>")
		)
	)
	(footprint ""
		(layer "F.Cu")
		(at 460.6798 -380.691898 90)
		(property "Reference" "PR73"
			(at 0 0 90)
			(layer "F.SilkS")
			(hide yes)
			(effects
				(font
					(size 1.27 1.27)
				)
			)
		)
		(property "Value" ""
			(at 0 0 90)
			(layer "F.Fab")
			(effects
				(font
					(size 1.27 1.27)
				)
			)
		)
		(duplicate_pad_numbers_are_jumpers no)
		(fp_line
			(start 0.7874 -0.4064)
			(end 0.7874 0.4064)
			(stroke
				(width 0.1524)
				(type default)
			)
			(layer "F.SilkS")
		)
		(fp_line
			(start -0.7874 -0.4064)
			(end 0.7874 -0.4064)
			(stroke
				(width 0.1524)
				(type default)
			)
			(layer "F.SilkS")
		)
		(fp_line
			(start 0.7874 0.4064)
			(end -0.7874 0.4064)
			(stroke
				(width 0.1524)
				(type default)
			)
			(layer "F.SilkS")
		)
		(fp_line
			(start -0.7874 0.4064)
			(end -0.7874 -0.4064)
			(stroke
				(width 0.1524)
				(type default)
			)
			(layer "F.SilkS")
		)
		(fp_line
			(start -0.12065 -0.305054)
			(end -0.12065 -0.2794)
			(stroke
				(width 0.1)
				(type default)
			)
			(layer "F.Fab")
		)
		(fp_line
			(start -0.67945 -0.305054)
			(end -0.12065 -0.305054)
			(stroke
				(width 0.1)
				(type default)
			)
			(layer "F.Fab")
		)
		(fp_line
			(start 0.67945 -0.3048)
			(end 0.67945 0.3048)
			(stroke
				(width 0.1)
				(type default)
			)
			(layer "F.Fab")
		)
		(fp_line
			(start 0.12065 -0.3048)
			(end 0.67945 -0.3048)
			(stroke
				(width 0.1)
				(type default)
			)
			(layer "F.Fab")
		)
		(fp_line
			(start 0.12065 -0.2794)
			(end 0.12065 -0.3048)
			(stroke
				(width 0.1)
				(type default)
			)
			(layer "F.Fab")
		)
		(fp_line
			(start -0.12065 -0.2794)
			(end 0.12065 -0.2794)
			(stroke
				(width 0.1)
				(type default)
			)
			(layer "F.Fab")
		)
		(fp_line
			(start 0.120396 0.2794)
			(end -0.12065 0.2794)
			(stroke
				(width 0.1)
				(type default)
			)
			(layer "F.Fab")
		)
		(fp_line
			(start -0.12065 0.2794)
			(end -0.12065 0.3048)
			(stroke
				(width 0.1)
				(type default)
			)
			(layer "F.Fab")
		)
		(fp_line
			(start 0.67945 0.3048)
			(end 0.120396 0.3048)
			(stroke
				(width 0.1)
				(type default)
			)
			(layer "F.Fab")
		)
		(fp_line
			(start 0.120396 0.3048)
			(end 0.120396 0.2794)
			(stroke
				(width 0.1)
				(type default)
			)
			(layer "F.Fab")
		)
		(fp_line
			(start -0.12065 0.3048)
			(end -0.67945 0.3048)
			(stroke
				(width 0.1)
				(type default)
			)
			(layer "F.Fab")
		)
		(fp_line
			(start -0.67945 0.3048)
			(end -0.67945 -0.305054)
			(stroke
				(width 0.1)
				(type default)
			)
			(layer "F.Fab")
		)
		(pad "1" smd circle
			(at -0.40005 0 90)
			(size 0 0)
			(layers "F.Cu" "F.Mask" "F.Paste")
			(net "P3V3_AUX")
		)
		(pad "2" smd circle
			(at 0.40005 0 90)
			(size 0 0)
			(layers "F.Cu" "F.Mask" "F.Paste")
			(net "PWRGD_P3V3_AUX")
		)
	)
	(footprint ""
		(layer "F.Cu")
		(at 163.50615 -418.514276 90)
		(property "Reference" "R3106"
			(at 0 0 90)
			(layer "F.SilkS")
			(hide yes)
			(effects
				(font
					(size 1.27 1.27)
				)
			)
		)
		(property "Value" ""
			(at 0 0 90)
			(layer "F.Fab")
			(effects
				(font
					(size 1.27 1.27)
				)
			)
		)
		(duplicate_pad_numbers_are_jumpers no)
		(fp_line
			(start 0.7874 -0.4064)
			(end 0.7874 0.4064)
			(stroke
				(width 0.1524)
				(type default)
			)
			(layer "F.SilkS")
		)
		(fp_line
			(start -0.7874 -0.4064)
			(end 0.7874 -0.4064)
			(stroke
				(width 0.1524)
				(type default)
			)
			(layer "F.SilkS")
		)
		(fp_line
			(start 0.7874 0.4064)
			(end -0.7874 0.4064)
			(stroke
				(width 0.1524)
				(type default)
			)
			(layer "F.SilkS")
		)
		(fp_line
			(start -0.7874 0.4064)
			(end -0.7874 -0.4064)
			(stroke
				(width 0.1524)
				(type default)
			)
			(layer "F.SilkS")
		)
		(fp_line
			(start -0.12065 -0.305054)
			(end -0.12065 -0.2794)
			(stroke
				(width 0.1)
				(type default)
			)
			(layer "F.Fab")
		)
		(fp_line
			(start -0.67945 -0.305054)
			(end -0.12065 -0.305054)
			(stroke
				(width 0.1)
				(type default)
			)
			(layer "F.Fab")
		)
		(fp_line
			(start 0.67945 -0.3048)
			(end 0.67945 0.3048)
			(stroke
				(width 0.1)
				(type default)
			)
			(layer "F.Fab")
		)
		(fp_line
			(start 0.12065 -0.3048)
			(end 0.67945 -0.3048)
			(stroke
				(width 0.1)
				(type default)
			)
			(layer "F.Fab")
		)
		(fp_line
			(start 0.12065 -0.2794)
			(end 0.12065 -0.3048)
			(stroke
				(width 0.1)
				(type default)
			)
			(layer "F.Fab")
		)
		(fp_line
			(start -0.12065 -0.2794)
			(end 0.12065 -0.2794)
			(stroke
				(width 0.1)
				(type default)
			)
			(layer "F.Fab")
		)
		(fp_line
			(start 0.120396 0.2794)
			(end -0.12065 0.2794)
			(stroke
				(width 0.1)
				(type default)
			)
			(layer "F.Fab")
		)
		(fp_line
			(start -0.12065 0.2794)
			(end -0.12065 0.3048)
			(stroke
				(width 0.1)
				(type default)
			)
			(layer "F.Fab")
		)
		(fp_line
			(start 0.67945 0.3048)
			(end 0.120396 0.3048)
			(stroke
				(width 0.1)
				(type default)
			)
			(layer "F.Fab")
		)
		(fp_line
			(start 0.120396 0.3048)
			(end 0.120396 0.2794)
			(stroke
				(width 0.1)
				(type default)
			)
			(layer "F.Fab")
		)
		(fp_line
			(start -0.12065 0.3048)
			(end -0.67945 0.3048)
			(stroke
				(width 0.1)
				(type default)
			)
			(layer "F.Fab")
		)
		(fp_line
			(start -0.67945 0.3048)
			(end -0.67945 -0.305054)
			(stroke
				(width 0.1)
				(type default)
			)
			(layer "F.Fab")
		)
		(pad "1" smd circle
			(at -0.40005 0 90)
			(size 0 0)
			(layers "F.Cu" "F.Mask" "F.Paste")
			(net "SMB_BMC_SWB_SDA")
		)
		(pad "2" smd circle
			(at 0.40005 0 90)
			(size 0 0)
			(layers "F.Cu" "F.Mask" "F.Paste")
			(net "SMB_BMC_SWB_R_SDA")
		)
	)
	(footprint ""
		(layer "F.Cu")
		(at 88.837262 -337.126326)
		(property "Reference" "PU25_P1_6"
			(at -2.0955 -6.41985 0)
			(unlocked yes)
			(layer "F.SilkS")
			(effects
				(font
					(size 0.7874 0.5842)
					(thickness 0.1524)
				)
				(justify left)
			)
		)
		(property "Value" ""
			(at 0 0 0)
			(layer "F.Fab")
			(effects
				(font
					(size 1.27 1.27)
				)
			)
		)
		(duplicate_pad_numbers_are_jumpers no)
		(fp_line
			(start -2.500122 -2.999994)
			(end -2.24409 -2.999994)
			(stroke
				(width 0.1524)
				(type default)
			)
			(layer "F.SilkS")
		)
		(fp_line
			(start -2.500122 -2.529078)
			(end -2.500122 -2.999994)
			(stroke
				(width 0.1524)
				(type default)
			)
			(layer "F.SilkS")
		)
		(fp_line
			(start -2.500122 0.6604)
			(end -2.500122 0.229108)
			(stroke
				(width 0.1524)
				(type default)
			)
			(layer "F.SilkS")
		)
		(fp_line
			(start -2.500122 2.999994)
			(end -2.500122 2.339594)
			(stroke
				(width 0.1524)
				(type default)
			)
			(layer "F.SilkS")
		)
		(fp_line
			(start -2.2987 2.999994)
			(end -2.500122 2.999994)
			(stroke
				(width 0.1524)
				(type default)
			)
			(layer "F.SilkS")
		)
		(fp_line
			(start 2.31394 -2.999994)
			(end 2.500122 -2.999994)
			(stroke
				(width 0.1524)
				(type default)
			)
			(layer "F.SilkS")
		)
		(fp_line
			(start 2.500122 -2.999994)
			(end 2.500122 -2.44348)
			(stroke
				(width 0.1524)
				(type default)
			)
			(layer "F.SilkS")
		)
		(fp_line
			(start 2.500122 2.339594)
			(end 2.500122 2.999994)
			(stroke
				(width 0.1524)
				(type default)
			)
			(layer "F.SilkS")
		)
		(fp_line
			(start 2.500122 2.999994)
			(end 2.2987 2.999994)
			(stroke
				(width 0.1524)
				(type default)
			)
			(layer "F.SilkS")
		)
		(fp_poly
			(pts
				(xy -2.209546 -3.690112) (xy -2.717546 -2.674112) (xy -3.225546 -3.690112)
			)
			(stroke
				(width 0)
				(type default)
			)
			(fill yes)
			(layer "F.SilkS")
		)
		(fp_line
			(start -2.500122 -2.999994)
			(end 2.500122 -2.999994)
			(stroke
				(width 0.1)
				(type default)
			)
			(layer "F.Fab")
		)
		(fp_line
			(start -2.500122 2.999994)
			(end -2.500122 -2.999994)
			(stroke
				(width 0.1)
				(type default)
			)
			(layer "F.Fab")
		)
		(fp_line
			(start 2.500122 -2.999994)
			(end 2.500122 2.999994)
			(stroke
				(width 0.1)
				(type default)
			)
			(layer "F.Fab")
		)
		(fp_line
			(start 2.500122 2.999994)
			(end -2.500122 2.999994)
			(stroke
				(width 0.1)
				(type default)
			)
			(layer "F.Fab")
		)
		(fp_poly
			(pts
				(xy -4.218432 -2.783078) (xy -4.218432 -1.767078) (xy -3.202432 -2.275078)
			)
			(stroke
				(width 0)
				(type default)
			)
			(fill yes)
			(layer "F.Fab")
		)
		(pad "1" smd rect
			(at -2.400046 -2.275078 90)
			(size 0.2286 0.6096)
			(layers "F.Cu" "F.Mask" "F.Paste")
			(net "PVCCIN_CPU1_VOS6")
		)
		(pad "2" smd rect
			(at -2.400046 -1.82499 90)
			(size 0.2286 0.6096)
			(layers "F.Cu" "F.Mask" "F.Paste")
			(net "GND")
		)
		(pad "3" smd rect
			(at -2.400046 -1.374902 90)
			(size 0.2286 0.6096)
			(layers "F.Cu" "F.Mask" "F.Paste")
			(net "PVCCIN_CPU1_VDD6")
		)
		(pad "4" smd rect
			(at -2.400046 -0.925068 90)
			(size 0.2286 0.6096)
			(layers "F.Cu" "F.Mask" "F.Paste")
			(net "PVCCIN_CPU1_PVCC")
		)
		(pad "5" smd rect
			(at -2.400046 -0.47498 90)
			(size 0.2286 0.6096)
			(layers "F.Cu" "F.Mask" "F.Paste")
			(net "GND")
		)
		(pad "6" smd rect
			(at -2.400046 -0.024892 90)
			(size 0.2286 0.6096)
			(layers "F.Cu" "F.Mask" "F.Paste")
			(net "Net_8535")
		)
		(pad "7_9-20_24" smd circle
			(at 0 1.150112 90)
			(size 0 0)
			(layers "F.Cu" "F.Mask" "F.Paste")
			(net "GND")
		)
		(pad "10_19" smd rect
			(at 0 2.899918 90)
			(size 0.6096 4.318)
			(layers "F.Cu" "F.Mask" "F.Paste")
			(net "SW_PVCCIN_CPU1_SW6")
		)
		(pad "25_29" smd rect
			(at 1.549908 -1.279906 270)
			(size 2.0574 2.3114)
			(layers "F.Cu" "F.Mask" "F.Paste")
			(net "SW_P12V_PVCCIN_CPU1_FLT")
		)
		(pad "30" smd rect
			(at 2.05994 -2.899918)
			(size 0.2286 0.6096)
			(layers "F.Cu" "F.Mask" "F.Paste")
			(net "SW_P12V_PVCCIN_CPU1_FLT")
		)
		(pad "31" smd rect
			(at 1.610106 -2.899918)
			(size 0.2286 0.6096)
			(layers "F.Cu" "F.Mask" "F.Paste")
			(net "Net_8536")
		)
		(pad "32" smd rect
			(at 1.160018 -2.899918)
			(size 0.2286 0.6096)
			(layers "F.Cu" "F.Mask" "F.Paste")
			(net "SW_PVCCIN_CPU1_BOOTR6")
		)
		(pad "33" smd rect
			(at 0.70993 -2.899918)
			(size 0.2286 0.6096)
			(layers "F.Cu" "F.Mask" "F.Paste")
			(net "SW_PVCCIN_CPU1_BOOT6")
		)
		(pad "34" smd rect
			(at 0.260096 -2.899918)
			(size 0.2286 0.6096)
			(layers "F.Cu" "F.Mask" "F.Paste")
			(net "PVCCIN_CPU1_PWM6")
		)
		(pad "35" smd rect
			(at -0.189992 -2.899918)
			(size 0.2286 0.6096)
			(layers "F.Cu" "F.Mask" "F.Paste")
			(net "PVCCIN_CPU1_VDD6")
		)
		(pad "36" smd rect
			(at -0.64008 -2.899918)
			(size 0.2286 0.6096)
			(layers "F.Cu" "F.Mask" "F.Paste")
			(net "PVCCIN_CPU1_ATSEN")
		)
		(pad "37" smd rect
			(at -1.089914 -2.899918)
			(size 0.2286 0.6096)
			(layers "F.Cu" "F.Mask" "F.Paste")
			(net "PVCCIN_CPU1_LSET6")
		)
		(pad "38" smd rect
			(at -1.540002 -2.899918)
			(size 0.2286 0.6096)
			(layers "F.Cu" "F.Mask" "F.Paste")
			(net "PVCCIN_CPU1_IMON6")
		)
		(pad "39" smd rect
			(at -1.99009 -2.899918)
			(size 0.2286 0.6096)
			(layers "F.Cu" "F.Mask" "F.Paste")
			(net "PVCCIN_CPU1_VREF")
		)
		(pad "40" smd rect
			(at -0.87503 -1.27508)
			(size 1.7526 1.9558)
			(layers "F.Cu" "F.Mask" "F.Paste")
			(net "GND")
		)
		(pad "41" smd rect
			(at -1.525016 0.249936 270)
			(size 0.3048 0.4572)
			(layers "F.Cu" "F.Mask" "F.Paste")
			(net "Net_8534")
		)
		(zone
			(layer "F.Cu")
			(hatch none 0.5)
			(connect_pads
				(clearance 0)
			)
			(min_thickness 0.25)
			(keepout
				(tracks not_allowed)
				(vias allowed)
				(pads allowed)
				(copperpour not_allowed)
				(footprints allowed)
			)
			(placement
				(enabled no)
				(sheetname "")
			)
			(fill
				(thermal_gap 0.5)
				(thermal_bridge_width 0.5)
				(island_removal_mode 0)
			)
			(polygon
				(pts
					(xy 86.33714 -334.126332) (xy 86.33714 -334.875632) (xy 91.337384 -334.875632) (xy 91.337384 -334.126332)
					(xy 91.047062 -334.126332) (xy 91.047062 -334.582008) (xy 86.627462 -334.582008) (xy 86.627462 -334.126332)
				)
			)
		)
		(zone
			(layer "F.Cu")
			(hatch none 0.5)
			(connect_pads
				(clearance 0)
			)
			(min_thickness 0.25)
			(keepout
				(tracks not_allowed)
				(vias allowed)
				(pads allowed)
				(copperpour not_allowed)
				(footprints allowed)
			)
			(placement
				(enabled no)
				(sheetname "")
			)
			(fill
				(thermal_gap 0.5)
				(thermal_bridge_width 0.5)
				(island_removal_mode 0)
			)
			(polygon
				(pts
					(xy 86.792816 -337.464908) (xy 87.035132 -337.464908) (xy 87.035132 -337.372706) (xy 87.82812 -337.372706)
					(xy 87.82812 -337.035648) (xy 87.88654 -337.035648) (xy 87.88654 -336.377026) (xy 86.33714 -336.377026)
					(xy 86.33714 -336.833718) (xy 87.032846 -336.833718) (xy 87.032846 -336.67319) (xy 87.591646 -336.67319)
					(xy 87.591646 -337.07959) (xy 87.032846 -337.07959) (xy 87.032846 -336.859118) (xy 86.33714 -336.859118)
					(xy 86.33714 -336.986118) (xy 86.792816 -336.986118)
				)
			)
		)
	)
	(footprint ""
		(layer "F.Cu")
		(at 28.337002 -135.001 180)
		(property "Reference" "PJ51"
			(at 4.60756 -0.056896 0)
			(unlocked yes)
			(layer "F.SilkS")
			(effects
				(font
					(size 0.7874 0.5842)
					(thickness 0.1524)
				)
				(justify left)
			)
		)
		(property "Value" ""
			(at 0 0 180)
			(layer "F.Fab")
			(effects
				(font
					(size 1.27 1.27)
				)
			)
		)
		(duplicate_pad_numbers_are_jumpers no)
		(pad "1" smd circle
			(at -0.7493 0 270)
			(size 0 0)
			(layers "F.Cu" "F.Mask" "F.Paste")
			(net "VSENSE_PVCCFA_EHV_CPU1_DP")
		)
		(pad "2" smd rect
			(at 0.7493 0 90)
			(size 0.7112 0.8128)
			(layers "F.Cu" "F.Mask" "F.Paste")
			(net "SH_PVCCFA_EHV_CPU1")
		)
		(zone
			(layer "F.Cu")
			(hatch none 0.5)
			(connect_pads
				(clearance 0)
			)
			(min_thickness 0.25)
			(keepout
				(tracks allowed)
				(vias not_allowed)
				(pads allowed)
				(copperpour not_allowed)
				(footprints allowed)
			)
			(placement
				(enabled no)
				(sheetname "")
			)
			(fill
				(thermal_gap 0.5)
				(thermal_bridge_width 0.5)
				(island_removal_mode 0)
			)
			(polygon
				(pts
					(xy 27.130502 -134.5946) (xy 29.518102 -134.5946) (xy 29.518102 -135.412226) (xy 27.130502 -135.412226)
				)
			)
		)
	)
	(footprint ""
		(layer "F.Cu")
		(at 116.159534 -39.335456)
		(property "Reference" "R3326"
			(at 0 0 0)
			(layer "F.SilkS")
			(hide yes)
			(effects
				(font
					(size 1.27 1.27)
				)
			)
		)
		(property "Value" ""
			(at 0 0 0)
			(layer "F.Fab")
			(effects
				(font
					(size 1.27 1.27)
				)
			)
		)
		(duplicate_pad_numbers_are_jumpers no)
		(fp_line
			(start -0.7874 -0.4064)
			(end 0.7874 -0.4064)
			(stroke
				(width 0.1524)
				(type default)
			)
			(layer "F.SilkS")
		)
		(fp_line
			(start -0.7874 0.4064)
			(end -0.7874 -0.4064)
			(stroke
				(width 0.1524)
				(type default)
			)
			(layer "F.SilkS")
		)
		(fp_line
			(start 0.7874 -0.4064)
			(end 0.7874 0.4064)
			(stroke
				(width 0.1524)
				(type default)
			)
			(layer "F.SilkS")
		)
		(fp_line
			(start 0.7874 0.4064)
			(end -0.7874 0.4064)
			(stroke
				(width 0.1524)
				(type default)
			)
			(layer "F.SilkS")
		)
		(fp_line
			(start -0.67945 -0.305054)
			(end -0.12065 -0.305054)
			(stroke
				(width 0.1)
				(type default)
			)
			(layer "F.Fab")
		)
		(fp_line
			(start -0.67945 0.3048)
			(end -0.67945 -0.305054)
			(stroke
				(width 0.1)
				(type default)
			)
			(layer "F.Fab")
		)
		(fp_line
			(start -0.12065 -0.305054)
			(end -0.12065 -0.2794)
			(stroke
				(width 0.1)
				(type default)
			)
			(layer "F.Fab")
		)
		(fp_line
			(start -0.12065 -0.2794)
			(end 0.12065 -0.2794)
			(stroke
				(width 0.1)
				(type default)
			)
			(layer "F.Fab")
		)
		(fp_line
			(start -0.12065 0.2794)
			(end -0.12065 0.3048)
			(stroke
				(width 0.1)
				(type default)
			)
			(layer "F.Fab")
		)
		(fp_line
			(start -0.12065 0.3048)
			(end -0.67945 0.3048)
			(stroke
				(width 0.1)
				(type default)
			)
			(layer "F.Fab")
		)
		(fp_line
			(start 0.120396 0.2794)
			(end -0.12065 0.2794)
			(stroke
				(width 0.1)
				(type default)
			)
			(layer "F.Fab")
		)
		(fp_line
			(start 0.120396 0.3048)
			(end 0.120396 0.2794)
			(stroke
				(width 0.1)
				(type default)
			)
			(layer "F.Fab")
		)
		(fp_line
			(start 0.12065 -0.3048)
			(end 0.67945 -0.3048)
			(stroke
				(width 0.1)
				(type default)
			)
			(layer "F.Fab")
		)
		(fp_line
			(start 0.12065 -0.2794)
			(end 0.12065 -0.3048)
			(stroke
				(width 0.1)
				(type default)
			)
			(layer "F.Fab")
		)
		(fp_line
			(start 0.67945 -0.3048)
			(end 0.67945 0.3048)
			(stroke
				(width 0.1)
				(type default)
			)
			(layer "F.Fab")
		)
		(fp_line
			(start 0.67945 0.3048)
			(end 0.120396 0.3048)
			(stroke
				(width 0.1)
				(type default)
			)
			(layer "F.Fab")
		)
		(pad "1" smd circle
			(at -0.40005 0)
			(size 0 0)
			(layers "F.Cu" "F.Mask" "F.Paste")
			(net "GPU_FPGA_READY_N")
		)
		(pad "2" smd circle
			(at 0.40005 0)
			(size 0 0)
			(layers "F.Cu" "F.Mask" "F.Paste")
			(net "GPU_FPGA_READY_R_N")
		)
	)
	(footprint ""
		(layer "F.Cu")
		(at 197.19036 -119.344948)
		(property "Reference" "R1421"
			(at 0 0 0)
			(layer "F.SilkS")
			(hide yes)
			(effects
				(font
					(size 1.27 1.27)
				)
			)
		)
		(property "Value" ""
			(at 0 0 0)
			(layer "F.Fab")
			(effects
				(font
					(size 1.27 1.27)
				)
			)
		)
		(duplicate_pad_numbers_are_jumpers no)
		(fp_line
			(start -0.7874 -0.4064)
			(end 0.7874 -0.4064)
			(stroke
				(width 0.1524)
				(type default)
			)
			(layer "F.SilkS")
		)
		(fp_line
			(start -0.7874 0.4064)
			(end -0.7874 -0.4064)
			(stroke
				(width 0.1524)
				(type default)
			)
			(layer "F.SilkS")
		)
		(fp_line
			(start 0.7874 -0.4064)
			(end 0.7874 0.4064)
			(stroke
				(width 0.1524)
				(type default)
			)
			(layer "F.SilkS")
		)
		(fp_line
			(start 0.7874 0.4064)
			(end -0.7874 0.4064)
			(stroke
				(width 0.1524)
				(type default)
			)
			(layer "F.SilkS")
		)
		(fp_line
			(start -0.67945 -0.305054)
			(end -0.12065 -0.305054)
			(stroke
				(width 0.1)
				(type default)
			)
			(layer "F.Fab")
		)
		(fp_line
			(start -0.67945 0.3048)
			(end -0.67945 -0.305054)
			(stroke
				(width 0.1)
				(type default)
			)
			(layer "F.Fab")
		)
		(fp_line
			(start -0.12065 -0.305054)
			(end -0.12065 -0.2794)
			(stroke
				(width 0.1)
				(type default)
			)
			(layer "F.Fab")
		)
		(fp_line
			(start -0.12065 -0.2794)
			(end 0.12065 -0.2794)
			(stroke
				(width 0.1)
				(type default)
			)
			(layer "F.Fab")
		)
		(fp_line
			(start -0.12065 0.2794)
			(end -0.12065 0.3048)
			(stroke
				(width 0.1)
				(type default)
			)
			(layer "F.Fab")
		)
		(fp_line
			(start -0.12065 0.3048)
			(end -0.67945 0.3048)
			(stroke
				(width 0.1)
				(type default)
			)
			(layer "F.Fab")
		)
		(fp_line
			(start 0.120396 0.2794)
			(end -0.12065 0.2794)
			(stroke
				(width 0.1)
				(type default)
			)
			(layer "F.Fab")
		)
		(fp_line
			(start 0.120396 0.3048)
			(end 0.120396 0.2794)
			(stroke
				(width 0.1)
				(type default)
			)
			(layer "F.Fab")
		)
		(fp_line
			(start 0.12065 -0.3048)
			(end 0.67945 -0.3048)
			(stroke
				(width 0.1)
				(type default)
			)
			(layer "F.Fab")
		)
		(fp_line
			(start 0.12065 -0.2794)
			(end 0.12065 -0.3048)
			(stroke
				(width 0.1)
				(type default)
			)
			(layer "F.Fab")
		)
		(fp_line
			(start 0.67945 -0.3048)
			(end 0.67945 0.3048)
			(stroke
				(width 0.1)
				(type default)
			)
			(layer "F.Fab")
		)
		(fp_line
			(start 0.67945 0.3048)
			(end 0.120396 0.3048)
			(stroke
				(width 0.1)
				(type default)
			)
			(layer "F.Fab")
		)
		(pad "1" smd circle
			(at -0.40005 0)
			(size 0 0)
			(layers "F.Cu" "F.Mask" "F.Paste")
			(net "RST_RSMRST_PLD_R_N")
		)
		(pad "2" smd circle
			(at 0.40005 0)
			(size 0 0)
			(layers "F.Cu" "F.Mask" "F.Paste")
			(net "GND")
		)
	)
	(footprint ""
		(layer "F.Cu")
		(at 24.046942 -415.127948 180)
		(property "Reference" "C1756"
			(at 0 0 180)
			(layer "F.SilkS")
			(hide yes)
			(effects
				(font
					(size 1.27 1.27)
				)
			)
		)
		(property "Value" ""
			(at 0 0 180)
			(layer "F.Fab")
			(effects
				(font
					(size 1.27 1.27)
				)
			)
		)
		(duplicate_pad_numbers_are_jumpers no)
		(fp_line
			(start 0.7874 0.4064)
			(end -0.7874 0.4064)
			(stroke
				(width 0.1524)
				(type default)
			)
			(layer "F.SilkS")
		)
		(fp_line
			(start 0.7874 -0.4064)
			(end 0.7874 0.4064)
			(stroke
				(width 0.1524)
				(type default)
			)
			(layer "F.SilkS")
		)
		(fp_line
			(start -0.7874 0.4064)
			(end -0.7874 -0.4064)
			(stroke
				(width 0.1524)
				(type default)
			)
			(layer "F.SilkS")
		)
		(fp_line
			(start -0.7874 -0.4064)
			(end 0.7874 -0.4064)
			(stroke
				(width 0.1524)
				(type default)
			)
			(layer "F.SilkS")
		)
		(fp_line
			(start 0.67945 0.3048)
			(end 0.120396 0.3048)
			(stroke
				(width 0.1)
				(type default)
			)
			(layer "F.Fab")
		)
		(fp_line
			(start 0.67945 -0.3048)
			(end 0.67945 0.3048)
			(stroke
				(width 0.1)
				(type default)
			)
			(layer "F.Fab")
		)
		(fp_line
			(start 0.12065 -0.2794)
			(end 0.12065 -0.3048)
			(stroke
				(width 0.1)
				(type default)
			)
			(layer "F.Fab")
		)
		(fp_line
			(start 0.12065 -0.3048)
			(end 0.67945 -0.3048)
			(stroke
				(width 0.1)
				(type default)
			)
			(layer "F.Fab")
		)
		(fp_line
			(start 0.120396 0.3048)
			(end 0.120396 0.2794)
			(stroke
				(width 0.1)
				(type default)
			)
			(layer "F.Fab")
		)
		(fp_line
			(start 0.120396 0.2794)
			(end -0.12065 0.2794)
			(stroke
				(width 0.1)
				(type default)
			)
			(layer "F.Fab")
		)
		(fp_line
			(start -0.12065 0.3048)
			(end -0.67945 0.3048)
			(stroke
				(width 0.1)
				(type default)
			)
			(layer "F.Fab")
		)
		(fp_line
			(start -0.12065 0.2794)
			(end -0.12065 0.3048)
			(stroke
				(width 0.1)
				(type default)
			)
			(layer "F.Fab")
		)
		(fp_line
			(start -0.12065 -0.2794)
			(end 0.12065 -0.2794)
			(stroke
				(width 0.1)
				(type default)
			)
			(layer "F.Fab")
		)
		(fp_line
			(start -0.12065 -0.305054)
			(end -0.12065 -0.2794)
			(stroke
				(width 0.1)
				(type default)
			)
			(layer "F.Fab")
		)
		(fp_line
			(start -0.67945 0.3048)
			(end -0.67945 -0.305054)
			(stroke
				(width 0.1)
				(type default)
			)
			(layer "F.Fab")
		)
		(fp_line
			(start -0.67945 -0.305054)
			(end -0.12065 -0.305054)
			(stroke
				(width 0.1)
				(type default)
			)
			(layer "F.Fab")
		)
		(pad "1" smd circle
			(at -0.40005 0 180)
			(size 0 0)
			(layers "F.Cu" "F.Mask" "F.Paste")
			(net "FM_GPU_PWRGD_ISO")
		)
		(pad "2" smd circle
			(at 0.40005 0 180)
			(size 0 0)
			(layers "F.Cu" "F.Mask" "F.Paste")
			(net "GND")
		)
	)
	(footprint ""
		(layer "F.Cu")
		(at 126.534926 -122.096784 90)
		(property "Reference" "R939"
			(at 0 0 90)
			(layer "F.SilkS")
			(hide yes)
			(effects
				(font
					(size 1.27 1.27)
				)
			)
		)
		(property "Value" ""
			(at 0 0 90)
			(layer "F.Fab")
			(effects
				(font
					(size 1.27 1.27)
				)
			)
		)
		(duplicate_pad_numbers_are_jumpers no)
		(fp_line
			(start 0.7874 -0.4064)
			(end 0.7874 0.4064)
			(stroke
				(width 0.1524)
				(type default)
			)
			(layer "F.SilkS")
		)
		(fp_line
			(start -0.7874 -0.4064)
			(end 0.7874 -0.4064)
			(stroke
				(width 0.1524)
				(type default)
			)
			(layer "F.SilkS")
		)
		(fp_line
			(start 0.7874 0.4064)
			(end -0.7874 0.4064)
			(stroke
				(width 0.1524)
				(type default)
			)
			(layer "F.SilkS")
		)
		(fp_line
			(start -0.7874 0.4064)
			(end -0.7874 -0.4064)
			(stroke
				(width 0.1524)
				(type default)
			)
			(layer "F.SilkS")
		)
		(fp_line
			(start -0.12065 -0.305054)
			(end -0.12065 -0.2794)
			(stroke
				(width 0.1)
				(type default)
			)
			(layer "F.Fab")
		)
		(fp_line
			(start -0.67945 -0.305054)
			(end -0.12065 -0.305054)
			(stroke
				(width 0.1)
				(type default)
			)
			(layer "F.Fab")
		)
		(fp_line
			(start 0.67945 -0.3048)
			(end 0.67945 0.3048)
			(stroke
				(width 0.1)
				(type default)
			)
			(layer "F.Fab")
		)
		(fp_line
			(start 0.12065 -0.3048)
			(end 0.67945 -0.3048)
			(stroke
				(width 0.1)
				(type default)
			)
			(layer "F.Fab")
		)
		(fp_line
			(start 0.12065 -0.2794)
			(end 0.12065 -0.3048)
			(stroke
				(width 0.1)
				(type default)
			)
			(layer "F.Fab")
		)
		(fp_line
			(start -0.12065 -0.2794)
			(end 0.12065 -0.2794)
			(stroke
				(width 0.1)
				(type default)
			)
			(layer "F.Fab")
		)
		(fp_line
			(start 0.120396 0.2794)
			(end -0.12065 0.2794)
			(stroke
				(width 0.1)
				(type default)
			)
			(layer "F.Fab")
		)
		(fp_line
			(start -0.12065 0.2794)
			(end -0.12065 0.3048)
			(stroke
				(width 0.1)
				(type default)
			)
			(layer "F.Fab")
		)
		(fp_line
			(start 0.67945 0.3048)
			(end 0.120396 0.3048)
			(stroke
				(width 0.1)
				(type default)
			)
			(layer "F.Fab")
		)
		(fp_line
			(start 0.120396 0.3048)
			(end 0.120396 0.2794)
			(stroke
				(width 0.1)
				(type default)
			)
			(layer "F.Fab")
		)
		(fp_line
			(start -0.12065 0.3048)
			(end -0.67945 0.3048)
			(stroke
				(width 0.1)
				(type default)
			)
			(layer "F.Fab")
		)
		(fp_line
			(start -0.67945 0.3048)
			(end -0.67945 -0.305054)
			(stroke
				(width 0.1)
				(type default)
			)
			(layer "F.Fab")
		)
		(pad "1" smd circle
			(at -0.40005 0 90)
			(size 0 0)
			(layers "F.Cu" "F.Mask" "F.Paste")
			(net "RST_CPU1_DRAM_GH_N")
		)
		(pad "2" smd circle
			(at 0.40005 0 90)
			(size 0 0)
			(layers "F.Cu" "F.Mask" "F.Paste")
			(net "GND")
		)
	)
	(footprint ""
		(layer "F.Cu")
		(at 52.759864 -358.20223 -90)
		(property "Reference" "PC402"
			(at 0 0 270)
			(layer "F.SilkS")
			(hide yes)
			(effects
				(font
					(size 1.27 1.27)
				)
			)
		)
		(property "Value" ""
			(at 0 0 270)
			(layer "F.Fab")
			(effects
				(font
					(size 1.27 1.27)
				)
			)
		)
		(duplicate_pad_numbers_are_jumpers no)
		(fp_line
			(start -0.7874 0.4064)
			(end -0.7874 -0.4064)
			(stroke
				(width 0.1524)
				(type default)
			)
			(layer "F.SilkS")
		)
		(fp_line
			(start 0.7874 0.4064)
			(end -0.7874 0.4064)
			(stroke
				(width 0.1524)
				(type default)
			)
			(layer "F.SilkS")
		)
		(fp_line
			(start -0.7874 -0.4064)
			(end 0.7874 -0.4064)
			(stroke
				(width 0.1524)
				(type default)
			)
			(layer "F.SilkS")
		)
		(fp_line
			(start 0.7874 -0.4064)
			(end 0.7874 0.4064)
			(stroke
				(width 0.1524)
				(type default)
			)
			(layer "F.SilkS")
		)
		(fp_line
			(start -0.67945 0.3048)
			(end -0.67945 -0.305054)
			(stroke
				(width 0.1)
				(type default)
			)
			(layer "F.Fab")
		)
		(fp_line
			(start -0.12065 0.3048)
			(end -0.67945 0.3048)
			(stroke
				(width 0.1)
				(type default)
			)
			(layer "F.Fab")
		)
		(fp_line
			(start 0.120396 0.3048)
			(end 0.120396 0.2794)
			(stroke
				(width 0.1)
				(type default)
			)
			(layer "F.Fab")
		)
		(fp_line
			(start 0.67945 0.3048)
			(end 0.120396 0.3048)
			(stroke
				(width 0.1)
				(type default)
			)
			(layer "F.Fab")
		)
		(fp_line
			(start -0.12065 0.2794)
			(end -0.12065 0.3048)
			(stroke
				(width 0.1)
				(type default)
			)
			(layer "F.Fab")
		)
		(fp_line
			(start 0.120396 0.2794)
			(end -0.12065 0.2794)
			(stroke
				(width 0.1)
				(type default)
			)
			(layer "F.Fab")
		)
		(fp_line
			(start -0.12065 -0.2794)
			(end 0.12065 -0.2794)
			(stroke
				(width 0.1)
				(type default)
			)
			(layer "F.Fab")
		)
		(fp_line
			(start 0.12065 -0.2794)
			(end 0.12065 -0.3048)
			(stroke
				(width 0.1)
				(type default)
			)
			(layer "F.Fab")
		)
		(fp_line
			(start 0.12065 -0.3048)
			(end 0.67945 -0.3048)
			(stroke
				(width 0.1)
				(type default)
			)
			(layer "F.Fab")
		)
		(fp_line
			(start 0.67945 -0.3048)
			(end 0.67945 0.3048)
			(stroke
				(width 0.1)
				(type default)
			)
			(layer "F.Fab")
		)
		(fp_line
			(start -0.67945 -0.305054)
			(end -0.12065 -0.305054)
			(stroke
				(width 0.1)
				(type default)
			)
			(layer "F.Fab")
		)
		(fp_line
			(start -0.12065 -0.305054)
			(end -0.12065 -0.2794)
			(stroke
				(width 0.1)
				(type default)
			)
			(layer "F.Fab")
		)
		(pad "1" smd circle
			(at -0.40005 0 270)
			(size 0 0)
			(layers "F.Cu" "F.Mask" "F.Paste")
			(net "SW_PVCCFA_EHV_FIVRA_CPU1_BOOT2_")
		)
		(pad "2" smd circle
			(at 0.40005 0 270)
			(size 0 0)
			(layers "F.Cu" "F.Mask" "F.Paste")
			(net "SW_PVCCFA_EHV_FIVRA_CPU1_BOOTR2")
		)
	)
	(footprint ""
		(layer "F.Cu")
		(at 367.411 -54.828948)
		(property "Reference" "R754"
			(at 0 0 0)
			(layer "F.SilkS")
			(hide yes)
			(effects
				(font
					(size 1.27 1.27)
				)
			)
		)
		(property "Value" ""
			(at 0 0 0)
			(layer "F.Fab")
			(effects
				(font
					(size 1.27 1.27)
				)
			)
		)
		(duplicate_pad_numbers_are_jumpers no)
		(fp_line
			(start -0.7874 -0.4064)
			(end 0.7874 -0.4064)
			(stroke
				(width 0.1524)
				(type default)
			)
			(layer "F.SilkS")
		)
		(fp_line
			(start -0.7874 0.4064)
			(end -0.7874 -0.4064)
			(stroke
				(width 0.1524)
				(type default)
			)
			(layer "F.SilkS")
		)
		(fp_line
			(start 0.7874 -0.4064)
			(end 0.7874 0.4064)
			(stroke
				(width 0.1524)
				(type default)
			)
			(layer "F.SilkS")
		)
		(fp_line
			(start 0.7874 0.4064)
			(end -0.7874 0.4064)
			(stroke
				(width 0.1524)
				(type default)
			)
			(layer "F.SilkS")
		)
		(fp_line
			(start -0.67945 -0.305054)
			(end -0.12065 -0.305054)
			(stroke
				(width 0.1)
				(type default)
			)
			(layer "F.Fab")
		)
		(fp_line
			(start -0.67945 0.3048)
			(end -0.67945 -0.305054)
			(stroke
				(width 0.1)
				(type default)
			)
			(layer "F.Fab")
		)
		(fp_line
			(start -0.12065 -0.305054)
			(end -0.12065 -0.2794)
			(stroke
				(width 0.1)
				(type default)
			)
			(layer "F.Fab")
		)
		(fp_line
			(start -0.12065 -0.2794)
			(end 0.12065 -0.2794)
			(stroke
				(width 0.1)
				(type default)
			)
			(layer "F.Fab")
		)
		(fp_line
			(start -0.12065 0.2794)
			(end -0.12065 0.3048)
			(stroke
				(width 0.1)
				(type default)
			)
			(layer "F.Fab")
		)
		(fp_line
			(start -0.12065 0.3048)
			(end -0.67945 0.3048)
			(stroke
				(width 0.1)
				(type default)
			)
			(layer "F.Fab")
		)
		(fp_line
			(start 0.120396 0.2794)
			(end -0.12065 0.2794)
			(stroke
				(width 0.1)
				(type default)
			)
			(layer "F.Fab")
		)
		(fp_line
			(start 0.120396 0.3048)
			(end 0.120396 0.2794)
			(stroke
				(width 0.1)
				(type default)
			)
			(layer "F.Fab")
		)
		(fp_line
			(start 0.12065 -0.3048)
			(end 0.67945 -0.3048)
			(stroke
				(width 0.1)
				(type default)
			)
			(layer "F.Fab")
		)
		(fp_line
			(start 0.12065 -0.2794)
			(end 0.12065 -0.3048)
			(stroke
				(width 0.1)
				(type default)
			)
			(layer "F.Fab")
		)
		(fp_line
			(start 0.67945 -0.3048)
			(end 0.67945 0.3048)
			(stroke
				(width 0.1)
				(type default)
			)
			(layer "F.Fab")
		)
		(fp_line
			(start 0.67945 0.3048)
			(end 0.120396 0.3048)
			(stroke
				(width 0.1)
				(type default)
			)
			(layer "F.Fab")
		)
		(pad "1" smd circle
			(at -0.40005 0)
			(size 0 0)
			(layers "F.Cu" "F.Mask" "F.Paste")
			(net "JTAG_DBP_TMS")
		)
		(pad "2" smd circle
			(at 0.40005 0)
			(size 0 0)
			(layers "F.Cu" "F.Mask" "F.Paste")
			(net "JTAG_DBP_TMS_PCH")
		)
	)
	(footprint ""
		(layer "F.Cu")
		(at 400.558 -152.339548)
		(property "Reference" "PC2180"
			(at 0 0 0)
			(layer "F.SilkS")
			(hide yes)
			(effects
				(font
					(size 1.27 1.27)
				)
			)
		)
		(property "Value" ""
			(at 0 0 0)
			(layer "F.Fab")
			(effects
				(font
					(size 1.27 1.27)
				)
			)
		)
		(duplicate_pad_numbers_are_jumpers no)
		(fp_line
			(start 2.750058 0.999998)
			(end -2.750058 0.999998)
			(stroke
				(width 0.1524)
				(type default)
			)
			(layer "F.SilkS")
		)
		(fp_circle
			(center 0 0.999998)
			(end 2.750058 0.999998)
			(stroke
				(width 0.1524)
				(type default)
			)
			(fill no)
			(layer "F.SilkS")
		)
		(fp_poly
			(pts
				(arc
					(start 2.750058 0.999998)
					(mid 0 3.750056)
					(end -2.750058 0.999998)
				)
			)
			(stroke
				(width 0)
				(type default)
			)
			(fill yes)
			(layer "F.SilkS")
		)
		(fp_circle
			(center 0 0.999998)
			(end 2.750058 0.999998)
			(stroke
				(width 0.1)
				(type default)
			)
			(fill no)
			(layer "F.Fab")
		)
		(pad "1" thru_hole rect
			(at 0 0)
			(size 1.5748 1.5748)
			(drill 1.0668)
			(layers "*.Cu" "*.Mask")
			(remove_unused_layers no)
			(net "PVCCFA_EHV_CPU0")
			(clearance 0)
			(padstack
				(mode front_inner_back)
				(layer "Inner"
					(shape circle)
					(size 1.5748 1.5748)
					(clearance 0)
				)
				(layer "B.Cu"
					(shape rect)
					(size 1.5748 1.5748)
					(clearance 0)
				)
			)
		)
		(pad "2" thru_hole circle
			(at 0 1.999996)
			(size 1.5748 1.5748)
			(drill 1.0668)
			(layers "*.Cu" "*.Mask")
			(remove_unused_layers no)
			(net "GND")
			(clearance 0)
		)
	)
	(footprint ""
		(layer "F.Cu")
		(at 24.050752 -403.822408 180)
		(property "Reference" "R3511"
			(at 0 0 180)
			(layer "F.SilkS")
			(hide yes)
			(effects
				(font
					(size 1.27 1.27)
				)
			)
		)
		(property "Value" ""
			(at 0 0 180)
			(layer "F.Fab")
			(effects
				(font
					(size 1.27 1.27)
				)
			)
		)
		(duplicate_pad_numbers_are_jumpers no)
		(fp_line
			(start 0.7874 0.4064)
			(end -0.7874 0.4064)
			(stroke
				(width 0.1524)
				(type default)
			)
			(layer "F.SilkS")
		)
		(fp_line
			(start 0.7874 -0.4064)
			(end 0.7874 0.4064)
			(stroke
				(width 0.1524)
				(type default)
			)
			(layer "F.SilkS")
		)
		(fp_line
			(start -0.7874 0.4064)
			(end -0.7874 -0.4064)
			(stroke
				(width 0.1524)
				(type default)
			)
			(layer "F.SilkS")
		)
		(fp_line
			(start -0.7874 -0.4064)
			(end 0.7874 -0.4064)
			(stroke
				(width 0.1524)
				(type default)
			)
			(layer "F.SilkS")
		)
		(fp_line
			(start 0.67945 0.3048)
			(end 0.120396 0.3048)
			(stroke
				(width 0.1)
				(type default)
			)
			(layer "F.Fab")
		)
		(fp_line
			(start 0.67945 -0.3048)
			(end 0.67945 0.3048)
			(stroke
				(width 0.1)
				(type default)
			)
			(layer "F.Fab")
		)
		(fp_line
			(start 0.12065 -0.2794)
			(end 0.12065 -0.3048)
			(stroke
				(width 0.1)
				(type default)
			)
			(layer "F.Fab")
		)
		(fp_line
			(start 0.12065 -0.3048)
			(end 0.67945 -0.3048)
			(stroke
				(width 0.1)
				(type default)
			)
			(layer "F.Fab")
		)
		(fp_line
			(start 0.120396 0.3048)
			(end 0.120396 0.2794)
			(stroke
				(width 0.1)
				(type default)
			)
			(layer "F.Fab")
		)
		(fp_line
			(start 0.120396 0.2794)
			(end -0.12065 0.2794)
			(stroke
				(width 0.1)
				(type default)
			)
			(layer "F.Fab")
		)
		(fp_line
			(start -0.12065 0.3048)
			(end -0.67945 0.3048)
			(stroke
				(width 0.1)
				(type default)
			)
			(layer "F.Fab")
		)
		(fp_line
			(start -0.12065 0.2794)
			(end -0.12065 0.3048)
			(stroke
				(width 0.1)
				(type default)
			)
			(layer "F.Fab")
		)
		(fp_line
			(start -0.12065 -0.2794)
			(end 0.12065 -0.2794)
			(stroke
				(width 0.1)
				(type default)
			)
			(layer "F.Fab")
		)
		(fp_line
			(start -0.12065 -0.305054)
			(end -0.12065 -0.2794)
			(stroke
				(width 0.1)
				(type default)
			)
			(layer "F.Fab")
		)
		(fp_line
			(start -0.67945 0.3048)
			(end -0.67945 -0.305054)
			(stroke
				(width 0.1)
				(type default)
			)
			(layer "F.Fab")
		)
		(fp_line
			(start -0.67945 -0.305054)
			(end -0.12065 -0.305054)
			(stroke
				(width 0.1)
				(type default)
			)
			(layer "F.Fab")
		)
		(pad "1" smd circle
			(at -0.40005 0 180)
			(size 0 0)
			(layers "F.Cu" "F.Mask" "F.Paste")
			(net "GPU_FPGA_READY")
		)
		(pad "2" smd circle
			(at 0.40005 0 180)
			(size 0 0)
			(layers "F.Cu" "F.Mask" "F.Paste")
			(net "GND")
		)
	)
	(footprint ""
		(layer "F.Cu")
		(at 278.414734 -19.279108 180)
		(property "Reference" "U217"
			(at 1.229868 1.844548 0)
			(unlocked yes)
			(layer "F.SilkS")
			(effects
				(font
					(size 0.7874 0.5842)
					(thickness 0.1524)
				)
				(justify left)
			)
		)
		(property "Value" ""
			(at 0 0 180)
			(layer "F.Fab")
			(effects
				(font
					(size 1.27 1.27)
				)
			)
		)
		(duplicate_pad_numbers_are_jumpers no)
		(fp_line
			(start 1.400048 1.100074)
			(end -1.400048 1.100074)
			(stroke
				(width 0.1524)
				(type default)
			)
			(layer "F.SilkS")
		)
		(fp_line
			(start 1.400048 -1.100074)
			(end 1.400048 1.100074)
			(stroke
				(width 0.1524)
				(type default)
			)
			(layer "F.SilkS")
		)
		(fp_line
			(start 1.400048 -1.100074)
			(end -1.400048 -1.100074)
			(stroke
				(width 0.1524)
				(type default)
			)
			(layer "F.SilkS")
		)
		(fp_line
			(start -1.400048 1.100074)
			(end -1.400048 -1.100074)
			(stroke
				(width 0.1524)
				(type default)
			)
			(layer "F.SilkS")
		)
		(fp_poly
			(pts
				(xy -1.02362 -1.291082) (xy -1.53162 -2.307082) (xy -0.51562 -2.307082)
			)
			(stroke
				(width 0)
				(type default)
			)
			(fill yes)
			(layer "F.SilkS")
		)
		(fp_line
			(start 0.674878 1.100074)
			(end -0.674878 1.100074)
			(stroke
				(width 0.1)
				(type default)
			)
			(layer "F.Fab")
		)
		(fp_line
			(start 0.674878 -1.100074)
			(end 0.674878 1.100074)
			(stroke
				(width 0.1)
				(type default)
			)
			(layer "F.Fab")
		)
		(fp_line
			(start -0.674878 1.100074)
			(end -0.674878 -1.100074)
			(stroke
				(width 0.1)
				(type default)
			)
			(layer "F.Fab")
		)
		(fp_line
			(start -0.674878 -1.100074)
			(end 0.674878 -1.100074)
			(stroke
				(width 0.1)
				(type default)
			)
			(layer "F.Fab")
		)
		(fp_poly
			(pts
				(xy -1.590548 -0.649986) (xy -2.606548 -1.157986) (xy -2.606548 -0.141986)
			)
			(stroke
				(width 0)
				(type default)
			)
			(fill yes)
			(layer "F.Fab")
		)
		(pad "1" smd rect
			(at -0.94996 -0.649986 90)
			(size 0.4318 0.6096)
			(layers "F.Cu" "F.Mask" "F.Paste")
			(net "PU_OCP_V3_2_WAKE_OE")
		)
		(pad "2" smd rect
			(at -0.94996 0 90)
			(size 0.4318 0.6096)
			(layers "F.Cu" "F.Mask" "F.Paste")
			(net "IRQ_LVC3_OCP_V3_2_WAKE_N")
		)
		(pad "3" smd rect
			(at -0.94996 0.649986 90)
			(size 0.4318 0.6096)
			(layers "F.Cu" "F.Mask" "F.Paste")
			(net "GND")
		)
		(pad "4" smd rect
			(at 0.94996 0.649986 90)
			(size 0.4318 0.6096)
			(layers "F.Cu" "F.Mask" "F.Paste")
			(net "OCP_V3_2_WAKE_BUFF_N")
		)
		(pad "5" smd rect
			(at 0.94996 -0.649986 90)
			(size 0.4318 0.6096)
			(layers "F.Cu" "F.Mask" "F.Paste")
			(net "P3V3_AUX")
		)
	)
	(footprint ""
		(layer "F.Cu")
		(at 201.047604 -35.025838 90)
		(property "Reference" "R3635"
			(at 0 0 90)
			(layer "F.SilkS")
			(hide yes)
			(effects
				(font
					(size 1.27 1.27)
				)
			)
		)
		(property "Value" ""
			(at 0 0 90)
			(layer "F.Fab")
			(effects
				(font
					(size 1.27 1.27)
				)
			)
		)
		(duplicate_pad_numbers_are_jumpers no)
		(fp_line
			(start 4.0386 -1.7526)
			(end 4.0386 1.7526)
			(stroke
				(width 0.1524)
				(type default)
			)
			(layer "F.SilkS")
		)
		(fp_line
			(start -4.0386 -1.7526)
			(end 4.0386 -1.7526)
			(stroke
				(width 0.1524)
				(type default)
			)
			(layer "F.SilkS")
		)
		(fp_line
			(start 4.0386 1.7526)
			(end -4.0386 1.7526)
			(stroke
				(width 0.1524)
				(type default)
			)
			(layer "F.SilkS")
		)
		(fp_line
			(start -4.0386 1.7526)
			(end -4.0386 -1.7526)
			(stroke
				(width 0.1524)
				(type default)
			)
			(layer "F.SilkS")
		)
		(fp_line
			(start 4.0386 -1.7526)
			(end 4.0386 1.7526)
			(stroke
				(width 0.1)
				(type default)
			)
			(layer "F.Fab")
		)
		(fp_line
			(start -4.0386 -1.7526)
			(end 4.0386 -1.7526)
			(stroke
				(width 0.1)
				(type default)
			)
			(layer "F.Fab")
		)
		(fp_line
			(start 4.0386 1.7526)
			(end -4.0386 1.7526)
			(stroke
				(width 0.1)
				(type default)
			)
			(layer "F.Fab")
		)
		(fp_line
			(start -4.0386 1.7526)
			(end -4.0386 -1.7526)
			(stroke
				(width 0.1)
				(type default)
			)
			(layer "F.Fab")
		)
		(pad "1" smd rect
			(at -3.1115 0 90)
			(size 1.524 3.2004)
			(layers "F.Cu" "F.Mask" "F.Paste")
			(net "P12V_SCM")
		)
		(pad "2" smd rect
			(at 3.1115 0 90)
			(size 1.524 3.2004)
			(layers "F.Cu" "F.Mask" "F.Paste")
			(net "P12V_SCM_R")
		)
	)
	(footprint ""
		(layer "F.Cu")
		(at 35.066478 -17.623536 90)
		(property "Reference" "C820"
			(at 0 0 90)
			(layer "F.SilkS")
			(hide yes)
			(effects
				(font
					(size 1.27 1.27)
				)
			)
		)
		(property "Value" ""
			(at 0 0 90)
			(layer "F.Fab")
			(effects
				(font
					(size 1.27 1.27)
				)
			)
		)
		(duplicate_pad_numbers_are_jumpers no)
		(fp_line
			(start 0.299974 -0.150114)
			(end 0.299974 0.150114)
			(stroke
				(width 0.1)
				(type default)
			)
			(layer "F.Fab")
		)
		(fp_line
			(start -0.299974 -0.150114)
			(end 0.299974 -0.150114)
			(stroke
				(width 0.1)
				(type default)
			)
			(layer "F.Fab")
		)
		(fp_line
			(start 0.299974 0.150114)
			(end -0.299974 0.150114)
			(stroke
				(width 0.1)
				(type default)
			)
			(layer "F.Fab")
		)
		(fp_line
			(start -0.299974 0.150114)
			(end -0.299974 -0.150114)
			(stroke
				(width 0.1)
				(type default)
			)
			(layer "F.Fab")
		)
		(pad "1" smd rect
			(at -0.2667 0 90)
			(size 0.3048 0.381)
			(layers "F.Cu" "F.Mask" "F.Paste")
			(net "P5E_CPU1_PE1_TX_C_DN<8>")
		)
		(pad "2" smd rect
			(at 0.2667 0 90)
			(size 0.3048 0.381)
			(layers "F.Cu" "F.Mask" "F.Paste")
			(net "P5E_CPU1_PE1_TX_DN<8>")
		)
	)
	(footprint ""
		(layer "F.Cu")
		(at 277.6347 -95.029274)
		(property "Reference" "R717"
			(at 0 0 0)
			(layer "F.SilkS")
			(hide yes)
			(effects
				(font
					(size 1.27 1.27)
				)
			)
		)
		(property "Value" ""
			(at 0 0 0)
			(layer "F.Fab")
			(effects
				(font
					(size 1.27 1.27)
				)
			)
		)
		(duplicate_pad_numbers_are_jumpers no)
		(fp_line
			(start -0.7874 -0.4064)
			(end 0.7874 -0.4064)
			(stroke
				(width 0.1524)
				(type default)
			)
			(layer "F.SilkS")
		)
		(fp_line
			(start -0.7874 0.4064)
			(end -0.7874 -0.4064)
			(stroke
				(width 0.1524)
				(type default)
			)
			(layer "F.SilkS")
		)
		(fp_line
			(start 0.7874 -0.4064)
			(end 0.7874 0.4064)
			(stroke
				(width 0.1524)
				(type default)
			)
			(layer "F.SilkS")
		)
		(fp_line
			(start 0.7874 0.4064)
			(end -0.7874 0.4064)
			(stroke
				(width 0.1524)
				(type default)
			)
			(layer "F.SilkS")
		)
		(fp_line
			(start -0.67945 -0.305054)
			(end -0.12065 -0.305054)
			(stroke
				(width 0.1)
				(type default)
			)
			(layer "F.Fab")
		)
		(fp_line
			(start -0.67945 0.3048)
			(end -0.67945 -0.305054)
			(stroke
				(width 0.1)
				(type default)
			)
			(layer "F.Fab")
		)
		(fp_line
			(start -0.12065 -0.305054)
			(end -0.12065 -0.2794)
			(stroke
				(width 0.1)
				(type default)
			)
			(layer "F.Fab")
		)
		(fp_line
			(start -0.12065 -0.2794)
			(end 0.12065 -0.2794)
			(stroke
				(width 0.1)
				(type default)
			)
			(layer "F.Fab")
		)
		(fp_line
			(start -0.12065 0.2794)
			(end -0.12065 0.3048)
			(stroke
				(width 0.1)
				(type default)
			)
			(layer "F.Fab")
		)
		(fp_line
			(start -0.12065 0.3048)
			(end -0.67945 0.3048)
			(stroke
				(width 0.1)
				(type default)
			)
			(layer "F.Fab")
		)
		(fp_line
			(start 0.120396 0.2794)
			(end -0.12065 0.2794)
			(stroke
				(width 0.1)
				(type default)
			)
			(layer "F.Fab")
		)
		(fp_line
			(start 0.120396 0.3048)
			(end 0.120396 0.2794)
			(stroke
				(width 0.1)
				(type default)
			)
			(layer "F.Fab")
		)
		(fp_line
			(start 0.12065 -0.3048)
			(end 0.67945 -0.3048)
			(stroke
				(width 0.1)
				(type default)
			)
			(layer "F.Fab")
		)
		(fp_line
			(start 0.12065 -0.2794)
			(end 0.12065 -0.3048)
			(stroke
				(width 0.1)
				(type default)
			)
			(layer "F.Fab")
		)
		(fp_line
			(start 0.67945 -0.3048)
			(end 0.67945 0.3048)
			(stroke
				(width 0.1)
				(type default)
			)
			(layer "F.Fab")
		)
		(fp_line
			(start 0.67945 0.3048)
			(end 0.120396 0.3048)
			(stroke
				(width 0.1)
				(type default)
			)
			(layer "F.Fab")
		)
		(pad "1" smd circle
			(at -0.40005 0)
			(size 0 0)
			(layers "F.Cu" "F.Mask" "F.Paste")
			(net "P3V3_AUX")
		)
		(pad "2" smd circle
			(at 0.40005 0)
			(size 0 0)
			(layers "F.Cu" "F.Mask" "F.Paste")
			(net "MB_FRU_ADDR1")
		)
	)
	(footprint ""
		(layer "F.Cu")
		(at 30.765242 -179.587906)
		(property "Reference" "PL121"
			(at -1.874012 5.29082 0)
			(unlocked yes)
			(layer "F.SilkS")
			(effects
				(font
					(size 0.7874 0.5842)
					(thickness 0.1524)
				)
				(justify left)
			)
		)
		(property "Value" ""
			(at 0 0 0)
			(layer "F.Fab")
			(effects
				(font
					(size 1.27 1.27)
				)
			)
		)
		(duplicate_pad_numbers_are_jumpers no)
		(fp_line
			(start -3.6576 -3.350006)
			(end 3.64998 -3.350006)
			(stroke
				(width 0.1524)
				(type default)
			)
			(layer "F.SilkS")
		)
		(fp_line
			(start -3.64998 -1.8034)
			(end -3.64998 -3.350006)
			(stroke
				(width 0.1524)
				(type default)
			)
			(layer "F.SilkS")
		)
		(fp_line
			(start -3.64998 3.350006)
			(end -3.64998 1.8288)
			(stroke
				(width 0.1524)
				(type default)
			)
			(layer "F.SilkS")
		)
		(fp_line
			(start 3.64998 -3.350006)
			(end 3.64998 -1.8034)
			(stroke
				(width 0.1524)
				(type default)
			)
			(layer "F.SilkS")
		)
		(fp_line
			(start 3.64998 1.8034)
			(end 3.64998 3.350006)
			(stroke
				(width 0.1524)
				(type default)
			)
			(layer "F.SilkS")
		)
		(fp_line
			(start 3.64998 3.350006)
			(end -3.64998 3.350006)
			(stroke
				(width 0.1524)
				(type default)
			)
			(layer "F.SilkS")
		)
		(fp_line
			(start -3.64998 -3.350006)
			(end 3.64998 -3.350006)
			(stroke
				(width 0.1)
				(type default)
			)
			(layer "F.Fab")
		)
		(fp_line
			(start -3.64998 3.350006)
			(end -3.64998 -3.350006)
			(stroke
				(width 0.1)
				(type default)
			)
			(layer "F.Fab")
		)
		(fp_line
			(start 3.64998 -3.350006)
			(end 3.64998 3.350006)
			(stroke
				(width 0.1)
				(type default)
			)
			(layer "F.Fab")
		)
		(fp_line
			(start 3.64998 3.350006)
			(end -3.64998 3.350006)
			(stroke
				(width 0.1)
				(type default)
			)
			(layer "F.Fab")
		)
		(pad "1" smd rect
			(at -2.92481 0)
			(size 2.15392 3.302)
			(layers "F.Cu" "F.Mask" "F.Paste")
			(net "SW_PVNN_MAIN_CPU1_SW")
		)
		(pad "2" smd rect
			(at 2.92481 0)
			(size 2.15392 3.302)
			(layers "F.Cu" "F.Mask" "F.Paste")
			(net "PVNN_MAIN_CPU1")
		)
	)
	(footprint ""
		(layer "F.Cu")
		(at 187.28436 -29.77769 -90)
		(property "Reference" "PC2230"
			(at 0 0 270)
			(layer "F.SilkS")
			(hide yes)
			(effects
				(font
					(size 1.27 1.27)
				)
			)
		)
		(property "Value" ""
			(at 0 0 270)
			(layer "F.Fab")
			(effects
				(font
					(size 1.27 1.27)
				)
			)
		)
		(duplicate_pad_numbers_are_jumpers no)
		(fp_line
			(start -0.7874 0.4064)
			(end -0.7874 -0.4064)
			(stroke
				(width 0.1524)
				(type default)
			)
			(layer "F.SilkS")
		)
		(fp_line
			(start 0.7874 0.4064)
			(end -0.7874 0.4064)
			(stroke
				(width 0.1524)
				(type default)
			)
			(layer "F.SilkS")
		)
		(fp_line
			(start -0.7874 -0.4064)
			(end 0.7874 -0.4064)
			(stroke
				(width 0.1524)
				(type default)
			)
			(layer "F.SilkS")
		)
		(fp_line
			(start 0.7874 -0.4064)
			(end 0.7874 0.4064)
			(stroke
				(width 0.1524)
				(type default)
			)
			(layer "F.SilkS")
		)
		(fp_line
			(start -0.67945 0.3048)
			(end -0.67945 -0.305054)
			(stroke
				(width 0.1)
				(type default)
			)
			(layer "F.Fab")
		)
		(fp_line
			(start -0.12065 0.3048)
			(end -0.67945 0.3048)
			(stroke
				(width 0.1)
				(type default)
			)
			(layer "F.Fab")
		)
		(fp_line
			(start 0.120396 0.3048)
			(end 0.120396 0.2794)
			(stroke
				(width 0.1)
				(type default)
			)
			(layer "F.Fab")
		)
		(fp_line
			(start 0.67945 0.3048)
			(end 0.120396 0.3048)
			(stroke
				(width 0.1)
				(type default)
			)
			(layer "F.Fab")
		)
		(fp_line
			(start -0.12065 0.2794)
			(end -0.12065 0.3048)
			(stroke
				(width 0.1)
				(type default)
			)
			(layer "F.Fab")
		)
		(fp_line
			(start 0.120396 0.2794)
			(end -0.12065 0.2794)
			(stroke
				(width 0.1)
				(type default)
			)
			(layer "F.Fab")
		)
		(fp_line
			(start -0.12065 -0.2794)
			(end 0.12065 -0.2794)
			(stroke
				(width 0.1)
				(type default)
			)
			(layer "F.Fab")
		)
		(fp_line
			(start 0.12065 -0.2794)
			(end 0.12065 -0.3048)
			(stroke
				(width 0.1)
				(type default)
			)
			(layer "F.Fab")
		)
		(fp_line
			(start 0.12065 -0.3048)
			(end 0.67945 -0.3048)
			(stroke
				(width 0.1)
				(type default)
			)
			(layer "F.Fab")
		)
		(fp_line
			(start 0.67945 -0.3048)
			(end 0.67945 0.3048)
			(stroke
				(width 0.1)
				(type default)
			)
			(layer "F.Fab")
		)
		(fp_line
			(start -0.67945 -0.305054)
			(end -0.12065 -0.305054)
			(stroke
				(width 0.1)
				(type default)
			)
			(layer "F.Fab")
		)
		(fp_line
			(start -0.12065 -0.305054)
			(end -0.12065 -0.2794)
			(stroke
				(width 0.1)
				(type default)
			)
			(layer "F.Fab")
		)
		(pad "1" smd circle
			(at -0.40005 0 270)
			(size 0 0)
			(layers "F.Cu" "F.Mask" "F.Paste")
			(net "P12V_AUX")
		)
		(pad "2" smd circle
			(at 0.40005 0 270)
			(size 0 0)
			(layers "F.Cu" "F.Mask" "F.Paste")
			(net "GND")
		)
	)
	(footprint ""
		(layer "F.Cu")
		(at 428.007526 -140.269214 180)
		(property "Reference" "PC215"
			(at 0 0 180)
			(layer "F.SilkS")
			(hide yes)
			(effects
				(font
					(size 1.27 1.27)
				)
			)
		)
		(property "Value" ""
			(at 0 0 180)
			(layer "F.Fab")
			(effects
				(font
					(size 1.27 1.27)
				)
			)
		)
		(duplicate_pad_numbers_are_jumpers no)
		(fp_line
			(start 0.7874 0.4064)
			(end -0.7874 0.4064)
			(stroke
				(width 0.1524)
				(type default)
			)
			(layer "F.SilkS")
		)
		(fp_line
			(start 0.7874 -0.4064)
			(end 0.7874 0.4064)
			(stroke
				(width 0.1524)
				(type default)
			)
			(layer "F.SilkS")
		)
		(fp_line
			(start -0.7874 0.4064)
			(end -0.7874 -0.4064)
			(stroke
				(width 0.1524)
				(type default)
			)
			(layer "F.SilkS")
		)
		(fp_line
			(start -0.7874 -0.4064)
			(end 0.7874 -0.4064)
			(stroke
				(width 0.1524)
				(type default)
			)
			(layer "F.SilkS")
		)
		(fp_line
			(start 0.67945 0.3048)
			(end 0.120396 0.3048)
			(stroke
				(width 0.1)
				(type default)
			)
			(layer "F.Fab")
		)
		(fp_line
			(start 0.67945 -0.3048)
			(end 0.67945 0.3048)
			(stroke
				(width 0.1)
				(type default)
			)
			(layer "F.Fab")
		)
		(fp_line
			(start 0.12065 -0.2794)
			(end 0.12065 -0.3048)
			(stroke
				(width 0.1)
				(type default)
			)
			(layer "F.Fab")
		)
		(fp_line
			(start 0.12065 -0.3048)
			(end 0.67945 -0.3048)
			(stroke
				(width 0.1)
				(type default)
			)
			(layer "F.Fab")
		)
		(fp_line
			(start 0.120396 0.3048)
			(end 0.120396 0.2794)
			(stroke
				(width 0.1)
				(type default)
			)
			(layer "F.Fab")
		)
		(fp_line
			(start 0.120396 0.2794)
			(end -0.12065 0.2794)
			(stroke
				(width 0.1)
				(type default)
			)
			(layer "F.Fab")
		)
		(fp_line
			(start -0.12065 0.3048)
			(end -0.67945 0.3048)
			(stroke
				(width 0.1)
				(type default)
			)
			(layer "F.Fab")
		)
		(fp_line
			(start -0.12065 0.2794)
			(end -0.12065 0.3048)
			(stroke
				(width 0.1)
				(type default)
			)
			(layer "F.Fab")
		)
		(fp_line
			(start -0.12065 -0.2794)
			(end 0.12065 -0.2794)
			(stroke
				(width 0.1)
				(type default)
			)
			(layer "F.Fab")
		)
		(fp_line
			(start -0.12065 -0.305054)
			(end -0.12065 -0.2794)
			(stroke
				(width 0.1)
				(type default)
			)
			(layer "F.Fab")
		)
		(fp_line
			(start -0.67945 0.3048)
			(end -0.67945 -0.305054)
			(stroke
				(width 0.1)
				(type default)
			)
			(layer "F.Fab")
		)
		(fp_line
			(start -0.67945 -0.305054)
			(end -0.12065 -0.305054)
			(stroke
				(width 0.1)
				(type default)
			)
			(layer "F.Fab")
		)
		(pad "1" smd circle
			(at -0.40005 0 180)
			(size 0 0)
			(layers "F.Cu" "F.Mask" "F.Paste")
			(net "SH_PVCCINFAON_CPU0_R")
		)
		(pad "2" smd circle
			(at 0.40005 0 180)
			(size 0 0)
			(layers "F.Cu" "F.Mask" "F.Paste")
			(net "VSENSE_PVCCINFAON_CPU0_DN")
		)
	)
	(footprint ""
		(layer "F.Cu")
		(at 363.62005 -355.985826 90)
		(property "Reference" "PJ53"
			(at -0.293878 1.27762 90)
			(unlocked yes)
			(layer "F.SilkS")
			(effects
				(font
					(size 0.7874 0.5842)
					(thickness 0.1524)
				)
				(justify left)
			)
		)
		(property "Value" ""
			(at 0 0 90)
			(layer "F.Fab")
			(effects
				(font
					(size 1.27 1.27)
				)
			)
		)
		(duplicate_pad_numbers_are_jumpers no)
		(pad "1" smd circle
			(at -0.7493 0 180)
			(size 0 0)
			(layers "F.Cu" "F.Mask" "F.Paste")
			(net "VSENSE_PVCCFA_EHV_FIVRA_CPU0_DP")
		)
		(pad "2" smd rect
			(at 0.7493 0)
			(size 0.7112 0.8128)
			(layers "F.Cu" "F.Mask" "F.Paste")
			(net "SH_PVCCFA_EHV_FIVRA_CPU0")
		)
		(zone
			(layer "F.Cu")
			(hatch none 0.5)
			(connect_pads
				(clearance 0)
			)
			(min_thickness 0.25)
			(keepout
				(tracks allowed)
				(vias not_allowed)
				(pads allowed)
				(copperpour not_allowed)
				(footprints allowed)
			)
			(placement
				(enabled no)
				(sheetname "")
			)
			(fill
				(thermal_gap 0.5)
				(thermal_bridge_width 0.5)
				(island_removal_mode 0)
			)
			(polygon
				(pts
					(xy 363.21365 -354.804726) (xy 364.031276 -354.804726) (xy 364.031276 -357.192326) (xy 363.21365 -357.192326)
				)
			)
		)
	)
	(footprint ""
		(layer "F.Cu")
		(at 120.908572 -133.971538)
		(property "Reference" "U36"
			(at -2.1844 -4.587748 0)
			(unlocked yes)
			(layer "F.SilkS")
			(effects
				(font
					(size 0.7874 0.5842)
					(thickness 0.1524)
				)
				(justify left)
			)
		)
		(property "Value" ""
			(at 0 0 0)
			(layer "F.Fab")
			(effects
				(font
					(size 1.27 1.27)
				)
			)
		)
		(duplicate_pad_numbers_are_jumpers no)
		(fp_line
			(start -1.8542 -3.949954)
			(end -1.8542 3.949954)
			(stroke
				(width 0.1524)
				(type default)
			)
			(layer "F.SilkS")
		)
		(fp_line
			(start -1.8542 3.949954)
			(end 1.8542 3.949954)
			(stroke
				(width 0.1524)
				(type default)
			)
			(layer "F.SilkS")
		)
		(fp_line
			(start -1.282954 -3.949954)
			(end -1.8542 -3.949954)
			(stroke
				(width 0.1524)
				(type default)
			)
			(layer "F.SilkS")
		)
		(fp_line
			(start 0 -2.667)
			(end -1.282954 -3.949954)
			(stroke
				(width 0.1524)
				(type default)
			)
			(layer "F.SilkS")
		)
		(fp_line
			(start 1.282954 -3.949954)
			(end 0 -2.667)
			(stroke
				(width 0.1524)
				(type default)
			)
			(layer "F.SilkS")
		)
		(fp_line
			(start 1.8542 -3.949954)
			(end 1.282954 -3.949954)
			(stroke
				(width 0.1524)
				(type default)
			)
			(layer "F.SilkS")
		)
		(fp_line
			(start 1.8542 3.949954)
			(end 1.8542 -3.949954)
			(stroke
				(width 0.1524)
				(type default)
			)
			(layer "F.SilkS")
		)
		(fp_poly
			(pts
				(xy -4.8006 -4.08305) (xy -4.8006 -3.06705) (xy -3.7846 -3.57505)
			)
			(stroke
				(width 0)
				(type default)
			)
			(fill yes)
			(layer "F.SilkS")
		)
		(fp_line
			(start -2.249932 -3.949954)
			(end -2.249932 3.949954)
			(stroke
				(width 0.1)
				(type default)
			)
			(layer "F.Fab")
		)
		(fp_line
			(start -2.249932 3.949954)
			(end 2.249932 3.949954)
			(stroke
				(width 0.1)
				(type default)
			)
			(layer "F.Fab")
		)
		(fp_line
			(start 2.249932 -3.949954)
			(end -2.249932 -3.949954)
			(stroke
				(width 0.1)
				(type default)
			)
			(layer "F.Fab")
		)
		(fp_line
			(start 2.249932 3.949954)
			(end 2.249932 -3.949954)
			(stroke
				(width 0.1)
				(type default)
			)
			(layer "F.Fab")
		)
		(fp_poly
			(pts
				(xy -4.8006 -4.08305) (xy -4.8006 -3.06705) (xy -3.7846 -3.57505)
			)
			(stroke
				(width 0)
				(type default)
			)
			(fill yes)
			(layer "F.Fab")
		)
		(pad "1" smd rect
			(at -2.800096 -3.57505 270)
			(size 0.3048 1.6002)
			(layers "F.Cu" "F.Mask" "F.Paste")
			(net "PCA9548_PCIE3_ADDR0")
		)
		(pad "2" smd rect
			(at -2.800096 -2.925064 270)
			(size 0.3048 1.6002)
			(layers "F.Cu" "F.Mask" "F.Paste")
			(net "PCA9548_PCIE3_ADDR1")
		)
		(pad "3" smd rect
			(at -2.800096 -2.275078 270)
			(size 0.3048 1.6002)
			(layers "F.Cu" "F.Mask" "F.Paste")
			(net "PU_RST_SMB_PCIE0_N")
		)
		(pad "4" smd rect
			(at -2.800096 -1.625092 270)
			(size 0.3048 1.6002)
			(layers "F.Cu" "F.Mask" "F.Paste")
			(net "Net_283")
		)
		(pad "5" smd rect
			(at -2.800096 -0.975106 270)
			(size 0.3048 1.6002)
			(layers "F.Cu" "F.Mask" "F.Paste")
			(net "Net_281")
		)
		(pad "6" smd rect
			(at -2.800096 -0.32512 270)
			(size 0.3048 1.6002)
			(layers "F.Cu" "F.Mask" "F.Paste")
			(net "SMB_IOEXP_3V3AUX_SDA_R")
		)
		(pad "7" smd rect
			(at -2.800096 0.32512 270)
			(size 0.3048 1.6002)
			(layers "F.Cu" "F.Mask" "F.Paste")
			(net "SMB_IOEXP_3V3AUX_SCL_R")
		)
		(pad "8" smd rect
			(at -2.800096 0.975106 270)
			(size 0.3048 1.6002)
			(layers "F.Cu" "F.Mask" "F.Paste")
			(net "SMB_PCIE0_3V3AUX_SDA_R3")
		)
		(pad "9" smd rect
			(at -2.800096 1.625092 270)
			(size 0.3048 1.6002)
			(layers "F.Cu" "F.Mask" "F.Paste")
			(net "SMB_PCIE0_3V3AUX_SCL_R3")
		)
		(pad "10" smd rect
			(at -2.800096 2.275078 270)
			(size 0.3048 1.6002)
			(layers "F.Cu" "F.Mask" "F.Paste")
			(net "SMB_PCIE0_3V3AUX_SDA_R5")
		)
		(pad "11" smd rect
			(at -2.800096 2.925064 270)
			(size 0.3048 1.6002)
			(layers "F.Cu" "F.Mask" "F.Paste")
			(net "SMB_PCIE0_3V3AUX_SCL_R5")
		)
		(pad "12" smd rect
			(at -2.800096 3.57505 270)
			(size 0.3048 1.6002)
			(layers "F.Cu" "F.Mask" "F.Paste")
			(net "GND")
		)
		(pad "13" smd rect
			(at 2.800096 3.57505 270)
			(size 0.3048 1.6002)
			(layers "F.Cu" "F.Mask" "F.Paste")
			(net "SMB_BMC_SWB_SDA_R4")
		)
		(pad "14" smd rect
			(at 2.800096 2.925064 270)
			(size 0.3048 1.6002)
			(layers "F.Cu" "F.Mask" "F.Paste")
			(net "SMB_BMC_SWB_SCL_R4")
		)
		(pad "15" smd rect
			(at 2.800096 2.275078 270)
			(size 0.3048 1.6002)
			(layers "F.Cu" "F.Mask" "F.Paste")
			(net "SMB_FRU_3V3AUX_SDA_R")
		)
		(pad "16" smd rect
			(at 2.800096 1.625092 270)
			(size 0.3048 1.6002)
			(layers "F.Cu" "F.Mask" "F.Paste")
			(net "SMB_FRU_3V3AUX_SCL_R")
		)
		(pad "17" smd rect
			(at 2.800096 0.975106 270)
			(size 0.3048 1.6002)
			(layers "F.Cu" "F.Mask" "F.Paste")
			(net "SMB_INA230_3V3AUX_SDA_R")
		)
		(pad "18" smd rect
			(at 2.800096 0.32512 270)
			(size 0.3048 1.6002)
			(layers "F.Cu" "F.Mask" "F.Paste")
			(net "SMB_INA230_3V3AUX_SCL_R")
		)
		(pad "19" smd rect
			(at 2.800096 -0.32512 270)
			(size 0.3048 1.6002)
			(layers "F.Cu" "F.Mask" "F.Paste")
			(net "Net_284")
		)
		(pad "20" smd rect
			(at 2.800096 -0.975106 270)
			(size 0.3048 1.6002)
			(layers "F.Cu" "F.Mask" "F.Paste")
			(net "Net_282")
		)
		(pad "21" smd rect
			(at 2.800096 -1.625092 270)
			(size 0.3048 1.6002)
			(layers "F.Cu" "F.Mask" "F.Paste")
			(net "PCA9548_PCIE3_ADDR2")
		)
		(pad "22" smd rect
			(at 2.800096 -2.275078 270)
			(size 0.3048 1.6002)
			(layers "F.Cu" "F.Mask" "F.Paste")
			(net "SMB_PCIE0_3V3AUX_SCL_R")
		)
		(pad "23" smd rect
			(at 2.800096 -2.925064 270)
			(size 0.3048 1.6002)
			(layers "F.Cu" "F.Mask" "F.Paste")
			(net "SMB_PCIE0_3V3AUX_SDA_R")
		)
		(pad "24" smd rect
			(at 2.800096 -3.57505 270)
			(size 0.3048 1.6002)
			(layers "F.Cu" "F.Mask" "F.Paste")
			(net "P3V3_AUX")
		)
	)
	(footprint ""
		(layer "F.Cu")
		(at 22.91588 -429.351948 180)
		(property "Reference" "R2918"
			(at 0 0 180)
			(layer "F.SilkS")
			(hide yes)
			(effects
				(font
					(size 1.27 1.27)
				)
			)
		)
		(property "Value" ""
			(at 0 0 180)
			(layer "F.Fab")
			(effects
				(font
					(size 1.27 1.27)
				)
			)
		)
		(duplicate_pad_numbers_are_jumpers no)
		(fp_line
			(start 0.7874 0.4064)
			(end -0.7874 0.4064)
			(stroke
				(width 0.1524)
				(type default)
			)
			(layer "F.SilkS")
		)
		(fp_line
			(start 0.7874 -0.4064)
			(end 0.7874 0.4064)
			(stroke
				(width 0.1524)
				(type default)
			)
			(layer "F.SilkS")
		)
		(fp_line
			(start -0.7874 0.4064)
			(end -0.7874 -0.4064)
			(stroke
				(width 0.1524)
				(type default)
			)
			(layer "F.SilkS")
		)
		(fp_line
			(start -0.7874 -0.4064)
			(end 0.7874 -0.4064)
			(stroke
				(width 0.1524)
				(type default)
			)
			(layer "F.SilkS")
		)
		(fp_line
			(start 0.67945 0.3048)
			(end 0.120396 0.3048)
			(stroke
				(width 0.1)
				(type default)
			)
			(layer "F.Fab")
		)
		(fp_line
			(start 0.67945 -0.3048)
			(end 0.67945 0.3048)
			(stroke
				(width 0.1)
				(type default)
			)
			(layer "F.Fab")
		)
		(fp_line
			(start 0.12065 -0.2794)
			(end 0.12065 -0.3048)
			(stroke
				(width 0.1)
				(type default)
			)
			(layer "F.Fab")
		)
		(fp_line
			(start 0.12065 -0.3048)
			(end 0.67945 -0.3048)
			(stroke
				(width 0.1)
				(type default)
			)
			(layer "F.Fab")
		)
		(fp_line
			(start 0.120396 0.3048)
			(end 0.120396 0.2794)
			(stroke
				(width 0.1)
				(type default)
			)
			(layer "F.Fab")
		)
		(fp_line
			(start 0.120396 0.2794)
			(end -0.12065 0.2794)
			(stroke
				(width 0.1)
				(type default)
			)
			(layer "F.Fab")
		)
		(fp_line
			(start -0.12065 0.3048)
			(end -0.67945 0.3048)
			(stroke
				(width 0.1)
				(type default)
			)
			(layer "F.Fab")
		)
		(fp_line
			(start -0.12065 0.2794)
			(end -0.12065 0.3048)
			(stroke
				(width 0.1)
				(type default)
			)
			(layer "F.Fab")
		)
		(fp_line
			(start -0.12065 -0.2794)
			(end 0.12065 -0.2794)
			(stroke
				(width 0.1)
				(type default)
			)
			(layer "F.Fab")
		)
		(fp_line
			(start -0.12065 -0.305054)
			(end -0.12065 -0.2794)
			(stroke
				(width 0.1)
				(type default)
			)
			(layer "F.Fab")
		)
		(fp_line
			(start -0.67945 0.3048)
			(end -0.67945 -0.305054)
			(stroke
				(width 0.1)
				(type default)
			)
			(layer "F.Fab")
		)
		(fp_line
			(start -0.67945 -0.305054)
			(end -0.12065 -0.305054)
			(stroke
				(width 0.1)
				(type default)
			)
			(layer "F.Fab")
		)
		(pad "1" smd circle
			(at -0.40005 0 180)
			(size 0 0)
			(layers "F.Cu" "F.Mask" "F.Paste")
			(net "FM_SWB_PWR_EN_R")
		)
		(pad "2" smd circle
			(at 0.40005 0 180)
			(size 0 0)
			(layers "F.Cu" "F.Mask" "F.Paste")
			(net "GND")
		)
	)
	(footprint ""
		(layer "F.Cu")
		(at 24.069802 -412.450534 180)
		(property "Reference" "R3473"
			(at 0 0 180)
			(layer "F.SilkS")
			(hide yes)
			(effects
				(font
					(size 1.27 1.27)
				)
			)
		)
		(property "Value" ""
			(at 0 0 180)
			(layer "F.Fab")
			(effects
				(font
					(size 1.27 1.27)
				)
			)
		)
		(duplicate_pad_numbers_are_jumpers no)
		(fp_line
			(start 0.7874 0.4064)
			(end -0.7874 0.4064)
			(stroke
				(width 0.1524)
				(type default)
			)
			(layer "F.SilkS")
		)
		(fp_line
			(start 0.7874 -0.4064)
			(end 0.7874 0.4064)
			(stroke
				(width 0.1524)
				(type default)
			)
			(layer "F.SilkS")
		)
		(fp_line
			(start -0.7874 0.4064)
			(end -0.7874 -0.4064)
			(stroke
				(width 0.1524)
				(type default)
			)
			(layer "F.SilkS")
		)
		(fp_line
			(start -0.7874 -0.4064)
			(end 0.7874 -0.4064)
			(stroke
				(width 0.1524)
				(type default)
			)
			(layer "F.SilkS")
		)
		(fp_line
			(start 0.67945 0.3048)
			(end 0.120396 0.3048)
			(stroke
				(width 0.1)
				(type default)
			)
			(layer "F.Fab")
		)
		(fp_line
			(start 0.67945 -0.3048)
			(end 0.67945 0.3048)
			(stroke
				(width 0.1)
				(type default)
			)
			(layer "F.Fab")
		)
		(fp_line
			(start 0.12065 -0.2794)
			(end 0.12065 -0.3048)
			(stroke
				(width 0.1)
				(type default)
			)
			(layer "F.Fab")
		)
		(fp_line
			(start 0.12065 -0.3048)
			(end 0.67945 -0.3048)
			(stroke
				(width 0.1)
				(type default)
			)
			(layer "F.Fab")
		)
		(fp_line
			(start 0.120396 0.3048)
			(end 0.120396 0.2794)
			(stroke
				(width 0.1)
				(type default)
			)
			(layer "F.Fab")
		)
		(fp_line
			(start 0.120396 0.2794)
			(end -0.12065 0.2794)
			(stroke
				(width 0.1)
				(type default)
			)
			(layer "F.Fab")
		)
		(fp_line
			(start -0.12065 0.3048)
			(end -0.67945 0.3048)
			(stroke
				(width 0.1)
				(type default)
			)
			(layer "F.Fab")
		)
		(fp_line
			(start -0.12065 0.2794)
			(end -0.12065 0.3048)
			(stroke
				(width 0.1)
				(type default)
			)
			(layer "F.Fab")
		)
		(fp_line
			(start -0.12065 -0.2794)
			(end 0.12065 -0.2794)
			(stroke
				(width 0.1)
				(type default)
			)
			(layer "F.Fab")
		)
		(fp_line
			(start -0.12065 -0.305054)
			(end -0.12065 -0.2794)
			(stroke
				(width 0.1)
				(type default)
			)
			(layer "F.Fab")
		)
		(fp_line
			(start -0.67945 0.3048)
			(end -0.67945 -0.305054)
			(stroke
				(width 0.1)
				(type default)
			)
			(layer "F.Fab")
		)
		(fp_line
			(start -0.67945 -0.305054)
			(end -0.12065 -0.305054)
			(stroke
				(width 0.1)
				(type default)
			)
			(layer "F.Fab")
		)
		(pad "1" smd circle
			(at -0.40005 0 180)
			(size 0 0)
			(layers "F.Cu" "F.Mask" "F.Paste")
			(net "GPU_PRSNT_N")
		)
		(pad "2" smd circle
			(at 0.40005 0 180)
			(size 0 0)
			(layers "F.Cu" "F.Mask" "F.Paste")
			(net "GND")
		)
	)
	(footprint ""
		(layer "F.Cu")
		(at 106.342434 -247.715278 90)
		(property "Reference" "C227"
			(at 0 0 90)
			(layer "F.SilkS")
			(hide yes)
			(effects
				(font
					(size 1.27 1.27)
				)
			)
		)
		(property "Value" ""
			(at 0 0 90)
			(layer "F.Fab")
			(effects
				(font
					(size 1.27 1.27)
				)
			)
		)
		(duplicate_pad_numbers_are_jumpers no)
		(fp_line
			(start 0.7874 -0.4064)
			(end 0.7874 0.4064)
			(stroke
				(width 0.1524)
				(type default)
			)
			(layer "F.SilkS")
		)
		(fp_line
			(start -0.7874 -0.4064)
			(end 0.7874 -0.4064)
			(stroke
				(width 0.1524)
				(type default)
			)
			(layer "F.SilkS")
		)
		(fp_line
			(start 0.7874 0.4064)
			(end -0.7874 0.4064)
			(stroke
				(width 0.1524)
				(type default)
			)
			(layer "F.SilkS")
		)
		(fp_line
			(start -0.7874 0.4064)
			(end -0.7874 -0.4064)
			(stroke
				(width 0.1524)
				(type default)
			)
			(layer "F.SilkS")
		)
		(fp_line
			(start -0.12065 -0.305054)
			(end -0.12065 -0.2794)
			(stroke
				(width 0.1)
				(type default)
			)
			(layer "F.Fab")
		)
		(fp_line
			(start -0.67945 -0.305054)
			(end -0.12065 -0.305054)
			(stroke
				(width 0.1)
				(type default)
			)
			(layer "F.Fab")
		)
		(fp_line
			(start 0.67945 -0.3048)
			(end 0.67945 0.3048)
			(stroke
				(width 0.1)
				(type default)
			)
			(layer "F.Fab")
		)
		(fp_line
			(start 0.12065 -0.3048)
			(end 0.67945 -0.3048)
			(stroke
				(width 0.1)
				(type default)
			)
			(layer "F.Fab")
		)
		(fp_line
			(start 0.12065 -0.2794)
			(end 0.12065 -0.3048)
			(stroke
				(width 0.1)
				(type default)
			)
			(layer "F.Fab")
		)
		(fp_line
			(start -0.12065 -0.2794)
			(end 0.12065 -0.2794)
			(stroke
				(width 0.1)
				(type default)
			)
			(layer "F.Fab")
		)
		(fp_line
			(start 0.120396 0.2794)
			(end -0.12065 0.2794)
			(stroke
				(width 0.1)
				(type default)
			)
			(layer "F.Fab")
		)
		(fp_line
			(start -0.12065 0.2794)
			(end -0.12065 0.3048)
			(stroke
				(width 0.1)
				(type default)
			)
			(layer "F.Fab")
		)
		(fp_line
			(start 0.67945 0.3048)
			(end 0.120396 0.3048)
			(stroke
				(width 0.1)
				(type default)
			)
			(layer "F.Fab")
		)
		(fp_line
			(start 0.120396 0.3048)
			(end 0.120396 0.2794)
			(stroke
				(width 0.1)
				(type default)
			)
			(layer "F.Fab")
		)
		(fp_line
			(start -0.12065 0.3048)
			(end -0.67945 0.3048)
			(stroke
				(width 0.1)
				(type default)
			)
			(layer "F.Fab")
		)
		(fp_line
			(start -0.67945 0.3048)
			(end -0.67945 -0.305054)
			(stroke
				(width 0.1)
				(type default)
			)
			(layer "F.Fab")
		)
		(pad "1" smd circle
			(at -0.40005 0 90)
			(size 0 0)
			(layers "F.Cu" "F.Mask" "F.Paste")
			(net "PVCCIN_CPU1")
		)
		(pad "2" smd circle
			(at 0.40005 0 90)
			(size 0 0)
			(layers "F.Cu" "F.Mask" "F.Paste")
			(net "GND")
		)
	)
	(footprint ""
		(layer "F.Cu")
		(at 250.890278 -92.36964)
		(property "Reference" "R106"
			(at 0 0 0)
			(layer "F.SilkS")
			(hide yes)
			(effects
				(font
					(size 1.27 1.27)
				)
			)
		)
		(property "Value" ""
			(at 0 0 0)
			(layer "F.Fab")
			(effects
				(font
					(size 1.27 1.27)
				)
			)
		)
		(duplicate_pad_numbers_are_jumpers no)
		(fp_line
			(start -0.7874 -0.4064)
			(end 0.7874 -0.4064)
			(stroke
				(width 0.1524)
				(type default)
			)
			(layer "F.SilkS")
		)
		(fp_line
			(start -0.7874 0.4064)
			(end -0.7874 -0.4064)
			(stroke
				(width 0.1524)
				(type default)
			)
			(layer "F.SilkS")
		)
		(fp_line
			(start 0.7874 -0.4064)
			(end 0.7874 0.4064)
			(stroke
				(width 0.1524)
				(type default)
			)
			(layer "F.SilkS")
		)
		(fp_line
			(start 0.7874 0.4064)
			(end -0.7874 0.4064)
			(stroke
				(width 0.1524)
				(type default)
			)
			(layer "F.SilkS")
		)
		(fp_line
			(start -0.67945 -0.305054)
			(end -0.12065 -0.305054)
			(stroke
				(width 0.1)
				(type default)
			)
			(layer "F.Fab")
		)
		(fp_line
			(start -0.67945 0.3048)
			(end -0.67945 -0.305054)
			(stroke
				(width 0.1)
				(type default)
			)
			(layer "F.Fab")
		)
		(fp_line
			(start -0.12065 -0.305054)
			(end -0.12065 -0.2794)
			(stroke
				(width 0.1)
				(type default)
			)
			(layer "F.Fab")
		)
		(fp_line
			(start -0.12065 -0.2794)
			(end 0.12065 -0.2794)
			(stroke
				(width 0.1)
				(type default)
			)
			(layer "F.Fab")
		)
		(fp_line
			(start -0.12065 0.2794)
			(end -0.12065 0.3048)
			(stroke
				(width 0.1)
				(type default)
			)
			(layer "F.Fab")
		)
		(fp_line
			(start -0.12065 0.3048)
			(end -0.67945 0.3048)
			(stroke
				(width 0.1)
				(type default)
			)
			(layer "F.Fab")
		)
		(fp_line
			(start 0.120396 0.2794)
			(end -0.12065 0.2794)
			(stroke
				(width 0.1)
				(type default)
			)
			(layer "F.Fab")
		)
		(fp_line
			(start 0.120396 0.3048)
			(end 0.120396 0.2794)
			(stroke
				(width 0.1)
				(type default)
			)
			(layer "F.Fab")
		)
		(fp_line
			(start 0.12065 -0.3048)
			(end 0.67945 -0.3048)
			(stroke
				(width 0.1)
				(type default)
			)
			(layer "F.Fab")
		)
		(fp_line
			(start 0.12065 -0.2794)
			(end 0.12065 -0.3048)
			(stroke
				(width 0.1)
				(type default)
			)
			(layer "F.Fab")
		)
		(fp_line
			(start 0.67945 -0.3048)
			(end 0.67945 0.3048)
			(stroke
				(width 0.1)
				(type default)
			)
			(layer "F.Fab")
		)
		(fp_line
			(start 0.67945 0.3048)
			(end 0.120396 0.3048)
			(stroke
				(width 0.1)
				(type default)
			)
			(layer "F.Fab")
		)
		(pad "1" smd circle
			(at -0.40005 0)
			(size 0 0)
			(layers "F.Cu" "F.Mask" "F.Paste")
			(net "GND")
		)
		(pad "2" smd circle
			(at 0.40005 0)
			(size 0 0)
			(layers "F.Cu" "F.Mask" "F.Paste")
			(net "FM_PLD_CLKS_DEV_EN")
		)
	)
	(footprint ""
		(layer "F.Cu")
		(at 7.24916 -99.346766)
		(property "Reference" "Y4"
			(at -1.9558 -2.748788 0)
			(unlocked yes)
			(layer "F.SilkS")
			(effects
				(font
					(size 0.7874 0.5842)
					(thickness 0.1524)
				)
				(justify left)
			)
		)
		(property "Value" ""
			(at 0 0 0)
			(layer "F.Fab")
			(effects
				(font
					(size 1.27 1.27)
				)
			)
		)
		(duplicate_pad_numbers_are_jumpers no)
		(fp_line
			(start -1.2446 -1.4986)
			(end -1.2446 1.4986)
			(stroke
				(width 0.1524)
				(type default)
			)
			(layer "F.SilkS")
		)
		(fp_line
			(start -1.2446 1.4986)
			(end 1.2446 1.4986)
			(stroke
				(width 0.1524)
				(type default)
			)
			(layer "F.SilkS")
		)
		(fp_line
			(start 1.2446 -1.4986)
			(end -1.2446 -1.4986)
			(stroke
				(width 0.1524)
				(type default)
			)
			(layer "F.SilkS")
		)
		(fp_line
			(start 1.2446 1.4986)
			(end 1.2446 -1.4986)
			(stroke
				(width 0.1524)
				(type default)
			)
			(layer "F.SilkS")
		)
		(fp_poly
			(pts
				(xy -2.72288 -1.357884) (xy -1.70688 -0.849884) (xy -2.72288 -0.341884)
			)
			(stroke
				(width 0)
				(type default)
			)
			(fill yes)
			(layer "F.SilkS")
		)
		(fp_line
			(start -1.050036 -1.299972)
			(end -1.050036 1.299972)
			(stroke
				(width 0.1)
				(type default)
			)
			(layer "F.Fab")
		)
		(fp_line
			(start -1.050036 1.299972)
			(end 1.050036 1.299972)
			(stroke
				(width 0.1)
				(type default)
			)
			(layer "F.Fab")
		)
		(fp_line
			(start 1.050036 -1.299972)
			(end -1.050036 -1.299972)
			(stroke
				(width 0.1)
				(type default)
			)
			(layer "F.Fab")
		)
		(fp_line
			(start 1.050036 1.299972)
			(end 1.050036 -1.299972)
			(stroke
				(width 0.1)
				(type default)
			)
			(layer "F.Fab")
		)
		(fp_poly
			(pts
				(xy -2.4638 -1.357884) (xy -2.4638 -0.341884) (xy -1.4478 -0.849884)
			)
			(stroke
				(width 0)
				(type default)
			)
			(fill yes)
			(layer "F.Fab")
		)
		(pad "1" smd rect
			(at -0.649986 -0.849884 180)
			(size 0.9144 1.016)
			(layers "F.Cu" "F.Mask" "F.Paste")
			(net "USB_HUB_XTAL_IN")
		)
		(pad "2" smd rect
			(at -0.649986 0.849884 180)
			(size 0.9144 1.016)
			(layers "F.Cu" "F.Mask" "F.Paste")
			(net "GND")
		)
		(pad "3" smd rect
			(at 0.649986 0.849884 180)
			(size 0.9144 1.016)
			(layers "F.Cu" "F.Mask" "F.Paste")
			(net "USB_HUB_XTAL_OUT")
		)
		(pad "4" smd rect
			(at 0.649986 -0.849884 180)
			(size 0.9144 1.016)
			(layers "F.Cu" "F.Mask" "F.Paste")
			(net "GND")
		)
	)
	(footprint ""
		(layer "F.Cu")
		(at 10.63498 -383.867914)
		(property "Reference" "H30"
			(at -2.6416 -7.392924 0)
			(unlocked yes)
			(layer "F.SilkS")
			(effects
				(font
					(size 0.7874 0.5842)
					(thickness 0.1524)
				)
				(justify left)
			)
		)
		(property "Value" ""
			(at 0 0 0)
			(layer "F.Fab")
			(effects
				(font
					(size 1.27 1.27)
				)
			)
		)
		(duplicate_pad_numbers_are_jumpers no)
		(fp_circle
			(center 0 0)
			(end 2.4003 0)
			(stroke
				(width 0.1524)
				(type default)
			)
			(fill no)
			(layer "F.SilkS")
		)
		(fp_circle
			(center 0 0)
			(end 6.5913 0)
			(stroke
				(width 0.1524)
				(type default)
			)
			(fill no)
			(layer "B.SilkS")
		)
		(fp_circle
			(center 0 0)
			(end 6.5913 0)
			(stroke
				(width 0.1)
				(type default)
			)
			(fill no)
			(layer "B.Fab")
		)
		(fp_circle
			(center 0 0)
			(end 2.4003 0)
			(stroke
				(width 0.1)
				(type default)
			)
			(fill no)
			(layer "F.Fab")
		)
		(pad "" np_thru_hole circle
			(at 0 0)
			(size 3.175 3.175)
			(drill 3.175)
			(layers "*.Cu" "*.Mask")
			(clearance 0.381)
			(thermal_gap 0.381)
		)
		(zone
			(layers "F.Cu" "B.Cu" "In1.Cu" "In2.Cu" "In3.Cu" "In4.Cu" "In5.Cu" "In6.Cu"
				"In7.Cu" "In8.Cu" "In9.Cu" "In10.Cu" "In11.Cu" "In12.Cu" "In13.Cu" "In14.Cu"
				"In15.Cu" "In16.Cu"
			)
			(hatch none 0.5)
			(connect_pads
				(clearance 0)
			)
			(min_thickness 0.25)
			(keepout
				(tracks not_allowed)
				(vias allowed)
				(pads allowed)
				(copperpour not_allowed)
				(footprints allowed)
			)
			(placement
				(enabled no)
				(sheetname "")
			)
			(fill
				(thermal_gap 0.5)
				(thermal_bridge_width 0.5)
				(island_removal_mode 0)
			)
			(polygon
				(pts
					(arc
						(start 12.73048 -383.867914)
						(mid 8.53948 -383.867914)
						(end 12.73048 -383.867914)
					)
				)
			)
		)
	)
	(footprint ""
		(layer "F.Cu")
		(at 166.07028 -21.783548 90)
		(property "Reference" "R1356"
			(at 0 0 90)
			(layer "F.SilkS")
			(hide yes)
			(effects
				(font
					(size 1.27 1.27)
				)
			)
		)
		(property "Value" ""
			(at 0 0 90)
			(layer "F.Fab")
			(effects
				(font
					(size 1.27 1.27)
				)
			)
		)
		(duplicate_pad_numbers_are_jumpers no)
		(fp_line
			(start 0.7874 -0.4064)
			(end 0.7874 0.4064)
			(stroke
				(width 0.1524)
				(type default)
			)
			(layer "F.SilkS")
		)
		(fp_line
			(start -0.7874 -0.4064)
			(end 0.7874 -0.4064)
			(stroke
				(width 0.1524)
				(type default)
			)
			(layer "F.SilkS")
		)
		(fp_line
			(start 0.7874 0.4064)
			(end -0.7874 0.4064)
			(stroke
				(width 0.1524)
				(type default)
			)
			(layer "F.SilkS")
		)
		(fp_line
			(start -0.7874 0.4064)
			(end -0.7874 -0.4064)
			(stroke
				(width 0.1524)
				(type default)
			)
			(layer "F.SilkS")
		)
		(fp_line
			(start -0.12065 -0.305054)
			(end -0.12065 -0.2794)
			(stroke
				(width 0.1)
				(type default)
			)
			(layer "F.Fab")
		)
		(fp_line
			(start -0.67945 -0.305054)
			(end -0.12065 -0.305054)
			(stroke
				(width 0.1)
				(type default)
			)
			(layer "F.Fab")
		)
		(fp_line
			(start 0.67945 -0.3048)
			(end 0.67945 0.3048)
			(stroke
				(width 0.1)
				(type default)
			)
			(layer "F.Fab")
		)
		(fp_line
			(start 0.12065 -0.3048)
			(end 0.67945 -0.3048)
			(stroke
				(width 0.1)
				(type default)
			)
			(layer "F.Fab")
		)
		(fp_line
			(start 0.12065 -0.2794)
			(end 0.12065 -0.3048)
			(stroke
				(width 0.1)
				(type default)
			)
			(layer "F.Fab")
		)
		(fp_line
			(start -0.12065 -0.2794)
			(end 0.12065 -0.2794)
			(stroke
				(width 0.1)
				(type default)
			)
			(layer "F.Fab")
		)
		(fp_line
			(start 0.120396 0.2794)
			(end -0.12065 0.2794)
			(stroke
				(width 0.1)
				(type default)
			)
			(layer "F.Fab")
		)
		(fp_line
			(start -0.12065 0.2794)
			(end -0.12065 0.3048)
			(stroke
				(width 0.1)
				(type default)
			)
			(layer "F.Fab")
		)
		(fp_line
			(start 0.67945 0.3048)
			(end 0.120396 0.3048)
			(stroke
				(width 0.1)
				(type default)
			)
			(layer "F.Fab")
		)
		(fp_line
			(start 0.120396 0.3048)
			(end 0.120396 0.2794)
			(stroke
				(width 0.1)
				(type default)
			)
			(layer "F.Fab")
		)
		(fp_line
			(start -0.12065 0.3048)
			(end -0.67945 0.3048)
			(stroke
				(width 0.1)
				(type default)
			)
			(layer "F.Fab")
		)
		(fp_line
			(start -0.67945 0.3048)
			(end -0.67945 -0.305054)
			(stroke
				(width 0.1)
				(type default)
			)
			(layer "F.Fab")
		)
		(pad "1" smd circle
			(at -0.40005 0 90)
			(size 0 0)
			(layers "F.Cu" "F.Mask" "F.Paste")
			(net "RMII_BMC_OCP_RX_ER")
		)
		(pad "2" smd circle
			(at 0.40005 0 90)
			(size 0 0)
			(layers "F.Cu" "F.Mask" "F.Paste")
			(net "GND")
		)
	)
	(footprint ""
		(layer "F.Cu")
		(at 130.233674 -402.371052 -90)
		(property "Reference" "C748"
			(at 0 0 270)
			(layer "F.SilkS")
			(hide yes)
			(effects
				(font
					(size 1.27 1.27)
				)
			)
		)
		(property "Value" ""
			(at 0 0 270)
			(layer "F.Fab")
			(effects
				(font
					(size 1.27 1.27)
				)
			)
		)
		(duplicate_pad_numbers_are_jumpers no)
		(fp_line
			(start -0.299974 0.150114)
			(end -0.299974 -0.150114)
			(stroke
				(width 0.1)
				(type default)
			)
			(layer "F.Fab")
		)
		(fp_line
			(start 0.299974 0.150114)
			(end -0.299974 0.150114)
			(stroke
				(width 0.1)
				(type default)
			)
			(layer "F.Fab")
		)
		(fp_line
			(start -0.299974 -0.150114)
			(end 0.299974 -0.150114)
			(stroke
				(width 0.1)
				(type default)
			)
			(layer "F.Fab")
		)
		(fp_line
			(start 0.299974 -0.150114)
			(end 0.299974 0.150114)
			(stroke
				(width 0.1)
				(type default)
			)
			(layer "F.Fab")
		)
		(pad "1" smd rect
			(at -0.2667 0 270)
			(size 0.3048 0.381)
			(layers "F.Cu" "F.Mask" "F.Paste")
			(net "P5E_CPU1_PE2_TX_C_DN<12>")
		)
		(pad "2" smd rect
			(at 0.2667 0 270)
			(size 0.3048 0.381)
			(layers "F.Cu" "F.Mask" "F.Paste")
			(net "P5E_CPU1_PE2_TX_DN<12>")
		)
	)
	(footprint ""
		(layer "F.Cu")
		(at 33.021524 -124.99721 90)
		(property "Reference" "R2563"
			(at 0 0 90)
			(layer "F.SilkS")
			(hide yes)
			(effects
				(font
					(size 1.27 1.27)
				)
			)
		)
		(property "Value" ""
			(at 0 0 90)
			(layer "F.Fab")
			(effects
				(font
					(size 1.27 1.27)
				)
			)
		)
		(duplicate_pad_numbers_are_jumpers no)
		(fp_line
			(start 0.7874 -0.4064)
			(end 0.7874 0.4064)
			(stroke
				(width 0.1524)
				(type default)
			)
			(layer "F.SilkS")
		)
		(fp_line
			(start -0.7874 -0.4064)
			(end 0.7874 -0.4064)
			(stroke
				(width 0.1524)
				(type default)
			)
			(layer "F.SilkS")
		)
		(fp_line
			(start 0.7874 0.4064)
			(end -0.7874 0.4064)
			(stroke
				(width 0.1524)
				(type default)
			)
			(layer "F.SilkS")
		)
		(fp_line
			(start -0.7874 0.4064)
			(end -0.7874 -0.4064)
			(stroke
				(width 0.1524)
				(type default)
			)
			(layer "F.SilkS")
		)
		(fp_line
			(start -0.12065 -0.305054)
			(end -0.12065 -0.2794)
			(stroke
				(width 0.1)
				(type default)
			)
			(layer "F.Fab")
		)
		(fp_line
			(start -0.67945 -0.305054)
			(end -0.12065 -0.305054)
			(stroke
				(width 0.1)
				(type default)
			)
			(layer "F.Fab")
		)
		(fp_line
			(start 0.67945 -0.3048)
			(end 0.67945 0.3048)
			(stroke
				(width 0.1)
				(type default)
			)
			(layer "F.Fab")
		)
		(fp_line
			(start 0.12065 -0.3048)
			(end 0.67945 -0.3048)
			(stroke
				(width 0.1)
				(type default)
			)
			(layer "F.Fab")
		)
		(fp_line
			(start 0.12065 -0.2794)
			(end 0.12065 -0.3048)
			(stroke
				(width 0.1)
				(type default)
			)
			(layer "F.Fab")
		)
		(fp_line
			(start -0.12065 -0.2794)
			(end 0.12065 -0.2794)
			(stroke
				(width 0.1)
				(type default)
			)
			(layer "F.Fab")
		)
		(fp_line
			(start 0.120396 0.2794)
			(end -0.12065 0.2794)
			(stroke
				(width 0.1)
				(type default)
			)
			(layer "F.Fab")
		)
		(fp_line
			(start -0.12065 0.2794)
			(end -0.12065 0.3048)
			(stroke
				(width 0.1)
				(type default)
			)
			(layer "F.Fab")
		)
		(fp_line
			(start 0.67945 0.3048)
			(end 0.120396 0.3048)
			(stroke
				(width 0.1)
				(type default)
			)
			(layer "F.Fab")
		)
		(fp_line
			(start 0.120396 0.3048)
			(end 0.120396 0.2794)
			(stroke
				(width 0.1)
				(type default)
			)
			(layer "F.Fab")
		)
		(fp_line
			(start -0.12065 0.3048)
			(end -0.67945 0.3048)
			(stroke
				(width 0.1)
				(type default)
			)
			(layer "F.Fab")
		)
		(fp_line
			(start -0.67945 0.3048)
			(end -0.67945 -0.305054)
			(stroke
				(width 0.1)
				(type default)
			)
			(layer "F.Fab")
		)
		(pad "1" smd circle
			(at -0.40005 0 90)
			(size 0 0)
			(layers "F.Cu" "F.Mask" "F.Paste")
			(net "SMB_VR_3V3AUX_SDA_R")
		)
		(pad "2" smd circle
			(at 0.40005 0 90)
			(size 0 0)
			(layers "F.Cu" "F.Mask" "F.Paste")
			(net "SMB_DIO_PVCCINFAON_CPU1")
		)
	)
	(footprint ""
		(layer "F.Cu")
		(at 293.720012 -34.001964 -90)
		(property "Reference" "BT1"
			(at -1.233424 -1.985772 0)
			(unlocked yes)
			(layer "F.SilkS")
			(effects
				(font
					(size 0.7874 0.5842)
					(thickness 0.1524)
				)
				(justify left)
			)
		)
		(property "Value" ""
			(at 0 0 270)
			(layer "F.Fab")
			(effects
				(font
					(size 1.27 1.27)
				)
			)
		)
		(duplicate_pad_numbers_are_jumpers no)
		(fp_line
			(start 3.666236 22.820122)
			(end -3.666236 22.820122)
			(stroke
				(width 0.1524)
				(type default)
			)
			(layer "F.SilkS")
		)
		(fp_line
			(start -4.012692 22.800056)
			(end -3.724148 22.800056)
			(stroke
				(width 0.1524)
				(type default)
			)
			(layer "F.SilkS")
		)
		(fp_line
			(start 3.724148 22.800056)
			(end 4.012692 22.800056)
			(stroke
				(width 0.1524)
				(type default)
			)
			(layer "F.SilkS")
		)
		(fp_line
			(start -3.800094 1.807464)
			(end -3.800094 -1.180084)
			(stroke
				(width 0.1524)
				(type default)
			)
			(layer "F.SilkS")
		)
		(fp_line
			(start 3.899916 1.737614)
			(end 3.899916 -1.260094)
			(stroke
				(width 0.1524)
				(type default)
			)
			(layer "F.SilkS")
		)
		(fp_line
			(start -3.800094 -1.180084)
			(end 3.800094 -1.180084)
			(stroke
				(width 0.1524)
				(type default)
			)
			(layer "F.SilkS")
		)
		(fp_line
			(start 3.800094 -1.180084)
			(end 3.800094 1.807464)
			(stroke
				(width 0.1524)
				(type default)
			)
			(layer "F.SilkS")
		)
		(fp_line
			(start -3.899916 -1.260094)
			(end -3.899916 1.737614)
			(stroke
				(width 0.1524)
				(type default)
			)
			(layer "F.SilkS")
		)
		(fp_line
			(start 3.899916 -1.260094)
			(end -3.899916 -1.260094)
			(stroke
				(width 0.1524)
				(type default)
			)
			(layer "F.SilkS")
		)
		(fp_arc
			(start -3.666236 22.820122)
			(mid -11.149833 12.361061)
			(end -3.800094 1.807464)
			(stroke
				(width 0.1524)
				(type default)
			)
			(layer "F.SilkS")
		)
		(fp_arc
			(start -4.012692 22.800056)
			(mid -11.249872 12.229778)
			(end -3.899916 1.737614)
			(stroke
				(width 0.1524)
				(type default)
			)
			(layer "F.SilkS")
		)
		(fp_arc
			(start 3.800094 1.807464)
			(mid 11.149895 12.361062)
			(end 3.666236 22.820122)
			(stroke
				(width 0.1524)
				(type default)
			)
			(layer "F.SilkS")
		)
		(fp_arc
			(start 3.899916 1.737614)
			(mid 11.249813 12.229779)
			(end 4.012692 22.800056)
			(stroke
				(width 0.1524)
				(type default)
			)
			(layer "F.SilkS")
		)
		(fp_line
			(start 3.666236 22.820122)
			(end -3.666236 22.820122)
			(stroke
				(width 0.1)
				(type default)
			)
			(layer "F.Fab")
		)
		(fp_line
			(start -3.800094 1.807464)
			(end -3.800094 -1.180084)
			(stroke
				(width 0.1)
				(type default)
			)
			(layer "F.Fab")
		)
		(fp_line
			(start -3.800094 -1.180084)
			(end 3.800094 -1.180084)
			(stroke
				(width 0.1)
				(type default)
			)
			(layer "F.Fab")
		)
		(fp_line
			(start 3.800094 -1.180084)
			(end 3.800094 1.807464)
			(stroke
				(width 0.1)
				(type default)
			)
			(layer "F.Fab")
		)
		(fp_arc
			(start -3.666236 22.820122)
			(mid -11.149833 12.361061)
			(end -3.800094 1.807464)
			(stroke
				(width 0.1)
				(type default)
			)
			(layer "F.Fab")
		)
		(fp_arc
			(start 3.800094 1.807464)
			(mid 11.149895 12.361062)
			(end 3.666236 22.820122)
			(stroke
				(width 0.1)
				(type default)
			)
			(layer "F.Fab")
		)
		(fp_text user "-"
			(at 0.26035 22.7076 180)
			(unlocked yes)
			(layer "F.Fab")
			(effects
				(font
					(size 1.905 1.4224)
					(thickness 0.1524)
				)
				(justify left)
			)
		)
		(fp_text user "+"
			(at 0.20955 -2.5908 180)
			(unlocked yes)
			(layer "F.Fab")
			(effects
				(font
					(size 1.905 1.4224)
					(thickness 0.1524)
				)
				(justify left)
			)
		)
		(pad "1" thru_hole rect
			(at 0 0 270)
			(size 1.6256 1.6256)
			(drill 1.1176)
			(layers "*.Cu" "*.Mask")
			(remove_unused_layers no)
			(net "P3V_BAT")
			(clearance 0)
			(padstack
				(mode front_inner_back)
				(layer "Inner"
					(shape circle)
					(size 1.6256 1.6256)
					(clearance 0)
				)
				(layer "B.Cu"
					(shape rect)
					(size 1.6256 1.6256)
					(clearance 0)
				)
			)
		)
		(pad "2" thru_hole circle
			(at 0 19.99996 270)
			(size 1.524 1.524)
			(drill 1.016)
			(layers "*.Cu" "*.Mask")
			(remove_unused_layers no)
			(net "GND")
			(clearance 0)
		)
	)
	(footprint ""
		(layer "F.Cu")
		(at 49.342294 -16.099536 90)
		(property "Reference" "C831"
			(at 0 0 90)
			(layer "F.SilkS")
			(hide yes)
			(effects
				(font
					(size 1.27 1.27)
				)
			)
		)
		(property "Value" ""
			(at 0 0 90)
			(layer "F.Fab")
			(effects
				(font
					(size 1.27 1.27)
				)
			)
		)
		(duplicate_pad_numbers_are_jumpers no)
		(fp_line
			(start 0.299974 -0.150114)
			(end 0.299974 0.150114)
			(stroke
				(width 0.1)
				(type default)
			)
			(layer "F.Fab")
		)
		(fp_line
			(start -0.299974 -0.150114)
			(end 0.299974 -0.150114)
			(stroke
				(width 0.1)
				(type default)
			)
			(layer "F.Fab")
		)
		(fp_line
			(start 0.299974 0.150114)
			(end -0.299974 0.150114)
			(stroke
				(width 0.1)
				(type default)
			)
			(layer "F.Fab")
		)
		(fp_line
			(start -0.299974 0.150114)
			(end -0.299974 -0.150114)
			(stroke
				(width 0.1)
				(type default)
			)
			(layer "F.Fab")
		)
		(pad "1" smd rect
			(at -0.2667 0 90)
			(size 0.3048 0.381)
			(layers "F.Cu" "F.Mask" "F.Paste")
			(net "P5E_CPU1_PE1_TX_C_DP<3>")
		)
		(pad "2" smd rect
			(at 0.2667 0 90)
			(size 0.3048 0.381)
			(layers "F.Cu" "F.Mask" "F.Paste")
			(net "P5E_CPU1_PE1_TX_DP<3>")
		)
	)
	(footprint ""
		(layer "F.Cu")
		(at 70.311518 -402.371052 -90)
		(property "Reference" "C725"
			(at 0 0 270)
			(layer "F.SilkS")
			(hide yes)
			(effects
				(font
					(size 1.27 1.27)
				)
			)
		)
		(property "Value" ""
			(at 0 0 270)
			(layer "F.Fab")
			(effects
				(font
					(size 1.27 1.27)
				)
			)
		)
		(duplicate_pad_numbers_are_jumpers no)
		(fp_line
			(start -0.299974 0.150114)
			(end -0.299974 -0.150114)
			(stroke
				(width 0.1)
				(type default)
			)
			(layer "F.Fab")
		)
		(fp_line
			(start 0.299974 0.150114)
			(end -0.299974 0.150114)
			(stroke
				(width 0.1)
				(type default)
			)
			(layer "F.Fab")
		)
		(fp_line
			(start -0.299974 -0.150114)
			(end 0.299974 -0.150114)
			(stroke
				(width 0.1)
				(type default)
			)
			(layer "F.Fab")
		)
		(fp_line
			(start 0.299974 -0.150114)
			(end 0.299974 0.150114)
			(stroke
				(width 0.1)
				(type default)
			)
			(layer "F.Fab")
		)
		(pad "1" smd rect
			(at -0.2667 0 270)
			(size 0.3048 0.381)
			(layers "F.Cu" "F.Mask" "F.Paste")
			(net "P5E_CPU1_PE0_TX_C_DP<8>")
		)
		(pad "2" smd rect
			(at 0.2667 0 270)
			(size 0.3048 0.381)
			(layers "F.Cu" "F.Mask" "F.Paste")
			(net "P5E_CPU1_PE0_TX_DP<8>")
		)
	)
	(footprint ""
		(layer "F.Cu")
		(at 454.447402 -18.030698)
		(property "Reference" "R3144"
			(at 0 0 0)
			(layer "F.SilkS")
			(hide yes)
			(effects
				(font
					(size 1.27 1.27)
				)
			)
		)
		(property "Value" ""
			(at 0 0 0)
			(layer "F.Fab")
			(effects
				(font
					(size 1.27 1.27)
				)
			)
		)
		(duplicate_pad_numbers_are_jumpers no)
		(fp_line
			(start -0.7874 -0.4064)
			(end 0.7874 -0.4064)
			(stroke
				(width 0.1524)
				(type default)
			)
			(layer "F.SilkS")
		)
		(fp_line
			(start -0.7874 0.4064)
			(end -0.7874 -0.4064)
			(stroke
				(width 0.1524)
				(type default)
			)
			(layer "F.SilkS")
		)
		(fp_line
			(start 0.7874 -0.4064)
			(end 0.7874 0.4064)
			(stroke
				(width 0.1524)
				(type default)
			)
			(layer "F.SilkS")
		)
		(fp_line
			(start 0.7874 0.4064)
			(end -0.7874 0.4064)
			(stroke
				(width 0.1524)
				(type default)
			)
			(layer "F.SilkS")
		)
		(fp_line
			(start -0.67945 -0.305054)
			(end -0.12065 -0.305054)
			(stroke
				(width 0.1)
				(type default)
			)
			(layer "F.Fab")
		)
		(fp_line
			(start -0.67945 0.3048)
			(end -0.67945 -0.305054)
			(stroke
				(width 0.1)
				(type default)
			)
			(layer "F.Fab")
		)
		(fp_line
			(start -0.12065 -0.305054)
			(end -0.12065 -0.2794)
			(stroke
				(width 0.1)
				(type default)
			)
			(layer "F.Fab")
		)
		(fp_line
			(start -0.12065 -0.2794)
			(end 0.12065 -0.2794)
			(stroke
				(width 0.1)
				(type default)
			)
			(layer "F.Fab")
		)
		(fp_line
			(start -0.12065 0.2794)
			(end -0.12065 0.3048)
			(stroke
				(width 0.1)
				(type default)
			)
			(layer "F.Fab")
		)
		(fp_line
			(start -0.12065 0.3048)
			(end -0.67945 0.3048)
			(stroke
				(width 0.1)
				(type default)
			)
			(layer "F.Fab")
		)
		(fp_line
			(start 0.120396 0.2794)
			(end -0.12065 0.2794)
			(stroke
				(width 0.1)
				(type default)
			)
			(layer "F.Fab")
		)
		(fp_line
			(start 0.120396 0.3048)
			(end 0.120396 0.2794)
			(stroke
				(width 0.1)
				(type default)
			)
			(layer "F.Fab")
		)
		(fp_line
			(start 0.12065 -0.3048)
			(end 0.67945 -0.3048)
			(stroke
				(width 0.1)
				(type default)
			)
			(layer "F.Fab")
		)
		(fp_line
			(start 0.12065 -0.2794)
			(end 0.12065 -0.3048)
			(stroke
				(width 0.1)
				(type default)
			)
			(layer "F.Fab")
		)
		(fp_line
			(start 0.67945 -0.3048)
			(end 0.67945 0.3048)
			(stroke
				(width 0.1)
				(type default)
			)
			(layer "F.Fab")
		)
		(fp_line
			(start 0.67945 0.3048)
			(end 0.120396 0.3048)
			(stroke
				(width 0.1)
				(type default)
			)
			(layer "F.Fab")
		)
		(pad "1" smd circle
			(at -0.40005 0)
			(size 0 0)
			(layers "F.Cu" "F.Mask" "F.Paste")
			(net "P12V_OCP_PWRGD_1")
		)
		(pad "2" smd circle
			(at 0.40005 0)
			(size 0 0)
			(layers "F.Cu" "F.Mask" "F.Paste")
			(net "HP_LVC3_OCP_V3_1_P12V_PWRGD")
		)
	)
	(footprint ""
		(layer "F.Cu")
		(at 338.564728 -402.371052 -90)
		(property "Reference" "C1556"
			(at 0 0 270)
			(layer "F.SilkS")
			(hide yes)
			(effects
				(font
					(size 1.27 1.27)
				)
			)
		)
		(property "Value" ""
			(at 0 0 270)
			(layer "F.Fab")
			(effects
				(font
					(size 1.27 1.27)
				)
			)
		)
		(duplicate_pad_numbers_are_jumpers no)
		(fp_line
			(start -0.299974 0.150114)
			(end -0.299974 -0.150114)
			(stroke
				(width 0.1)
				(type default)
			)
			(layer "F.Fab")
		)
		(fp_line
			(start 0.299974 0.150114)
			(end -0.299974 0.150114)
			(stroke
				(width 0.1)
				(type default)
			)
			(layer "F.Fab")
		)
		(fp_line
			(start -0.299974 -0.150114)
			(end 0.299974 -0.150114)
			(stroke
				(width 0.1)
				(type default)
			)
			(layer "F.Fab")
		)
		(fp_line
			(start 0.299974 -0.150114)
			(end 0.299974 0.150114)
			(stroke
				(width 0.1)
				(type default)
			)
			(layer "F.Fab")
		)
		(pad "1" smd rect
			(at -0.2667 0 270)
			(size 0.3048 0.381)
			(layers "F.Cu" "F.Mask" "F.Paste")
			(net "P5E_CPU0_PE4_TX_C_DN<11>")
		)
		(pad "2" smd rect
			(at 0.2667 0 270)
			(size 0.3048 0.381)
			(layers "F.Cu" "F.Mask" "F.Paste")
			(net "P5E_CPU0_PE4_TX_DN<11>")
		)
	)
	(footprint ""
		(layer "F.Cu")
		(at 225.270568 -233.76255)
		(property "Reference" "R978"
			(at 0 0 0)
			(layer "F.SilkS")
			(hide yes)
			(effects
				(font
					(size 1.27 1.27)
				)
			)
		)
		(property "Value" ""
			(at 0 0 0)
			(layer "F.Fab")
			(effects
				(font
					(size 1.27 1.27)
				)
			)
		)
		(duplicate_pad_numbers_are_jumpers no)
		(fp_line
			(start -0.7874 -0.4064)
			(end 0.7874 -0.4064)
			(stroke
				(width 0.1524)
				(type default)
			)
			(layer "F.SilkS")
		)
		(fp_line
			(start -0.7874 0.4064)
			(end -0.7874 -0.4064)
			(stroke
				(width 0.1524)
				(type default)
			)
			(layer "F.SilkS")
		)
		(fp_line
			(start 0.7874 -0.4064)
			(end 0.7874 0.4064)
			(stroke
				(width 0.1524)
				(type default)
			)
			(layer "F.SilkS")
		)
		(fp_line
			(start 0.7874 0.4064)
			(end -0.7874 0.4064)
			(stroke
				(width 0.1524)
				(type default)
			)
			(layer "F.SilkS")
		)
		(fp_line
			(start -0.67945 -0.305054)
			(end -0.12065 -0.305054)
			(stroke
				(width 0.1)
				(type default)
			)
			(layer "F.Fab")
		)
		(fp_line
			(start -0.67945 0.3048)
			(end -0.67945 -0.305054)
			(stroke
				(width 0.1)
				(type default)
			)
			(layer "F.Fab")
		)
		(fp_line
			(start -0.12065 -0.305054)
			(end -0.12065 -0.2794)
			(stroke
				(width 0.1)
				(type default)
			)
			(layer "F.Fab")
		)
		(fp_line
			(start -0.12065 -0.2794)
			(end 0.12065 -0.2794)
			(stroke
				(width 0.1)
				(type default)
			)
			(layer "F.Fab")
		)
		(fp_line
			(start -0.12065 0.2794)
			(end -0.12065 0.3048)
			(stroke
				(width 0.1)
				(type default)
			)
			(layer "F.Fab")
		)
		(fp_line
			(start -0.12065 0.3048)
			(end -0.67945 0.3048)
			(stroke
				(width 0.1)
				(type default)
			)
			(layer "F.Fab")
		)
		(fp_line
			(start 0.120396 0.2794)
			(end -0.12065 0.2794)
			(stroke
				(width 0.1)
				(type default)
			)
			(layer "F.Fab")
		)
		(fp_line
			(start 0.120396 0.3048)
			(end 0.120396 0.2794)
			(stroke
				(width 0.1)
				(type default)
			)
			(layer "F.Fab")
		)
		(fp_line
			(start 0.12065 -0.3048)
			(end 0.67945 -0.3048)
			(stroke
				(width 0.1)
				(type default)
			)
			(layer "F.Fab")
		)
		(fp_line
			(start 0.12065 -0.2794)
			(end 0.12065 -0.3048)
			(stroke
				(width 0.1)
				(type default)
			)
			(layer "F.Fab")
		)
		(fp_line
			(start 0.67945 -0.3048)
			(end 0.67945 0.3048)
			(stroke
				(width 0.1)
				(type default)
			)
			(layer "F.Fab")
		)
		(fp_line
			(start 0.67945 0.3048)
			(end 0.120396 0.3048)
			(stroke
				(width 0.1)
				(type default)
			)
			(layer "F.Fab")
		)
		(pad "1" smd circle
			(at -0.40005 0)
			(size 0 0)
			(layers "F.Cu" "F.Mask" "F.Paste")
			(net "P3V3_AUX")
		)
		(pad "2" smd circle
			(at 0.40005 0)
			(size 0 0)
			(layers "F.Cu" "F.Mask" "F.Paste")
			(net "SMB_S3M_CPU1_3V3AUX_SCL")
		)
	)
	(footprint ""
		(layer "F.Cu")
		(at 94.817438 -402.371052 -90)
		(property "Reference" "C741"
			(at 0 0 270)
			(layer "F.SilkS")
			(hide yes)
			(effects
				(font
					(size 1.27 1.27)
				)
			)
		)
		(property "Value" ""
			(at 0 0 270)
			(layer "F.Fab")
			(effects
				(font
					(size 1.27 1.27)
				)
			)
		)
		(duplicate_pad_numbers_are_jumpers no)
		(fp_line
			(start -0.299974 0.150114)
			(end -0.299974 -0.150114)
			(stroke
				(width 0.1)
				(type default)
			)
			(layer "F.Fab")
		)
		(fp_line
			(start 0.299974 0.150114)
			(end -0.299974 0.150114)
			(stroke
				(width 0.1)
				(type default)
			)
			(layer "F.Fab")
		)
		(fp_line
			(start -0.299974 -0.150114)
			(end 0.299974 -0.150114)
			(stroke
				(width 0.1)
				(type default)
			)
			(layer "F.Fab")
		)
		(fp_line
			(start 0.299974 -0.150114)
			(end 0.299974 0.150114)
			(stroke
				(width 0.1)
				(type default)
			)
			(layer "F.Fab")
		)
		(pad "1" smd rect
			(at -0.2667 0 270)
			(size 0.3048 0.381)
			(layers "F.Cu" "F.Mask" "F.Paste")
			(net "P5E_CPU1_PE0_TX_C_DP<0>")
		)
		(pad "2" smd rect
			(at 0.2667 0 270)
			(size 0.3048 0.381)
			(layers "F.Cu" "F.Mask" "F.Paste")
			(net "P5E_CPU1_PE0_TX_DP<0>")
		)
	)
	(footprint ""
		(layer "F.Cu")
		(at 144.54378 -344.232738 180)
		(property "Reference" "PR639"
			(at 0 0 180)
			(layer "F.SilkS")
			(hide yes)
			(effects
				(font
					(size 1.27 1.27)
				)
			)
		)
		(property "Value" ""
			(at 0 0 180)
			(layer "F.Fab")
			(effects
				(font
					(size 1.27 1.27)
				)
			)
		)
		(duplicate_pad_numbers_are_jumpers no)
		(fp_line
			(start 0.7874 0.4064)
			(end -0.7874 0.4064)
			(stroke
				(width 0.1524)
				(type default)
			)
			(layer "F.SilkS")
		)
		(fp_line
			(start 0.7874 -0.4064)
			(end 0.7874 0.4064)
			(stroke
				(width 0.1524)
				(type default)
			)
			(layer "F.SilkS")
		)
		(fp_line
			(start -0.7874 0.4064)
			(end -0.7874 -0.4064)
			(stroke
				(width 0.1524)
				(type default)
			)
			(layer "F.SilkS")
		)
		(fp_line
			(start -0.7874 -0.4064)
			(end 0.7874 -0.4064)
			(stroke
				(width 0.1524)
				(type default)
			)
			(layer "F.SilkS")
		)
		(fp_line
			(start 0.67945 0.3048)
			(end 0.120396 0.3048)
			(stroke
				(width 0.1)
				(type default)
			)
			(layer "F.Fab")
		)
		(fp_line
			(start 0.67945 -0.3048)
			(end 0.67945 0.3048)
			(stroke
				(width 0.1)
				(type default)
			)
			(layer "F.Fab")
		)
		(fp_line
			(start 0.12065 -0.2794)
			(end 0.12065 -0.3048)
			(stroke
				(width 0.1)
				(type default)
			)
			(layer "F.Fab")
		)
		(fp_line
			(start 0.12065 -0.3048)
			(end 0.67945 -0.3048)
			(stroke
				(width 0.1)
				(type default)
			)
			(layer "F.Fab")
		)
		(fp_line
			(start 0.120396 0.3048)
			(end 0.120396 0.2794)
			(stroke
				(width 0.1)
				(type default)
			)
			(layer "F.Fab")
		)
		(fp_line
			(start 0.120396 0.2794)
			(end -0.12065 0.2794)
			(stroke
				(width 0.1)
				(type default)
			)
			(layer "F.Fab")
		)
		(fp_line
			(start -0.12065 0.3048)
			(end -0.67945 0.3048)
			(stroke
				(width 0.1)
				(type default)
			)
			(layer "F.Fab")
		)
		(fp_line
			(start -0.12065 0.2794)
			(end -0.12065 0.3048)
			(stroke
				(width 0.1)
				(type default)
			)
			(layer "F.Fab")
		)
		(fp_line
			(start -0.12065 -0.2794)
			(end 0.12065 -0.2794)
			(stroke
				(width 0.1)
				(type default)
			)
			(layer "F.Fab")
		)
		(fp_line
			(start -0.12065 -0.305054)
			(end -0.12065 -0.2794)
			(stroke
				(width 0.1)
				(type default)
			)
			(layer "F.Fab")
		)
		(fp_line
			(start -0.67945 0.3048)
			(end -0.67945 -0.305054)
			(stroke
				(width 0.1)
				(type default)
			)
			(layer "F.Fab")
		)
		(fp_line
			(start -0.67945 -0.305054)
			(end -0.12065 -0.305054)
			(stroke
				(width 0.1)
				(type default)
			)
			(layer "F.Fab")
		)
		(pad "1" smd circle
			(at -0.40005 0 180)
			(size 0 0)
			(layers "F.Cu" "F.Mask" "F.Paste")
			(net "P5V")
		)
		(pad "2" smd circle
			(at 0.40005 0 180)
			(size 0 0)
			(layers "F.Cu" "F.Mask" "F.Paste")
			(net "PVCCIN_CPU1_PVCC")
		)
	)
	(footprint ""
		(layer "F.Cu")
		(at 207.772 -97.6884 90)
		(property "Reference" "R4784"
			(at 0 0 90)
			(layer "F.SilkS")
			(hide yes)
			(effects
				(font
					(size 1.27 1.27)
				)
			)
		)
		(property "Value" ""
			(at 0 0 90)
			(layer "F.Fab")
			(effects
				(font
					(size 1.27 1.27)
				)
			)
		)
		(duplicate_pad_numbers_are_jumpers no)
		(fp_line
			(start 0.7874 -0.4064)
			(end 0.7874 0.4064)
			(stroke
				(width 0.1524)
				(type default)
			)
			(layer "F.SilkS")
		)
		(fp_line
			(start -0.7874 -0.4064)
			(end 0.7874 -0.4064)
			(stroke
				(width 0.1524)
				(type default)
			)
			(layer "F.SilkS")
		)
		(fp_line
			(start 0.7874 0.4064)
			(end -0.7874 0.4064)
			(stroke
				(width 0.1524)
				(type default)
			)
			(layer "F.SilkS")
		)
		(fp_line
			(start -0.7874 0.4064)
			(end -0.7874 -0.4064)
			(stroke
				(width 0.1524)
				(type default)
			)
			(layer "F.SilkS")
		)
		(fp_line
			(start -0.12065 -0.305054)
			(end -0.12065 -0.2794)
			(stroke
				(width 0.1)
				(type default)
			)
			(layer "F.Fab")
		)
		(fp_line
			(start -0.67945 -0.305054)
			(end -0.12065 -0.305054)
			(stroke
				(width 0.1)
				(type default)
			)
			(layer "F.Fab")
		)
		(fp_line
			(start 0.67945 -0.3048)
			(end 0.67945 0.3048)
			(stroke
				(width 0.1)
				(type default)
			)
			(layer "F.Fab")
		)
		(fp_line
			(start 0.12065 -0.3048)
			(end 0.67945 -0.3048)
			(stroke
				(width 0.1)
				(type default)
			)
			(layer "F.Fab")
		)
		(fp_line
			(start 0.12065 -0.2794)
			(end 0.12065 -0.3048)
			(stroke
				(width 0.1)
				(type default)
			)
			(layer "F.Fab")
		)
		(fp_line
			(start -0.12065 -0.2794)
			(end 0.12065 -0.2794)
			(stroke
				(width 0.1)
				(type default)
			)
			(layer "F.Fab")
		)
		(fp_line
			(start 0.120396 0.2794)
			(end -0.12065 0.2794)
			(stroke
				(width 0.1)
				(type default)
			)
			(layer "F.Fab")
		)
		(fp_line
			(start -0.12065 0.2794)
			(end -0.12065 0.3048)
			(stroke
				(width 0.1)
				(type default)
			)
			(layer "F.Fab")
		)
		(fp_line
			(start 0.67945 0.3048)
			(end 0.120396 0.3048)
			(stroke
				(width 0.1)
				(type default)
			)
			(layer "F.Fab")
		)
		(fp_line
			(start 0.120396 0.3048)
			(end 0.120396 0.2794)
			(stroke
				(width 0.1)
				(type default)
			)
			(layer "F.Fab")
		)
		(fp_line
			(start -0.12065 0.3048)
			(end -0.67945 0.3048)
			(stroke
				(width 0.1)
				(type default)
			)
			(layer "F.Fab")
		)
		(fp_line
			(start -0.67945 0.3048)
			(end -0.67945 -0.305054)
			(stroke
				(width 0.1)
				(type default)
			)
			(layer "F.Fab")
		)
		(pad "1" smd circle
			(at -0.40005 0 90)
			(size 0 0)
			(layers "F.Cu" "F.Mask" "F.Paste")
			(net "P3V3_AUX")
		)
		(pad "2" smd circle
			(at 0.40005 0 90)
			(size 0 0)
			(layers "F.Cu" "F.Mask" "F.Paste")
			(net "FM_UV_ADR_TRIGGER_N")
		)
	)
	(footprint ""
		(layer "F.Cu")
		(at 192.052448 -401.112482)
		(property "Reference" "R3934"
			(at 0 0 0)
			(layer "F.SilkS")
			(hide yes)
			(effects
				(font
					(size 1.27 1.27)
				)
			)
		)
		(property "Value" ""
			(at 0 0 0)
			(layer "F.Fab")
			(effects
				(font
					(size 1.27 1.27)
				)
			)
		)
		(duplicate_pad_numbers_are_jumpers no)
		(fp_line
			(start -0.7874 -0.4064)
			(end 0.7874 -0.4064)
			(stroke
				(width 0.1524)
				(type default)
			)
			(layer "F.SilkS")
		)
		(fp_line
			(start -0.7874 0.4064)
			(end -0.7874 -0.4064)
			(stroke
				(width 0.1524)
				(type default)
			)
			(layer "F.SilkS")
		)
		(fp_line
			(start 0.7874 -0.4064)
			(end 0.7874 0.4064)
			(stroke
				(width 0.1524)
				(type default)
			)
			(layer "F.SilkS")
		)
		(fp_line
			(start 0.7874 0.4064)
			(end -0.7874 0.4064)
			(stroke
				(width 0.1524)
				(type default)
			)
			(layer "F.SilkS")
		)
		(fp_line
			(start -0.67945 -0.305054)
			(end -0.12065 -0.305054)
			(stroke
				(width 0.1)
				(type default)
			)
			(layer "F.Fab")
		)
		(fp_line
			(start -0.67945 0.3048)
			(end -0.67945 -0.305054)
			(stroke
				(width 0.1)
				(type default)
			)
			(layer "F.Fab")
		)
		(fp_line
			(start -0.12065 -0.305054)
			(end -0.12065 -0.2794)
			(stroke
				(width 0.1)
				(type default)
			)
			(layer "F.Fab")
		)
		(fp_line
			(start -0.12065 -0.2794)
			(end 0.12065 -0.2794)
			(stroke
				(width 0.1)
				(type default)
			)
			(layer "F.Fab")
		)
		(fp_line
			(start -0.12065 0.2794)
			(end -0.12065 0.3048)
			(stroke
				(width 0.1)
				(type default)
			)
			(layer "F.Fab")
		)
		(fp_line
			(start -0.12065 0.3048)
			(end -0.67945 0.3048)
			(stroke
				(width 0.1)
				(type default)
			)
			(layer "F.Fab")
		)
		(fp_line
			(start 0.120396 0.2794)
			(end -0.12065 0.2794)
			(stroke
				(width 0.1)
				(type default)
			)
			(layer "F.Fab")
		)
		(fp_line
			(start 0.120396 0.3048)
			(end 0.120396 0.2794)
			(stroke
				(width 0.1)
				(type default)
			)
			(layer "F.Fab")
		)
		(fp_line
			(start 0.12065 -0.3048)
			(end 0.67945 -0.3048)
			(stroke
				(width 0.1)
				(type default)
			)
			(layer "F.Fab")
		)
		(fp_line
			(start 0.12065 -0.2794)
			(end 0.12065 -0.3048)
			(stroke
				(width 0.1)
				(type default)
			)
			(layer "F.Fab")
		)
		(fp_line
			(start 0.67945 -0.3048)
			(end 0.67945 0.3048)
			(stroke
				(width 0.1)
				(type default)
			)
			(layer "F.Fab")
		)
		(fp_line
			(start 0.67945 0.3048)
			(end 0.120396 0.3048)
			(stroke
				(width 0.1)
				(type default)
			)
			(layer "F.Fab")
		)
		(pad "1" smd circle
			(at -0.40005 0)
			(size 0 0)
			(layers "F.Cu" "F.Mask" "F.Paste")
			(net "HSC_D_OC_R")
		)
		(pad "2" smd circle
			(at 0.40005 0)
			(size 0 0)
			(layers "F.Cu" "F.Mask" "F.Paste")
			(net "HSC_D_OC")
		)
	)
	(footprint ""
		(layer "F.Cu")
		(at 297.147234 -16.715994 180)
		(property "Reference" "R4204"
			(at 0 0 180)
			(layer "F.SilkS")
			(hide yes)
			(effects
				(font
					(size 1.27 1.27)
				)
			)
		)
		(property "Value" ""
			(at 0 0 180)
			(layer "F.Fab")
			(effects
				(font
					(size 1.27 1.27)
				)
			)
		)
		(duplicate_pad_numbers_are_jumpers no)
		(fp_line
			(start 0.7874 0.4064)
			(end -0.7874 0.4064)
			(stroke
				(width 0.1524)
				(type default)
			)
			(layer "F.SilkS")
		)
		(fp_line
			(start 0.7874 -0.4064)
			(end 0.7874 0.4064)
			(stroke
				(width 0.1524)
				(type default)
			)
			(layer "F.SilkS")
		)
		(fp_line
			(start -0.7874 0.4064)
			(end -0.7874 -0.4064)
			(stroke
				(width 0.1524)
				(type default)
			)
			(layer "F.SilkS")
		)
		(fp_line
			(start -0.7874 -0.4064)
			(end 0.7874 -0.4064)
			(stroke
				(width 0.1524)
				(type default)
			)
			(layer "F.SilkS")
		)
		(fp_line
			(start 0.67945 0.3048)
			(end 0.120396 0.3048)
			(stroke
				(width 0.1)
				(type default)
			)
			(layer "F.Fab")
		)
		(fp_line
			(start 0.67945 -0.3048)
			(end 0.67945 0.3048)
			(stroke
				(width 0.1)
				(type default)
			)
			(layer "F.Fab")
		)
		(fp_line
			(start 0.12065 -0.2794)
			(end 0.12065 -0.3048)
			(stroke
				(width 0.1)
				(type default)
			)
			(layer "F.Fab")
		)
		(fp_line
			(start 0.12065 -0.3048)
			(end 0.67945 -0.3048)
			(stroke
				(width 0.1)
				(type default)
			)
			(layer "F.Fab")
		)
		(fp_line
			(start 0.120396 0.3048)
			(end 0.120396 0.2794)
			(stroke
				(width 0.1)
				(type default)
			)
			(layer "F.Fab")
		)
		(fp_line
			(start 0.120396 0.2794)
			(end -0.12065 0.2794)
			(stroke
				(width 0.1)
				(type default)
			)
			(layer "F.Fab")
		)
		(fp_line
			(start -0.12065 0.3048)
			(end -0.67945 0.3048)
			(stroke
				(width 0.1)
				(type default)
			)
			(layer "F.Fab")
		)
		(fp_line
			(start -0.12065 0.2794)
			(end -0.12065 0.3048)
			(stroke
				(width 0.1)
				(type default)
			)
			(layer "F.Fab")
		)
		(fp_line
			(start -0.12065 -0.2794)
			(end 0.12065 -0.2794)
			(stroke
				(width 0.1)
				(type default)
			)
			(layer "F.Fab")
		)
		(fp_line
			(start -0.12065 -0.305054)
			(end -0.12065 -0.2794)
			(stroke
				(width 0.1)
				(type default)
			)
			(layer "F.Fab")
		)
		(fp_line
			(start -0.67945 0.3048)
			(end -0.67945 -0.305054)
			(stroke
				(width 0.1)
				(type default)
			)
			(layer "F.Fab")
		)
		(fp_line
			(start -0.67945 -0.305054)
			(end -0.12065 -0.305054)
			(stroke
				(width 0.1)
				(type default)
			)
			(layer "F.Fab")
		)
		(pad "1" smd circle
			(at -0.40005 0 180)
			(size 0 0)
			(layers "F.Cu" "F.Mask" "F.Paste")
			(net "P3V3_AUX")
		)
		(pad "2" smd circle
			(at 0.40005 0 180)
			(size 0 0)
			(layers "F.Cu" "F.Mask" "F.Paste")
			(net "U271_1_ADD0")
		)
	)
	(footprint ""
		(layer "F.Cu")
		(at 50.317654 -162.280854)
		(property "Reference" "PC1371"
			(at 0 0 0)
			(layer "F.SilkS")
			(hide yes)
			(effects
				(font
					(size 1.27 1.27)
				)
			)
		)
		(property "Value" ""
			(at 0 0 0)
			(layer "F.Fab")
			(effects
				(font
					(size 1.27 1.27)
				)
			)
		)
		(duplicate_pad_numbers_are_jumpers no)
		(fp_line
			(start -0.7874 -0.4064)
			(end 0.7874 -0.4064)
			(stroke
				(width 0.1524)
				(type default)
			)
			(layer "F.SilkS")
		)
		(fp_line
			(start -0.7874 0.4064)
			(end -0.7874 -0.4064)
			(stroke
				(width 0.1524)
				(type default)
			)
			(layer "F.SilkS")
		)
		(fp_line
			(start 0.7874 -0.4064)
			(end 0.7874 0.4064)
			(stroke
				(width 0.1524)
				(type default)
			)
			(layer "F.SilkS")
		)
		(fp_line
			(start 0.7874 0.4064)
			(end -0.7874 0.4064)
			(stroke
				(width 0.1524)
				(type default)
			)
			(layer "F.SilkS")
		)
		(fp_line
			(start -0.67945 -0.305054)
			(end -0.12065 -0.305054)
			(stroke
				(width 0.1)
				(type default)
			)
			(layer "F.Fab")
		)
		(fp_line
			(start -0.67945 0.3048)
			(end -0.67945 -0.305054)
			(stroke
				(width 0.1)
				(type default)
			)
			(layer "F.Fab")
		)
		(fp_line
			(start -0.12065 -0.305054)
			(end -0.12065 -0.2794)
			(stroke
				(width 0.1)
				(type default)
			)
			(layer "F.Fab")
		)
		(fp_line
			(start -0.12065 -0.2794)
			(end 0.12065 -0.2794)
			(stroke
				(width 0.1)
				(type default)
			)
			(layer "F.Fab")
		)
		(fp_line
			(start -0.12065 0.2794)
			(end -0.12065 0.3048)
			(stroke
				(width 0.1)
				(type default)
			)
			(layer "F.Fab")
		)
		(fp_line
			(start -0.12065 0.3048)
			(end -0.67945 0.3048)
			(stroke
				(width 0.1)
				(type default)
			)
			(layer "F.Fab")
		)
		(fp_line
			(start 0.120396 0.2794)
			(end -0.12065 0.2794)
			(stroke
				(width 0.1)
				(type default)
			)
			(layer "F.Fab")
		)
		(fp_line
			(start 0.120396 0.3048)
			(end 0.120396 0.2794)
			(stroke
				(width 0.1)
				(type default)
			)
			(layer "F.Fab")
		)
		(fp_line
			(start 0.12065 -0.3048)
			(end 0.67945 -0.3048)
			(stroke
				(width 0.1)
				(type default)
			)
			(layer "F.Fab")
		)
		(fp_line
			(start 0.12065 -0.2794)
			(end 0.12065 -0.3048)
			(stroke
				(width 0.1)
				(type default)
			)
			(layer "F.Fab")
		)
		(fp_line
			(start 0.67945 -0.3048)
			(end 0.67945 0.3048)
			(stroke
				(width 0.1)
				(type default)
			)
			(layer "F.Fab")
		)
		(fp_line
			(start 0.67945 0.3048)
			(end 0.120396 0.3048)
			(stroke
				(width 0.1)
				(type default)
			)
			(layer "F.Fab")
		)
		(pad "1" smd circle
			(at -0.40005 0)
			(size 0 0)
			(layers "F.Cu" "F.Mask" "F.Paste")
			(net "GND")
		)
		(pad "2" smd circle
			(at 0.40005 0)
			(size 0 0)
			(layers "F.Cu" "F.Mask" "F.Paste")
			(net "PVCCD_HV_CPU1_VREF")
		)
	)
	(footprint ""
		(layer "F.Cu")
		(at 15.494 -426.1358 -90)
		(property "Reference" "R4802"
			(at 0 0 270)
			(layer "F.SilkS")
			(hide yes)
			(effects
				(font
					(size 1.27 1.27)
				)
			)
		)
		(property "Value" ""
			(at 0 0 270)
			(layer "F.Fab")
			(effects
				(font
					(size 1.27 1.27)
				)
			)
		)
		(duplicate_pad_numbers_are_jumpers no)
		(fp_line
			(start -0.7874 0.4064)
			(end -0.7874 -0.4064)
			(stroke
				(width 0.1524)
				(type default)
			)
			(layer "F.SilkS")
		)
		(fp_line
			(start 0.7874 0.4064)
			(end -0.7874 0.4064)
			(stroke
				(width 0.1524)
				(type default)
			)
			(layer "F.SilkS")
		)
		(fp_line
			(start -0.7874 -0.4064)
			(end 0.7874 -0.4064)
			(stroke
				(width 0.1524)
				(type default)
			)
			(layer "F.SilkS")
		)
		(fp_line
			(start 0.7874 -0.4064)
			(end 0.7874 0.4064)
			(stroke
				(width 0.1524)
				(type default)
			)
			(layer "F.SilkS")
		)
		(fp_line
			(start -0.67945 0.3048)
			(end -0.67945 -0.305054)
			(stroke
				(width 0.1)
				(type default)
			)
			(layer "F.Fab")
		)
		(fp_line
			(start -0.12065 0.3048)
			(end -0.67945 0.3048)
			(stroke
				(width 0.1)
				(type default)
			)
			(layer "F.Fab")
		)
		(fp_line
			(start 0.120396 0.3048)
			(end 0.120396 0.2794)
			(stroke
				(width 0.1)
				(type default)
			)
			(layer "F.Fab")
		)
		(fp_line
			(start 0.67945 0.3048)
			(end 0.120396 0.3048)
			(stroke
				(width 0.1)
				(type default)
			)
			(layer "F.Fab")
		)
		(fp_line
			(start -0.12065 0.2794)
			(end -0.12065 0.3048)
			(stroke
				(width 0.1)
				(type default)
			)
			(layer "F.Fab")
		)
		(fp_line
			(start 0.120396 0.2794)
			(end -0.12065 0.2794)
			(stroke
				(width 0.1)
				(type default)
			)
			(layer "F.Fab")
		)
		(fp_line
			(start -0.12065 -0.2794)
			(end 0.12065 -0.2794)
			(stroke
				(width 0.1)
				(type default)
			)
			(layer "F.Fab")
		)
		(fp_line
			(start 0.12065 -0.2794)
			(end 0.12065 -0.3048)
			(stroke
				(width 0.1)
				(type default)
			)
			(layer "F.Fab")
		)
		(fp_line
			(start 0.12065 -0.3048)
			(end 0.67945 -0.3048)
			(stroke
				(width 0.1)
				(type default)
			)
			(layer "F.Fab")
		)
		(fp_line
			(start 0.67945 -0.3048)
			(end 0.67945 0.3048)
			(stroke
				(width 0.1)
				(type default)
			)
			(layer "F.Fab")
		)
		(fp_line
			(start -0.67945 -0.305054)
			(end -0.12065 -0.305054)
			(stroke
				(width 0.1)
				(type default)
			)
			(layer "F.Fab")
		)
		(fp_line
			(start -0.12065 -0.305054)
			(end -0.12065 -0.2794)
			(stroke
				(width 0.1)
				(type default)
			)
			(layer "F.Fab")
		)
		(pad "1" smd circle
			(at -0.40005 0 270)
			(size 0 0)
			(layers "F.Cu" "F.Mask" "F.Paste")
			(net "PRSNT_CABLE_GPU_A3_ISO_N")
		)
		(pad "2" smd circle
			(at 0.40005 0 270)
			(size 0 0)
			(layers "F.Cu" "F.Mask" "F.Paste")
			(net "PRSNT_CABLE_GPU_A3_ISO_R_N")
		)
	)
	(footprint ""
		(layer "F.Cu")
		(at 403.985984 -17.612614 90)
		(property "Reference" "C848"
			(at 0 0 90)
			(layer "F.SilkS")
			(hide yes)
			(effects
				(font
					(size 1.27 1.27)
				)
			)
		)
		(property "Value" ""
			(at 0 0 90)
			(layer "F.Fab")
			(effects
				(font
					(size 1.27 1.27)
				)
			)
		)
		(duplicate_pad_numbers_are_jumpers no)
		(fp_line
			(start 0.299974 -0.150114)
			(end 0.299974 0.150114)
			(stroke
				(width 0.1)
				(type default)
			)
			(layer "F.Fab")
		)
		(fp_line
			(start -0.299974 -0.150114)
			(end 0.299974 -0.150114)
			(stroke
				(width 0.1)
				(type default)
			)
			(layer "F.Fab")
		)
		(fp_line
			(start 0.299974 0.150114)
			(end -0.299974 0.150114)
			(stroke
				(width 0.1)
				(type default)
			)
			(layer "F.Fab")
		)
		(fp_line
			(start -0.299974 0.150114)
			(end -0.299974 -0.150114)
			(stroke
				(width 0.1)
				(type default)
			)
			(layer "F.Fab")
		)
		(pad "1" smd rect
			(at -0.2667 0 90)
			(size 0.3048 0.381)
			(layers "F.Cu" "F.Mask" "F.Paste")
			(net "P5E_CPU0_PE1_TX_C_DN<10>")
		)
		(pad "2" smd rect
			(at 0.2667 0 90)
			(size 0.3048 0.381)
			(layers "F.Cu" "F.Mask" "F.Paste")
			(net "P5E_CPU0_PE1_TX_DN<10>")
		)
	)
	(footprint ""
		(layer "F.Cu")
		(at 117.526816 -240.277142 90)
		(property "Reference" "C223"
			(at 0 0 90)
			(layer "F.SilkS")
			(hide yes)
			(effects
				(font
					(size 1.27 1.27)
				)
			)
		)
		(property "Value" ""
			(at 0 0 90)
			(layer "F.Fab")
			(effects
				(font
					(size 1.27 1.27)
				)
			)
		)
		(duplicate_pad_numbers_are_jumpers no)
		(fp_line
			(start 0.7874 -0.4064)
			(end 0.7874 0.4064)
			(stroke
				(width 0.1524)
				(type default)
			)
			(layer "F.SilkS")
		)
		(fp_line
			(start -0.7874 -0.4064)
			(end 0.7874 -0.4064)
			(stroke
				(width 0.1524)
				(type default)
			)
			(layer "F.SilkS")
		)
		(fp_line
			(start 0.7874 0.4064)
			(end -0.7874 0.4064)
			(stroke
				(width 0.1524)
				(type default)
			)
			(layer "F.SilkS")
		)
		(fp_line
			(start -0.7874 0.4064)
			(end -0.7874 -0.4064)
			(stroke
				(width 0.1524)
				(type default)
			)
			(layer "F.SilkS")
		)
		(fp_line
			(start -0.12065 -0.305054)
			(end -0.12065 -0.2794)
			(stroke
				(width 0.1)
				(type default)
			)
			(layer "F.Fab")
		)
		(fp_line
			(start -0.67945 -0.305054)
			(end -0.12065 -0.305054)
			(stroke
				(width 0.1)
				(type default)
			)
			(layer "F.Fab")
		)
		(fp_line
			(start 0.67945 -0.3048)
			(end 0.67945 0.3048)
			(stroke
				(width 0.1)
				(type default)
			)
			(layer "F.Fab")
		)
		(fp_line
			(start 0.12065 -0.3048)
			(end 0.67945 -0.3048)
			(stroke
				(width 0.1)
				(type default)
			)
			(layer "F.Fab")
		)
		(fp_line
			(start 0.12065 -0.2794)
			(end 0.12065 -0.3048)
			(stroke
				(width 0.1)
				(type default)
			)
			(layer "F.Fab")
		)
		(fp_line
			(start -0.12065 -0.2794)
			(end 0.12065 -0.2794)
			(stroke
				(width 0.1)
				(type default)
			)
			(layer "F.Fab")
		)
		(fp_line
			(start 0.120396 0.2794)
			(end -0.12065 0.2794)
			(stroke
				(width 0.1)
				(type default)
			)
			(layer "F.Fab")
		)
		(fp_line
			(start -0.12065 0.2794)
			(end -0.12065 0.3048)
			(stroke
				(width 0.1)
				(type default)
			)
			(layer "F.Fab")
		)
		(fp_line
			(start 0.67945 0.3048)
			(end 0.120396 0.3048)
			(stroke
				(width 0.1)
				(type default)
			)
			(layer "F.Fab")
		)
		(fp_line
			(start 0.120396 0.3048)
			(end 0.120396 0.2794)
			(stroke
				(width 0.1)
				(type default)
			)
			(layer "F.Fab")
		)
		(fp_line
			(start -0.12065 0.3048)
			(end -0.67945 0.3048)
			(stroke
				(width 0.1)
				(type default)
			)
			(layer "F.Fab")
		)
		(fp_line
			(start -0.67945 0.3048)
			(end -0.67945 -0.305054)
			(stroke
				(width 0.1)
				(type default)
			)
			(layer "F.Fab")
		)
		(pad "1" smd circle
			(at -0.40005 0 90)
			(size 0 0)
			(layers "F.Cu" "F.Mask" "F.Paste")
			(net "PVCCIN_CPU1")
		)
		(pad "2" smd circle
			(at 0.40005 0 90)
			(size 0 0)
			(layers "F.Cu" "F.Mask" "F.Paste")
			(net "GND")
		)
	)
	(footprint ""
		(layer "F.Cu")
		(at 375.80697 -408.517344 -90)
		(property "Reference" "C872"
			(at 0 0 270)
			(layer "F.SilkS")
			(hide yes)
			(effects
				(font
					(size 1.27 1.27)
				)
			)
		)
		(property "Value" ""
			(at 0 0 270)
			(layer "F.Fab")
			(effects
				(font
					(size 1.27 1.27)
				)
			)
		)
		(duplicate_pad_numbers_are_jumpers no)
		(fp_line
			(start -0.299974 0.150114)
			(end -0.299974 -0.150114)
			(stroke
				(width 0.1)
				(type default)
			)
			(layer "F.Fab")
		)
		(fp_line
			(start 0.299974 0.150114)
			(end -0.299974 0.150114)
			(stroke
				(width 0.1)
				(type default)
			)
			(layer "F.Fab")
		)
		(fp_line
			(start -0.299974 -0.150114)
			(end 0.299974 -0.150114)
			(stroke
				(width 0.1)
				(type default)
			)
			(layer "F.Fab")
		)
		(fp_line
			(start 0.299974 -0.150114)
			(end 0.299974 0.150114)
			(stroke
				(width 0.1)
				(type default)
			)
			(layer "F.Fab")
		)
		(pad "1" smd rect
			(at -0.2667 0 270)
			(size 0.3048 0.381)
			(layers "F.Cu" "F.Mask" "F.Paste")
			(net "P5E_CPU0_PE3_TX_C_DN<14>")
		)
		(pad "2" smd rect
			(at 0.2667 0 270)
			(size 0.3048 0.381)
			(layers "F.Cu" "F.Mask" "F.Paste")
			(net "P5E_CPU0_PE3_TX_DN<14>")
		)
	)
	(footprint ""
		(layer "F.Cu")
		(at 134.225538 -345.393264 90)
		(property "Reference" "PC479"
			(at 0 0 90)
			(layer "F.SilkS")
			(hide yes)
			(effects
				(font
					(size 1.27 1.27)
				)
			)
		)
		(property "Value" ""
			(at 0 0 90)
			(layer "F.Fab")
			(effects
				(font
					(size 1.27 1.27)
				)
			)
		)
		(duplicate_pad_numbers_are_jumpers no)
		(fp_line
			(start 0.7874 -0.4064)
			(end 0.7874 0.4064)
			(stroke
				(width 0.1524)
				(type default)
			)
			(layer "F.SilkS")
		)
		(fp_line
			(start -0.7874 -0.4064)
			(end 0.7874 -0.4064)
			(stroke
				(width 0.1524)
				(type default)
			)
			(layer "F.SilkS")
		)
		(fp_line
			(start 0.7874 0.4064)
			(end -0.7874 0.4064)
			(stroke
				(width 0.1524)
				(type default)
			)
			(layer "F.SilkS")
		)
		(fp_line
			(start -0.7874 0.4064)
			(end -0.7874 -0.4064)
			(stroke
				(width 0.1524)
				(type default)
			)
			(layer "F.SilkS")
		)
		(fp_line
			(start -0.12065 -0.305054)
			(end -0.12065 -0.2794)
			(stroke
				(width 0.1)
				(type default)
			)
			(layer "F.Fab")
		)
		(fp_line
			(start -0.67945 -0.305054)
			(end -0.12065 -0.305054)
			(stroke
				(width 0.1)
				(type default)
			)
			(layer "F.Fab")
		)
		(fp_line
			(start 0.67945 -0.3048)
			(end 0.67945 0.3048)
			(stroke
				(width 0.1)
				(type default)
			)
			(layer "F.Fab")
		)
		(fp_line
			(start 0.12065 -0.3048)
			(end 0.67945 -0.3048)
			(stroke
				(width 0.1)
				(type default)
			)
			(layer "F.Fab")
		)
		(fp_line
			(start 0.12065 -0.2794)
			(end 0.12065 -0.3048)
			(stroke
				(width 0.1)
				(type default)
			)
			(layer "F.Fab")
		)
		(fp_line
			(start -0.12065 -0.2794)
			(end 0.12065 -0.2794)
			(stroke
				(width 0.1)
				(type default)
			)
			(layer "F.Fab")
		)
		(fp_line
			(start 0.120396 0.2794)
			(end -0.12065 0.2794)
			(stroke
				(width 0.1)
				(type default)
			)
			(layer "F.Fab")
		)
		(fp_line
			(start -0.12065 0.2794)
			(end -0.12065 0.3048)
			(stroke
				(width 0.1)
				(type default)
			)
			(layer "F.Fab")
		)
		(fp_line
			(start 0.67945 0.3048)
			(end 0.120396 0.3048)
			(stroke
				(width 0.1)
				(type default)
			)
			(layer "F.Fab")
		)
		(fp_line
			(start 0.120396 0.3048)
			(end 0.120396 0.2794)
			(stroke
				(width 0.1)
				(type default)
			)
			(layer "F.Fab")
		)
		(fp_line
			(start -0.12065 0.3048)
			(end -0.67945 0.3048)
			(stroke
				(width 0.1)
				(type default)
			)
			(layer "F.Fab")
		)
		(fp_line
			(start -0.67945 0.3048)
			(end -0.67945 -0.305054)
			(stroke
				(width 0.1)
				(type default)
			)
			(layer "F.Fab")
		)
		(pad "1" smd circle
			(at -0.40005 0 90)
			(size 0 0)
			(layers "F.Cu" "F.Mask" "F.Paste")
			(net "PVCCIN_CPU1_VDD8")
		)
		(pad "2" smd circle
			(at 0.40005 0 90)
			(size 0 0)
			(layers "F.Cu" "F.Mask" "F.Paste")
			(net "GND")
		)
	)
	(footprint ""
		(layer "F.Cu")
		(at 416.169348 -353.312984 -90)
		(property "Reference" "PL33"
			(at -2.921254 7.125208 0)
			(unlocked yes)
			(layer "F.SilkS")
			(effects
				(font
					(size 0.7874 0.5842)
					(thickness 0.1524)
				)
				(justify left)
			)
		)
		(property "Value" ""
			(at 0 0 270)
			(layer "F.Fab")
			(effects
				(font
					(size 1.27 1.27)
				)
			)
		)
		(duplicate_pad_numbers_are_jumpers no)
		(fp_line
			(start -4.99999 3.750056)
			(end -4.99999 2.2479)
			(stroke
				(width 0.1524)
				(type default)
			)
			(layer "F.SilkS")
		)
		(fp_line
			(start 0 3.750056)
			(end -4.99999 3.750056)
			(stroke
				(width 0.1524)
				(type default)
			)
			(layer "F.SilkS")
		)
		(fp_line
			(start 4.99999 3.750056)
			(end 0 3.750056)
			(stroke
				(width 0.1524)
				(type default)
			)
			(layer "F.SilkS")
		)
		(fp_line
			(start 4.99999 2.2352)
			(end 4.99999 3.750056)
			(stroke
				(width 0.1524)
				(type default)
			)
			(layer "F.SilkS")
		)
		(fp_line
			(start -4.99999 -2.2479)
			(end -4.99999 -3.750056)
			(stroke
				(width 0.1524)
				(type default)
			)
			(layer "F.SilkS")
		)
		(fp_line
			(start -4.99999 -3.750056)
			(end 4.99999 -3.750056)
			(stroke
				(width 0.1524)
				(type default)
			)
			(layer "F.SilkS")
		)
		(fp_line
			(start 4.99999 -3.750056)
			(end 4.99999 -2.2479)
			(stroke
				(width 0.1524)
				(type default)
			)
			(layer "F.SilkS")
		)
		(fp_line
			(start -4.99999 3.750056)
			(end -4.99999 -3.750056)
			(stroke
				(width 0.1)
				(type default)
			)
			(layer "F.Fab")
		)
		(fp_line
			(start 0 3.750056)
			(end -4.99999 3.750056)
			(stroke
				(width 0.1)
				(type default)
			)
			(layer "F.Fab")
		)
		(fp_line
			(start 4.99999 3.750056)
			(end 0 3.750056)
			(stroke
				(width 0.1)
				(type default)
			)
			(layer "F.Fab")
		)
		(fp_line
			(start -4.99999 -3.750056)
			(end 4.99999 -3.750056)
			(stroke
				(width 0.1)
				(type default)
			)
			(layer "F.Fab")
		)
		(fp_line
			(start 4.99999 -3.750056)
			(end 4.99999 3.750056)
			(stroke
				(width 0.1)
				(type default)
			)
			(layer "F.Fab")
		)
		(pad "1" smd rect
			(at -3.299968 0 270)
			(size 3.302 4.2164)
			(layers "F.Cu" "F.Mask" "F.Paste")
			(net "SW_PVCCFA_EHV_FIVRA_CPU0_SW1")
		)
		(pad "2" smd rect
			(at 3.299968 0 270)
			(size 3.302 4.2164)
			(layers "F.Cu" "F.Mask" "F.Paste")
			(net "PVCCFA_EHV_FIVRA_CPU0")
		)
	)
	(footprint ""
		(layer "F.Cu")
		(at 109.599476 -79.078836)
		(property "Reference" "D91"
			(at -54.33441 38.649402 90)
			(unlocked yes)
			(layer "F.SilkS")
			(effects
				(font
					(size 0.635 0.4064)
					(thickness 0.1524)
				)
				(justify left)
			)
		)
		(property "Value" ""
			(at 0 0 0)
			(layer "F.Fab")
			(effects
				(font
					(size 1.27 1.27)
				)
			)
		)
		(duplicate_pad_numbers_are_jumpers no)
		(fp_line
			(start -0.90678 0.4826)
			(end -0.90678 -0.4699)
			(stroke
				(width 0.1524)
				(type default)
			)
			(layer "F.SilkS")
		)
		(fp_line
			(start -0.89408 -0.4826)
			(end 0.90678 -0.4826)
			(stroke
				(width 0.1524)
				(type default)
			)
			(layer "F.SilkS")
		)
		(fp_line
			(start -0.79248 -0.4826)
			(end 1.03378 -0.4826)
			(stroke
				(width 0.1524)
				(type default)
			)
			(layer "F.SilkS")
		)
		(fp_line
			(start -0.64008 -0.4826)
			(end 1.16078 -0.4826)
			(stroke
				(width 0.1524)
				(type default)
			)
			(layer "F.SilkS")
		)
		(fp_line
			(start 0.90678 -0.4826)
			(end 0.90678 0.4826)
			(stroke
				(width 0.1524)
				(type default)
			)
			(layer "F.SilkS")
		)
		(fp_line
			(start 0.90678 0.4826)
			(end -0.90678 0.4826)
			(stroke
				(width 0.1524)
				(type default)
			)
			(layer "F.SilkS")
		)
		(fp_line
			(start 1.03378 -0.4826)
			(end 1.03378 0.4826)
			(stroke
				(width 0.1524)
				(type default)
			)
			(layer "F.SilkS")
		)
		(fp_line
			(start 1.03378 0.4826)
			(end -0.79248 0.4826)
			(stroke
				(width 0.1524)
				(type default)
			)
			(layer "F.SilkS")
		)
		(fp_line
			(start 1.16078 -0.4826)
			(end 1.16078 0.4826)
			(stroke
				(width 0.1524)
				(type default)
			)
			(layer "F.SilkS")
		)
		(fp_line
			(start 1.16078 0.4826)
			(end -0.64008 0.4826)
			(stroke
				(width 0.1524)
				(type default)
			)
			(layer "F.SilkS")
		)
		(fp_line
			(start -0.499872 -0.249936)
			(end 0.499872 -0.249936)
			(stroke
				(width 0.1)
				(type default)
			)
			(layer "F.Fab")
		)
		(fp_line
			(start -0.499872 0.249936)
			(end -0.499872 -0.249936)
			(stroke
				(width 0.1)
				(type default)
			)
			(layer "F.Fab")
		)
		(fp_line
			(start 0.499872 -0.249936)
			(end 0.499872 0.249936)
			(stroke
				(width 0.1)
				(type default)
			)
			(layer "F.Fab")
		)
		(fp_line
			(start 0.499872 0.249936)
			(end -0.499872 0.249936)
			(stroke
				(width 0.1)
				(type default)
			)
			(layer "F.Fab")
		)
		(pad "A" smd rect
			(at -0.47498 0)
			(size 0.6096 0.7112)
			(layers "F.Cu" "F.Mask" "F.Paste")
			(net "LED_PWRGD_P1V8_PCH_AUX")
		)
		(pad "C" smd rect
			(at 0.47498 0)
			(size 0.6096 0.7112)
			(layers "F.Cu" "F.Mask" "F.Paste")
			(net "LED_PWRGD_P1V8_PCH_AUX_D")
		)
	)
	(footprint ""
		(layer "F.Cu")
		(at 108.05668 -60.086748)
		(property "Reference" "C1288"
			(at 0 0 0)
			(layer "F.SilkS")
			(hide yes)
			(effects
				(font
					(size 1.27 1.27)
				)
			)
		)
		(property "Value" ""
			(at 0 0 0)
			(layer "F.Fab")
			(effects
				(font
					(size 1.27 1.27)
				)
			)
		)
		(duplicate_pad_numbers_are_jumpers no)
		(fp_line
			(start -0.7874 -0.4064)
			(end 0.7874 -0.4064)
			(stroke
				(width 0.1524)
				(type default)
			)
			(layer "F.SilkS")
		)
		(fp_line
			(start -0.7874 0.4064)
			(end -0.7874 -0.4064)
			(stroke
				(width 0.1524)
				(type default)
			)
			(layer "F.SilkS")
		)
		(fp_line
			(start 0.7874 -0.4064)
			(end 0.7874 0.4064)
			(stroke
				(width 0.1524)
				(type default)
			)
			(layer "F.SilkS")
		)
		(fp_line
			(start 0.7874 0.4064)
			(end -0.7874 0.4064)
			(stroke
				(width 0.1524)
				(type default)
			)
			(layer "F.SilkS")
		)
		(fp_line
			(start -0.67945 -0.305054)
			(end -0.12065 -0.305054)
			(stroke
				(width 0.1)
				(type default)
			)
			(layer "F.Fab")
		)
		(fp_line
			(start -0.67945 0.3048)
			(end -0.67945 -0.305054)
			(stroke
				(width 0.1)
				(type default)
			)
			(layer "F.Fab")
		)
		(fp_line
			(start -0.12065 -0.305054)
			(end -0.12065 -0.2794)
			(stroke
				(width 0.1)
				(type default)
			)
			(layer "F.Fab")
		)
		(fp_line
			(start -0.12065 -0.2794)
			(end 0.12065 -0.2794)
			(stroke
				(width 0.1)
				(type default)
			)
			(layer "F.Fab")
		)
		(fp_line
			(start -0.12065 0.2794)
			(end -0.12065 0.3048)
			(stroke
				(width 0.1)
				(type default)
			)
			(layer "F.Fab")
		)
		(fp_line
			(start -0.12065 0.3048)
			(end -0.67945 0.3048)
			(stroke
				(width 0.1)
				(type default)
			)
			(layer "F.Fab")
		)
		(fp_line
			(start 0.120396 0.2794)
			(end -0.12065 0.2794)
			(stroke
				(width 0.1)
				(type default)
			)
			(layer "F.Fab")
		)
		(fp_line
			(start 0.120396 0.3048)
			(end 0.120396 0.2794)
			(stroke
				(width 0.1)
				(type default)
			)
			(layer "F.Fab")
		)
		(fp_line
			(start 0.12065 -0.3048)
			(end 0.67945 -0.3048)
			(stroke
				(width 0.1)
				(type default)
			)
			(layer "F.Fab")
		)
		(fp_line
			(start 0.12065 -0.2794)
			(end 0.12065 -0.3048)
			(stroke
				(width 0.1)
				(type default)
			)
			(layer "F.Fab")
		)
		(fp_line
			(start 0.67945 -0.3048)
			(end 0.67945 0.3048)
			(stroke
				(width 0.1)
				(type default)
			)
			(layer "F.Fab")
		)
		(fp_line
			(start 0.67945 0.3048)
			(end 0.120396 0.3048)
			(stroke
				(width 0.1)
				(type default)
			)
			(layer "F.Fab")
		)
		(pad "1" smd circle
			(at -0.40005 0)
			(size 0 0)
			(layers "F.Cu" "F.Mask" "F.Paste")
			(net "P3V3_AUX")
		)
		(pad "2" smd circle
			(at 0.40005 0)
			(size 0 0)
			(layers "F.Cu" "F.Mask" "F.Paste")
			(net "GND")
		)
	)
	(footprint ""
		(layer "F.Cu")
		(at 160.83788 -105.755948 180)
		(property "Reference" "R2845"
			(at 0 0 180)
			(layer "F.SilkS")
			(hide yes)
			(effects
				(font
					(size 1.27 1.27)
				)
			)
		)
		(property "Value" ""
			(at 0 0 180)
			(layer "F.Fab")
			(effects
				(font
					(size 1.27 1.27)
				)
			)
		)
		(duplicate_pad_numbers_are_jumpers no)
		(fp_line
			(start 0.7874 0.4064)
			(end -0.7874 0.4064)
			(stroke
				(width 0.1524)
				(type default)
			)
			(layer "F.SilkS")
		)
		(fp_line
			(start 0.7874 -0.4064)
			(end 0.7874 0.4064)
			(stroke
				(width 0.1524)
				(type default)
			)
			(layer "F.SilkS")
		)
		(fp_line
			(start -0.7874 0.4064)
			(end -0.7874 -0.4064)
			(stroke
				(width 0.1524)
				(type default)
			)
			(layer "F.SilkS")
		)
		(fp_line
			(start -0.7874 -0.4064)
			(end 0.7874 -0.4064)
			(stroke
				(width 0.1524)
				(type default)
			)
			(layer "F.SilkS")
		)
		(fp_line
			(start 0.67945 0.3048)
			(end 0.120396 0.3048)
			(stroke
				(width 0.1)
				(type default)
			)
			(layer "F.Fab")
		)
		(fp_line
			(start 0.67945 -0.3048)
			(end 0.67945 0.3048)
			(stroke
				(width 0.1)
				(type default)
			)
			(layer "F.Fab")
		)
		(fp_line
			(start 0.12065 -0.2794)
			(end 0.12065 -0.3048)
			(stroke
				(width 0.1)
				(type default)
			)
			(layer "F.Fab")
		)
		(fp_line
			(start 0.12065 -0.3048)
			(end 0.67945 -0.3048)
			(stroke
				(width 0.1)
				(type default)
			)
			(layer "F.Fab")
		)
		(fp_line
			(start 0.120396 0.3048)
			(end 0.120396 0.2794)
			(stroke
				(width 0.1)
				(type default)
			)
			(layer "F.Fab")
		)
		(fp_line
			(start 0.120396 0.2794)
			(end -0.12065 0.2794)
			(stroke
				(width 0.1)
				(type default)
			)
			(layer "F.Fab")
		)
		(fp_line
			(start -0.12065 0.3048)
			(end -0.67945 0.3048)
			(stroke
				(width 0.1)
				(type default)
			)
			(layer "F.Fab")
		)
		(fp_line
			(start -0.12065 0.2794)
			(end -0.12065 0.3048)
			(stroke
				(width 0.1)
				(type default)
			)
			(layer "F.Fab")
		)
		(fp_line
			(start -0.12065 -0.2794)
			(end 0.12065 -0.2794)
			(stroke
				(width 0.1)
				(type default)
			)
			(layer "F.Fab")
		)
		(fp_line
			(start -0.12065 -0.305054)
			(end -0.12065 -0.2794)
			(stroke
				(width 0.1)
				(type default)
			)
			(layer "F.Fab")
		)
		(fp_line
			(start -0.67945 0.3048)
			(end -0.67945 -0.305054)
			(stroke
				(width 0.1)
				(type default)
			)
			(layer "F.Fab")
		)
		(fp_line
			(start -0.67945 -0.305054)
			(end -0.12065 -0.305054)
			(stroke
				(width 0.1)
				(type default)
			)
			(layer "F.Fab")
		)
		(pad "1" smd circle
			(at -0.40005 0 180)
			(size 0 0)
			(layers "F.Cu" "F.Mask" "F.Paste")
			(net "BMC_MONITER")
		)
		(pad "2" smd circle
			(at 0.40005 0 180)
			(size 0 0)
			(layers "F.Cu" "F.Mask" "F.Paste")
			(net "BMC_MONITER_R")
		)
	)
	(footprint ""
		(layer "F.Cu")
		(at 406.124664 -358.436926 180)
		(property "Reference" "R1238"
			(at 0 0 180)
			(layer "F.SilkS")
			(hide yes)
			(effects
				(font
					(size 1.27 1.27)
				)
			)
		)
		(property "Value" ""
			(at 0 0 180)
			(layer "F.Fab")
			(effects
				(font
					(size 1.27 1.27)
				)
			)
		)
		(duplicate_pad_numbers_are_jumpers no)
		(fp_line
			(start 0.7874 0.4064)
			(end -0.7874 0.4064)
			(stroke
				(width 0.1524)
				(type default)
			)
			(layer "F.SilkS")
		)
		(fp_line
			(start 0.7874 -0.4064)
			(end 0.7874 0.4064)
			(stroke
				(width 0.1524)
				(type default)
			)
			(layer "F.SilkS")
		)
		(fp_line
			(start -0.7874 0.4064)
			(end -0.7874 -0.4064)
			(stroke
				(width 0.1524)
				(type default)
			)
			(layer "F.SilkS")
		)
		(fp_line
			(start -0.7874 -0.4064)
			(end 0.7874 -0.4064)
			(stroke
				(width 0.1524)
				(type default)
			)
			(layer "F.SilkS")
		)
		(fp_line
			(start 0.67945 0.3048)
			(end 0.120396 0.3048)
			(stroke
				(width 0.1)
				(type default)
			)
			(layer "F.Fab")
		)
		(fp_line
			(start 0.67945 -0.3048)
			(end 0.67945 0.3048)
			(stroke
				(width 0.1)
				(type default)
			)
			(layer "F.Fab")
		)
		(fp_line
			(start 0.12065 -0.2794)
			(end 0.12065 -0.3048)
			(stroke
				(width 0.1)
				(type default)
			)
			(layer "F.Fab")
		)
		(fp_line
			(start 0.12065 -0.3048)
			(end 0.67945 -0.3048)
			(stroke
				(width 0.1)
				(type default)
			)
			(layer "F.Fab")
		)
		(fp_line
			(start 0.120396 0.3048)
			(end 0.120396 0.2794)
			(stroke
				(width 0.1)
				(type default)
			)
			(layer "F.Fab")
		)
		(fp_line
			(start 0.120396 0.2794)
			(end -0.12065 0.2794)
			(stroke
				(width 0.1)
				(type default)
			)
			(layer "F.Fab")
		)
		(fp_line
			(start -0.12065 0.3048)
			(end -0.67945 0.3048)
			(stroke
				(width 0.1)
				(type default)
			)
			(layer "F.Fab")
		)
		(fp_line
			(start -0.12065 0.2794)
			(end -0.12065 0.3048)
			(stroke
				(width 0.1)
				(type default)
			)
			(layer "F.Fab")
		)
		(fp_line
			(start -0.12065 -0.2794)
			(end 0.12065 -0.2794)
			(stroke
				(width 0.1)
				(type default)
			)
			(layer "F.Fab")
		)
		(fp_line
			(start -0.12065 -0.305054)
			(end -0.12065 -0.2794)
			(stroke
				(width 0.1)
				(type default)
			)
			(layer "F.Fab")
		)
		(fp_line
			(start -0.67945 0.3048)
			(end -0.67945 -0.305054)
			(stroke
				(width 0.1)
				(type default)
			)
			(layer "F.Fab")
		)
		(fp_line
			(start -0.67945 -0.305054)
			(end -0.12065 -0.305054)
			(stroke
				(width 0.1)
				(type default)
			)
			(layer "F.Fab")
		)
		(pad "1" smd circle
			(at -0.40005 0 180)
			(size 0 0)
			(layers "F.Cu" "F.Mask" "F.Paste")
			(net "GND")
		)
		(pad "2" smd circle
			(at 0.40005 0 180)
			(size 0 0)
			(layers "F.Cu" "F.Mask" "F.Paste")
			(net "PUD_XTAL_CPU0_MODE0")
		)
	)
	(footprint ""
		(layer "F.Cu")
		(at 315.946028 -25.09139)
		(property "Reference" "R1442"
			(at 0 0 0)
			(layer "F.SilkS")
			(hide yes)
			(effects
				(font
					(size 1.27 1.27)
				)
			)
		)
		(property "Value" ""
			(at 0 0 0)
			(layer "F.Fab")
			(effects
				(font
					(size 1.27 1.27)
				)
			)
		)
		(duplicate_pad_numbers_are_jumpers no)
		(fp_line
			(start -0.7874 -0.4064)
			(end 0.7874 -0.4064)
			(stroke
				(width 0.1524)
				(type default)
			)
			(layer "F.SilkS")
		)
		(fp_line
			(start -0.7874 0.4064)
			(end -0.7874 -0.4064)
			(stroke
				(width 0.1524)
				(type default)
			)
			(layer "F.SilkS")
		)
		(fp_line
			(start 0.7874 -0.4064)
			(end 0.7874 0.4064)
			(stroke
				(width 0.1524)
				(type default)
			)
			(layer "F.SilkS")
		)
		(fp_line
			(start 0.7874 0.4064)
			(end -0.7874 0.4064)
			(stroke
				(width 0.1524)
				(type default)
			)
			(layer "F.SilkS")
		)
		(fp_line
			(start -0.67945 -0.305054)
			(end -0.12065 -0.305054)
			(stroke
				(width 0.1)
				(type default)
			)
			(layer "F.Fab")
		)
		(fp_line
			(start -0.67945 0.3048)
			(end -0.67945 -0.305054)
			(stroke
				(width 0.1)
				(type default)
			)
			(layer "F.Fab")
		)
		(fp_line
			(start -0.12065 -0.305054)
			(end -0.12065 -0.2794)
			(stroke
				(width 0.1)
				(type default)
			)
			(layer "F.Fab")
		)
		(fp_line
			(start -0.12065 -0.2794)
			(end 0.12065 -0.2794)
			(stroke
				(width 0.1)
				(type default)
			)
			(layer "F.Fab")
		)
		(fp_line
			(start -0.12065 0.2794)
			(end -0.12065 0.3048)
			(stroke
				(width 0.1)
				(type default)
			)
			(layer "F.Fab")
		)
		(fp_line
			(start -0.12065 0.3048)
			(end -0.67945 0.3048)
			(stroke
				(width 0.1)
				(type default)
			)
			(layer "F.Fab")
		)
		(fp_line
			(start 0.120396 0.2794)
			(end -0.12065 0.2794)
			(stroke
				(width 0.1)
				(type default)
			)
			(layer "F.Fab")
		)
		(fp_line
			(start 0.120396 0.3048)
			(end 0.120396 0.2794)
			(stroke
				(width 0.1)
				(type default)
			)
			(layer "F.Fab")
		)
		(fp_line
			(start 0.12065 -0.3048)
			(end 0.67945 -0.3048)
			(stroke
				(width 0.1)
				(type default)
			)
			(layer "F.Fab")
		)
		(fp_line
			(start 0.12065 -0.2794)
			(end 0.12065 -0.3048)
			(stroke
				(width 0.1)
				(type default)
			)
			(layer "F.Fab")
		)
		(fp_line
			(start 0.67945 -0.3048)
			(end 0.67945 0.3048)
			(stroke
				(width 0.1)
				(type default)
			)
			(layer "F.Fab")
		)
		(fp_line
			(start 0.67945 0.3048)
			(end 0.120396 0.3048)
			(stroke
				(width 0.1)
				(type default)
			)
			(layer "F.Fab")
		)
		(pad "1" smd circle
			(at -0.40005 0)
			(size 0 0)
			(layers "F.Cu" "F.Mask" "F.Paste")
			(net "PWRGD_PCH_PWROK_R")
		)
		(pad "2" smd circle
			(at 0.40005 0)
			(size 0 0)
			(layers "F.Cu" "F.Mask" "F.Paste")
			(net "PWRGD_PCH_PWROK")
		)
	)
	(footprint ""
		(layer "F.Cu")
		(at 204.93736 -114.264948 180)
		(property "Reference" "R4147"
			(at 0 0 180)
			(layer "F.SilkS")
			(hide yes)
			(effects
				(font
					(size 1.27 1.27)
				)
			)
		)
		(property "Value" ""
			(at 0 0 180)
			(layer "F.Fab")
			(effects
				(font
					(size 1.27 1.27)
				)
			)
		)
		(duplicate_pad_numbers_are_jumpers no)
		(fp_line
			(start 0.7874 0.4064)
			(end -0.7874 0.4064)
			(stroke
				(width 0.1524)
				(type default)
			)
			(layer "F.SilkS")
		)
		(fp_line
			(start 0.7874 -0.4064)
			(end 0.7874 0.4064)
			(stroke
				(width 0.1524)
				(type default)
			)
			(layer "F.SilkS")
		)
		(fp_line
			(start -0.7874 0.4064)
			(end -0.7874 -0.4064)
			(stroke
				(width 0.1524)
				(type default)
			)
			(layer "F.SilkS")
		)
		(fp_line
			(start -0.7874 -0.4064)
			(end 0.7874 -0.4064)
			(stroke
				(width 0.1524)
				(type default)
			)
			(layer "F.SilkS")
		)
		(fp_line
			(start 0.67945 0.3048)
			(end 0.120396 0.3048)
			(stroke
				(width 0.1)
				(type default)
			)
			(layer "F.Fab")
		)
		(fp_line
			(start 0.67945 -0.3048)
			(end 0.67945 0.3048)
			(stroke
				(width 0.1)
				(type default)
			)
			(layer "F.Fab")
		)
		(fp_line
			(start 0.12065 -0.2794)
			(end 0.12065 -0.3048)
			(stroke
				(width 0.1)
				(type default)
			)
			(layer "F.Fab")
		)
		(fp_line
			(start 0.12065 -0.3048)
			(end 0.67945 -0.3048)
			(stroke
				(width 0.1)
				(type default)
			)
			(layer "F.Fab")
		)
		(fp_line
			(start 0.120396 0.3048)
			(end 0.120396 0.2794)
			(stroke
				(width 0.1)
				(type default)
			)
			(layer "F.Fab")
		)
		(fp_line
			(start 0.120396 0.2794)
			(end -0.12065 0.2794)
			(stroke
				(width 0.1)
				(type default)
			)
			(layer "F.Fab")
		)
		(fp_line
			(start -0.12065 0.3048)
			(end -0.67945 0.3048)
			(stroke
				(width 0.1)
				(type default)
			)
			(layer "F.Fab")
		)
		(fp_line
			(start -0.12065 0.2794)
			(end -0.12065 0.3048)
			(stroke
				(width 0.1)
				(type default)
			)
			(layer "F.Fab")
		)
		(fp_line
			(start -0.12065 -0.2794)
			(end 0.12065 -0.2794)
			(stroke
				(width 0.1)
				(type default)
			)
			(layer "F.Fab")
		)
		(fp_line
			(start -0.12065 -0.305054)
			(end -0.12065 -0.2794)
			(stroke
				(width 0.1)
				(type default)
			)
			(layer "F.Fab")
		)
		(fp_line
			(start -0.67945 0.3048)
			(end -0.67945 -0.305054)
			(stroke
				(width 0.1)
				(type default)
			)
			(layer "F.Fab")
		)
		(fp_line
			(start -0.67945 -0.305054)
			(end -0.12065 -0.305054)
			(stroke
				(width 0.1)
				(type default)
			)
			(layer "F.Fab")
		)
		(pad "1" smd circle
			(at -0.40005 0 180)
			(size 0 0)
			(layers "F.Cu" "F.Mask" "F.Paste")
			(net "PRSNT_CABLE_GPU_A2_ISO_N")
		)
		(pad "2" smd circle
			(at 0.40005 0 180)
			(size 0 0)
			(layers "F.Cu" "F.Mask" "F.Paste")
			(net "PRSNT_CABLE_GPU_A2_ISO_R_N")
		)
	)
	(footprint ""
		(layer "F.Cu")
		(at 437.875172 -28.668218)
		(property "Reference" "R4532"
			(at 0 0 0)
			(layer "F.SilkS")
			(hide yes)
			(effects
				(font
					(size 1.27 1.27)
				)
			)
		)
		(property "Value" ""
			(at 0 0 0)
			(layer "F.Fab")
			(effects
				(font
					(size 1.27 1.27)
				)
			)
		)
		(duplicate_pad_numbers_are_jumpers no)
		(fp_line
			(start -0.7874 -0.4064)
			(end 0.7874 -0.4064)
			(stroke
				(width 0.1524)
				(type default)
			)
			(layer "F.SilkS")
		)
		(fp_line
			(start -0.7874 0.4064)
			(end -0.7874 -0.4064)
			(stroke
				(width 0.1524)
				(type default)
			)
			(layer "F.SilkS")
		)
		(fp_line
			(start 0.7874 -0.4064)
			(end 0.7874 0.4064)
			(stroke
				(width 0.1524)
				(type default)
			)
			(layer "F.SilkS")
		)
		(fp_line
			(start 0.7874 0.4064)
			(end -0.7874 0.4064)
			(stroke
				(width 0.1524)
				(type default)
			)
			(layer "F.SilkS")
		)
		(fp_line
			(start -0.67945 -0.305054)
			(end -0.12065 -0.305054)
			(stroke
				(width 0.1)
				(type default)
			)
			(layer "F.Fab")
		)
		(fp_line
			(start -0.67945 0.3048)
			(end -0.67945 -0.305054)
			(stroke
				(width 0.1)
				(type default)
			)
			(layer "F.Fab")
		)
		(fp_line
			(start -0.12065 -0.305054)
			(end -0.12065 -0.2794)
			(stroke
				(width 0.1)
				(type default)
			)
			(layer "F.Fab")
		)
		(fp_line
			(start -0.12065 -0.2794)
			(end 0.12065 -0.2794)
			(stroke
				(width 0.1)
				(type default)
			)
			(layer "F.Fab")
		)
		(fp_line
			(start -0.12065 0.2794)
			(end -0.12065 0.3048)
			(stroke
				(width 0.1)
				(type default)
			)
			(layer "F.Fab")
		)
		(fp_line
			(start -0.12065 0.3048)
			(end -0.67945 0.3048)
			(stroke
				(width 0.1)
				(type default)
			)
			(layer "F.Fab")
		)
		(fp_line
			(start 0.120396 0.2794)
			(end -0.12065 0.2794)
			(stroke
				(width 0.1)
				(type default)
			)
			(layer "F.Fab")
		)
		(fp_line
			(start 0.120396 0.3048)
			(end 0.120396 0.2794)
			(stroke
				(width 0.1)
				(type default)
			)
			(layer "F.Fab")
		)
		(fp_line
			(start 0.12065 -0.3048)
			(end 0.67945 -0.3048)
			(stroke
				(width 0.1)
				(type default)
			)
			(layer "F.Fab")
		)
		(fp_line
			(start 0.12065 -0.2794)
			(end 0.12065 -0.3048)
			(stroke
				(width 0.1)
				(type default)
			)
			(layer "F.Fab")
		)
		(fp_line
			(start 0.67945 -0.3048)
			(end 0.67945 0.3048)
			(stroke
				(width 0.1)
				(type default)
			)
			(layer "F.Fab")
		)
		(fp_line
			(start 0.67945 0.3048)
			(end 0.120396 0.3048)
			(stroke
				(width 0.1)
				(type default)
			)
			(layer "F.Fab")
		)
		(pad "1" smd circle
			(at -0.40005 0)
			(size 0 0)
			(layers "F.Cu" "F.Mask" "F.Paste")
			(net "P3V3_AUX")
		)
		(pad "2" smd circle
			(at 0.40005 0)
			(size 0 0)
			(layers "F.Cu" "F.Mask" "F.Paste")
			(net "HP_LVC3_OCP_V3_1_P12V_PWRGD")
		)
	)
	(footprint ""
		(layer "F.Cu")
		(at 8.80872 -76.827888)
		(property "Reference" "C1875"
			(at 0 0 0)
			(layer "F.SilkS")
			(hide yes)
			(effects
				(font
					(size 1.27 1.27)
				)
			)
		)
		(property "Value" ""
			(at 0 0 0)
			(layer "F.Fab")
			(effects
				(font
					(size 1.27 1.27)
				)
			)
		)
		(duplicate_pad_numbers_are_jumpers no)
		(fp_line
			(start -0.7874 -0.4064)
			(end 0.7874 -0.4064)
			(stroke
				(width 0.1524)
				(type default)
			)
			(layer "F.SilkS")
		)
		(fp_line
			(start -0.7874 0.4064)
			(end -0.7874 -0.4064)
			(stroke
				(width 0.1524)
				(type default)
			)
			(layer "F.SilkS")
		)
		(fp_line
			(start 0.7874 -0.4064)
			(end 0.7874 0.4064)
			(stroke
				(width 0.1524)
				(type default)
			)
			(layer "F.SilkS")
		)
		(fp_line
			(start 0.7874 0.4064)
			(end -0.7874 0.4064)
			(stroke
				(width 0.1524)
				(type default)
			)
			(layer "F.SilkS")
		)
		(fp_line
			(start -0.67945 -0.305054)
			(end -0.12065 -0.305054)
			(stroke
				(width 0.1)
				(type default)
			)
			(layer "F.Fab")
		)
		(fp_line
			(start -0.67945 0.3048)
			(end -0.67945 -0.305054)
			(stroke
				(width 0.1)
				(type default)
			)
			(layer "F.Fab")
		)
		(fp_line
			(start -0.12065 -0.305054)
			(end -0.12065 -0.2794)
			(stroke
				(width 0.1)
				(type default)
			)
			(layer "F.Fab")
		)
		(fp_line
			(start -0.12065 -0.2794)
			(end 0.12065 -0.2794)
			(stroke
				(width 0.1)
				(type default)
			)
			(layer "F.Fab")
		)
		(fp_line
			(start -0.12065 0.2794)
			(end -0.12065 0.3048)
			(stroke
				(width 0.1)
				(type default)
			)
			(layer "F.Fab")
		)
		(fp_line
			(start -0.12065 0.3048)
			(end -0.67945 0.3048)
			(stroke
				(width 0.1)
				(type default)
			)
			(layer "F.Fab")
		)
		(fp_line
			(start 0.120396 0.2794)
			(end -0.12065 0.2794)
			(stroke
				(width 0.1)
				(type default)
			)
			(layer "F.Fab")
		)
		(fp_line
			(start 0.120396 0.3048)
			(end 0.120396 0.2794)
			(stroke
				(width 0.1)
				(type default)
			)
			(layer "F.Fab")
		)
		(fp_line
			(start 0.12065 -0.3048)
			(end 0.67945 -0.3048)
			(stroke
				(width 0.1)
				(type default)
			)
			(layer "F.Fab")
		)
		(fp_line
			(start 0.12065 -0.2794)
			(end 0.12065 -0.3048)
			(stroke
				(width 0.1)
				(type default)
			)
			(layer "F.Fab")
		)
		(fp_line
			(start 0.67945 -0.3048)
			(end 0.67945 0.3048)
			(stroke
				(width 0.1)
				(type default)
			)
			(layer "F.Fab")
		)
		(fp_line
			(start 0.67945 0.3048)
			(end 0.120396 0.3048)
			(stroke
				(width 0.1)
				(type default)
			)
			(layer "F.Fab")
		)
		(pad "1" smd circle
			(at -0.40005 0)
			(size 0 0)
			(layers "F.Cu" "F.Mask" "F.Paste")
			(net "P3V3_AUX")
		)
		(pad "2" smd circle
			(at 0.40005 0)
			(size 0 0)
			(layers "F.Cu" "F.Mask" "F.Paste")
			(net "GND")
		)
	)
	(footprint ""
		(layer "F.Cu")
		(at 125.711204 -366.689132 90)
		(property "Reference" "PL119"
			(at -3.896614 4.481576 0)
			(unlocked yes)
			(layer "F.SilkS")
			(effects
				(font
					(size 0.7874 0.5842)
					(thickness 0.1524)
				)
				(justify left)
			)
		)
		(property "Value" ""
			(at 0 0 90)
			(layer "F.Fab")
			(effects
				(font
					(size 1.27 1.27)
				)
			)
		)
		(duplicate_pad_numbers_are_jumpers no)
		(fp_line
			(start 3.64998 -3.350006)
			(end 3.64998 -1.8034)
			(stroke
				(width 0.1524)
				(type default)
			)
			(layer "F.SilkS")
		)
		(fp_line
			(start -3.6576 -3.350006)
			(end 3.64998 -3.350006)
			(stroke
				(width 0.1524)
				(type default)
			)
			(layer "F.SilkS")
		)
		(fp_line
			(start -3.64998 -1.8034)
			(end -3.64998 -3.350006)
			(stroke
				(width 0.1524)
				(type default)
			)
			(layer "F.SilkS")
		)
		(fp_line
			(start 3.64998 1.8034)
			(end 3.64998 3.350006)
			(stroke
				(width 0.1524)
				(type default)
			)
			(layer "F.SilkS")
		)
		(fp_line
			(start 3.64998 3.350006)
			(end -3.64998 3.350006)
			(stroke
				(width 0.1524)
				(type default)
			)
			(layer "F.SilkS")
		)
		(fp_line
			(start -3.64998 3.350006)
			(end -3.64998 1.8288)
			(stroke
				(width 0.1524)
				(type default)
			)
			(layer "F.SilkS")
		)
		(fp_line
			(start 3.64998 -3.350006)
			(end 3.64998 3.350006)
			(stroke
				(width 0.1)
				(type default)
			)
			(layer "F.Fab")
		)
		(fp_line
			(start -3.64998 -3.350006)
			(end 3.64998 -3.350006)
			(stroke
				(width 0.1)
				(type default)
			)
			(layer "F.Fab")
		)
		(fp_line
			(start 3.64998 3.350006)
			(end -3.64998 3.350006)
			(stroke
				(width 0.1)
				(type default)
			)
			(layer "F.Fab")
		)
		(fp_line
			(start -3.64998 3.350006)
			(end -3.64998 -3.350006)
			(stroke
				(width 0.1)
				(type default)
			)
			(layer "F.Fab")
		)
		(pad "1" smd rect
			(at -2.92481 0 90)
			(size 2.15392 3.302)
			(layers "F.Cu" "F.Mask" "F.Paste")
			(net "SW_PVPP_HBM_CPU1_SW")
		)
		(pad "2" smd rect
			(at 2.92481 0 90)
			(size 2.15392 3.302)
			(layers "F.Cu" "F.Mask" "F.Paste")
			(net "PVPP_HBM_CPU1")
		)
	)
	(footprint ""
		(layer "F.Cu")
		(at 371.39753 -402.371052 -90)
		(property "Reference" "C934"
			(at 0 0 270)
			(layer "F.SilkS")
			(hide yes)
			(effects
				(font
					(size 1.27 1.27)
				)
			)
		)
		(property "Value" ""
			(at 0 0 270)
			(layer "F.Fab")
			(effects
				(font
					(size 1.27 1.27)
				)
			)
		)
		(duplicate_pad_numbers_are_jumpers no)
		(fp_line
			(start -0.299974 0.150114)
			(end -0.299974 -0.150114)
			(stroke
				(width 0.1)
				(type default)
			)
			(layer "F.Fab")
		)
		(fp_line
			(start 0.299974 0.150114)
			(end -0.299974 0.150114)
			(stroke
				(width 0.1)
				(type default)
			)
			(layer "F.Fab")
		)
		(fp_line
			(start -0.299974 -0.150114)
			(end 0.299974 -0.150114)
			(stroke
				(width 0.1)
				(type default)
			)
			(layer "F.Fab")
		)
		(fp_line
			(start 0.299974 -0.150114)
			(end 0.299974 0.150114)
			(stroke
				(width 0.1)
				(type default)
			)
			(layer "F.Fab")
		)
		(pad "1" smd rect
			(at -0.2667 0 270)
			(size 0.3048 0.381)
			(layers "F.Cu" "F.Mask" "F.Paste")
			(net "P5E_CPU0_PE2_TX_C_DN<15>")
		)
		(pad "2" smd rect
			(at 0.2667 0 270)
			(size 0.3048 0.381)
			(layers "F.Cu" "F.Mask" "F.Paste")
			(net "P5E_CPU0_PE2_TX_DN<15>")
		)
	)
	(footprint ""
		(layer "F.Cu")
		(at 451.81774 -113.172748 -90)
		(property "Reference" "C578"
			(at 0 0 270)
			(layer "F.SilkS")
			(hide yes)
			(effects
				(font
					(size 1.27 1.27)
				)
			)
		)
		(property "Value" ""
			(at 0 0 270)
			(layer "F.Fab")
			(effects
				(font
					(size 1.27 1.27)
				)
			)
		)
		(duplicate_pad_numbers_are_jumpers no)
		(fp_line
			(start -0.7874 0.4064)
			(end -0.7874 -0.4064)
			(stroke
				(width 0.1524)
				(type default)
			)
			(layer "F.SilkS")
		)
		(fp_line
			(start 0.7874 0.4064)
			(end -0.7874 0.4064)
			(stroke
				(width 0.1524)
				(type default)
			)
			(layer "F.SilkS")
		)
		(fp_line
			(start -0.7874 -0.4064)
			(end 0.7874 -0.4064)
			(stroke
				(width 0.1524)
				(type default)
			)
			(layer "F.SilkS")
		)
		(fp_line
			(start 0.7874 -0.4064)
			(end 0.7874 0.4064)
			(stroke
				(width 0.1524)
				(type default)
			)
			(layer "F.SilkS")
		)
		(fp_line
			(start -0.67945 0.3048)
			(end -0.67945 -0.305054)
			(stroke
				(width 0.1)
				(type default)
			)
			(layer "F.Fab")
		)
		(fp_line
			(start -0.12065 0.3048)
			(end -0.67945 0.3048)
			(stroke
				(width 0.1)
				(type default)
			)
			(layer "F.Fab")
		)
		(fp_line
			(start 0.120396 0.3048)
			(end 0.120396 0.2794)
			(stroke
				(width 0.1)
				(type default)
			)
			(layer "F.Fab")
		)
		(fp_line
			(start 0.67945 0.3048)
			(end 0.120396 0.3048)
			(stroke
				(width 0.1)
				(type default)
			)
			(layer "F.Fab")
		)
		(fp_line
			(start -0.12065 0.2794)
			(end -0.12065 0.3048)
			(stroke
				(width 0.1)
				(type default)
			)
			(layer "F.Fab")
		)
		(fp_line
			(start 0.120396 0.2794)
			(end -0.12065 0.2794)
			(stroke
				(width 0.1)
				(type default)
			)
			(layer "F.Fab")
		)
		(fp_line
			(start -0.12065 -0.2794)
			(end 0.12065 -0.2794)
			(stroke
				(width 0.1)
				(type default)
			)
			(layer "F.Fab")
		)
		(fp_line
			(start 0.12065 -0.2794)
			(end 0.12065 -0.3048)
			(stroke
				(width 0.1)
				(type default)
			)
			(layer "F.Fab")
		)
		(fp_line
			(start 0.12065 -0.3048)
			(end 0.67945 -0.3048)
			(stroke
				(width 0.1)
				(type default)
			)
			(layer "F.Fab")
		)
		(fp_line
			(start 0.67945 -0.3048)
			(end 0.67945 0.3048)
			(stroke
				(width 0.1)
				(type default)
			)
			(layer "F.Fab")
		)
		(fp_line
			(start -0.67945 -0.305054)
			(end -0.12065 -0.305054)
			(stroke
				(width 0.1)
				(type default)
			)
			(layer "F.Fab")
		)
		(fp_line
			(start -0.12065 -0.305054)
			(end -0.12065 -0.2794)
			(stroke
				(width 0.1)
				(type default)
			)
			(layer "F.Fab")
		)
		(pad "1" smd circle
			(at -0.40005 0 270)
			(size 0 0)
			(layers "F.Cu" "F.Mask" "F.Paste")
			(net "P3V3_AUX")
		)
		(pad "2" smd circle
			(at 0.40005 0 270)
			(size 0 0)
			(layers "F.Cu" "F.Mask" "F.Paste")
			(net "GND")
		)
	)
	(footprint ""
		(layer "F.Cu")
		(at 126.534926 -119.810784 -90)
		(property "Reference" "R2969"
			(at 0 0 270)
			(layer "F.SilkS")
			(hide yes)
			(effects
				(font
					(size 1.27 1.27)
				)
			)
		)
		(property "Value" ""
			(at 0 0 270)
			(layer "F.Fab")
			(effects
				(font
					(size 1.27 1.27)
				)
			)
		)
		(duplicate_pad_numbers_are_jumpers no)
		(fp_line
			(start -0.7874 0.4064)
			(end -0.7874 -0.4064)
			(stroke
				(width 0.1524)
				(type default)
			)
			(layer "F.SilkS")
		)
		(fp_line
			(start 0.7874 0.4064)
			(end -0.7874 0.4064)
			(stroke
				(width 0.1524)
				(type default)
			)
			(layer "F.SilkS")
		)
		(fp_line
			(start -0.7874 -0.4064)
			(end 0.7874 -0.4064)
			(stroke
				(width 0.1524)
				(type default)
			)
			(layer "F.SilkS")
		)
		(fp_line
			(start 0.7874 -0.4064)
			(end 0.7874 0.4064)
			(stroke
				(width 0.1524)
				(type default)
			)
			(layer "F.SilkS")
		)
		(fp_line
			(start -0.67945 0.3048)
			(end -0.67945 -0.305054)
			(stroke
				(width 0.1)
				(type default)
			)
			(layer "F.Fab")
		)
		(fp_line
			(start -0.12065 0.3048)
			(end -0.67945 0.3048)
			(stroke
				(width 0.1)
				(type default)
			)
			(layer "F.Fab")
		)
		(fp_line
			(start 0.120396 0.3048)
			(end 0.120396 0.2794)
			(stroke
				(width 0.1)
				(type default)
			)
			(layer "F.Fab")
		)
		(fp_line
			(start 0.67945 0.3048)
			(end 0.120396 0.3048)
			(stroke
				(width 0.1)
				(type default)
			)
			(layer "F.Fab")
		)
		(fp_line
			(start -0.12065 0.2794)
			(end -0.12065 0.3048)
			(stroke
				(width 0.1)
				(type default)
			)
			(layer "F.Fab")
		)
		(fp_line
			(start 0.120396 0.2794)
			(end -0.12065 0.2794)
			(stroke
				(width 0.1)
				(type default)
			)
			(layer "F.Fab")
		)
		(fp_line
			(start -0.12065 -0.2794)
			(end 0.12065 -0.2794)
			(stroke
				(width 0.1)
				(type default)
			)
			(layer "F.Fab")
		)
		(fp_line
			(start 0.12065 -0.2794)
			(end 0.12065 -0.3048)
			(stroke
				(width 0.1)
				(type default)
			)
			(layer "F.Fab")
		)
		(fp_line
			(start 0.12065 -0.3048)
			(end 0.67945 -0.3048)
			(stroke
				(width 0.1)
				(type default)
			)
			(layer "F.Fab")
		)
		(fp_line
			(start 0.67945 -0.3048)
			(end 0.67945 0.3048)
			(stroke
				(width 0.1)
				(type default)
			)
			(layer "F.Fab")
		)
		(fp_line
			(start -0.67945 -0.305054)
			(end -0.12065 -0.305054)
			(stroke
				(width 0.1)
				(type default)
			)
			(layer "F.Fab")
		)
		(fp_line
			(start -0.12065 -0.305054)
			(end -0.12065 -0.2794)
			(stroke
				(width 0.1)
				(type default)
			)
			(layer "F.Fab")
		)
		(pad "1" smd circle
			(at -0.40005 0 270)
			(size 0 0)
			(layers "F.Cu" "F.Mask" "F.Paste")
			(net "RST_CPU1_DRAM_GH_N")
		)
		(pad "2" smd circle
			(at 0.40005 0 270)
			(size 0 0)
			(layers "F.Cu" "F.Mask" "F.Paste")
			(net "RST_CPU1_DRAM_GH_PLD_N")
		)
	)
	(footprint ""
		(layer "F.Cu")
		(at 15.436596 -395.247876 180)
		(property "Reference" "R3268"
			(at 0 0 180)
			(layer "F.SilkS")
			(hide yes)
			(effects
				(font
					(size 1.27 1.27)
				)
			)
		)
		(property "Value" ""
			(at 0 0 180)
			(layer "F.Fab")
			(effects
				(font
					(size 1.27 1.27)
				)
			)
		)
		(duplicate_pad_numbers_are_jumpers no)
		(fp_line
			(start 0.7874 0.4064)
			(end -0.7874 0.4064)
			(stroke
				(width 0.1524)
				(type default)
			)
			(layer "F.SilkS")
		)
		(fp_line
			(start 0.7874 -0.4064)
			(end 0.7874 0.4064)
			(stroke
				(width 0.1524)
				(type default)
			)
			(layer "F.SilkS")
		)
		(fp_line
			(start -0.7874 0.4064)
			(end -0.7874 -0.4064)
			(stroke
				(width 0.1524)
				(type default)
			)
			(layer "F.SilkS")
		)
		(fp_line
			(start -0.7874 -0.4064)
			(end 0.7874 -0.4064)
			(stroke
				(width 0.1524)
				(type default)
			)
			(layer "F.SilkS")
		)
		(fp_line
			(start 0.67945 0.3048)
			(end 0.120396 0.3048)
			(stroke
				(width 0.1)
				(type default)
			)
			(layer "F.Fab")
		)
		(fp_line
			(start 0.67945 -0.3048)
			(end 0.67945 0.3048)
			(stroke
				(width 0.1)
				(type default)
			)
			(layer "F.Fab")
		)
		(fp_line
			(start 0.12065 -0.2794)
			(end 0.12065 -0.3048)
			(stroke
				(width 0.1)
				(type default)
			)
			(layer "F.Fab")
		)
		(fp_line
			(start 0.12065 -0.3048)
			(end 0.67945 -0.3048)
			(stroke
				(width 0.1)
				(type default)
			)
			(layer "F.Fab")
		)
		(fp_line
			(start 0.120396 0.3048)
			(end 0.120396 0.2794)
			(stroke
				(width 0.1)
				(type default)
			)
			(layer "F.Fab")
		)
		(fp_line
			(start 0.120396 0.2794)
			(end -0.12065 0.2794)
			(stroke
				(width 0.1)
				(type default)
			)
			(layer "F.Fab")
		)
		(fp_line
			(start -0.12065 0.3048)
			(end -0.67945 0.3048)
			(stroke
				(width 0.1)
				(type default)
			)
			(layer "F.Fab")
		)
		(fp_line
			(start -0.12065 0.2794)
			(end -0.12065 0.3048)
			(stroke
				(width 0.1)
				(type default)
			)
			(layer "F.Fab")
		)
		(fp_line
			(start -0.12065 -0.2794)
			(end 0.12065 -0.2794)
			(stroke
				(width 0.1)
				(type default)
			)
			(layer "F.Fab")
		)
		(fp_line
			(start -0.12065 -0.305054)
			(end -0.12065 -0.2794)
			(stroke
				(width 0.1)
				(type default)
			)
			(layer "F.Fab")
		)
		(fp_line
			(start -0.67945 0.3048)
			(end -0.67945 -0.305054)
			(stroke
				(width 0.1)
				(type default)
			)
			(layer "F.Fab")
		)
		(fp_line
			(start -0.67945 -0.305054)
			(end -0.12065 -0.305054)
			(stroke
				(width 0.1)
				(type default)
			)
			(layer "F.Fab")
		)
		(pad "1" smd circle
			(at -0.40005 0 180)
			(size 0 0)
			(layers "F.Cu" "F.Mask" "F.Paste")
			(net "FM_P2E_EQA1")
		)
		(pad "2" smd circle
			(at 0.40005 0 180)
			(size 0 0)
			(layers "F.Cu" "F.Mask" "F.Paste")
			(net "GND")
		)
	)
	(footprint ""
		(layer "F.Cu")
		(at 116.561616 -247.715278 90)
		(property "Reference" "C282"
			(at 0 0 90)
			(layer "F.SilkS")
			(hide yes)
			(effects
				(font
					(size 1.27 1.27)
				)
			)
		)
		(property "Value" ""
			(at 0 0 90)
			(layer "F.Fab")
			(effects
				(font
					(size 1.27 1.27)
				)
			)
		)
		(duplicate_pad_numbers_are_jumpers no)
		(fp_line
			(start 0.7874 -0.4064)
			(end 0.7874 0.4064)
			(stroke
				(width 0.1524)
				(type default)
			)
			(layer "F.SilkS")
		)
		(fp_line
			(start -0.7874 -0.4064)
			(end 0.7874 -0.4064)
			(stroke
				(width 0.1524)
				(type default)
			)
			(layer "F.SilkS")
		)
		(fp_line
			(start 0.7874 0.4064)
			(end -0.7874 0.4064)
			(stroke
				(width 0.1524)
				(type default)
			)
			(layer "F.SilkS")
		)
		(fp_line
			(start -0.7874 0.4064)
			(end -0.7874 -0.4064)
			(stroke
				(width 0.1524)
				(type default)
			)
			(layer "F.SilkS")
		)
		(fp_line
			(start -0.12065 -0.305054)
			(end -0.12065 -0.2794)
			(stroke
				(width 0.1)
				(type default)
			)
			(layer "F.Fab")
		)
		(fp_line
			(start -0.67945 -0.305054)
			(end -0.12065 -0.305054)
			(stroke
				(width 0.1)
				(type default)
			)
			(layer "F.Fab")
		)
		(fp_line
			(start 0.67945 -0.3048)
			(end 0.67945 0.3048)
			(stroke
				(width 0.1)
				(type default)
			)
			(layer "F.Fab")
		)
		(fp_line
			(start 0.12065 -0.3048)
			(end 0.67945 -0.3048)
			(stroke
				(width 0.1)
				(type default)
			)
			(layer "F.Fab")
		)
		(fp_line
			(start 0.12065 -0.2794)
			(end 0.12065 -0.3048)
			(stroke
				(width 0.1)
				(type default)
			)
			(layer "F.Fab")
		)
		(fp_line
			(start -0.12065 -0.2794)
			(end 0.12065 -0.2794)
			(stroke
				(width 0.1)
				(type default)
			)
			(layer "F.Fab")
		)
		(fp_line
			(start 0.120396 0.2794)
			(end -0.12065 0.2794)
			(stroke
				(width 0.1)
				(type default)
			)
			(layer "F.Fab")
		)
		(fp_line
			(start -0.12065 0.2794)
			(end -0.12065 0.3048)
			(stroke
				(width 0.1)
				(type default)
			)
			(layer "F.Fab")
		)
		(fp_line
			(start 0.67945 0.3048)
			(end 0.120396 0.3048)
			(stroke
				(width 0.1)
				(type default)
			)
			(layer "F.Fab")
		)
		(fp_line
			(start 0.120396 0.3048)
			(end 0.120396 0.2794)
			(stroke
				(width 0.1)
				(type default)
			)
			(layer "F.Fab")
		)
		(fp_line
			(start -0.12065 0.3048)
			(end -0.67945 0.3048)
			(stroke
				(width 0.1)
				(type default)
			)
			(layer "F.Fab")
		)
		(fp_line
			(start -0.67945 0.3048)
			(end -0.67945 -0.305054)
			(stroke
				(width 0.1)
				(type default)
			)
			(layer "F.Fab")
		)
		(pad "1" smd circle
			(at -0.40005 0 90)
			(size 0 0)
			(layers "F.Cu" "F.Mask" "F.Paste")
			(net "PVCCIN_CPU1")
		)
		(pad "2" smd circle
			(at 0.40005 0 90)
			(size 0 0)
			(layers "F.Cu" "F.Mask" "F.Paste")
			(net "GND")
		)
	)
	(footprint ""
		(layer "F.Cu")
		(at 21.176996 -99.413314 180)
		(property "Reference" "R3657"
			(at 0 0 180)
			(layer "F.SilkS")
			(hide yes)
			(effects
				(font
					(size 1.27 1.27)
				)
			)
		)
		(property "Value" ""
			(at 0 0 180)
			(layer "F.Fab")
			(effects
				(font
					(size 1.27 1.27)
				)
			)
		)
		(duplicate_pad_numbers_are_jumpers no)
		(fp_line
			(start 0.7874 0.4064)
			(end -0.7874 0.4064)
			(stroke
				(width 0.1524)
				(type default)
			)
			(layer "F.SilkS")
		)
		(fp_line
			(start 0.7874 -0.4064)
			(end 0.7874 0.4064)
			(stroke
				(width 0.1524)
				(type default)
			)
			(layer "F.SilkS")
		)
		(fp_line
			(start -0.7874 0.4064)
			(end -0.7874 -0.4064)
			(stroke
				(width 0.1524)
				(type default)
			)
			(layer "F.SilkS")
		)
		(fp_line
			(start -0.7874 -0.4064)
			(end 0.7874 -0.4064)
			(stroke
				(width 0.1524)
				(type default)
			)
			(layer "F.SilkS")
		)
		(fp_line
			(start 0.67945 0.3048)
			(end 0.120396 0.3048)
			(stroke
				(width 0.1)
				(type default)
			)
			(layer "F.Fab")
		)
		(fp_line
			(start 0.67945 -0.3048)
			(end 0.67945 0.3048)
			(stroke
				(width 0.1)
				(type default)
			)
			(layer "F.Fab")
		)
		(fp_line
			(start 0.12065 -0.2794)
			(end 0.12065 -0.3048)
			(stroke
				(width 0.1)
				(type default)
			)
			(layer "F.Fab")
		)
		(fp_line
			(start 0.12065 -0.3048)
			(end 0.67945 -0.3048)
			(stroke
				(width 0.1)
				(type default)
			)
			(layer "F.Fab")
		)
		(fp_line
			(start 0.120396 0.3048)
			(end 0.120396 0.2794)
			(stroke
				(width 0.1)
				(type default)
			)
			(layer "F.Fab")
		)
		(fp_line
			(start 0.120396 0.2794)
			(end -0.12065 0.2794)
			(stroke
				(width 0.1)
				(type default)
			)
			(layer "F.Fab")
		)
		(fp_line
			(start -0.12065 0.3048)
			(end -0.67945 0.3048)
			(stroke
				(width 0.1)
				(type default)
			)
			(layer "F.Fab")
		)
		(fp_line
			(start -0.12065 0.2794)
			(end -0.12065 0.3048)
			(stroke
				(width 0.1)
				(type default)
			)
			(layer "F.Fab")
		)
		(fp_line
			(start -0.12065 -0.2794)
			(end 0.12065 -0.2794)
			(stroke
				(width 0.1)
				(type default)
			)
			(layer "F.Fab")
		)
		(fp_line
			(start -0.12065 -0.305054)
			(end -0.12065 -0.2794)
			(stroke
				(width 0.1)
				(type default)
			)
			(layer "F.Fab")
		)
		(fp_line
			(start -0.67945 0.3048)
			(end -0.67945 -0.305054)
			(stroke
				(width 0.1)
				(type default)
			)
			(layer "F.Fab")
		)
		(fp_line
			(start -0.67945 -0.305054)
			(end -0.12065 -0.305054)
			(stroke
				(width 0.1)
				(type default)
			)
			(layer "F.Fab")
		)
		(pad "1" smd circle
			(at -0.40005 0 180)
			(size 0 0)
			(layers "F.Cu" "F.Mask" "F.Paste")
			(net "P3V3_AUX")
		)
		(pad "2" smd circle
			(at 0.40005 0 180)
			(size 0 0)
			(layers "F.Cu" "F.Mask" "F.Paste")
			(net "USB_HUB_OVCUR2")
		)
	)
	(footprint ""
		(layer "F.Cu")
		(at 157.061408 -45.462698 -90)
		(property "Reference" "R4461"
			(at 0 0 270)
			(layer "F.SilkS")
			(hide yes)
			(effects
				(font
					(size 1.27 1.27)
				)
			)
		)
		(property "Value" ""
			(at 0 0 270)
			(layer "F.Fab")
			(effects
				(font
					(size 1.27 1.27)
				)
			)
		)
		(duplicate_pad_numbers_are_jumpers no)
		(fp_line
			(start -0.7874 -0.4064)
			(end 0.7874 -0.4064)
			(stroke
				(width 0.1524)
				(type default)
			)
			(layer "F.SilkS")
		)
		(fp_line
			(start 0.7874 -0.4064)
			(end 0.7874 0.4064)
			(stroke
				(width 0.1524)
				(type default)
			)
			(layer "F.SilkS")
		)
		(fp_line
			(start -0.67945 0.3048)
			(end -0.67945 -0.305054)
			(stroke
				(width 0.1)
				(type default)
			)
			(layer "F.Fab")
		)
		(fp_line
			(start -0.12065 0.3048)
			(end -0.67945 0.3048)
			(stroke
				(width 0.1)
				(type default)
			)
			(layer "F.Fab")
		)
		(fp_line
			(start 0.120396 0.3048)
			(end 0.120396 0.2794)
			(stroke
				(width 0.1)
				(type default)
			)
			(layer "F.Fab")
		)
		(fp_line
			(start 0.67945 0.3048)
			(end 0.120396 0.3048)
			(stroke
				(width 0.1)
				(type default)
			)
			(layer "F.Fab")
		)
		(fp_line
			(start -0.12065 0.2794)
			(end -0.12065 0.3048)
			(stroke
				(width 0.1)
				(type default)
			)
			(layer "F.Fab")
		)
		(fp_line
			(start 0.120396 0.2794)
			(end -0.12065 0.2794)
			(stroke
				(width 0.1)
				(type default)
			)
			(layer "F.Fab")
		)
		(fp_line
			(start -0.12065 -0.2794)
			(end 0.12065 -0.2794)
			(stroke
				(width 0.1)
				(type default)
			)
			(layer "F.Fab")
		)
		(fp_line
			(start 0.12065 -0.2794)
			(end 0.12065 -0.3048)
			(stroke
				(width 0.1)
				(type default)
			)
			(layer "F.Fab")
		)
		(fp_line
			(start 0.12065 -0.3048)
			(end 0.67945 -0.3048)
			(stroke
				(width 0.1)
				(type default)
			)
			(layer "F.Fab")
		)
		(fp_line
			(start 0.67945 -0.3048)
			(end 0.67945 0.3048)
			(stroke
				(width 0.1)
				(type default)
			)
			(layer "F.Fab")
		)
		(fp_line
			(start -0.67945 -0.305054)
			(end -0.12065 -0.305054)
			(stroke
				(width 0.1)
				(type default)
			)
			(layer "F.Fab")
		)
		(fp_line
			(start -0.12065 -0.305054)
			(end -0.12065 -0.2794)
			(stroke
				(width 0.1)
				(type default)
			)
			(layer "F.Fab")
		)
		(pad "1" smd rect
			(at -0.40005 0 90)
			(size 0.4572 0.508)
			(layers "F.Cu" "F.Mask" "F.Paste")
			(net "USB2_HOST_PCH_0_DN")
		)
		(pad "2" smd rect
			(at 0.40005 0 90)
			(size 0.4572 0.508)
			(layers "F.Cu" "F.Mask" "F.Paste")
			(net "USB2_HUB_2_BUF_EXT_R_DN")
		)
	)
	(footprint ""
		(layer "F.Cu")
		(at 346.70619 -69.36994 90)
		(property "Reference" "C149"
			(at 0 0 90)
			(layer "F.SilkS")
			(hide yes)
			(effects
				(font
					(size 1.27 1.27)
				)
			)
		)
		(property "Value" ""
			(at 0 0 90)
			(layer "F.Fab")
			(effects
				(font
					(size 1.27 1.27)
				)
			)
		)
		(duplicate_pad_numbers_are_jumpers no)
		(fp_line
			(start 0.299974 -0.150114)
			(end 0.299974 0.150114)
			(stroke
				(width 0.1)
				(type default)
			)
			(layer "F.Fab")
		)
		(fp_line
			(start -0.299974 -0.150114)
			(end 0.299974 -0.150114)
			(stroke
				(width 0.1)
				(type default)
			)
			(layer "F.Fab")
		)
		(fp_line
			(start 0.299974 0.150114)
			(end -0.299974 0.150114)
			(stroke
				(width 0.1)
				(type default)
			)
			(layer "F.Fab")
		)
		(fp_line
			(start -0.299974 0.150114)
			(end -0.299974 -0.150114)
			(stroke
				(width 0.1)
				(type default)
			)
			(layer "F.Fab")
		)
		(pad "1" smd rect
			(at -0.2667 0 90)
			(size 0.3048 0.381)
			(layers "F.Cu" "F.Mask" "F.Paste")
			(net "DMI_CPU0_PCH_TX_C_DN<2>")
		)
		(pad "2" smd rect
			(at 0.2667 0 90)
			(size 0.3048 0.381)
			(layers "F.Cu" "F.Mask" "F.Paste")
			(net "DMI_CPU0_PCH_TX_DN<2>")
		)
		(zone
			(layer "In1.Cu")
			(hatch none 0.5)
			(connect_pads
				(clearance 0)
			)
			(min_thickness 0.25)
			(keepout
				(tracks not_allowed)
				(vias allowed)
				(pads allowed)
				(copperpour not_allowed)
				(footprints allowed)
			)
			(placement
				(enabled no)
				(sheetname "")
			)
			(fill
				(thermal_gap 0.5)
				(thermal_bridge_width 0.5)
				(island_removal_mode 0)
			)
			(polygon
				(pts
					(arc
						(start 346.94749 -69.50964)
						(mid 346.925172 -69.455758)
						(end 346.87129 -69.43344)
					)
					(arc
						(start 346.54109 -69.43344)
						(mid 346.487208 -69.455758)
						(end 346.46489 -69.50964)
					)
					(arc
						(start 346.46489 -69.76364)
						(mid 346.487208 -69.817522)
						(end 346.54109 -69.83984)
					)
					(arc
						(start 346.87129 -69.83984)
						(mid 346.925172 -69.817522)
						(end 346.94749 -69.76364)
					)
				)
			)
		)
		(zone
			(layer "In1.Cu")
			(hatch none 0.5)
			(connect_pads
				(clearance 0)
			)
			(min_thickness 0.25)
			(keepout
				(tracks not_allowed)
				(vias allowed)
				(pads allowed)
				(copperpour not_allowed)
				(footprints allowed)
			)
			(placement
				(enabled no)
				(sheetname "")
			)
			(fill
				(thermal_gap 0.5)
				(thermal_bridge_width 0.5)
				(island_removal_mode 0)
			)
			(polygon
				(pts
					(arc
						(start 346.94749 -68.97624)
						(mid 346.925172 -68.922358)
						(end 346.87129 -68.90004)
					)
					(arc
						(start 346.54109 -68.90004)
						(mid 346.487208 -68.922358)
						(end 346.46489 -68.97624)
					)
					(arc
						(start 346.46489 -69.23024)
						(mid 346.487208 -69.284122)
						(end 346.54109 -69.30644)
					)
					(arc
						(start 346.87129 -69.30644)
						(mid 346.925172 -69.284122)
						(end 346.94749 -69.23024)
					)
				)
			)
		)
	)
	(footprint ""
		(layer "F.Cu")
		(at 501.233948 2.33426 -90)
		(property "Reference" "X21"
			(at -1.33604 3.115818 90)
			(unlocked yes)
			(layer "F.SilkS")
			(effects
				(font
					(size 0.7874 0.5842)
					(thickness 0.1524)
				)
				(justify left)
			)
		)
		(property "Value" ""
			(at 0 0 270)
			(layer "F.Fab")
			(effects
				(font
					(size 1.27 1.27)
				)
			)
		)
		(property "Device Type" "TP_TDR_4P_FTS_MPKT4_H025P0200_I"
			(at 1.30175 1.27 0)
			(unlocked yes)
			(layer "F.Fab")
			(hide yes)
			(effects
				(font
					(size 0.635 0.4064)
					(thickness 0.1524)
				)
			)
		)
		(property "User Part Number" "TP15"
			(at 1.30175 1.27 0)
			(unlocked yes)
			(layer "Cmts.User")
			(hide yes)
			(effects
				(font
					(size 0.635 0.4064)
					(thickness 0.1524)
				)
			)
		)
		(duplicate_pad_numbers_are_jumpers no)
		(fp_line
			(start 0 3.81)
			(end 2.54 3.81)
			(stroke
				(width 0.1524)
				(type default)
			)
			(layer "F.SilkS")
		)
		(fp_line
			(start 2.54 3.81)
			(end 2.54 3.6703)
			(stroke
				(width 0.1524)
				(type default)
			)
			(layer "F.SilkS")
		)
		(fp_line
			(start 0 3.175)
			(end 0 3.81)
			(stroke
				(width 0.1524)
				(type default)
			)
			(layer "F.SilkS")
		)
		(fp_line
			(start 2.54 1.4097)
			(end 2.54 1.1303)
			(stroke
				(width 0.1524)
				(type default)
			)
			(layer "F.SilkS")
		)
		(fp_line
			(start 0 0.635)
			(end 0 1.905)
			(stroke
				(width 0.1524)
				(type default)
			)
			(layer "F.SilkS")
		)
		(fp_line
			(start 2.54 -1.1303)
			(end 2.54 -1.27)
			(stroke
				(width 0.1524)
				(type default)
			)
			(layer "F.SilkS")
		)
		(fp_line
			(start 0 -1.27)
			(end 0 -0.635)
			(stroke
				(width 0.1524)
				(type default)
			)
			(layer "F.SilkS")
		)
		(fp_line
			(start 2.54 -1.27)
			(end 0 -1.27)
			(stroke
				(width 0.1524)
				(type default)
			)
			(layer "F.SilkS")
		)
		(fp_poly
			(pts
				(xy -1.3589 0.041148) (xy -2.8829 0.803148) (xy -2.8829 -0.720852)
			)
			(stroke
				(width 0)
				(type default)
			)
			(fill yes)
			(layer "F.SilkS")
		)
		(fp_line
			(start 0 3.81)
			(end 2.54 3.81)
			(stroke
				(width 0.1)
				(type default)
			)
			(layer "F.Fab")
		)
		(fp_line
			(start 2.54 3.81)
			(end 2.54 -1.27)
			(stroke
				(width 0.1)
				(type default)
			)
			(layer "F.Fab")
		)
		(fp_line
			(start 0 -1.27)
			(end 0 3.81)
			(stroke
				(width 0.1)
				(type default)
			)
			(layer "F.Fab")
		)
		(fp_line
			(start 2.54 -1.27)
			(end 0 -1.27)
			(stroke
				(width 0.1)
				(type default)
			)
			(layer "F.Fab")
		)
		(fp_poly
			(pts
				(xy -0.761746 0) (xy -2.285746 -0.762) (xy -2.285746 0.762)
			)
			(stroke
				(width 0)
				(type default)
			)
			(fill yes)
			(layer "F.Fab")
		)
		(pad "1" thru_hole circle
			(at 0 0 270)
			(size 1.0033 1.0033)
			(drill 0.249936)
			(layers "*.Cu" "*.Mask")
			(remove_unused_layers no)
			(net "TDR_DIFF_100_IN2_DN")
			(clearance 0.10795)
			(thermal_gap 0.10795)
			(padstack
				(mode front_inner_back)
				(layer "Inner"
					(shape circle)
					(size 0.8001 0.8001)
					(clearance 0.1524)
				)
				(layer "B.Cu"
					(shape circle)
					(size 1.0033 1.0033)
					(clearance 0.10795)
				)
			)
		)
		(pad "2" thru_hole circle
			(at 2.54 0 270)
			(size 1.9939 1.9939)
			(drill 0.249936)
			(layers "*.Cu" "*.Mask")
			(remove_unused_layers no)
			(net "T1_GND")
			(clearance 0.10795)
			(thermal_gap 0.10795)
			(padstack
				(mode front_inner_back)
				(layer "Inner"
					(shape circle)
					(size 0.8001 0.8001)
					(clearance 0.1524)
				)
				(layer "B.Cu"
					(shape circle)
					(size 1.9939 1.9939)
					(clearance 0.10795)
				)
			)
		)
		(pad "3" thru_hole circle
			(at 2.54 2.54 270)
			(size 1.9939 1.9939)
			(drill 0.249936)
			(layers "*.Cu" "*.Mask")
			(remove_unused_layers no)
			(net "T1_GND")
			(clearance 0.10795)
			(thermal_gap 0.10795)
			(padstack
				(mode front_inner_back)
				(layer "Inner"
					(shape circle)
					(size 0.8001 0.8001)
					(clearance 0.1524)
				)
				(layer "B.Cu"
					(shape circle)
					(size 1.9939 1.9939)
					(clearance 0.10795)
				)
			)
		)
		(pad "4" thru_hole circle
			(at 0 2.54 270)
			(size 1.0033 1.0033)
			(drill 0.249936)
			(layers "*.Cu" "*.Mask")
			(remove_unused_layers no)
			(net "TDR_DIFF_100_IN2_DP")
			(clearance 0.10795)
			(thermal_gap 0.10795)
			(padstack
				(mode front_inner_back)
				(layer "Inner"
					(shape circle)
					(size 0.8001 0.8001)
					(clearance 0.1524)
				)
				(layer "B.Cu"
					(shape circle)
					(size 1.0033 1.0033)
					(clearance 0.10795)
				)
			)
		)
	)
	(footprint ""
		(layer "F.Cu")
		(at 364.50143 -247.715024 90)
		(property "Reference" "C985"
			(at 0 0 90)
			(layer "F.SilkS")
			(hide yes)
			(effects
				(font
					(size 1.27 1.27)
				)
			)
		)
		(property "Value" ""
			(at 0 0 90)
			(layer "F.Fab")
			(effects
				(font
					(size 1.27 1.27)
				)
			)
		)
		(duplicate_pad_numbers_are_jumpers no)
		(fp_line
			(start 0.7874 -0.4064)
			(end 0.7874 0.4064)
			(stroke
				(width 0.1524)
				(type default)
			)
			(layer "F.SilkS")
		)
		(fp_line
			(start -0.7874 -0.4064)
			(end 0.7874 -0.4064)
			(stroke
				(width 0.1524)
				(type default)
			)
			(layer "F.SilkS")
		)
		(fp_line
			(start 0.7874 0.4064)
			(end -0.7874 0.4064)
			(stroke
				(width 0.1524)
				(type default)
			)
			(layer "F.SilkS")
		)
		(fp_line
			(start -0.7874 0.4064)
			(end -0.7874 -0.4064)
			(stroke
				(width 0.1524)
				(type default)
			)
			(layer "F.SilkS")
		)
		(fp_line
			(start -0.12065 -0.305054)
			(end -0.12065 -0.2794)
			(stroke
				(width 0.1)
				(type default)
			)
			(layer "F.Fab")
		)
		(fp_line
			(start -0.67945 -0.305054)
			(end -0.12065 -0.305054)
			(stroke
				(width 0.1)
				(type default)
			)
			(layer "F.Fab")
		)
		(fp_line
			(start 0.67945 -0.3048)
			(end 0.67945 0.3048)
			(stroke
				(width 0.1)
				(type default)
			)
			(layer "F.Fab")
		)
		(fp_line
			(start 0.12065 -0.3048)
			(end 0.67945 -0.3048)
			(stroke
				(width 0.1)
				(type default)
			)
			(layer "F.Fab")
		)
		(fp_line
			(start 0.12065 -0.2794)
			(end 0.12065 -0.3048)
			(stroke
				(width 0.1)
				(type default)
			)
			(layer "F.Fab")
		)
		(fp_line
			(start -0.12065 -0.2794)
			(end 0.12065 -0.2794)
			(stroke
				(width 0.1)
				(type default)
			)
			(layer "F.Fab")
		)
		(fp_line
			(start 0.120396 0.2794)
			(end -0.12065 0.2794)
			(stroke
				(width 0.1)
				(type default)
			)
			(layer "F.Fab")
		)
		(fp_line
			(start -0.12065 0.2794)
			(end -0.12065 0.3048)
			(stroke
				(width 0.1)
				(type default)
			)
			(layer "F.Fab")
		)
		(fp_line
			(start 0.67945 0.3048)
			(end 0.120396 0.3048)
			(stroke
				(width 0.1)
				(type default)
			)
			(layer "F.Fab")
		)
		(fp_line
			(start 0.120396 0.3048)
			(end 0.120396 0.2794)
			(stroke
				(width 0.1)
				(type default)
			)
			(layer "F.Fab")
		)
		(fp_line
			(start -0.12065 0.3048)
			(end -0.67945 0.3048)
			(stroke
				(width 0.1)
				(type default)
			)
			(layer "F.Fab")
		)
		(fp_line
			(start -0.67945 0.3048)
			(end -0.67945 -0.305054)
			(stroke
				(width 0.1)
				(type default)
			)
			(layer "F.Fab")
		)
		(pad "1" smd circle
			(at -0.40005 0 90)
			(size 0 0)
			(layers "F.Cu" "F.Mask" "F.Paste")
			(net "PVCCIN_CPU0")
		)
		(pad "2" smd circle
			(at 0.40005 0 90)
			(size 0 0)
			(layers "F.Cu" "F.Mask" "F.Paste")
			(net "GND")
		)
	)
	(footprint ""
		(layer "F.Cu")
		(at 228.760782 -126.383542 180)
		(property "Reference" "R564"
			(at 0 0 180)
			(layer "F.SilkS")
			(hide yes)
			(effects
				(font
					(size 1.27 1.27)
				)
			)
		)
		(property "Value" ""
			(at 0 0 180)
			(layer "F.Fab")
			(effects
				(font
					(size 1.27 1.27)
				)
			)
		)
		(duplicate_pad_numbers_are_jumpers no)
		(fp_line
			(start 0.7874 -0.4064)
			(end 0.7874 0.039878)
			(stroke
				(width 0.1524)
				(type default)
			)
			(layer "F.SilkS")
		)
		(fp_line
			(start 0.330962 0.4064)
			(end -0.433578 0.4064)
			(stroke
				(width 0.1524)
				(type default)
			)
			(layer "F.SilkS")
		)
		(fp_line
			(start -0.7874 0.029718)
			(end -0.7874 -0.4064)
			(stroke
				(width 0.1524)
				(type default)
			)
			(layer "F.SilkS")
		)
		(fp_line
			(start -0.7874 -0.4064)
			(end 0.7874 -0.4064)
			(stroke
				(width 0.1524)
				(type default)
			)
			(layer "F.SilkS")
		)
		(fp_line
			(start 0.67945 0.3048)
			(end 0.120396 0.3048)
			(stroke
				(width 0.1)
				(type default)
			)
			(layer "F.Fab")
		)
		(fp_line
			(start 0.67945 -0.3048)
			(end 0.67945 0.3048)
			(stroke
				(width 0.1)
				(type default)
			)
			(layer "F.Fab")
		)
		(fp_line
			(start 0.12065 -0.2794)
			(end 0.12065 -0.3048)
			(stroke
				(width 0.1)
				(type default)
			)
			(layer "F.Fab")
		)
		(fp_line
			(start 0.12065 -0.3048)
			(end 0.67945 -0.3048)
			(stroke
				(width 0.1)
				(type default)
			)
			(layer "F.Fab")
		)
		(fp_line
			(start 0.120396 0.3048)
			(end 0.120396 0.2794)
			(stroke
				(width 0.1)
				(type default)
			)
			(layer "F.Fab")
		)
		(fp_line
			(start 0.120396 0.2794)
			(end -0.12065 0.2794)
			(stroke
				(width 0.1)
				(type default)
			)
			(layer "F.Fab")
		)
		(fp_line
			(start -0.12065 0.3048)
			(end -0.67945 0.3048)
			(stroke
				(width 0.1)
				(type default)
			)
			(layer "F.Fab")
		)
		(fp_line
			(start -0.12065 0.2794)
			(end -0.12065 0.3048)
			(stroke
				(width 0.1)
				(type default)
			)
			(layer "F.Fab")
		)
		(fp_line
			(start -0.12065 -0.2794)
			(end 0.12065 -0.2794)
			(stroke
				(width 0.1)
				(type default)
			)
			(layer "F.Fab")
		)
		(fp_line
			(start -0.12065 -0.305054)
			(end -0.12065 -0.2794)
			(stroke
				(width 0.1)
				(type default)
			)
			(layer "F.Fab")
		)
		(fp_line
			(start -0.67945 0.3048)
			(end -0.67945 -0.305054)
			(stroke
				(width 0.1)
				(type default)
			)
			(layer "F.Fab")
		)
		(fp_line
			(start -0.67945 -0.305054)
			(end -0.12065 -0.305054)
			(stroke
				(width 0.1)
				(type default)
			)
			(layer "F.Fab")
		)
		(pad "1" smd circle
			(at -0.40005 0 180)
			(size 0 0)
			(layers "F.Cu" "F.Mask" "F.Paste")
			(net "CLK_100M_OCP_SFF_0_R_DN")
		)
		(pad "2" smd circle
			(at 0.40005 0 180)
			(size 0 0)
			(layers "F.Cu" "F.Mask" "F.Paste")
			(net "CLK_100M_OCP_SFF_0_DN")
		)
	)
	(footprint ""
		(layer "F.Cu")
		(at 364.50143 -251.375418 90)
		(property "Reference" "C1032"
			(at 0 0 90)
			(layer "F.SilkS")
			(hide yes)
			(effects
				(font
					(size 1.27 1.27)
				)
			)
		)
		(property "Value" ""
			(at 0 0 90)
			(layer "F.Fab")
			(effects
				(font
					(size 1.27 1.27)
				)
			)
		)
		(duplicate_pad_numbers_are_jumpers no)
		(fp_line
			(start 0.7874 -0.4064)
			(end 0.7874 0.4064)
			(stroke
				(width 0.1524)
				(type default)
			)
			(layer "F.SilkS")
		)
		(fp_line
			(start -0.7874 -0.4064)
			(end 0.7874 -0.4064)
			(stroke
				(width 0.1524)
				(type default)
			)
			(layer "F.SilkS")
		)
		(fp_line
			(start 0.7874 0.4064)
			(end -0.7874 0.4064)
			(stroke
				(width 0.1524)
				(type default)
			)
			(layer "F.SilkS")
		)
		(fp_line
			(start -0.7874 0.4064)
			(end -0.7874 -0.4064)
			(stroke
				(width 0.1524)
				(type default)
			)
			(layer "F.SilkS")
		)
		(fp_line
			(start -0.12065 -0.305054)
			(end -0.12065 -0.2794)
			(stroke
				(width 0.1)
				(type default)
			)
			(layer "F.Fab")
		)
		(fp_line
			(start -0.67945 -0.305054)
			(end -0.12065 -0.305054)
			(stroke
				(width 0.1)
				(type default)
			)
			(layer "F.Fab")
		)
		(fp_line
			(start 0.67945 -0.3048)
			(end 0.67945 0.3048)
			(stroke
				(width 0.1)
				(type default)
			)
			(layer "F.Fab")
		)
		(fp_line
			(start 0.12065 -0.3048)
			(end 0.67945 -0.3048)
			(stroke
				(width 0.1)
				(type default)
			)
			(layer "F.Fab")
		)
		(fp_line
			(start 0.12065 -0.2794)
			(end 0.12065 -0.3048)
			(stroke
				(width 0.1)
				(type default)
			)
			(layer "F.Fab")
		)
		(fp_line
			(start -0.12065 -0.2794)
			(end 0.12065 -0.2794)
			(stroke
				(width 0.1)
				(type default)
			)
			(layer "F.Fab")
		)
		(fp_line
			(start 0.120396 0.2794)
			(end -0.12065 0.2794)
			(stroke
				(width 0.1)
				(type default)
			)
			(layer "F.Fab")
		)
		(fp_line
			(start -0.12065 0.2794)
			(end -0.12065 0.3048)
			(stroke
				(width 0.1)
				(type default)
			)
			(layer "F.Fab")
		)
		(fp_line
			(start 0.67945 0.3048)
			(end 0.120396 0.3048)
			(stroke
				(width 0.1)
				(type default)
			)
			(layer "F.Fab")
		)
		(fp_line
			(start 0.120396 0.3048)
			(end 0.120396 0.2794)
			(stroke
				(width 0.1)
				(type default)
			)
			(layer "F.Fab")
		)
		(fp_line
			(start -0.12065 0.3048)
			(end -0.67945 0.3048)
			(stroke
				(width 0.1)
				(type default)
			)
			(layer "F.Fab")
		)
		(fp_line
			(start -0.67945 0.3048)
			(end -0.67945 -0.305054)
			(stroke
				(width 0.1)
				(type default)
			)
			(layer "F.Fab")
		)
		(pad "1" smd circle
			(at -0.40005 0 90)
			(size 0 0)
			(layers "F.Cu" "F.Mask" "F.Paste")
			(net "PVCCIN_CPU0")
		)
		(pad "2" smd circle
			(at 0.40005 0 90)
			(size 0 0)
			(layers "F.Cu" "F.Mask" "F.Paste")
			(net "GND")
		)
	)
	(footprint ""
		(layer "F.Cu")
		(at 174.90948 -424.398948)
		(property "Reference" "C1769"
			(at 0 0 0)
			(layer "F.SilkS")
			(hide yes)
			(effects
				(font
					(size 1.27 1.27)
				)
			)
		)
		(property "Value" ""
			(at 0 0 0)
			(layer "F.Fab")
			(effects
				(font
					(size 1.27 1.27)
				)
			)
		)
		(duplicate_pad_numbers_are_jumpers no)
		(fp_line
			(start -0.7874 -0.4064)
			(end 0.7874 -0.4064)
			(stroke
				(width 0.1524)
				(type default)
			)
			(layer "F.SilkS")
		)
		(fp_line
			(start -0.7874 0.4064)
			(end -0.7874 -0.4064)
			(stroke
				(width 0.1524)
				(type default)
			)
			(layer "F.SilkS")
		)
		(fp_line
			(start 0.7874 -0.4064)
			(end 0.7874 0.4064)
			(stroke
				(width 0.1524)
				(type default)
			)
			(layer "F.SilkS")
		)
		(fp_line
			(start 0.7874 0.4064)
			(end -0.7874 0.4064)
			(stroke
				(width 0.1524)
				(type default)
			)
			(layer "F.SilkS")
		)
		(fp_line
			(start -0.67945 -0.305054)
			(end -0.12065 -0.305054)
			(stroke
				(width 0.1)
				(type default)
			)
			(layer "F.Fab")
		)
		(fp_line
			(start -0.67945 0.3048)
			(end -0.67945 -0.305054)
			(stroke
				(width 0.1)
				(type default)
			)
			(layer "F.Fab")
		)
		(fp_line
			(start -0.12065 -0.305054)
			(end -0.12065 -0.2794)
			(stroke
				(width 0.1)
				(type default)
			)
			(layer "F.Fab")
		)
		(fp_line
			(start -0.12065 -0.2794)
			(end 0.12065 -0.2794)
			(stroke
				(width 0.1)
				(type default)
			)
			(layer "F.Fab")
		)
		(fp_line
			(start -0.12065 0.2794)
			(end -0.12065 0.3048)
			(stroke
				(width 0.1)
				(type default)
			)
			(layer "F.Fab")
		)
		(fp_line
			(start -0.12065 0.3048)
			(end -0.67945 0.3048)
			(stroke
				(width 0.1)
				(type default)
			)
			(layer "F.Fab")
		)
		(fp_line
			(start 0.120396 0.2794)
			(end -0.12065 0.2794)
			(stroke
				(width 0.1)
				(type default)
			)
			(layer "F.Fab")
		)
		(fp_line
			(start 0.120396 0.3048)
			(end 0.120396 0.2794)
			(stroke
				(width 0.1)
				(type default)
			)
			(layer "F.Fab")
		)
		(fp_line
			(start 0.12065 -0.3048)
			(end 0.67945 -0.3048)
			(stroke
				(width 0.1)
				(type default)
			)
			(layer "F.Fab")
		)
		(fp_line
			(start 0.12065 -0.2794)
			(end 0.12065 -0.3048)
			(stroke
				(width 0.1)
				(type default)
			)
			(layer "F.Fab")
		)
		(fp_line
			(start 0.67945 -0.3048)
			(end 0.67945 0.3048)
			(stroke
				(width 0.1)
				(type default)
			)
			(layer "F.Fab")
		)
		(fp_line
			(start 0.67945 0.3048)
			(end 0.120396 0.3048)
			(stroke
				(width 0.1)
				(type default)
			)
			(layer "F.Fab")
		)
		(pad "1" smd circle
			(at -0.40005 0)
			(size 0 0)
			(layers "F.Cu" "F.Mask" "F.Paste")
			(net "P3V3_AUX")
		)
		(pad "2" smd circle
			(at 0.40005 0)
			(size 0 0)
			(layers "F.Cu" "F.Mask" "F.Paste")
			(net "GND")
		)
	)
	(footprint ""
		(layer "F.Cu")
		(at 261.94258 -77.485748 -90)
		(property "Reference" "PC2279"
			(at 0 0 270)
			(layer "F.SilkS")
			(hide yes)
			(effects
				(font
					(size 1.27 1.27)
				)
			)
		)
		(property "Value" ""
			(at 0 0 270)
			(layer "F.Fab")
			(effects
				(font
					(size 1.27 1.27)
				)
			)
		)
		(duplicate_pad_numbers_are_jumpers no)
		(fp_line
			(start -0.7874 0.4064)
			(end -0.7874 -0.4064)
			(stroke
				(width 0.1524)
				(type default)
			)
			(layer "F.SilkS")
		)
		(fp_line
			(start 0.7874 0.4064)
			(end -0.7874 0.4064)
			(stroke
				(width 0.1524)
				(type default)
			)
			(layer "F.SilkS")
		)
		(fp_line
			(start -0.7874 -0.4064)
			(end 0.7874 -0.4064)
			(stroke
				(width 0.1524)
				(type default)
			)
			(layer "F.SilkS")
		)
		(fp_line
			(start 0.7874 -0.4064)
			(end 0.7874 0.4064)
			(stroke
				(width 0.1524)
				(type default)
			)
			(layer "F.SilkS")
		)
		(fp_line
			(start -0.67945 0.3048)
			(end -0.67945 -0.305054)
			(stroke
				(width 0.1)
				(type default)
			)
			(layer "F.Fab")
		)
		(fp_line
			(start -0.12065 0.3048)
			(end -0.67945 0.3048)
			(stroke
				(width 0.1)
				(type default)
			)
			(layer "F.Fab")
		)
		(fp_line
			(start 0.120396 0.3048)
			(end 0.120396 0.2794)
			(stroke
				(width 0.1)
				(type default)
			)
			(layer "F.Fab")
		)
		(fp_line
			(start 0.67945 0.3048)
			(end 0.120396 0.3048)
			(stroke
				(width 0.1)
				(type default)
			)
			(layer "F.Fab")
		)
		(fp_line
			(start -0.12065 0.2794)
			(end -0.12065 0.3048)
			(stroke
				(width 0.1)
				(type default)
			)
			(layer "F.Fab")
		)
		(fp_line
			(start 0.120396 0.2794)
			(end -0.12065 0.2794)
			(stroke
				(width 0.1)
				(type default)
			)
			(layer "F.Fab")
		)
		(fp_line
			(start -0.12065 -0.2794)
			(end 0.12065 -0.2794)
			(stroke
				(width 0.1)
				(type default)
			)
			(layer "F.Fab")
		)
		(fp_line
			(start 0.12065 -0.2794)
			(end 0.12065 -0.3048)
			(stroke
				(width 0.1)
				(type default)
			)
			(layer "F.Fab")
		)
		(fp_line
			(start 0.12065 -0.3048)
			(end 0.67945 -0.3048)
			(stroke
				(width 0.1)
				(type default)
			)
			(layer "F.Fab")
		)
		(fp_line
			(start 0.67945 -0.3048)
			(end 0.67945 0.3048)
			(stroke
				(width 0.1)
				(type default)
			)
			(layer "F.Fab")
		)
		(fp_line
			(start -0.67945 -0.305054)
			(end -0.12065 -0.305054)
			(stroke
				(width 0.1)
				(type default)
			)
			(layer "F.Fab")
		)
		(fp_line
			(start -0.12065 -0.305054)
			(end -0.12065 -0.2794)
			(stroke
				(width 0.1)
				(type default)
			)
			(layer "F.Fab")
		)
		(pad "1" smd circle
			(at -0.40005 0 270)
			(size 0 0)
			(layers "F.Cu" "F.Mask" "F.Paste")
			(net "SH_P1V05_PCH_AUX_P")
		)
		(pad "2" smd circle
			(at 0.40005 0 270)
			(size 0 0)
			(layers "F.Cu" "F.Mask" "F.Paste")
			(net "SH_P1V05_PCH_AUX_N")
		)
	)
	(footprint ""
		(layer "F.Cu")
		(at 271.312894 -64.457834 180)
		(property "Reference" "PC117"
			(at 0 0 180)
			(layer "F.SilkS")
			(hide yes)
			(effects
				(font
					(size 1.27 1.27)
				)
			)
		)
		(property "Value" ""
			(at 0 0 180)
			(layer "F.Fab")
			(effects
				(font
					(size 1.27 1.27)
				)
			)
		)
		(duplicate_pad_numbers_are_jumpers no)
		(fp_line
			(start 4.53898 2.15011)
			(end -4.53898 2.15011)
			(stroke
				(width 0.1524)
				(type default)
			)
			(layer "F.SilkS")
		)
		(fp_line
			(start 4.53898 -2.15011)
			(end 4.53898 2.15011)
			(stroke
				(width 0.1524)
				(type default)
			)
			(layer "F.SilkS")
		)
		(fp_line
			(start -4.53898 2.15011)
			(end -4.53898 -2.15011)
			(stroke
				(width 0.1524)
				(type default)
			)
			(layer "F.SilkS")
		)
		(fp_line
			(start -4.53898 -2.15011)
			(end 4.53898 -2.15011)
			(stroke
				(width 0.1524)
				(type default)
			)
			(layer "F.SilkS")
		)
		(fp_line
			(start -4.53898 -2.150618)
			(end -4.539742 2.152142)
			(stroke
				(width 0.1524)
				(type default)
			)
			(layer "F.SilkS")
		)
		(fp_line
			(start -4.69138 -2.150618)
			(end -4.692396 2.161032)
			(stroke
				(width 0.1524)
				(type default)
			)
			(layer "F.SilkS")
		)
		(fp_line
			(start -4.83108 2.150364)
			(end -4.447794 2.149348)
			(stroke
				(width 0.1524)
				(type default)
			)
			(layer "F.SilkS")
		)
		(fp_line
			(start -4.84378 -2.150618)
			(end -4.53898 -2.150618)
			(stroke
				(width 0.1524)
				(type default)
			)
			(layer "F.SilkS")
		)
		(fp_line
			(start -4.84378 -2.150618)
			(end -4.842256 2.163064)
			(stroke
				(width 0.1524)
				(type default)
			)
			(layer "F.SilkS")
		)
		(fp_line
			(start 3.64998 2.15011)
			(end -3.64998 2.15011)
			(stroke
				(width 0.1)
				(type default)
			)
			(layer "F.Fab")
		)
		(fp_line
			(start 3.64998 -2.15011)
			(end 3.64998 2.15011)
			(stroke
				(width 0.1)
				(type default)
			)
			(layer "F.Fab")
		)
		(fp_line
			(start -3.64998 2.15011)
			(end -3.64998 -2.15011)
			(stroke
				(width 0.1)
				(type default)
			)
			(layer "F.Fab")
		)
		(fp_line
			(start -3.64998 -2.15011)
			(end 3.64998 -2.15011)
			(stroke
				(width 0.1)
				(type default)
			)
			(layer "F.Fab")
		)
		(fp_text user "-"
			(at 5.788914 -0.077216 180)
			(unlocked yes)
			(layer "F.SilkS")
			(effects
				(font
					(size 1.905 1.4224)
					(thickness 0.1524)
				)
				(justify left)
			)
		)
		(fp_text user "+"
			(at -4.894326 -3.203956 180)
			(unlocked yes)
			(layer "F.SilkS")
			(effects
				(font
					(size 1.905 1.4224)
					(thickness 0.1524)
				)
				(justify left)
			)
		)
		(fp_text user "-"
			(at 4.313174 -0.094488 180)
			(unlocked yes)
			(layer "F.Fab")
			(effects
				(font
					(size 1.905 1.4224)
					(thickness 0.1524)
				)
				(justify left)
			)
		)
		(fp_text user "+"
			(at -6.214872 -0.337058 180)
			(unlocked yes)
			(layer "F.Fab")
			(effects
				(font
					(size 1.905 1.4224)
					(thickness 0.1524)
				)
				(justify left)
			)
		)
		(pad "1" smd rect
			(at -3.199892 0 180)
			(size 2.413 2.8194)
			(layers "F.Cu" "F.Mask" "F.Paste")
			(net "P1V05_PCH_AUX")
		)
		(pad "2" smd rect
			(at 3.199892 0 180)
			(size 2.413 2.8194)
			(layers "F.Cu" "F.Mask" "F.Paste")
			(net "GND")
		)
	)
	(footprint ""
		(layer "F.Cu")
		(at 58.650124 -440.489848)
		(property "Reference" "J112"
			(at -7.9883 9.742932 0)
			(unlocked yes)
			(layer "F.SilkS")
			(effects
				(font
					(size 0.7874 0.5842)
					(thickness 0.1524)
				)
				(justify left)
			)
		)
		(property "Value" ""
			(at 0 0 0)
			(layer "F.Fab")
			(effects
				(font
					(size 1.27 1.27)
				)
			)
		)
		(duplicate_pad_numbers_are_jumpers no)
		(fp_line
			(start -4.249928 -11.999976)
			(end -4.249928 29.59989)
			(stroke
				(width 0.1524)
				(type default)
			)
			(layer "F.SilkS")
		)
		(fp_line
			(start -4.249928 29.59989)
			(end 18.64995 29.59989)
			(stroke
				(width 0.1524)
				(type default)
			)
			(layer "F.SilkS")
		)
		(fp_line
			(start -1.249934 -8.999982)
			(end 15.649956 -8.999982)
			(stroke
				(width 0.1524)
				(type default)
			)
			(layer "F.SilkS")
		)
		(fp_line
			(start -1.249934 -1.500124)
			(end 15.649956 -1.500124)
			(stroke
				(width 0.1524)
				(type default)
			)
			(layer "F.SilkS")
		)
		(fp_line
			(start -1.249934 26.599896)
			(end -1.249934 -8.999982)
			(stroke
				(width 0.1524)
				(type default)
			)
			(layer "F.SilkS")
		)
		(fp_line
			(start 0.2413 -0.9144)
			(end 1.2573 -0.9144)
			(stroke
				(width 0.1524)
				(type default)
			)
			(layer "F.SilkS")
		)
		(fp_line
			(start 0.7493 -1.4224)
			(end 0.2413 -0.9144)
			(stroke
				(width 0.1524)
				(type default)
			)
			(layer "F.SilkS")
		)
		(fp_line
			(start 0.7493 -1.4224)
			(end 0.7493 -0.5588)
			(stroke
				(width 0.1524)
				(type default)
			)
			(layer "F.SilkS")
		)
		(fp_line
			(start 0.7493 -0.5588)
			(end 2.0193 -0.5588)
			(stroke
				(width 0.1524)
				(type default)
			)
			(layer "F.SilkS")
		)
		(fp_line
			(start 1.2573 -0.9144)
			(end 0.7493 -1.4224)
			(stroke
				(width 0.1524)
				(type default)
			)
			(layer "F.SilkS")
		)
		(fp_line
			(start 2.0193 -0.5588)
			(end 2.2479 -0.7874)
			(stroke
				(width 0.1524)
				(type default)
			)
			(layer "F.SilkS")
		)
		(fp_line
			(start 15.649956 -8.999982)
			(end 15.649956 26.599896)
			(stroke
				(width 0.1524)
				(type default)
			)
			(layer "F.SilkS")
		)
		(fp_line
			(start 15.649956 26.599896)
			(end -1.249934 26.599896)
			(stroke
				(width 0.1524)
				(type default)
			)
			(layer "F.SilkS")
		)
		(fp_line
			(start 18.64995 -11.999976)
			(end -4.249928 -11.999976)
			(stroke
				(width 0.1524)
				(type default)
			)
			(layer "F.SilkS")
		)
		(fp_line
			(start 18.64995 -1.023112)
			(end 18.64995 -11.999976)
			(stroke
				(width 0.1524)
				(type default)
			)
			(layer "F.SilkS")
		)
		(fp_line
			(start 18.64995 29.59989)
			(end 18.64995 16.596868)
			(stroke
				(width 0.1524)
				(type default)
			)
			(layer "F.SilkS")
		)
		(fp_poly
			(pts
				(xy -2.792222 0.597662) (xy -2.792222 -0.597662) (xy -1.596898 0)
			)
			(stroke
				(width 0)
				(type default)
			)
			(fill yes)
			(layer "F.SilkS")
		)
		(fp_line
			(start -4.249928 -11.999976)
			(end -4.249928 4.06654)
			(stroke
				(width 0.1524)
				(type default)
			)
			(layer "B.SilkS")
		)
		(fp_line
			(start -4.249928 6.07568)
			(end -4.249928 21.57222)
			(stroke
				(width 0.1524)
				(type default)
			)
			(layer "B.SilkS")
		)
		(fp_line
			(start -4.249928 23.18766)
			(end -4.249928 26.83256)
			(stroke
				(width 0.1524)
				(type default)
			)
			(layer "B.SilkS")
		)
		(fp_line
			(start -4.249928 27.91968)
			(end -4.249928 29.59989)
			(stroke
				(width 0.1524)
				(type default)
			)
			(layer "B.SilkS")
		)
		(fp_line
			(start -4.249928 29.59989)
			(end 4.001516 29.59989)
			(stroke
				(width 0.1524)
				(type default)
			)
			(layer "B.SilkS")
		)
		(fp_line
			(start 5.606796 29.59989)
			(end 10.381996 29.59989)
			(stroke
				(width 0.1524)
				(type default)
			)
			(layer "B.SilkS")
		)
		(fp_line
			(start 12.083796 29.59989)
			(end 13.719556 29.59989)
			(stroke
				(width 0.1524)
				(type default)
			)
			(layer "B.SilkS")
		)
		(fp_line
			(start 14.829536 29.59989)
			(end 18.64995 29.59989)
			(stroke
				(width 0.1524)
				(type default)
			)
			(layer "B.SilkS")
		)
		(fp_line
			(start 18.64995 -11.999976)
			(end -4.249928 -11.999976)
			(stroke
				(width 0.1524)
				(type default)
			)
			(layer "B.SilkS")
		)
		(fp_line
			(start 18.64995 -1.000252)
			(end 18.64995 -11.999976)
			(stroke
				(width 0.1524)
				(type default)
			)
			(layer "B.SilkS")
		)
		(fp_line
			(start 18.64995 29.59989)
			(end 18.64995 17.838928)
			(stroke
				(width 0.1524)
				(type default)
			)
			(layer "B.SilkS")
		)
		(fp_line
			(start -4.249928 -11.999976)
			(end -4.249928 29.59989)
			(stroke
				(width 0.1)
				(type default)
			)
			(layer "B.Fab")
		)
		(fp_line
			(start -4.249928 29.59989)
			(end 18.64995 29.59989)
			(stroke
				(width 0.1)
				(type default)
			)
			(layer "B.Fab")
		)
		(fp_line
			(start 18.64995 -11.999976)
			(end -4.249928 -11.999976)
			(stroke
				(width 0.1)
				(type default)
			)
			(layer "B.Fab")
		)
		(fp_line
			(start 18.64995 29.59989)
			(end 18.64995 -11.999976)
			(stroke
				(width 0.1)
				(type default)
			)
			(layer "B.Fab")
		)
		(fp_line
			(start -1.249934 -8.999982)
			(end 15.649956 -8.999982)
			(stroke
				(width 0.1)
				(type default)
			)
			(layer "F.Fab")
		)
		(fp_line
			(start -1.249934 26.599896)
			(end -1.249934 -8.999982)
			(stroke
				(width 0.1)
				(type default)
			)
			(layer "F.Fab")
		)
		(fp_line
			(start 15.649956 -8.999982)
			(end 15.649956 26.599896)
			(stroke
				(width 0.1)
				(type default)
			)
			(layer "F.Fab")
		)
		(fp_line
			(start 15.649956 26.599896)
			(end -1.249934 26.599896)
			(stroke
				(width 0.1)
				(type default)
			)
			(layer "F.Fab")
		)
		(fp_poly
			(pts
				(xy -1.596898 0) (xy -2.792222 0.597662) (xy -2.792222 -0.597662)
			)
			(stroke
				(width 0)
				(type default)
			)
			(fill yes)
			(layer "F.Fab")
		)
		(fp_text user "B"
			(at -2.1844 1.205484 0)
			(unlocked yes)
			(layer "F.SilkS")
			(effects
				(font
					(size 0.7874 0.5842)
					(thickness 0.1524)
				)
			)
		)
		(fp_text user "C"
			(at -2.1844 2.40538 0)
			(unlocked yes)
			(layer "F.SilkS")
			(effects
				(font
					(size 0.7874 0.5842)
					(thickness 0.1524)
				)
			)
		)
		(fp_text user "D"
			(at -2.1844 3.60553 0)
			(unlocked yes)
			(layer "F.SilkS")
			(effects
				(font
					(size 0.7874 0.5842)
					(thickness 0.1524)
				)
			)
		)
		(fp_text user "E"
			(at -2.1844 4.805426 0)
			(unlocked yes)
			(layer "F.SilkS")
			(effects
				(font
					(size 0.7874 0.5842)
					(thickness 0.1524)
				)
			)
		)
		(fp_text user "F"
			(at -2.1844 6.005576 0)
			(unlocked yes)
			(layer "F.SilkS")
			(effects
				(font
					(size 0.7874 0.5842)
					(thickness 0.1524)
				)
			)
		)
		(fp_text user "G"
			(at -2.1844 7.205472 0)
			(unlocked yes)
			(layer "F.SilkS")
			(effects
				(font
					(size 0.7874 0.5842)
					(thickness 0.1524)
				)
			)
		)
		(fp_text user "H"
			(at -2.1844 8.405622 0)
			(unlocked yes)
			(layer "F.SilkS")
			(effects
				(font
					(size 0.7874 0.5842)
					(thickness 0.1524)
				)
			)
		)
		(fp_text user "I"
			(at -2.1844 9.605518 0)
			(unlocked yes)
			(layer "F.SilkS")
			(effects
				(font
					(size 0.7874 0.5842)
					(thickness 0.1524)
				)
			)
		)
		(fp_text user "J"
			(at -2.1844 10.805414 0)
			(unlocked yes)
			(layer "F.SilkS")
			(effects
				(font
					(size 0.7874 0.5842)
					(thickness 0.1524)
				)
			)
		)
		(fp_text user "K"
			(at -2.1844 12.005564 0)
			(unlocked yes)
			(layer "F.SilkS")
			(effects
				(font
					(size 0.7874 0.5842)
					(thickness 0.1524)
				)
			)
		)
		(fp_text user "L"
			(at -2.1844 13.20546 0)
			(unlocked yes)
			(layer "F.SilkS")
			(effects
				(font
					(size 0.7874 0.5842)
					(thickness 0.1524)
				)
			)
		)
		(fp_text user "M"
			(at -2.1844 14.40561 0)
			(unlocked yes)
			(layer "F.SilkS")
			(effects
				(font
					(size 0.7874 0.5842)
					(thickness 0.1524)
				)
			)
		)
		(fp_text user "N"
			(at -2.1844 15.605506 0)
			(unlocked yes)
			(layer "F.SilkS")
			(effects
				(font
					(size 0.7874 0.5842)
					(thickness 0.1524)
				)
			)
		)
		(fp_text user "O"
			(at -2.1844 16.805402 0)
			(unlocked yes)
			(layer "F.SilkS")
			(effects
				(font
					(size 0.7874 0.5842)
					(thickness 0.1524)
				)
			)
		)
		(fp_text user "P"
			(at -2.1844 18.005552 0)
			(unlocked yes)
			(layer "F.SilkS")
			(effects
				(font
					(size 0.7874 0.5842)
					(thickness 0.1524)
				)
			)
		)
		(fp_text user "Q"
			(at -2.1844 19.205448 0)
			(unlocked yes)
			(layer "F.SilkS")
			(effects
				(font
					(size 0.7874 0.5842)
					(thickness 0.1524)
				)
			)
		)
		(fp_text user "R"
			(at -2.1844 20.405598 0)
			(unlocked yes)
			(layer "F.SilkS")
			(effects
				(font
					(size 0.7874 0.5842)
					(thickness 0.1524)
				)
			)
		)
		(fp_text user "S"
			(at -2.1844 21.605494 0)
			(unlocked yes)
			(layer "F.SilkS")
			(effects
				(font
					(size 0.7874 0.5842)
					(thickness 0.1524)
				)
			)
		)
		(fp_text user "T"
			(at -2.1844 22.80539 0)
			(unlocked yes)
			(layer "F.SilkS")
			(effects
				(font
					(size 0.7874 0.5842)
					(thickness 0.1524)
				)
			)
		)
		(fp_text user "PRESS-FIT"
			(at -1.347724 25.34539 0)
			(unlocked yes)
			(layer "F.SilkS")
			(effects
				(font
					(size 1.905 1.4224)
					(thickness 0.1524)
				)
				(justify left)
			)
		)
		(fp_text user "1"
			(at 0 27.277568 0)
			(unlocked yes)
			(layer "F.SilkS")
			(effects
				(font
					(size 0.7874 0.5842)
					(thickness 0.1524)
				)
			)
		)
		(fp_text user "2"
			(at 1.999996 27.294586 0)
			(unlocked yes)
			(layer "F.SilkS")
			(effects
				(font
					(size 0.7874 0.5842)
					(thickness 0.1524)
				)
			)
		)
		(fp_text user "EDGE OF DAUGHTERCARD"
			(at 2.54 -0.886968 0)
			(unlocked yes)
			(layer "F.SilkS")
			(effects
				(font
					(size 0.635 0.4064)
					(thickness 0.1524)
				)
				(justify left)
			)
		)
		(fp_text user "3"
			(at 3.999992 27.277568 0)
			(unlocked yes)
			(layer "F.SilkS")
			(effects
				(font
					(size 0.7874 0.5842)
					(thickness 0.1524)
				)
			)
		)
		(fp_text user "4"
			(at 5.999988 27.294586 0)
			(unlocked yes)
			(layer "F.SilkS")
			(effects
				(font
					(size 0.7874 0.5842)
					(thickness 0.1524)
				)
			)
		)
		(fp_text user "5"
			(at 7.999984 27.277568 0)
			(unlocked yes)
			(layer "F.SilkS")
			(effects
				(font
					(size 0.7874 0.5842)
					(thickness 0.1524)
				)
			)
		)
		(fp_text user "6"
			(at 9.99998 27.294586 0)
			(unlocked yes)
			(layer "F.SilkS")
			(effects
				(font
					(size 0.7874 0.5842)
					(thickness 0.1524)
				)
			)
		)
		(fp_text user "7"
			(at 11.999976 27.277568 0)
			(unlocked yes)
			(layer "F.SilkS")
			(effects
				(font
					(size 0.7874 0.5842)
					(thickness 0.1524)
				)
			)
		)
		(fp_text user "8"
			(at 13.999972 27.294586 0)
			(unlocked yes)
			(layer "F.SilkS")
			(effects
				(font
					(size 0.7874 0.5842)
					(thickness 0.1524)
				)
			)
		)
		(fp_text user "Q"
			(at -1.1557 19.094704 0)
			(unlocked yes)
			(layer "B.SilkS")
			(effects
				(font
					(size 0.7874 0.5842)
					(thickness 0.1524)
				)
				(justify mirror)
			)
		)
		(fp_text user "R"
			(at -1.1557 20.2946 0)
			(unlocked yes)
			(layer "B.SilkS")
			(effects
				(font
					(size 0.7874 0.5842)
					(thickness 0.1524)
				)
				(justify mirror)
			)
		)
		(fp_text user "A"
			(at -1.13538 0.04953 0)
			(unlocked yes)
			(layer "B.SilkS")
			(effects
				(font
					(size 0.7874 0.5842)
					(thickness 0.1524)
				)
				(justify mirror)
			)
		)
		(fp_text user "B"
			(at -1.13538 1.24968 0)
			(unlocked yes)
			(layer "B.SilkS")
			(effects
				(font
					(size 0.7874 0.5842)
					(thickness 0.1524)
				)
				(justify mirror)
			)
		)
		(fp_text user "C"
			(at -1.13538 2.449576 0)
			(unlocked yes)
			(layer "B.SilkS")
			(effects
				(font
					(size 0.7874 0.5842)
					(thickness 0.1524)
				)
				(justify mirror)
			)
		)
		(fp_text user "D"
			(at -1.13538 3.649726 0)
			(unlocked yes)
			(layer "B.SilkS")
			(effects
				(font
					(size 0.7874 0.5842)
					(thickness 0.1524)
				)
				(justify mirror)
			)
		)
		(fp_text user "E"
			(at -1.13538 4.849622 0)
			(unlocked yes)
			(layer "B.SilkS")
			(effects
				(font
					(size 0.7874 0.5842)
					(thickness 0.1524)
				)
				(justify mirror)
			)
		)
		(fp_text user "F"
			(at -1.13538 6.049518 0)
			(unlocked yes)
			(layer "B.SilkS")
			(effects
				(font
					(size 0.7874 0.5842)
					(thickness 0.1524)
				)
				(justify mirror)
			)
		)
		(fp_text user "G"
			(at -1.13538 7.249668 0)
			(unlocked yes)
			(layer "B.SilkS")
			(effects
				(font
					(size 0.7874 0.5842)
					(thickness 0.1524)
				)
				(justify mirror)
			)
		)
		(fp_text user "H"
			(at -1.13538 8.449564 0)
			(unlocked yes)
			(layer "B.SilkS")
			(effects
				(font
					(size 0.7874 0.5842)
					(thickness 0.1524)
				)
				(justify mirror)
			)
		)
		(fp_text user "I"
			(at -1.13538 9.649714 0)
			(unlocked yes)
			(layer "B.SilkS")
			(effects
				(font
					(size 0.7874 0.5842)
					(thickness 0.1524)
				)
				(justify mirror)
			)
		)
		(fp_text user "J"
			(at -1.13538 10.84961 0)
			(unlocked yes)
			(layer "B.SilkS")
			(effects
				(font
					(size 0.7874 0.5842)
					(thickness 0.1524)
				)
				(justify mirror)
			)
		)
		(fp_text user "K"
			(at -1.13538 12.049506 0)
			(unlocked yes)
			(layer "B.SilkS")
			(effects
				(font
					(size 0.7874 0.5842)
					(thickness 0.1524)
				)
				(justify mirror)
			)
		)
		(fp_text user "L"
			(at -1.13538 13.249656 0)
			(unlocked yes)
			(layer "B.SilkS")
			(effects
				(font
					(size 0.7874 0.5842)
					(thickness 0.1524)
				)
				(justify mirror)
			)
		)
		(fp_text user "M"
			(at -1.13538 14.449552 0)
			(unlocked yes)
			(layer "B.SilkS")
			(effects
				(font
					(size 0.7874 0.5842)
					(thickness 0.1524)
				)
				(justify mirror)
			)
		)
		(fp_text user "N"
			(at -1.13538 15.649702 0)
			(unlocked yes)
			(layer "B.SilkS")
			(effects
				(font
					(size 0.7874 0.5842)
					(thickness 0.1524)
				)
				(justify mirror)
			)
		)
		(fp_text user "O"
			(at -1.13538 16.849598 0)
			(unlocked yes)
			(layer "B.SilkS")
			(effects
				(font
					(size 0.7874 0.5842)
					(thickness 0.1524)
				)
				(justify mirror)
			)
		)
		(fp_text user "P"
			(at -1.13538 18.049494 0)
			(unlocked yes)
			(layer "B.SilkS")
			(effects
				(font
					(size 0.7874 0.5842)
					(thickness 0.1524)
				)
				(justify mirror)
			)
		)
		(fp_text user "S"
			(at -1.12522 22.05355 0)
			(unlocked yes)
			(layer "B.SilkS")
			(effects
				(font
					(size 0.7874 0.5842)
					(thickness 0.1524)
				)
				(justify mirror)
			)
		)
		(fp_text user "T"
			(at -1.12522 23.253446 0)
			(unlocked yes)
			(layer "B.SilkS")
			(effects
				(font
					(size 0.7874 0.5842)
					(thickness 0.1524)
				)
				(justify mirror)
			)
		)
		(fp_text user "1"
			(at 0.0254 24.127968 0)
			(unlocked yes)
			(layer "B.SilkS")
			(effects
				(font
					(size 0.7874 0.5842)
					(thickness 0.1524)
				)
				(justify mirror)
			)
		)
		(fp_text user "2"
			(at 2.025396 24.144986 0)
			(unlocked yes)
			(layer "B.SilkS")
			(effects
				(font
					(size 0.7874 0.5842)
					(thickness 0.1524)
				)
				(justify mirror)
			)
		)
		(fp_text user "3"
			(at 4.025392 24.127968 0)
			(unlocked yes)
			(layer "B.SilkS")
			(effects
				(font
					(size 0.7874 0.5842)
					(thickness 0.1524)
				)
				(justify mirror)
			)
		)
		(fp_text user "4"
			(at 6.025388 24.144986 0)
			(unlocked yes)
			(layer "B.SilkS")
			(effects
				(font
					(size 0.7874 0.5842)
					(thickness 0.1524)
				)
				(justify mirror)
			)
		)
		(fp_text user "5"
			(at 8.025384 24.127968 0)
			(unlocked yes)
			(layer "B.SilkS")
			(effects
				(font
					(size 0.7874 0.5842)
					(thickness 0.1524)
				)
				(justify mirror)
			)
		)
		(fp_text user "6"
			(at 10.02538 24.144986 0)
			(unlocked yes)
			(layer "B.SilkS")
			(effects
				(font
					(size 0.7874 0.5842)
					(thickness 0.1524)
				)
				(justify mirror)
			)
		)
		(fp_text user "7"
			(at 12.025376 24.127968 0)
			(unlocked yes)
			(layer "B.SilkS")
			(effects
				(font
					(size 0.7874 0.5842)
					(thickness 0.1524)
				)
				(justify mirror)
			)
		)
		(fp_text user "8"
			(at 14.025372 24.144986 0)
			(unlocked yes)
			(layer "B.SilkS")
			(effects
				(font
					(size 0.7874 0.5842)
					(thickness 0.1524)
				)
				(justify mirror)
			)
		)
		(fp_text user "PRESS-FIT"
			(at 35.576256 26.73985 0)
			(unlocked yes)
			(layer "B.SilkS")
			(effects
				(font
					(size 1.905 1.4224)
					(thickness 0.1524)
				)
				(justify left mirror)
			)
		)
		(fp_text user "A"
			(at -1.13538 0.04953 0)
			(unlocked yes)
			(layer "B.Fab")
			(effects
				(font
					(size 0.7874 0.5842)
					(thickness 0.1524)
				)
				(justify mirror)
			)
		)
		(fp_text user "B"
			(at -1.13538 1.24968 0)
			(unlocked yes)
			(layer "B.Fab")
			(effects
				(font
					(size 0.7874 0.5842)
					(thickness 0.1524)
				)
				(justify mirror)
			)
		)
		(fp_text user "C"
			(at -1.13538 2.449576 0)
			(unlocked yes)
			(layer "B.Fab")
			(effects
				(font
					(size 0.7874 0.5842)
					(thickness 0.1524)
				)
				(justify mirror)
			)
		)
		(fp_text user "D"
			(at -1.13538 3.649726 0)
			(unlocked yes)
			(layer "B.Fab")
			(effects
				(font
					(size 0.7874 0.5842)
					(thickness 0.1524)
				)
				(justify mirror)
			)
		)
		(fp_text user "E"
			(at -1.13538 4.849622 0)
			(unlocked yes)
			(layer "B.Fab")
			(effects
				(font
					(size 0.7874 0.5842)
					(thickness 0.1524)
				)
				(justify mirror)
			)
		)
		(fp_text user "F"
			(at -1.13538 6.049518 0)
			(unlocked yes)
			(layer "B.Fab")
			(effects
				(font
					(size 0.7874 0.5842)
					(thickness 0.1524)
				)
				(justify mirror)
			)
		)
		(fp_text user "G"
			(at -1.13538 7.249668 0)
			(unlocked yes)
			(layer "B.Fab")
			(effects
				(font
					(size 0.7874 0.5842)
					(thickness 0.1524)
				)
				(justify mirror)
			)
		)
		(fp_text user "H"
			(at -1.13538 8.449564 0)
			(unlocked yes)
			(layer "B.Fab")
			(effects
				(font
					(size 0.7874 0.5842)
					(thickness 0.1524)
				)
				(justify mirror)
			)
		)
		(fp_text user "I"
			(at -1.13538 9.649714 0)
			(unlocked yes)
			(layer "B.Fab")
			(effects
				(font
					(size 0.7874 0.5842)
					(thickness 0.1524)
				)
				(justify mirror)
			)
		)
		(fp_text user "J"
			(at -1.13538 10.84961 0)
			(unlocked yes)
			(layer "B.Fab")
			(effects
				(font
					(size 0.7874 0.5842)
					(thickness 0.1524)
				)
				(justify mirror)
			)
		)
		(fp_text user "K"
			(at -1.13538 12.049506 0)
			(unlocked yes)
			(layer "B.Fab")
			(effects
				(font
					(size 0.7874 0.5842)
					(thickness 0.1524)
				)
				(justify mirror)
			)
		)
		(fp_text user "L"
			(at -1.13538 13.249656 0)
			(unlocked yes)
			(layer "B.Fab")
			(effects
				(font
					(size 0.7874 0.5842)
					(thickness 0.1524)
				)
				(justify mirror)
			)
		)
		(fp_text user "M"
			(at -1.13538 14.449552 0)
			(unlocked yes)
			(layer "B.Fab")
			(effects
				(font
					(size 0.7874 0.5842)
					(thickness 0.1524)
				)
				(justify mirror)
			)
		)
		(fp_text user "N"
			(at -1.13538 15.649702 0)
			(unlocked yes)
			(layer "B.Fab")
			(effects
				(font
					(size 0.7874 0.5842)
					(thickness 0.1524)
				)
				(justify mirror)
			)
		)
		(fp_text user "O"
			(at -1.13538 16.849598 0)
			(unlocked yes)
			(layer "B.Fab")
			(effects
				(font
					(size 0.7874 0.5842)
					(thickness 0.1524)
				)
				(justify mirror)
			)
		)
		(fp_text user "P"
			(at -1.13538 18.049494 0)
			(unlocked yes)
			(layer "B.Fab")
			(effects
				(font
					(size 0.7874 0.5842)
					(thickness 0.1524)
				)
				(justify mirror)
			)
		)
		(fp_text user "Q"
			(at -1.13538 19.249644 0)
			(unlocked yes)
			(layer "B.Fab")
			(effects
				(font
					(size 0.7874 0.5842)
					(thickness 0.1524)
				)
				(justify mirror)
			)
		)
		(fp_text user "R"
			(at -1.13538 20.44954 0)
			(unlocked yes)
			(layer "B.Fab")
			(effects
				(font
					(size 0.7874 0.5842)
					(thickness 0.1524)
				)
				(justify mirror)
			)
		)
		(fp_text user "S"
			(at -1.13538 21.64969 0)
			(unlocked yes)
			(layer "B.Fab")
			(effects
				(font
					(size 0.7874 0.5842)
					(thickness 0.1524)
				)
				(justify mirror)
			)
		)
		(fp_text user "T"
			(at -1.13538 22.849586 0)
			(unlocked yes)
			(layer "B.Fab")
			(effects
				(font
					(size 0.7874 0.5842)
					(thickness 0.1524)
				)
				(justify mirror)
			)
		)
		(fp_text user "1"
			(at 0.0254 24.127968 0)
			(unlocked yes)
			(layer "B.Fab")
			(effects
				(font
					(size 0.7874 0.5842)
					(thickness 0.1524)
				)
				(justify mirror)
			)
		)
		(fp_text user "2"
			(at 2.025396 24.144986 0)
			(unlocked yes)
			(layer "B.Fab")
			(effects
				(font
					(size 0.7874 0.5842)
					(thickness 0.1524)
				)
				(justify mirror)
			)
		)
		(fp_text user "3"
			(at 4.025392 24.127968 0)
			(unlocked yes)
			(layer "B.Fab")
			(effects
				(font
					(size 0.7874 0.5842)
					(thickness 0.1524)
				)
				(justify mirror)
			)
		)
		(fp_text user "4"
			(at 6.025388 24.144986 0)
			(unlocked yes)
			(layer "B.Fab")
			(effects
				(font
					(size 0.7874 0.5842)
					(thickness 0.1524)
				)
				(justify mirror)
			)
		)
		(fp_text user "5"
			(at 8.025384 24.127968 0)
			(unlocked yes)
			(layer "B.Fab")
			(effects
				(font
					(size 0.7874 0.5842)
					(thickness 0.1524)
				)
				(justify mirror)
			)
		)
		(fp_text user "6"
			(at 10.02538 24.144986 0)
			(unlocked yes)
			(layer "B.Fab")
			(effects
				(font
					(size 0.7874 0.5842)
					(thickness 0.1524)
				)
				(justify mirror)
			)
		)
		(fp_text user "7"
			(at 12.025376 24.127968 0)
			(unlocked yes)
			(layer "B.Fab")
			(effects
				(font
					(size 0.7874 0.5842)
					(thickness 0.1524)
				)
				(justify mirror)
			)
		)
		(fp_text user "8"
			(at 14.025372 24.144986 0)
			(unlocked yes)
			(layer "B.Fab")
			(effects
				(font
					(size 0.7874 0.5842)
					(thickness 0.1524)
				)
				(justify mirror)
			)
		)
		(fp_text user "PRESS-FIT"
			(at 17.292828 3.961384 90)
			(unlocked yes)
			(layer "B.Fab")
			(effects
				(font
					(size 1.905 1.4224)
					(thickness 0.1524)
				)
				(justify left mirror)
			)
		)
		(fp_text user "B"
			(at -2.1844 1.205484 0)
			(unlocked yes)
			(layer "F.Fab")
			(effects
				(font
					(size 0.7874 0.5842)
					(thickness 0.1524)
				)
			)
		)
		(fp_text user "C"
			(at -2.1844 2.40538 0)
			(unlocked yes)
			(layer "F.Fab")
			(effects
				(font
					(size 0.7874 0.5842)
					(thickness 0.1524)
				)
			)
		)
		(fp_text user "D"
			(at -2.1844 3.60553 0)
			(unlocked yes)
			(layer "F.Fab")
			(effects
				(font
					(size 0.7874 0.5842)
					(thickness 0.1524)
				)
			)
		)
		(fp_text user "E"
			(at -2.1844 4.805426 0)
			(unlocked yes)
			(layer "F.Fab")
			(effects
				(font
					(size 0.7874 0.5842)
					(thickness 0.1524)
				)
			)
		)
		(fp_text user "F"
			(at -2.1844 6.005576 0)
			(unlocked yes)
			(layer "F.Fab")
			(effects
				(font
					(size 0.7874 0.5842)
					(thickness 0.1524)
				)
			)
		)
		(fp_text user "G"
			(at -2.1844 7.205472 0)
			(unlocked yes)
			(layer "F.Fab")
			(effects
				(font
					(size 0.7874 0.5842)
					(thickness 0.1524)
				)
			)
		)
		(fp_text user "H"
			(at -2.1844 8.405622 0)
			(unlocked yes)
			(layer "F.Fab")
			(effects
				(font
					(size 0.7874 0.5842)
					(thickness 0.1524)
				)
			)
		)
		(fp_text user "I"
			(at -2.1844 9.605518 0)
			(unlocked yes)
			(layer "F.Fab")
			(effects
				(font
					(size 0.7874 0.5842)
					(thickness 0.1524)
				)
			)
		)
		(fp_text user "J"
			(at -2.1844 10.805414 0)
			(unlocked yes)
			(layer "F.Fab")
			(effects
				(font
					(size 0.7874 0.5842)
					(thickness 0.1524)
				)
			)
		)
		(fp_text user "K"
			(at -2.1844 12.005564 0)
			(unlocked yes)
			(layer "F.Fab")
			(effects
				(font
					(size 0.7874 0.5842)
					(thickness 0.1524)
				)
			)
		)
		(fp_text user "L"
			(at -2.1844 13.20546 0)
			(unlocked yes)
			(layer "F.Fab")
			(effects
				(font
					(size 0.7874 0.5842)
					(thickness 0.1524)
				)
			)
		)
		(fp_text user "M"
			(at -2.1844 14.40561 0)
			(unlocked yes)
			(layer "F.Fab")
			(effects
				(font
					(size 0.7874 0.5842)
					(thickness 0.1524)
				)
			)
		)
		(fp_text user "N"
			(at -2.1844 15.605506 0)
			(unlocked yes)
			(layer "F.Fab")
			(effects
				(font
					(size 0.7874 0.5842)
					(thickness 0.1524)
				)
			)
		)
		(fp_text user "O"
			(at -2.1844 16.805402 0)
			(unlocked yes)
			(layer "F.Fab")
			(effects
				(font
					(size 0.7874 0.5842)
					(thickness 0.1524)
				)
			)
		)
		(fp_text user "P"
			(at -2.1844 18.005552 0)
			(unlocked yes)
			(layer "F.Fab")
			(effects
				(font
					(size 0.7874 0.5842)
					(thickness 0.1524)
				)
			)
		)
		(fp_text user "Q"
			(at -2.1844 19.205448 0)
			(unlocked yes)
			(layer "F.Fab")
			(effects
				(font
					(size 0.7874 0.5842)
					(thickness 0.1524)
				)
			)
		)
		(fp_text user "R"
			(at -2.1844 20.405598 0)
			(unlocked yes)
			(layer "F.Fab")
			(effects
				(font
					(size 0.7874 0.5842)
					(thickness 0.1524)
				)
			)
		)
		(fp_text user "S"
			(at -2.1844 21.605494 0)
			(unlocked yes)
			(layer "F.Fab")
			(effects
				(font
					(size 0.7874 0.5842)
					(thickness 0.1524)
				)
			)
		)
		(fp_text user "T"
			(at -2.1844 22.80539 0)
			(unlocked yes)
			(layer "F.Fab")
			(effects
				(font
					(size 0.7874 0.5842)
					(thickness 0.1524)
				)
			)
		)
		(fp_text user "1"
			(at 0 27.277568 0)
			(unlocked yes)
			(layer "F.Fab")
			(effects
				(font
					(size 0.7874 0.5842)
					(thickness 0.1524)
				)
			)
		)
		(fp_text user "2"
			(at 1.999996 27.294586 0)
			(unlocked yes)
			(layer "F.Fab")
			(effects
				(font
					(size 0.7874 0.5842)
					(thickness 0.1524)
				)
			)
		)
		(fp_text user "3"
			(at 3.999992 27.277568 0)
			(unlocked yes)
			(layer "F.Fab")
			(effects
				(font
					(size 0.7874 0.5842)
					(thickness 0.1524)
				)
			)
		)
		(fp_text user "4"
			(at 5.999988 27.294586 0)
			(unlocked yes)
			(layer "F.Fab")
			(effects
				(font
					(size 0.7874 0.5842)
					(thickness 0.1524)
				)
			)
		)
		(fp_text user "5"
			(at 7.999984 27.277568 0)
			(unlocked yes)
			(layer "F.Fab")
			(effects
				(font
					(size 0.7874 0.5842)
					(thickness 0.1524)
				)
			)
		)
		(fp_text user "6"
			(at 9.99998 27.294586 0)
			(unlocked yes)
			(layer "F.Fab")
			(effects
				(font
					(size 0.7874 0.5842)
					(thickness 0.1524)
				)
			)
		)
		(fp_text user "7"
			(at 11.999976 27.277568 0)
			(unlocked yes)
			(layer "F.Fab")
			(effects
				(font
					(size 0.7874 0.5842)
					(thickness 0.1524)
				)
			)
		)
		(fp_text user "8"
			(at 13.999972 27.294586 0)
			(unlocked yes)
			(layer "F.Fab")
			(effects
				(font
					(size 0.7874 0.5842)
					(thickness 0.1524)
				)
			)
		)
		(fp_text user "PRESS-FIT"
			(at 17.229328 20.636484 90)
			(unlocked yes)
			(layer "F.Fab")
			(effects
				(font
					(size 1.905 1.4224)
					(thickness 0.1524)
				)
				(justify left)
			)
		)
		(pad "A1" thru_hole rect
			(at 0 0 180)
			(size 0.766318 0.766318)
			(drill 0.359918)
			(layers "*.Cu" "*.Mask")
			(remove_unused_layers no)
			(net "RST_PERST_2_SWB_BUF_N")
			(clearance 0.0508)
			(thermal_gap 0.0508)
			(padstack
				(mode front_inner_back)
				(layer "Inner"
					(shape circle)
					(size 0.766318 0.766318)
					(clearance 0.0508)
				)
				(layer "B.Cu"
					(shape rect)
					(size 0.766318 0.766318)
					(clearance 0.0508)
				)
			)
		)
		(pad "A2" thru_hole circle
			(at 1.999996 0.199898 180)
			(size 0.906272 0.906272)
			(drill 0.499872)
			(layers "*.Cu" "*.Mask")
			(remove_unused_layers no)
			(net "GND")
			(clearance 0.0508)
			(thermal_gap 0.0508)
		)
		(pad "A3" thru_hole circle
			(at 3.999992 0 180)
			(size 0.766318 0.766318)
			(drill 0.359918)
			(layers "*.Cu" "*.Mask")
			(remove_unused_layers no)
			(net "HGX_DETECT_N_ISO")
			(clearance 0.0508)
			(thermal_gap 0.0508)
		)
		(pad "A4" thru_hole circle
			(at 5.999988 0.199898 180)
			(size 0.906272 0.906272)
			(drill 0.499872)
			(layers "*.Cu" "*.Mask")
			(remove_unused_layers no)
			(net "GND")
			(clearance 0.0508)
			(thermal_gap 0.0508)
		)
		(pad "A5" thru_hole circle
			(at 7.999984 0 180)
			(size 0.766318 0.766318)
			(drill 0.359918)
			(layers "*.Cu" "*.Mask")
			(remove_unused_layers no)
			(net "RST_PERST_1_SWB_BUF_N")
			(clearance 0.0508)
			(thermal_gap 0.0508)
		)
		(pad "A6" thru_hole circle
			(at 9.99998 0.199898 180)
			(size 0.906272 0.906272)
			(drill 0.499872)
			(layers "*.Cu" "*.Mask")
			(remove_unused_layers no)
			(net "GND")
			(clearance 0.0508)
			(thermal_gap 0.0508)
		)
		(pad "A7" thru_hole circle
			(at 11.999976 0 180)
			(size 0.766318 0.766318)
			(drill 0.359918)
			(layers "*.Cu" "*.Mask")
			(remove_unused_layers no)
			(net "PRSNT_SWB_N")
			(clearance 0.0508)
			(thermal_gap 0.0508)
		)
		(pad "A8" thru_hole circle
			(at 13.999972 0.199898 180)
			(size 0.906272 0.906272)
			(drill 0.499872)
			(layers "*.Cu" "*.Mask")
			(remove_unused_layers no)
			(net "GND")
			(clearance 0.0508)
			(thermal_gap 0.0508)
		)
		(pad "B1" thru_hole circle
			(at 0 1.199896 180)
			(size 0.906272 0.906272)
			(drill 0.499872)
			(layers "*.Cu" "*.Mask")
			(remove_unused_layers no)
			(net "GND")
			(clearance 0.0508)
			(thermal_gap 0.0508)
		)
		(pad "B3" thru_hole circle
			(at 3.999992 1.199896 180)
			(size 0.906272 0.906272)
			(drill 0.499872)
			(layers "*.Cu" "*.Mask")
			(remove_unused_layers no)
			(net "GND")
			(clearance 0.0508)
			(thermal_gap 0.0508)
		)
		(pad "B5" thru_hole circle
			(at 7.999984 1.199896 180)
			(size 0.906272 0.906272)
			(drill 0.499872)
			(layers "*.Cu" "*.Mask")
			(remove_unused_layers no)
			(net "GND")
			(clearance 0.0508)
			(thermal_gap 0.0508)
		)
		(pad "B7" thru_hole circle
			(at 11.999976 1.199896 180)
			(size 0.906272 0.906272)
			(drill 0.499872)
			(layers "*.Cu" "*.Mask")
			(remove_unused_layers no)
			(net "GND")
			(clearance 0.0508)
			(thermal_gap 0.0508)
		)
		(pad "D2" thru_hole circle
			(at 1.999996 3.800094 180)
			(size 0.906272 0.906272)
			(drill 0.499872)
			(layers "*.Cu" "*.Mask")
			(remove_unused_layers no)
			(net "GND")
			(clearance 0.0508)
			(thermal_gap 0.0508)
		)
		(pad "D4" thru_hole circle
			(at 5.999988 3.800094 180)
			(size 0.906272 0.906272)
			(drill 0.499872)
			(layers "*.Cu" "*.Mask")
			(remove_unused_layers no)
			(net "GND")
			(clearance 0.0508)
			(thermal_gap 0.0508)
		)
		(pad "D6" thru_hole circle
			(at 9.99998 3.800094 180)
			(size 0.906272 0.906272)
			(drill 0.499872)
			(layers "*.Cu" "*.Mask")
			(remove_unused_layers no)
			(net "GND")
			(clearance 0.0508)
			(thermal_gap 0.0508)
		)
		(pad "D8" thru_hole circle
			(at 13.999972 3.800094 180)
			(size 0.906272 0.906272)
			(drill 0.499872)
			(layers "*.Cu" "*.Mask")
			(remove_unused_layers no)
			(net "GND")
			(clearance 0.0508)
			(thermal_gap 0.0508)
		)
		(pad "E1" thru_hole circle
			(at 0 4.800092 180)
			(size 0.906272 0.906272)
			(drill 0.499872)
			(layers "*.Cu" "*.Mask")
			(remove_unused_layers no)
			(net "GND")
			(clearance 0.0508)
			(thermal_gap 0.0508)
		)
		(pad "E3" thru_hole circle
			(at 3.999992 4.800092 180)
			(size 0.906272 0.906272)
			(drill 0.499872)
			(layers "*.Cu" "*.Mask")
			(remove_unused_layers no)
			(net "GND")
			(clearance 0.0508)
			(thermal_gap 0.0508)
		)
		(pad "E5" thru_hole circle
			(at 7.999984 4.800092 180)
			(size 0.906272 0.906272)
			(drill 0.499872)
			(layers "*.Cu" "*.Mask")
			(remove_unused_layers no)
			(net "GND")
			(clearance 0.0508)
			(thermal_gap 0.0508)
		)
		(pad "E7" thru_hole circle
			(at 11.999976 4.800092 180)
			(size 0.906272 0.906272)
			(drill 0.499872)
			(layers "*.Cu" "*.Mask")
			(remove_unused_layers no)
			(net "GND")
			(clearance 0.0508)
			(thermal_gap 0.0508)
		)
		(pad "G2" thru_hole circle
			(at 1.999996 7.400036 180)
			(size 0.906272 0.906272)
			(drill 0.499872)
			(layers "*.Cu" "*.Mask")
			(remove_unused_layers no)
			(net "GND")
			(clearance 0.0508)
			(thermal_gap 0.0508)
		)
		(pad "G4" thru_hole circle
			(at 5.999988 7.400036 180)
			(size 0.906272 0.906272)
			(drill 0.499872)
			(layers "*.Cu" "*.Mask")
			(remove_unused_layers no)
			(net "GND")
			(clearance 0.0508)
			(thermal_gap 0.0508)
		)
		(pad "G6" thru_hole circle
			(at 9.99998 7.400036 180)
			(size 0.906272 0.906272)
			(drill 0.499872)
			(layers "*.Cu" "*.Mask")
			(remove_unused_layers no)
			(net "GND")
			(clearance 0.0508)
			(thermal_gap 0.0508)
		)
		(pad "G8" thru_hole circle
			(at 13.999972 7.400036 180)
			(size 0.906272 0.906272)
			(drill 0.499872)
			(layers "*.Cu" "*.Mask")
			(remove_unused_layers no)
			(net "GND")
			(clearance 0.0508)
			(thermal_gap 0.0508)
		)
		(pad "H1" thru_hole circle
			(at 0 8.400034 180)
			(size 0.906272 0.906272)
			(drill 0.499872)
			(layers "*.Cu" "*.Mask")
			(remove_unused_layers no)
			(net "GND")
			(clearance 0.0508)
			(thermal_gap 0.0508)
		)
		(pad "H3" thru_hole circle
			(at 3.999992 8.400034 180)
			(size 0.906272 0.906272)
			(drill 0.499872)
			(layers "*.Cu" "*.Mask")
			(remove_unused_layers no)
			(net "GND")
			(clearance 0.0508)
			(thermal_gap 0.0508)
		)
		(pad "H5" thru_hole circle
			(at 7.999984 8.400034 180)
			(size 0.906272 0.906272)
			(drill 0.499872)
			(layers "*.Cu" "*.Mask")
			(remove_unused_layers no)
			(net "GND")
			(clearance 0.0508)
			(thermal_gap 0.0508)
		)
		(pad "H7" thru_hole circle
			(at 11.999976 8.400034 180)
			(size 0.906272 0.906272)
			(drill 0.499872)
			(layers "*.Cu" "*.Mask")
			(remove_unused_layers no)
			(net "GND")
			(clearance 0.0508)
			(thermal_gap 0.0508)
		)
		(pad "J2" thru_hole circle
			(at 1.999996 10.999978 180)
			(size 0.906272 0.906272)
			(drill 0.499872)
			(layers "*.Cu" "*.Mask")
			(remove_unused_layers no)
			(net "GND")
			(clearance 0.0508)
			(thermal_gap 0.0508)
		)
		(pad "J4" thru_hole circle
			(at 5.999988 10.999978 180)
			(size 0.906272 0.906272)
			(drill 0.499872)
			(layers "*.Cu" "*.Mask")
			(remove_unused_layers no)
			(net "GND")
			(clearance 0.0508)
			(thermal_gap 0.0508)
		)
		(pad "J6" thru_hole circle
			(at 9.99998 10.999978 180)
			(size 0.906272 0.906272)
			(drill 0.499872)
			(layers "*.Cu" "*.Mask")
			(remove_unused_layers no)
			(net "GND")
			(clearance 0.0508)
			(thermal_gap 0.0508)
		)
		(pad "J8" thru_hole circle
			(at 13.999972 10.999978 180)
			(size 0.906272 0.906272)
			(drill 0.499872)
			(layers "*.Cu" "*.Mask")
			(remove_unused_layers no)
			(net "GND")
			(clearance 0.0508)
			(thermal_gap 0.0508)
		)
		(pad "K1" thru_hole circle
			(at 0 11.999976 180)
			(size 0.906272 0.906272)
			(drill 0.499872)
			(layers "*.Cu" "*.Mask")
			(remove_unused_layers no)
			(net "GND")
			(clearance 0.0508)
			(thermal_gap 0.0508)
		)
		(pad "K3" thru_hole circle
			(at 3.999992 11.999976 180)
			(size 0.906272 0.906272)
			(drill 0.499872)
			(layers "*.Cu" "*.Mask")
			(remove_unused_layers no)
			(net "GND")
			(clearance 0.0508)
			(thermal_gap 0.0508)
		)
		(pad "K5" thru_hole circle
			(at 7.999984 11.999976 180)
			(size 0.906272 0.906272)
			(drill 0.499872)
			(layers "*.Cu" "*.Mask")
			(remove_unused_layers no)
			(net "GND")
			(clearance 0.0508)
			(thermal_gap 0.0508)
		)
		(pad "K7" thru_hole circle
			(at 11.999976 11.999976 180)
			(size 0.906272 0.906272)
			(drill 0.499872)
			(layers "*.Cu" "*.Mask")
			(remove_unused_layers no)
			(net "GND")
			(clearance 0.0508)
			(thermal_gap 0.0508)
		)
		(pad "M2" thru_hole circle
			(at 1.999996 14.59992 180)
			(size 0.906272 0.906272)
			(drill 0.499872)
			(layers "*.Cu" "*.Mask")
			(remove_unused_layers no)
			(net "GND")
			(clearance 0.0508)
			(thermal_gap 0.0508)
		)
		(pad "M4" thru_hole circle
			(at 5.999988 14.59992 180)
			(size 0.906272 0.906272)
			(drill 0.499872)
			(layers "*.Cu" "*.Mask")
			(remove_unused_layers no)
			(net "GND")
			(clearance 0.0508)
			(thermal_gap 0.0508)
		)
		(pad "M6" thru_hole circle
			(at 9.99998 14.59992 180)
			(size 0.906272 0.906272)
			(drill 0.499872)
			(layers "*.Cu" "*.Mask")
			(remove_unused_layers no)
			(net "GND")
			(clearance 0.0508)
			(thermal_gap 0.0508)
		)
		(pad "M8" thru_hole circle
			(at 13.999972 14.59992 180)
			(size 0.906272 0.906272)
			(drill 0.499872)
			(layers "*.Cu" "*.Mask")
			(remove_unused_layers no)
			(net "GND")
			(clearance 0.0508)
			(thermal_gap 0.0508)
		)
		(pad "N1" thru_hole circle
			(at 0 15.599918 180)
			(size 0.906272 0.906272)
			(drill 0.499872)
			(layers "*.Cu" "*.Mask")
			(remove_unused_layers no)
			(net "GND")
			(clearance 0.0508)
			(thermal_gap 0.0508)
		)
		(pad "N2" thru_hole circle
			(at 1.999996 15.80007 180)
			(size 0.766318 0.766318)
			(drill 0.359918)
			(layers "*.Cu" "*.Mask")
			(remove_unused_layers no)
			(net "NC_J112_N2")
			(clearance 0.0508)
			(thermal_gap 0.0508)
		)
		(pad "N3" thru_hole circle
			(at 3.999992 15.599918 180)
			(size 0.906272 0.906272)
			(drill 0.499872)
			(layers "*.Cu" "*.Mask")
			(remove_unused_layers no)
			(net "GND")
			(clearance 0.0508)
			(thermal_gap 0.0508)
		)
		(pad "N4" thru_hole circle
			(at 5.999988 15.80007 180)
			(size 0.766318 0.766318)
			(drill 0.359918)
			(layers "*.Cu" "*.Mask")
			(remove_unused_layers no)
			(net "CLK_100M_GPU_1_DN")
			(clearance 0.0508)
			(thermal_gap 0.0508)
		)
		(pad "N5" thru_hole circle
			(at 7.999984 15.599918 180)
			(size 0.906272 0.906272)
			(drill 0.499872)
			(layers "*.Cu" "*.Mask")
			(remove_unused_layers no)
			(net "GND")
			(clearance 0.0508)
			(thermal_gap 0.0508)
		)
		(pad "N6" thru_hole circle
			(at 9.99998 15.80007 180)
			(size 0.766318 0.766318)
			(drill 0.359918)
			(layers "*.Cu" "*.Mask")
			(remove_unused_layers no)
			(net "P2E_MB_BMC_RX_DN<0>")
			(clearance 0.0508)
			(thermal_gap 0.0508)
		)
		(pad "N7" thru_hole circle
			(at 11.999976 15.599918 180)
			(size 0.906272 0.906272)
			(drill 0.499872)
			(layers "*.Cu" "*.Mask")
			(remove_unused_layers no)
			(net "GND")
			(clearance 0.0508)
			(thermal_gap 0.0508)
		)
		(pad "O1" thru_hole circle
			(at 0 16.800068 180)
			(size 0.766318 0.766318)
			(drill 0.359918)
			(layers "*.Cu" "*.Mask")
			(remove_unused_layers no)
			(net "CLK_100M_GPU_2_DN")
			(clearance 0.0508)
			(thermal_gap 0.0508)
		)
		(pad "O2" thru_hole circle
			(at 1.999996 16.999966 180)
			(size 0.766318 0.766318)
			(drill 0.359918)
			(layers "*.Cu" "*.Mask")
			(remove_unused_layers no)
			(net "NC_J112_O2")
			(clearance 0.0508)
			(thermal_gap 0.0508)
		)
		(pad "O3" thru_hole circle
			(at 3.999992 16.800068 180)
			(size 0.766318 0.766318)
			(drill 0.359918)
			(layers "*.Cu" "*.Mask")
			(remove_unused_layers no)
			(net "CLK_100M_SWB_DN")
			(clearance 0.0508)
			(thermal_gap 0.0508)
		)
		(pad "O4" thru_hole circle
			(at 5.999988 16.999966 180)
			(size 0.766318 0.766318)
			(drill 0.359918)
			(layers "*.Cu" "*.Mask")
			(remove_unused_layers no)
			(net "CLK_100M_GPU_1_DP")
			(clearance 0.0508)
			(thermal_gap 0.0508)
		)
		(pad "O5" thru_hole circle
			(at 7.999984 16.800068 180)
			(size 0.766318 0.766318)
			(drill 0.359918)
			(layers "*.Cu" "*.Mask")
			(remove_unused_layers no)
			(net "NC_J112_O5")
			(clearance 0.0508)
			(thermal_gap 0.0508)
		)
		(pad "O6" thru_hole circle
			(at 9.99998 16.999966 180)
			(size 0.766318 0.766318)
			(drill 0.359918)
			(layers "*.Cu" "*.Mask")
			(remove_unused_layers no)
			(net "P2E_MB_BMC_RX_DP<0>")
			(clearance 0.0508)
			(thermal_gap 0.0508)
		)
		(pad "O7" thru_hole circle
			(at 11.999976 16.800068 180)
			(size 0.766318 0.766318)
			(drill 0.359918)
			(layers "*.Cu" "*.Mask")
			(remove_unused_layers no)
			(net "P3E_PCH_NVS_RX_DN<1>")
			(clearance 0.0508)
			(thermal_gap 0.0508)
		)
		(pad "P1" thru_hole circle
			(at 0 17.999964 180)
			(size 0.766318 0.766318)
			(drill 0.359918)
			(layers "*.Cu" "*.Mask")
			(remove_unused_layers no)
			(net "CLK_100M_GPU_2_DP")
			(clearance 0.0508)
			(thermal_gap 0.0508)
		)
		(pad "P2" thru_hole circle
			(at 1.999996 18.200116 180)
			(size 0.906272 0.906272)
			(drill 0.499872)
			(layers "*.Cu" "*.Mask")
			(remove_unused_layers no)
			(net "GND")
			(clearance 0.0508)
			(thermal_gap 0.0508)
		)
		(pad "P3" thru_hole circle
			(at 3.999992 17.999964 180)
			(size 0.766318 0.766318)
			(drill 0.359918)
			(layers "*.Cu" "*.Mask")
			(remove_unused_layers no)
			(net "CLK_100M_SWB_DP")
			(clearance 0.0508)
			(thermal_gap 0.0508)
		)
		(pad "P4" thru_hole circle
			(at 5.999988 18.200116 180)
			(size 0.906272 0.906272)
			(drill 0.499872)
			(layers "*.Cu" "*.Mask")
			(remove_unused_layers no)
			(net "GND")
			(clearance 0.0508)
			(thermal_gap 0.0508)
		)
		(pad "P5" thru_hole circle
			(at 7.999984 17.999964 180)
			(size 0.766318 0.766318)
			(drill 0.359918)
			(layers "*.Cu" "*.Mask")
			(remove_unused_layers no)
			(net "NC_J112_P5")
			(clearance 0.0508)
			(thermal_gap 0.0508)
		)
		(pad "P6" thru_hole circle
			(at 9.99998 18.200116 180)
			(size 0.906272 0.906272)
			(drill 0.499872)
			(layers "*.Cu" "*.Mask")
			(remove_unused_layers no)
			(net "GND")
			(clearance 0.0508)
			(thermal_gap 0.0508)
		)
		(pad "P7" thru_hole circle
			(at 11.999976 17.999964 180)
			(size 0.766318 0.766318)
			(drill 0.359918)
			(layers "*.Cu" "*.Mask")
			(remove_unused_layers no)
			(net "P3E_PCH_NVS_RX_DP<1>")
			(clearance 0.0508)
			(thermal_gap 0.0508)
		)
		(pad "P8" thru_hole circle
			(at 13.999972 18.200116 180)
			(size 0.906272 0.906272)
			(drill 0.499872)
			(layers "*.Cu" "*.Mask")
			(remove_unused_layers no)
			(net "GND")
			(clearance 0.0508)
			(thermal_gap 0.0508)
		)
		(pad "Q1" thru_hole circle
			(at 0 19.200114 180)
			(size 0.906272 0.906272)
			(drill 0.499872)
			(layers "*.Cu" "*.Mask")
			(remove_unused_layers no)
			(net "GND")
			(clearance 0.0508)
			(thermal_gap 0.0508)
		)
		(pad "Q2" thru_hole circle
			(at 1.999996 19.400012 180)
			(size 0.766318 0.766318)
			(drill 0.359918)
			(layers "*.Cu" "*.Mask")
			(remove_unused_layers no)
			(net "CLK_100M_GPU_FPGA_DN")
			(clearance 0.0508)
			(thermal_gap 0.0508)
		)
		(pad "Q3" thru_hole circle
			(at 3.999992 19.200114 180)
			(size 0.906272 0.906272)
			(drill 0.499872)
			(layers "*.Cu" "*.Mask")
			(remove_unused_layers no)
			(net "GND")
			(clearance 0.0508)
			(thermal_gap 0.0508)
		)
		(pad "Q4" thru_hole circle
			(at 5.999988 19.400012 180)
			(size 0.766318 0.766318)
			(drill 0.359918)
			(layers "*.Cu" "*.Mask")
			(remove_unused_layers no)
			(net "SMB_1_BMC_GPU_BUF_SCL")
			(clearance 0.0508)
			(thermal_gap 0.0508)
		)
		(pad "Q5" thru_hole circle
			(at 7.999984 19.200114 180)
			(size 0.906272 0.906272)
			(drill 0.499872)
			(layers "*.Cu" "*.Mask")
			(remove_unused_layers no)
			(net "GND")
			(clearance 0.0508)
			(thermal_gap 0.0508)
		)
		(pad "Q7" thru_hole circle
			(at 11.999976 19.200114 180)
			(size 0.906272 0.906272)
			(drill 0.499872)
			(layers "*.Cu" "*.Mask")
			(remove_unused_layers no)
			(net "GND")
			(clearance 0.0508)
			(thermal_gap 0.0508)
		)
		(pad "R1" thru_hole circle
			(at 0 20.40001 180)
			(size 0.766318 0.766318)
			(drill 0.359918)
			(layers "*.Cu" "*.Mask")
			(remove_unused_layers no)
			(net "USB2_HUB_BUF_SWB_DN")
			(clearance 0.0508)
			(thermal_gap 0.0508)
		)
		(pad "R2" thru_hole circle
			(at 1.999996 20.599908 180)
			(size 0.766318 0.766318)
			(drill 0.359918)
			(layers "*.Cu" "*.Mask")
			(remove_unused_layers no)
			(net "CLK_100M_GPU_FPGA_DP")
			(clearance 0.0508)
			(thermal_gap 0.0508)
		)
		(pad "R3" thru_hole circle
			(at 3.999992 20.40001 180)
			(size 0.766318 0.766318)
			(drill 0.359918)
			(layers "*.Cu" "*.Mask")
			(remove_unused_layers no)
			(net "SMB_2_BMC_GPU_BUF_SCL")
			(clearance 0.0508)
			(thermal_gap 0.0508)
		)
		(pad "R4" thru_hole circle
			(at 5.999988 20.599908 180)
			(size 0.766318 0.766318)
			(drill 0.359918)
			(layers "*.Cu" "*.Mask")
			(remove_unused_layers no)
			(net "SMB_1_BMC_GPU_BUF_SDA")
			(clearance 0.0508)
			(thermal_gap 0.0508)
		)
		(pad "R5" thru_hole circle
			(at 7.999984 20.40001 180)
			(size 0.766318 0.766318)
			(drill 0.359918)
			(layers "*.Cu" "*.Mask")
			(remove_unused_layers no)
			(net "NC_J112_R5")
			(clearance 0.0508)
			(thermal_gap 0.0508)
		)
		(pad "R7" thru_hole circle
			(at 11.999976 20.40001 180)
			(size 0.766318 0.766318)
			(drill 0.359918)
			(layers "*.Cu" "*.Mask")
			(remove_unused_layers no)
			(net "P3E_PCH_NVS_TX_C_DN<1>")
			(clearance 0.0508)
			(thermal_gap 0.0508)
		)
		(pad "S1" thru_hole circle
			(at 0 21.599906 180)
			(size 0.766318 0.766318)
			(drill 0.359918)
			(layers "*.Cu" "*.Mask")
			(remove_unused_layers no)
			(net "USB2_HUB_BUF_SWB_DP")
			(clearance 0.0508)
			(thermal_gap 0.0508)
		)
		(pad "S2" thru_hole circle
			(at 1.999996 21.800058 180)
			(size 0.906272 0.906272)
			(drill 0.499872)
			(layers "*.Cu" "*.Mask")
			(remove_unused_layers no)
			(net "GND")
			(clearance 0.0508)
			(thermal_gap 0.0508)
		)
		(pad "S3" thru_hole circle
			(at 3.999992 21.599906 180)
			(size 0.766318 0.766318)
			(drill 0.359918)
			(layers "*.Cu" "*.Mask")
			(remove_unused_layers no)
			(net "SMB_2_BMC_GPU_BUF_SDA")
			(clearance 0.0508)
			(thermal_gap 0.0508)
		)
		(pad "S4" thru_hole circle
			(at 5.999988 21.800058 180)
			(size 0.906272 0.906272)
			(drill 0.499872)
			(layers "*.Cu" "*.Mask")
			(remove_unused_layers no)
			(net "GND")
			(clearance 0.0508)
			(thermal_gap 0.0508)
		)
		(pad "S5" thru_hole circle
			(at 7.999984 21.599906 180)
			(size 0.766318 0.766318)
			(drill 0.359918)
			(layers "*.Cu" "*.Mask")
			(remove_unused_layers no)
			(net "NC_J112_S5")
			(clearance 0.0508)
			(thermal_gap 0.0508)
		)
		(pad "S6" thru_hole circle
			(at 9.99998 21.800058 180)
			(size 0.906272 0.906272)
			(drill 0.499872)
			(layers "*.Cu" "*.Mask")
			(remove_unused_layers no)
			(net "GND")
			(clearance 0.0508)
			(thermal_gap 0.0508)
		)
		(pad "S7" thru_hole circle
			(at 11.999976 21.599906 180)
			(size 0.766318 0.766318)
			(drill 0.359918)
			(layers "*.Cu" "*.Mask")
			(remove_unused_layers no)
			(net "P3E_PCH_NVS_TX_C_DP<1>")
			(clearance 0.0508)
			(thermal_gap 0.0508)
		)
		(pad "S8" thru_hole circle
			(at 13.999972 21.800058 180)
			(size 0.906272 0.906272)
			(drill 0.499872)
			(layers "*.Cu" "*.Mask")
			(remove_unused_layers no)
			(net "GND")
			(clearance 0.0508)
			(thermal_gap 0.0508)
		)
		(pad "T1" thru_hole circle
			(at 0 22.800056 180)
			(size 0.906272 0.906272)
			(drill 0.499872)
			(layers "*.Cu" "*.Mask")
			(remove_unused_layers no)
			(net "GND")
			(clearance 0.0508)
			(thermal_gap 0.0508)
		)
		(pad "T2" thru_hole circle
			(at 1.999996 22.999954 180)
			(size 0.766318 0.766318)
			(drill 0.359918)
			(layers "*.Cu" "*.Mask")
			(remove_unused_layers no)
			(net "GPU_FPGA_READY")
			(clearance 0.0508)
			(thermal_gap 0.0508)
		)
		(pad "T3" thru_hole circle
			(at 3.999992 22.800056 180)
			(size 0.906272 0.906272)
			(drill 0.499872)
			(layers "*.Cu" "*.Mask")
			(remove_unused_layers no)
			(net "GND")
			(clearance 0.0508)
			(thermal_gap 0.0508)
		)
		(pad "T4" thru_hole circle
			(at 5.999988 22.999954 180)
			(size 0.766318 0.766318)
			(drill 0.359918)
			(layers "*.Cu" "*.Mask")
			(remove_unused_layers no)
			(net "GPU_NVS_PWR_BRAKE_N_BUF")
			(clearance 0.0508)
			(thermal_gap 0.0508)
		)
		(pad "T5" thru_hole circle
			(at 7.999984 22.800056 180)
			(size 0.906272 0.906272)
			(drill 0.499872)
			(layers "*.Cu" "*.Mask")
			(remove_unused_layers no)
			(net "GND")
			(clearance 0.0508)
			(thermal_gap 0.0508)
		)
		(pad "T6" thru_hole circle
			(at 9.99998 22.999954 180)
			(size 0.766318 0.766318)
			(drill 0.359918)
			(layers "*.Cu" "*.Mask")
			(remove_unused_layers no)
			(net "GPU_FPGA_THERM_OVERT_N")
			(clearance 0.0508)
			(thermal_gap 0.0508)
		)
		(pad "T7" thru_hole circle
			(at 11.999976 22.800056 180)
			(size 0.906272 0.906272)
			(drill 0.499872)
			(layers "*.Cu" "*.Mask")
			(remove_unused_layers no)
			(net "GND")
			(clearance 0.0508)
			(thermal_gap 0.0508)
		)
		(pad "T8" thru_hole circle
			(at 13.999972 22.999954 180)
			(size 0.766318 0.766318)
			(drill 0.359918)
			(layers "*.Cu" "*.Mask")
			(remove_unused_layers no)
			(net "RST_PERST_0_SWB_BUF_N")
			(clearance 0.0508)
			(thermal_gap 0.0508)
		)
	)
	(footprint ""
		(layer "F.Cu")
		(at 122.238516 -338.17814 90)
		(property "Reference" "PR1788"
			(at 0 0 90)
			(layer "F.SilkS")
			(hide yes)
			(effects
				(font
					(size 1.27 1.27)
				)
			)
		)
		(property "Value" ""
			(at 0 0 90)
			(layer "F.Fab")
			(effects
				(font
					(size 1.27 1.27)
				)
			)
		)
		(duplicate_pad_numbers_are_jumpers no)
		(fp_line
			(start 0.7874 -0.4064)
			(end 0.7874 0.4064)
			(stroke
				(width 0.1524)
				(type default)
			)
			(layer "F.SilkS")
		)
		(fp_line
			(start -0.7874 -0.4064)
			(end 0.7874 -0.4064)
			(stroke
				(width 0.1524)
				(type default)
			)
			(layer "F.SilkS")
		)
		(fp_line
			(start 0.7874 0.4064)
			(end -0.7874 0.4064)
			(stroke
				(width 0.1524)
				(type default)
			)
			(layer "F.SilkS")
		)
		(fp_line
			(start -0.7874 0.4064)
			(end -0.7874 -0.4064)
			(stroke
				(width 0.1524)
				(type default)
			)
			(layer "F.SilkS")
		)
		(fp_line
			(start -0.12065 -0.305054)
			(end -0.12065 -0.2794)
			(stroke
				(width 0.1)
				(type default)
			)
			(layer "F.Fab")
		)
		(fp_line
			(start -0.67945 -0.305054)
			(end -0.12065 -0.305054)
			(stroke
				(width 0.1)
				(type default)
			)
			(layer "F.Fab")
		)
		(fp_line
			(start 0.67945 -0.3048)
			(end 0.67945 0.3048)
			(stroke
				(width 0.1)
				(type default)
			)
			(layer "F.Fab")
		)
		(fp_line
			(start 0.12065 -0.3048)
			(end 0.67945 -0.3048)
			(stroke
				(width 0.1)
				(type default)
			)
			(layer "F.Fab")
		)
		(fp_line
			(start 0.12065 -0.2794)
			(end 0.12065 -0.3048)
			(stroke
				(width 0.1)
				(type default)
			)
			(layer "F.Fab")
		)
		(fp_line
			(start -0.12065 -0.2794)
			(end 0.12065 -0.2794)
			(stroke
				(width 0.1)
				(type default)
			)
			(layer "F.Fab")
		)
		(fp_line
			(start 0.120396 0.2794)
			(end -0.12065 0.2794)
			(stroke
				(width 0.1)
				(type default)
			)
			(layer "F.Fab")
		)
		(fp_line
			(start -0.12065 0.2794)
			(end -0.12065 0.3048)
			(stroke
				(width 0.1)
				(type default)
			)
			(layer "F.Fab")
		)
		(fp_line
			(start 0.67945 0.3048)
			(end 0.120396 0.3048)
			(stroke
				(width 0.1)
				(type default)
			)
			(layer "F.Fab")
		)
		(fp_line
			(start 0.120396 0.3048)
			(end 0.120396 0.2794)
			(stroke
				(width 0.1)
				(type default)
			)
			(layer "F.Fab")
		)
		(fp_line
			(start -0.12065 0.3048)
			(end -0.67945 0.3048)
			(stroke
				(width 0.1)
				(type default)
			)
			(layer "F.Fab")
		)
		(fp_line
			(start -0.67945 0.3048)
			(end -0.67945 -0.305054)
			(stroke
				(width 0.1)
				(type default)
			)
			(layer "F.Fab")
		)
		(pad "1" smd circle
			(at -0.40005 0 90)
			(size 0 0)
			(layers "F.Cu" "F.Mask" "F.Paste")
			(net "SW_PVCCIN_CPU1_BOOT4")
		)
		(pad "2" smd circle
			(at 0.40005 0 90)
			(size 0 0)
			(layers "F.Cu" "F.Mask" "F.Paste")
			(net "SW_PVCCIN_CPU1_BOOT4_R")
		)
	)
	(footprint ""
		(layer "F.Cu")
		(at 200.057004 -77.06614 180)
		(property "Reference" "R1292"
			(at 0 0 180)
			(layer "F.SilkS")
			(hide yes)
			(effects
				(font
					(size 1.27 1.27)
				)
			)
		)
		(property "Value" ""
			(at 0 0 180)
			(layer "F.Fab")
			(effects
				(font
					(size 1.27 1.27)
				)
			)
		)
		(duplicate_pad_numbers_are_jumpers no)
		(fp_line
			(start 0.7874 0.4064)
			(end -0.7874 0.4064)
			(stroke
				(width 0.1524)
				(type default)
			)
			(layer "F.SilkS")
		)
		(fp_line
			(start 0.7874 -0.4064)
			(end 0.7874 0.4064)
			(stroke
				(width 0.1524)
				(type default)
			)
			(layer "F.SilkS")
		)
		(fp_line
			(start -0.7874 0.4064)
			(end -0.7874 -0.4064)
			(stroke
				(width 0.1524)
				(type default)
			)
			(layer "F.SilkS")
		)
		(fp_line
			(start -0.7874 -0.4064)
			(end 0.7874 -0.4064)
			(stroke
				(width 0.1524)
				(type default)
			)
			(layer "F.SilkS")
		)
		(fp_line
			(start 0.67945 0.3048)
			(end 0.120396 0.3048)
			(stroke
				(width 0.1)
				(type default)
			)
			(layer "F.Fab")
		)
		(fp_line
			(start 0.67945 -0.3048)
			(end 0.67945 0.3048)
			(stroke
				(width 0.1)
				(type default)
			)
			(layer "F.Fab")
		)
		(fp_line
			(start 0.12065 -0.2794)
			(end 0.12065 -0.3048)
			(stroke
				(width 0.1)
				(type default)
			)
			(layer "F.Fab")
		)
		(fp_line
			(start 0.12065 -0.3048)
			(end 0.67945 -0.3048)
			(stroke
				(width 0.1)
				(type default)
			)
			(layer "F.Fab")
		)
		(fp_line
			(start 0.120396 0.3048)
			(end 0.120396 0.2794)
			(stroke
				(width 0.1)
				(type default)
			)
			(layer "F.Fab")
		)
		(fp_line
			(start 0.120396 0.2794)
			(end -0.12065 0.2794)
			(stroke
				(width 0.1)
				(type default)
			)
			(layer "F.Fab")
		)
		(fp_line
			(start -0.12065 0.3048)
			(end -0.67945 0.3048)
			(stroke
				(width 0.1)
				(type default)
			)
			(layer "F.Fab")
		)
		(fp_line
			(start -0.12065 0.2794)
			(end -0.12065 0.3048)
			(stroke
				(width 0.1)
				(type default)
			)
			(layer "F.Fab")
		)
		(fp_line
			(start -0.12065 -0.2794)
			(end 0.12065 -0.2794)
			(stroke
				(width 0.1)
				(type default)
			)
			(layer "F.Fab")
		)
		(fp_line
			(start -0.12065 -0.305054)
			(end -0.12065 -0.2794)
			(stroke
				(width 0.1)
				(type default)
			)
			(layer "F.Fab")
		)
		(fp_line
			(start -0.67945 0.3048)
			(end -0.67945 -0.305054)
			(stroke
				(width 0.1)
				(type default)
			)
			(layer "F.Fab")
		)
		(fp_line
			(start -0.67945 -0.305054)
			(end -0.12065 -0.305054)
			(stroke
				(width 0.1)
				(type default)
			)
			(layer "F.Fab")
		)
		(pad "1" smd circle
			(at -0.40005 0 180)
			(size 0 0)
			(layers "F.Cu" "F.Mask" "F.Paste")
			(net "NCSI_BMC_RXD0_R")
		)
		(pad "2" smd circle
			(at 0.40005 0 180)
			(size 0 0)
			(layers "F.Cu" "F.Mask" "F.Paste")
			(net "RMII_OCP_BMC_RXD_0")
		)
	)
	(footprint ""
		(layer "F.Cu")
		(at 306.263294 -15.50924 180)
		(property "Reference" "R2489"
			(at 0 0 180)
			(layer "F.SilkS")
			(hide yes)
			(effects
				(font
					(size 1.27 1.27)
				)
			)
		)
		(property "Value" ""
			(at 0 0 180)
			(layer "F.Fab")
			(effects
				(font
					(size 1.27 1.27)
				)
			)
		)
		(duplicate_pad_numbers_are_jumpers no)
		(fp_line
			(start 0.7874 0.4064)
			(end -0.7874 0.4064)
			(stroke
				(width 0.1524)
				(type default)
			)
			(layer "F.SilkS")
		)
		(fp_line
			(start 0.7874 -0.4064)
			(end 0.7874 0.4064)
			(stroke
				(width 0.1524)
				(type default)
			)
			(layer "F.SilkS")
		)
		(fp_line
			(start -0.7874 0.4064)
			(end -0.7874 -0.4064)
			(stroke
				(width 0.1524)
				(type default)
			)
			(layer "F.SilkS")
		)
		(fp_line
			(start -0.7874 -0.4064)
			(end 0.7874 -0.4064)
			(stroke
				(width 0.1524)
				(type default)
			)
			(layer "F.SilkS")
		)
		(fp_line
			(start 0.67945 0.3048)
			(end 0.120396 0.3048)
			(stroke
				(width 0.1)
				(type default)
			)
			(layer "F.Fab")
		)
		(fp_line
			(start 0.67945 -0.3048)
			(end 0.67945 0.3048)
			(stroke
				(width 0.1)
				(type default)
			)
			(layer "F.Fab")
		)
		(fp_line
			(start 0.12065 -0.2794)
			(end 0.12065 -0.3048)
			(stroke
				(width 0.1)
				(type default)
			)
			(layer "F.Fab")
		)
		(fp_line
			(start 0.12065 -0.3048)
			(end 0.67945 -0.3048)
			(stroke
				(width 0.1)
				(type default)
			)
			(layer "F.Fab")
		)
		(fp_line
			(start 0.120396 0.3048)
			(end 0.120396 0.2794)
			(stroke
				(width 0.1)
				(type default)
			)
			(layer "F.Fab")
		)
		(fp_line
			(start 0.120396 0.2794)
			(end -0.12065 0.2794)
			(stroke
				(width 0.1)
				(type default)
			)
			(layer "F.Fab")
		)
		(fp_line
			(start -0.12065 0.3048)
			(end -0.67945 0.3048)
			(stroke
				(width 0.1)
				(type default)
			)
			(layer "F.Fab")
		)
		(fp_line
			(start -0.12065 0.2794)
			(end -0.12065 0.3048)
			(stroke
				(width 0.1)
				(type default)
			)
			(layer "F.Fab")
		)
		(fp_line
			(start -0.12065 -0.2794)
			(end 0.12065 -0.2794)
			(stroke
				(width 0.1)
				(type default)
			)
			(layer "F.Fab")
		)
		(fp_line
			(start -0.12065 -0.305054)
			(end -0.12065 -0.2794)
			(stroke
				(width 0.1)
				(type default)
			)
			(layer "F.Fab")
		)
		(fp_line
			(start -0.67945 0.3048)
			(end -0.67945 -0.305054)
			(stroke
				(width 0.1)
				(type default)
			)
			(layer "F.Fab")
		)
		(fp_line
			(start -0.67945 -0.305054)
			(end -0.12065 -0.305054)
			(stroke
				(width 0.1)
				(type default)
			)
			(layer "F.Fab")
		)
		(pad "1" smd circle
			(at -0.40005 0 180)
			(size 0 0)
			(layers "F.Cu" "F.Mask" "F.Paste")
			(net "IRQ_LVC3_WAKE_BUF_N")
		)
		(pad "2" smd circle
			(at 0.40005 0 180)
			(size 0 0)
			(layers "F.Cu" "F.Mask" "F.Paste")
			(net "IRQ_LVC3_WAKE_N")
		)
	)
	(footprint ""
		(layer "F.Cu")
		(at 368.243358 -92.962984 90)
		(property "Reference" "R3055"
			(at 0 0 90)
			(layer "F.SilkS")
			(hide yes)
			(effects
				(font
					(size 1.27 1.27)
				)
			)
		)
		(property "Value" ""
			(at 0 0 90)
			(layer "F.Fab")
			(effects
				(font
					(size 1.27 1.27)
				)
			)
		)
		(duplicate_pad_numbers_are_jumpers no)
		(fp_line
			(start 0.7874 -0.4064)
			(end 0.7874 0.4064)
			(stroke
				(width 0.1524)
				(type default)
			)
			(layer "F.SilkS")
		)
		(fp_line
			(start -0.7874 -0.4064)
			(end 0.7874 -0.4064)
			(stroke
				(width 0.1524)
				(type default)
			)
			(layer "F.SilkS")
		)
		(fp_line
			(start 0.7874 0.4064)
			(end -0.7874 0.4064)
			(stroke
				(width 0.1524)
				(type default)
			)
			(layer "F.SilkS")
		)
		(fp_line
			(start -0.7874 0.4064)
			(end -0.7874 -0.4064)
			(stroke
				(width 0.1524)
				(type default)
			)
			(layer "F.SilkS")
		)
		(fp_line
			(start -0.12065 -0.305054)
			(end -0.12065 -0.2794)
			(stroke
				(width 0.1)
				(type default)
			)
			(layer "F.Fab")
		)
		(fp_line
			(start -0.67945 -0.305054)
			(end -0.12065 -0.305054)
			(stroke
				(width 0.1)
				(type default)
			)
			(layer "F.Fab")
		)
		(fp_line
			(start 0.67945 -0.3048)
			(end 0.67945 0.3048)
			(stroke
				(width 0.1)
				(type default)
			)
			(layer "F.Fab")
		)
		(fp_line
			(start 0.12065 -0.3048)
			(end 0.67945 -0.3048)
			(stroke
				(width 0.1)
				(type default)
			)
			(layer "F.Fab")
		)
		(fp_line
			(start 0.12065 -0.2794)
			(end 0.12065 -0.3048)
			(stroke
				(width 0.1)
				(type default)
			)
			(layer "F.Fab")
		)
		(fp_line
			(start -0.12065 -0.2794)
			(end 0.12065 -0.2794)
			(stroke
				(width 0.1)
				(type default)
			)
			(layer "F.Fab")
		)
		(fp_line
			(start 0.120396 0.2794)
			(end -0.12065 0.2794)
			(stroke
				(width 0.1)
				(type default)
			)
			(layer "F.Fab")
		)
		(fp_line
			(start -0.12065 0.2794)
			(end -0.12065 0.3048)
			(stroke
				(width 0.1)
				(type default)
			)
			(layer "F.Fab")
		)
		(fp_line
			(start 0.67945 0.3048)
			(end 0.120396 0.3048)
			(stroke
				(width 0.1)
				(type default)
			)
			(layer "F.Fab")
		)
		(fp_line
			(start 0.120396 0.3048)
			(end 0.120396 0.2794)
			(stroke
				(width 0.1)
				(type default)
			)
			(layer "F.Fab")
		)
		(fp_line
			(start -0.12065 0.3048)
			(end -0.67945 0.3048)
			(stroke
				(width 0.1)
				(type default)
			)
			(layer "F.Fab")
		)
		(fp_line
			(start -0.67945 0.3048)
			(end -0.67945 -0.305054)
			(stroke
				(width 0.1)
				(type default)
			)
			(layer "F.Fab")
		)
		(pad "1" smd circle
			(at -0.40005 0 90)
			(size 0 0)
			(layers "F.Cu" "F.Mask" "F.Paste")
			(net "P3V3_AUX")
		)
		(pad "2" smd circle
			(at 0.40005 0 90)
			(size 0 0)
			(layers "F.Cu" "F.Mask" "F.Paste")
			(net "PU_GTL2014_BMC_JTAG_DIR_1")
		)
	)
	(footprint ""
		(layer "F.Cu")
		(at 57.144158 -402.371052 -90)
		(property "Reference" "C716"
			(at 0 0 270)
			(layer "F.SilkS")
			(hide yes)
			(effects
				(font
					(size 1.27 1.27)
				)
			)
		)
		(property "Value" ""
			(at 0 0 270)
			(layer "F.Fab")
			(effects
				(font
					(size 1.27 1.27)
				)
			)
		)
		(duplicate_pad_numbers_are_jumpers no)
		(fp_line
			(start -0.299974 0.150114)
			(end -0.299974 -0.150114)
			(stroke
				(width 0.1)
				(type default)
			)
			(layer "F.Fab")
		)
		(fp_line
			(start 0.299974 0.150114)
			(end -0.299974 0.150114)
			(stroke
				(width 0.1)
				(type default)
			)
			(layer "F.Fab")
		)
		(fp_line
			(start -0.299974 -0.150114)
			(end 0.299974 -0.150114)
			(stroke
				(width 0.1)
				(type default)
			)
			(layer "F.Fab")
		)
		(fp_line
			(start 0.299974 -0.150114)
			(end 0.299974 0.150114)
			(stroke
				(width 0.1)
				(type default)
			)
			(layer "F.Fab")
		)
		(pad "1" smd rect
			(at -0.2667 0 270)
			(size 0.3048 0.381)
			(layers "F.Cu" "F.Mask" "F.Paste")
			(net "P5E_CPU1_PE0_TX_C_DN<12>")
		)
		(pad "2" smd rect
			(at 0.2667 0 270)
			(size 0.3048 0.381)
			(layers "F.Cu" "F.Mask" "F.Paste")
			(net "P5E_CPU1_PE0_TX_DN<12>")
		)
	)
	(footprint ""
		(layer "F.Cu")
		(at 320.617088 -408.517344 -90)
		(property "Reference" "C912"
			(at 0 0 270)
			(layer "F.SilkS")
			(hide yes)
			(effects
				(font
					(size 1.27 1.27)
				)
			)
		)
		(property "Value" ""
			(at 0 0 270)
			(layer "F.Fab")
			(effects
				(font
					(size 1.27 1.27)
				)
			)
		)
		(duplicate_pad_numbers_are_jumpers no)
		(fp_line
			(start -0.299974 0.150114)
			(end -0.299974 -0.150114)
			(stroke
				(width 0.1)
				(type default)
			)
			(layer "F.Fab")
		)
		(fp_line
			(start 0.299974 0.150114)
			(end -0.299974 0.150114)
			(stroke
				(width 0.1)
				(type default)
			)
			(layer "F.Fab")
		)
		(fp_line
			(start -0.299974 -0.150114)
			(end 0.299974 -0.150114)
			(stroke
				(width 0.1)
				(type default)
			)
			(layer "F.Fab")
		)
		(fp_line
			(start 0.299974 -0.150114)
			(end 0.299974 0.150114)
			(stroke
				(width 0.1)
				(type default)
			)
			(layer "F.Fab")
		)
		(pad "1" smd rect
			(at -0.2667 0 270)
			(size 0.3048 0.381)
			(layers "F.Cu" "F.Mask" "F.Paste")
			(net "P5E_CPU0_PE0_TX_C_DN<10>")
		)
		(pad "2" smd rect
			(at 0.2667 0 270)
			(size 0.3048 0.381)
			(layers "F.Cu" "F.Mask" "F.Paste")
			(net "P5E_CPU0_PE0_TX_DN<10>")
		)
	)
	(footprint ""
		(layer "F.Cu")
		(at 392.119866 -31.185612 -90)
		(property "Reference" "R1593"
			(at 0 0 270)
			(layer "F.SilkS")
			(hide yes)
			(effects
				(font
					(size 1.27 1.27)
				)
			)
		)
		(property "Value" ""
			(at 0 0 270)
			(layer "F.Fab")
			(effects
				(font
					(size 1.27 1.27)
				)
			)
		)
		(duplicate_pad_numbers_are_jumpers no)
		(fp_line
			(start -0.7874 0.4064)
			(end -0.7874 -0.4064)
			(stroke
				(width 0.1524)
				(type default)
			)
			(layer "F.SilkS")
		)
		(fp_line
			(start 0.7874 0.4064)
			(end -0.7874 0.4064)
			(stroke
				(width 0.1524)
				(type default)
			)
			(layer "F.SilkS")
		)
		(fp_line
			(start -0.7874 -0.4064)
			(end 0.7874 -0.4064)
			(stroke
				(width 0.1524)
				(type default)
			)
			(layer "F.SilkS")
		)
		(fp_line
			(start 0.7874 -0.4064)
			(end 0.7874 0.4064)
			(stroke
				(width 0.1524)
				(type default)
			)
			(layer "F.SilkS")
		)
		(fp_line
			(start -0.67945 0.3048)
			(end -0.67945 -0.305054)
			(stroke
				(width 0.1)
				(type default)
			)
			(layer "F.Fab")
		)
		(fp_line
			(start -0.12065 0.3048)
			(end -0.67945 0.3048)
			(stroke
				(width 0.1)
				(type default)
			)
			(layer "F.Fab")
		)
		(fp_line
			(start 0.120396 0.3048)
			(end 0.120396 0.2794)
			(stroke
				(width 0.1)
				(type default)
			)
			(layer "F.Fab")
		)
		(fp_line
			(start 0.67945 0.3048)
			(end 0.120396 0.3048)
			(stroke
				(width 0.1)
				(type default)
			)
			(layer "F.Fab")
		)
		(fp_line
			(start -0.12065 0.2794)
			(end -0.12065 0.3048)
			(stroke
				(width 0.1)
				(type default)
			)
			(layer "F.Fab")
		)
		(fp_line
			(start 0.120396 0.2794)
			(end -0.12065 0.2794)
			(stroke
				(width 0.1)
				(type default)
			)
			(layer "F.Fab")
		)
		(fp_line
			(start -0.12065 -0.2794)
			(end 0.12065 -0.2794)
			(stroke
				(width 0.1)
				(type default)
			)
			(layer "F.Fab")
		)
		(fp_line
			(start 0.12065 -0.2794)
			(end 0.12065 -0.3048)
			(stroke
				(width 0.1)
				(type default)
			)
			(layer "F.Fab")
		)
		(fp_line
			(start 0.12065 -0.3048)
			(end 0.67945 -0.3048)
			(stroke
				(width 0.1)
				(type default)
			)
			(layer "F.Fab")
		)
		(fp_line
			(start 0.67945 -0.3048)
			(end 0.67945 0.3048)
			(stroke
				(width 0.1)
				(type default)
			)
			(layer "F.Fab")
		)
		(fp_line
			(start -0.67945 -0.305054)
			(end -0.12065 -0.305054)
			(stroke
				(width 0.1)
				(type default)
			)
			(layer "F.Fab")
		)
		(fp_line
			(start -0.12065 -0.305054)
			(end -0.12065 -0.2794)
			(stroke
				(width 0.1)
				(type default)
			)
			(layer "F.Fab")
		)
		(pad "1" smd circle
			(at -0.40005 0 270)
			(size 0 0)
			(layers "F.Cu" "F.Mask" "F.Paste")
			(net "P3V3_AUX")
		)
		(pad "2" smd circle
			(at 0.40005 0 270)
			(size 0 0)
			(layers "F.Cu" "F.Mask" "F.Paste")
			(net "OCP_SFF_PWRBRK_BUFF_N")
		)
	)
	(footprint ""
		(layer "F.Cu")
		(at 239.152684 -52.01285 180)
		(property "Reference" "C1995"
			(at 0 0 180)
			(layer "F.SilkS")
			(hide yes)
			(effects
				(font
					(size 1.27 1.27)
				)
			)
		)
		(property "Value" ""
			(at 0 0 180)
			(layer "F.Fab")
			(effects
				(font
					(size 1.27 1.27)
				)
			)
		)
		(duplicate_pad_numbers_are_jumpers no)
		(fp_line
			(start 0.299974 0.150114)
			(end -0.299974 0.150114)
			(stroke
				(width 0.1)
				(type default)
			)
			(layer "F.Fab")
		)
		(fp_line
			(start 0.299974 -0.150114)
			(end 0.299974 0.150114)
			(stroke
				(width 0.1)
				(type default)
			)
			(layer "F.Fab")
		)
		(fp_line
			(start -0.299974 0.150114)
			(end -0.299974 -0.150114)
			(stroke
				(width 0.1)
				(type default)
			)
			(layer "F.Fab")
		)
		(fp_line
			(start -0.299974 -0.150114)
			(end 0.299974 -0.150114)
			(stroke
				(width 0.1)
				(type default)
			)
			(layer "F.Fab")
		)
		(pad "1" smd rect
			(at -0.2667 0 180)
			(size 0.3048 0.381)
			(layers "F.Cu" "F.Mask" "F.Paste")
			(net "P3E_PCH_E1S_TX_DP<0>")
		)
		(pad "2" smd rect
			(at 0.2667 0 180)
			(size 0.3048 0.381)
			(layers "F.Cu" "F.Mask" "F.Paste")
			(net "P3E_PCH_E1S_TX_C_DP<0>")
		)
		(zone
			(layer "In1.Cu")
			(hatch none 0.5)
			(connect_pads
				(clearance 0)
			)
			(min_thickness 0.25)
			(keepout
				(tracks not_allowed)
				(vias allowed)
				(pads allowed)
				(copperpour not_allowed)
				(footprints allowed)
			)
			(placement
				(enabled no)
				(sheetname "")
			)
			(fill
				(thermal_gap 0.5)
				(thermal_bridge_width 0.5)
				(island_removal_mode 0)
			)
			(polygon
				(pts
					(arc
						(start 239.012984 -52.253134)
						(mid 239.066866 -52.230816)
						(end 239.089184 -52.176934)
					)
					(arc
						(start 239.089184 -51.846734)
						(mid 239.066866 -51.792852)
						(end 239.012984 -51.770534)
					)
					(arc
						(start 238.758984 -51.770534)
						(mid 238.705102 -51.792852)
						(end 238.682784 -51.846734)
					)
					(arc
						(start 238.682784 -52.176934)
						(mid 238.705102 -52.230816)
						(end 238.758984 -52.253134)
					)
				)
			)
		)
		(zone
			(layer "In1.Cu")
			(hatch none 0.5)
			(connect_pads
				(clearance 0)
			)
			(min_thickness 0.25)
			(keepout
				(tracks not_allowed)
				(vias allowed)
				(pads allowed)
				(copperpour not_allowed)
				(footprints allowed)
			)
			(placement
				(enabled no)
				(sheetname "")
			)
			(fill
				(thermal_gap 0.5)
				(thermal_bridge_width 0.5)
				(island_removal_mode 0)
			)
			(polygon
				(pts
					(arc
						(start 239.546384 -52.253134)
						(mid 239.600266 -52.230816)
						(end 239.622584 -52.176934)
					)
					(arc
						(start 239.622584 -51.846734)
						(mid 239.600266 -51.792852)
						(end 239.546384 -51.770534)
					)
					(arc
						(start 239.292384 -51.770534)
						(mid 239.238502 -51.792852)
						(end 239.216184 -51.846734)
					)
					(arc
						(start 239.216184 -52.176934)
						(mid 239.238502 -52.230816)
						(end 239.292384 -52.253134)
					)
				)
			)
		)
	)
	(footprint ""
		(layer "F.Cu")
		(at 122.61088 -96.230948 -90)
		(property "Reference" "Q138"
			(at -4.130802 0.18288 0)
			(unlocked yes)
			(layer "F.SilkS")
			(effects
				(font
					(size 0.635 0.4064)
					(thickness 0.1524)
				)
			)
		)
		(property "Value" ""
			(at 0 0 270)
			(layer "F.Fab")
			(effects
				(font
					(size 1.27 1.27)
				)
			)
		)
		(duplicate_pad_numbers_are_jumpers no)
		(fp_line
			(start -1.376172 1.199896)
			(end -1.376172 -1.199896)
			(stroke
				(width 0.1524)
				(type default)
			)
			(layer "F.SilkS")
		)
		(fp_line
			(start 1.376172 1.199896)
			(end -1.376172 1.199896)
			(stroke
				(width 0.1524)
				(type default)
			)
			(layer "F.SilkS")
		)
		(fp_line
			(start 0 -0.762)
			(end 0.508 -1.199896)
			(stroke
				(width 0.1524)
				(type default)
			)
			(layer "F.SilkS")
		)
		(fp_line
			(start -1.376172 -1.199896)
			(end -0.508 -1.199896)
			(stroke
				(width 0.1524)
				(type default)
			)
			(layer "F.SilkS")
		)
		(fp_line
			(start -0.508 -1.199896)
			(end 0 -0.762)
			(stroke
				(width 0.1524)
				(type default)
			)
			(layer "F.SilkS")
		)
		(fp_line
			(start 0.508 -1.199896)
			(end 1.376172 -1.199896)
			(stroke
				(width 0.1524)
				(type default)
			)
			(layer "F.SilkS")
		)
		(fp_line
			(start 1.376172 -1.199896)
			(end 1.376172 1.199896)
			(stroke
				(width 0.1524)
				(type default)
			)
			(layer "F.SilkS")
		)
		(fp_poly
			(pts
				(xy -1.5875 -1.0033) (xy -2.3495 -1.3843) (xy -2.3495 -0.6223)
			)
			(stroke
				(width 0)
				(type default)
			)
			(fill yes)
			(layer "F.SilkS")
		)
		(fp_line
			(start -0.674878 1.100074)
			(end -0.674878 -1.100074)
			(stroke
				(width 0.1)
				(type default)
			)
			(layer "F.Fab")
		)
		(fp_line
			(start 0.674878 1.100074)
			(end -0.674878 1.100074)
			(stroke
				(width 0.1)
				(type default)
			)
			(layer "F.Fab")
		)
		(fp_line
			(start -0.674878 -1.100074)
			(end 0.674878 -1.100074)
			(stroke
				(width 0.1)
				(type default)
			)
			(layer "F.Fab")
		)
		(fp_line
			(start 0.674878 -1.100074)
			(end 0.674878 1.100074)
			(stroke
				(width 0.1)
				(type default)
			)
			(layer "F.Fab")
		)
		(fp_poly
			(pts
				(xy -1.4605 -0.7493) (xy -2.2225 -1.1303) (xy -2.2225 -0.3683)
			)
			(stroke
				(width 0)
				(type default)
			)
			(fill yes)
			(layer "F.Fab")
		)
		(pad "1" smd rect
			(at -0.899922 -0.750062 180)
			(size 0.6096 0.6096)
			(layers "F.Cu" "F.Mask" "F.Paste")
			(net "GND")
		)
		(pad "2" smd rect
			(at -0.899922 0 180)
			(size 0.4064 0.6096)
			(layers "F.Cu" "F.Mask" "F.Paste")
			(net "H_CPU0_THERMTRIP_R_N")
		)
		(pad "3" smd rect
			(at -0.899922 0.750062 180)
			(size 0.6096 0.6096)
			(layers "F.Cu" "F.Mask" "F.Paste")
			(net "H_CPU0_THERMTRIP_N")
		)
		(pad "4" smd rect
			(at 0.899922 0.750062 180)
			(size 0.6096 0.6096)
			(layers "F.Cu" "F.Mask" "F.Paste")
			(net "PVNN_TERM_CPU0")
		)
		(pad "5" smd rect
			(at 0.899922 0 180)
			(size 0.4064 0.6096)
			(layers "F.Cu" "F.Mask" "F.Paste")
			(net "H_CPU0_THERMTRIP_VT_R_N")
		)
		(pad "6" smd rect
			(at 0.899922 -0.750062 180)
			(size 0.6096 0.6096)
			(layers "F.Cu" "F.Mask" "F.Paste")
			(net "H_CPU0_THERMTRIP_VT_N")
		)
	)
	(footprint ""
		(layer "F.Cu")
		(at 35.577018 -436.903368 180)
		(property "Reference" "C1796"
			(at 0 0 180)
			(layer "F.SilkS")
			(hide yes)
			(effects
				(font
					(size 1.27 1.27)
				)
			)
		)
		(property "Value" ""
			(at 0 0 180)
			(layer "F.Fab")
			(effects
				(font
					(size 1.27 1.27)
				)
			)
		)
		(duplicate_pad_numbers_are_jumpers no)
		(fp_line
			(start 0.7874 0.4064)
			(end -0.7874 0.4064)
			(stroke
				(width 0.1524)
				(type default)
			)
			(layer "F.SilkS")
		)
		(fp_line
			(start 0.7874 -0.4064)
			(end 0.7874 0.4064)
			(stroke
				(width 0.1524)
				(type default)
			)
			(layer "F.SilkS")
		)
		(fp_line
			(start -0.7874 0.4064)
			(end -0.7874 -0.4064)
			(stroke
				(width 0.1524)
				(type default)
			)
			(layer "F.SilkS")
		)
		(fp_line
			(start -0.7874 -0.4064)
			(end 0.7874 -0.4064)
			(stroke
				(width 0.1524)
				(type default)
			)
			(layer "F.SilkS")
		)
		(fp_line
			(start 0.67945 0.3048)
			(end 0.120396 0.3048)
			(stroke
				(width 0.1)
				(type default)
			)
			(layer "F.Fab")
		)
		(fp_line
			(start 0.67945 -0.3048)
			(end 0.67945 0.3048)
			(stroke
				(width 0.1)
				(type default)
			)
			(layer "F.Fab")
		)
		(fp_line
			(start 0.12065 -0.2794)
			(end 0.12065 -0.3048)
			(stroke
				(width 0.1)
				(type default)
			)
			(layer "F.Fab")
		)
		(fp_line
			(start 0.12065 -0.3048)
			(end 0.67945 -0.3048)
			(stroke
				(width 0.1)
				(type default)
			)
			(layer "F.Fab")
		)
		(fp_line
			(start 0.120396 0.3048)
			(end 0.120396 0.2794)
			(stroke
				(width 0.1)
				(type default)
			)
			(layer "F.Fab")
		)
		(fp_line
			(start 0.120396 0.2794)
			(end -0.12065 0.2794)
			(stroke
				(width 0.1)
				(type default)
			)
			(layer "F.Fab")
		)
		(fp_line
			(start -0.12065 0.3048)
			(end -0.67945 0.3048)
			(stroke
				(width 0.1)
				(type default)
			)
			(layer "F.Fab")
		)
		(fp_line
			(start -0.12065 0.2794)
			(end -0.12065 0.3048)
			(stroke
				(width 0.1)
				(type default)
			)
			(layer "F.Fab")
		)
		(fp_line
			(start -0.12065 -0.2794)
			(end 0.12065 -0.2794)
			(stroke
				(width 0.1)
				(type default)
			)
			(layer "F.Fab")
		)
		(fp_line
			(start -0.12065 -0.305054)
			(end -0.12065 -0.2794)
			(stroke
				(width 0.1)
				(type default)
			)
			(layer "F.Fab")
		)
		(fp_line
			(start -0.67945 0.3048)
			(end -0.67945 -0.305054)
			(stroke
				(width 0.1)
				(type default)
			)
			(layer "F.Fab")
		)
		(fp_line
			(start -0.67945 -0.305054)
			(end -0.12065 -0.305054)
			(stroke
				(width 0.1)
				(type default)
			)
			(layer "F.Fab")
		)
		(pad "1" smd circle
			(at -0.40005 0 180)
			(size 0 0)
			(layers "F.Cu" "F.Mask" "F.Paste")
			(net "P3V3_AUX")
		)
		(pad "2" smd circle
			(at 0.40005 0 180)
			(size 0 0)
			(layers "F.Cu" "F.Mask" "F.Paste")
			(net "GND")
		)
	)
	(footprint ""
		(layer "F.Cu")
		(at 445.157098 -92.468192 180)
		(property "Reference" "R3628"
			(at 0 0 180)
			(layer "F.SilkS")
			(hide yes)
			(effects
				(font
					(size 1.27 1.27)
				)
			)
		)
		(property "Value" ""
			(at 0 0 180)
			(layer "F.Fab")
			(effects
				(font
					(size 1.27 1.27)
				)
			)
		)
		(duplicate_pad_numbers_are_jumpers no)
		(fp_line
			(start 0.7874 0.4064)
			(end -0.7874 0.4064)
			(stroke
				(width 0.1524)
				(type default)
			)
			(layer "F.SilkS")
		)
		(fp_line
			(start 0.7874 -0.4064)
			(end 0.7874 0.4064)
			(stroke
				(width 0.1524)
				(type default)
			)
			(layer "F.SilkS")
		)
		(fp_line
			(start -0.7874 0.4064)
			(end -0.7874 -0.4064)
			(stroke
				(width 0.1524)
				(type default)
			)
			(layer "F.SilkS")
		)
		(fp_line
			(start -0.7874 -0.4064)
			(end 0.7874 -0.4064)
			(stroke
				(width 0.1524)
				(type default)
			)
			(layer "F.SilkS")
		)
		(fp_line
			(start 0.67945 0.3048)
			(end 0.120396 0.3048)
			(stroke
				(width 0.1)
				(type default)
			)
			(layer "F.Fab")
		)
		(fp_line
			(start 0.67945 -0.3048)
			(end 0.67945 0.3048)
			(stroke
				(width 0.1)
				(type default)
			)
			(layer "F.Fab")
		)
		(fp_line
			(start 0.12065 -0.2794)
			(end 0.12065 -0.3048)
			(stroke
				(width 0.1)
				(type default)
			)
			(layer "F.Fab")
		)
		(fp_line
			(start 0.12065 -0.3048)
			(end 0.67945 -0.3048)
			(stroke
				(width 0.1)
				(type default)
			)
			(layer "F.Fab")
		)
		(fp_line
			(start 0.120396 0.3048)
			(end 0.120396 0.2794)
			(stroke
				(width 0.1)
				(type default)
			)
			(layer "F.Fab")
		)
		(fp_line
			(start 0.120396 0.2794)
			(end -0.12065 0.2794)
			(stroke
				(width 0.1)
				(type default)
			)
			(layer "F.Fab")
		)
		(fp_line
			(start -0.12065 0.3048)
			(end -0.67945 0.3048)
			(stroke
				(width 0.1)
				(type default)
			)
			(layer "F.Fab")
		)
		(fp_line
			(start -0.12065 0.2794)
			(end -0.12065 0.3048)
			(stroke
				(width 0.1)
				(type default)
			)
			(layer "F.Fab")
		)
		(fp_line
			(start -0.12065 -0.2794)
			(end 0.12065 -0.2794)
			(stroke
				(width 0.1)
				(type default)
			)
			(layer "F.Fab")
		)
		(fp_line
			(start -0.12065 -0.305054)
			(end -0.12065 -0.2794)
			(stroke
				(width 0.1)
				(type default)
			)
			(layer "F.Fab")
		)
		(fp_line
			(start -0.67945 0.3048)
			(end -0.67945 -0.305054)
			(stroke
				(width 0.1)
				(type default)
			)
			(layer "F.Fab")
		)
		(fp_line
			(start -0.67945 -0.305054)
			(end -0.12065 -0.305054)
			(stroke
				(width 0.1)
				(type default)
			)
			(layer "F.Fab")
		)
		(pad "1" smd circle
			(at -0.40005 0 180)
			(size 0 0)
			(layers "F.Cu" "F.Mask" "F.Paste")
			(net "P3V3_AUX")
		)
		(pad "2" smd circle
			(at 0.40005 0 180)
			(size 0 0)
			(layers "F.Cu" "F.Mask" "F.Paste")
			(net "INA230_1_A1")
		)
	)
	(footprint ""
		(layer "F.Cu")
		(at 366.18672 -403.957028)
		(property "Reference" "C1803"
			(at 0 0 0)
			(layer "F.SilkS")
			(hide yes)
			(effects
				(font
					(size 1.27 1.27)
				)
			)
		)
		(property "Value" ""
			(at 0 0 0)
			(layer "F.Fab")
			(effects
				(font
					(size 1.27 1.27)
				)
			)
		)
		(duplicate_pad_numbers_are_jumpers no)
		(fp_line
			(start -0.7874 -0.4064)
			(end 0.7874 -0.4064)
			(stroke
				(width 0.1524)
				(type default)
			)
			(layer "F.SilkS")
		)
		(fp_line
			(start -0.7874 0.4064)
			(end -0.7874 -0.4064)
			(stroke
				(width 0.1524)
				(type default)
			)
			(layer "F.SilkS")
		)
		(fp_line
			(start 0.7874 -0.4064)
			(end 0.7874 0.4064)
			(stroke
				(width 0.1524)
				(type default)
			)
			(layer "F.SilkS")
		)
		(fp_line
			(start 0.7874 0.4064)
			(end -0.7874 0.4064)
			(stroke
				(width 0.1524)
				(type default)
			)
			(layer "F.SilkS")
		)
		(fp_line
			(start -0.67945 -0.305054)
			(end -0.12065 -0.305054)
			(stroke
				(width 0.1)
				(type default)
			)
			(layer "F.Fab")
		)
		(fp_line
			(start -0.67945 0.3048)
			(end -0.67945 -0.305054)
			(stroke
				(width 0.1)
				(type default)
			)
			(layer "F.Fab")
		)
		(fp_line
			(start -0.12065 -0.305054)
			(end -0.12065 -0.2794)
			(stroke
				(width 0.1)
				(type default)
			)
			(layer "F.Fab")
		)
		(fp_line
			(start -0.12065 -0.2794)
			(end 0.12065 -0.2794)
			(stroke
				(width 0.1)
				(type default)
			)
			(layer "F.Fab")
		)
		(fp_line
			(start -0.12065 0.2794)
			(end -0.12065 0.3048)
			(stroke
				(width 0.1)
				(type default)
			)
			(layer "F.Fab")
		)
		(fp_line
			(start -0.12065 0.3048)
			(end -0.67945 0.3048)
			(stroke
				(width 0.1)
				(type default)
			)
			(layer "F.Fab")
		)
		(fp_line
			(start 0.120396 0.2794)
			(end -0.12065 0.2794)
			(stroke
				(width 0.1)
				(type default)
			)
			(layer "F.Fab")
		)
		(fp_line
			(start 0.120396 0.3048)
			(end 0.120396 0.2794)
			(stroke
				(width 0.1)
				(type default)
			)
			(layer "F.Fab")
		)
		(fp_line
			(start 0.12065 -0.3048)
			(end 0.67945 -0.3048)
			(stroke
				(width 0.1)
				(type default)
			)
			(layer "F.Fab")
		)
		(fp_line
			(start 0.12065 -0.2794)
			(end 0.12065 -0.3048)
			(stroke
				(width 0.1)
				(type default)
			)
			(layer "F.Fab")
		)
		(fp_line
			(start 0.67945 -0.3048)
			(end 0.67945 0.3048)
			(stroke
				(width 0.1)
				(type default)
			)
			(layer "F.Fab")
		)
		(fp_line
			(start 0.67945 0.3048)
			(end 0.120396 0.3048)
			(stroke
				(width 0.1)
				(type default)
			)
			(layer "F.Fab")
		)
		(pad "1" smd circle
			(at -0.40005 0)
			(size 0 0)
			(layers "F.Cu" "F.Mask" "F.Paste")
			(net "P3V3_AUX")
		)
		(pad "2" smd circle
			(at 0.40005 0)
			(size 0 0)
			(layers "F.Cu" "F.Mask" "F.Paste")
			(net "GND")
		)
	)
	(footprint ""
		(layer "F.Cu")
		(at 116.561616 -240.277142 90)
		(property "Reference" "C302"
			(at 0 0 90)
			(layer "F.SilkS")
			(hide yes)
			(effects
				(font
					(size 1.27 1.27)
				)
			)
		)
		(property "Value" ""
			(at 0 0 90)
			(layer "F.Fab")
			(effects
				(font
					(size 1.27 1.27)
				)
			)
		)
		(duplicate_pad_numbers_are_jumpers no)
		(fp_line
			(start 0.7874 -0.4064)
			(end 0.7874 0.4064)
			(stroke
				(width 0.1524)
				(type default)
			)
			(layer "F.SilkS")
		)
		(fp_line
			(start -0.7874 -0.4064)
			(end 0.7874 -0.4064)
			(stroke
				(width 0.1524)
				(type default)
			)
			(layer "F.SilkS")
		)
		(fp_line
			(start 0.7874 0.4064)
			(end -0.7874 0.4064)
			(stroke
				(width 0.1524)
				(type default)
			)
			(layer "F.SilkS")
		)
		(fp_line
			(start -0.7874 0.4064)
			(end -0.7874 -0.4064)
			(stroke
				(width 0.1524)
				(type default)
			)
			(layer "F.SilkS")
		)
		(fp_line
			(start -0.12065 -0.305054)
			(end -0.12065 -0.2794)
			(stroke
				(width 0.1)
				(type default)
			)
			(layer "F.Fab")
		)
		(fp_line
			(start -0.67945 -0.305054)
			(end -0.12065 -0.305054)
			(stroke
				(width 0.1)
				(type default)
			)
			(layer "F.Fab")
		)
		(fp_line
			(start 0.67945 -0.3048)
			(end 0.67945 0.3048)
			(stroke
				(width 0.1)
				(type default)
			)
			(layer "F.Fab")
		)
		(fp_line
			(start 0.12065 -0.3048)
			(end 0.67945 -0.3048)
			(stroke
				(width 0.1)
				(type default)
			)
			(layer "F.Fab")
		)
		(fp_line
			(start 0.12065 -0.2794)
			(end 0.12065 -0.3048)
			(stroke
				(width 0.1)
				(type default)
			)
			(layer "F.Fab")
		)
		(fp_line
			(start -0.12065 -0.2794)
			(end 0.12065 -0.2794)
			(stroke
				(width 0.1)
				(type default)
			)
			(layer "F.Fab")
		)
		(fp_line
			(start 0.120396 0.2794)
			(end -0.12065 0.2794)
			(stroke
				(width 0.1)
				(type default)
			)
			(layer "F.Fab")
		)
		(fp_line
			(start -0.12065 0.2794)
			(end -0.12065 0.3048)
			(stroke
				(width 0.1)
				(type default)
			)
			(layer "F.Fab")
		)
		(fp_line
			(start 0.67945 0.3048)
			(end 0.120396 0.3048)
			(stroke
				(width 0.1)
				(type default)
			)
			(layer "F.Fab")
		)
		(fp_line
			(start 0.120396 0.3048)
			(end 0.120396 0.2794)
			(stroke
				(width 0.1)
				(type default)
			)
			(layer "F.Fab")
		)
		(fp_line
			(start -0.12065 0.3048)
			(end -0.67945 0.3048)
			(stroke
				(width 0.1)
				(type default)
			)
			(layer "F.Fab")
		)
		(fp_line
			(start -0.67945 0.3048)
			(end -0.67945 -0.305054)
			(stroke
				(width 0.1)
				(type default)
			)
			(layer "F.Fab")
		)
		(pad "1" smd circle
			(at -0.40005 0 90)
			(size 0 0)
			(layers "F.Cu" "F.Mask" "F.Paste")
			(net "PVCCIN_CPU1")
		)
		(pad "2" smd circle
			(at 0.40005 0 90)
			(size 0 0)
			(layers "F.Cu" "F.Mask" "F.Paste")
			(net "GND")
		)
	)
	(footprint ""
		(layer "F.Cu")
		(at 432.151536 -101.97719)
		(property "Reference" "R3796"
			(at 0 0 0)
			(layer "F.SilkS")
			(hide yes)
			(effects
				(font
					(size 1.27 1.27)
				)
			)
		)
		(property "Value" ""
			(at 0 0 0)
			(layer "F.Fab")
			(effects
				(font
					(size 1.27 1.27)
				)
			)
		)
		(duplicate_pad_numbers_are_jumpers no)
		(fp_line
			(start -0.7874 -0.4064)
			(end 0.7874 -0.4064)
			(stroke
				(width 0.1524)
				(type default)
			)
			(layer "F.SilkS")
		)
		(fp_line
			(start -0.7874 0.4064)
			(end -0.7874 -0.4064)
			(stroke
				(width 0.1524)
				(type default)
			)
			(layer "F.SilkS")
		)
		(fp_line
			(start 0.7874 -0.4064)
			(end 0.7874 0.4064)
			(stroke
				(width 0.1524)
				(type default)
			)
			(layer "F.SilkS")
		)
		(fp_line
			(start 0.7874 0.4064)
			(end -0.7874 0.4064)
			(stroke
				(width 0.1524)
				(type default)
			)
			(layer "F.SilkS")
		)
		(fp_line
			(start -0.67945 -0.305054)
			(end -0.12065 -0.305054)
			(stroke
				(width 0.1)
				(type default)
			)
			(layer "F.Fab")
		)
		(fp_line
			(start -0.67945 0.3048)
			(end -0.67945 -0.305054)
			(stroke
				(width 0.1)
				(type default)
			)
			(layer "F.Fab")
		)
		(fp_line
			(start -0.12065 -0.305054)
			(end -0.12065 -0.2794)
			(stroke
				(width 0.1)
				(type default)
			)
			(layer "F.Fab")
		)
		(fp_line
			(start -0.12065 -0.2794)
			(end 0.12065 -0.2794)
			(stroke
				(width 0.1)
				(type default)
			)
			(layer "F.Fab")
		)
		(fp_line
			(start -0.12065 0.2794)
			(end -0.12065 0.3048)
			(stroke
				(width 0.1)
				(type default)
			)
			(layer "F.Fab")
		)
		(fp_line
			(start -0.12065 0.3048)
			(end -0.67945 0.3048)
			(stroke
				(width 0.1)
				(type default)
			)
			(layer "F.Fab")
		)
		(fp_line
			(start 0.120396 0.2794)
			(end -0.12065 0.2794)
			(stroke
				(width 0.1)
				(type default)
			)
			(layer "F.Fab")
		)
		(fp_line
			(start 0.120396 0.3048)
			(end 0.120396 0.2794)
			(stroke
				(width 0.1)
				(type default)
			)
			(layer "F.Fab")
		)
		(fp_line
			(start 0.12065 -0.3048)
			(end 0.67945 -0.3048)
			(stroke
				(width 0.1)
				(type default)
			)
			(layer "F.Fab")
		)
		(fp_line
			(start 0.12065 -0.2794)
			(end 0.12065 -0.3048)
			(stroke
				(width 0.1)
				(type default)
			)
			(layer "F.Fab")
		)
		(fp_line
			(start 0.67945 -0.3048)
			(end 0.67945 0.3048)
			(stroke
				(width 0.1)
				(type default)
			)
			(layer "F.Fab")
		)
		(fp_line
			(start 0.67945 0.3048)
			(end 0.120396 0.3048)
			(stroke
				(width 0.1)
				(type default)
			)
			(layer "F.Fab")
		)
		(pad "1" smd circle
			(at -0.40005 0)
			(size 0 0)
			(layers "F.Cu" "F.Mask" "F.Paste")
			(net "P3V3_AUX")
		)
		(pad "2" smd circle
			(at 0.40005 0)
			(size 0 0)
			(layers "F.Cu" "F.Mask" "F.Paste")
			(net "P3V3_OCP_FAULT_1")
		)
	)
	(footprint ""
		(layer "F.Cu")
		(at 469.694514 -41.87825 -90)
		(property "Reference" "R4068"
			(at 0 0 270)
			(layer "F.SilkS")
			(hide yes)
			(effects
				(font
					(size 1.27 1.27)
				)
			)
		)
		(property "Value" ""
			(at 0 0 270)
			(layer "F.Fab")
			(effects
				(font
					(size 1.27 1.27)
				)
			)
		)
		(duplicate_pad_numbers_are_jumpers no)
		(fp_line
			(start -0.7874 0.4064)
			(end -0.7874 -0.4064)
			(stroke
				(width 0.1524)
				(type default)
			)
			(layer "F.SilkS")
		)
		(fp_line
			(start 0.7874 0.4064)
			(end -0.7874 0.4064)
			(stroke
				(width 0.1524)
				(type default)
			)
			(layer "F.SilkS")
		)
		(fp_line
			(start -0.7874 -0.4064)
			(end 0.7874 -0.4064)
			(stroke
				(width 0.1524)
				(type default)
			)
			(layer "F.SilkS")
		)
		(fp_line
			(start 0.7874 -0.4064)
			(end 0.7874 0.4064)
			(stroke
				(width 0.1524)
				(type default)
			)
			(layer "F.SilkS")
		)
		(fp_line
			(start -0.67945 0.3048)
			(end -0.67945 -0.305054)
			(stroke
				(width 0.1)
				(type default)
			)
			(layer "F.Fab")
		)
		(fp_line
			(start -0.12065 0.3048)
			(end -0.67945 0.3048)
			(stroke
				(width 0.1)
				(type default)
			)
			(layer "F.Fab")
		)
		(fp_line
			(start 0.120396 0.3048)
			(end 0.120396 0.2794)
			(stroke
				(width 0.1)
				(type default)
			)
			(layer "F.Fab")
		)
		(fp_line
			(start 0.67945 0.3048)
			(end 0.120396 0.3048)
			(stroke
				(width 0.1)
				(type default)
			)
			(layer "F.Fab")
		)
		(fp_line
			(start -0.12065 0.2794)
			(end -0.12065 0.3048)
			(stroke
				(width 0.1)
				(type default)
			)
			(layer "F.Fab")
		)
		(fp_line
			(start 0.120396 0.2794)
			(end -0.12065 0.2794)
			(stroke
				(width 0.1)
				(type default)
			)
			(layer "F.Fab")
		)
		(fp_line
			(start -0.12065 -0.2794)
			(end 0.12065 -0.2794)
			(stroke
				(width 0.1)
				(type default)
			)
			(layer "F.Fab")
		)
		(fp_line
			(start 0.12065 -0.2794)
			(end 0.12065 -0.3048)
			(stroke
				(width 0.1)
				(type default)
			)
			(layer "F.Fab")
		)
		(fp_line
			(start 0.12065 -0.3048)
			(end 0.67945 -0.3048)
			(stroke
				(width 0.1)
				(type default)
			)
			(layer "F.Fab")
		)
		(fp_line
			(start 0.67945 -0.3048)
			(end 0.67945 0.3048)
			(stroke
				(width 0.1)
				(type default)
			)
			(layer "F.Fab")
		)
		(fp_line
			(start -0.67945 -0.305054)
			(end -0.12065 -0.305054)
			(stroke
				(width 0.1)
				(type default)
			)
			(layer "F.Fab")
		)
		(fp_line
			(start -0.12065 -0.305054)
			(end -0.12065 -0.2794)
			(stroke
				(width 0.1)
				(type default)
			)
			(layer "F.Fab")
		)
		(pad "1" smd circle
			(at -0.40005 0 270)
			(size 0 0)
			(layers "F.Cu" "F.Mask" "F.Paste")
			(net "P12V_AUX")
		)
		(pad "2" smd circle
			(at 0.40005 0 270)
			(size 0 0)
			(layers "F.Cu" "F.Mask" "F.Paste")
			(net "P12V_OCP_1_EN_G")
		)
	)
	(footprint ""
		(layer "F.Cu")
		(at 288.786062 -362.7755)
		(property "Reference" "PU72_P0_4"
			(at -10.910062 -7.494778 0)
			(unlocked yes)
			(layer "F.SilkS")
			(effects
				(font
					(size 0.7874 0.5842)
					(thickness 0.1524)
				)
				(justify left)
			)
		)
		(property "Value" ""
			(at 0 0 0)
			(layer "F.Fab")
			(effects
				(font
					(size 1.27 1.27)
				)
			)
		)
		(duplicate_pad_numbers_are_jumpers no)
		(fp_line
			(start -2.500122 -2.999994)
			(end -2.24409 -2.999994)
			(stroke
				(width 0.1524)
				(type default)
			)
			(layer "F.SilkS")
		)
		(fp_line
			(start -2.500122 -2.529078)
			(end -2.500122 -2.999994)
			(stroke
				(width 0.1524)
				(type default)
			)
			(layer "F.SilkS")
		)
		(fp_line
			(start -2.500122 0.6604)
			(end -2.500122 0.229108)
			(stroke
				(width 0.1524)
				(type default)
			)
			(layer "F.SilkS")
		)
		(fp_line
			(start -2.500122 2.999994)
			(end -2.500122 2.339594)
			(stroke
				(width 0.1524)
				(type default)
			)
			(layer "F.SilkS")
		)
		(fp_line
			(start -2.2987 2.999994)
			(end -2.500122 2.999994)
			(stroke
				(width 0.1524)
				(type default)
			)
			(layer "F.SilkS")
		)
		(fp_line
			(start 2.31394 -2.999994)
			(end 2.500122 -2.999994)
			(stroke
				(width 0.1524)
				(type default)
			)
			(layer "F.SilkS")
		)
		(fp_line
			(start 2.500122 -2.999994)
			(end 2.500122 -2.44348)
			(stroke
				(width 0.1524)
				(type default)
			)
			(layer "F.SilkS")
		)
		(fp_line
			(start 2.500122 2.339594)
			(end 2.500122 2.999994)
			(stroke
				(width 0.1524)
				(type default)
			)
			(layer "F.SilkS")
		)
		(fp_line
			(start 2.500122 2.999994)
			(end 2.2987 2.999994)
			(stroke
				(width 0.1524)
				(type default)
			)
			(layer "F.SilkS")
		)
		(fp_poly
			(pts
				(xy -2.211832 -3.514598) (xy -2.719832 -2.498598) (xy -3.227832 -3.514598)
			)
			(stroke
				(width 0)
				(type default)
			)
			(fill yes)
			(layer "F.SilkS")
		)
		(fp_line
			(start -2.500122 -2.999994)
			(end 2.500122 -2.999994)
			(stroke
				(width 0.1)
				(type default)
			)
			(layer "F.Fab")
		)
		(fp_line
			(start -2.500122 2.999994)
			(end -2.500122 -2.999994)
			(stroke
				(width 0.1)
				(type default)
			)
			(layer "F.Fab")
		)
		(fp_line
			(start 2.500122 -2.999994)
			(end 2.500122 2.999994)
			(stroke
				(width 0.1)
				(type default)
			)
			(layer "F.Fab")
		)
		(fp_line
			(start 2.500122 2.999994)
			(end -2.500122 2.999994)
			(stroke
				(width 0.1)
				(type default)
			)
			(layer "F.Fab")
		)
		(fp_poly
			(pts
				(xy -4.218432 -2.783078) (xy -4.218432 -1.767078) (xy -3.202432 -2.275078)
			)
			(stroke
				(width 0)
				(type default)
			)
			(fill yes)
			(layer "F.Fab")
		)
		(pad "1" smd rect
			(at -2.400046 -2.275078 90)
			(size 0.2286 0.6096)
			(layers "F.Cu" "F.Mask" "F.Paste")
			(net "PVCCFA_EHV_FIVRA_CPU0_VOS4")
		)
		(pad "2" smd rect
			(at -2.400046 -1.82499 90)
			(size 0.2286 0.6096)
			(layers "F.Cu" "F.Mask" "F.Paste")
			(net "GND")
		)
		(pad "3" smd rect
			(at -2.400046 -1.374902 90)
			(size 0.2286 0.6096)
			(layers "F.Cu" "F.Mask" "F.Paste")
			(net "PVCCFA_EHV_FIVRA_CPU0_VDD4")
		)
		(pad "4" smd rect
			(at -2.400046 -0.925068 90)
			(size 0.2286 0.6096)
			(layers "F.Cu" "F.Mask" "F.Paste")
			(net "PVCCFA_EHV_FIVRA_CPU0_PVCC2")
		)
		(pad "5" smd rect
			(at -2.400046 -0.47498 90)
			(size 0.2286 0.6096)
			(layers "F.Cu" "F.Mask" "F.Paste")
			(net "GND")
		)
		(pad "6" smd rect
			(at -2.400046 -0.024892 90)
			(size 0.2286 0.6096)
			(layers "F.Cu" "F.Mask" "F.Paste")
			(net "Net_8508")
		)
		(pad "7_9-20_24" smd circle
			(at 0 1.150112 90)
			(size 0 0)
			(layers "F.Cu" "F.Mask" "F.Paste")
			(net "GND")
		)
		(pad "10_19" smd rect
			(at 0 2.899918 90)
			(size 0.6096 4.318)
			(layers "F.Cu" "F.Mask" "F.Paste")
			(net "SW_PVCCFA_EHV_FIVRA_CPU0_SW4")
		)
		(pad "25_29" smd rect
			(at 1.549908 -1.279906 270)
			(size 2.0574 2.3114)
			(layers "F.Cu" "F.Mask" "F.Paste")
			(net "SW_P12V_PVCCFA_EHV_FIVRA_CPU0_L")
		)
		(pad "30" smd rect
			(at 2.05994 -2.899918)
			(size 0.2286 0.6096)
			(layers "F.Cu" "F.Mask" "F.Paste")
			(net "SW_P12V_PVCCFA_EHV_FIVRA_CPU0_L")
		)
		(pad "31" smd rect
			(at 1.610106 -2.899918)
			(size 0.2286 0.6096)
			(layers "F.Cu" "F.Mask" "F.Paste")
			(net "Net_8509")
		)
		(pad "32" smd rect
			(at 1.160018 -2.899918)
			(size 0.2286 0.6096)
			(layers "F.Cu" "F.Mask" "F.Paste")
			(net "SW_PVCCFA_EHV_FIVRA_CPU0_BOOTR4")
		)
		(pad "33" smd rect
			(at 0.70993 -2.899918)
			(size 0.2286 0.6096)
			(layers "F.Cu" "F.Mask" "F.Paste")
			(net "SW_PVCCFA_EHV_FIVRA_CPU0_BOOT4")
		)
		(pad "34" smd rect
			(at 0.260096 -2.899918)
			(size 0.2286 0.6096)
			(layers "F.Cu" "F.Mask" "F.Paste")
			(net "PVCCFA_EHV_FIVRA_CPU0_PWM4")
		)
		(pad "35" smd rect
			(at -0.189992 -2.899918)
			(size 0.2286 0.6096)
			(layers "F.Cu" "F.Mask" "F.Paste")
			(net "PVCCFA_EHV_FIVRA_CPU0_VDD4")
		)
		(pad "36" smd rect
			(at -0.64008 -2.899918)
			(size 0.2286 0.6096)
			(layers "F.Cu" "F.Mask" "F.Paste")
			(net "PVCCFA_EHV_FIVRA_CPU0_BTSEN")
		)
		(pad "37" smd rect
			(at -1.089914 -2.899918)
			(size 0.2286 0.6096)
			(layers "F.Cu" "F.Mask" "F.Paste")
			(net "PVCCFA_EHV_FIVRA_CPU0_LSET4")
		)
		(pad "38" smd rect
			(at -1.540002 -2.899918)
			(size 0.2286 0.6096)
			(layers "F.Cu" "F.Mask" "F.Paste")
			(net "PVCCFA_EHV_FIVRA_CPU0_IMON4")
		)
		(pad "39" smd rect
			(at -1.99009 -2.899918)
			(size 0.2286 0.6096)
			(layers "F.Cu" "F.Mask" "F.Paste")
			(net "PVCCIN_CPU0_VREF")
		)
		(pad "40" smd rect
			(at -0.87503 -1.27508)
			(size 1.7526 1.9558)
			(layers "F.Cu" "F.Mask" "F.Paste")
			(net "GND")
		)
		(pad "41" smd rect
			(at -1.525016 0.249936 270)
			(size 0.3048 0.4572)
			(layers "F.Cu" "F.Mask" "F.Paste")
			(net "Net_8507")
		)
		(zone
			(layer "F.Cu")
			(hatch none 0.5)
			(connect_pads
				(clearance 0)
			)
			(min_thickness 0.25)
			(keepout
				(tracks not_allowed)
				(vias allowed)
				(pads allowed)
				(copperpour not_allowed)
				(footprints allowed)
			)
			(placement
				(enabled no)
				(sheetname "")
			)
			(fill
				(thermal_gap 0.5)
				(thermal_bridge_width 0.5)
				(island_removal_mode 0)
			)
			(polygon
				(pts
					(xy 286.28594 -359.775506) (xy 286.28594 -360.500168) (xy 291.286184 -360.500168) (xy 291.286184 -359.775506)
					(xy 290.995862 -359.775506) (xy 290.995862 -360.231182) (xy 286.576262 -360.231182) (xy 286.576262 -359.775506)
				)
			)
		)
		(zone
			(layer "F.Cu")
			(hatch none 0.5)
			(connect_pads
				(clearance 0)
			)
			(min_thickness 0.25)
			(keepout
				(tracks not_allowed)
				(vias allowed)
				(pads allowed)
				(copperpour not_allowed)
				(footprints allowed)
			)
			(placement
				(enabled no)
				(sheetname "")
			)
			(fill
				(thermal_gap 0.5)
				(thermal_bridge_width 0.5)
				(island_removal_mode 0)
			)
			(polygon
				(pts
					(xy 287.0073 -363.02188) (xy 287.78708 -363.02188) (xy 287.78708 -362.712508) (xy 287.83534 -362.712508)
					(xy 287.83534 -362.08716) (xy 287.77438 -362.0262) (xy 286.28594 -362.0262) (xy 286.28594 -362.482892)
					(xy 286.981646 -362.482892) (xy 286.981646 -362.322364) (xy 287.540446 -362.322364) (xy 287.540446 -362.728764)
					(xy 286.981646 -362.728764) (xy 286.981646 -362.508292) (xy 286.28594 -362.508292) (xy 286.28594 -362.635292)
					(xy 286.741616 -362.635292) (xy 286.741616 -363.007148) (xy 287.0073 -363.007148)
				)
			)
		)
	)
	(footprint ""
		(layer "F.Cu")
		(at 441.99048 -51.077368 -90)
		(property "Reference" "C1338"
			(at 0 0 270)
			(layer "F.SilkS")
			(hide yes)
			(effects
				(font
					(size 1.27 1.27)
				)
			)
		)
		(property "Value" ""
			(at 0 0 270)
			(layer "F.Fab")
			(effects
				(font
					(size 1.27 1.27)
				)
			)
		)
		(duplicate_pad_numbers_are_jumpers no)
		(fp_line
			(start -1.524 0.762)
			(end -1.524 -0.762)
			(stroke
				(width 0.1524)
				(type default)
			)
			(layer "F.SilkS")
		)
		(fp_line
			(start 1.524 0.762)
			(end -1.524 0.762)
			(stroke
				(width 0.1524)
				(type default)
			)
			(layer "F.SilkS")
		)
		(fp_line
			(start -1.524 -0.762)
			(end 1.524 -0.762)
			(stroke
				(width 0.1524)
				(type default)
			)
			(layer "F.SilkS")
		)
		(fp_line
			(start 1.524 -0.762)
			(end 1.524 0.762)
			(stroke
				(width 0.1524)
				(type default)
			)
			(layer "F.SilkS")
		)
		(fp_line
			(start -1.1049 0.724916)
			(end 1.1049 0.724916)
			(stroke
				(width 0.1)
				(type default)
			)
			(layer "F.Fab")
		)
		(fp_line
			(start 1.1049 0.724916)
			(end 1.1049 -0.724916)
			(stroke
				(width 0.1)
				(type default)
			)
			(layer "F.Fab")
		)
		(fp_line
			(start -1.1049 -0.724916)
			(end -1.1049 0.724916)
			(stroke
				(width 0.1)
				(type default)
			)
			(layer "F.Fab")
		)
		(fp_line
			(start 1.1049 -0.724916)
			(end -1.1049 -0.724916)
			(stroke
				(width 0.1)
				(type default)
			)
			(layer "F.Fab")
		)
		(pad "1" smd rect
			(at -0.889 0 90)
			(size 1.016 1.27)
			(layers "F.Cu" "F.Mask" "F.Paste")
			(net "P3V3_AUX")
		)
		(pad "2" smd rect
			(at 0.889 0 90)
			(size 1.016 1.27)
			(layers "F.Cu" "F.Mask" "F.Paste")
			(net "GND")
		)
	)
	(footprint ""
		(layer "F.Cu")
		(at 320.190622 -62.880748)
		(property "Reference" "R615"
			(at 0 0 0)
			(layer "F.SilkS")
			(hide yes)
			(effects
				(font
					(size 1.27 1.27)
				)
			)
		)
		(property "Value" ""
			(at 0 0 0)
			(layer "F.Fab")
			(effects
				(font
					(size 1.27 1.27)
				)
			)
		)
		(duplicate_pad_numbers_are_jumpers no)
		(fp_line
			(start -0.7874 -0.4064)
			(end 0.7874 -0.4064)
			(stroke
				(width 0.1524)
				(type default)
			)
			(layer "F.SilkS")
		)
		(fp_line
			(start -0.7874 0.4064)
			(end -0.7874 -0.4064)
			(stroke
				(width 0.1524)
				(type default)
			)
			(layer "F.SilkS")
		)
		(fp_line
			(start 0.7874 -0.4064)
			(end 0.7874 0.4064)
			(stroke
				(width 0.1524)
				(type default)
			)
			(layer "F.SilkS")
		)
		(fp_line
			(start 0.7874 0.4064)
			(end -0.7874 0.4064)
			(stroke
				(width 0.1524)
				(type default)
			)
			(layer "F.SilkS")
		)
		(fp_line
			(start -0.67945 -0.305054)
			(end -0.12065 -0.305054)
			(stroke
				(width 0.1)
				(type default)
			)
			(layer "F.Fab")
		)
		(fp_line
			(start -0.67945 0.3048)
			(end -0.67945 -0.305054)
			(stroke
				(width 0.1)
				(type default)
			)
			(layer "F.Fab")
		)
		(fp_line
			(start -0.12065 -0.305054)
			(end -0.12065 -0.2794)
			(stroke
				(width 0.1)
				(type default)
			)
			(layer "F.Fab")
		)
		(fp_line
			(start -0.12065 -0.2794)
			(end 0.12065 -0.2794)
			(stroke
				(width 0.1)
				(type default)
			)
			(layer "F.Fab")
		)
		(fp_line
			(start -0.12065 0.2794)
			(end -0.12065 0.3048)
			(stroke
				(width 0.1)
				(type default)
			)
			(layer "F.Fab")
		)
		(fp_line
			(start -0.12065 0.3048)
			(end -0.67945 0.3048)
			(stroke
				(width 0.1)
				(type default)
			)
			(layer "F.Fab")
		)
		(fp_line
			(start 0.120396 0.2794)
			(end -0.12065 0.2794)
			(stroke
				(width 0.1)
				(type default)
			)
			(layer "F.Fab")
		)
		(fp_line
			(start 0.120396 0.3048)
			(end 0.120396 0.2794)
			(stroke
				(width 0.1)
				(type default)
			)
			(layer "F.Fab")
		)
		(fp_line
			(start 0.12065 -0.3048)
			(end 0.67945 -0.3048)
			(stroke
				(width 0.1)
				(type default)
			)
			(layer "F.Fab")
		)
		(fp_line
			(start 0.12065 -0.2794)
			(end 0.12065 -0.3048)
			(stroke
				(width 0.1)
				(type default)
			)
			(layer "F.Fab")
		)
		(fp_line
			(start 0.67945 -0.3048)
			(end 0.67945 0.3048)
			(stroke
				(width 0.1)
				(type default)
			)
			(layer "F.Fab")
		)
		(fp_line
			(start 0.67945 0.3048)
			(end 0.120396 0.3048)
			(stroke
				(width 0.1)
				(type default)
			)
			(layer "F.Fab")
		)
		(pad "1" smd circle
			(at -0.40005 0)
			(size 0 0)
			(layers "F.Cu" "F.Mask" "F.Paste")
			(net "P3V3_AUX")
		)
		(pad "2" smd circle
			(at 0.40005 0)
			(size 0 0)
			(layers "F.Cu" "F.Mask" "F.Paste")
			(net "FM_PCH_VISA_DEFAULT")
		)
	)
	(footprint ""
		(layer "F.Cu")
		(at 448.418966 -73.02754)
		(property "Reference" "PU9"
			(at -8.757666 -1.038098 0)
			(unlocked yes)
			(layer "F.SilkS")
			(effects
				(font
					(size 0.7874 0.5842)
					(thickness 0.1524)
				)
				(justify left)
			)
		)
		(property "Value" ""
			(at 0 0 0)
			(layer "F.Fab")
			(effects
				(font
					(size 1.27 1.27)
				)
			)
		)
		(duplicate_pad_numbers_are_jumpers no)
		(fp_line
			(start -2.549906 -3.050032)
			(end -2.549906 -2.51968)
			(stroke
				(width 0.1524)
				(type default)
			)
			(layer "F.SilkS")
		)
		(fp_line
			(start -2.549906 2.4892)
			(end -2.549906 3.050032)
			(stroke
				(width 0.1524)
				(type default)
			)
			(layer "F.SilkS")
		)
		(fp_line
			(start -2.549906 3.050032)
			(end -1.9812 3.050032)
			(stroke
				(width 0.1524)
				(type default)
			)
			(layer "F.SilkS")
		)
		(fp_line
			(start -2.032 -3.050032)
			(end -2.549906 -3.050032)
			(stroke
				(width 0.1524)
				(type default)
			)
			(layer "F.SilkS")
		)
		(fp_line
			(start 1.9812 3.050032)
			(end 2.549906 3.050032)
			(stroke
				(width 0.1524)
				(type default)
			)
			(layer "F.SilkS")
		)
		(fp_line
			(start 2.549906 -3.050032)
			(end 2.032 -3.050032)
			(stroke
				(width 0.1524)
				(type default)
			)
			(layer "F.SilkS")
		)
		(fp_line
			(start 2.549906 -2.51968)
			(end 2.549906 -3.050032)
			(stroke
				(width 0.1524)
				(type default)
			)
			(layer "F.SilkS")
		)
		(fp_line
			(start 2.549906 3.050032)
			(end 2.549906 2.4892)
			(stroke
				(width 0.1524)
				(type default)
			)
			(layer "F.SilkS")
		)
		(fp_poly
			(pts
				(xy -3.111246 -2.409444) (xy -2.790444 -2.24917) (xy -3.111246 -2.088896)
			)
			(stroke
				(width 0)
				(type default)
			)
			(fill yes)
			(layer "F.SilkS")
		)
		(fp_line
			(start -2.549906 -3.050032)
			(end -2.549906 3.050032)
			(stroke
				(width 0.1)
				(type default)
			)
			(layer "F.Fab")
		)
		(fp_line
			(start -2.549906 3.050032)
			(end 2.549906 3.050032)
			(stroke
				(width 0.1)
				(type default)
			)
			(layer "F.Fab")
		)
		(fp_line
			(start 2.549906 -3.050032)
			(end -2.549906 -3.050032)
			(stroke
				(width 0.1)
				(type default)
			)
			(layer "F.Fab")
		)
		(fp_line
			(start 2.549906 3.050032)
			(end 2.549906 -3.050032)
			(stroke
				(width 0.1)
				(type default)
			)
			(layer "F.Fab")
		)
		(fp_poly
			(pts
				(xy -3.8354 -2.757932) (xy -3.8354 -1.741932) (xy -2.8194 -2.249932)
			)
			(stroke
				(width 0)
				(type default)
			)
			(fill yes)
			(layer "F.Fab")
		)
		(pad "1" smd rect
			(at -2.362708 -2.249932 90)
			(size 0.2794 0.5842)
			(layers "F.Cu" "F.Mask" "F.Paste")
			(net "P3V3_AUX_ILIM")
		)
		(pad "2" smd rect
			(at -2.350008 -1.75006 90)
			(size 0.2794 0.6096)
			(layers "F.Cu" "F.Mask" "F.Paste")
			(net "PWRGD_P3V3_AUX")
		)
		(pad "3" smd rect
			(at -2.350008 -1.249934 90)
			(size 0.2794 0.6096)
			(layers "F.Cu" "F.Mask" "F.Paste")
			(net "P12V_AUX")
		)
		(pad "4" smd rect
			(at -2.350008 -0.750062 90)
			(size 0.2794 0.6096)
			(layers "F.Cu" "F.Mask" "F.Paste")
			(net "P3V3_AUX_VCC")
		)
		(pad "5" smd rect
			(at -2.350008 -0.249936 90)
			(size 0.2794 0.6096)
			(layers "F.Cu" "F.Mask" "F.Paste")
			(net "P3V3_AUX_VDRV")
		)
		(pad "6" smd rect
			(at -2.350008 0.249936 90)
			(size 0.2794 0.6096)
			(layers "F.Cu" "F.Mask" "F.Paste")
			(net "NC_PU9_3")
		)
		(pad "7_10-19" smd circle
			(at 0 0.062484 270)
			(size 0 0)
			(layers "F.Cu" "F.Mask" "F.Paste")
			(net "GND")
		)
		(pad "11_18" smd circle
			(at 0 2.712466 270)
			(size 0 0)
			(layers "F.Cu" "F.Mask" "F.Paste")
			(net "SW_P3V3_AUX_SW")
		)
		(pad "20_24" smd circle
			(at 1.787906 0.749808)
			(size 0 0)
			(layers "F.Cu" "F.Mask" "F.Paste")
			(net "SW_P3V3_AUX_FLT")
		)
		(pad "25" smd rect
			(at 2.350008 -0.750062 90)
			(size 0.2794 0.6096)
			(layers "F.Cu" "F.Mask" "F.Paste")
			(net "SW_P3V3_AUX_BOOTR")
		)
		(pad "26" smd rect
			(at 2.350008 -1.249934 90)
			(size 0.2794 0.6096)
			(layers "F.Cu" "F.Mask" "F.Paste")
			(net "SW_P3V3_AUX_BOOT")
		)
		(pad "27" smd rect
			(at 2.350008 -1.75006 90)
			(size 0.2794 0.6096)
			(layers "F.Cu" "F.Mask" "F.Paste")
			(net "P3V3_AUX_EN")
		)
		(pad "28" smd rect
			(at 2.362708 -2.249932 90)
			(size 0.2794 0.5842)
			(layers "F.Cu" "F.Mask" "F.Paste")
			(net "P3V3_AUX_VOS")
		)
		(pad "29" smd rect
			(at 1.75006 -2.887726)
			(size 0.2794 0.5842)
			(layers "F.Cu" "F.Mask" "F.Paste")
			(net "P3V3_AUX_SS")
		)
		(pad "30" smd rect
			(at 1.249934 -2.875026)
			(size 0.2794 0.6096)
			(layers "F.Cu" "F.Mask" "F.Paste")
			(net "P3V3_AUX_FB")
		)
		(pad "31" smd rect
			(at 0.750062 -2.875026)
			(size 0.2794 0.6096)
			(layers "F.Cu" "F.Mask" "F.Paste")
			(net "GND")
		)
		(pad "32" smd rect
			(at 0.249936 -2.875026)
			(size 0.2794 0.6096)
			(layers "F.Cu" "F.Mask" "F.Paste")
			(net "GND")
		)
		(pad "33" smd rect
			(at -0.249936 -2.875026)
			(size 0.2794 0.6096)
			(layers "F.Cu" "F.Mask" "F.Paste")
			(net "NC_PU9_1")
		)
		(pad "34" smd rect
			(at -0.750062 -2.875026)
			(size 0.2794 0.6096)
			(layers "F.Cu" "F.Mask" "F.Paste")
			(net "NC_PU9_2")
		)
		(pad "35" smd rect
			(at -1.249934 -2.875026)
			(size 0.2794 0.6096)
			(layers "F.Cu" "F.Mask" "F.Paste")
			(net "NC_HICCUP")
		)
		(pad "36" smd rect
			(at -1.75006 -2.887726)
			(size 0.2794 0.5842)
			(layers "F.Cu" "F.Mask" "F.Paste")
			(net "P3V3_AUX_MODE")
		)
		(pad "37" smd rect
			(at -1.549908 0.150114 90)
			(size 0.3048 0.508)
			(layers "F.Cu" "F.Mask" "F.Paste")
			(net "NC_PU9_4")
		)
		(zone
			(layer "F.Cu")
			(hatch none 0.5)
			(connect_pads
				(clearance 0)
			)
			(min_thickness 0.25)
			(keepout
				(tracks not_allowed)
				(vias allowed)
				(pads allowed)
				(copperpour not_allowed)
				(footprints allowed)
			)
			(placement
				(enabled no)
				(sheetname "")
			)
			(fill
				(thermal_gap 0.5)
				(thermal_bridge_width 0.5)
				(island_removal_mode 0)
			)
			(polygon
				(pts
					(xy 446.148206 -70.627494) (xy 446.329308 -70.627494) (xy 446.36436 -70.662546) (xy 450.473572 -70.662546)
					(xy 450.508624 -70.627494) (xy 450.958966 -70.627494) (xy 450.958966 -70.452488) (xy 445.9732 -70.452488)
				)
			)
		)
		(zone
			(layer "F.Cu")
			(hatch none 0.5)
			(connect_pads
				(clearance 0)
			)
			(min_thickness 0.25)
			(keepout
				(tracks not_allowed)
				(vias allowed)
				(pads allowed)
				(copperpour not_allowed)
				(footprints allowed)
			)
			(placement
				(enabled no)
				(sheetname "")
			)
			(fill
				(thermal_gap 0.5)
				(thermal_bridge_width 0.5)
				(island_removal_mode 0)
			)
			(polygon
				(pts
					(xy 446.424558 -73.00087) (xy 446.564258 -73.00087) (xy 446.564258 -72.673972) (xy 447.173858 -72.673972)
					(xy 447.173858 -73.080626) (xy 446.564258 -73.080626) (xy 446.564258 -73.02627) (xy 446.424558 -73.02627)
					(xy 446.424558 -74.98334) (xy 446.399158 -74.98334) (xy 446.399158 -75.572366) (xy 446.971166 -75.572366)
					(xy 446.971166 -75.546966) (xy 449.866766 -75.546966) (xy 449.866766 -75.572366) (xy 450.438774 -75.572366)
					(xy 450.438774 -74.98334) (xy 450.413374 -74.98334) (xy 450.413374 -73.358502) (xy 449.344796 -73.358502)
					(xy 449.344796 -71.162418) (xy 450.473826 -71.162418) (xy 450.508624 -71.12762) (xy 450.958966 -71.12762)
					(xy 450.958966 -70.927468) (xy 450.529452 -70.927468) (xy 450.4944 -70.96252) (xy 449.044822 -70.96252)
					(xy 449.044822 -73.627488) (xy 450.193918 -73.627488) (xy 450.193918 -75.302618) (xy 446.644014 -75.302618)
					(xy 446.644014 -73.327514) (xy 447.394076 -73.327514) (xy 447.394076 -72.427592) (xy 446.424558 -72.427592)
				)
			)
		)
	)
	(footprint ""
		(layer "F.Cu")
		(at 151.56688 -44.351448)
		(property "Reference" "C1873"
			(at 0 0 0)
			(layer "F.SilkS")
			(hide yes)
			(effects
				(font
					(size 1.27 1.27)
				)
			)
		)
		(property "Value" ""
			(at 0 0 0)
			(layer "F.Fab")
			(effects
				(font
					(size 1.27 1.27)
				)
			)
		)
		(duplicate_pad_numbers_are_jumpers no)
		(fp_line
			(start -0.7874 -0.4064)
			(end 0.7874 -0.4064)
			(stroke
				(width 0.1524)
				(type default)
			)
			(layer "F.SilkS")
		)
		(fp_line
			(start -0.7874 0.4064)
			(end -0.7874 -0.4064)
			(stroke
				(width 0.1524)
				(type default)
			)
			(layer "F.SilkS")
		)
		(fp_line
			(start 0.7874 -0.4064)
			(end 0.7874 0.4064)
			(stroke
				(width 0.1524)
				(type default)
			)
			(layer "F.SilkS")
		)
		(fp_line
			(start 0.7874 0.4064)
			(end -0.7874 0.4064)
			(stroke
				(width 0.1524)
				(type default)
			)
			(layer "F.SilkS")
		)
		(fp_line
			(start -0.67945 -0.305054)
			(end -0.12065 -0.305054)
			(stroke
				(width 0.1)
				(type default)
			)
			(layer "F.Fab")
		)
		(fp_line
			(start -0.67945 0.3048)
			(end -0.67945 -0.305054)
			(stroke
				(width 0.1)
				(type default)
			)
			(layer "F.Fab")
		)
		(fp_line
			(start -0.12065 -0.305054)
			(end -0.12065 -0.2794)
			(stroke
				(width 0.1)
				(type default)
			)
			(layer "F.Fab")
		)
		(fp_line
			(start -0.12065 -0.2794)
			(end 0.12065 -0.2794)
			(stroke
				(width 0.1)
				(type default)
			)
			(layer "F.Fab")
		)
		(fp_line
			(start -0.12065 0.2794)
			(end -0.12065 0.3048)
			(stroke
				(width 0.1)
				(type default)
			)
			(layer "F.Fab")
		)
		(fp_line
			(start -0.12065 0.3048)
			(end -0.67945 0.3048)
			(stroke
				(width 0.1)
				(type default)
			)
			(layer "F.Fab")
		)
		(fp_line
			(start 0.120396 0.2794)
			(end -0.12065 0.2794)
			(stroke
				(width 0.1)
				(type default)
			)
			(layer "F.Fab")
		)
		(fp_line
			(start 0.120396 0.3048)
			(end 0.120396 0.2794)
			(stroke
				(width 0.1)
				(type default)
			)
			(layer "F.Fab")
		)
		(fp_line
			(start 0.12065 -0.3048)
			(end 0.67945 -0.3048)
			(stroke
				(width 0.1)
				(type default)
			)
			(layer "F.Fab")
		)
		(fp_line
			(start 0.12065 -0.2794)
			(end 0.12065 -0.3048)
			(stroke
				(width 0.1)
				(type default)
			)
			(layer "F.Fab")
		)
		(fp_line
			(start 0.67945 -0.3048)
			(end 0.67945 0.3048)
			(stroke
				(width 0.1)
				(type default)
			)
			(layer "F.Fab")
		)
		(fp_line
			(start 0.67945 0.3048)
			(end 0.120396 0.3048)
			(stroke
				(width 0.1)
				(type default)
			)
			(layer "F.Fab")
		)
		(pad "1" smd circle
			(at -0.40005 0)
			(size 0 0)
			(layers "F.Cu" "F.Mask" "F.Paste")
			(net "P3V3_AUX")
		)
		(pad "2" smd circle
			(at 0.40005 0)
			(size 0 0)
			(layers "F.Cu" "F.Mask" "F.Paste")
			(net "GND")
		)
	)
	(footprint ""
		(layer "F.Cu")
		(at 297.74642 -424.00601 90)
		(property "Reference" "Q129"
			(at -7.70382 9.049512 90)
			(unlocked yes)
			(layer "F.SilkS")
			(effects
				(font
					(size 0.7874 0.5842)
					(thickness 0.1524)
				)
				(justify left)
			)
		)
		(property "Value" ""
			(at 0 0 90)
			(layer "F.Fab")
			(effects
				(font
					(size 1.27 1.27)
				)
			)
		)
		(duplicate_pad_numbers_are_jumpers no)
		(fp_line
			(start 1.332738 -1.100074)
			(end 1.332738 1.100074)
			(stroke
				(width 0.1524)
				(type default)
			)
			(layer "F.SilkS")
		)
		(fp_line
			(start 0.4826 -1.100074)
			(end 1.332738 -1.100074)
			(stroke
				(width 0.1524)
				(type default)
			)
			(layer "F.SilkS")
		)
		(fp_line
			(start -0.4826 -1.100074)
			(end 0 -0.541274)
			(stroke
				(width 0.1524)
				(type default)
			)
			(layer "F.SilkS")
		)
		(fp_line
			(start -1.332738 -1.100074)
			(end -0.4826 -1.100074)
			(stroke
				(width 0.1524)
				(type default)
			)
			(layer "F.SilkS")
		)
		(fp_line
			(start 0 -0.541274)
			(end 0.4826 -1.100074)
			(stroke
				(width 0.1524)
				(type default)
			)
			(layer "F.SilkS")
		)
		(fp_line
			(start 1.332738 1.100074)
			(end -1.332738 1.100074)
			(stroke
				(width 0.1524)
				(type default)
			)
			(layer "F.SilkS")
		)
		(fp_line
			(start -1.332738 1.100074)
			(end -1.332738 -1.100074)
			(stroke
				(width 0.1524)
				(type default)
			)
			(layer "F.SilkS")
		)
		(fp_poly
			(pts
				(xy -2.25552 -1.425194) (xy -1.553464 -1.074166) (xy -2.25552 -0.723138)
			)
			(stroke
				(width 0)
				(type default)
			)
			(fill yes)
			(layer "F.SilkS")
		)
		(fp_line
			(start 0.674878 -1.100074)
			(end 0.674878 1.100074)
			(stroke
				(width 0.1)
				(type default)
			)
			(layer "F.Fab")
		)
		(fp_line
			(start -0.674878 -1.100074)
			(end 0.674878 -1.100074)
			(stroke
				(width 0.1)
				(type default)
			)
			(layer "F.Fab")
		)
		(fp_line
			(start 0.674878 1.100074)
			(end -0.674878 1.100074)
			(stroke
				(width 0.1)
				(type default)
			)
			(layer "F.Fab")
		)
		(fp_line
			(start -0.674878 1.100074)
			(end -0.674878 -1.100074)
			(stroke
				(width 0.1)
				(type default)
			)
			(layer "F.Fab")
		)
		(fp_poly
			(pts
				(xy -2.2352 -0.298958) (xy -2.2352 -1.001014) (xy -1.533144 -0.649986)
			)
			(stroke
				(width 0)
				(type default)
			)
			(fill yes)
			(layer "F.Fab")
		)
		(pad "1" smd rect
			(at -0.94996 -0.649986 180)
			(size 0.4318 0.508)
			(layers "F.Cu" "F.Mask" "F.Paste")
			(net "GND")
		)
		(pad "2" smd rect
			(at -0.94996 0 180)
			(size 0.4318 0.508)
			(layers "F.Cu" "F.Mask" "F.Paste")
			(net "GPU_3V3IO_RSVD5_FFU")
		)
		(pad "3" smd rect
			(at -0.94996 0.649986 180)
			(size 0.4318 0.508)
			(layers "F.Cu" "F.Mask" "F.Paste")
			(net "GPU_3V3IO_RSVD5_FFU_ISO")
		)
		(pad "4" smd rect
			(at 0.94996 0.649986 180)
			(size 0.4318 0.508)
			(layers "F.Cu" "F.Mask" "F.Paste")
			(net "GND")
		)
		(pad "5" smd rect
			(at 0.94996 0 180)
			(size 0.4318 0.508)
			(layers "F.Cu" "F.Mask" "F.Paste")
			(net "GPU_3V3IO_RSVD5_FFU_N")
		)
		(pad "6" smd rect
			(at 0.94996 -0.649986 180)
			(size 0.4318 0.508)
			(layers "F.Cu" "F.Mask" "F.Paste")
			(net "GPU_3V3IO_RSVD5_FFU_N")
		)
	)
	(footprint ""
		(layer "F.Cu")
		(at 106.399076 -79.078836)
		(property "Reference" "D92"
			(at -52.93741 38.649402 90)
			(unlocked yes)
			(layer "F.SilkS")
			(effects
				(font
					(size 0.635 0.4064)
					(thickness 0.1524)
				)
				(justify left)
			)
		)
		(property "Value" ""
			(at 0 0 0)
			(layer "F.Fab")
			(effects
				(font
					(size 1.27 1.27)
				)
			)
		)
		(duplicate_pad_numbers_are_jumpers no)
		(fp_line
			(start -0.90678 0.4826)
			(end -0.90678 -0.4699)
			(stroke
				(width 0.1524)
				(type default)
			)
			(layer "F.SilkS")
		)
		(fp_line
			(start -0.89408 -0.4826)
			(end 0.90678 -0.4826)
			(stroke
				(width 0.1524)
				(type default)
			)
			(layer "F.SilkS")
		)
		(fp_line
			(start -0.79248 -0.4826)
			(end 1.03378 -0.4826)
			(stroke
				(width 0.1524)
				(type default)
			)
			(layer "F.SilkS")
		)
		(fp_line
			(start -0.64008 -0.4826)
			(end 1.16078 -0.4826)
			(stroke
				(width 0.1524)
				(type default)
			)
			(layer "F.SilkS")
		)
		(fp_line
			(start 0.90678 -0.4826)
			(end 0.90678 0.4826)
			(stroke
				(width 0.1524)
				(type default)
			)
			(layer "F.SilkS")
		)
		(fp_line
			(start 0.90678 0.4826)
			(end -0.90678 0.4826)
			(stroke
				(width 0.1524)
				(type default)
			)
			(layer "F.SilkS")
		)
		(fp_line
			(start 1.03378 -0.4826)
			(end 1.03378 0.4826)
			(stroke
				(width 0.1524)
				(type default)
			)
			(layer "F.SilkS")
		)
		(fp_line
			(start 1.03378 0.4826)
			(end -0.79248 0.4826)
			(stroke
				(width 0.1524)
				(type default)
			)
			(layer "F.SilkS")
		)
		(fp_line
			(start 1.16078 -0.4826)
			(end 1.16078 0.4826)
			(stroke
				(width 0.1524)
				(type default)
			)
			(layer "F.SilkS")
		)
		(fp_line
			(start 1.16078 0.4826)
			(end -0.64008 0.4826)
			(stroke
				(width 0.1524)
				(type default)
			)
			(layer "F.SilkS")
		)
		(fp_line
			(start -0.499872 -0.249936)
			(end 0.499872 -0.249936)
			(stroke
				(width 0.1)
				(type default)
			)
			(layer "F.Fab")
		)
		(fp_line
			(start -0.499872 0.249936)
			(end -0.499872 -0.249936)
			(stroke
				(width 0.1)
				(type default)
			)
			(layer "F.Fab")
		)
		(fp_line
			(start 0.499872 -0.249936)
			(end 0.499872 0.249936)
			(stroke
				(width 0.1)
				(type default)
			)
			(layer "F.Fab")
		)
		(fp_line
			(start 0.499872 0.249936)
			(end -0.499872 0.249936)
			(stroke
				(width 0.1)
				(type default)
			)
			(layer "F.Fab")
		)
		(pad "A" smd rect
			(at -0.47498 0)
			(size 0.6096 0.7112)
			(layers "F.Cu" "F.Mask" "F.Paste")
			(net "LED_PWRGD_P1V05_PCH_AUX")
		)
		(pad "C" smd rect
			(at 0.47498 0)
			(size 0.6096 0.7112)
			(layers "F.Cu" "F.Mask" "F.Paste")
			(net "LED_PWRGD_P1V05_PCH_AUX_D")
		)
	)
	(footprint ""
		(layer "F.Cu")
		(at 152.32888 -45.938948 90)
		(property "Reference" "R3594"
			(at 0 0 90)
			(layer "F.SilkS")
			(hide yes)
			(effects
				(font
					(size 1.27 1.27)
				)
			)
		)
		(property "Value" ""
			(at 0 0 90)
			(layer "F.Fab")
			(effects
				(font
					(size 1.27 1.27)
				)
			)
		)
		(duplicate_pad_numbers_are_jumpers no)
		(fp_line
			(start 0.7874 -0.4064)
			(end 0.7874 0.4064)
			(stroke
				(width 0.1524)
				(type default)
			)
			(layer "F.SilkS")
		)
		(fp_line
			(start -0.7874 -0.4064)
			(end 0.7874 -0.4064)
			(stroke
				(width 0.1524)
				(type default)
			)
			(layer "F.SilkS")
		)
		(fp_line
			(start 0.7874 0.4064)
			(end -0.7874 0.4064)
			(stroke
				(width 0.1524)
				(type default)
			)
			(layer "F.SilkS")
		)
		(fp_line
			(start -0.7874 0.4064)
			(end -0.7874 -0.4064)
			(stroke
				(width 0.1524)
				(type default)
			)
			(layer "F.SilkS")
		)
		(fp_line
			(start -0.12065 -0.305054)
			(end -0.12065 -0.2794)
			(stroke
				(width 0.1)
				(type default)
			)
			(layer "F.Fab")
		)
		(fp_line
			(start -0.67945 -0.305054)
			(end -0.12065 -0.305054)
			(stroke
				(width 0.1)
				(type default)
			)
			(layer "F.Fab")
		)
		(fp_line
			(start 0.67945 -0.3048)
			(end 0.67945 0.3048)
			(stroke
				(width 0.1)
				(type default)
			)
			(layer "F.Fab")
		)
		(fp_line
			(start 0.12065 -0.3048)
			(end 0.67945 -0.3048)
			(stroke
				(width 0.1)
				(type default)
			)
			(layer "F.Fab")
		)
		(fp_line
			(start 0.12065 -0.2794)
			(end 0.12065 -0.3048)
			(stroke
				(width 0.1)
				(type default)
			)
			(layer "F.Fab")
		)
		(fp_line
			(start -0.12065 -0.2794)
			(end 0.12065 -0.2794)
			(stroke
				(width 0.1)
				(type default)
			)
			(layer "F.Fab")
		)
		(fp_line
			(start 0.120396 0.2794)
			(end -0.12065 0.2794)
			(stroke
				(width 0.1)
				(type default)
			)
			(layer "F.Fab")
		)
		(fp_line
			(start -0.12065 0.2794)
			(end -0.12065 0.3048)
			(stroke
				(width 0.1)
				(type default)
			)
			(layer "F.Fab")
		)
		(fp_line
			(start 0.67945 0.3048)
			(end 0.120396 0.3048)
			(stroke
				(width 0.1)
				(type default)
			)
			(layer "F.Fab")
		)
		(fp_line
			(start 0.120396 0.3048)
			(end 0.120396 0.2794)
			(stroke
				(width 0.1)
				(type default)
			)
			(layer "F.Fab")
		)
		(fp_line
			(start -0.12065 0.3048)
			(end -0.67945 0.3048)
			(stroke
				(width 0.1)
				(type default)
			)
			(layer "F.Fab")
		)
		(fp_line
			(start -0.67945 0.3048)
			(end -0.67945 -0.305054)
			(stroke
				(width 0.1)
				(type default)
			)
			(layer "F.Fab")
		)
		(pad "1" smd circle
			(at -0.40005 0 90)
			(size 0 0)
			(layers "F.Cu" "F.Mask" "F.Paste")
			(net "SMB_INA230_3V3AUX_SCL")
		)
		(pad "2" smd circle
			(at 0.40005 0 90)
			(size 0 0)
			(layers "F.Cu" "F.Mask" "F.Paste")
			(net "SMB_INA230_4_3V3AUX_SCL_R")
		)
	)
	(footprint ""
		(layer "F.Cu")
		(at 260.806692 -407.416 -90)
		(property "Reference" "PR2534"
			(at 0 0 270)
			(layer "F.SilkS")
			(hide yes)
			(effects
				(font
					(size 1.27 1.27)
				)
			)
		)
		(property "Value" ""
			(at 0 0 270)
			(layer "F.Fab")
			(effects
				(font
					(size 1.27 1.27)
				)
			)
		)
		(duplicate_pad_numbers_are_jumpers no)
		(fp_line
			(start -3.9878 3.5814)
			(end -3.9878 -3.5814)
			(stroke
				(width 0.1524)
				(type default)
			)
			(layer "F.SilkS")
		)
		(fp_line
			(start 3.9878 3.5814)
			(end -3.9878 3.5814)
			(stroke
				(width 0.1524)
				(type default)
			)
			(layer "F.SilkS")
		)
		(fp_line
			(start -3.9878 -3.5814)
			(end 3.9878 -3.5814)
			(stroke
				(width 0.1524)
				(type default)
			)
			(layer "F.SilkS")
		)
		(fp_line
			(start 3.9878 -3.5814)
			(end 3.9878 3.5814)
			(stroke
				(width 0.1524)
				(type default)
			)
			(layer "F.SilkS")
		)
		(fp_line
			(start -3.5306 3.353054)
			(end -3.5306 -3.353054)
			(stroke
				(width 0.1)
				(type default)
			)
			(layer "F.Fab")
		)
		(fp_line
			(start 3.5306 3.353054)
			(end -3.5306 3.353054)
			(stroke
				(width 0.1)
				(type default)
			)
			(layer "F.Fab")
		)
		(fp_line
			(start -3.5306 -3.353054)
			(end 3.5306 -3.353054)
			(stroke
				(width 0.1)
				(type default)
			)
			(layer "F.Fab")
		)
		(fp_line
			(start 3.5306 -3.353054)
			(end 3.5306 3.353054)
			(stroke
				(width 0.1)
				(type default)
			)
			(layer "F.Fab")
		)
		(pad "1A" smd rect
			(at -2.249932 0 90)
			(size 3.2004 6.858)
			(layers "F.Cu" "F.Mask" "F.Paste")
			(net "P12V_PSU")
		)
		(pad "1B" smd rect
			(at -0.776732 0 270)
			(size 0.254 0.508)
			(layers "F.Cu" "F.Mask" "F.Paste")
			(net "P12V_HSC_SENSE2_R4_P")
		)
		(pad "2A" smd rect
			(at 2.249932 0 90)
			(size 3.2004 6.858)
			(layers "F.Cu" "F.Mask" "F.Paste")
			(net "P12V_MAIN_R")
		)
		(pad "2B" smd rect
			(at 0.776732 0 270)
			(size 0.254 0.508)
			(layers "F.Cu" "F.Mask" "F.Paste")
			(net "P12V_HSC_SENSE2_R4_N")
		)
	)
	(footprint ""
		(layer "F.Cu")
		(at 116.561616 -252.956568 -90)
		(property "Reference" "C277"
			(at 0 0 270)
			(layer "F.SilkS")
			(hide yes)
			(effects
				(font
					(size 1.27 1.27)
				)
			)
		)
		(property "Value" ""
			(at 0 0 270)
			(layer "F.Fab")
			(effects
				(font
					(size 1.27 1.27)
				)
			)
		)
		(duplicate_pad_numbers_are_jumpers no)
		(fp_line
			(start -0.7874 0.4064)
			(end -0.7874 -0.4064)
			(stroke
				(width 0.1524)
				(type default)
			)
			(layer "F.SilkS")
		)
		(fp_line
			(start 0.7874 0.4064)
			(end -0.7874 0.4064)
			(stroke
				(width 0.1524)
				(type default)
			)
			(layer "F.SilkS")
		)
		(fp_line
			(start -0.7874 -0.4064)
			(end 0.7874 -0.4064)
			(stroke
				(width 0.1524)
				(type default)
			)
			(layer "F.SilkS")
		)
		(fp_line
			(start 0.7874 -0.4064)
			(end 0.7874 0.4064)
			(stroke
				(width 0.1524)
				(type default)
			)
			(layer "F.SilkS")
		)
		(fp_line
			(start -0.67945 0.3048)
			(end -0.67945 -0.305054)
			(stroke
				(width 0.1)
				(type default)
			)
			(layer "F.Fab")
		)
		(fp_line
			(start -0.12065 0.3048)
			(end -0.67945 0.3048)
			(stroke
				(width 0.1)
				(type default)
			)
			(layer "F.Fab")
		)
		(fp_line
			(start 0.120396 0.3048)
			(end 0.120396 0.2794)
			(stroke
				(width 0.1)
				(type default)
			)
			(layer "F.Fab")
		)
		(fp_line
			(start 0.67945 0.3048)
			(end 0.120396 0.3048)
			(stroke
				(width 0.1)
				(type default)
			)
			(layer "F.Fab")
		)
		(fp_line
			(start -0.12065 0.2794)
			(end -0.12065 0.3048)
			(stroke
				(width 0.1)
				(type default)
			)
			(layer "F.Fab")
		)
		(fp_line
			(start 0.120396 0.2794)
			(end -0.12065 0.2794)
			(stroke
				(width 0.1)
				(type default)
			)
			(layer "F.Fab")
		)
		(fp_line
			(start -0.12065 -0.2794)
			(end 0.12065 -0.2794)
			(stroke
				(width 0.1)
				(type default)
			)
			(layer "F.Fab")
		)
		(fp_line
			(start 0.12065 -0.2794)
			(end 0.12065 -0.3048)
			(stroke
				(width 0.1)
				(type default)
			)
			(layer "F.Fab")
		)
		(fp_line
			(start 0.12065 -0.3048)
			(end 0.67945 -0.3048)
			(stroke
				(width 0.1)
				(type default)
			)
			(layer "F.Fab")
		)
		(fp_line
			(start 0.67945 -0.3048)
			(end 0.67945 0.3048)
			(stroke
				(width 0.1)
				(type default)
			)
			(layer "F.Fab")
		)
		(fp_line
			(start -0.67945 -0.305054)
			(end -0.12065 -0.305054)
			(stroke
				(width 0.1)
				(type default)
			)
			(layer "F.Fab")
		)
		(fp_line
			(start -0.12065 -0.305054)
			(end -0.12065 -0.2794)
			(stroke
				(width 0.1)
				(type default)
			)
			(layer "F.Fab")
		)
		(pad "1" smd circle
			(at -0.40005 0 270)
			(size 0 0)
			(layers "F.Cu" "F.Mask" "F.Paste")
			(net "PVCCIN_CPU1")
		)
		(pad "2" smd circle
			(at 0.40005 0 270)
			(size 0 0)
			(layers "F.Cu" "F.Mask" "F.Paste")
			(net "GND")
		)
	)
	(footprint ""
		(layer "F.Cu")
		(at 123.741942 -16.90751 180)
		(property "Reference" "R4200"
			(at 0 0 180)
			(layer "F.SilkS")
			(hide yes)
			(effects
				(font
					(size 1.27 1.27)
				)
			)
		)
		(property "Value" ""
			(at 0 0 180)
			(layer "F.Fab")
			(effects
				(font
					(size 1.27 1.27)
				)
			)
		)
		(duplicate_pad_numbers_are_jumpers no)
		(fp_line
			(start 0.7874 0.4064)
			(end -0.7874 0.4064)
			(stroke
				(width 0.1524)
				(type default)
			)
			(layer "F.SilkS")
		)
		(fp_line
			(start 0.7874 -0.4064)
			(end 0.7874 0.4064)
			(stroke
				(width 0.1524)
				(type default)
			)
			(layer "F.SilkS")
		)
		(fp_line
			(start -0.7874 0.4064)
			(end -0.7874 -0.4064)
			(stroke
				(width 0.1524)
				(type default)
			)
			(layer "F.SilkS")
		)
		(fp_line
			(start -0.7874 -0.4064)
			(end 0.7874 -0.4064)
			(stroke
				(width 0.1524)
				(type default)
			)
			(layer "F.SilkS")
		)
		(fp_line
			(start 0.67945 0.3048)
			(end 0.120396 0.3048)
			(stroke
				(width 0.1)
				(type default)
			)
			(layer "F.Fab")
		)
		(fp_line
			(start 0.67945 -0.3048)
			(end 0.67945 0.3048)
			(stroke
				(width 0.1)
				(type default)
			)
			(layer "F.Fab")
		)
		(fp_line
			(start 0.12065 -0.2794)
			(end 0.12065 -0.3048)
			(stroke
				(width 0.1)
				(type default)
			)
			(layer "F.Fab")
		)
		(fp_line
			(start 0.12065 -0.3048)
			(end 0.67945 -0.3048)
			(stroke
				(width 0.1)
				(type default)
			)
			(layer "F.Fab")
		)
		(fp_line
			(start 0.120396 0.3048)
			(end 0.120396 0.2794)
			(stroke
				(width 0.1)
				(type default)
			)
			(layer "F.Fab")
		)
		(fp_line
			(start 0.120396 0.2794)
			(end -0.12065 0.2794)
			(stroke
				(width 0.1)
				(type default)
			)
			(layer "F.Fab")
		)
		(fp_line
			(start -0.12065 0.3048)
			(end -0.67945 0.3048)
			(stroke
				(width 0.1)
				(type default)
			)
			(layer "F.Fab")
		)
		(fp_line
			(start -0.12065 0.2794)
			(end -0.12065 0.3048)
			(stroke
				(width 0.1)
				(type default)
			)
			(layer "F.Fab")
		)
		(fp_line
			(start -0.12065 -0.2794)
			(end 0.12065 -0.2794)
			(stroke
				(width 0.1)
				(type default)
			)
			(layer "F.Fab")
		)
		(fp_line
			(start -0.12065 -0.305054)
			(end -0.12065 -0.2794)
			(stroke
				(width 0.1)
				(type default)
			)
			(layer "F.Fab")
		)
		(fp_line
			(start -0.67945 0.3048)
			(end -0.67945 -0.305054)
			(stroke
				(width 0.1)
				(type default)
			)
			(layer "F.Fab")
		)
		(fp_line
			(start -0.67945 -0.305054)
			(end -0.12065 -0.305054)
			(stroke
				(width 0.1)
				(type default)
			)
			(layer "F.Fab")
		)
		(pad "1" smd circle
			(at -0.40005 0 180)
			(size 0 0)
			(layers "F.Cu" "F.Mask" "F.Paste")
			(net "P3V3_AUX")
		)
		(pad "2" smd circle
			(at 0.40005 0 180)
			(size 0 0)
			(layers "F.Cu" "F.Mask" "F.Paste")
			(net "U273_3_ADD0")
		)
	)
	(footprint ""
		(layer "F.Cu")
		(at 369.292632 -396.249398)
		(property "Reference" "R2706"
			(at 0 0 0)
			(layer "F.SilkS")
			(hide yes)
			(effects
				(font
					(size 1.27 1.27)
				)
			)
		)
		(property "Value" ""
			(at 0 0 0)
			(layer "F.Fab")
			(effects
				(font
					(size 1.27 1.27)
				)
			)
		)
		(duplicate_pad_numbers_are_jumpers no)
		(fp_line
			(start -0.7874 -0.4064)
			(end 0.7874 -0.4064)
			(stroke
				(width 0.1524)
				(type default)
			)
			(layer "F.SilkS")
		)
		(fp_line
			(start -0.7874 0.4064)
			(end -0.7874 -0.4064)
			(stroke
				(width 0.1524)
				(type default)
			)
			(layer "F.SilkS")
		)
		(fp_line
			(start 0.7874 -0.4064)
			(end 0.7874 0.4064)
			(stroke
				(width 0.1524)
				(type default)
			)
			(layer "F.SilkS")
		)
		(fp_line
			(start 0.7874 0.4064)
			(end -0.7874 0.4064)
			(stroke
				(width 0.1524)
				(type default)
			)
			(layer "F.SilkS")
		)
		(fp_line
			(start -0.67945 -0.305054)
			(end -0.12065 -0.305054)
			(stroke
				(width 0.1)
				(type default)
			)
			(layer "F.Fab")
		)
		(fp_line
			(start -0.67945 0.3048)
			(end -0.67945 -0.305054)
			(stroke
				(width 0.1)
				(type default)
			)
			(layer "F.Fab")
		)
		(fp_line
			(start -0.12065 -0.305054)
			(end -0.12065 -0.2794)
			(stroke
				(width 0.1)
				(type default)
			)
			(layer "F.Fab")
		)
		(fp_line
			(start -0.12065 -0.2794)
			(end 0.12065 -0.2794)
			(stroke
				(width 0.1)
				(type default)
			)
			(layer "F.Fab")
		)
		(fp_line
			(start -0.12065 0.2794)
			(end -0.12065 0.3048)
			(stroke
				(width 0.1)
				(type default)
			)
			(layer "F.Fab")
		)
		(fp_line
			(start -0.12065 0.3048)
			(end -0.67945 0.3048)
			(stroke
				(width 0.1)
				(type default)
			)
			(layer "F.Fab")
		)
		(fp_line
			(start 0.120396 0.2794)
			(end -0.12065 0.2794)
			(stroke
				(width 0.1)
				(type default)
			)
			(layer "F.Fab")
		)
		(fp_line
			(start 0.120396 0.3048)
			(end 0.120396 0.2794)
			(stroke
				(width 0.1)
				(type default)
			)
			(layer "F.Fab")
		)
		(fp_line
			(start 0.12065 -0.3048)
			(end 0.67945 -0.3048)
			(stroke
				(width 0.1)
				(type default)
			)
			(layer "F.Fab")
		)
		(fp_line
			(start 0.12065 -0.2794)
			(end 0.12065 -0.3048)
			(stroke
				(width 0.1)
				(type default)
			)
			(layer "F.Fab")
		)
		(fp_line
			(start 0.67945 -0.3048)
			(end 0.67945 0.3048)
			(stroke
				(width 0.1)
				(type default)
			)
			(layer "F.Fab")
		)
		(fp_line
			(start 0.67945 0.3048)
			(end 0.120396 0.3048)
			(stroke
				(width 0.1)
				(type default)
			)
			(layer "F.Fab")
		)
		(pad "1" smd circle
			(at -0.40005 0)
			(size 0 0)
			(layers "F.Cu" "F.Mask" "F.Paste")
			(net "I3C_BMC_SWB_R_SDA")
		)
		(pad "2" smd circle
			(at 0.40005 0)
			(size 0 0)
			(layers "F.Cu" "F.Mask" "F.Paste")
			(net "I3C_BMC_SWB_BUF_R_SDA")
		)
	)
	(footprint ""
		(layer "F.Cu")
		(at 313.144408 -402.371052 -90)
		(property "Reference" "C1572"
			(at 0 0 270)
			(layer "F.SilkS")
			(hide yes)
			(effects
				(font
					(size 1.27 1.27)
				)
			)
		)
		(property "Value" ""
			(at 0 0 270)
			(layer "F.Fab")
			(effects
				(font
					(size 1.27 1.27)
				)
			)
		)
		(duplicate_pad_numbers_are_jumpers no)
		(fp_line
			(start -0.299974 0.150114)
			(end -0.299974 -0.150114)
			(stroke
				(width 0.1)
				(type default)
			)
			(layer "F.Fab")
		)
		(fp_line
			(start 0.299974 0.150114)
			(end -0.299974 0.150114)
			(stroke
				(width 0.1)
				(type default)
			)
			(layer "F.Fab")
		)
		(fp_line
			(start -0.299974 -0.150114)
			(end 0.299974 -0.150114)
			(stroke
				(width 0.1)
				(type default)
			)
			(layer "F.Fab")
		)
		(fp_line
			(start 0.299974 -0.150114)
			(end 0.299974 0.150114)
			(stroke
				(width 0.1)
				(type default)
			)
			(layer "F.Fab")
		)
		(pad "1" smd rect
			(at -0.2667 0 270)
			(size 0.3048 0.381)
			(layers "F.Cu" "F.Mask" "F.Paste")
			(net "P5E_CPU0_PE4_TX_C_DN<3>")
		)
		(pad "2" smd rect
			(at 0.2667 0 270)
			(size 0.3048 0.381)
			(layers "F.Cu" "F.Mask" "F.Paste")
			(net "P5E_CPU0_PE4_TX_DN<3>")
		)
	)
	(footprint ""
		(layer "F.Cu")
		(at 164.64788 -108.295948 180)
		(property "Reference" "R1547"
			(at 0 0 180)
			(layer "F.SilkS")
			(hide yes)
			(effects
				(font
					(size 1.27 1.27)
				)
			)
		)
		(property "Value" ""
			(at 0 0 180)
			(layer "F.Fab")
			(effects
				(font
					(size 1.27 1.27)
				)
			)
		)
		(duplicate_pad_numbers_are_jumpers no)
		(fp_line
			(start 0.7874 0.4064)
			(end -0.7874 0.4064)
			(stroke
				(width 0.1524)
				(type default)
			)
			(layer "F.SilkS")
		)
		(fp_line
			(start 0.7874 -0.4064)
			(end 0.7874 0.4064)
			(stroke
				(width 0.1524)
				(type default)
			)
			(layer "F.SilkS")
		)
		(fp_line
			(start -0.7874 0.4064)
			(end -0.7874 -0.4064)
			(stroke
				(width 0.1524)
				(type default)
			)
			(layer "F.SilkS")
		)
		(fp_line
			(start -0.7874 -0.4064)
			(end 0.7874 -0.4064)
			(stroke
				(width 0.1524)
				(type default)
			)
			(layer "F.SilkS")
		)
		(fp_line
			(start 0.67945 0.3048)
			(end 0.120396 0.3048)
			(stroke
				(width 0.1)
				(type default)
			)
			(layer "F.Fab")
		)
		(fp_line
			(start 0.67945 -0.3048)
			(end 0.67945 0.3048)
			(stroke
				(width 0.1)
				(type default)
			)
			(layer "F.Fab")
		)
		(fp_line
			(start 0.12065 -0.2794)
			(end 0.12065 -0.3048)
			(stroke
				(width 0.1)
				(type default)
			)
			(layer "F.Fab")
		)
		(fp_line
			(start 0.12065 -0.3048)
			(end 0.67945 -0.3048)
			(stroke
				(width 0.1)
				(type default)
			)
			(layer "F.Fab")
		)
		(fp_line
			(start 0.120396 0.3048)
			(end 0.120396 0.2794)
			(stroke
				(width 0.1)
				(type default)
			)
			(layer "F.Fab")
		)
		(fp_line
			(start 0.120396 0.2794)
			(end -0.12065 0.2794)
			(stroke
				(width 0.1)
				(type default)
			)
			(layer "F.Fab")
		)
		(fp_line
			(start -0.12065 0.3048)
			(end -0.67945 0.3048)
			(stroke
				(width 0.1)
				(type default)
			)
			(layer "F.Fab")
		)
		(fp_line
			(start -0.12065 0.2794)
			(end -0.12065 0.3048)
			(stroke
				(width 0.1)
				(type default)
			)
			(layer "F.Fab")
		)
		(fp_line
			(start -0.12065 -0.2794)
			(end 0.12065 -0.2794)
			(stroke
				(width 0.1)
				(type default)
			)
			(layer "F.Fab")
		)
		(fp_line
			(start -0.12065 -0.305054)
			(end -0.12065 -0.2794)
			(stroke
				(width 0.1)
				(type default)
			)
			(layer "F.Fab")
		)
		(fp_line
			(start -0.67945 0.3048)
			(end -0.67945 -0.305054)
			(stroke
				(width 0.1)
				(type default)
			)
			(layer "F.Fab")
		)
		(fp_line
			(start -0.67945 -0.305054)
			(end -0.12065 -0.305054)
			(stroke
				(width 0.1)
				(type default)
			)
			(layer "F.Fab")
		)
		(pad "1" smd circle
			(at -0.40005 0 180)
			(size 0 0)
			(layers "F.Cu" "F.Mask" "F.Paste")
			(net "FM_TPM_PRSNT_R_N")
		)
		(pad "2" smd circle
			(at 0.40005 0 180)
			(size 0 0)
			(layers "F.Cu" "F.Mask" "F.Paste")
			(net "FM_TPM_PRSNT_N")
		)
	)
	(footprint ""
		(layer "F.Cu")
		(at 194.056 -92.801948 90)
		(property "Reference" "R4606"
			(at 0 0 90)
			(layer "F.SilkS")
			(hide yes)
			(effects
				(font
					(size 1.27 1.27)
				)
			)
		)
		(property "Value" ""
			(at 0 0 90)
			(layer "F.Fab")
			(effects
				(font
					(size 1.27 1.27)
				)
			)
		)
		(duplicate_pad_numbers_are_jumpers no)
		(fp_line
			(start 0.7874 -0.4064)
			(end 0.7874 0.4064)
			(stroke
				(width 0.1524)
				(type default)
			)
			(layer "F.SilkS")
		)
		(fp_line
			(start -0.7874 -0.4064)
			(end 0.7874 -0.4064)
			(stroke
				(width 0.1524)
				(type default)
			)
			(layer "F.SilkS")
		)
		(fp_line
			(start 0.7874 0.4064)
			(end -0.7874 0.4064)
			(stroke
				(width 0.1524)
				(type default)
			)
			(layer "F.SilkS")
		)
		(fp_line
			(start -0.7874 0.4064)
			(end -0.7874 -0.4064)
			(stroke
				(width 0.1524)
				(type default)
			)
			(layer "F.SilkS")
		)
		(fp_line
			(start -0.12065 -0.305054)
			(end -0.12065 -0.2794)
			(stroke
				(width 0.1)
				(type default)
			)
			(layer "F.Fab")
		)
		(fp_line
			(start -0.67945 -0.305054)
			(end -0.12065 -0.305054)
			(stroke
				(width 0.1)
				(type default)
			)
			(layer "F.Fab")
		)
		(fp_line
			(start 0.67945 -0.3048)
			(end 0.67945 0.3048)
			(stroke
				(width 0.1)
				(type default)
			)
			(layer "F.Fab")
		)
		(fp_line
			(start 0.12065 -0.3048)
			(end 0.67945 -0.3048)
			(stroke
				(width 0.1)
				(type default)
			)
			(layer "F.Fab")
		)
		(fp_line
			(start 0.12065 -0.2794)
			(end 0.12065 -0.3048)
			(stroke
				(width 0.1)
				(type default)
			)
			(layer "F.Fab")
		)
		(fp_line
			(start -0.12065 -0.2794)
			(end 0.12065 -0.2794)
			(stroke
				(width 0.1)
				(type default)
			)
			(layer "F.Fab")
		)
		(fp_line
			(start 0.120396 0.2794)
			(end -0.12065 0.2794)
			(stroke
				(width 0.1)
				(type default)
			)
			(layer "F.Fab")
		)
		(fp_line
			(start -0.12065 0.2794)
			(end -0.12065 0.3048)
			(stroke
				(width 0.1)
				(type default)
			)
			(layer "F.Fab")
		)
		(fp_line
			(start 0.67945 0.3048)
			(end 0.120396 0.3048)
			(stroke
				(width 0.1)
				(type default)
			)
			(layer "F.Fab")
		)
		(fp_line
			(start 0.120396 0.3048)
			(end 0.120396 0.2794)
			(stroke
				(width 0.1)
				(type default)
			)
			(layer "F.Fab")
		)
		(fp_line
			(start -0.12065 0.3048)
			(end -0.67945 0.3048)
			(stroke
				(width 0.1)
				(type default)
			)
			(layer "F.Fab")
		)
		(fp_line
			(start -0.67945 0.3048)
			(end -0.67945 -0.305054)
			(stroke
				(width 0.1)
				(type default)
			)
			(layer "F.Fab")
		)
		(pad "1" smd circle
			(at -0.40005 0 90)
			(size 0 0)
			(layers "F.Cu" "F.Mask" "F.Paste")
			(net "E1S_0_LED_ACT_R_N")
		)
		(pad "2" smd circle
			(at 0.40005 0 90)
			(size 0 0)
			(layers "F.Cu" "F.Mask" "F.Paste")
			(net "E1S_0_LED_ACT_N")
		)
	)
	(footprint ""
		(layer "F.Cu")
		(at 430.600104 -136.526778 180)
		(property "Reference" "R2596"
			(at 0 0 180)
			(layer "F.SilkS")
			(hide yes)
			(effects
				(font
					(size 1.27 1.27)
				)
			)
		)
		(property "Value" ""
			(at 0 0 180)
			(layer "F.Fab")
			(effects
				(font
					(size 1.27 1.27)
				)
			)
		)
		(duplicate_pad_numbers_are_jumpers no)
		(fp_line
			(start 0.7874 0.4064)
			(end -0.7874 0.4064)
			(stroke
				(width 0.1524)
				(type default)
			)
			(layer "F.SilkS")
		)
		(fp_line
			(start 0.7874 -0.4064)
			(end 0.7874 0.4064)
			(stroke
				(width 0.1524)
				(type default)
			)
			(layer "F.SilkS")
		)
		(fp_line
			(start -0.7874 0.4064)
			(end -0.7874 -0.4064)
			(stroke
				(width 0.1524)
				(type default)
			)
			(layer "F.SilkS")
		)
		(fp_line
			(start -0.7874 -0.4064)
			(end 0.7874 -0.4064)
			(stroke
				(width 0.1524)
				(type default)
			)
			(layer "F.SilkS")
		)
		(fp_line
			(start 0.67945 0.3048)
			(end 0.120396 0.3048)
			(stroke
				(width 0.1)
				(type default)
			)
			(layer "F.Fab")
		)
		(fp_line
			(start 0.67945 -0.3048)
			(end 0.67945 0.3048)
			(stroke
				(width 0.1)
				(type default)
			)
			(layer "F.Fab")
		)
		(fp_line
			(start 0.12065 -0.2794)
			(end 0.12065 -0.3048)
			(stroke
				(width 0.1)
				(type default)
			)
			(layer "F.Fab")
		)
		(fp_line
			(start 0.12065 -0.3048)
			(end 0.67945 -0.3048)
			(stroke
				(width 0.1)
				(type default)
			)
			(layer "F.Fab")
		)
		(fp_line
			(start 0.120396 0.3048)
			(end 0.120396 0.2794)
			(stroke
				(width 0.1)
				(type default)
			)
			(layer "F.Fab")
		)
		(fp_line
			(start 0.120396 0.2794)
			(end -0.12065 0.2794)
			(stroke
				(width 0.1)
				(type default)
			)
			(layer "F.Fab")
		)
		(fp_line
			(start -0.12065 0.3048)
			(end -0.67945 0.3048)
			(stroke
				(width 0.1)
				(type default)
			)
			(layer "F.Fab")
		)
		(fp_line
			(start -0.12065 0.2794)
			(end -0.12065 0.3048)
			(stroke
				(width 0.1)
				(type default)
			)
			(layer "F.Fab")
		)
		(fp_line
			(start -0.12065 -0.2794)
			(end 0.12065 -0.2794)
			(stroke
				(width 0.1)
				(type default)
			)
			(layer "F.Fab")
		)
		(fp_line
			(start -0.12065 -0.305054)
			(end -0.12065 -0.2794)
			(stroke
				(width 0.1)
				(type default)
			)
			(layer "F.Fab")
		)
		(fp_line
			(start -0.67945 0.3048)
			(end -0.67945 -0.305054)
			(stroke
				(width 0.1)
				(type default)
			)
			(layer "F.Fab")
		)
		(fp_line
			(start -0.67945 -0.305054)
			(end -0.12065 -0.305054)
			(stroke
				(width 0.1)
				(type default)
			)
			(layer "F.Fab")
		)
		(pad "1" smd circle
			(at -0.40005 0 180)
			(size 0 0)
			(layers "F.Cu" "F.Mask" "F.Paste")
			(net "SVID_CLK0_CPU0_R")
		)
		(pad "2" smd circle
			(at 0.40005 0 180)
			(size 0 0)
			(layers "F.Cu" "F.Mask" "F.Paste")
			(net "SVID_CLK_PVCCINFAON_CPU0_R")
		)
	)
	(footprint ""
		(layer "F.Cu")
		(at 116.367306 -29.450792)
		(property "Reference" "R3191"
			(at 0 0 0)
			(layer "F.SilkS")
			(hide yes)
			(effects
				(font
					(size 1.27 1.27)
				)
			)
		)
		(property "Value" ""
			(at 0 0 0)
			(layer "F.Fab")
			(effects
				(font
					(size 1.27 1.27)
				)
			)
		)
		(duplicate_pad_numbers_are_jumpers no)
		(fp_line
			(start -0.7874 -0.4064)
			(end 0.7874 -0.4064)
			(stroke
				(width 0.1524)
				(type default)
			)
			(layer "F.SilkS")
		)
		(fp_line
			(start -0.7874 0.4064)
			(end -0.7874 -0.4064)
			(stroke
				(width 0.1524)
				(type default)
			)
			(layer "F.SilkS")
		)
		(fp_line
			(start 0.7874 -0.4064)
			(end 0.7874 0.4064)
			(stroke
				(width 0.1524)
				(type default)
			)
			(layer "F.SilkS")
		)
		(fp_line
			(start 0.7874 0.4064)
			(end -0.7874 0.4064)
			(stroke
				(width 0.1524)
				(type default)
			)
			(layer "F.SilkS")
		)
		(fp_line
			(start -0.67945 -0.305054)
			(end -0.12065 -0.305054)
			(stroke
				(width 0.1)
				(type default)
			)
			(layer "F.Fab")
		)
		(fp_line
			(start -0.67945 0.3048)
			(end -0.67945 -0.305054)
			(stroke
				(width 0.1)
				(type default)
			)
			(layer "F.Fab")
		)
		(fp_line
			(start -0.12065 -0.305054)
			(end -0.12065 -0.2794)
			(stroke
				(width 0.1)
				(type default)
			)
			(layer "F.Fab")
		)
		(fp_line
			(start -0.12065 -0.2794)
			(end 0.12065 -0.2794)
			(stroke
				(width 0.1)
				(type default)
			)
			(layer "F.Fab")
		)
		(fp_line
			(start -0.12065 0.2794)
			(end -0.12065 0.3048)
			(stroke
				(width 0.1)
				(type default)
			)
			(layer "F.Fab")
		)
		(fp_line
			(start -0.12065 0.3048)
			(end -0.67945 0.3048)
			(stroke
				(width 0.1)
				(type default)
			)
			(layer "F.Fab")
		)
		(fp_line
			(start 0.120396 0.2794)
			(end -0.12065 0.2794)
			(stroke
				(width 0.1)
				(type default)
			)
			(layer "F.Fab")
		)
		(fp_line
			(start 0.120396 0.3048)
			(end 0.120396 0.2794)
			(stroke
				(width 0.1)
				(type default)
			)
			(layer "F.Fab")
		)
		(fp_line
			(start 0.12065 -0.3048)
			(end 0.67945 -0.3048)
			(stroke
				(width 0.1)
				(type default)
			)
			(layer "F.Fab")
		)
		(fp_line
			(start 0.12065 -0.2794)
			(end 0.12065 -0.3048)
			(stroke
				(width 0.1)
				(type default)
			)
			(layer "F.Fab")
		)
		(fp_line
			(start 0.67945 -0.3048)
			(end 0.67945 0.3048)
			(stroke
				(width 0.1)
				(type default)
			)
			(layer "F.Fab")
		)
		(fp_line
			(start 0.67945 0.3048)
			(end 0.120396 0.3048)
			(stroke
				(width 0.1)
				(type default)
			)
			(layer "F.Fab")
		)
		(pad "1" smd circle
			(at -0.40005 0)
			(size 0 0)
			(layers "F.Cu" "F.Mask" "F.Paste")
			(net "OCP_V3_2_PWRBRK_BUFF_N")
		)
		(pad "2" smd circle
			(at 0.40005 0)
			(size 0 0)
			(layers "F.Cu" "F.Mask" "F.Paste")
			(net "OCP_V3_2_PWRBRK_N")
		)
	)
	(footprint ""
		(layer "F.Cu")
		(at 445.157098 -93.484192 180)
		(property "Reference" "R3627"
			(at 0 0 180)
			(layer "F.SilkS")
			(hide yes)
			(effects
				(font
					(size 1.27 1.27)
				)
			)
		)
		(property "Value" ""
			(at 0 0 180)
			(layer "F.Fab")
			(effects
				(font
					(size 1.27 1.27)
				)
			)
		)
		(duplicate_pad_numbers_are_jumpers no)
		(fp_line
			(start 0.7874 0.4064)
			(end -0.7874 0.4064)
			(stroke
				(width 0.1524)
				(type default)
			)
			(layer "F.SilkS")
		)
		(fp_line
			(start 0.7874 -0.4064)
			(end 0.7874 0.4064)
			(stroke
				(width 0.1524)
				(type default)
			)
			(layer "F.SilkS")
		)
		(fp_line
			(start -0.7874 0.4064)
			(end -0.7874 -0.4064)
			(stroke
				(width 0.1524)
				(type default)
			)
			(layer "F.SilkS")
		)
		(fp_line
			(start -0.7874 -0.4064)
			(end 0.7874 -0.4064)
			(stroke
				(width 0.1524)
				(type default)
			)
			(layer "F.SilkS")
		)
		(fp_line
			(start 0.67945 0.3048)
			(end 0.120396 0.3048)
			(stroke
				(width 0.1)
				(type default)
			)
			(layer "F.Fab")
		)
		(fp_line
			(start 0.67945 -0.3048)
			(end 0.67945 0.3048)
			(stroke
				(width 0.1)
				(type default)
			)
			(layer "F.Fab")
		)
		(fp_line
			(start 0.12065 -0.2794)
			(end 0.12065 -0.3048)
			(stroke
				(width 0.1)
				(type default)
			)
			(layer "F.Fab")
		)
		(fp_line
			(start 0.12065 -0.3048)
			(end 0.67945 -0.3048)
			(stroke
				(width 0.1)
				(type default)
			)
			(layer "F.Fab")
		)
		(fp_line
			(start 0.120396 0.3048)
			(end 0.120396 0.2794)
			(stroke
				(width 0.1)
				(type default)
			)
			(layer "F.Fab")
		)
		(fp_line
			(start 0.120396 0.2794)
			(end -0.12065 0.2794)
			(stroke
				(width 0.1)
				(type default)
			)
			(layer "F.Fab")
		)
		(fp_line
			(start -0.12065 0.3048)
			(end -0.67945 0.3048)
			(stroke
				(width 0.1)
				(type default)
			)
			(layer "F.Fab")
		)
		(fp_line
			(start -0.12065 0.2794)
			(end -0.12065 0.3048)
			(stroke
				(width 0.1)
				(type default)
			)
			(layer "F.Fab")
		)
		(fp_line
			(start -0.12065 -0.2794)
			(end 0.12065 -0.2794)
			(stroke
				(width 0.1)
				(type default)
			)
			(layer "F.Fab")
		)
		(fp_line
			(start -0.12065 -0.305054)
			(end -0.12065 -0.2794)
			(stroke
				(width 0.1)
				(type default)
			)
			(layer "F.Fab")
		)
		(fp_line
			(start -0.67945 0.3048)
			(end -0.67945 -0.305054)
			(stroke
				(width 0.1)
				(type default)
			)
			(layer "F.Fab")
		)
		(fp_line
			(start -0.67945 -0.305054)
			(end -0.12065 -0.305054)
			(stroke
				(width 0.1)
				(type default)
			)
			(layer "F.Fab")
		)
		(pad "1" smd circle
			(at -0.40005 0 180)
			(size 0 0)
			(layers "F.Cu" "F.Mask" "F.Paste")
			(net "P3V3_AUX")
		)
		(pad "2" smd circle
			(at 0.40005 0 180)
			(size 0 0)
			(layers "F.Cu" "F.Mask" "F.Paste")
			(net "INA230_1_A0")
		)
	)
	(footprint ""
		(layer "F.Cu")
		(at 113.494312 -130.424682 180)
		(property "Reference" "R2967"
			(at 0 0 180)
			(layer "F.SilkS")
			(hide yes)
			(effects
				(font
					(size 1.27 1.27)
				)
			)
		)
		(property "Value" ""
			(at 0 0 180)
			(layer "F.Fab")
			(effects
				(font
					(size 1.27 1.27)
				)
			)
		)
		(duplicate_pad_numbers_are_jumpers no)
		(fp_line
			(start 0.7874 0.4064)
			(end -0.7874 0.4064)
			(stroke
				(width 0.1524)
				(type default)
			)
			(layer "F.SilkS")
		)
		(fp_line
			(start 0.7874 -0.4064)
			(end 0.7874 0.4064)
			(stroke
				(width 0.1524)
				(type default)
			)
			(layer "F.SilkS")
		)
		(fp_line
			(start -0.7874 0.4064)
			(end -0.7874 -0.4064)
			(stroke
				(width 0.1524)
				(type default)
			)
			(layer "F.SilkS")
		)
		(fp_line
			(start -0.7874 -0.4064)
			(end 0.7874 -0.4064)
			(stroke
				(width 0.1524)
				(type default)
			)
			(layer "F.SilkS")
		)
		(fp_line
			(start 0.67945 0.3048)
			(end 0.120396 0.3048)
			(stroke
				(width 0.1)
				(type default)
			)
			(layer "F.Fab")
		)
		(fp_line
			(start 0.67945 -0.3048)
			(end 0.67945 0.3048)
			(stroke
				(width 0.1)
				(type default)
			)
			(layer "F.Fab")
		)
		(fp_line
			(start 0.12065 -0.2794)
			(end 0.12065 -0.3048)
			(stroke
				(width 0.1)
				(type default)
			)
			(layer "F.Fab")
		)
		(fp_line
			(start 0.12065 -0.3048)
			(end 0.67945 -0.3048)
			(stroke
				(width 0.1)
				(type default)
			)
			(layer "F.Fab")
		)
		(fp_line
			(start 0.120396 0.3048)
			(end 0.120396 0.2794)
			(stroke
				(width 0.1)
				(type default)
			)
			(layer "F.Fab")
		)
		(fp_line
			(start 0.120396 0.2794)
			(end -0.12065 0.2794)
			(stroke
				(width 0.1)
				(type default)
			)
			(layer "F.Fab")
		)
		(fp_line
			(start -0.12065 0.3048)
			(end -0.67945 0.3048)
			(stroke
				(width 0.1)
				(type default)
			)
			(layer "F.Fab")
		)
		(fp_line
			(start -0.12065 0.2794)
			(end -0.12065 0.3048)
			(stroke
				(width 0.1)
				(type default)
			)
			(layer "F.Fab")
		)
		(fp_line
			(start -0.12065 -0.2794)
			(end 0.12065 -0.2794)
			(stroke
				(width 0.1)
				(type default)
			)
			(layer "F.Fab")
		)
		(fp_line
			(start -0.12065 -0.305054)
			(end -0.12065 -0.2794)
			(stroke
				(width 0.1)
				(type default)
			)
			(layer "F.Fab")
		)
		(fp_line
			(start -0.67945 0.3048)
			(end -0.67945 -0.305054)
			(stroke
				(width 0.1)
				(type default)
			)
			(layer "F.Fab")
		)
		(fp_line
			(start -0.67945 -0.305054)
			(end -0.12065 -0.305054)
			(stroke
				(width 0.1)
				(type default)
			)
			(layer "F.Fab")
		)
		(pad "1" smd circle
			(at -0.40005 0 180)
			(size 0 0)
			(layers "F.Cu" "F.Mask" "F.Paste")
			(net "SMB_PCIE0_3V3AUX_SCL_R3")
		)
		(pad "2" smd circle
			(at 0.40005 0 180)
			(size 0 0)
			(layers "F.Cu" "F.Mask" "F.Paste")
			(net "SMB_SENSOR_M2_P0_3V3AUX_SCL")
		)
	)
	(footprint ""
		(layer "F.Cu")
		(at 26.684478 -16.099536 90)
		(property "Reference" "C815"
			(at 0 0 90)
			(layer "F.SilkS")
			(hide yes)
			(effects
				(font
					(size 1.27 1.27)
				)
			)
		)
		(property "Value" ""
			(at 0 0 90)
			(layer "F.Fab")
			(effects
				(font
					(size 1.27 1.27)
				)
			)
		)
		(duplicate_pad_numbers_are_jumpers no)
		(fp_line
			(start 0.299974 -0.150114)
			(end 0.299974 0.150114)
			(stroke
				(width 0.1)
				(type default)
			)
			(layer "F.Fab")
		)
		(fp_line
			(start -0.299974 -0.150114)
			(end 0.299974 -0.150114)
			(stroke
				(width 0.1)
				(type default)
			)
			(layer "F.Fab")
		)
		(fp_line
			(start 0.299974 0.150114)
			(end -0.299974 0.150114)
			(stroke
				(width 0.1)
				(type default)
			)
			(layer "F.Fab")
		)
		(fp_line
			(start -0.299974 0.150114)
			(end -0.299974 -0.150114)
			(stroke
				(width 0.1)
				(type default)
			)
			(layer "F.Fab")
		)
		(pad "1" smd rect
			(at -0.2667 0 90)
			(size 0.3048 0.381)
			(layers "F.Cu" "F.Mask" "F.Paste")
			(net "P5E_CPU1_PE1_TX_C_DP<11>")
		)
		(pad "2" smd rect
			(at 0.2667 0 90)
			(size 0.3048 0.381)
			(layers "F.Cu" "F.Mask" "F.Paste")
			(net "P5E_CPU1_PE1_TX_DP<11>")
		)
	)
	(footprint ""
		(layer "F.Cu")
		(at 40.627554 -107.031282)
		(property "Reference" "R3681"
			(at 0 0 0)
			(layer "F.SilkS")
			(hide yes)
			(effects
				(font
					(size 1.27 1.27)
				)
			)
		)
		(property "Value" ""
			(at 0 0 0)
			(layer "F.Fab")
			(effects
				(font
					(size 1.27 1.27)
				)
			)
		)
		(duplicate_pad_numbers_are_jumpers no)
		(fp_line
			(start -0.7874 -0.4064)
			(end 0.7874 -0.4064)
			(stroke
				(width 0.1524)
				(type default)
			)
			(layer "F.SilkS")
		)
		(fp_line
			(start -0.7874 0.4064)
			(end -0.7874 -0.4064)
			(stroke
				(width 0.1524)
				(type default)
			)
			(layer "F.SilkS")
		)
		(fp_line
			(start 0.7874 -0.4064)
			(end 0.7874 0.4064)
			(stroke
				(width 0.1524)
				(type default)
			)
			(layer "F.SilkS")
		)
		(fp_line
			(start 0.7874 0.4064)
			(end -0.7874 0.4064)
			(stroke
				(width 0.1524)
				(type default)
			)
			(layer "F.SilkS")
		)
		(fp_line
			(start -0.67945 -0.305054)
			(end -0.12065 -0.305054)
			(stroke
				(width 0.1)
				(type default)
			)
			(layer "F.Fab")
		)
		(fp_line
			(start -0.67945 0.3048)
			(end -0.67945 -0.305054)
			(stroke
				(width 0.1)
				(type default)
			)
			(layer "F.Fab")
		)
		(fp_line
			(start -0.12065 -0.305054)
			(end -0.12065 -0.2794)
			(stroke
				(width 0.1)
				(type default)
			)
			(layer "F.Fab")
		)
		(fp_line
			(start -0.12065 -0.2794)
			(end 0.12065 -0.2794)
			(stroke
				(width 0.1)
				(type default)
			)
			(layer "F.Fab")
		)
		(fp_line
			(start -0.12065 0.2794)
			(end -0.12065 0.3048)
			(stroke
				(width 0.1)
				(type default)
			)
			(layer "F.Fab")
		)
		(fp_line
			(start -0.12065 0.3048)
			(end -0.67945 0.3048)
			(stroke
				(width 0.1)
				(type default)
			)
			(layer "F.Fab")
		)
		(fp_line
			(start 0.120396 0.2794)
			(end -0.12065 0.2794)
			(stroke
				(width 0.1)
				(type default)
			)
			(layer "F.Fab")
		)
		(fp_line
			(start 0.120396 0.3048)
			(end 0.120396 0.2794)
			(stroke
				(width 0.1)
				(type default)
			)
			(layer "F.Fab")
		)
		(fp_line
			(start 0.12065 -0.3048)
			(end 0.67945 -0.3048)
			(stroke
				(width 0.1)
				(type default)
			)
			(layer "F.Fab")
		)
		(fp_line
			(start 0.12065 -0.2794)
			(end 0.12065 -0.3048)
			(stroke
				(width 0.1)
				(type default)
			)
			(layer "F.Fab")
		)
		(fp_line
			(start 0.67945 -0.3048)
			(end 0.67945 0.3048)
			(stroke
				(width 0.1)
				(type default)
			)
			(layer "F.Fab")
		)
		(fp_line
			(start 0.67945 0.3048)
			(end 0.120396 0.3048)
			(stroke
				(width 0.1)
				(type default)
			)
			(layer "F.Fab")
		)
		(pad "1" smd rect
			(at -0.40005 0 180)
			(size 0.4572 0.508)
			(layers "F.Cu" "F.Mask" "F.Paste")
			(net "P3V3_AUX_ADC")
		)
		(pad "2" smd rect
			(at 0.40005 0 180)
			(size 0.4572 0.508)
			(layers "F.Cu" "F.Mask" "F.Paste")
			(net "P3V3_AUX_ADC_MAM")
		)
	)
	(footprint ""
		(layer "F.Cu")
		(at 424.511724 -149.239224 -90)
		(property "Reference" "PC180"
			(at 0 0 270)
			(layer "F.SilkS")
			(hide yes)
			(effects
				(font
					(size 1.27 1.27)
				)
			)
		)
		(property "Value" ""
			(at 0 0 270)
			(layer "F.Fab")
			(effects
				(font
					(size 1.27 1.27)
				)
			)
		)
		(duplicate_pad_numbers_are_jumpers no)
		(fp_line
			(start -1.524 0.762)
			(end -1.524 -0.762)
			(stroke
				(width 0.1524)
				(type default)
			)
			(layer "F.SilkS")
		)
		(fp_line
			(start 1.524 0.762)
			(end -1.524 0.762)
			(stroke
				(width 0.1524)
				(type default)
			)
			(layer "F.SilkS")
		)
		(fp_line
			(start -1.524 -0.762)
			(end 1.524 -0.762)
			(stroke
				(width 0.1524)
				(type default)
			)
			(layer "F.SilkS")
		)
		(fp_line
			(start 1.524 -0.762)
			(end 1.524 0.762)
			(stroke
				(width 0.1524)
				(type default)
			)
			(layer "F.SilkS")
		)
		(fp_line
			(start -1.1049 0.724916)
			(end 1.1049 0.724916)
			(stroke
				(width 0.1)
				(type default)
			)
			(layer "F.Fab")
		)
		(fp_line
			(start 1.1049 0.724916)
			(end 1.1049 -0.724916)
			(stroke
				(width 0.1)
				(type default)
			)
			(layer "F.Fab")
		)
		(fp_line
			(start -1.1049 -0.724916)
			(end -1.1049 0.724916)
			(stroke
				(width 0.1)
				(type default)
			)
			(layer "F.Fab")
		)
		(fp_line
			(start 1.1049 -0.724916)
			(end -1.1049 -0.724916)
			(stroke
				(width 0.1)
				(type default)
			)
			(layer "F.Fab")
		)
		(pad "1" smd rect
			(at -0.889 0 90)
			(size 1.016 1.27)
			(layers "F.Cu" "F.Mask" "F.Paste")
			(net "SW_P12V_PVCCINFAON_CPU0_FLT")
		)
		(pad "2" smd rect
			(at 0.889 0 90)
			(size 1.016 1.27)
			(layers "F.Cu" "F.Mask" "F.Paste")
			(net "GND")
		)
	)
	(footprint ""
		(layer "F.Cu")
		(at 191.295782 -29.283152 180)
		(property "Reference" "PC2236"
			(at 0 0 180)
			(layer "F.SilkS")
			(hide yes)
			(effects
				(font
					(size 1.27 1.27)
				)
			)
		)
		(property "Value" ""
			(at 0 0 180)
			(layer "F.Fab")
			(effects
				(font
					(size 1.27 1.27)
				)
			)
		)
		(duplicate_pad_numbers_are_jumpers no)
		(fp_line
			(start 0.7874 0.4064)
			(end -0.7874 0.4064)
			(stroke
				(width 0.1524)
				(type default)
			)
			(layer "F.SilkS")
		)
		(fp_line
			(start 0.7874 -0.4064)
			(end 0.7874 0.4064)
			(stroke
				(width 0.1524)
				(type default)
			)
			(layer "F.SilkS")
		)
		(fp_line
			(start -0.7874 0.4064)
			(end -0.7874 -0.4064)
			(stroke
				(width 0.1524)
				(type default)
			)
			(layer "F.SilkS")
		)
		(fp_line
			(start -0.7874 -0.4064)
			(end 0.7874 -0.4064)
			(stroke
				(width 0.1524)
				(type default)
			)
			(layer "F.SilkS")
		)
		(fp_line
			(start 0.67945 0.3048)
			(end 0.120396 0.3048)
			(stroke
				(width 0.1)
				(type default)
			)
			(layer "F.Fab")
		)
		(fp_line
			(start 0.67945 -0.3048)
			(end 0.67945 0.3048)
			(stroke
				(width 0.1)
				(type default)
			)
			(layer "F.Fab")
		)
		(fp_line
			(start 0.12065 -0.2794)
			(end 0.12065 -0.3048)
			(stroke
				(width 0.1)
				(type default)
			)
			(layer "F.Fab")
		)
		(fp_line
			(start 0.12065 -0.3048)
			(end 0.67945 -0.3048)
			(stroke
				(width 0.1)
				(type default)
			)
			(layer "F.Fab")
		)
		(fp_line
			(start 0.120396 0.3048)
			(end 0.120396 0.2794)
			(stroke
				(width 0.1)
				(type default)
			)
			(layer "F.Fab")
		)
		(fp_line
			(start 0.120396 0.2794)
			(end -0.12065 0.2794)
			(stroke
				(width 0.1)
				(type default)
			)
			(layer "F.Fab")
		)
		(fp_line
			(start -0.12065 0.3048)
			(end -0.67945 0.3048)
			(stroke
				(width 0.1)
				(type default)
			)
			(layer "F.Fab")
		)
		(fp_line
			(start -0.12065 0.2794)
			(end -0.12065 0.3048)
			(stroke
				(width 0.1)
				(type default)
			)
			(layer "F.Fab")
		)
		(fp_line
			(start -0.12065 -0.2794)
			(end 0.12065 -0.2794)
			(stroke
				(width 0.1)
				(type default)
			)
			(layer "F.Fab")
		)
		(fp_line
			(start -0.12065 -0.305054)
			(end -0.12065 -0.2794)
			(stroke
				(width 0.1)
				(type default)
			)
			(layer "F.Fab")
		)
		(fp_line
			(start -0.67945 0.3048)
			(end -0.67945 -0.305054)
			(stroke
				(width 0.1)
				(type default)
			)
			(layer "F.Fab")
		)
		(fp_line
			(start -0.67945 -0.305054)
			(end -0.12065 -0.305054)
			(stroke
				(width 0.1)
				(type default)
			)
			(layer "F.Fab")
		)
		(pad "1" smd circle
			(at -0.40005 0 180)
			(size 0 0)
			(layers "F.Cu" "F.Mask" "F.Paste")
			(net "P12V_SCM_R")
		)
		(pad "2" smd circle
			(at 0.40005 0 180)
			(size 0 0)
			(layers "F.Cu" "F.Mask" "F.Paste")
			(net "P12V_SCM_GATE")
		)
	)
	(footprint ""
		(layer "F.Cu")
		(at 260.593332 -92.497656 90)
		(property "Reference" "R3639"
			(at 0 0 90)
			(layer "F.SilkS")
			(hide yes)
			(effects
				(font
					(size 1.27 1.27)
				)
			)
		)
		(property "Value" ""
			(at 0 0 90)
			(layer "F.Fab")
			(effects
				(font
					(size 1.27 1.27)
				)
			)
		)
		(duplicate_pad_numbers_are_jumpers no)
		(fp_line
			(start 0.7874 -0.4064)
			(end 0.7874 0.4064)
			(stroke
				(width 0.1524)
				(type default)
			)
			(layer "F.SilkS")
		)
		(fp_line
			(start -0.7874 -0.4064)
			(end 0.7874 -0.4064)
			(stroke
				(width 0.1524)
				(type default)
			)
			(layer "F.SilkS")
		)
		(fp_line
			(start 0.7874 0.4064)
			(end -0.7874 0.4064)
			(stroke
				(width 0.1524)
				(type default)
			)
			(layer "F.SilkS")
		)
		(fp_line
			(start -0.7874 0.4064)
			(end -0.7874 -0.4064)
			(stroke
				(width 0.1524)
				(type default)
			)
			(layer "F.SilkS")
		)
		(fp_line
			(start -0.12065 -0.305054)
			(end -0.12065 -0.2794)
			(stroke
				(width 0.1)
				(type default)
			)
			(layer "F.Fab")
		)
		(fp_line
			(start -0.67945 -0.305054)
			(end -0.12065 -0.305054)
			(stroke
				(width 0.1)
				(type default)
			)
			(layer "F.Fab")
		)
		(fp_line
			(start 0.67945 -0.3048)
			(end 0.67945 0.3048)
			(stroke
				(width 0.1)
				(type default)
			)
			(layer "F.Fab")
		)
		(fp_line
			(start 0.12065 -0.3048)
			(end 0.67945 -0.3048)
			(stroke
				(width 0.1)
				(type default)
			)
			(layer "F.Fab")
		)
		(fp_line
			(start 0.12065 -0.2794)
			(end 0.12065 -0.3048)
			(stroke
				(width 0.1)
				(type default)
			)
			(layer "F.Fab")
		)
		(fp_line
			(start -0.12065 -0.2794)
			(end 0.12065 -0.2794)
			(stroke
				(width 0.1)
				(type default)
			)
			(layer "F.Fab")
		)
		(fp_line
			(start 0.120396 0.2794)
			(end -0.12065 0.2794)
			(stroke
				(width 0.1)
				(type default)
			)
			(layer "F.Fab")
		)
		(fp_line
			(start -0.12065 0.2794)
			(end -0.12065 0.3048)
			(stroke
				(width 0.1)
				(type default)
			)
			(layer "F.Fab")
		)
		(fp_line
			(start 0.67945 0.3048)
			(end 0.120396 0.3048)
			(stroke
				(width 0.1)
				(type default)
			)
			(layer "F.Fab")
		)
		(fp_line
			(start 0.120396 0.3048)
			(end 0.120396 0.2794)
			(stroke
				(width 0.1)
				(type default)
			)
			(layer "F.Fab")
		)
		(fp_line
			(start -0.12065 0.3048)
			(end -0.67945 0.3048)
			(stroke
				(width 0.1)
				(type default)
			)
			(layer "F.Fab")
		)
		(fp_line
			(start -0.67945 0.3048)
			(end -0.67945 -0.305054)
			(stroke
				(width 0.1)
				(type default)
			)
			(layer "F.Fab")
		)
		(pad "1" smd circle
			(at -0.40005 0 90)
			(size 0 0)
			(layers "F.Cu" "F.Mask" "F.Paste")
			(net "P3V3_AUX")
		)
		(pad "2" smd circle
			(at 0.40005 0 90)
			(size 0 0)
			(layers "F.Cu" "F.Mask" "F.Paste")
			(net "CK440Q_OE_2")
		)
	)
	(footprint ""
		(layer "F.Cu")
		(at 277.859744 -407.401776 -90)
		(property "Reference" "PR3"
			(at 0 0 270)
			(layer "F.SilkS")
			(hide yes)
			(effects
				(font
					(size 1.27 1.27)
				)
			)
		)
		(property "Value" ""
			(at 0 0 270)
			(layer "F.Fab")
			(effects
				(font
					(size 1.27 1.27)
				)
			)
		)
		(duplicate_pad_numbers_are_jumpers no)
		(fp_line
			(start -4.0386 1.7526)
			(end -4.0386 -1.7526)
			(stroke
				(width 0.1524)
				(type default)
			)
			(layer "F.SilkS")
		)
		(fp_line
			(start 4.0386 1.7526)
			(end -4.0386 1.7526)
			(stroke
				(width 0.1524)
				(type default)
			)
			(layer "F.SilkS")
		)
		(fp_line
			(start -4.0386 -1.7526)
			(end 4.0386 -1.7526)
			(stroke
				(width 0.1524)
				(type default)
			)
			(layer "F.SilkS")
		)
		(fp_line
			(start 4.0386 -1.7526)
			(end 4.0386 1.7526)
			(stroke
				(width 0.1524)
				(type default)
			)
			(layer "F.SilkS")
		)
		(fp_line
			(start -4.0386 1.7526)
			(end -4.0386 -1.7526)
			(stroke
				(width 0.1)
				(type default)
			)
			(layer "F.Fab")
		)
		(fp_line
			(start 4.0386 1.7526)
			(end -4.0386 1.7526)
			(stroke
				(width 0.1)
				(type default)
			)
			(layer "F.Fab")
		)
		(fp_line
			(start -4.0386 -1.7526)
			(end 4.0386 -1.7526)
			(stroke
				(width 0.1)
				(type default)
			)
			(layer "F.Fab")
		)
		(fp_line
			(start 4.0386 -1.7526)
			(end 4.0386 1.7526)
			(stroke
				(width 0.1)
				(type default)
			)
			(layer "F.Fab")
		)
		(pad "1" smd circle
			(at -3.700018 0 180)
			(size 0 0)
			(layers "F.Cu" "F.Mask" "F.Paste")
			(net "P12V_PSU")
		)
		(pad "2" smd circle
			(at 3.700018 0)
			(size 0 0)
			(layers "F.Cu" "F.Mask" "F.Paste")
			(net "P12V_MAIN_R_0")
		)
		(pad "3" smd rect
			(at -2.70002 0)
			(size 0.4064 1.1176)
			(layers "F.Cu" "F.Mask" "F.Paste")
			(net "P12V_HSC_SENSE1_P")
		)
		(pad "4" smd rect
			(at 2.70002 0)
			(size 0.4064 1.1176)
			(layers "F.Cu" "F.Mask" "F.Paste")
			(net "P12V_HSC_SENSE1_N")
		)
	)
	(footprint ""
		(layer "F.Cu")
		(at 463.90687 -68.519802 90)
		(property "Reference" "PC3"
			(at 0 0 90)
			(layer "F.SilkS")
			(hide yes)
			(effects
				(font
					(size 1.27 1.27)
				)
			)
		)
		(property "Value" ""
			(at 0 0 90)
			(layer "F.Fab")
			(effects
				(font
					(size 1.27 1.27)
				)
			)
		)
		(duplicate_pad_numbers_are_jumpers no)
		(fp_line
			(start -3.400044 1.249934)
			(end 3.400044 1.249934)
			(stroke
				(width 0.1524)
				(type default)
			)
			(layer "F.SilkS")
		)
		(fp_circle
			(center 0 1.249934)
			(end 0 4.649978)
			(stroke
				(width 0.1524)
				(type default)
			)
			(fill no)
			(layer "F.SilkS")
		)
		(fp_poly
			(pts
				(arc
					(start -3.400044 1.249934)
					(mid 0 4.649978)
					(end 3.400044 1.249934)
				)
			)
			(stroke
				(width 0)
				(type default)
			)
			(fill yes)
			(layer "F.SilkS")
		)
		(fp_circle
			(center 0 1.249934)
			(end 0 4.649978)
			(stroke
				(width 0.1)
				(type default)
			)
			(fill no)
			(layer "F.Fab")
		)
		(pad "1" thru_hole rect
			(at 0 0 90)
			(size 1.524 1.524)
			(drill 1.016)
			(layers "*.Cu" "*.Mask")
			(remove_unused_layers no)
			(net "SW_P3V3_AUX_FLT")
			(clearance 0)
			(padstack
				(mode front_inner_back)
				(layer "Inner"
					(shape circle)
					(size 1.524 1.524)
					(clearance 0)
				)
				(layer "B.Cu"
					(shape rect)
					(size 1.524 1.524)
					(clearance 0)
				)
			)
		)
		(pad "2" thru_hole circle
			(at 0 2.500122 90)
			(size 1.524 1.524)
			(drill 1.016)
			(layers "*.Cu" "*.Mask")
			(remove_unused_layers no)
			(net "GND")
			(clearance 0)
		)
	)
	(footprint ""
		(layer "F.Cu")
		(at 103.306372 -362.602526)
		(property "Reference" "R2520"
			(at 0 0 0)
			(layer "F.SilkS")
			(hide yes)
			(effects
				(font
					(size 1.27 1.27)
				)
			)
		)
		(property "Value" ""
			(at 0 0 0)
			(layer "F.Fab")
			(effects
				(font
					(size 1.27 1.27)
				)
			)
		)
		(duplicate_pad_numbers_are_jumpers no)
		(fp_line
			(start -0.7874 -0.4064)
			(end 0.7874 -0.4064)
			(stroke
				(width 0.1524)
				(type default)
			)
			(layer "F.SilkS")
		)
		(fp_line
			(start -0.7874 0.4064)
			(end -0.7874 -0.4064)
			(stroke
				(width 0.1524)
				(type default)
			)
			(layer "F.SilkS")
		)
		(fp_line
			(start 0.7874 -0.4064)
			(end 0.7874 0.4064)
			(stroke
				(width 0.1524)
				(type default)
			)
			(layer "F.SilkS")
		)
		(fp_line
			(start 0.7874 0.4064)
			(end -0.7874 0.4064)
			(stroke
				(width 0.1524)
				(type default)
			)
			(layer "F.SilkS")
		)
		(fp_line
			(start -0.67945 -0.305054)
			(end -0.12065 -0.305054)
			(stroke
				(width 0.1)
				(type default)
			)
			(layer "F.Fab")
		)
		(fp_line
			(start -0.67945 0.3048)
			(end -0.67945 -0.305054)
			(stroke
				(width 0.1)
				(type default)
			)
			(layer "F.Fab")
		)
		(fp_line
			(start -0.12065 -0.305054)
			(end -0.12065 -0.2794)
			(stroke
				(width 0.1)
				(type default)
			)
			(layer "F.Fab")
		)
		(fp_line
			(start -0.12065 -0.2794)
			(end 0.12065 -0.2794)
			(stroke
				(width 0.1)
				(type default)
			)
			(layer "F.Fab")
		)
		(fp_line
			(start -0.12065 0.2794)
			(end -0.12065 0.3048)
			(stroke
				(width 0.1)
				(type default)
			)
			(layer "F.Fab")
		)
		(fp_line
			(start -0.12065 0.3048)
			(end -0.67945 0.3048)
			(stroke
				(width 0.1)
				(type default)
			)
			(layer "F.Fab")
		)
		(fp_line
			(start 0.120396 0.2794)
			(end -0.12065 0.2794)
			(stroke
				(width 0.1)
				(type default)
			)
			(layer "F.Fab")
		)
		(fp_line
			(start 0.120396 0.3048)
			(end 0.120396 0.2794)
			(stroke
				(width 0.1)
				(type default)
			)
			(layer "F.Fab")
		)
		(fp_line
			(start 0.12065 -0.3048)
			(end 0.67945 -0.3048)
			(stroke
				(width 0.1)
				(type default)
			)
			(layer "F.Fab")
		)
		(fp_line
			(start 0.12065 -0.2794)
			(end 0.12065 -0.3048)
			(stroke
				(width 0.1)
				(type default)
			)
			(layer "F.Fab")
		)
		(fp_line
			(start 0.67945 -0.3048)
			(end 0.67945 0.3048)
			(stroke
				(width 0.1)
				(type default)
			)
			(layer "F.Fab")
		)
		(fp_line
			(start 0.67945 0.3048)
			(end 0.120396 0.3048)
			(stroke
				(width 0.1)
				(type default)
			)
			(layer "F.Fab")
		)
		(pad "1" smd circle
			(at -0.40005 0)
			(size 0 0)
			(layers "F.Cu" "F.Mask" "F.Paste")
			(net "SMB_VR_3V3AUX_SCL_R3")
		)
		(pad "2" smd circle
			(at 0.40005 0)
			(size 0 0)
			(layers "F.Cu" "F.Mask" "F.Paste")
			(net "SMB_CLK_PVCCIN_CPU1")
		)
	)
	(footprint ""
		(layer "F.Cu")
		(at 104.349804 -245.634256 -90)
		(property "Reference" "C423"
			(at 0 0 270)
			(layer "F.SilkS")
			(hide yes)
			(effects
				(font
					(size 1.27 1.27)
				)
			)
		)
		(property "Value" ""
			(at 0 0 270)
			(layer "F.Fab")
			(effects
				(font
					(size 1.27 1.27)
				)
			)
		)
		(duplicate_pad_numbers_are_jumpers no)
		(fp_line
			(start -0.7874 0.4064)
			(end -0.7874 -0.4064)
			(stroke
				(width 0.1524)
				(type default)
			)
			(layer "F.SilkS")
		)
		(fp_line
			(start 0.7874 0.4064)
			(end -0.7874 0.4064)
			(stroke
				(width 0.1524)
				(type default)
			)
			(layer "F.SilkS")
		)
		(fp_line
			(start -0.7874 -0.4064)
			(end 0.7874 -0.4064)
			(stroke
				(width 0.1524)
				(type default)
			)
			(layer "F.SilkS")
		)
		(fp_line
			(start 0.7874 -0.4064)
			(end 0.7874 0.4064)
			(stroke
				(width 0.1524)
				(type default)
			)
			(layer "F.SilkS")
		)
		(fp_line
			(start -0.67945 0.3048)
			(end -0.67945 -0.305054)
			(stroke
				(width 0.1)
				(type default)
			)
			(layer "F.Fab")
		)
		(fp_line
			(start -0.12065 0.3048)
			(end -0.67945 0.3048)
			(stroke
				(width 0.1)
				(type default)
			)
			(layer "F.Fab")
		)
		(fp_line
			(start 0.120396 0.3048)
			(end 0.120396 0.2794)
			(stroke
				(width 0.1)
				(type default)
			)
			(layer "F.Fab")
		)
		(fp_line
			(start 0.67945 0.3048)
			(end 0.120396 0.3048)
			(stroke
				(width 0.1)
				(type default)
			)
			(layer "F.Fab")
		)
		(fp_line
			(start -0.12065 0.2794)
			(end -0.12065 0.3048)
			(stroke
				(width 0.1)
				(type default)
			)
			(layer "F.Fab")
		)
		(fp_line
			(start 0.120396 0.2794)
			(end -0.12065 0.2794)
			(stroke
				(width 0.1)
				(type default)
			)
			(layer "F.Fab")
		)
		(fp_line
			(start -0.12065 -0.2794)
			(end 0.12065 -0.2794)
			(stroke
				(width 0.1)
				(type default)
			)
			(layer "F.Fab")
		)
		(fp_line
			(start 0.12065 -0.2794)
			(end 0.12065 -0.3048)
			(stroke
				(width 0.1)
				(type default)
			)
			(layer "F.Fab")
		)
		(fp_line
			(start 0.12065 -0.3048)
			(end 0.67945 -0.3048)
			(stroke
				(width 0.1)
				(type default)
			)
			(layer "F.Fab")
		)
		(fp_line
			(start 0.67945 -0.3048)
			(end 0.67945 0.3048)
			(stroke
				(width 0.1)
				(type default)
			)
			(layer "F.Fab")
		)
		(fp_line
			(start -0.67945 -0.305054)
			(end -0.12065 -0.305054)
			(stroke
				(width 0.1)
				(type default)
			)
			(layer "F.Fab")
		)
		(fp_line
			(start -0.12065 -0.305054)
			(end -0.12065 -0.2794)
			(stroke
				(width 0.1)
				(type default)
			)
			(layer "F.Fab")
		)
		(pad "1" smd circle
			(at -0.40005 0 270)
			(size 0 0)
			(layers "F.Cu" "F.Mask" "F.Paste")
			(net "PVCCD_HV_CPU1")
		)
		(pad "2" smd circle
			(at 0.40005 0 270)
			(size 0 0)
			(layers "F.Cu" "F.Mask" "F.Paste")
			(net "GND")
		)
	)
	(footprint ""
		(layer "F.Cu")
		(at 336.319622 -63.363348 -90)
		(property "Reference" "R1720"
			(at 0 0 270)
			(layer "F.SilkS")
			(hide yes)
			(effects
				(font
					(size 1.27 1.27)
				)
			)
		)
		(property "Value" ""
			(at 0 0 270)
			(layer "F.Fab")
			(effects
				(font
					(size 1.27 1.27)
				)
			)
		)
		(duplicate_pad_numbers_are_jumpers no)
		(fp_line
			(start -0.7874 0.4064)
			(end -0.7874 -0.4064)
			(stroke
				(width 0.1524)
				(type default)
			)
			(layer "F.SilkS")
		)
		(fp_line
			(start 0.7874 0.4064)
			(end -0.7874 0.4064)
			(stroke
				(width 0.1524)
				(type default)
			)
			(layer "F.SilkS")
		)
		(fp_line
			(start -0.7874 -0.4064)
			(end 0.7874 -0.4064)
			(stroke
				(width 0.1524)
				(type default)
			)
			(layer "F.SilkS")
		)
		(fp_line
			(start 0.7874 -0.4064)
			(end 0.7874 0.4064)
			(stroke
				(width 0.1524)
				(type default)
			)
			(layer "F.SilkS")
		)
		(fp_line
			(start -0.67945 0.3048)
			(end -0.67945 -0.305054)
			(stroke
				(width 0.1)
				(type default)
			)
			(layer "F.Fab")
		)
		(fp_line
			(start -0.12065 0.3048)
			(end -0.67945 0.3048)
			(stroke
				(width 0.1)
				(type default)
			)
			(layer "F.Fab")
		)
		(fp_line
			(start 0.120396 0.3048)
			(end 0.120396 0.2794)
			(stroke
				(width 0.1)
				(type default)
			)
			(layer "F.Fab")
		)
		(fp_line
			(start 0.67945 0.3048)
			(end 0.120396 0.3048)
			(stroke
				(width 0.1)
				(type default)
			)
			(layer "F.Fab")
		)
		(fp_line
			(start -0.12065 0.2794)
			(end -0.12065 0.3048)
			(stroke
				(width 0.1)
				(type default)
			)
			(layer "F.Fab")
		)
		(fp_line
			(start 0.120396 0.2794)
			(end -0.12065 0.2794)
			(stroke
				(width 0.1)
				(type default)
			)
			(layer "F.Fab")
		)
		(fp_line
			(start -0.12065 -0.2794)
			(end 0.12065 -0.2794)
			(stroke
				(width 0.1)
				(type default)
			)
			(layer "F.Fab")
		)
		(fp_line
			(start 0.12065 -0.2794)
			(end 0.12065 -0.3048)
			(stroke
				(width 0.1)
				(type default)
			)
			(layer "F.Fab")
		)
		(fp_line
			(start 0.12065 -0.3048)
			(end 0.67945 -0.3048)
			(stroke
				(width 0.1)
				(type default)
			)
			(layer "F.Fab")
		)
		(fp_line
			(start 0.67945 -0.3048)
			(end 0.67945 0.3048)
			(stroke
				(width 0.1)
				(type default)
			)
			(layer "F.Fab")
		)
		(fp_line
			(start -0.67945 -0.305054)
			(end -0.12065 -0.305054)
			(stroke
				(width 0.1)
				(type default)
			)
			(layer "F.Fab")
		)
		(fp_line
			(start -0.12065 -0.305054)
			(end -0.12065 -0.2794)
			(stroke
				(width 0.1)
				(type default)
			)
			(layer "F.Fab")
		)
		(pad "1" smd circle
			(at -0.40005 0 270)
			(size 0 0)
			(layers "F.Cu" "F.Mask" "F.Paste")
			(net "XTAL_PCH_25M_IN_R")
		)
		(pad "2" smd circle
			(at 0.40005 0 270)
			(size 0 0)
			(layers "F.Cu" "F.Mask" "F.Paste")
			(net "XTAL_PCH_25M_IN")
		)
	)
	(footprint ""
		(layer "F.Cu")
		(at 125.26772 -164.447728)
		(property "Reference" ""
			(at 0 0 0)
			(layer "F.SilkS")
			(hide yes)
			(effects
				(font
					(size 1.27 1.27)
				)
			)
		)
		(property "Value" ""
			(at 0 0 0)
			(layer "F.Fab")
			(effects
				(font
					(size 1.27 1.27)
				)
			)
		)
		(duplicate_pad_numbers_are_jumpers no)
		(pad "1" smd circle
			(at 0 0)
			(size 0.9906 0.9906)
			(layers "F.Cu" "F.Mask" "F.Paste")
			(net "Net_290")
		)
		(zone
			(layer "F.Cu")
			(hatch none 0.5)
			(connect_pads
				(clearance 0)
			)
			(min_thickness 0.25)
			(keepout
				(tracks not_allowed)
				(vias allowed)
				(pads allowed)
				(copperpour not_allowed)
				(footprints allowed)
			)
			(placement
				(enabled no)
				(sheetname "")
			)
			(fill
				(thermal_gap 0.5)
				(thermal_bridge_width 0.5)
				(island_removal_mode 0)
			)
			(polygon
				(pts
					(arc
						(start 126.89332 -164.447728)
						(mid 123.64212 -164.447728)
						(end 126.89332 -164.447728)
					)
				)
			)
		)
	)
	(footprint ""
		(layer "F.Cu")
		(at 27.628596 -396.390876)
		(property "Reference" "R3281"
			(at 0 0 0)
			(layer "F.SilkS")
			(hide yes)
			(effects
				(font
					(size 1.27 1.27)
				)
			)
		)
		(property "Value" ""
			(at 0 0 0)
			(layer "F.Fab")
			(effects
				(font
					(size 1.27 1.27)
				)
			)
		)
		(duplicate_pad_numbers_are_jumpers no)
		(fp_line
			(start -0.7874 -0.4064)
			(end 0.7874 -0.4064)
			(stroke
				(width 0.1524)
				(type default)
			)
			(layer "F.SilkS")
		)
		(fp_line
			(start -0.7874 0.4064)
			(end -0.7874 -0.4064)
			(stroke
				(width 0.1524)
				(type default)
			)
			(layer "F.SilkS")
		)
		(fp_line
			(start 0.7874 -0.4064)
			(end 0.7874 0.4064)
			(stroke
				(width 0.1524)
				(type default)
			)
			(layer "F.SilkS")
		)
		(fp_line
			(start 0.7874 0.4064)
			(end -0.7874 0.4064)
			(stroke
				(width 0.1524)
				(type default)
			)
			(layer "F.SilkS")
		)
		(fp_line
			(start -0.67945 -0.305054)
			(end -0.12065 -0.305054)
			(stroke
				(width 0.1)
				(type default)
			)
			(layer "F.Fab")
		)
		(fp_line
			(start -0.67945 0.3048)
			(end -0.67945 -0.305054)
			(stroke
				(width 0.1)
				(type default)
			)
			(layer "F.Fab")
		)
		(fp_line
			(start -0.12065 -0.305054)
			(end -0.12065 -0.2794)
			(stroke
				(width 0.1)
				(type default)
			)
			(layer "F.Fab")
		)
		(fp_line
			(start -0.12065 -0.2794)
			(end 0.12065 -0.2794)
			(stroke
				(width 0.1)
				(type default)
			)
			(layer "F.Fab")
		)
		(fp_line
			(start -0.12065 0.2794)
			(end -0.12065 0.3048)
			(stroke
				(width 0.1)
				(type default)
			)
			(layer "F.Fab")
		)
		(fp_line
			(start -0.12065 0.3048)
			(end -0.67945 0.3048)
			(stroke
				(width 0.1)
				(type default)
			)
			(layer "F.Fab")
		)
		(fp_line
			(start 0.120396 0.2794)
			(end -0.12065 0.2794)
			(stroke
				(width 0.1)
				(type default)
			)
			(layer "F.Fab")
		)
		(fp_line
			(start 0.120396 0.3048)
			(end 0.120396 0.2794)
			(stroke
				(width 0.1)
				(type default)
			)
			(layer "F.Fab")
		)
		(fp_line
			(start 0.12065 -0.3048)
			(end 0.67945 -0.3048)
			(stroke
				(width 0.1)
				(type default)
			)
			(layer "F.Fab")
		)
		(fp_line
			(start 0.12065 -0.2794)
			(end 0.12065 -0.3048)
			(stroke
				(width 0.1)
				(type default)
			)
			(layer "F.Fab")
		)
		(fp_line
			(start 0.67945 -0.3048)
			(end 0.67945 0.3048)
			(stroke
				(width 0.1)
				(type default)
			)
			(layer "F.Fab")
		)
		(fp_line
			(start 0.67945 0.3048)
			(end 0.120396 0.3048)
			(stroke
				(width 0.1)
				(type default)
			)
			(layer "F.Fab")
		)
		(pad "1" smd circle
			(at -0.40005 0)
			(size 0 0)
			(layers "F.Cu" "F.Mask" "F.Paste")
			(net "FM_P2E_EQB1")
		)
		(pad "2" smd circle
			(at 0.40005 0)
			(size 0 0)
			(layers "F.Cu" "F.Mask" "F.Paste")
			(net "GND")
		)
	)
	(footprint ""
		(layer "F.Cu")
		(at 395.550898 -160.13049 90)
		(property "Reference" "C567"
			(at 0 0 90)
			(layer "F.SilkS")
			(hide yes)
			(effects
				(font
					(size 1.27 1.27)
				)
			)
		)
		(property "Value" ""
			(at 0 0 90)
			(layer "F.Fab")
			(effects
				(font
					(size 1.27 1.27)
				)
			)
		)
		(duplicate_pad_numbers_are_jumpers no)
		(fp_line
			(start 0.7874 -0.4064)
			(end 0.7874 0.4064)
			(stroke
				(width 0.1524)
				(type default)
			)
			(layer "F.SilkS")
		)
		(fp_line
			(start -0.7874 -0.4064)
			(end 0.7874 -0.4064)
			(stroke
				(width 0.1524)
				(type default)
			)
			(layer "F.SilkS")
		)
		(fp_line
			(start 0.7874 0.4064)
			(end -0.7874 0.4064)
			(stroke
				(width 0.1524)
				(type default)
			)
			(layer "F.SilkS")
		)
		(fp_line
			(start -0.7874 0.4064)
			(end -0.7874 -0.4064)
			(stroke
				(width 0.1524)
				(type default)
			)
			(layer "F.SilkS")
		)
		(fp_line
			(start -0.12065 -0.305054)
			(end -0.12065 -0.2794)
			(stroke
				(width 0.1)
				(type default)
			)
			(layer "F.Fab")
		)
		(fp_line
			(start -0.67945 -0.305054)
			(end -0.12065 -0.305054)
			(stroke
				(width 0.1)
				(type default)
			)
			(layer "F.Fab")
		)
		(fp_line
			(start 0.67945 -0.3048)
			(end 0.67945 0.3048)
			(stroke
				(width 0.1)
				(type default)
			)
			(layer "F.Fab")
		)
		(fp_line
			(start 0.12065 -0.3048)
			(end 0.67945 -0.3048)
			(stroke
				(width 0.1)
				(type default)
			)
			(layer "F.Fab")
		)
		(fp_line
			(start 0.12065 -0.2794)
			(end 0.12065 -0.3048)
			(stroke
				(width 0.1)
				(type default)
			)
			(layer "F.Fab")
		)
		(fp_line
			(start -0.12065 -0.2794)
			(end 0.12065 -0.2794)
			(stroke
				(width 0.1)
				(type default)
			)
			(layer "F.Fab")
		)
		(fp_line
			(start 0.120396 0.2794)
			(end -0.12065 0.2794)
			(stroke
				(width 0.1)
				(type default)
			)
			(layer "F.Fab")
		)
		(fp_line
			(start -0.12065 0.2794)
			(end -0.12065 0.3048)
			(stroke
				(width 0.1)
				(type default)
			)
			(layer "F.Fab")
		)
		(fp_line
			(start 0.67945 0.3048)
			(end 0.120396 0.3048)
			(stroke
				(width 0.1)
				(type default)
			)
			(layer "F.Fab")
		)
		(fp_line
			(start 0.120396 0.3048)
			(end 0.120396 0.2794)
			(stroke
				(width 0.1)
				(type default)
			)
			(layer "F.Fab")
		)
		(fp_line
			(start -0.12065 0.3048)
			(end -0.67945 0.3048)
			(stroke
				(width 0.1)
				(type default)
			)
			(layer "F.Fab")
		)
		(fp_line
			(start -0.67945 0.3048)
			(end -0.67945 -0.305054)
			(stroke
				(width 0.1)
				(type default)
			)
			(layer "F.Fab")
		)
		(pad "1" smd circle
			(at -0.40005 0 90)
			(size 0 0)
			(layers "F.Cu" "F.Mask" "F.Paste")
			(net "PVNN_TERM_CPU0")
		)
		(pad "2" smd circle
			(at 0.40005 0 90)
			(size 0 0)
			(layers "F.Cu" "F.Mask" "F.Paste")
			(net "GND")
		)
	)
	(footprint ""
		(layer "F.Cu")
		(at 303.457102 -28.997656 90)
		(property "Reference" "U62"
			(at 1.246378 -4.518914 0)
			(unlocked yes)
			(layer "F.SilkS")
			(effects
				(font
					(size 0.7874 0.5842)
					(thickness 0.1524)
				)
				(justify left)
			)
		)
		(property "Value" ""
			(at 0 0 90)
			(layer "F.Fab")
			(effects
				(font
					(size 1.27 1.27)
				)
			)
		)
		(duplicate_pad_numbers_are_jumpers no)
		(fp_line
			(start 1.584198 -1.500124)
			(end -1.584198 -1.500124)
			(stroke
				(width 0.1524)
				(type default)
			)
			(layer "F.SilkS")
		)
		(fp_line
			(start -1.584198 -1.500124)
			(end -1.584198 1.500124)
			(stroke
				(width 0.1524)
				(type default)
			)
			(layer "F.SilkS")
		)
		(fp_line
			(start 1.584198 1.500124)
			(end 1.584198 -1.500124)
			(stroke
				(width 0.1524)
				(type default)
			)
			(layer "F.SilkS")
		)
		(fp_line
			(start -1.584198 1.500124)
			(end 1.584198 1.500124)
			(stroke
				(width 0.1524)
				(type default)
			)
			(layer "F.SilkS")
		)
		(fp_line
			(start 0.700024 -1.500124)
			(end -0.700024 -1.500124)
			(stroke
				(width 0.1)
				(type default)
			)
			(layer "F.Fab")
		)
		(fp_line
			(start -0.700024 -1.500124)
			(end -0.700024 1.500124)
			(stroke
				(width 0.1)
				(type default)
			)
			(layer "F.Fab")
		)
		(fp_line
			(start 0.700024 1.500124)
			(end 0.700024 -1.500124)
			(stroke
				(width 0.1)
				(type default)
			)
			(layer "F.Fab")
		)
		(fp_line
			(start -0.700024 1.500124)
			(end 0.700024 1.500124)
			(stroke
				(width 0.1)
				(type default)
			)
			(layer "F.Fab")
		)
		(pad "1" smd rect
			(at -0.999998 -0.94996)
			(size 0.8128 0.9144)
			(layers "F.Cu" "F.Mask" "F.Paste")
			(net "P3V_BAT_R")
		)
		(pad "2" smd rect
			(at -0.999998 0.94996)
			(size 0.8128 0.9144)
			(layers "F.Cu" "F.Mask" "F.Paste")
			(net "P3V3_AUX")
		)
		(pad "3" smd rect
			(at 0.999998 0)
			(size 0.8128 0.9144)
			(layers "F.Cu" "F.Mask" "F.Paste")
			(net "P3V3_RTC_AUX")
		)
	)
	(footprint ""
		(layer "F.Cu")
		(at 355.216714 -255.053846 90)
		(property "Reference" "C994"
			(at 0 0 90)
			(layer "F.SilkS")
			(hide yes)
			(effects
				(font
					(size 1.27 1.27)
				)
			)
		)
		(property "Value" ""
			(at 0 0 90)
			(layer "F.Fab")
			(effects
				(font
					(size 1.27 1.27)
				)
			)
		)
		(duplicate_pad_numbers_are_jumpers no)
		(fp_line
			(start 0.7874 -0.4064)
			(end 0.7874 0.4064)
			(stroke
				(width 0.1524)
				(type default)
			)
			(layer "F.SilkS")
		)
		(fp_line
			(start -0.7874 -0.4064)
			(end 0.7874 -0.4064)
			(stroke
				(width 0.1524)
				(type default)
			)
			(layer "F.SilkS")
		)
		(fp_line
			(start 0.7874 0.4064)
			(end -0.7874 0.4064)
			(stroke
				(width 0.1524)
				(type default)
			)
			(layer "F.SilkS")
		)
		(fp_line
			(start -0.7874 0.4064)
			(end -0.7874 -0.4064)
			(stroke
				(width 0.1524)
				(type default)
			)
			(layer "F.SilkS")
		)
		(fp_line
			(start -0.12065 -0.305054)
			(end -0.12065 -0.2794)
			(stroke
				(width 0.1)
				(type default)
			)
			(layer "F.Fab")
		)
		(fp_line
			(start -0.67945 -0.305054)
			(end -0.12065 -0.305054)
			(stroke
				(width 0.1)
				(type default)
			)
			(layer "F.Fab")
		)
		(fp_line
			(start 0.67945 -0.3048)
			(end 0.67945 0.3048)
			(stroke
				(width 0.1)
				(type default)
			)
			(layer "F.Fab")
		)
		(fp_line
			(start 0.12065 -0.3048)
			(end 0.67945 -0.3048)
			(stroke
				(width 0.1)
				(type default)
			)
			(layer "F.Fab")
		)
		(fp_line
			(start 0.12065 -0.2794)
			(end 0.12065 -0.3048)
			(stroke
				(width 0.1)
				(type default)
			)
			(layer "F.Fab")
		)
		(fp_line
			(start -0.12065 -0.2794)
			(end 0.12065 -0.2794)
			(stroke
				(width 0.1)
				(type default)
			)
			(layer "F.Fab")
		)
		(fp_line
			(start 0.120396 0.2794)
			(end -0.12065 0.2794)
			(stroke
				(width 0.1)
				(type default)
			)
			(layer "F.Fab")
		)
		(fp_line
			(start -0.12065 0.2794)
			(end -0.12065 0.3048)
			(stroke
				(width 0.1)
				(type default)
			)
			(layer "F.Fab")
		)
		(fp_line
			(start 0.67945 0.3048)
			(end 0.120396 0.3048)
			(stroke
				(width 0.1)
				(type default)
			)
			(layer "F.Fab")
		)
		(fp_line
			(start 0.120396 0.3048)
			(end 0.120396 0.2794)
			(stroke
				(width 0.1)
				(type default)
			)
			(layer "F.Fab")
		)
		(fp_line
			(start -0.12065 0.3048)
			(end -0.67945 0.3048)
			(stroke
				(width 0.1)
				(type default)
			)
			(layer "F.Fab")
		)
		(fp_line
			(start -0.67945 0.3048)
			(end -0.67945 -0.305054)
			(stroke
				(width 0.1)
				(type default)
			)
			(layer "F.Fab")
		)
		(pad "1" smd circle
			(at -0.40005 0 90)
			(size 0 0)
			(layers "F.Cu" "F.Mask" "F.Paste")
			(net "PVCCIN_CPU0")
		)
		(pad "2" smd circle
			(at 0.40005 0 90)
			(size 0 0)
			(layers "F.Cu" "F.Mask" "F.Paste")
			(net "GND")
		)
	)
	(footprint ""
		(layer "F.Cu")
		(at 106.331004 -244.032024 90)
		(property "Reference" "C300"
			(at 0 0 90)
			(layer "F.SilkS")
			(hide yes)
			(effects
				(font
					(size 1.27 1.27)
				)
			)
		)
		(property "Value" ""
			(at 0 0 90)
			(layer "F.Fab")
			(effects
				(font
					(size 1.27 1.27)
				)
			)
		)
		(duplicate_pad_numbers_are_jumpers no)
		(fp_line
			(start 0.7874 -0.4064)
			(end 0.7874 0.4064)
			(stroke
				(width 0.1524)
				(type default)
			)
			(layer "F.SilkS")
		)
		(fp_line
			(start -0.7874 -0.4064)
			(end 0.7874 -0.4064)
			(stroke
				(width 0.1524)
				(type default)
			)
			(layer "F.SilkS")
		)
		(fp_line
			(start 0.7874 0.4064)
			(end -0.7874 0.4064)
			(stroke
				(width 0.1524)
				(type default)
			)
			(layer "F.SilkS")
		)
		(fp_line
			(start -0.7874 0.4064)
			(end -0.7874 -0.4064)
			(stroke
				(width 0.1524)
				(type default)
			)
			(layer "F.SilkS")
		)
		(fp_line
			(start -0.12065 -0.305054)
			(end -0.12065 -0.2794)
			(stroke
				(width 0.1)
				(type default)
			)
			(layer "F.Fab")
		)
		(fp_line
			(start -0.67945 -0.305054)
			(end -0.12065 -0.305054)
			(stroke
				(width 0.1)
				(type default)
			)
			(layer "F.Fab")
		)
		(fp_line
			(start 0.67945 -0.3048)
			(end 0.67945 0.3048)
			(stroke
				(width 0.1)
				(type default)
			)
			(layer "F.Fab")
		)
		(fp_line
			(start 0.12065 -0.3048)
			(end 0.67945 -0.3048)
			(stroke
				(width 0.1)
				(type default)
			)
			(layer "F.Fab")
		)
		(fp_line
			(start 0.12065 -0.2794)
			(end 0.12065 -0.3048)
			(stroke
				(width 0.1)
				(type default)
			)
			(layer "F.Fab")
		)
		(fp_line
			(start -0.12065 -0.2794)
			(end 0.12065 -0.2794)
			(stroke
				(width 0.1)
				(type default)
			)
			(layer "F.Fab")
		)
		(fp_line
			(start 0.120396 0.2794)
			(end -0.12065 0.2794)
			(stroke
				(width 0.1)
				(type default)
			)
			(layer "F.Fab")
		)
		(fp_line
			(start -0.12065 0.2794)
			(end -0.12065 0.3048)
			(stroke
				(width 0.1)
				(type default)
			)
			(layer "F.Fab")
		)
		(fp_line
			(start 0.67945 0.3048)
			(end 0.120396 0.3048)
			(stroke
				(width 0.1)
				(type default)
			)
			(layer "F.Fab")
		)
		(fp_line
			(start 0.120396 0.3048)
			(end 0.120396 0.2794)
			(stroke
				(width 0.1)
				(type default)
			)
			(layer "F.Fab")
		)
		(fp_line
			(start -0.12065 0.3048)
			(end -0.67945 0.3048)
			(stroke
				(width 0.1)
				(type default)
			)
			(layer "F.Fab")
		)
		(fp_line
			(start -0.67945 0.3048)
			(end -0.67945 -0.305054)
			(stroke
				(width 0.1)
				(type default)
			)
			(layer "F.Fab")
		)
		(pad "1" smd circle
			(at -0.40005 0 90)
			(size 0 0)
			(layers "F.Cu" "F.Mask" "F.Paste")
			(net "PVCCIN_CPU1")
		)
		(pad "2" smd circle
			(at 0.40005 0 90)
			(size 0 0)
			(layers "F.Cu" "F.Mask" "F.Paste")
			(net "GND")
		)
	)
	(footprint ""
		(layer "F.Cu")
		(at 378.5616 -107.183428)
		(property "Reference" "C1664"
			(at 0 0 0)
			(layer "F.SilkS")
			(hide yes)
			(effects
				(font
					(size 1.27 1.27)
				)
			)
		)
		(property "Value" ""
			(at 0 0 0)
			(layer "F.Fab")
			(effects
				(font
					(size 1.27 1.27)
				)
			)
		)
		(duplicate_pad_numbers_are_jumpers no)
		(fp_line
			(start -0.7874 -0.4064)
			(end 0.7874 -0.4064)
			(stroke
				(width 0.1524)
				(type default)
			)
			(layer "F.SilkS")
		)
		(fp_line
			(start -0.7874 0.4064)
			(end -0.7874 -0.4064)
			(stroke
				(width 0.1524)
				(type default)
			)
			(layer "F.SilkS")
		)
		(fp_line
			(start 0.7874 -0.4064)
			(end 0.7874 0.4064)
			(stroke
				(width 0.1524)
				(type default)
			)
			(layer "F.SilkS")
		)
		(fp_line
			(start 0.7874 0.4064)
			(end -0.7874 0.4064)
			(stroke
				(width 0.1524)
				(type default)
			)
			(layer "F.SilkS")
		)
		(fp_line
			(start -0.67945 -0.305054)
			(end -0.12065 -0.305054)
			(stroke
				(width 0.1)
				(type default)
			)
			(layer "F.Fab")
		)
		(fp_line
			(start -0.67945 0.3048)
			(end -0.67945 -0.305054)
			(stroke
				(width 0.1)
				(type default)
			)
			(layer "F.Fab")
		)
		(fp_line
			(start -0.12065 -0.305054)
			(end -0.12065 -0.2794)
			(stroke
				(width 0.1)
				(type default)
			)
			(layer "F.Fab")
		)
		(fp_line
			(start -0.12065 -0.2794)
			(end 0.12065 -0.2794)
			(stroke
				(width 0.1)
				(type default)
			)
			(layer "F.Fab")
		)
		(fp_line
			(start -0.12065 0.2794)
			(end -0.12065 0.3048)
			(stroke
				(width 0.1)
				(type default)
			)
			(layer "F.Fab")
		)
		(fp_line
			(start -0.12065 0.3048)
			(end -0.67945 0.3048)
			(stroke
				(width 0.1)
				(type default)
			)
			(layer "F.Fab")
		)
		(fp_line
			(start 0.120396 0.2794)
			(end -0.12065 0.2794)
			(stroke
				(width 0.1)
				(type default)
			)
			(layer "F.Fab")
		)
		(fp_line
			(start 0.120396 0.3048)
			(end 0.120396 0.2794)
			(stroke
				(width 0.1)
				(type default)
			)
			(layer "F.Fab")
		)
		(fp_line
			(start 0.12065 -0.3048)
			(end 0.67945 -0.3048)
			(stroke
				(width 0.1)
				(type default)
			)
			(layer "F.Fab")
		)
		(fp_line
			(start 0.12065 -0.2794)
			(end 0.12065 -0.3048)
			(stroke
				(width 0.1)
				(type default)
			)
			(layer "F.Fab")
		)
		(fp_line
			(start 0.67945 -0.3048)
			(end 0.67945 0.3048)
			(stroke
				(width 0.1)
				(type default)
			)
			(layer "F.Fab")
		)
		(fp_line
			(start 0.67945 0.3048)
			(end 0.120396 0.3048)
			(stroke
				(width 0.1)
				(type default)
			)
			(layer "F.Fab")
		)
		(pad "1" smd circle
			(at -0.40005 0)
			(size 0 0)
			(layers "F.Cu" "F.Mask" "F.Paste")
			(net "P0V7_JTAG_VREF_2")
		)
		(pad "2" smd circle
			(at 0.40005 0)
			(size 0 0)
			(layers "F.Cu" "F.Mask" "F.Paste")
			(net "GND")
		)
	)
	(footprint ""
		(layer "F.Cu")
		(at 352.283014 -251.375418 90)
		(property "Reference" "C1014"
			(at 0 0 90)
			(layer "F.SilkS")
			(hide yes)
			(effects
				(font
					(size 1.27 1.27)
				)
			)
		)
		(property "Value" ""
			(at 0 0 90)
			(layer "F.Fab")
			(effects
				(font
					(size 1.27 1.27)
				)
			)
		)
		(duplicate_pad_numbers_are_jumpers no)
		(fp_line
			(start 0.7874 -0.4064)
			(end 0.7874 0.4064)
			(stroke
				(width 0.1524)
				(type default)
			)
			(layer "F.SilkS")
		)
		(fp_line
			(start -0.7874 -0.4064)
			(end 0.7874 -0.4064)
			(stroke
				(width 0.1524)
				(type default)
			)
			(layer "F.SilkS")
		)
		(fp_line
			(start 0.7874 0.4064)
			(end -0.7874 0.4064)
			(stroke
				(width 0.1524)
				(type default)
			)
			(layer "F.SilkS")
		)
		(fp_line
			(start -0.7874 0.4064)
			(end -0.7874 -0.4064)
			(stroke
				(width 0.1524)
				(type default)
			)
			(layer "F.SilkS")
		)
		(fp_line
			(start -0.12065 -0.305054)
			(end -0.12065 -0.2794)
			(stroke
				(width 0.1)
				(type default)
			)
			(layer "F.Fab")
		)
		(fp_line
			(start -0.67945 -0.305054)
			(end -0.12065 -0.305054)
			(stroke
				(width 0.1)
				(type default)
			)
			(layer "F.Fab")
		)
		(fp_line
			(start 0.67945 -0.3048)
			(end 0.67945 0.3048)
			(stroke
				(width 0.1)
				(type default)
			)
			(layer "F.Fab")
		)
		(fp_line
			(start 0.12065 -0.3048)
			(end 0.67945 -0.3048)
			(stroke
				(width 0.1)
				(type default)
			)
			(layer "F.Fab")
		)
		(fp_line
			(start 0.12065 -0.2794)
			(end 0.12065 -0.3048)
			(stroke
				(width 0.1)
				(type default)
			)
			(layer "F.Fab")
		)
		(fp_line
			(start -0.12065 -0.2794)
			(end 0.12065 -0.2794)
			(stroke
				(width 0.1)
				(type default)
			)
			(layer "F.Fab")
		)
		(fp_line
			(start 0.120396 0.2794)
			(end -0.12065 0.2794)
			(stroke
				(width 0.1)
				(type default)
			)
			(layer "F.Fab")
		)
		(fp_line
			(start -0.12065 0.2794)
			(end -0.12065 0.3048)
			(stroke
				(width 0.1)
				(type default)
			)
			(layer "F.Fab")
		)
		(fp_line
			(start 0.67945 0.3048)
			(end 0.120396 0.3048)
			(stroke
				(width 0.1)
				(type default)
			)
			(layer "F.Fab")
		)
		(fp_line
			(start 0.120396 0.3048)
			(end 0.120396 0.2794)
			(stroke
				(width 0.1)
				(type default)
			)
			(layer "F.Fab")
		)
		(fp_line
			(start -0.12065 0.3048)
			(end -0.67945 0.3048)
			(stroke
				(width 0.1)
				(type default)
			)
			(layer "F.Fab")
		)
		(fp_line
			(start -0.67945 0.3048)
			(end -0.67945 -0.305054)
			(stroke
				(width 0.1)
				(type default)
			)
			(layer "F.Fab")
		)
		(pad "1" smd circle
			(at -0.40005 0 90)
			(size 0 0)
			(layers "F.Cu" "F.Mask" "F.Paste")
			(net "PVCCIN_CPU0")
		)
		(pad "2" smd circle
			(at 0.40005 0 90)
			(size 0 0)
			(layers "F.Cu" "F.Mask" "F.Paste")
			(net "GND")
		)
	)
	(footprint ""
		(layer "F.Cu")
		(at 367.44783 -256.654046 -90)
		(property "Reference" "C996"
			(at 0 0 270)
			(layer "F.SilkS")
			(hide yes)
			(effects
				(font
					(size 1.27 1.27)
				)
			)
		)
		(property "Value" ""
			(at 0 0 270)
			(layer "F.Fab")
			(effects
				(font
					(size 1.27 1.27)
				)
			)
		)
		(duplicate_pad_numbers_are_jumpers no)
		(fp_line
			(start -0.7874 0.4064)
			(end -0.7874 -0.4064)
			(stroke
				(width 0.1524)
				(type default)
			)
			(layer "F.SilkS")
		)
		(fp_line
			(start 0.7874 0.4064)
			(end -0.7874 0.4064)
			(stroke
				(width 0.1524)
				(type default)
			)
			(layer "F.SilkS")
		)
		(fp_line
			(start -0.7874 -0.4064)
			(end 0.7874 -0.4064)
			(stroke
				(width 0.1524)
				(type default)
			)
			(layer "F.SilkS")
		)
		(fp_line
			(start 0.7874 -0.4064)
			(end 0.7874 0.4064)
			(stroke
				(width 0.1524)
				(type default)
			)
			(layer "F.SilkS")
		)
		(fp_line
			(start -0.67945 0.3048)
			(end -0.67945 -0.305054)
			(stroke
				(width 0.1)
				(type default)
			)
			(layer "F.Fab")
		)
		(fp_line
			(start -0.12065 0.3048)
			(end -0.67945 0.3048)
			(stroke
				(width 0.1)
				(type default)
			)
			(layer "F.Fab")
		)
		(fp_line
			(start 0.120396 0.3048)
			(end 0.120396 0.2794)
			(stroke
				(width 0.1)
				(type default)
			)
			(layer "F.Fab")
		)
		(fp_line
			(start 0.67945 0.3048)
			(end 0.120396 0.3048)
			(stroke
				(width 0.1)
				(type default)
			)
			(layer "F.Fab")
		)
		(fp_line
			(start -0.12065 0.2794)
			(end -0.12065 0.3048)
			(stroke
				(width 0.1)
				(type default)
			)
			(layer "F.Fab")
		)
		(fp_line
			(start 0.120396 0.2794)
			(end -0.12065 0.2794)
			(stroke
				(width 0.1)
				(type default)
			)
			(layer "F.Fab")
		)
		(fp_line
			(start -0.12065 -0.2794)
			(end 0.12065 -0.2794)
			(stroke
				(width 0.1)
				(type default)
			)
			(layer "F.Fab")
		)
		(fp_line
			(start 0.12065 -0.2794)
			(end 0.12065 -0.3048)
			(stroke
				(width 0.1)
				(type default)
			)
			(layer "F.Fab")
		)
		(fp_line
			(start 0.12065 -0.3048)
			(end 0.67945 -0.3048)
			(stroke
				(width 0.1)
				(type default)
			)
			(layer "F.Fab")
		)
		(fp_line
			(start 0.67945 -0.3048)
			(end 0.67945 0.3048)
			(stroke
				(width 0.1)
				(type default)
			)
			(layer "F.Fab")
		)
		(fp_line
			(start -0.67945 -0.305054)
			(end -0.12065 -0.305054)
			(stroke
				(width 0.1)
				(type default)
			)
			(layer "F.Fab")
		)
		(fp_line
			(start -0.12065 -0.305054)
			(end -0.12065 -0.2794)
			(stroke
				(width 0.1)
				(type default)
			)
			(layer "F.Fab")
		)
		(pad "1" smd circle
			(at -0.40005 0 270)
			(size 0 0)
			(layers "F.Cu" "F.Mask" "F.Paste")
			(net "PVCCIN_CPU0")
		)
		(pad "2" smd circle
			(at 0.40005 0 270)
			(size 0 0)
			(layers "F.Cu" "F.Mask" "F.Paste")
			(net "GND")
		)
	)
	(footprint ""
		(layer "F.Cu")
		(at 393.880086 -251.76988)
		(property "Reference" "H19"
			(at 4.645914 -4.708398 0)
			(unlocked yes)
			(layer "F.SilkS")
			(effects
				(font
					(size 0.7874 0.5842)
					(thickness 0.1524)
				)
				(justify left)
			)
		)
		(property "Value" ""
			(at 0 0 0)
			(layer "F.Fab")
			(effects
				(font
					(size 1.27 1.27)
				)
			)
		)
		(duplicate_pad_numbers_are_jumpers no)
		(fp_circle
			(center 0 0)
			(end 2.5273 0)
			(stroke
				(width 0.1524)
				(type default)
			)
			(fill no)
			(layer "F.SilkS")
		)
		(fp_circle
			(center 0 0)
			(end 2.5273 0)
			(stroke
				(width 0.1524)
				(type default)
			)
			(fill no)
			(layer "B.SilkS")
		)
		(fp_circle
			(center 0 0)
			(end 2.5273 0)
			(stroke
				(width 0.1)
				(type default)
			)
			(fill no)
			(layer "B.Fab")
		)
		(fp_circle
			(center 0 0)
			(end 2.5273 0)
			(stroke
				(width 0.1)
				(type default)
			)
			(fill no)
			(layer "F.Fab")
		)
		(pad "" np_thru_hole circle
			(at 0 0)
			(size 3.429 3.429)
			(drill 3.429)
			(layers "*.Cu" "*.Mask")
			(clearance 0.381)
			(thermal_gap 0.381)
		)
	)
	(footprint ""
		(layer "F.Cu")
		(at 55.978298 -353.643946 -90)
		(property "Reference" "PC398_P1_2"
			(at 0 0 270)
			(layer "F.SilkS")
			(hide yes)
			(effects
				(font
					(size 1.27 1.27)
				)
			)
		)
		(property "Value" ""
			(at 0 0 270)
			(layer "F.Fab")
			(effects
				(font
					(size 1.27 1.27)
				)
			)
		)
		(duplicate_pad_numbers_are_jumpers no)
		(fp_line
			(start -0.7874 0.4064)
			(end -0.7874 -0.4064)
			(stroke
				(width 0.1524)
				(type default)
			)
			(layer "F.SilkS")
		)
		(fp_line
			(start 0.7874 0.4064)
			(end -0.7874 0.4064)
			(stroke
				(width 0.1524)
				(type default)
			)
			(layer "F.SilkS")
		)
		(fp_line
			(start -0.7874 -0.4064)
			(end 0.7874 -0.4064)
			(stroke
				(width 0.1524)
				(type default)
			)
			(layer "F.SilkS")
		)
		(fp_line
			(start 0.7874 -0.4064)
			(end 0.7874 0.4064)
			(stroke
				(width 0.1524)
				(type default)
			)
			(layer "F.SilkS")
		)
		(fp_line
			(start -0.67945 0.3048)
			(end -0.67945 -0.305054)
			(stroke
				(width 0.1)
				(type default)
			)
			(layer "F.Fab")
		)
		(fp_line
			(start -0.12065 0.3048)
			(end -0.67945 0.3048)
			(stroke
				(width 0.1)
				(type default)
			)
			(layer "F.Fab")
		)
		(fp_line
			(start 0.120396 0.3048)
			(end 0.120396 0.2794)
			(stroke
				(width 0.1)
				(type default)
			)
			(layer "F.Fab")
		)
		(fp_line
			(start 0.67945 0.3048)
			(end 0.120396 0.3048)
			(stroke
				(width 0.1)
				(type default)
			)
			(layer "F.Fab")
		)
		(fp_line
			(start -0.12065 0.2794)
			(end -0.12065 0.3048)
			(stroke
				(width 0.1)
				(type default)
			)
			(layer "F.Fab")
		)
		(fp_line
			(start 0.120396 0.2794)
			(end -0.12065 0.2794)
			(stroke
				(width 0.1)
				(type default)
			)
			(layer "F.Fab")
		)
		(fp_line
			(start -0.12065 -0.2794)
			(end 0.12065 -0.2794)
			(stroke
				(width 0.1)
				(type default)
			)
			(layer "F.Fab")
		)
		(fp_line
			(start 0.12065 -0.2794)
			(end 0.12065 -0.3048)
			(stroke
				(width 0.1)
				(type default)
			)
			(layer "F.Fab")
		)
		(fp_line
			(start 0.12065 -0.3048)
			(end 0.67945 -0.3048)
			(stroke
				(width 0.1)
				(type default)
			)
			(layer "F.Fab")
		)
		(fp_line
			(start 0.67945 -0.3048)
			(end 0.67945 0.3048)
			(stroke
				(width 0.1)
				(type default)
			)
			(layer "F.Fab")
		)
		(fp_line
			(start -0.67945 -0.305054)
			(end -0.12065 -0.305054)
			(stroke
				(width 0.1)
				(type default)
			)
			(layer "F.Fab")
		)
		(fp_line
			(start -0.12065 -0.305054)
			(end -0.12065 -0.2794)
			(stroke
				(width 0.1)
				(type default)
			)
			(layer "F.Fab")
		)
		(pad "1" smd circle
			(at -0.40005 0 270)
			(size 0 0)
			(layers "F.Cu" "F.Mask" "F.Paste")
			(net "SW_P12V_PVCCFA_EHV_FIVRA_CPU1_L")
		)
		(pad "2" smd circle
			(at 0.40005 0 270)
			(size 0 0)
			(layers "F.Cu" "F.Mask" "F.Paste")
			(net "GND")
		)
	)
	(footprint ""
		(layer "F.Cu")
		(at 302.895 -421.49395 90)
		(property "Reference" "R4119"
			(at 0 0 90)
			(layer "F.SilkS")
			(hide yes)
			(effects
				(font
					(size 1.27 1.27)
				)
			)
		)
		(property "Value" ""
			(at 0 0 90)
			(layer "F.Fab")
			(effects
				(font
					(size 1.27 1.27)
				)
			)
		)
		(duplicate_pad_numbers_are_jumpers no)
		(fp_line
			(start 0.7874 -0.4064)
			(end 0.7874 0.4064)
			(stroke
				(width 0.1524)
				(type default)
			)
			(layer "F.SilkS")
		)
		(fp_line
			(start -0.7874 -0.4064)
			(end 0.7874 -0.4064)
			(stroke
				(width 0.1524)
				(type default)
			)
			(layer "F.SilkS")
		)
		(fp_line
			(start 0.7874 0.4064)
			(end -0.7874 0.4064)
			(stroke
				(width 0.1524)
				(type default)
			)
			(layer "F.SilkS")
		)
		(fp_line
			(start -0.7874 0.4064)
			(end -0.7874 -0.4064)
			(stroke
				(width 0.1524)
				(type default)
			)
			(layer "F.SilkS")
		)
		(fp_line
			(start -0.12065 -0.305054)
			(end -0.12065 -0.2794)
			(stroke
				(width 0.1)
				(type default)
			)
			(layer "F.Fab")
		)
		(fp_line
			(start -0.67945 -0.305054)
			(end -0.12065 -0.305054)
			(stroke
				(width 0.1)
				(type default)
			)
			(layer "F.Fab")
		)
		(fp_line
			(start 0.67945 -0.3048)
			(end 0.67945 0.3048)
			(stroke
				(width 0.1)
				(type default)
			)
			(layer "F.Fab")
		)
		(fp_line
			(start 0.12065 -0.3048)
			(end 0.67945 -0.3048)
			(stroke
				(width 0.1)
				(type default)
			)
			(layer "F.Fab")
		)
		(fp_line
			(start 0.12065 -0.2794)
			(end 0.12065 -0.3048)
			(stroke
				(width 0.1)
				(type default)
			)
			(layer "F.Fab")
		)
		(fp_line
			(start -0.12065 -0.2794)
			(end 0.12065 -0.2794)
			(stroke
				(width 0.1)
				(type default)
			)
			(layer "F.Fab")
		)
		(fp_line
			(start 0.120396 0.2794)
			(end -0.12065 0.2794)
			(stroke
				(width 0.1)
				(type default)
			)
			(layer "F.Fab")
		)
		(fp_line
			(start -0.12065 0.2794)
			(end -0.12065 0.3048)
			(stroke
				(width 0.1)
				(type default)
			)
			(layer "F.Fab")
		)
		(fp_line
			(start 0.67945 0.3048)
			(end 0.120396 0.3048)
			(stroke
				(width 0.1)
				(type default)
			)
			(layer "F.Fab")
		)
		(fp_line
			(start 0.120396 0.3048)
			(end 0.120396 0.2794)
			(stroke
				(width 0.1)
				(type default)
			)
			(layer "F.Fab")
		)
		(fp_line
			(start -0.12065 0.3048)
			(end -0.67945 0.3048)
			(stroke
				(width 0.1)
				(type default)
			)
			(layer "F.Fab")
		)
		(fp_line
			(start -0.67945 0.3048)
			(end -0.67945 -0.305054)
			(stroke
				(width 0.1)
				(type default)
			)
			(layer "F.Fab")
		)
		(pad "1" smd circle
			(at -0.40005 0 90)
			(size 0 0)
			(layers "F.Cu" "F.Mask" "F.Paste")
			(net "P3V3_AUX")
		)
		(pad "2" smd circle
			(at 0.40005 0 90)
			(size 0 0)
			(layers "F.Cu" "F.Mask" "F.Paste")
			(net "GPU_3V3IO_RSVD0_FFU")
		)
	)
	(footprint ""
		(layer "F.Cu")
		(at 307.95087 -425.186602)
		(property "Reference" "C2283"
			(at 0 0 0)
			(layer "F.SilkS")
			(hide yes)
			(effects
				(font
					(size 1.27 1.27)
				)
			)
		)
		(property "Value" ""
			(at 0 0 0)
			(layer "F.Fab")
			(effects
				(font
					(size 1.27 1.27)
				)
			)
		)
		(duplicate_pad_numbers_are_jumpers no)
		(fp_line
			(start -0.7874 -0.4064)
			(end 0.7874 -0.4064)
			(stroke
				(width 0.1524)
				(type default)
			)
			(layer "F.SilkS")
		)
		(fp_line
			(start -0.7874 0.4064)
			(end -0.7874 -0.4064)
			(stroke
				(width 0.1524)
				(type default)
			)
			(layer "F.SilkS")
		)
		(fp_line
			(start 0.7874 -0.4064)
			(end 0.7874 0.4064)
			(stroke
				(width 0.1524)
				(type default)
			)
			(layer "F.SilkS")
		)
		(fp_line
			(start 0.7874 0.4064)
			(end -0.7874 0.4064)
			(stroke
				(width 0.1524)
				(type default)
			)
			(layer "F.SilkS")
		)
		(fp_line
			(start -0.67945 -0.305054)
			(end -0.12065 -0.305054)
			(stroke
				(width 0.1)
				(type default)
			)
			(layer "F.Fab")
		)
		(fp_line
			(start -0.67945 0.3048)
			(end -0.67945 -0.305054)
			(stroke
				(width 0.1)
				(type default)
			)
			(layer "F.Fab")
		)
		(fp_line
			(start -0.12065 -0.305054)
			(end -0.12065 -0.2794)
			(stroke
				(width 0.1)
				(type default)
			)
			(layer "F.Fab")
		)
		(fp_line
			(start -0.12065 -0.2794)
			(end 0.12065 -0.2794)
			(stroke
				(width 0.1)
				(type default)
			)
			(layer "F.Fab")
		)
		(fp_line
			(start -0.12065 0.2794)
			(end -0.12065 0.3048)
			(stroke
				(width 0.1)
				(type default)
			)
			(layer "F.Fab")
		)
		(fp_line
			(start -0.12065 0.3048)
			(end -0.67945 0.3048)
			(stroke
				(width 0.1)
				(type default)
			)
			(layer "F.Fab")
		)
		(fp_line
			(start 0.120396 0.2794)
			(end -0.12065 0.2794)
			(stroke
				(width 0.1)
				(type default)
			)
			(layer "F.Fab")
		)
		(fp_line
			(start 0.120396 0.3048)
			(end 0.120396 0.2794)
			(stroke
				(width 0.1)
				(type default)
			)
			(layer "F.Fab")
		)
		(fp_line
			(start 0.12065 -0.3048)
			(end 0.67945 -0.3048)
			(stroke
				(width 0.1)
				(type default)
			)
			(layer "F.Fab")
		)
		(fp_line
			(start 0.12065 -0.2794)
			(end 0.12065 -0.3048)
			(stroke
				(width 0.1)
				(type default)
			)
			(layer "F.Fab")
		)
		(fp_line
			(start 0.67945 -0.3048)
			(end 0.67945 0.3048)
			(stroke
				(width 0.1)
				(type default)
			)
			(layer "F.Fab")
		)
		(fp_line
			(start 0.67945 0.3048)
			(end 0.120396 0.3048)
			(stroke
				(width 0.1)
				(type default)
			)
			(layer "F.Fab")
		)
		(pad "1" smd circle
			(at -0.40005 0)
			(size 0 0)
			(layers "F.Cu" "F.Mask" "F.Paste")
			(net "P3V3_AUX")
		)
		(pad "2" smd circle
			(at 0.40005 0)
			(size 0 0)
			(layers "F.Cu" "F.Mask" "F.Paste")
			(net "GND")
		)
	)
	(footprint ""
		(layer "F.Cu")
		(at 429.28032 -140.654278 -90)
		(property "Reference" "PR120"
			(at 0 0 270)
			(layer "F.SilkS")
			(hide yes)
			(effects
				(font
					(size 1.27 1.27)
				)
			)
		)
		(property "Value" ""
			(at 0 0 270)
			(layer "F.Fab")
			(effects
				(font
					(size 1.27 1.27)
				)
			)
		)
		(duplicate_pad_numbers_are_jumpers no)
		(fp_line
			(start -0.7874 0.4064)
			(end -0.7874 -0.4064)
			(stroke
				(width 0.1524)
				(type default)
			)
			(layer "F.SilkS")
		)
		(fp_line
			(start 0.7874 0.4064)
			(end -0.7874 0.4064)
			(stroke
				(width 0.1524)
				(type default)
			)
			(layer "F.SilkS")
		)
		(fp_line
			(start -0.7874 -0.4064)
			(end 0.7874 -0.4064)
			(stroke
				(width 0.1524)
				(type default)
			)
			(layer "F.SilkS")
		)
		(fp_line
			(start 0.7874 -0.4064)
			(end 0.7874 0.4064)
			(stroke
				(width 0.1524)
				(type default)
			)
			(layer "F.SilkS")
		)
		(fp_line
			(start -0.67945 0.3048)
			(end -0.67945 -0.305054)
			(stroke
				(width 0.1)
				(type default)
			)
			(layer "F.Fab")
		)
		(fp_line
			(start -0.12065 0.3048)
			(end -0.67945 0.3048)
			(stroke
				(width 0.1)
				(type default)
			)
			(layer "F.Fab")
		)
		(fp_line
			(start 0.120396 0.3048)
			(end 0.120396 0.2794)
			(stroke
				(width 0.1)
				(type default)
			)
			(layer "F.Fab")
		)
		(fp_line
			(start 0.67945 0.3048)
			(end 0.120396 0.3048)
			(stroke
				(width 0.1)
				(type default)
			)
			(layer "F.Fab")
		)
		(fp_line
			(start -0.12065 0.2794)
			(end -0.12065 0.3048)
			(stroke
				(width 0.1)
				(type default)
			)
			(layer "F.Fab")
		)
		(fp_line
			(start 0.120396 0.2794)
			(end -0.12065 0.2794)
			(stroke
				(width 0.1)
				(type default)
			)
			(layer "F.Fab")
		)
		(fp_line
			(start -0.12065 -0.2794)
			(end 0.12065 -0.2794)
			(stroke
				(width 0.1)
				(type default)
			)
			(layer "F.Fab")
		)
		(fp_line
			(start 0.12065 -0.2794)
			(end 0.12065 -0.3048)
			(stroke
				(width 0.1)
				(type default)
			)
			(layer "F.Fab")
		)
		(fp_line
			(start 0.12065 -0.3048)
			(end 0.67945 -0.3048)
			(stroke
				(width 0.1)
				(type default)
			)
			(layer "F.Fab")
		)
		(fp_line
			(start 0.67945 -0.3048)
			(end 0.67945 0.3048)
			(stroke
				(width 0.1)
				(type default)
			)
			(layer "F.Fab")
		)
		(fp_line
			(start -0.67945 -0.305054)
			(end -0.12065 -0.305054)
			(stroke
				(width 0.1)
				(type default)
			)
			(layer "F.Fab")
		)
		(fp_line
			(start -0.12065 -0.305054)
			(end -0.12065 -0.2794)
			(stroke
				(width 0.1)
				(type default)
			)
			(layer "F.Fab")
		)
		(pad "1" smd circle
			(at -0.40005 0 270)
			(size 0 0)
			(layers "F.Cu" "F.Mask" "F.Paste")
			(net "SH_PVCCINFAON_CPU0")
		)
		(pad "2" smd circle
			(at 0.40005 0 270)
			(size 0 0)
			(layers "F.Cu" "F.Mask" "F.Paste")
			(net "SH_PVCCINFAON_CPU0_R")
		)
	)
	(footprint ""
		(layer "F.Cu")
		(at 136.668256 -68.445888 180)
		(property "Reference" "R2304"
			(at 0 0 180)
			(layer "F.SilkS")
			(hide yes)
			(effects
				(font
					(size 1.27 1.27)
				)
			)
		)
		(property "Value" ""
			(at 0 0 180)
			(layer "F.Fab")
			(effects
				(font
					(size 1.27 1.27)
				)
			)
		)
		(duplicate_pad_numbers_are_jumpers no)
		(fp_line
			(start 0.7874 0.4064)
			(end -0.7874 0.4064)
			(stroke
				(width 0.1524)
				(type default)
			)
			(layer "F.SilkS")
		)
		(fp_line
			(start 0.7874 -0.4064)
			(end 0.7874 0.4064)
			(stroke
				(width 0.1524)
				(type default)
			)
			(layer "F.SilkS")
		)
		(fp_line
			(start -0.7874 0.4064)
			(end -0.7874 -0.4064)
			(stroke
				(width 0.1524)
				(type default)
			)
			(layer "F.SilkS")
		)
		(fp_line
			(start -0.7874 -0.4064)
			(end 0.7874 -0.4064)
			(stroke
				(width 0.1524)
				(type default)
			)
			(layer "F.SilkS")
		)
		(fp_line
			(start 0.67945 0.3048)
			(end 0.120396 0.3048)
			(stroke
				(width 0.1)
				(type default)
			)
			(layer "F.Fab")
		)
		(fp_line
			(start 0.67945 -0.3048)
			(end 0.67945 0.3048)
			(stroke
				(width 0.1)
				(type default)
			)
			(layer "F.Fab")
		)
		(fp_line
			(start 0.12065 -0.2794)
			(end 0.12065 -0.3048)
			(stroke
				(width 0.1)
				(type default)
			)
			(layer "F.Fab")
		)
		(fp_line
			(start 0.12065 -0.3048)
			(end 0.67945 -0.3048)
			(stroke
				(width 0.1)
				(type default)
			)
			(layer "F.Fab")
		)
		(fp_line
			(start 0.120396 0.3048)
			(end 0.120396 0.2794)
			(stroke
				(width 0.1)
				(type default)
			)
			(layer "F.Fab")
		)
		(fp_line
			(start 0.120396 0.2794)
			(end -0.12065 0.2794)
			(stroke
				(width 0.1)
				(type default)
			)
			(layer "F.Fab")
		)
		(fp_line
			(start -0.12065 0.3048)
			(end -0.67945 0.3048)
			(stroke
				(width 0.1)
				(type default)
			)
			(layer "F.Fab")
		)
		(fp_line
			(start -0.12065 0.2794)
			(end -0.12065 0.3048)
			(stroke
				(width 0.1)
				(type default)
			)
			(layer "F.Fab")
		)
		(fp_line
			(start -0.12065 -0.2794)
			(end 0.12065 -0.2794)
			(stroke
				(width 0.1)
				(type default)
			)
			(layer "F.Fab")
		)
		(fp_line
			(start -0.12065 -0.305054)
			(end -0.12065 -0.2794)
			(stroke
				(width 0.1)
				(type default)
			)
			(layer "F.Fab")
		)
		(fp_line
			(start -0.67945 0.3048)
			(end -0.67945 -0.305054)
			(stroke
				(width 0.1)
				(type default)
			)
			(layer "F.Fab")
		)
		(fp_line
			(start -0.67945 -0.305054)
			(end -0.12065 -0.305054)
			(stroke
				(width 0.1)
				(type default)
			)
			(layer "F.Fab")
		)
		(pad "1" smd circle
			(at -0.40005 0 180)
			(size 0 0)
			(layers "F.Cu" "F.Mask" "F.Paste")
			(net "P3V3_AUX")
		)
		(pad "2" smd circle
			(at 0.40005 0 180)
			(size 0 0)
			(layers "F.Cu" "F.Mask" "F.Paste")
			(net "E1S_0_PRSNT_N")
		)
	)
	(footprint ""
		(layer "F.Cu")
		(at 369.191286 -357.11638 90)
		(property "Reference" "PC1253"
			(at 0 0 90)
			(layer "F.SilkS")
			(hide yes)
			(effects
				(font
					(size 1.27 1.27)
				)
			)
		)
		(property "Value" ""
			(at 0 0 90)
			(layer "F.Fab")
			(effects
				(font
					(size 1.27 1.27)
				)
			)
		)
		(duplicate_pad_numbers_are_jumpers no)
		(fp_line
			(start 0.7874 -0.4064)
			(end 0.7874 0.4064)
			(stroke
				(width 0.1524)
				(type default)
			)
			(layer "F.SilkS")
		)
		(fp_line
			(start -0.7874 -0.4064)
			(end 0.7874 -0.4064)
			(stroke
				(width 0.1524)
				(type default)
			)
			(layer "F.SilkS")
		)
		(fp_line
			(start 0.7874 0.4064)
			(end -0.7874 0.4064)
			(stroke
				(width 0.1524)
				(type default)
			)
			(layer "F.SilkS")
		)
		(fp_line
			(start -0.7874 0.4064)
			(end -0.7874 -0.4064)
			(stroke
				(width 0.1524)
				(type default)
			)
			(layer "F.SilkS")
		)
		(fp_line
			(start -0.12065 -0.305054)
			(end -0.12065 -0.2794)
			(stroke
				(width 0.1)
				(type default)
			)
			(layer "F.Fab")
		)
		(fp_line
			(start -0.67945 -0.305054)
			(end -0.12065 -0.305054)
			(stroke
				(width 0.1)
				(type default)
			)
			(layer "F.Fab")
		)
		(fp_line
			(start 0.67945 -0.3048)
			(end 0.67945 0.3048)
			(stroke
				(width 0.1)
				(type default)
			)
			(layer "F.Fab")
		)
		(fp_line
			(start 0.12065 -0.3048)
			(end 0.67945 -0.3048)
			(stroke
				(width 0.1)
				(type default)
			)
			(layer "F.Fab")
		)
		(fp_line
			(start 0.12065 -0.2794)
			(end 0.12065 -0.3048)
			(stroke
				(width 0.1)
				(type default)
			)
			(layer "F.Fab")
		)
		(fp_line
			(start -0.12065 -0.2794)
			(end 0.12065 -0.2794)
			(stroke
				(width 0.1)
				(type default)
			)
			(layer "F.Fab")
		)
		(fp_line
			(start 0.120396 0.2794)
			(end -0.12065 0.2794)
			(stroke
				(width 0.1)
				(type default)
			)
			(layer "F.Fab")
		)
		(fp_line
			(start -0.12065 0.2794)
			(end -0.12065 0.3048)
			(stroke
				(width 0.1)
				(type default)
			)
			(layer "F.Fab")
		)
		(fp_line
			(start 0.67945 0.3048)
			(end 0.120396 0.3048)
			(stroke
				(width 0.1)
				(type default)
			)
			(layer "F.Fab")
		)
		(fp_line
			(start 0.120396 0.3048)
			(end 0.120396 0.2794)
			(stroke
				(width 0.1)
				(type default)
			)
			(layer "F.Fab")
		)
		(fp_line
			(start -0.12065 0.3048)
			(end -0.67945 0.3048)
			(stroke
				(width 0.1)
				(type default)
			)
			(layer "F.Fab")
		)
		(fp_line
			(start -0.67945 0.3048)
			(end -0.67945 -0.305054)
			(stroke
				(width 0.1)
				(type default)
			)
			(layer "F.Fab")
		)
		(pad "1" smd circle
			(at -0.40005 0 90)
			(size 0 0)
			(layers "F.Cu" "F.Mask" "F.Paste")
			(net "PVPP_HBM_CPU0_FB")
		)
		(pad "2" smd circle
			(at 0.40005 0 90)
			(size 0 0)
			(layers "F.Cu" "F.Mask" "F.Paste")
			(net "SH_PVPP_HBM_CPU0_P")
		)
	)
	(footprint ""
		(layer "F.Cu")
		(at 108.727494 -333.804514 -90)
		(property "Reference" "PC562_P1_2"
			(at 0 0 270)
			(layer "F.SilkS")
			(hide yes)
			(effects
				(font
					(size 1.27 1.27)
				)
			)
		)
		(property "Value" ""
			(at 0 0 270)
			(layer "F.Fab")
			(effects
				(font
					(size 1.27 1.27)
				)
			)
		)
		(duplicate_pad_numbers_are_jumpers no)
		(fp_line
			(start -0.7874 0.4064)
			(end -0.7874 -0.4064)
			(stroke
				(width 0.1524)
				(type default)
			)
			(layer "F.SilkS")
		)
		(fp_line
			(start 0.7874 0.4064)
			(end -0.7874 0.4064)
			(stroke
				(width 0.1524)
				(type default)
			)
			(layer "F.SilkS")
		)
		(fp_line
			(start -0.7874 -0.4064)
			(end 0.7874 -0.4064)
			(stroke
				(width 0.1524)
				(type default)
			)
			(layer "F.SilkS")
		)
		(fp_line
			(start 0.7874 -0.4064)
			(end 0.7874 0.4064)
			(stroke
				(width 0.1524)
				(type default)
			)
			(layer "F.SilkS")
		)
		(fp_line
			(start -0.67945 0.3048)
			(end -0.67945 -0.305054)
			(stroke
				(width 0.1)
				(type default)
			)
			(layer "F.Fab")
		)
		(fp_line
			(start -0.12065 0.3048)
			(end -0.67945 0.3048)
			(stroke
				(width 0.1)
				(type default)
			)
			(layer "F.Fab")
		)
		(fp_line
			(start 0.120396 0.3048)
			(end 0.120396 0.2794)
			(stroke
				(width 0.1)
				(type default)
			)
			(layer "F.Fab")
		)
		(fp_line
			(start 0.67945 0.3048)
			(end 0.120396 0.3048)
			(stroke
				(width 0.1)
				(type default)
			)
			(layer "F.Fab")
		)
		(fp_line
			(start -0.12065 0.2794)
			(end -0.12065 0.3048)
			(stroke
				(width 0.1)
				(type default)
			)
			(layer "F.Fab")
		)
		(fp_line
			(start 0.120396 0.2794)
			(end -0.12065 0.2794)
			(stroke
				(width 0.1)
				(type default)
			)
			(layer "F.Fab")
		)
		(fp_line
			(start -0.12065 -0.2794)
			(end 0.12065 -0.2794)
			(stroke
				(width 0.1)
				(type default)
			)
			(layer "F.Fab")
		)
		(fp_line
			(start 0.12065 -0.2794)
			(end 0.12065 -0.3048)
			(stroke
				(width 0.1)
				(type default)
			)
			(layer "F.Fab")
		)
		(fp_line
			(start 0.12065 -0.3048)
			(end 0.67945 -0.3048)
			(stroke
				(width 0.1)
				(type default)
			)
			(layer "F.Fab")
		)
		(fp_line
			(start 0.67945 -0.3048)
			(end 0.67945 0.3048)
			(stroke
				(width 0.1)
				(type default)
			)
			(layer "F.Fab")
		)
		(fp_line
			(start -0.67945 -0.305054)
			(end -0.12065 -0.305054)
			(stroke
				(width 0.1)
				(type default)
			)
			(layer "F.Fab")
		)
		(fp_line
			(start -0.12065 -0.305054)
			(end -0.12065 -0.2794)
			(stroke
				(width 0.1)
				(type default)
			)
			(layer "F.Fab")
		)
		(pad "1" smd circle
			(at -0.40005 0 270)
			(size 0 0)
			(layers "F.Cu" "F.Mask" "F.Paste")
			(net "SW_P12V_PVCCIN_CPU1_FLT")
		)
		(pad "2" smd circle
			(at 0.40005 0 270)
			(size 0 0)
			(layers "F.Cu" "F.Mask" "F.Paste")
			(net "GND")
		)
	)
	(footprint ""
		(layer "F.Cu")
		(at 40.36568 -258.091686)
		(property "Reference" "J19"
			(at -5.21716 -81.970372 0)
			(unlocked yes)
			(layer "F.SilkS")
			(effects
				(font
					(size 0.7874 0.5842)
					(thickness 0.1524)
				)
				(justify left)
			)
		)
		(property "Value" ""
			(at 0 0 0)
			(layer "F.Fab")
			(effects
				(font
					(size 1.27 1.27)
				)
			)
		)
		(duplicate_pad_numbers_are_jumpers no)
		(fp_line
			(start -3.24993 -81.000092)
			(end -3.24993 74.593958)
			(stroke
				(width 0.1524)
				(type default)
			)
			(layer "F.SilkS")
		)
		(fp_line
			(start -1.51384 81.000092)
			(end 3.24993 81.000092)
			(stroke
				(width 0.1524)
				(type default)
			)
			(layer "F.SilkS")
		)
		(fp_line
			(start -1.25984 -81.000092)
			(end -3.24993 -81.000092)
			(stroke
				(width 0.1524)
				(type default)
			)
			(layer "F.SilkS")
		)
		(fp_line
			(start 3.24993 -81.000092)
			(end 1.66624 -81.000092)
			(stroke
				(width 0.1524)
				(type default)
			)
			(layer "F.SilkS")
		)
		(fp_line
			(start 3.24993 -72.00011)
			(end -3.24993 -72.00011)
			(stroke
				(width 0.1524)
				(type default)
			)
			(layer "F.SilkS")
		)
		(fp_line
			(start 3.24993 72.00011)
			(end -3.24993 72.00011)
			(stroke
				(width 0.1524)
				(type default)
			)
			(layer "F.SilkS")
		)
		(fp_line
			(start 3.24993 81.000092)
			(end 3.24993 -81.000092)
			(stroke
				(width 0.1524)
				(type default)
			)
			(layer "F.SilkS")
		)
		(fp_poly
			(pts
				(xy -4.200906 -63.759842) (xy -3.366008 -63.342266) (xy -4.200906 -62.92469)
			)
			(stroke
				(width 0)
				(type default)
			)
			(fill yes)
			(layer "F.SilkS")
		)
		(fp_line
			(start -3.24993 -81.000092)
			(end -3.24993 81.000092)
			(stroke
				(width 0.1)
				(type default)
			)
			(layer "F.Fab")
		)
		(fp_line
			(start -3.24993 81.000092)
			(end 3.24993 81.000092)
			(stroke
				(width 0.1)
				(type default)
			)
			(layer "F.Fab")
		)
		(fp_line
			(start 3.24993 -81.000092)
			(end -3.24993 -81.000092)
			(stroke
				(width 0.1)
				(type default)
			)
			(layer "F.Fab")
		)
		(fp_line
			(start 3.24993 -72.00011)
			(end -3.24993 -72.00011)
			(stroke
				(width 0.1)
				(type default)
			)
			(layer "F.Fab")
		)
		(fp_line
			(start 3.24993 -71.000112)
			(end -3.24993 -71.000112)
			(stroke
				(width 0.1)
				(type default)
			)
			(layer "F.Fab")
		)
		(fp_line
			(start 3.24993 71.000112)
			(end -3.24993 71.000112)
			(stroke
				(width 0.1)
				(type default)
			)
			(layer "F.Fab")
		)
		(fp_line
			(start 3.24993 72.00011)
			(end -3.24993 72.00011)
			(stroke
				(width 0.1)
				(type default)
			)
			(layer "F.Fab")
		)
		(fp_line
			(start 3.24993 81.000092)
			(end 3.24993 -81.000092)
			(stroke
				(width 0.1)
				(type default)
			)
			(layer "F.Fab")
		)
		(fp_poly
			(pts
				(xy -4.445 -63.832994) (xy -4.445 -62.816994) (xy -3.429 -63.324994)
			)
			(stroke
				(width 0)
				(type default)
			)
			(fill yes)
			(layer "F.Fab")
		)
		(pad "1" smd rect
			(at -2.050034 -63.324994 270)
			(size 0.519938 1.4986)
			(layers "F.Cu" "F.Mask" "F.Paste")
			(net "P12V_S3_AUX_CPU1_NVDIMM")
		)
		(pad "2" smd rect
			(at -2.050034 -62.47511 270)
			(size 0.519938 1.4986)
			(layers "F.Cu" "F.Mask" "F.Paste")
			(net "TP_CHB_CPU1_DIMM1_FRU_0")
		)
		(pad "3" smd rect
			(at -2.050034 -61.624972 270)
			(size 0.519938 1.4986)
			(layers "F.Cu" "F.Mask" "F.Paste")
			(net "P3V3_AUX")
		)
		(pad "4" smd rect
			(at -2.050034 -60.775088 270)
			(size 0.519938 1.4986)
			(layers "F.Cu" "F.Mask" "F.Paste")
			(net "I3C_SPD_DDRABCD_CPU1_LVC1_SCL_2")
		)
		(pad "5" smd rect
			(at -2.050034 -59.92495 270)
			(size 0.519938 1.4986)
			(layers "F.Cu" "F.Mask" "F.Paste")
			(net "I3C_SPD_DDRABCD_CPU1_LVC1_SDA")
		)
		(pad "6" smd rect
			(at -2.050034 -59.075066 270)
			(size 0.519938 1.4986)
			(layers "F.Cu" "F.Mask" "F.Paste")
			(net "GND")
		)
		(pad "7" smd rect
			(at -2.050034 -58.224928 270)
			(size 0.519938 1.4986)
			(layers "F.Cu" "F.Mask" "F.Paste")
			(net "M_B_CPU1_SA_DQ<0>")
		)
		(pad "8" smd rect
			(at -2.050034 -57.375044 270)
			(size 0.519938 1.4986)
			(layers "F.Cu" "F.Mask" "F.Paste")
			(net "GND")
		)
		(pad "9" smd rect
			(at -2.050034 -56.524906 270)
			(size 0.519938 1.4986)
			(layers "F.Cu" "F.Mask" "F.Paste")
			(net "M_B_CPU1_SA_DQ<1>")
		)
		(pad "10" smd rect
			(at -2.050034 -55.675022 270)
			(size 0.519938 1.4986)
			(layers "F.Cu" "F.Mask" "F.Paste")
			(net "GND")
		)
		(pad "11" smd rect
			(at -2.050034 -54.824884 270)
			(size 0.519938 1.4986)
			(layers "F.Cu" "F.Mask" "F.Paste")
			(net "M_B_CPU1_SA_DQS_DP<0>")
		)
		(pad "12" smd rect
			(at -2.050034 -53.975 270)
			(size 0.519938 1.4986)
			(layers "F.Cu" "F.Mask" "F.Paste")
			(net "M_B_CPU1_SA_DQS_DN<0>")
		)
		(pad "13" smd rect
			(at -2.050034 -53.125116 270)
			(size 0.519938 1.4986)
			(layers "F.Cu" "F.Mask" "F.Paste")
			(net "GND")
		)
		(pad "14" smd rect
			(at -2.050034 -52.274978 270)
			(size 0.519938 1.4986)
			(layers "F.Cu" "F.Mask" "F.Paste")
			(net "M_B_CPU1_SA_DQ<4>")
		)
		(pad "15" smd rect
			(at -2.050034 -51.425094 270)
			(size 0.519938 1.4986)
			(layers "F.Cu" "F.Mask" "F.Paste")
			(net "GND")
		)
		(pad "16" smd rect
			(at -2.050034 -50.574956 270)
			(size 0.519938 1.4986)
			(layers "F.Cu" "F.Mask" "F.Paste")
			(net "M_B_CPU1_SA_DQ<5>")
		)
		(pad "17" smd rect
			(at -2.050034 -49.725072 270)
			(size 0.519938 1.4986)
			(layers "F.Cu" "F.Mask" "F.Paste")
			(net "GND")
		)
		(pad "18" smd rect
			(at -2.050034 -48.874934 270)
			(size 0.519938 1.4986)
			(layers "F.Cu" "F.Mask" "F.Paste")
			(net "M_B_CPU1_SA_DQ<8>")
		)
		(pad "19" smd rect
			(at -2.050034 -48.02505 270)
			(size 0.519938 1.4986)
			(layers "F.Cu" "F.Mask" "F.Paste")
			(net "GND")
		)
		(pad "20" smd rect
			(at -2.050034 -47.174912 270)
			(size 0.519938 1.4986)
			(layers "F.Cu" "F.Mask" "F.Paste")
			(net "M_B_CPU1_SA_DQ<9>")
		)
		(pad "21" smd rect
			(at -2.050034 -46.325028 270)
			(size 0.519938 1.4986)
			(layers "F.Cu" "F.Mask" "F.Paste")
			(net "GND")
		)
		(pad "22" smd rect
			(at -2.050034 -45.47489 270)
			(size 0.519938 1.4986)
			(layers "F.Cu" "F.Mask" "F.Paste")
			(net "M_B_CPU1_SA_DQS_DP<1>")
		)
		(pad "23" smd rect
			(at -2.050034 -44.625006 270)
			(size 0.519938 1.4986)
			(layers "F.Cu" "F.Mask" "F.Paste")
			(net "M_B_CPU1_SA_DQS_DN<1>")
		)
		(pad "24" smd rect
			(at -2.050034 -43.775122 270)
			(size 0.519938 1.4986)
			(layers "F.Cu" "F.Mask" "F.Paste")
			(net "GND")
		)
		(pad "25" smd rect
			(at -2.050034 -42.924984 270)
			(size 0.519938 1.4986)
			(layers "F.Cu" "F.Mask" "F.Paste")
			(net "M_B_CPU1_SA_DQ<12>")
		)
		(pad "26" smd rect
			(at -2.050034 -42.0751 270)
			(size 0.519938 1.4986)
			(layers "F.Cu" "F.Mask" "F.Paste")
			(net "GND")
		)
		(pad "27" smd rect
			(at -2.050034 -41.224962 270)
			(size 0.519938 1.4986)
			(layers "F.Cu" "F.Mask" "F.Paste")
			(net "M_B_CPU1_SA_DQ<13>")
		)
		(pad "28" smd rect
			(at -2.050034 -40.375078 270)
			(size 0.519938 1.4986)
			(layers "F.Cu" "F.Mask" "F.Paste")
			(net "GND")
		)
		(pad "29" smd rect
			(at -2.050034 -39.52494 270)
			(size 0.519938 1.4986)
			(layers "F.Cu" "F.Mask" "F.Paste")
			(net "M_B_CPU1_SA_DQ<16>")
		)
		(pad "30" smd rect
			(at -2.050034 -38.675056 270)
			(size 0.519938 1.4986)
			(layers "F.Cu" "F.Mask" "F.Paste")
			(net "GND")
		)
		(pad "31" smd rect
			(at -2.050034 -37.824918 270)
			(size 0.519938 1.4986)
			(layers "F.Cu" "F.Mask" "F.Paste")
			(net "M_B_CPU1_SA_DQ<17>")
		)
		(pad "32" smd rect
			(at -2.050034 -36.975034 270)
			(size 0.519938 1.4986)
			(layers "F.Cu" "F.Mask" "F.Paste")
			(net "GND")
		)
		(pad "33" smd rect
			(at -2.050034 -36.124896 270)
			(size 0.519938 1.4986)
			(layers "F.Cu" "F.Mask" "F.Paste")
			(net "M_B_CPU1_SA_DQS_DP<2>")
		)
		(pad "34" smd rect
			(at -2.050034 -35.275012 270)
			(size 0.519938 1.4986)
			(layers "F.Cu" "F.Mask" "F.Paste")
			(net "M_B_CPU1_SA_DQS_DN<2>")
		)
		(pad "35" smd rect
			(at -2.050034 -34.425128 270)
			(size 0.519938 1.4986)
			(layers "F.Cu" "F.Mask" "F.Paste")
			(net "GND")
		)
		(pad "36" smd rect
			(at -2.050034 -33.57499 270)
			(size 0.519938 1.4986)
			(layers "F.Cu" "F.Mask" "F.Paste")
			(net "M_B_CPU1_SA_DQ<20>")
		)
		(pad "37" smd rect
			(at -2.050034 -32.725106 270)
			(size 0.519938 1.4986)
			(layers "F.Cu" "F.Mask" "F.Paste")
			(net "GND")
		)
		(pad "38" smd rect
			(at -2.050034 -31.874968 270)
			(size 0.519938 1.4986)
			(layers "F.Cu" "F.Mask" "F.Paste")
			(net "M_B_CPU1_SA_DQ<21>")
		)
		(pad "39" smd rect
			(at -2.050034 -31.025084 270)
			(size 0.519938 1.4986)
			(layers "F.Cu" "F.Mask" "F.Paste")
			(net "GND")
		)
		(pad "40" smd rect
			(at -2.050034 -30.174946 270)
			(size 0.519938 1.4986)
			(layers "F.Cu" "F.Mask" "F.Paste")
			(net "M_B_CPU1_SA_DQ<24>")
		)
		(pad "41" smd rect
			(at -2.050034 -29.325062 270)
			(size 0.519938 1.4986)
			(layers "F.Cu" "F.Mask" "F.Paste")
			(net "GND")
		)
		(pad "42" smd rect
			(at -2.050034 -28.474924 270)
			(size 0.519938 1.4986)
			(layers "F.Cu" "F.Mask" "F.Paste")
			(net "M_B_CPU1_SA_DQ<25>")
		)
		(pad "43" smd rect
			(at -2.050034 -27.62504 270)
			(size 0.519938 1.4986)
			(layers "F.Cu" "F.Mask" "F.Paste")
			(net "GND")
		)
		(pad "44" smd rect
			(at -2.050034 -26.774902 270)
			(size 0.519938 1.4986)
			(layers "F.Cu" "F.Mask" "F.Paste")
			(net "M_B_CPU1_SA_DQS_DP<3>")
		)
		(pad "45" smd rect
			(at -2.050034 -25.925018 270)
			(size 0.519938 1.4986)
			(layers "F.Cu" "F.Mask" "F.Paste")
			(net "M_B_CPU1_SA_DQS_DN<3>")
		)
		(pad "46" smd rect
			(at -2.050034 -25.07488 270)
			(size 0.519938 1.4986)
			(layers "F.Cu" "F.Mask" "F.Paste")
			(net "GND")
		)
		(pad "47" smd rect
			(at -2.050034 -24.224996 270)
			(size 0.519938 1.4986)
			(layers "F.Cu" "F.Mask" "F.Paste")
			(net "M_B_CPU1_SA_DQ<28>")
		)
		(pad "48" smd rect
			(at -2.050034 -23.375112 270)
			(size 0.519938 1.4986)
			(layers "F.Cu" "F.Mask" "F.Paste")
			(net "GND")
		)
		(pad "49" smd rect
			(at -2.050034 -22.524974 270)
			(size 0.519938 1.4986)
			(layers "F.Cu" "F.Mask" "F.Paste")
			(net "M_B_CPU1_SA_DQ<29>")
		)
		(pad "50" smd rect
			(at -2.050034 -21.67509 270)
			(size 0.519938 1.4986)
			(layers "F.Cu" "F.Mask" "F.Paste")
			(net "GND")
		)
		(pad "51" smd rect
			(at -2.050034 -20.824952 270)
			(size 0.519938 1.4986)
			(layers "F.Cu" "F.Mask" "F.Paste")
			(net "M_B_CPU1_SA_CB<0>")
		)
		(pad "52" smd rect
			(at -2.050034 -19.975068 270)
			(size 0.519938 1.4986)
			(layers "F.Cu" "F.Mask" "F.Paste")
			(net "GND")
		)
		(pad "53" smd rect
			(at -2.050034 -19.12493 270)
			(size 0.519938 1.4986)
			(layers "F.Cu" "F.Mask" "F.Paste")
			(net "M_B_CPU1_SA_CB<1>")
		)
		(pad "54" smd rect
			(at -2.050034 -18.275046 270)
			(size 0.519938 1.4986)
			(layers "F.Cu" "F.Mask" "F.Paste")
			(net "GND")
		)
		(pad "55" smd rect
			(at -2.050034 -17.424908 270)
			(size 0.519938 1.4986)
			(layers "F.Cu" "F.Mask" "F.Paste")
			(net "M_B_CPU1_SA_DQS_DP<4>")
		)
		(pad "56" smd rect
			(at -2.050034 -16.575024 270)
			(size 0.519938 1.4986)
			(layers "F.Cu" "F.Mask" "F.Paste")
			(net "M_B_CPU1_SA_DQS_DN<4>")
		)
		(pad "57" smd rect
			(at -2.050034 -15.724886 270)
			(size 0.519938 1.4986)
			(layers "F.Cu" "F.Mask" "F.Paste")
			(net "GND")
		)
		(pad "58" smd rect
			(at -2.050034 -14.875002 270)
			(size 0.519938 1.4986)
			(layers "F.Cu" "F.Mask" "F.Paste")
			(net "M_B_CPU1_SA_CB<4>")
		)
		(pad "59" smd rect
			(at -2.050034 -14.025118 270)
			(size 0.519938 1.4986)
			(layers "F.Cu" "F.Mask" "F.Paste")
			(net "GND")
		)
		(pad "60" smd rect
			(at -2.050034 -13.17498 270)
			(size 0.519938 1.4986)
			(layers "F.Cu" "F.Mask" "F.Paste")
			(net "M_B_CPU1_SA_CB<5>")
		)
		(pad "61" smd rect
			(at -2.050034 -12.325096 270)
			(size 0.519938 1.4986)
			(layers "F.Cu" "F.Mask" "F.Paste")
			(net "GND")
		)
		(pad "62" smd rect
			(at -2.050034 -11.474958 270)
			(size 0.519938 1.4986)
			(layers "F.Cu" "F.Mask" "F.Paste")
			(net "M_B_CPU1_ALERT_N")
		)
		(pad "63" smd rect
			(at -2.050034 -10.625074 270)
			(size 0.519938 1.4986)
			(layers "F.Cu" "F.Mask" "F.Paste")
			(net "GND")
		)
		(pad "64" smd rect
			(at -2.050034 -9.774936 270)
			(size 0.519938 1.4986)
			(layers "F.Cu" "F.Mask" "F.Paste")
			(net "M_B_CPU1_SA_CS_N<0>")
		)
		(pad "65" smd rect
			(at -2.050034 -8.925052 270)
			(size 0.519938 1.4986)
			(layers "F.Cu" "F.Mask" "F.Paste")
			(net "GND")
		)
		(pad "66" smd rect
			(at -2.050034 -8.074914 270)
			(size 0.519938 1.4986)
			(layers "F.Cu" "F.Mask" "F.Paste")
			(net "M_B_CPU1_SA_CA<0>")
		)
		(pad "67" smd rect
			(at -2.050034 -7.22503 270)
			(size 0.519938 1.4986)
			(layers "F.Cu" "F.Mask" "F.Paste")
			(net "GND")
		)
		(pad "68" smd rect
			(at -2.050034 -6.374892 270)
			(size 0.519938 1.4986)
			(layers "F.Cu" "F.Mask" "F.Paste")
			(net "M_B_CPU1_SA_CA<2>")
		)
		(pad "69" smd rect
			(at -2.050034 -5.525008 270)
			(size 0.519938 1.4986)
			(layers "F.Cu" "F.Mask" "F.Paste")
			(net "GND")
		)
		(pad "70" smd rect
			(at -2.050034 -4.675124 270)
			(size 0.519938 1.4986)
			(layers "F.Cu" "F.Mask" "F.Paste")
			(net "M_B_CPU1_SA_CA<4>")
		)
		(pad "71" smd rect
			(at -2.050034 -3.824986 270)
			(size 0.519938 1.4986)
			(layers "F.Cu" "F.Mask" "F.Paste")
			(net "GND")
		)
		(pad "72" smd rect
			(at -2.050034 -2.975102 270)
			(size 0.519938 1.4986)
			(layers "F.Cu" "F.Mask" "F.Paste")
			(net "M_B_CPU1_SA_CA<6>")
		)
		(pad "73" smd rect
			(at -2.050034 -2.124964 270)
			(size 0.519938 1.4986)
			(layers "F.Cu" "F.Mask" "F.Paste")
			(net "GND")
		)
		(pad "74" smd rect
			(at -2.050034 -1.27508 270)
			(size 0.519938 1.4986)
			(layers "F.Cu" "F.Mask" "F.Paste")
			(net "M_B_CPU1_SA_PAR")
		)
		(pad "75" smd rect
			(at -2.050034 -0.424942 270)
			(size 0.519938 1.4986)
			(layers "F.Cu" "F.Mask" "F.Paste")
			(net "GND")
		)
		(pad "76" smd rect
			(at -2.050034 5.525008 270)
			(size 0.519938 1.4986)
			(layers "F.Cu" "F.Mask" "F.Paste")
			(net "M_B_CPU1_SB_CA<0>")
		)
		(pad "77" smd rect
			(at -2.050034 6.374892 270)
			(size 0.519938 1.4986)
			(layers "F.Cu" "F.Mask" "F.Paste")
			(net "GND")
		)
		(pad "78" smd rect
			(at -2.050034 7.22503 270)
			(size 0.519938 1.4986)
			(layers "F.Cu" "F.Mask" "F.Paste")
			(net "M_B_CPU1_SB_CA<2>")
		)
		(pad "79" smd rect
			(at -2.050034 8.074914 270)
			(size 0.519938 1.4986)
			(layers "F.Cu" "F.Mask" "F.Paste")
			(net "GND")
		)
		(pad "80" smd rect
			(at -2.050034 8.925052 270)
			(size 0.519938 1.4986)
			(layers "F.Cu" "F.Mask" "F.Paste")
			(net "M_B_CPU1_SB_CA<4>")
		)
		(pad "81" smd rect
			(at -2.050034 9.774936 270)
			(size 0.519938 1.4986)
			(layers "F.Cu" "F.Mask" "F.Paste")
			(net "GND")
		)
		(pad "82" smd rect
			(at -2.050034 10.625074 270)
			(size 0.519938 1.4986)
			(layers "F.Cu" "F.Mask" "F.Paste")
			(net "M_B_CPU1_SB_CA<6>")
		)
		(pad "83" smd rect
			(at -2.050034 11.474958 270)
			(size 0.519938 1.4986)
			(layers "F.Cu" "F.Mask" "F.Paste")
			(net "GND")
		)
		(pad "84" smd rect
			(at -2.050034 12.325096 270)
			(size 0.519938 1.4986)
			(layers "F.Cu" "F.Mask" "F.Paste")
			(net "M_B_CPU1_SB_CS_N<0>")
		)
		(pad "85" smd rect
			(at -2.050034 13.17498 270)
			(size 0.519938 1.4986)
			(layers "F.Cu" "F.Mask" "F.Paste")
			(net "GND")
		)
		(pad "86" smd rect
			(at -2.050034 14.025118 270)
			(size 0.519938 1.4986)
			(layers "F.Cu" "F.Mask" "F.Paste")
			(net "M_B_CPU1_SA_RSP<0>")
		)
		(pad "87" smd rect
			(at -2.050034 14.875002 270)
			(size 0.519938 1.4986)
			(layers "F.Cu" "F.Mask" "F.Paste")
			(net "M_B_CPU1_SB_RSP<0>")
		)
		(pad "88" smd rect
			(at -2.050034 15.724886 270)
			(size 0.519938 1.4986)
			(layers "F.Cu" "F.Mask" "F.Paste")
			(net "GND")
		)
		(pad "89" smd rect
			(at -2.050034 16.575024 270)
			(size 0.519938 1.4986)
			(layers "F.Cu" "F.Mask" "F.Paste")
			(net "M_B_CPU1_SB_CB<4>")
		)
		(pad "90" smd rect
			(at -2.050034 17.424908 270)
			(size 0.519938 1.4986)
			(layers "F.Cu" "F.Mask" "F.Paste")
			(net "GND")
		)
		(pad "91" smd rect
			(at -2.050034 18.275046 270)
			(size 0.519938 1.4986)
			(layers "F.Cu" "F.Mask" "F.Paste")
			(net "M_B_CPU1_SB_CB<5>")
		)
		(pad "92" smd rect
			(at -2.050034 19.12493 270)
			(size 0.519938 1.4986)
			(layers "F.Cu" "F.Mask" "F.Paste")
			(net "GND")
		)
		(pad "93" smd rect
			(at -2.050034 19.975068 270)
			(size 0.519938 1.4986)
			(layers "F.Cu" "F.Mask" "F.Paste")
			(net "M_B_CPU1_SB_DQS_DP<9>")
		)
		(pad "94" smd rect
			(at -2.050034 20.824952 270)
			(size 0.519938 1.4986)
			(layers "F.Cu" "F.Mask" "F.Paste")
			(net "M_B_CPU1_SB_DQS_DN<9>")
		)
		(pad "95" smd rect
			(at -2.050034 21.67509 270)
			(size 0.519938 1.4986)
			(layers "F.Cu" "F.Mask" "F.Paste")
			(net "GND")
		)
		(pad "96" smd rect
			(at -2.050034 22.524974 270)
			(size 0.519938 1.4986)
			(layers "F.Cu" "F.Mask" "F.Paste")
			(net "M_B_CPU1_SB_CB<0>")
		)
		(pad "97" smd rect
			(at -2.050034 23.375112 270)
			(size 0.519938 1.4986)
			(layers "F.Cu" "F.Mask" "F.Paste")
			(net "GND")
		)
		(pad "98" smd rect
			(at -2.050034 24.224996 270)
			(size 0.519938 1.4986)
			(layers "F.Cu" "F.Mask" "F.Paste")
			(net "M_B_CPU1_SB_CB<1>")
		)
		(pad "99" smd rect
			(at -2.050034 25.07488 270)
			(size 0.519938 1.4986)
			(layers "F.Cu" "F.Mask" "F.Paste")
			(net "GND")
		)
		(pad "100" smd rect
			(at -2.050034 25.925018 270)
			(size 0.519938 1.4986)
			(layers "F.Cu" "F.Mask" "F.Paste")
			(net "M_B_CPU1_SB_DQ<0>")
		)
		(pad "101" smd rect
			(at -2.050034 26.774902 270)
			(size 0.519938 1.4986)
			(layers "F.Cu" "F.Mask" "F.Paste")
			(net "GND")
		)
		(pad "102" smd rect
			(at -2.050034 27.62504 270)
			(size 0.519938 1.4986)
			(layers "F.Cu" "F.Mask" "F.Paste")
			(net "M_B_CPU1_SB_DQ<1>")
		)
		(pad "103" smd rect
			(at -2.050034 28.474924 270)
			(size 0.519938 1.4986)
			(layers "F.Cu" "F.Mask" "F.Paste")
			(net "GND")
		)
		(pad "104" smd rect
			(at -2.050034 29.325062 270)
			(size 0.519938 1.4986)
			(layers "F.Cu" "F.Mask" "F.Paste")
			(net "M_B_CPU1_SB_DQS_DP<0>")
		)
		(pad "105" smd rect
			(at -2.050034 30.174946 270)
			(size 0.519938 1.4986)
			(layers "F.Cu" "F.Mask" "F.Paste")
			(net "M_B_CPU1_SB_DQS_DN<0>")
		)
		(pad "106" smd rect
			(at -2.050034 31.025084 270)
			(size 0.519938 1.4986)
			(layers "F.Cu" "F.Mask" "F.Paste")
			(net "GND")
		)
		(pad "107" smd rect
			(at -2.050034 31.874968 270)
			(size 0.519938 1.4986)
			(layers "F.Cu" "F.Mask" "F.Paste")
			(net "M_B_CPU1_SB_DQ<4>")
		)
		(pad "108" smd rect
			(at -2.050034 32.725106 270)
			(size 0.519938 1.4986)
			(layers "F.Cu" "F.Mask" "F.Paste")
			(net "GND")
		)
		(pad "109" smd rect
			(at -2.050034 33.57499 270)
			(size 0.519938 1.4986)
			(layers "F.Cu" "F.Mask" "F.Paste")
			(net "M_B_CPU1_SB_DQ<5>")
		)
		(pad "110" smd rect
			(at -2.050034 34.425128 270)
			(size 0.519938 1.4986)
			(layers "F.Cu" "F.Mask" "F.Paste")
			(net "GND")
		)
		(pad "111" smd rect
			(at -2.050034 35.275012 270)
			(size 0.519938 1.4986)
			(layers "F.Cu" "F.Mask" "F.Paste")
			(net "M_B_CPU1_SB_DQ<8>")
		)
		(pad "112" smd rect
			(at -2.050034 36.124896 270)
			(size 0.519938 1.4986)
			(layers "F.Cu" "F.Mask" "F.Paste")
			(net "GND")
		)
		(pad "113" smd rect
			(at -2.050034 36.975034 270)
			(size 0.519938 1.4986)
			(layers "F.Cu" "F.Mask" "F.Paste")
			(net "M_B_CPU1_SB_DQ<9>")
		)
		(pad "114" smd rect
			(at -2.050034 37.824918 270)
			(size 0.519938 1.4986)
			(layers "F.Cu" "F.Mask" "F.Paste")
			(net "GND")
		)
		(pad "115" smd rect
			(at -2.050034 38.675056 270)
			(size 0.519938 1.4986)
			(layers "F.Cu" "F.Mask" "F.Paste")
			(net "M_B_CPU1_SB_DQS_DP<1>")
		)
		(pad "116" smd rect
			(at -2.050034 39.52494 270)
			(size 0.519938 1.4986)
			(layers "F.Cu" "F.Mask" "F.Paste")
			(net "M_B_CPU1_SB_DQS_DN<1>")
		)
		(pad "117" smd rect
			(at -2.050034 40.375078 270)
			(size 0.519938 1.4986)
			(layers "F.Cu" "F.Mask" "F.Paste")
			(net "GND")
		)
		(pad "118" smd rect
			(at -2.050034 41.224962 270)
			(size 0.519938 1.4986)
			(layers "F.Cu" "F.Mask" "F.Paste")
			(net "M_B_CPU1_SB_DQ<12>")
		)
		(pad "119" smd rect
			(at -2.050034 42.0751 270)
			(size 0.519938 1.4986)
			(layers "F.Cu" "F.Mask" "F.Paste")
			(net "GND")
		)
		(pad "120" smd rect
			(at -2.050034 42.924984 270)
			(size 0.519938 1.4986)
			(layers "F.Cu" "F.Mask" "F.Paste")
			(net "M_B_CPU1_SB_DQ<13>")
		)
		(pad "121" smd rect
			(at -2.050034 43.775122 270)
			(size 0.519938 1.4986)
			(layers "F.Cu" "F.Mask" "F.Paste")
			(net "GND")
		)
		(pad "122" smd rect
			(at -2.050034 44.625006 270)
			(size 0.519938 1.4986)
			(layers "F.Cu" "F.Mask" "F.Paste")
			(net "M_B_CPU1_SB_DQ<16>")
		)
		(pad "123" smd rect
			(at -2.050034 45.47489 270)
			(size 0.519938 1.4986)
			(layers "F.Cu" "F.Mask" "F.Paste")
			(net "GND")
		)
		(pad "124" smd rect
			(at -2.050034 46.325028 270)
			(size 0.519938 1.4986)
			(layers "F.Cu" "F.Mask" "F.Paste")
			(net "M_B_CPU1_SB_DQ<17>")
		)
		(pad "125" smd rect
			(at -2.050034 47.174912 270)
			(size 0.519938 1.4986)
			(layers "F.Cu" "F.Mask" "F.Paste")
			(net "GND")
		)
		(pad "126" smd rect
			(at -2.050034 48.02505 270)
			(size 0.519938 1.4986)
			(layers "F.Cu" "F.Mask" "F.Paste")
			(net "M_B_CPU1_SB_DQS_DP<2>")
		)
		(pad "127" smd rect
			(at -2.050034 48.874934 270)
			(size 0.519938 1.4986)
			(layers "F.Cu" "F.Mask" "F.Paste")
			(net "M_B_CPU1_SB_DQS_DN<2>")
		)
		(pad "128" smd rect
			(at -2.050034 49.725072 270)
			(size 0.519938 1.4986)
			(layers "F.Cu" "F.Mask" "F.Paste")
			(net "GND")
		)
		(pad "129" smd rect
			(at -2.050034 50.574956 270)
			(size 0.519938 1.4986)
			(layers "F.Cu" "F.Mask" "F.Paste")
			(net "M_B_CPU1_SB_DQ<20>")
		)
		(pad "130" smd rect
			(at -2.050034 51.425094 270)
			(size 0.519938 1.4986)
			(layers "F.Cu" "F.Mask" "F.Paste")
			(net "GND")
		)
		(pad "131" smd rect
			(at -2.050034 52.274978 270)
			(size 0.519938 1.4986)
			(layers "F.Cu" "F.Mask" "F.Paste")
			(net "M_B_CPU1_SB_DQ<21>")
		)
		(pad "132" smd rect
			(at -2.050034 53.125116 270)
			(size 0.519938 1.4986)
			(layers "F.Cu" "F.Mask" "F.Paste")
			(net "GND")
		)
		(pad "133" smd rect
			(at -2.050034 53.975 270)
			(size 0.519938 1.4986)
			(layers "F.Cu" "F.Mask" "F.Paste")
			(net "M_B_CPU1_SB_DQ<24>")
		)
		(pad "134" smd rect
			(at -2.050034 54.824884 270)
			(size 0.519938 1.4986)
			(layers "F.Cu" "F.Mask" "F.Paste")
			(net "GND")
		)
		(pad "135" smd rect
			(at -2.050034 55.675022 270)
			(size 0.519938 1.4986)
			(layers "F.Cu" "F.Mask" "F.Paste")
			(net "M_B_CPU1_SB_DQ<25>")
		)
		(pad "136" smd rect
			(at -2.050034 56.524906 270)
			(size 0.519938 1.4986)
			(layers "F.Cu" "F.Mask" "F.Paste")
			(net "GND")
		)
		(pad "137" smd rect
			(at -2.050034 57.375044 270)
			(size 0.519938 1.4986)
			(layers "F.Cu" "F.Mask" "F.Paste")
			(net "M_B_CPU1_SB_DQS_DP<3>")
		)
		(pad "138" smd rect
			(at -2.050034 58.224928 270)
			(size 0.519938 1.4986)
			(layers "F.Cu" "F.Mask" "F.Paste")
			(net "M_B_CPU1_SB_DQS_DN<3>")
		)
		(pad "139" smd rect
			(at -2.050034 59.075066 270)
			(size 0.519938 1.4986)
			(layers "F.Cu" "F.Mask" "F.Paste")
			(net "GND")
		)
		(pad "140" smd rect
			(at -2.050034 59.92495 270)
			(size 0.519938 1.4986)
			(layers "F.Cu" "F.Mask" "F.Paste")
			(net "M_B_CPU1_SB_DQ<28>")
		)
		(pad "141" smd rect
			(at -2.050034 60.775088 270)
			(size 0.519938 1.4986)
			(layers "F.Cu" "F.Mask" "F.Paste")
			(net "GND")
		)
		(pad "142" smd rect
			(at -2.050034 61.624972 270)
			(size 0.519938 1.4986)
			(layers "F.Cu" "F.Mask" "F.Paste")
			(net "M_B_CPU1_SB_DQ<29>")
		)
		(pad "143" smd rect
			(at -2.050034 62.47511 270)
			(size 0.519938 1.4986)
			(layers "F.Cu" "F.Mask" "F.Paste")
			(net "GND")
		)
		(pad "144" smd rect
			(at -2.050034 63.324994 270)
			(size 0.519938 1.4986)
			(layers "F.Cu" "F.Mask" "F.Paste")
			(net "TP_CHB_CPU1_DIMM1_FRU_1")
		)
		(pad "145" smd rect
			(at 2.050034 -63.324994 270)
			(size 0.519938 1.4986)
			(layers "F.Cu" "F.Mask" "F.Paste")
			(net "P12V_S3_AUX_CPU1_NVDIMM")
		)
		(pad "146" smd rect
			(at 2.050034 -62.47511 270)
			(size 0.519938 1.4986)
			(layers "F.Cu" "F.Mask" "F.Paste")
			(net "P12V_S3_AUX_CPU1_NVDIMM")
		)
		(pad "147" smd rect
			(at 2.050034 -61.624972 270)
			(size 0.519938 1.4986)
			(layers "F.Cu" "F.Mask" "F.Paste")
			(net "PWRGD_CHB_CPU1_DIMM1")
		)
		(pad "148" smd rect
			(at 2.050034 -60.775088 270)
			(size 0.519938 1.4986)
			(layers "F.Cu" "F.Mask" "F.Paste")
			(net "PD_CHB_CPU1_DIMM1_SAA")
		)
		(pad "149" smd rect
			(at 2.050034 -59.92495 270)
			(size 0.519938 1.4986)
			(layers "F.Cu" "F.Mask" "F.Paste")
			(net "TP_CHB_CPU1_DIMM1_FRU_2")
		)
		(pad "150" smd rect
			(at 2.050034 -59.075066 270)
			(size 0.519938 1.4986)
			(layers "F.Cu" "F.Mask" "F.Paste")
			(net "TP_CHB_CPU1_DIMM1_FRU_3")
		)
		(pad "151" smd rect
			(at 2.050034 -58.224928 270)
			(size 0.519938 1.4986)
			(layers "F.Cu" "F.Mask" "F.Paste")
			(net "GND")
		)
		(pad "152" smd rect
			(at 2.050034 -57.375044 270)
			(size 0.519938 1.4986)
			(layers "F.Cu" "F.Mask" "F.Paste")
			(net "M_B_CPU1_SA_DQ<2>")
		)
		(pad "153" smd rect
			(at 2.050034 -56.524906 270)
			(size 0.519938 1.4986)
			(layers "F.Cu" "F.Mask" "F.Paste")
			(net "GND")
		)
		(pad "154" smd rect
			(at 2.050034 -55.675022 270)
			(size 0.519938 1.4986)
			(layers "F.Cu" "F.Mask" "F.Paste")
			(net "M_B_CPU1_SA_DQ<3>")
		)
		(pad "155" smd rect
			(at 2.050034 -54.824884 270)
			(size 0.519938 1.4986)
			(layers "F.Cu" "F.Mask" "F.Paste")
			(net "GND")
		)
		(pad "156" smd rect
			(at 2.050034 -53.975 270)
			(size 0.519938 1.4986)
			(layers "F.Cu" "F.Mask" "F.Paste")
			(net "M_B_CPU1_SA_DQS_DN<5>")
		)
		(pad "157" smd rect
			(at 2.050034 -53.125116 270)
			(size 0.519938 1.4986)
			(layers "F.Cu" "F.Mask" "F.Paste")
			(net "M_B_CPU1_SA_DQS_DP<5>")
		)
		(pad "158" smd rect
			(at 2.050034 -52.274978 270)
			(size 0.519938 1.4986)
			(layers "F.Cu" "F.Mask" "F.Paste")
			(net "GND")
		)
		(pad "159" smd rect
			(at 2.050034 -51.425094 270)
			(size 0.519938 1.4986)
			(layers "F.Cu" "F.Mask" "F.Paste")
			(net "M_B_CPU1_SA_DQ<6>")
		)
		(pad "160" smd rect
			(at 2.050034 -50.574956 270)
			(size 0.519938 1.4986)
			(layers "F.Cu" "F.Mask" "F.Paste")
			(net "GND")
		)
		(pad "161" smd rect
			(at 2.050034 -49.725072 270)
			(size 0.519938 1.4986)
			(layers "F.Cu" "F.Mask" "F.Paste")
			(net "M_B_CPU1_SA_DQ<7>")
		)
		(pad "162" smd rect
			(at 2.050034 -48.874934 270)
			(size 0.519938 1.4986)
			(layers "F.Cu" "F.Mask" "F.Paste")
			(net "GND")
		)
		(pad "163" smd rect
			(at 2.050034 -48.02505 270)
			(size 0.519938 1.4986)
			(layers "F.Cu" "F.Mask" "F.Paste")
			(net "M_B_CPU1_SA_DQ<10>")
		)
		(pad "164" smd rect
			(at 2.050034 -47.174912 270)
			(size 0.519938 1.4986)
			(layers "F.Cu" "F.Mask" "F.Paste")
			(net "GND")
		)
		(pad "165" smd rect
			(at 2.050034 -46.325028 270)
			(size 0.519938 1.4986)
			(layers "F.Cu" "F.Mask" "F.Paste")
			(net "M_B_CPU1_SA_DQ<11>")
		)
		(pad "166" smd rect
			(at 2.050034 -45.47489 270)
			(size 0.519938 1.4986)
			(layers "F.Cu" "F.Mask" "F.Paste")
			(net "GND")
		)
		(pad "167" smd rect
			(at 2.050034 -44.625006 270)
			(size 0.519938 1.4986)
			(layers "F.Cu" "F.Mask" "F.Paste")
			(net "M_B_CPU1_SA_DQS_DN<6>")
		)
		(pad "168" smd rect
			(at 2.050034 -43.775122 270)
			(size 0.519938 1.4986)
			(layers "F.Cu" "F.Mask" "F.Paste")
			(net "M_B_CPU1_SA_DQS_DP<6>")
		)
		(pad "169" smd rect
			(at 2.050034 -42.924984 270)
			(size 0.519938 1.4986)
			(layers "F.Cu" "F.Mask" "F.Paste")
			(net "GND")
		)
		(pad "170" smd rect
			(at 2.050034 -42.0751 270)
			(size 0.519938 1.4986)
			(layers "F.Cu" "F.Mask" "F.Paste")
			(net "M_B_CPU1_SA_DQ<14>")
		)
		(pad "171" smd rect
			(at 2.050034 -41.224962 270)
			(size 0.519938 1.4986)
			(layers "F.Cu" "F.Mask" "F.Paste")
			(net "GND")
		)
		(pad "172" smd rect
			(at 2.050034 -40.375078 270)
			(size 0.519938 1.4986)
			(layers "F.Cu" "F.Mask" "F.Paste")
			(net "M_B_CPU1_SA_DQ<15>")
		)
		(pad "173" smd rect
			(at 2.050034 -39.52494 270)
			(size 0.519938 1.4986)
			(layers "F.Cu" "F.Mask" "F.Paste")
			(net "GND")
		)
		(pad "174" smd rect
			(at 2.050034 -38.675056 270)
			(size 0.519938 1.4986)
			(layers "F.Cu" "F.Mask" "F.Paste")
			(net "M_B_CPU1_SA_DQ<18>")
		)
		(pad "175" smd rect
			(at 2.050034 -37.824918 270)
			(size 0.519938 1.4986)
			(layers "F.Cu" "F.Mask" "F.Paste")
			(net "GND")
		)
		(pad "176" smd rect
			(at 2.050034 -36.975034 270)
			(size 0.519938 1.4986)
			(layers "F.Cu" "F.Mask" "F.Paste")
			(net "M_B_CPU1_SA_DQ<19>")
		)
		(pad "177" smd rect
			(at 2.050034 -36.124896 270)
			(size 0.519938 1.4986)
			(layers "F.Cu" "F.Mask" "F.Paste")
			(net "GND")
		)
		(pad "178" smd rect
			(at 2.050034 -35.275012 270)
			(size 0.519938 1.4986)
			(layers "F.Cu" "F.Mask" "F.Paste")
			(net "M_B_CPU1_SA_DQS_DN<7>")
		)
		(pad "179" smd rect
			(at 2.050034 -34.425128 270)
			(size 0.519938 1.4986)
			(layers "F.Cu" "F.Mask" "F.Paste")
			(net "M_B_CPU1_SA_DQS_DP<7>")
		)
		(pad "180" smd rect
			(at 2.050034 -33.57499 270)
			(size 0.519938 1.4986)
			(layers "F.Cu" "F.Mask" "F.Paste")
			(net "GND")
		)
		(pad "181" smd rect
			(at 2.050034 -32.725106 270)
			(size 0.519938 1.4986)
			(layers "F.Cu" "F.Mask" "F.Paste")
			(net "M_B_CPU1_SA_DQ<22>")
		)
		(pad "182" smd rect
			(at 2.050034 -31.874968 270)
			(size 0.519938 1.4986)
			(layers "F.Cu" "F.Mask" "F.Paste")
			(net "GND")
		)
		(pad "183" smd rect
			(at 2.050034 -31.025084 270)
			(size 0.519938 1.4986)
			(layers "F.Cu" "F.Mask" "F.Paste")
			(net "M_B_CPU1_SA_DQ<23>")
		)
		(pad "184" smd rect
			(at 2.050034 -30.174946 270)
			(size 0.519938 1.4986)
			(layers "F.Cu" "F.Mask" "F.Paste")
			(net "GND")
		)
		(pad "185" smd rect
			(at 2.050034 -29.325062 270)
			(size 0.519938 1.4986)
			(layers "F.Cu" "F.Mask" "F.Paste")
			(net "M_B_CPU1_SA_DQ<26>")
		)
		(pad "186" smd rect
			(at 2.050034 -28.474924 270)
			(size 0.519938 1.4986)
			(layers "F.Cu" "F.Mask" "F.Paste")
			(net "GND")
		)
		(pad "187" smd rect
			(at 2.050034 -27.62504 270)
			(size 0.519938 1.4986)
			(layers "F.Cu" "F.Mask" "F.Paste")
			(net "M_B_CPU1_SA_DQ<27>")
		)
		(pad "188" smd rect
			(at 2.050034 -26.774902 270)
			(size 0.519938 1.4986)
			(layers "F.Cu" "F.Mask" "F.Paste")
			(net "GND")
		)
		(pad "189" smd rect
			(at 2.050034 -25.925018 270)
			(size 0.519938 1.4986)
			(layers "F.Cu" "F.Mask" "F.Paste")
			(net "M_B_CPU1_SA_DQS_DN<8>")
		)
		(pad "190" smd rect
			(at 2.050034 -25.07488 270)
			(size 0.519938 1.4986)
			(layers "F.Cu" "F.Mask" "F.Paste")
			(net "M_B_CPU1_SA_DQS_DP<8>")
		)
		(pad "191" smd rect
			(at 2.050034 -24.224996 270)
			(size 0.519938 1.4986)
			(layers "F.Cu" "F.Mask" "F.Paste")
			(net "GND")
		)
		(pad "192" smd rect
			(at 2.050034 -23.375112 270)
			(size 0.519938 1.4986)
			(layers "F.Cu" "F.Mask" "F.Paste")
			(net "M_B_CPU1_SA_DQ<30>")
		)
		(pad "193" smd rect
			(at 2.050034 -22.524974 270)
			(size 0.519938 1.4986)
			(layers "F.Cu" "F.Mask" "F.Paste")
			(net "GND")
		)
		(pad "194" smd rect
			(at 2.050034 -21.67509 270)
			(size 0.519938 1.4986)
			(layers "F.Cu" "F.Mask" "F.Paste")
			(net "M_B_CPU1_SA_DQ<31>")
		)
		(pad "195" smd rect
			(at 2.050034 -20.824952 270)
			(size 0.519938 1.4986)
			(layers "F.Cu" "F.Mask" "F.Paste")
			(net "GND")
		)
		(pad "196" smd rect
			(at 2.050034 -19.975068 270)
			(size 0.519938 1.4986)
			(layers "F.Cu" "F.Mask" "F.Paste")
			(net "M_B_CPU1_SA_CB<2>")
		)
		(pad "197" smd rect
			(at 2.050034 -19.12493 270)
			(size 0.519938 1.4986)
			(layers "F.Cu" "F.Mask" "F.Paste")
			(net "GND")
		)
		(pad "198" smd rect
			(at 2.050034 -18.275046 270)
			(size 0.519938 1.4986)
			(layers "F.Cu" "F.Mask" "F.Paste")
			(net "M_B_CPU1_SA_CB<3>")
		)
		(pad "199" smd rect
			(at 2.050034 -17.424908 270)
			(size 0.519938 1.4986)
			(layers "F.Cu" "F.Mask" "F.Paste")
			(net "GND")
		)
		(pad "200" smd rect
			(at 2.050034 -16.575024 270)
			(size 0.519938 1.4986)
			(layers "F.Cu" "F.Mask" "F.Paste")
			(net "M_B_CPU1_SA_DQS_DN<9>")
		)
		(pad "201" smd rect
			(at 2.050034 -15.724886 270)
			(size 0.519938 1.4986)
			(layers "F.Cu" "F.Mask" "F.Paste")
			(net "M_B_CPU1_SA_DQS_DP<9>")
		)
		(pad "202" smd rect
			(at 2.050034 -14.875002 270)
			(size 0.519938 1.4986)
			(layers "F.Cu" "F.Mask" "F.Paste")
			(net "GND")
		)
		(pad "203" smd rect
			(at 2.050034 -14.025118 270)
			(size 0.519938 1.4986)
			(layers "F.Cu" "F.Mask" "F.Paste")
			(net "M_B_CPU1_SA_CB<6>")
		)
		(pad "204" smd rect
			(at 2.050034 -13.17498 270)
			(size 0.519938 1.4986)
			(layers "F.Cu" "F.Mask" "F.Paste")
			(net "GND")
		)
		(pad "205" smd rect
			(at 2.050034 -12.325096 270)
			(size 0.519938 1.4986)
			(layers "F.Cu" "F.Mask" "F.Paste")
			(net "M_B_CPU1_SA_CB<7>")
		)
		(pad "206" smd rect
			(at 2.050034 -11.474958 270)
			(size 0.519938 1.4986)
			(layers "F.Cu" "F.Mask" "F.Paste")
			(net "GND")
		)
		(pad "207" smd rect
			(at 2.050034 -10.625074 270)
			(size 0.519938 1.4986)
			(layers "F.Cu" "F.Mask" "F.Paste")
			(net "RST_M_AB_CPU1_FPGA_N")
		)
		(pad "208" smd rect
			(at 2.050034 -9.774936 270)
			(size 0.519938 1.4986)
			(layers "F.Cu" "F.Mask" "F.Paste")
			(net "GND")
		)
		(pad "209" smd rect
			(at 2.050034 -8.925052 270)
			(size 0.519938 1.4986)
			(layers "F.Cu" "F.Mask" "F.Paste")
			(net "M_B_CPU1_SA_CS_N<1>")
		)
		(pad "210" smd rect
			(at 2.050034 -8.074914 270)
			(size 0.519938 1.4986)
			(layers "F.Cu" "F.Mask" "F.Paste")
			(net "GND")
		)
		(pad "211" smd rect
			(at 2.050034 -7.22503 270)
			(size 0.519938 1.4986)
			(layers "F.Cu" "F.Mask" "F.Paste")
			(net "M_B_CPU1_SA_CA<1>")
		)
		(pad "212" smd rect
			(at 2.050034 -6.374892 270)
			(size 0.519938 1.4986)
			(layers "F.Cu" "F.Mask" "F.Paste")
			(net "GND")
		)
		(pad "213" smd rect
			(at 2.050034 -5.525008 270)
			(size 0.519938 1.4986)
			(layers "F.Cu" "F.Mask" "F.Paste")
			(net "M_B_CPU1_SA_CA<3>")
		)
		(pad "214" smd rect
			(at 2.050034 -4.675124 270)
			(size 0.519938 1.4986)
			(layers "F.Cu" "F.Mask" "F.Paste")
			(net "GND")
		)
		(pad "215" smd rect
			(at 2.050034 -3.824986 270)
			(size 0.519938 1.4986)
			(layers "F.Cu" "F.Mask" "F.Paste")
			(net "M_B_CPU1_SA_CA<5>")
		)
		(pad "216" smd rect
			(at 2.050034 -2.975102 270)
			(size 0.519938 1.4986)
			(layers "F.Cu" "F.Mask" "F.Paste")
			(net "GND")
		)
		(pad "217" smd rect
			(at 2.050034 -2.124964 270)
			(size 0.519938 1.4986)
			(layers "F.Cu" "F.Mask" "F.Paste")
			(net "M_B_CPU1_CLK_DP<0>")
		)
		(pad "218" smd rect
			(at 2.050034 -1.27508 270)
			(size 0.519938 1.4986)
			(layers "F.Cu" "F.Mask" "F.Paste")
			(net "M_B_CPU1_CLK_DN<0>")
		)
		(pad "219" smd rect
			(at 2.050034 -0.424942 270)
			(size 0.519938 1.4986)
			(layers "F.Cu" "F.Mask" "F.Paste")
			(net "GND")
		)
		(pad "220" smd rect
			(at 2.050034 5.525008 270)
			(size 0.519938 1.4986)
			(layers "F.Cu" "F.Mask" "F.Paste")
			(net "TP_CHB_CPU1_DIMM1_FRU_4")
		)
		(pad "221" smd rect
			(at 2.050034 6.374892 270)
			(size 0.519938 1.4986)
			(layers "F.Cu" "F.Mask" "F.Paste")
			(net "M_B_CPU1_SB_CA<1>")
		)
		(pad "222" smd rect
			(at 2.050034 7.22503 270)
			(size 0.519938 1.4986)
			(layers "F.Cu" "F.Mask" "F.Paste")
			(net "GND")
		)
		(pad "223" smd rect
			(at 2.050034 8.074914 270)
			(size 0.519938 1.4986)
			(layers "F.Cu" "F.Mask" "F.Paste")
			(net "M_B_CPU1_SB_CA<3>")
		)
		(pad "224" smd rect
			(at 2.050034 8.925052 270)
			(size 0.519938 1.4986)
			(layers "F.Cu" "F.Mask" "F.Paste")
			(net "GND")
		)
		(pad "225" smd rect
			(at 2.050034 9.774936 270)
			(size 0.519938 1.4986)
			(layers "F.Cu" "F.Mask" "F.Paste")
			(net "M_B_CPU1_SB_CA<5>")
		)
		(pad "226" smd rect
			(at 2.050034 10.625074 270)
			(size 0.519938 1.4986)
			(layers "F.Cu" "F.Mask" "F.Paste")
			(net "GND")
		)
		(pad "227" smd rect
			(at 2.050034 11.474958 270)
			(size 0.519938 1.4986)
			(layers "F.Cu" "F.Mask" "F.Paste")
			(net "M_B_CPU1_SB_PAR")
		)
		(pad "228" smd rect
			(at 2.050034 12.325096 270)
			(size 0.519938 1.4986)
			(layers "F.Cu" "F.Mask" "F.Paste")
			(net "GND")
		)
		(pad "229" smd rect
			(at 2.050034 13.17498 270)
			(size 0.519938 1.4986)
			(layers "F.Cu" "F.Mask" "F.Paste")
			(net "M_B_CPU1_SB_CS_N<1>")
		)
		(pad "230" smd rect
			(at 2.050034 14.025118 270)
			(size 0.519938 1.4986)
			(layers "F.Cu" "F.Mask" "F.Paste")
			(net "GND")
		)
		(pad "231" smd rect
			(at 2.050034 14.875002 270)
			(size 0.519938 1.4986)
			(layers "F.Cu" "F.Mask" "F.Paste")
			(net "TP_CHB_CPU1_DIMM1_FRU_5")
		)
		(pad "232" smd rect
			(at 2.050034 15.724886 270)
			(size 0.519938 1.4986)
			(layers "F.Cu" "F.Mask" "F.Paste")
			(net "TP_CHB_CPU1_DIMM1_FRU_6")
		)
		(pad "233" smd rect
			(at 2.050034 16.575024 270)
			(size 0.519938 1.4986)
			(layers "F.Cu" "F.Mask" "F.Paste")
			(net "GND")
		)
		(pad "234" smd rect
			(at 2.050034 17.424908 270)
			(size 0.519938 1.4986)
			(layers "F.Cu" "F.Mask" "F.Paste")
			(net "M_B_CPU1_SB_CB<6>")
		)
		(pad "235" smd rect
			(at 2.050034 18.275046 270)
			(size 0.519938 1.4986)
			(layers "F.Cu" "F.Mask" "F.Paste")
			(net "GND")
		)
		(pad "236" smd rect
			(at 2.050034 19.12493 270)
			(size 0.519938 1.4986)
			(layers "F.Cu" "F.Mask" "F.Paste")
			(net "M_B_CPU1_SB_CB<7>")
		)
		(pad "237" smd rect
			(at 2.050034 19.975068 270)
			(size 0.519938 1.4986)
			(layers "F.Cu" "F.Mask" "F.Paste")
			(net "GND")
		)
		(pad "238" smd rect
			(at 2.050034 20.824952 270)
			(size 0.519938 1.4986)
			(layers "F.Cu" "F.Mask" "F.Paste")
			(net "M_B_CPU1_SB_DQS_DN<4>")
		)
		(pad "239" smd rect
			(at 2.050034 21.67509 270)
			(size 0.519938 1.4986)
			(layers "F.Cu" "F.Mask" "F.Paste")
			(net "M_B_CPU1_SB_DQS_DP<4>")
		)
		(pad "240" smd rect
			(at 2.050034 22.524974 270)
			(size 0.519938 1.4986)
			(layers "F.Cu" "F.Mask" "F.Paste")
			(net "GND")
		)
		(pad "241" smd rect
			(at 2.050034 23.375112 270)
			(size 0.519938 1.4986)
			(layers "F.Cu" "F.Mask" "F.Paste")
			(net "M_B_CPU1_SB_CB<2>")
		)
		(pad "242" smd rect
			(at 2.050034 24.224996 270)
			(size 0.519938 1.4986)
			(layers "F.Cu" "F.Mask" "F.Paste")
			(net "GND")
		)
		(pad "243" smd rect
			(at 2.050034 25.07488 270)
			(size 0.519938 1.4986)
			(layers "F.Cu" "F.Mask" "F.Paste")
			(net "M_B_CPU1_SB_CB<3>")
		)
		(pad "244" smd rect
			(at 2.050034 25.925018 270)
			(size 0.519938 1.4986)
			(layers "F.Cu" "F.Mask" "F.Paste")
			(net "GND")
		)
		(pad "245" smd rect
			(at 2.050034 26.774902 270)
			(size 0.519938 1.4986)
			(layers "F.Cu" "F.Mask" "F.Paste")
			(net "M_B_CPU1_SB_DQ<2>")
		)
		(pad "246" smd rect
			(at 2.050034 27.62504 270)
			(size 0.519938 1.4986)
			(layers "F.Cu" "F.Mask" "F.Paste")
			(net "GND")
		)
		(pad "247" smd rect
			(at 2.050034 28.474924 270)
			(size 0.519938 1.4986)
			(layers "F.Cu" "F.Mask" "F.Paste")
			(net "M_B_CPU1_SB_DQ<3>")
		)
		(pad "248" smd rect
			(at 2.050034 29.325062 270)
			(size 0.519938 1.4986)
			(layers "F.Cu" "F.Mask" "F.Paste")
			(net "GND")
		)
		(pad "249" smd rect
			(at 2.050034 30.174946 270)
			(size 0.519938 1.4986)
			(layers "F.Cu" "F.Mask" "F.Paste")
			(net "M_B_CPU1_SB_DQS_DN<5>")
		)
		(pad "250" smd rect
			(at 2.050034 31.025084 270)
			(size 0.519938 1.4986)
			(layers "F.Cu" "F.Mask" "F.Paste")
			(net "M_B_CPU1_SB_DQS_DP<5>")
		)
		(pad "251" smd rect
			(at 2.050034 31.874968 270)
			(size 0.519938 1.4986)
			(layers "F.Cu" "F.Mask" "F.Paste")
			(net "GND")
		)
		(pad "252" smd rect
			(at 2.050034 32.725106 270)
			(size 0.519938 1.4986)
			(layers "F.Cu" "F.Mask" "F.Paste")
			(net "M_B_CPU1_SB_DQ<6>")
		)
		(pad "253" smd rect
			(at 2.050034 33.57499 270)
			(size 0.519938 1.4986)
			(layers "F.Cu" "F.Mask" "F.Paste")
			(net "GND")
		)
		(pad "254" smd rect
			(at 2.050034 34.425128 270)
			(size 0.519938 1.4986)
			(layers "F.Cu" "F.Mask" "F.Paste")
			(net "M_B_CPU1_SB_DQ<7>")
		)
		(pad "255" smd rect
			(at 2.050034 35.275012 270)
			(size 0.519938 1.4986)
			(layers "F.Cu" "F.Mask" "F.Paste")
			(net "GND")
		)
		(pad "256" smd rect
			(at 2.050034 36.124896 270)
			(size 0.519938 1.4986)
			(layers "F.Cu" "F.Mask" "F.Paste")
			(net "M_B_CPU1_SB_DQ<10>")
		)
		(pad "257" smd rect
			(at 2.050034 36.975034 270)
			(size 0.519938 1.4986)
			(layers "F.Cu" "F.Mask" "F.Paste")
			(net "GND")
		)
		(pad "258" smd rect
			(at 2.050034 37.824918 270)
			(size 0.519938 1.4986)
			(layers "F.Cu" "F.Mask" "F.Paste")
			(net "M_B_CPU1_SB_DQ<11>")
		)
		(pad "259" smd rect
			(at 2.050034 38.675056 270)
			(size 0.519938 1.4986)
			(layers "F.Cu" "F.Mask" "F.Paste")
			(net "GND")
		)
		(pad "260" smd rect
			(at 2.050034 39.52494 270)
			(size 0.519938 1.4986)
			(layers "F.Cu" "F.Mask" "F.Paste")
			(net "M_B_CPU1_SB_DQS_DN<6>")
		)
		(pad "261" smd rect
			(at 2.050034 40.375078 270)
			(size 0.519938 1.4986)
			(layers "F.Cu" "F.Mask" "F.Paste")
			(net "M_B_CPU1_SB_DQS_DP<6>")
		)
		(pad "262" smd rect
			(at 2.050034 41.224962 270)
			(size 0.519938 1.4986)
			(layers "F.Cu" "F.Mask" "F.Paste")
			(net "GND")
		)
		(pad "263" smd rect
			(at 2.050034 42.0751 270)
			(size 0.519938 1.4986)
			(layers "F.Cu" "F.Mask" "F.Paste")
			(net "M_B_CPU1_SB_DQ<14>")
		)
		(pad "264" smd rect
			(at 2.050034 42.924984 270)
			(size 0.519938 1.4986)
			(layers "F.Cu" "F.Mask" "F.Paste")
			(net "GND")
		)
		(pad "265" smd rect
			(at 2.050034 43.775122 270)
			(size 0.519938 1.4986)
			(layers "F.Cu" "F.Mask" "F.Paste")
			(net "M_B_CPU1_SB_DQ<15>")
		)
		(pad "266" smd rect
			(at 2.050034 44.625006 270)
			(size 0.519938 1.4986)
			(layers "F.Cu" "F.Mask" "F.Paste")
			(net "GND")
		)
		(pad "267" smd rect
			(at 2.050034 45.47489 270)
			(size 0.519938 1.4986)
			(layers "F.Cu" "F.Mask" "F.Paste")
			(net "M_B_CPU1_SB_DQ<18>")
		)
		(pad "268" smd rect
			(at 2.050034 46.325028 270)
			(size 0.519938 1.4986)
			(layers "F.Cu" "F.Mask" "F.Paste")
			(net "GND")
		)
		(pad "269" smd rect
			(at 2.050034 47.174912 270)
			(size 0.519938 1.4986)
			(layers "F.Cu" "F.Mask" "F.Paste")
			(net "M_B_CPU1_SB_DQ<19>")
		)
		(pad "270" smd rect
			(at 2.050034 48.02505 270)
			(size 0.519938 1.4986)
			(layers "F.Cu" "F.Mask" "F.Paste")
			(net "GND")
		)
		(pad "271" smd rect
			(at 2.050034 48.874934 270)
			(size 0.519938 1.4986)
			(layers "F.Cu" "F.Mask" "F.Paste")
			(net "M_B_CPU1_SB_DQS_DN<7>")
		)
		(pad "272" smd rect
			(at 2.050034 49.725072 270)
			(size 0.519938 1.4986)
			(layers "F.Cu" "F.Mask" "F.Paste")
			(net "M_B_CPU1_SB_DQS_DP<7>")
		)
		(pad "273" smd rect
			(at 2.050034 50.574956 270)
			(size 0.519938 1.4986)
			(layers "F.Cu" "F.Mask" "F.Paste")
			(net "GND")
		)
		(pad "274" smd rect
			(at 2.050034 51.425094 270)
			(size 0.519938 1.4986)
			(layers "F.Cu" "F.Mask" "F.Paste")
			(net "M_B_CPU1_SB_DQ<22>")
		)
		(pad "275" smd rect
			(at 2.050034 52.274978 270)
			(size 0.519938 1.4986)
			(layers "F.Cu" "F.Mask" "F.Paste")
			(net "GND")
		)
		(pad "276" smd rect
			(at 2.050034 53.125116 270)
			(size 0.519938 1.4986)
			(layers "F.Cu" "F.Mask" "F.Paste")
			(net "M_B_CPU1_SB_DQ<23>")
		)
		(pad "277" smd rect
			(at 2.050034 53.975 270)
			(size 0.519938 1.4986)
			(layers "F.Cu" "F.Mask" "F.Paste")
			(net "GND")
		)
		(pad "278" smd rect
			(at 2.050034 54.824884 270)
			(size 0.519938 1.4986)
			(layers "F.Cu" "F.Mask" "F.Paste")
			(net "M_B_CPU1_SB_DQ<26>")
		)
		(pad "279" smd rect
			(at 2.050034 55.675022 270)
			(size 0.519938 1.4986)
			(layers "F.Cu" "F.Mask" "F.Paste")
			(net "GND")
		)
		(pad "280" smd rect
			(at 2.050034 56.524906 270)
			(size 0.519938 1.4986)
			(layers "F.Cu" "F.Mask" "F.Paste")
			(net "M_B_CPU1_SB_DQ<27>")
		)
		(pad "281" smd rect
			(at 2.050034 57.375044 270)
			(size 0.519938 1.4986)
			(layers "F.Cu" "F.Mask" "F.Paste")
			(net "GND")
		)
		(pad "282" smd rect
			(at 2.050034 58.224928 270)
			(size 0.519938 1.4986)
			(layers "F.Cu" "F.Mask" "F.Paste")
			(net "M_B_CPU1_SB_DQS_DN<8>")
		)
		(pad "283" smd rect
			(at 2.050034 59.075066 270)
			(size 0.519938 1.4986)
			(layers "F.Cu" "F.Mask" "F.Paste")
			(net "M_B_CPU1_SB_DQS_DP<8>")
		)
		(pad "284" smd rect
			(at 2.050034 59.92495 270)
			(size 0.519938 1.4986)
			(layers "F.Cu" "F.Mask" "F.Paste")
			(net "GND")
		)
		(pad "285" smd rect
			(at 2.050034 60.775088 270)
			(size 0.519938 1.4986)
			(layers "F.Cu" "F.Mask" "F.Paste")
			(net "M_B_CPU1_SB_DQ<30>")
		)
		(pad "286" smd rect
			(at 2.050034 61.624972 270)
			(size 0.519938 1.4986)
			(layers "F.Cu" "F.Mask" "F.Paste")
			(net "GND")
		)
		(pad "287" smd rect
			(at 2.050034 62.47511 270)
			(size 0.519938 1.4986)
			(layers "F.Cu" "F.Mask" "F.Paste")
			(net "M_B_CPU1_SB_DQ<31>")
		)
		(pad "288" smd rect
			(at 2.050034 63.324994 270)
			(size 0.519938 1.4986)
			(layers "F.Cu" "F.Mask" "F.Paste")
			(net "GND")
		)
		(pad "G1" thru_hole oval
			(at 0 -68.97497)
			(size 2.8194 1.5748)
			(drill oval 2.4384 1.1938)
			(layers "*.Cu" "*.Mask")
			(remove_unused_layers no)
			(net "GND")
			(clearance 0.127)
			(thermal_gap 0.127)
		)
		(pad "G2" thru_hole oval
			(at 0 3.875024)
			(size 2.8194 1.5748)
			(drill oval 2.4384 1.1938)
			(layers "*.Cu" "*.Mask")
			(remove_unused_layers no)
			(net "GND")
			(clearance 0.127)
			(thermal_gap 0.127)
		)
		(pad "G3" thru_hole oval
			(at 0 68.97497)
			(size 2.8194 1.5748)
			(drill oval 2.4384 1.1938)
			(layers "*.Cu" "*.Mask")
			(remove_unused_layers no)
			(net "GND")
			(clearance 0.127)
			(thermal_gap 0.127)
		)
	)
	(footprint ""
		(layer "F.Cu")
		(at 40.627554 -109.444282)
		(property "Reference" "R3685"
			(at 0 0 0)
			(layer "F.SilkS")
			(hide yes)
			(effects
				(font
					(size 1.27 1.27)
				)
			)
		)
		(property "Value" ""
			(at 0 0 0)
			(layer "F.Fab")
			(effects
				(font
					(size 1.27 1.27)
				)
			)
		)
		(duplicate_pad_numbers_are_jumpers no)
		(fp_line
			(start -0.7874 -0.4064)
			(end 0.7874 -0.4064)
			(stroke
				(width 0.1524)
				(type default)
			)
			(layer "F.SilkS")
		)
		(fp_line
			(start -0.7874 0.4064)
			(end -0.7874 -0.4064)
			(stroke
				(width 0.1524)
				(type default)
			)
			(layer "F.SilkS")
		)
		(fp_line
			(start 0.7874 -0.4064)
			(end 0.7874 0.4064)
			(stroke
				(width 0.1524)
				(type default)
			)
			(layer "F.SilkS")
		)
		(fp_line
			(start 0.7874 0.4064)
			(end -0.7874 0.4064)
			(stroke
				(width 0.1524)
				(type default)
			)
			(layer "F.SilkS")
		)
		(fp_line
			(start -0.67945 -0.305054)
			(end -0.12065 -0.305054)
			(stroke
				(width 0.1)
				(type default)
			)
			(layer "F.Fab")
		)
		(fp_line
			(start -0.67945 0.3048)
			(end -0.67945 -0.305054)
			(stroke
				(width 0.1)
				(type default)
			)
			(layer "F.Fab")
		)
		(fp_line
			(start -0.12065 -0.305054)
			(end -0.12065 -0.2794)
			(stroke
				(width 0.1)
				(type default)
			)
			(layer "F.Fab")
		)
		(fp_line
			(start -0.12065 -0.2794)
			(end 0.12065 -0.2794)
			(stroke
				(width 0.1)
				(type default)
			)
			(layer "F.Fab")
		)
		(fp_line
			(start -0.12065 0.2794)
			(end -0.12065 0.3048)
			(stroke
				(width 0.1)
				(type default)
			)
			(layer "F.Fab")
		)
		(fp_line
			(start -0.12065 0.3048)
			(end -0.67945 0.3048)
			(stroke
				(width 0.1)
				(type default)
			)
			(layer "F.Fab")
		)
		(fp_line
			(start 0.120396 0.2794)
			(end -0.12065 0.2794)
			(stroke
				(width 0.1)
				(type default)
			)
			(layer "F.Fab")
		)
		(fp_line
			(start 0.120396 0.3048)
			(end 0.120396 0.2794)
			(stroke
				(width 0.1)
				(type default)
			)
			(layer "F.Fab")
		)
		(fp_line
			(start 0.12065 -0.3048)
			(end 0.67945 -0.3048)
			(stroke
				(width 0.1)
				(type default)
			)
			(layer "F.Fab")
		)
		(fp_line
			(start 0.12065 -0.2794)
			(end 0.12065 -0.3048)
			(stroke
				(width 0.1)
				(type default)
			)
			(layer "F.Fab")
		)
		(fp_line
			(start 0.67945 -0.3048)
			(end 0.67945 0.3048)
			(stroke
				(width 0.1)
				(type default)
			)
			(layer "F.Fab")
		)
		(fp_line
			(start 0.67945 0.3048)
			(end 0.120396 0.3048)
			(stroke
				(width 0.1)
				(type default)
			)
			(layer "F.Fab")
		)
		(pad "1" smd rect
			(at -0.40005 0 180)
			(size 0.4572 0.508)
			(layers "F.Cu" "F.Mask" "F.Paste")
			(net "P5V_ADC")
		)
		(pad "2" smd rect
			(at 0.40005 0 180)
			(size 0.4572 0.508)
			(layers "F.Cu" "F.Mask" "F.Paste")
			(net "P5V_ADC_MAM")
		)
	)
	(footprint ""
		(layer "F.Cu")
		(at 211.85378 -4.699)
		(property "Reference" "J73"
			(at -4.18211 1.016 90)
			(unlocked yes)
			(layer "F.SilkS")
			(effects
				(font
					(size 0.7874 0.5842)
					(thickness 0.1524)
				)
				(justify left)
			)
		)
		(property "Value" ""
			(at 0 0 0)
			(layer "F.Fab")
			(effects
				(font
					(size 1.27 1.27)
				)
			)
		)
		(duplicate_pad_numbers_are_jumpers no)
		(fp_line
			(start -1.2192 -2.1082)
			(end 1.2192 -2.1082)
			(stroke
				(width 0.1524)
				(type default)
			)
			(layer "F.SilkS")
		)
		(fp_line
			(start -1.2192 2.1082)
			(end -1.2192 -2.1082)
			(stroke
				(width 0.1524)
				(type default)
			)
			(layer "F.SilkS")
		)
		(fp_line
			(start 1.2192 -2.1082)
			(end 1.2192 2.1082)
			(stroke
				(width 0.1524)
				(type default)
			)
			(layer "F.SilkS")
		)
		(fp_line
			(start 1.2192 2.1082)
			(end -1.2192 2.1082)
			(stroke
				(width 0.1524)
				(type default)
			)
			(layer "F.SilkS")
		)
		(pad "" np_thru_hole circle
			(at -2.8829 -1.27 270)
			(size 1.0414 1.0414)
			(drill 1.0414)
			(layers "*.Cu" "*.Mask")
			(clearance 0.381)
			(thermal_gap 0.381)
		)
		(pad "" np_thru_hole circle
			(at -2.8829 1.27 270)
			(size 1.0414 1.0414)
			(drill 1.0414)
			(layers "*.Cu" "*.Mask")
			(clearance 0.381)
			(thermal_gap 0.381)
		)
		(pad "" np_thru_hole circle
			(at 3.4671 -1.27 270)
			(size 1.0414 1.0414)
			(drill 1.0414)
			(layers "*.Cu" "*.Mask")
			(clearance 0.381)
			(thermal_gap 0.381)
		)
		(pad "" np_thru_hole circle
			(at 3.4671 1.27 270)
			(size 1.0414 1.0414)
			(drill 1.0414)
			(layers "*.Cu" "*.Mask")
			(clearance 0.381)
			(thermal_gap 0.381)
		)
		(pad "1" smd rect
			(at 0.8255 -0.249936 270)
			(size 0.3048 0.508)
			(layers "F.Cu" "F.Mask" "F.Paste")
			(net "DELTA_L_85_5INCH_IN3_DN")
		)
		(pad "2" smd rect
			(at 0.8255 0.249936 270)
			(size 0.3048 0.508)
			(layers "F.Cu" "F.Mask" "F.Paste")
			(net "DELTA_L_85_5INCH_IN3_DP")
		)
		(pad "3" smd circle
			(at 0 0)
			(size 0 0)
			(layers "F.Cu" "F.Mask" "F.Paste")
			(net "DELTA_L_GND_1")
		)
		(zone
			(layer "F.Cu")
			(hatch none 0.5)
			(connect_pads
				(clearance 0)
			)
			(min_thickness 0.25)
			(keepout
				(tracks not_allowed)
				(vias allowed)
				(pads allowed)
				(copperpour not_allowed)
				(footprints allowed)
			)
			(placement
				(enabled no)
				(sheetname "")
			)
			(fill
				(thermal_gap 0.5)
				(thermal_bridge_width 0.5)
				(island_removal_mode 0)
			)
			(polygon
				(pts
					(xy 212.97138 -5.24764) (xy 212.97138 -5.152136) (xy 212.37448 -5.152136) (xy 212.37448 -4.745736)
					(xy 212.97138 -4.745736) (xy 212.97138 -4.652264) (xy 212.37448 -4.652264) (xy 212.37448 -4.245864)
					(xy 212.97138 -4.245864) (xy 212.97138 -4.15036) (xy 212.27288 -4.15036) (xy 212.27288 -5.24764)
				)
			)
		)
		(zone
			(layers "F.Cu" "B.Cu" "In1.Cu" "In2.Cu" "In3.Cu" "In4.Cu" "In5.Cu" "In6.Cu"
				"In7.Cu" "In8.Cu" "In9.Cu" "In10.Cu" "In11.Cu" "In12.Cu" "In13.Cu" "In14.Cu"
				"In15.Cu" "In16.Cu"
			)
			(hatch none 0.5)
			(connect_pads
				(clearance 0)
			)
			(min_thickness 0.25)
			(keepout
				(tracks not_allowed)
				(vias allowed)
				(pads allowed)
				(copperpour not_allowed)
				(footprints allowed)
			)
			(placement
				(enabled no)
				(sheetname "")
			)
			(fill
				(thermal_gap 0.5)
				(thermal_bridge_width 0.5)
				(island_removal_mode 0)
			)
			(polygon
				(pts
					(arc
						(start 209.89798 -5.969)
						(mid 208.04378 -5.969)
						(end 209.89798 -5.969)
					)
				)
			)
		)
		(zone
			(layers "F.Cu" "B.Cu" "In1.Cu" "In2.Cu" "In3.Cu" "In4.Cu" "In5.Cu" "In6.Cu"
				"In7.Cu" "In8.Cu" "In9.Cu" "In10.Cu" "In11.Cu" "In12.Cu" "In13.Cu" "In14.Cu"
				"In15.Cu" "In16.Cu"
			)
			(hatch none 0.5)
			(connect_pads
				(clearance 0)
			)
			(min_thickness 0.25)
			(keepout
				(tracks not_allowed)
				(vias allowed)
				(pads allowed)
				(copperpour not_allowed)
				(footprints allowed)
			)
			(placement
				(enabled no)
				(sheetname "")
			)
			(fill
				(thermal_gap 0.5)
				(thermal_bridge_width 0.5)
				(island_removal_mode 0)
			)
			(polygon
				(pts
					(arc
						(start 209.89798 -3.429)
						(mid 208.04378 -3.429)
						(end 209.89798 -3.429)
					)
				)
			)
		)
		(zone
			(layers "F.Cu" "B.Cu" "In1.Cu" "In2.Cu" "In3.Cu" "In4.Cu" "In5.Cu" "In6.Cu"
				"In7.Cu" "In8.Cu" "In9.Cu" "In10.Cu" "In11.Cu" "In12.Cu" "In13.Cu" "In14.Cu"
				"In15.Cu" "In16.Cu"
			)
			(hatch none 0.5)
			(connect_pads
				(clearance 0)
			)
			(min_thickness 0.25)
			(keepout
				(tracks not_allowed)
				(vias allowed)
				(pads allowed)
				(copperpour not_allowed)
				(footprints allowed)
			)
			(placement
				(enabled no)
				(sheetname "")
			)
			(fill
				(thermal_gap 0.5)
				(thermal_bridge_width 0.5)
				(island_removal_mode 0)
			)
			(polygon
				(pts
					(arc
						(start 216.24798 -5.969)
						(mid 214.39378 -5.969)
						(end 216.24798 -5.969)
					)
				)
			)
		)
		(zone
			(layers "F.Cu" "B.Cu" "In1.Cu" "In2.Cu" "In3.Cu" "In4.Cu" "In5.Cu" "In6.Cu"
				"In7.Cu" "In8.Cu" "In9.Cu" "In10.Cu" "In11.Cu" "In12.Cu" "In13.Cu" "In14.Cu"
				"In15.Cu" "In16.Cu"
			)
			(hatch none 0.5)
			(connect_pads
				(clearance 0)
			)
			(min_thickness 0.25)
			(keepout
				(tracks not_allowed)
				(vias allowed)
				(pads allowed)
				(copperpour not_allowed)
				(footprints allowed)
			)
			(placement
				(enabled no)
				(sheetname "")
			)
			(fill
				(thermal_gap 0.5)
				(thermal_bridge_width 0.5)
				(island_removal_mode 0)
			)
			(polygon
				(pts
					(arc
						(start 216.24798 -3.429)
						(mid 214.39378 -3.429)
						(end 216.24798 -3.429)
					)
				)
			)
		)
	)
	(footprint ""
		(layer "F.Cu")
		(at 361.36072 -402.9456 90)
		(property "Reference" "R3063"
			(at 0 0 90)
			(layer "F.SilkS")
			(hide yes)
			(effects
				(font
					(size 1.27 1.27)
				)
			)
		)
		(property "Value" ""
			(at 0 0 90)
			(layer "F.Fab")
			(effects
				(font
					(size 1.27 1.27)
				)
			)
		)
		(duplicate_pad_numbers_are_jumpers no)
		(fp_line
			(start 0.7874 -0.4064)
			(end 0.7874 0.4064)
			(stroke
				(width 0.1524)
				(type default)
			)
			(layer "F.SilkS")
		)
		(fp_line
			(start -0.7874 -0.4064)
			(end 0.7874 -0.4064)
			(stroke
				(width 0.1524)
				(type default)
			)
			(layer "F.SilkS")
		)
		(fp_line
			(start 0.7874 0.4064)
			(end -0.7874 0.4064)
			(stroke
				(width 0.1524)
				(type default)
			)
			(layer "F.SilkS")
		)
		(fp_line
			(start -0.7874 0.4064)
			(end -0.7874 -0.4064)
			(stroke
				(width 0.1524)
				(type default)
			)
			(layer "F.SilkS")
		)
		(fp_line
			(start -0.12065 -0.305054)
			(end -0.12065 -0.2794)
			(stroke
				(width 0.1)
				(type default)
			)
			(layer "F.Fab")
		)
		(fp_line
			(start -0.67945 -0.305054)
			(end -0.12065 -0.305054)
			(stroke
				(width 0.1)
				(type default)
			)
			(layer "F.Fab")
		)
		(fp_line
			(start 0.67945 -0.3048)
			(end 0.67945 0.3048)
			(stroke
				(width 0.1)
				(type default)
			)
			(layer "F.Fab")
		)
		(fp_line
			(start 0.12065 -0.3048)
			(end 0.67945 -0.3048)
			(stroke
				(width 0.1)
				(type default)
			)
			(layer "F.Fab")
		)
		(fp_line
			(start 0.12065 -0.2794)
			(end 0.12065 -0.3048)
			(stroke
				(width 0.1)
				(type default)
			)
			(layer "F.Fab")
		)
		(fp_line
			(start -0.12065 -0.2794)
			(end 0.12065 -0.2794)
			(stroke
				(width 0.1)
				(type default)
			)
			(layer "F.Fab")
		)
		(fp_line
			(start 0.120396 0.2794)
			(end -0.12065 0.2794)
			(stroke
				(width 0.1)
				(type default)
			)
			(layer "F.Fab")
		)
		(fp_line
			(start -0.12065 0.2794)
			(end -0.12065 0.3048)
			(stroke
				(width 0.1)
				(type default)
			)
			(layer "F.Fab")
		)
		(fp_line
			(start 0.67945 0.3048)
			(end 0.120396 0.3048)
			(stroke
				(width 0.1)
				(type default)
			)
			(layer "F.Fab")
		)
		(fp_line
			(start 0.120396 0.3048)
			(end 0.120396 0.2794)
			(stroke
				(width 0.1)
				(type default)
			)
			(layer "F.Fab")
		)
		(fp_line
			(start -0.12065 0.3048)
			(end -0.67945 0.3048)
			(stroke
				(width 0.1)
				(type default)
			)
			(layer "F.Fab")
		)
		(fp_line
			(start -0.67945 0.3048)
			(end -0.67945 -0.305054)
			(stroke
				(width 0.1)
				(type default)
			)
			(layer "F.Fab")
		)
		(pad "1" smd circle
			(at -0.40005 0 90)
			(size 0 0)
			(layers "F.Cu" "F.Mask" "F.Paste")
			(net "FM_PDB_BUF_EN_R")
		)
		(pad "2" smd circle
			(at 0.40005 0 90)
			(size 0 0)
			(layers "F.Cu" "F.Mask" "F.Paste")
			(net "FM_UART_EN")
		)
	)
	(footprint ""
		(layer "F.Cu")
		(at 416.919664 -366.691164 90)
		(property "Reference" "PR1780"
			(at 0 0 90)
			(layer "F.SilkS")
			(hide yes)
			(effects
				(font
					(size 1.27 1.27)
				)
			)
		)
		(property "Value" ""
			(at 0 0 90)
			(layer "F.Fab")
			(effects
				(font
					(size 1.27 1.27)
				)
			)
		)
		(duplicate_pad_numbers_are_jumpers no)
		(fp_line
			(start 0.7874 -0.4064)
			(end 0.7874 0.4064)
			(stroke
				(width 0.1524)
				(type default)
			)
			(layer "F.SilkS")
		)
		(fp_line
			(start -0.7874 -0.4064)
			(end 0.7874 -0.4064)
			(stroke
				(width 0.1524)
				(type default)
			)
			(layer "F.SilkS")
		)
		(fp_line
			(start 0.7874 0.4064)
			(end -0.7874 0.4064)
			(stroke
				(width 0.1524)
				(type default)
			)
			(layer "F.SilkS")
		)
		(fp_line
			(start -0.7874 0.4064)
			(end -0.7874 -0.4064)
			(stroke
				(width 0.1524)
				(type default)
			)
			(layer "F.SilkS")
		)
		(fp_line
			(start -0.12065 -0.305054)
			(end -0.12065 -0.2794)
			(stroke
				(width 0.1)
				(type default)
			)
			(layer "F.Fab")
		)
		(fp_line
			(start -0.67945 -0.305054)
			(end -0.12065 -0.305054)
			(stroke
				(width 0.1)
				(type default)
			)
			(layer "F.Fab")
		)
		(fp_line
			(start 0.67945 -0.3048)
			(end 0.67945 0.3048)
			(stroke
				(width 0.1)
				(type default)
			)
			(layer "F.Fab")
		)
		(fp_line
			(start 0.12065 -0.3048)
			(end 0.67945 -0.3048)
			(stroke
				(width 0.1)
				(type default)
			)
			(layer "F.Fab")
		)
		(fp_line
			(start 0.12065 -0.2794)
			(end 0.12065 -0.3048)
			(stroke
				(width 0.1)
				(type default)
			)
			(layer "F.Fab")
		)
		(fp_line
			(start -0.12065 -0.2794)
			(end 0.12065 -0.2794)
			(stroke
				(width 0.1)
				(type default)
			)
			(layer "F.Fab")
		)
		(fp_line
			(start 0.120396 0.2794)
			(end -0.12065 0.2794)
			(stroke
				(width 0.1)
				(type default)
			)
			(layer "F.Fab")
		)
		(fp_line
			(start -0.12065 0.2794)
			(end -0.12065 0.3048)
			(stroke
				(width 0.1)
				(type default)
			)
			(layer "F.Fab")
		)
		(fp_line
			(start 0.67945 0.3048)
			(end 0.120396 0.3048)
			(stroke
				(width 0.1)
				(type default)
			)
			(layer "F.Fab")
		)
		(fp_line
			(start 0.120396 0.3048)
			(end 0.120396 0.2794)
			(stroke
				(width 0.1)
				(type default)
			)
			(layer "F.Fab")
		)
		(fp_line
			(start -0.12065 0.3048)
			(end -0.67945 0.3048)
			(stroke
				(width 0.1)
				(type default)
			)
			(layer "F.Fab")
		)
		(fp_line
			(start -0.67945 0.3048)
			(end -0.67945 -0.305054)
			(stroke
				(width 0.1)
				(type default)
			)
			(layer "F.Fab")
		)
		(pad "1" smd circle
			(at -0.40005 0 90)
			(size 0 0)
			(layers "F.Cu" "F.Mask" "F.Paste")
			(net "SW_PVCCFA_EHV_FIVRA_CPU0_BOOT1")
		)
		(pad "2" smd circle
			(at 0.40005 0 90)
			(size 0 0)
			(layers "F.Cu" "F.Mask" "F.Paste")
			(net "SW_PVCCFA_EHV_FIVRA_CPU0_BOOT1_")
		)
	)
	(footprint ""
		(layer "F.Cu")
		(at 164.247576 -35.737546 180)
		(property "Reference" "R4448"
			(at 0 0 180)
			(layer "F.SilkS")
			(hide yes)
			(effects
				(font
					(size 1.27 1.27)
				)
			)
		)
		(property "Value" ""
			(at 0 0 180)
			(layer "F.Fab")
			(effects
				(font
					(size 1.27 1.27)
				)
			)
		)
		(duplicate_pad_numbers_are_jumpers no)
		(fp_line
			(start 0.7874 0.4064)
			(end -0.7874 0.4064)
			(stroke
				(width 0.1524)
				(type default)
			)
			(layer "F.SilkS")
		)
		(fp_line
			(start 0.7874 -0.4064)
			(end 0.7874 0.4064)
			(stroke
				(width 0.1524)
				(type default)
			)
			(layer "F.SilkS")
		)
		(fp_line
			(start -0.7874 0.4064)
			(end -0.7874 -0.4064)
			(stroke
				(width 0.1524)
				(type default)
			)
			(layer "F.SilkS")
		)
		(fp_line
			(start -0.7874 -0.4064)
			(end 0.7874 -0.4064)
			(stroke
				(width 0.1524)
				(type default)
			)
			(layer "F.SilkS")
		)
		(fp_line
			(start 0.67945 0.3048)
			(end 0.120396 0.3048)
			(stroke
				(width 0.1)
				(type default)
			)
			(layer "F.Fab")
		)
		(fp_line
			(start 0.67945 -0.3048)
			(end 0.67945 0.3048)
			(stroke
				(width 0.1)
				(type default)
			)
			(layer "F.Fab")
		)
		(fp_line
			(start 0.12065 -0.2794)
			(end 0.12065 -0.3048)
			(stroke
				(width 0.1)
				(type default)
			)
			(layer "F.Fab")
		)
		(fp_line
			(start 0.12065 -0.3048)
			(end 0.67945 -0.3048)
			(stroke
				(width 0.1)
				(type default)
			)
			(layer "F.Fab")
		)
		(fp_line
			(start 0.120396 0.3048)
			(end 0.120396 0.2794)
			(stroke
				(width 0.1)
				(type default)
			)
			(layer "F.Fab")
		)
		(fp_line
			(start 0.120396 0.2794)
			(end -0.12065 0.2794)
			(stroke
				(width 0.1)
				(type default)
			)
			(layer "F.Fab")
		)
		(fp_line
			(start -0.12065 0.3048)
			(end -0.67945 0.3048)
			(stroke
				(width 0.1)
				(type default)
			)
			(layer "F.Fab")
		)
		(fp_line
			(start -0.12065 0.2794)
			(end -0.12065 0.3048)
			(stroke
				(width 0.1)
				(type default)
			)
			(layer "F.Fab")
		)
		(fp_line
			(start -0.12065 -0.2794)
			(end 0.12065 -0.2794)
			(stroke
				(width 0.1)
				(type default)
			)
			(layer "F.Fab")
		)
		(fp_line
			(start -0.12065 -0.305054)
			(end -0.12065 -0.2794)
			(stroke
				(width 0.1)
				(type default)
			)
			(layer "F.Fab")
		)
		(fp_line
			(start -0.67945 0.3048)
			(end -0.67945 -0.305054)
			(stroke
				(width 0.1)
				(type default)
			)
			(layer "F.Fab")
		)
		(fp_line
			(start -0.67945 -0.305054)
			(end -0.12065 -0.305054)
			(stroke
				(width 0.1)
				(type default)
			)
			(layer "F.Fab")
		)
		(pad "1" smd circle
			(at -0.40005 0 180)
			(size 0 0)
			(layers "F.Cu" "F.Mask" "F.Paste")
			(net "P3V3_AUX")
		)
		(pad "2" smd circle
			(at 0.40005 0 180)
			(size 0 0)
			(layers "F.Cu" "F.Mask" "F.Paste")
			(net "USB_HUB_2_PSELF")
		)
	)
	(footprint ""
		(layer "F.Cu")
		(at 461.609948 -258.091686)
		(property "Reference" "J15"
			(at 3.019552 -81.652872 0)
			(unlocked yes)
			(layer "F.SilkS")
			(effects
				(font
					(size 0.7874 0.5842)
					(thickness 0.1524)
				)
				(justify left)
			)
		)
		(property "Value" ""
			(at 0 0 0)
			(layer "F.Fab")
			(effects
				(font
					(size 1.27 1.27)
				)
			)
		)
		(duplicate_pad_numbers_are_jumpers no)
		(fp_line
			(start -3.24993 -81.000092)
			(end -3.24993 81.000092)
			(stroke
				(width 0.1524)
				(type default)
			)
			(layer "F.SilkS")
		)
		(fp_line
			(start -3.24993 81.000092)
			(end 3.24993 81.000092)
			(stroke
				(width 0.1524)
				(type default)
			)
			(layer "F.SilkS")
		)
		(fp_line
			(start 3.24993 -81.000092)
			(end -3.24993 -81.000092)
			(stroke
				(width 0.1524)
				(type default)
			)
			(layer "F.SilkS")
		)
		(fp_line
			(start 3.24993 -72.00011)
			(end -3.24993 -72.00011)
			(stroke
				(width 0.1524)
				(type default)
			)
			(layer "F.SilkS")
		)
		(fp_line
			(start 3.24993 72.00011)
			(end -3.24993 72.00011)
			(stroke
				(width 0.1524)
				(type default)
			)
			(layer "F.SilkS")
		)
		(fp_line
			(start 3.24993 81.000092)
			(end 3.24993 -81.000092)
			(stroke
				(width 0.1524)
				(type default)
			)
			(layer "F.SilkS")
		)
		(fp_poly
			(pts
				(xy -4.143248 -63.741554) (xy -3.318256 -63.329058) (xy -4.143248 -62.916562)
			)
			(stroke
				(width 0)
				(type default)
			)
			(fill yes)
			(layer "F.SilkS")
		)
		(fp_line
			(start -3.24993 -81.000092)
			(end -3.24993 81.000092)
			(stroke
				(width 0.1)
				(type default)
			)
			(layer "F.Fab")
		)
		(fp_line
			(start -3.24993 81.000092)
			(end 3.24993 81.000092)
			(stroke
				(width 0.1)
				(type default)
			)
			(layer "F.Fab")
		)
		(fp_line
			(start 3.24993 -81.000092)
			(end -3.24993 -81.000092)
			(stroke
				(width 0.1)
				(type default)
			)
			(layer "F.Fab")
		)
		(fp_line
			(start 3.24993 -72.00011)
			(end -3.24993 -72.00011)
			(stroke
				(width 0.1)
				(type default)
			)
			(layer "F.Fab")
		)
		(fp_line
			(start 3.24993 -71.000112)
			(end -3.24993 -71.000112)
			(stroke
				(width 0.1)
				(type default)
			)
			(layer "F.Fab")
		)
		(fp_line
			(start 3.24993 71.000112)
			(end -3.24993 71.000112)
			(stroke
				(width 0.1)
				(type default)
			)
			(layer "F.Fab")
		)
		(fp_line
			(start 3.24993 72.00011)
			(end -3.24993 72.00011)
			(stroke
				(width 0.1)
				(type default)
			)
			(layer "F.Fab")
		)
		(fp_line
			(start 3.24993 81.000092)
			(end 3.24993 -81.000092)
			(stroke
				(width 0.1)
				(type default)
			)
			(layer "F.Fab")
		)
		(fp_poly
			(pts
				(xy -4.445 -63.832994) (xy -4.445 -62.816994) (xy -3.429 -63.324994)
			)
			(stroke
				(width 0)
				(type default)
			)
			(fill yes)
			(layer "F.Fab")
		)
		(pad "1" smd rect
			(at -2.050034 -63.324994 270)
			(size 0.519938 1.4986)
			(layers "F.Cu" "F.Mask" "F.Paste")
			(net "P12V_S3_AUX_CPU0_NVDIMM")
		)
		(pad "2" smd rect
			(at -2.050034 -62.47511 270)
			(size 0.519938 1.4986)
			(layers "F.Cu" "F.Mask" "F.Paste")
			(net "TP_CHH_CPU0_DIMM1_FRU_0")
		)
		(pad "3" smd rect
			(at -2.050034 -61.624972 270)
			(size 0.519938 1.4986)
			(layers "F.Cu" "F.Mask" "F.Paste")
			(net "P3V3_AUX")
		)
		(pad "4" smd rect
			(at -2.050034 -60.775088 270)
			(size 0.519938 1.4986)
			(layers "F.Cu" "F.Mask" "F.Paste")
			(net "I3C_SPD_DDREFGH_CPU0_LVC1_SCL_6")
		)
		(pad "5" smd rect
			(at -2.050034 -59.92495 270)
			(size 0.519938 1.4986)
			(layers "F.Cu" "F.Mask" "F.Paste")
			(net "I3C_SPD_DDREFGH_CPU0_LVC1_SDA")
		)
		(pad "6" smd rect
			(at -2.050034 -59.075066 270)
			(size 0.519938 1.4986)
			(layers "F.Cu" "F.Mask" "F.Paste")
			(net "GND")
		)
		(pad "7" smd rect
			(at -2.050034 -58.224928 270)
			(size 0.519938 1.4986)
			(layers "F.Cu" "F.Mask" "F.Paste")
			(net "M_H_CPU0_SA_DQ<0>")
		)
		(pad "8" smd rect
			(at -2.050034 -57.375044 270)
			(size 0.519938 1.4986)
			(layers "F.Cu" "F.Mask" "F.Paste")
			(net "GND")
		)
		(pad "9" smd rect
			(at -2.050034 -56.524906 270)
			(size 0.519938 1.4986)
			(layers "F.Cu" "F.Mask" "F.Paste")
			(net "M_H_CPU0_SA_DQ<1>")
		)
		(pad "10" smd rect
			(at -2.050034 -55.675022 270)
			(size 0.519938 1.4986)
			(layers "F.Cu" "F.Mask" "F.Paste")
			(net "GND")
		)
		(pad "11" smd rect
			(at -2.050034 -54.824884 270)
			(size 0.519938 1.4986)
			(layers "F.Cu" "F.Mask" "F.Paste")
			(net "M_H_CPU0_SA_DQS_DP<0>")
		)
		(pad "12" smd rect
			(at -2.050034 -53.975 270)
			(size 0.519938 1.4986)
			(layers "F.Cu" "F.Mask" "F.Paste")
			(net "M_H_CPU0_SA_DQS_DN<0>")
		)
		(pad "13" smd rect
			(at -2.050034 -53.125116 270)
			(size 0.519938 1.4986)
			(layers "F.Cu" "F.Mask" "F.Paste")
			(net "GND")
		)
		(pad "14" smd rect
			(at -2.050034 -52.274978 270)
			(size 0.519938 1.4986)
			(layers "F.Cu" "F.Mask" "F.Paste")
			(net "M_H_CPU0_SA_DQ<4>")
		)
		(pad "15" smd rect
			(at -2.050034 -51.425094 270)
			(size 0.519938 1.4986)
			(layers "F.Cu" "F.Mask" "F.Paste")
			(net "GND")
		)
		(pad "16" smd rect
			(at -2.050034 -50.574956 270)
			(size 0.519938 1.4986)
			(layers "F.Cu" "F.Mask" "F.Paste")
			(net "M_H_CPU0_SA_DQ<5>")
		)
		(pad "17" smd rect
			(at -2.050034 -49.725072 270)
			(size 0.519938 1.4986)
			(layers "F.Cu" "F.Mask" "F.Paste")
			(net "GND")
		)
		(pad "18" smd rect
			(at -2.050034 -48.874934 270)
			(size 0.519938 1.4986)
			(layers "F.Cu" "F.Mask" "F.Paste")
			(net "M_H_CPU0_SA_DQ<8>")
		)
		(pad "19" smd rect
			(at -2.050034 -48.02505 270)
			(size 0.519938 1.4986)
			(layers "F.Cu" "F.Mask" "F.Paste")
			(net "GND")
		)
		(pad "20" smd rect
			(at -2.050034 -47.174912 270)
			(size 0.519938 1.4986)
			(layers "F.Cu" "F.Mask" "F.Paste")
			(net "M_H_CPU0_SA_DQ<9>")
		)
		(pad "21" smd rect
			(at -2.050034 -46.325028 270)
			(size 0.519938 1.4986)
			(layers "F.Cu" "F.Mask" "F.Paste")
			(net "GND")
		)
		(pad "22" smd rect
			(at -2.050034 -45.47489 270)
			(size 0.519938 1.4986)
			(layers "F.Cu" "F.Mask" "F.Paste")
			(net "M_H_CPU0_SA_DQS_DP<1>")
		)
		(pad "23" smd rect
			(at -2.050034 -44.625006 270)
			(size 0.519938 1.4986)
			(layers "F.Cu" "F.Mask" "F.Paste")
			(net "M_H_CPU0_SA_DQS_DN<1>")
		)
		(pad "24" smd rect
			(at -2.050034 -43.775122 270)
			(size 0.519938 1.4986)
			(layers "F.Cu" "F.Mask" "F.Paste")
			(net "GND")
		)
		(pad "25" smd rect
			(at -2.050034 -42.924984 270)
			(size 0.519938 1.4986)
			(layers "F.Cu" "F.Mask" "F.Paste")
			(net "M_H_CPU0_SA_DQ<12>")
		)
		(pad "26" smd rect
			(at -2.050034 -42.0751 270)
			(size 0.519938 1.4986)
			(layers "F.Cu" "F.Mask" "F.Paste")
			(net "GND")
		)
		(pad "27" smd rect
			(at -2.050034 -41.224962 270)
			(size 0.519938 1.4986)
			(layers "F.Cu" "F.Mask" "F.Paste")
			(net "M_H_CPU0_SA_DQ<13>")
		)
		(pad "28" smd rect
			(at -2.050034 -40.375078 270)
			(size 0.519938 1.4986)
			(layers "F.Cu" "F.Mask" "F.Paste")
			(net "GND")
		)
		(pad "29" smd rect
			(at -2.050034 -39.52494 270)
			(size 0.519938 1.4986)
			(layers "F.Cu" "F.Mask" "F.Paste")
			(net "M_H_CPU0_SA_DQ<16>")
		)
		(pad "30" smd rect
			(at -2.050034 -38.675056 270)
			(size 0.519938 1.4986)
			(layers "F.Cu" "F.Mask" "F.Paste")
			(net "GND")
		)
		(pad "31" smd rect
			(at -2.050034 -37.824918 270)
			(size 0.519938 1.4986)
			(layers "F.Cu" "F.Mask" "F.Paste")
			(net "M_H_CPU0_SA_DQ<17>")
		)
		(pad "32" smd rect
			(at -2.050034 -36.975034 270)
			(size 0.519938 1.4986)
			(layers "F.Cu" "F.Mask" "F.Paste")
			(net "GND")
		)
		(pad "33" smd rect
			(at -2.050034 -36.124896 270)
			(size 0.519938 1.4986)
			(layers "F.Cu" "F.Mask" "F.Paste")
			(net "M_H_CPU0_SA_DQS_DP<2>")
		)
		(pad "34" smd rect
			(at -2.050034 -35.275012 270)
			(size 0.519938 1.4986)
			(layers "F.Cu" "F.Mask" "F.Paste")
			(net "M_H_CPU0_SA_DQS_DN<2>")
		)
		(pad "35" smd rect
			(at -2.050034 -34.425128 270)
			(size 0.519938 1.4986)
			(layers "F.Cu" "F.Mask" "F.Paste")
			(net "GND")
		)
		(pad "36" smd rect
			(at -2.050034 -33.57499 270)
			(size 0.519938 1.4986)
			(layers "F.Cu" "F.Mask" "F.Paste")
			(net "M_H_CPU0_SA_DQ<20>")
		)
		(pad "37" smd rect
			(at -2.050034 -32.725106 270)
			(size 0.519938 1.4986)
			(layers "F.Cu" "F.Mask" "F.Paste")
			(net "GND")
		)
		(pad "38" smd rect
			(at -2.050034 -31.874968 270)
			(size 0.519938 1.4986)
			(layers "F.Cu" "F.Mask" "F.Paste")
			(net "M_H_CPU0_SA_DQ<21>")
		)
		(pad "39" smd rect
			(at -2.050034 -31.025084 270)
			(size 0.519938 1.4986)
			(layers "F.Cu" "F.Mask" "F.Paste")
			(net "GND")
		)
		(pad "40" smd rect
			(at -2.050034 -30.174946 270)
			(size 0.519938 1.4986)
			(layers "F.Cu" "F.Mask" "F.Paste")
			(net "M_H_CPU0_SA_DQ<24>")
		)
		(pad "41" smd rect
			(at -2.050034 -29.325062 270)
			(size 0.519938 1.4986)
			(layers "F.Cu" "F.Mask" "F.Paste")
			(net "GND")
		)
		(pad "42" smd rect
			(at -2.050034 -28.474924 270)
			(size 0.519938 1.4986)
			(layers "F.Cu" "F.Mask" "F.Paste")
			(net "M_H_CPU0_SA_DQ<25>")
		)
		(pad "43" smd rect
			(at -2.050034 -27.62504 270)
			(size 0.519938 1.4986)
			(layers "F.Cu" "F.Mask" "F.Paste")
			(net "GND")
		)
		(pad "44" smd rect
			(at -2.050034 -26.774902 270)
			(size 0.519938 1.4986)
			(layers "F.Cu" "F.Mask" "F.Paste")
			(net "M_H_CPU0_SA_DQS_DP<3>")
		)
		(pad "45" smd rect
			(at -2.050034 -25.925018 270)
			(size 0.519938 1.4986)
			(layers "F.Cu" "F.Mask" "F.Paste")
			(net "M_H_CPU0_SA_DQS_DN<3>")
		)
		(pad "46" smd rect
			(at -2.050034 -25.07488 270)
			(size 0.519938 1.4986)
			(layers "F.Cu" "F.Mask" "F.Paste")
			(net "GND")
		)
		(pad "47" smd rect
			(at -2.050034 -24.224996 270)
			(size 0.519938 1.4986)
			(layers "F.Cu" "F.Mask" "F.Paste")
			(net "M_H_CPU0_SA_DQ<28>")
		)
		(pad "48" smd rect
			(at -2.050034 -23.375112 270)
			(size 0.519938 1.4986)
			(layers "F.Cu" "F.Mask" "F.Paste")
			(net "GND")
		)
		(pad "49" smd rect
			(at -2.050034 -22.524974 270)
			(size 0.519938 1.4986)
			(layers "F.Cu" "F.Mask" "F.Paste")
			(net "M_H_CPU0_SA_DQ<29>")
		)
		(pad "50" smd rect
			(at -2.050034 -21.67509 270)
			(size 0.519938 1.4986)
			(layers "F.Cu" "F.Mask" "F.Paste")
			(net "GND")
		)
		(pad "51" smd rect
			(at -2.050034 -20.824952 270)
			(size 0.519938 1.4986)
			(layers "F.Cu" "F.Mask" "F.Paste")
			(net "M_H_CPU0_SA_CB<0>")
		)
		(pad "52" smd rect
			(at -2.050034 -19.975068 270)
			(size 0.519938 1.4986)
			(layers "F.Cu" "F.Mask" "F.Paste")
			(net "GND")
		)
		(pad "53" smd rect
			(at -2.050034 -19.12493 270)
			(size 0.519938 1.4986)
			(layers "F.Cu" "F.Mask" "F.Paste")
			(net "M_H_CPU0_SA_CB<1>")
		)
		(pad "54" smd rect
			(at -2.050034 -18.275046 270)
			(size 0.519938 1.4986)
			(layers "F.Cu" "F.Mask" "F.Paste")
			(net "GND")
		)
		(pad "55" smd rect
			(at -2.050034 -17.424908 270)
			(size 0.519938 1.4986)
			(layers "F.Cu" "F.Mask" "F.Paste")
			(net "M_H_CPU0_SA_DQS_DP<4>")
		)
		(pad "56" smd rect
			(at -2.050034 -16.575024 270)
			(size 0.519938 1.4986)
			(layers "F.Cu" "F.Mask" "F.Paste")
			(net "M_H_CPU0_SA_DQS_DN<4>")
		)
		(pad "57" smd rect
			(at -2.050034 -15.724886 270)
			(size 0.519938 1.4986)
			(layers "F.Cu" "F.Mask" "F.Paste")
			(net "GND")
		)
		(pad "58" smd rect
			(at -2.050034 -14.875002 270)
			(size 0.519938 1.4986)
			(layers "F.Cu" "F.Mask" "F.Paste")
			(net "M_H_CPU0_SA_CB<4>")
		)
		(pad "59" smd rect
			(at -2.050034 -14.025118 270)
			(size 0.519938 1.4986)
			(layers "F.Cu" "F.Mask" "F.Paste")
			(net "GND")
		)
		(pad "60" smd rect
			(at -2.050034 -13.17498 270)
			(size 0.519938 1.4986)
			(layers "F.Cu" "F.Mask" "F.Paste")
			(net "M_H_CPU0_SA_CB<5>")
		)
		(pad "61" smd rect
			(at -2.050034 -12.325096 270)
			(size 0.519938 1.4986)
			(layers "F.Cu" "F.Mask" "F.Paste")
			(net "GND")
		)
		(pad "62" smd rect
			(at -2.050034 -11.474958 270)
			(size 0.519938 1.4986)
			(layers "F.Cu" "F.Mask" "F.Paste")
			(net "M_H_CPU0_ALERT_N")
		)
		(pad "63" smd rect
			(at -2.050034 -10.625074 270)
			(size 0.519938 1.4986)
			(layers "F.Cu" "F.Mask" "F.Paste")
			(net "GND")
		)
		(pad "64" smd rect
			(at -2.050034 -9.774936 270)
			(size 0.519938 1.4986)
			(layers "F.Cu" "F.Mask" "F.Paste")
			(net "M_H_CPU0_SA_CS_N<0>")
		)
		(pad "65" smd rect
			(at -2.050034 -8.925052 270)
			(size 0.519938 1.4986)
			(layers "F.Cu" "F.Mask" "F.Paste")
			(net "GND")
		)
		(pad "66" smd rect
			(at -2.050034 -8.074914 270)
			(size 0.519938 1.4986)
			(layers "F.Cu" "F.Mask" "F.Paste")
			(net "M_H_CPU0_SA_CA<0>")
		)
		(pad "67" smd rect
			(at -2.050034 -7.22503 270)
			(size 0.519938 1.4986)
			(layers "F.Cu" "F.Mask" "F.Paste")
			(net "GND")
		)
		(pad "68" smd rect
			(at -2.050034 -6.374892 270)
			(size 0.519938 1.4986)
			(layers "F.Cu" "F.Mask" "F.Paste")
			(net "M_H_CPU0_SA_CA<2>")
		)
		(pad "69" smd rect
			(at -2.050034 -5.525008 270)
			(size 0.519938 1.4986)
			(layers "F.Cu" "F.Mask" "F.Paste")
			(net "GND")
		)
		(pad "70" smd rect
			(at -2.050034 -4.675124 270)
			(size 0.519938 1.4986)
			(layers "F.Cu" "F.Mask" "F.Paste")
			(net "M_H_CPU0_SA_CA<4>")
		)
		(pad "71" smd rect
			(at -2.050034 -3.824986 270)
			(size 0.519938 1.4986)
			(layers "F.Cu" "F.Mask" "F.Paste")
			(net "GND")
		)
		(pad "72" smd rect
			(at -2.050034 -2.975102 270)
			(size 0.519938 1.4986)
			(layers "F.Cu" "F.Mask" "F.Paste")
			(net "M_H_CPU0_SA_CA<6>")
		)
		(pad "73" smd rect
			(at -2.050034 -2.124964 270)
			(size 0.519938 1.4986)
			(layers "F.Cu" "F.Mask" "F.Paste")
			(net "GND")
		)
		(pad "74" smd rect
			(at -2.050034 -1.27508 270)
			(size 0.519938 1.4986)
			(layers "F.Cu" "F.Mask" "F.Paste")
			(net "M_H_CPU0_SA_PAR")
		)
		(pad "75" smd rect
			(at -2.050034 -0.424942 270)
			(size 0.519938 1.4986)
			(layers "F.Cu" "F.Mask" "F.Paste")
			(net "GND")
		)
		(pad "76" smd rect
			(at -2.050034 5.525008 270)
			(size 0.519938 1.4986)
			(layers "F.Cu" "F.Mask" "F.Paste")
			(net "M_H_CPU0_SB_CA<0>")
		)
		(pad "77" smd rect
			(at -2.050034 6.374892 270)
			(size 0.519938 1.4986)
			(layers "F.Cu" "F.Mask" "F.Paste")
			(net "GND")
		)
		(pad "78" smd rect
			(at -2.050034 7.22503 270)
			(size 0.519938 1.4986)
			(layers "F.Cu" "F.Mask" "F.Paste")
			(net "M_H_CPU0_SB_CA<2>")
		)
		(pad "79" smd rect
			(at -2.050034 8.074914 270)
			(size 0.519938 1.4986)
			(layers "F.Cu" "F.Mask" "F.Paste")
			(net "GND")
		)
		(pad "80" smd rect
			(at -2.050034 8.925052 270)
			(size 0.519938 1.4986)
			(layers "F.Cu" "F.Mask" "F.Paste")
			(net "M_H_CPU0_SB_CA<4>")
		)
		(pad "81" smd rect
			(at -2.050034 9.774936 270)
			(size 0.519938 1.4986)
			(layers "F.Cu" "F.Mask" "F.Paste")
			(net "GND")
		)
		(pad "82" smd rect
			(at -2.050034 10.625074 270)
			(size 0.519938 1.4986)
			(layers "F.Cu" "F.Mask" "F.Paste")
			(net "M_H_CPU0_SB_CA<6>")
		)
		(pad "83" smd rect
			(at -2.050034 11.474958 270)
			(size 0.519938 1.4986)
			(layers "F.Cu" "F.Mask" "F.Paste")
			(net "GND")
		)
		(pad "84" smd rect
			(at -2.050034 12.325096 270)
			(size 0.519938 1.4986)
			(layers "F.Cu" "F.Mask" "F.Paste")
			(net "M_H_CPU0_SB_CS_N<0>")
		)
		(pad "85" smd rect
			(at -2.050034 13.17498 270)
			(size 0.519938 1.4986)
			(layers "F.Cu" "F.Mask" "F.Paste")
			(net "GND")
		)
		(pad "86" smd rect
			(at -2.050034 14.025118 270)
			(size 0.519938 1.4986)
			(layers "F.Cu" "F.Mask" "F.Paste")
			(net "M_H_CPU0_SA_RSP<0>")
		)
		(pad "87" smd rect
			(at -2.050034 14.875002 270)
			(size 0.519938 1.4986)
			(layers "F.Cu" "F.Mask" "F.Paste")
			(net "M_H_CPU0_SB_RSP<0>")
		)
		(pad "88" smd rect
			(at -2.050034 15.724886 270)
			(size 0.519938 1.4986)
			(layers "F.Cu" "F.Mask" "F.Paste")
			(net "GND")
		)
		(pad "89" smd rect
			(at -2.050034 16.575024 270)
			(size 0.519938 1.4986)
			(layers "F.Cu" "F.Mask" "F.Paste")
			(net "M_H_CPU0_SB_CB<4>")
		)
		(pad "90" smd rect
			(at -2.050034 17.424908 270)
			(size 0.519938 1.4986)
			(layers "F.Cu" "F.Mask" "F.Paste")
			(net "GND")
		)
		(pad "91" smd rect
			(at -2.050034 18.275046 270)
			(size 0.519938 1.4986)
			(layers "F.Cu" "F.Mask" "F.Paste")
			(net "M_H_CPU0_SB_CB<5>")
		)
		(pad "92" smd rect
			(at -2.050034 19.12493 270)
			(size 0.519938 1.4986)
			(layers "F.Cu" "F.Mask" "F.Paste")
			(net "GND")
		)
		(pad "93" smd rect
			(at -2.050034 19.975068 270)
			(size 0.519938 1.4986)
			(layers "F.Cu" "F.Mask" "F.Paste")
			(net "M_H_CPU0_SB_DQS_DP<9>")
		)
		(pad "94" smd rect
			(at -2.050034 20.824952 270)
			(size 0.519938 1.4986)
			(layers "F.Cu" "F.Mask" "F.Paste")
			(net "M_H_CPU0_SB_DQS_DN<9>")
		)
		(pad "95" smd rect
			(at -2.050034 21.67509 270)
			(size 0.519938 1.4986)
			(layers "F.Cu" "F.Mask" "F.Paste")
			(net "GND")
		)
		(pad "96" smd rect
			(at -2.050034 22.524974 270)
			(size 0.519938 1.4986)
			(layers "F.Cu" "F.Mask" "F.Paste")
			(net "M_H_CPU0_SB_CB<0>")
		)
		(pad "97" smd rect
			(at -2.050034 23.375112 270)
			(size 0.519938 1.4986)
			(layers "F.Cu" "F.Mask" "F.Paste")
			(net "GND")
		)
		(pad "98" smd rect
			(at -2.050034 24.224996 270)
			(size 0.519938 1.4986)
			(layers "F.Cu" "F.Mask" "F.Paste")
			(net "M_H_CPU0_SB_CB<1>")
		)
		(pad "99" smd rect
			(at -2.050034 25.07488 270)
			(size 0.519938 1.4986)
			(layers "F.Cu" "F.Mask" "F.Paste")
			(net "GND")
		)
		(pad "100" smd rect
			(at -2.050034 25.925018 270)
			(size 0.519938 1.4986)
			(layers "F.Cu" "F.Mask" "F.Paste")
			(net "M_H_CPU0_SB_DQ<0>")
		)
		(pad "101" smd rect
			(at -2.050034 26.774902 270)
			(size 0.519938 1.4986)
			(layers "F.Cu" "F.Mask" "F.Paste")
			(net "GND")
		)
		(pad "102" smd rect
			(at -2.050034 27.62504 270)
			(size 0.519938 1.4986)
			(layers "F.Cu" "F.Mask" "F.Paste")
			(net "M_H_CPU0_SB_DQ<1>")
		)
		(pad "103" smd rect
			(at -2.050034 28.474924 270)
			(size 0.519938 1.4986)
			(layers "F.Cu" "F.Mask" "F.Paste")
			(net "GND")
		)
		(pad "104" smd rect
			(at -2.050034 29.325062 270)
			(size 0.519938 1.4986)
			(layers "F.Cu" "F.Mask" "F.Paste")
			(net "M_H_CPU0_SB_DQS_DP<0>")
		)
		(pad "105" smd rect
			(at -2.050034 30.174946 270)
			(size 0.519938 1.4986)
			(layers "F.Cu" "F.Mask" "F.Paste")
			(net "M_H_CPU0_SB_DQS_DN<0>")
		)
		(pad "106" smd rect
			(at -2.050034 31.025084 270)
			(size 0.519938 1.4986)
			(layers "F.Cu" "F.Mask" "F.Paste")
			(net "GND")
		)
		(pad "107" smd rect
			(at -2.050034 31.874968 270)
			(size 0.519938 1.4986)
			(layers "F.Cu" "F.Mask" "F.Paste")
			(net "M_H_CPU0_SB_DQ<4>")
		)
		(pad "108" smd rect
			(at -2.050034 32.725106 270)
			(size 0.519938 1.4986)
			(layers "F.Cu" "F.Mask" "F.Paste")
			(net "GND")
		)
		(pad "109" smd rect
			(at -2.050034 33.57499 270)
			(size 0.519938 1.4986)
			(layers "F.Cu" "F.Mask" "F.Paste")
			(net "M_H_CPU0_SB_DQ<5>")
		)
		(pad "110" smd rect
			(at -2.050034 34.425128 270)
			(size 0.519938 1.4986)
			(layers "F.Cu" "F.Mask" "F.Paste")
			(net "GND")
		)
		(pad "111" smd rect
			(at -2.050034 35.275012 270)
			(size 0.519938 1.4986)
			(layers "F.Cu" "F.Mask" "F.Paste")
			(net "M_H_CPU0_SB_DQ<8>")
		)
		(pad "112" smd rect
			(at -2.050034 36.124896 270)
			(size 0.519938 1.4986)
			(layers "F.Cu" "F.Mask" "F.Paste")
			(net "GND")
		)
		(pad "113" smd rect
			(at -2.050034 36.975034 270)
			(size 0.519938 1.4986)
			(layers "F.Cu" "F.Mask" "F.Paste")
			(net "M_H_CPU0_SB_DQ<9>")
		)
		(pad "114" smd rect
			(at -2.050034 37.824918 270)
			(size 0.519938 1.4986)
			(layers "F.Cu" "F.Mask" "F.Paste")
			(net "GND")
		)
		(pad "115" smd rect
			(at -2.050034 38.675056 270)
			(size 0.519938 1.4986)
			(layers "F.Cu" "F.Mask" "F.Paste")
			(net "M_H_CPU0_SB_DQS_DP<1>")
		)
		(pad "116" smd rect
			(at -2.050034 39.52494 270)
			(size 0.519938 1.4986)
			(layers "F.Cu" "F.Mask" "F.Paste")
			(net "M_H_CPU0_SB_DQS_DN<1>")
		)
		(pad "117" smd rect
			(at -2.050034 40.375078 270)
			(size 0.519938 1.4986)
			(layers "F.Cu" "F.Mask" "F.Paste")
			(net "GND")
		)
		(pad "118" smd rect
			(at -2.050034 41.224962 270)
			(size 0.519938 1.4986)
			(layers "F.Cu" "F.Mask" "F.Paste")
			(net "M_H_CPU0_SB_DQ<12>")
		)
		(pad "119" smd rect
			(at -2.050034 42.0751 270)
			(size 0.519938 1.4986)
			(layers "F.Cu" "F.Mask" "F.Paste")
			(net "GND")
		)
		(pad "120" smd rect
			(at -2.050034 42.924984 270)
			(size 0.519938 1.4986)
			(layers "F.Cu" "F.Mask" "F.Paste")
			(net "M_H_CPU0_SB_DQ<13>")
		)
		(pad "121" smd rect
			(at -2.050034 43.775122 270)
			(size 0.519938 1.4986)
			(layers "F.Cu" "F.Mask" "F.Paste")
			(net "GND")
		)
		(pad "122" smd rect
			(at -2.050034 44.625006 270)
			(size 0.519938 1.4986)
			(layers "F.Cu" "F.Mask" "F.Paste")
			(net "M_H_CPU0_SB_DQ<16>")
		)
		(pad "123" smd rect
			(at -2.050034 45.47489 270)
			(size 0.519938 1.4986)
			(layers "F.Cu" "F.Mask" "F.Paste")
			(net "GND")
		)
		(pad "124" smd rect
			(at -2.050034 46.325028 270)
			(size 0.519938 1.4986)
			(layers "F.Cu" "F.Mask" "F.Paste")
			(net "M_H_CPU0_SB_DQ<17>")
		)
		(pad "125" smd rect
			(at -2.050034 47.174912 270)
			(size 0.519938 1.4986)
			(layers "F.Cu" "F.Mask" "F.Paste")
			(net "GND")
		)
		(pad "126" smd rect
			(at -2.050034 48.02505 270)
			(size 0.519938 1.4986)
			(layers "F.Cu" "F.Mask" "F.Paste")
			(net "M_H_CPU0_SB_DQS_DP<2>")
		)
		(pad "127" smd rect
			(at -2.050034 48.874934 270)
			(size 0.519938 1.4986)
			(layers "F.Cu" "F.Mask" "F.Paste")
			(net "M_H_CPU0_SB_DQS_DN<2>")
		)
		(pad "128" smd rect
			(at -2.050034 49.725072 270)
			(size 0.519938 1.4986)
			(layers "F.Cu" "F.Mask" "F.Paste")
			(net "GND")
		)
		(pad "129" smd rect
			(at -2.050034 50.574956 270)
			(size 0.519938 1.4986)
			(layers "F.Cu" "F.Mask" "F.Paste")
			(net "M_H_CPU0_SB_DQ<20>")
		)
		(pad "130" smd rect
			(at -2.050034 51.425094 270)
			(size 0.519938 1.4986)
			(layers "F.Cu" "F.Mask" "F.Paste")
			(net "GND")
		)
		(pad "131" smd rect
			(at -2.050034 52.274978 270)
			(size 0.519938 1.4986)
			(layers "F.Cu" "F.Mask" "F.Paste")
			(net "M_H_CPU0_SB_DQ<21>")
		)
		(pad "132" smd rect
			(at -2.050034 53.125116 270)
			(size 0.519938 1.4986)
			(layers "F.Cu" "F.Mask" "F.Paste")
			(net "GND")
		)
		(pad "133" smd rect
			(at -2.050034 53.975 270)
			(size 0.519938 1.4986)
			(layers "F.Cu" "F.Mask" "F.Paste")
			(net "M_H_CPU0_SB_DQ<24>")
		)
		(pad "134" smd rect
			(at -2.050034 54.824884 270)
			(size 0.519938 1.4986)
			(layers "F.Cu" "F.Mask" "F.Paste")
			(net "GND")
		)
		(pad "135" smd rect
			(at -2.050034 55.675022 270)
			(size 0.519938 1.4986)
			(layers "F.Cu" "F.Mask" "F.Paste")
			(net "M_H_CPU0_SB_DQ<25>")
		)
		(pad "136" smd rect
			(at -2.050034 56.524906 270)
			(size 0.519938 1.4986)
			(layers "F.Cu" "F.Mask" "F.Paste")
			(net "GND")
		)
		(pad "137" smd rect
			(at -2.050034 57.375044 270)
			(size 0.519938 1.4986)
			(layers "F.Cu" "F.Mask" "F.Paste")
			(net "M_H_CPU0_SB_DQS_DP<3>")
		)
		(pad "138" smd rect
			(at -2.050034 58.224928 270)
			(size 0.519938 1.4986)
			(layers "F.Cu" "F.Mask" "F.Paste")
			(net "M_H_CPU0_SB_DQS_DN<3>")
		)
		(pad "139" smd rect
			(at -2.050034 59.075066 270)
			(size 0.519938 1.4986)
			(layers "F.Cu" "F.Mask" "F.Paste")
			(net "GND")
		)
		(pad "140" smd rect
			(at -2.050034 59.92495 270)
			(size 0.519938 1.4986)
			(layers "F.Cu" "F.Mask" "F.Paste")
			(net "M_H_CPU0_SB_DQ<28>")
		)
		(pad "141" smd rect
			(at -2.050034 60.775088 270)
			(size 0.519938 1.4986)
			(layers "F.Cu" "F.Mask" "F.Paste")
			(net "GND")
		)
		(pad "142" smd rect
			(at -2.050034 61.624972 270)
			(size 0.519938 1.4986)
			(layers "F.Cu" "F.Mask" "F.Paste")
			(net "M_H_CPU0_SB_DQ<29>")
		)
		(pad "143" smd rect
			(at -2.050034 62.47511 270)
			(size 0.519938 1.4986)
			(layers "F.Cu" "F.Mask" "F.Paste")
			(net "GND")
		)
		(pad "144" smd rect
			(at -2.050034 63.324994 270)
			(size 0.519938 1.4986)
			(layers "F.Cu" "F.Mask" "F.Paste")
			(net "TP_CHH_CPU0_DIMM1_FRU_1")
		)
		(pad "145" smd rect
			(at 2.050034 -63.324994 270)
			(size 0.519938 1.4986)
			(layers "F.Cu" "F.Mask" "F.Paste")
			(net "P12V_S3_AUX_CPU0_NVDIMM")
		)
		(pad "146" smd rect
			(at 2.050034 -62.47511 270)
			(size 0.519938 1.4986)
			(layers "F.Cu" "F.Mask" "F.Paste")
			(net "P12V_S3_AUX_CPU0_NVDIMM")
		)
		(pad "147" smd rect
			(at 2.050034 -61.624972 270)
			(size 0.519938 1.4986)
			(layers "F.Cu" "F.Mask" "F.Paste")
			(net "PWRGD_CHH_CPU0_DIMM1")
		)
		(pad "148" smd rect
			(at 2.050034 -60.775088 270)
			(size 0.519938 1.4986)
			(layers "F.Cu" "F.Mask" "F.Paste")
			(net "PD_CHH_CPU0_DIMM1_SAA")
		)
		(pad "149" smd rect
			(at 2.050034 -59.92495 270)
			(size 0.519938 1.4986)
			(layers "F.Cu" "F.Mask" "F.Paste")
			(net "TP_CHH_CPU0_DIMM1_FRU_2")
		)
		(pad "150" smd rect
			(at 2.050034 -59.075066 270)
			(size 0.519938 1.4986)
			(layers "F.Cu" "F.Mask" "F.Paste")
			(net "TP_CHH_CPU0_DIMM1_FRU_3")
		)
		(pad "151" smd rect
			(at 2.050034 -58.224928 270)
			(size 0.519938 1.4986)
			(layers "F.Cu" "F.Mask" "F.Paste")
			(net "GND")
		)
		(pad "152" smd rect
			(at 2.050034 -57.375044 270)
			(size 0.519938 1.4986)
			(layers "F.Cu" "F.Mask" "F.Paste")
			(net "M_H_CPU0_SA_DQ<2>")
		)
		(pad "153" smd rect
			(at 2.050034 -56.524906 270)
			(size 0.519938 1.4986)
			(layers "F.Cu" "F.Mask" "F.Paste")
			(net "GND")
		)
		(pad "154" smd rect
			(at 2.050034 -55.675022 270)
			(size 0.519938 1.4986)
			(layers "F.Cu" "F.Mask" "F.Paste")
			(net "M_H_CPU0_SA_DQ<3>")
		)
		(pad "155" smd rect
			(at 2.050034 -54.824884 270)
			(size 0.519938 1.4986)
			(layers "F.Cu" "F.Mask" "F.Paste")
			(net "GND")
		)
		(pad "156" smd rect
			(at 2.050034 -53.975 270)
			(size 0.519938 1.4986)
			(layers "F.Cu" "F.Mask" "F.Paste")
			(net "M_H_CPU0_SA_DQS_DN<5>")
		)
		(pad "157" smd rect
			(at 2.050034 -53.125116 270)
			(size 0.519938 1.4986)
			(layers "F.Cu" "F.Mask" "F.Paste")
			(net "M_H_CPU0_SA_DQS_DP<5>")
		)
		(pad "158" smd rect
			(at 2.050034 -52.274978 270)
			(size 0.519938 1.4986)
			(layers "F.Cu" "F.Mask" "F.Paste")
			(net "GND")
		)
		(pad "159" smd rect
			(at 2.050034 -51.425094 270)
			(size 0.519938 1.4986)
			(layers "F.Cu" "F.Mask" "F.Paste")
			(net "M_H_CPU0_SA_DQ<6>")
		)
		(pad "160" smd rect
			(at 2.050034 -50.574956 270)
			(size 0.519938 1.4986)
			(layers "F.Cu" "F.Mask" "F.Paste")
			(net "GND")
		)
		(pad "161" smd rect
			(at 2.050034 -49.725072 270)
			(size 0.519938 1.4986)
			(layers "F.Cu" "F.Mask" "F.Paste")
			(net "M_H_CPU0_SA_DQ<7>")
		)
		(pad "162" smd rect
			(at 2.050034 -48.874934 270)
			(size 0.519938 1.4986)
			(layers "F.Cu" "F.Mask" "F.Paste")
			(net "GND")
		)
		(pad "163" smd rect
			(at 2.050034 -48.02505 270)
			(size 0.519938 1.4986)
			(layers "F.Cu" "F.Mask" "F.Paste")
			(net "M_H_CPU0_SA_DQ<10>")
		)
		(pad "164" smd rect
			(at 2.050034 -47.174912 270)
			(size 0.519938 1.4986)
			(layers "F.Cu" "F.Mask" "F.Paste")
			(net "GND")
		)
		(pad "165" smd rect
			(at 2.050034 -46.325028 270)
			(size 0.519938 1.4986)
			(layers "F.Cu" "F.Mask" "F.Paste")
			(net "M_H_CPU0_SA_DQ<11>")
		)
		(pad "166" smd rect
			(at 2.050034 -45.47489 270)
			(size 0.519938 1.4986)
			(layers "F.Cu" "F.Mask" "F.Paste")
			(net "GND")
		)
		(pad "167" smd rect
			(at 2.050034 -44.625006 270)
			(size 0.519938 1.4986)
			(layers "F.Cu" "F.Mask" "F.Paste")
			(net "M_H_CPU0_SA_DQS_DN<6>")
		)
		(pad "168" smd rect
			(at 2.050034 -43.775122 270)
			(size 0.519938 1.4986)
			(layers "F.Cu" "F.Mask" "F.Paste")
			(net "M_H_CPU0_SA_DQS_DP<6>")
		)
		(pad "169" smd rect
			(at 2.050034 -42.924984 270)
			(size 0.519938 1.4986)
			(layers "F.Cu" "F.Mask" "F.Paste")
			(net "GND")
		)
		(pad "170" smd rect
			(at 2.050034 -42.0751 270)
			(size 0.519938 1.4986)
			(layers "F.Cu" "F.Mask" "F.Paste")
			(net "M_H_CPU0_SA_DQ<14>")
		)
		(pad "171" smd rect
			(at 2.050034 -41.224962 270)
			(size 0.519938 1.4986)
			(layers "F.Cu" "F.Mask" "F.Paste")
			(net "GND")
		)
		(pad "172" smd rect
			(at 2.050034 -40.375078 270)
			(size 0.519938 1.4986)
			(layers "F.Cu" "F.Mask" "F.Paste")
			(net "M_H_CPU0_SA_DQ<15>")
		)
		(pad "173" smd rect
			(at 2.050034 -39.52494 270)
			(size 0.519938 1.4986)
			(layers "F.Cu" "F.Mask" "F.Paste")
			(net "GND")
		)
		(pad "174" smd rect
			(at 2.050034 -38.675056 270)
			(size 0.519938 1.4986)
			(layers "F.Cu" "F.Mask" "F.Paste")
			(net "M_H_CPU0_SA_DQ<18>")
		)
		(pad "175" smd rect
			(at 2.050034 -37.824918 270)
			(size 0.519938 1.4986)
			(layers "F.Cu" "F.Mask" "F.Paste")
			(net "GND")
		)
		(pad "176" smd rect
			(at 2.050034 -36.975034 270)
			(size 0.519938 1.4986)
			(layers "F.Cu" "F.Mask" "F.Paste")
			(net "M_H_CPU0_SA_DQ<19>")
		)
		(pad "177" smd rect
			(at 2.050034 -36.124896 270)
			(size 0.519938 1.4986)
			(layers "F.Cu" "F.Mask" "F.Paste")
			(net "GND")
		)
		(pad "178" smd rect
			(at 2.050034 -35.275012 270)
			(size 0.519938 1.4986)
			(layers "F.Cu" "F.Mask" "F.Paste")
			(net "M_H_CPU0_SA_DQS_DN<7>")
		)
		(pad "179" smd rect
			(at 2.050034 -34.425128 270)
			(size 0.519938 1.4986)
			(layers "F.Cu" "F.Mask" "F.Paste")
			(net "M_H_CPU0_SA_DQS_DP<7>")
		)
		(pad "180" smd rect
			(at 2.050034 -33.57499 270)
			(size 0.519938 1.4986)
			(layers "F.Cu" "F.Mask" "F.Paste")
			(net "GND")
		)
		(pad "181" smd rect
			(at 2.050034 -32.725106 270)
			(size 0.519938 1.4986)
			(layers "F.Cu" "F.Mask" "F.Paste")
			(net "M_H_CPU0_SA_DQ<22>")
		)
		(pad "182" smd rect
			(at 2.050034 -31.874968 270)
			(size 0.519938 1.4986)
			(layers "F.Cu" "F.Mask" "F.Paste")
			(net "GND")
		)
		(pad "183" smd rect
			(at 2.050034 -31.025084 270)
			(size 0.519938 1.4986)
			(layers "F.Cu" "F.Mask" "F.Paste")
			(net "M_H_CPU0_SA_DQ<23>")
		)
		(pad "184" smd rect
			(at 2.050034 -30.174946 270)
			(size 0.519938 1.4986)
			(layers "F.Cu" "F.Mask" "F.Paste")
			(net "GND")
		)
		(pad "185" smd rect
			(at 2.050034 -29.325062 270)
			(size 0.519938 1.4986)
			(layers "F.Cu" "F.Mask" "F.Paste")
			(net "M_H_CPU0_SA_DQ<26>")
		)
		(pad "186" smd rect
			(at 2.050034 -28.474924 270)
			(size 0.519938 1.4986)
			(layers "F.Cu" "F.Mask" "F.Paste")
			(net "GND")
		)
		(pad "187" smd rect
			(at 2.050034 -27.62504 270)
			(size 0.519938 1.4986)
			(layers "F.Cu" "F.Mask" "F.Paste")
			(net "M_H_CPU0_SA_DQ<27>")
		)
		(pad "188" smd rect
			(at 2.050034 -26.774902 270)
			(size 0.519938 1.4986)
			(layers "F.Cu" "F.Mask" "F.Paste")
			(net "GND")
		)
		(pad "189" smd rect
			(at 2.050034 -25.925018 270)
			(size 0.519938 1.4986)
			(layers "F.Cu" "F.Mask" "F.Paste")
			(net "M_H_CPU0_SA_DQS_DN<8>")
		)
		(pad "190" smd rect
			(at 2.050034 -25.07488 270)
			(size 0.519938 1.4986)
			(layers "F.Cu" "F.Mask" "F.Paste")
			(net "M_H_CPU0_SA_DQS_DP<8>")
		)
		(pad "191" smd rect
			(at 2.050034 -24.224996 270)
			(size 0.519938 1.4986)
			(layers "F.Cu" "F.Mask" "F.Paste")
			(net "GND")
		)
		(pad "192" smd rect
			(at 2.050034 -23.375112 270)
			(size 0.519938 1.4986)
			(layers "F.Cu" "F.Mask" "F.Paste")
			(net "M_H_CPU0_SA_DQ<30>")
		)
		(pad "193" smd rect
			(at 2.050034 -22.524974 270)
			(size 0.519938 1.4986)
			(layers "F.Cu" "F.Mask" "F.Paste")
			(net "GND")
		)
		(pad "194" smd rect
			(at 2.050034 -21.67509 270)
			(size 0.519938 1.4986)
			(layers "F.Cu" "F.Mask" "F.Paste")
			(net "M_H_CPU0_SA_DQ<31>")
		)
		(pad "195" smd rect
			(at 2.050034 -20.824952 270)
			(size 0.519938 1.4986)
			(layers "F.Cu" "F.Mask" "F.Paste")
			(net "GND")
		)
		(pad "196" smd rect
			(at 2.050034 -19.975068 270)
			(size 0.519938 1.4986)
			(layers "F.Cu" "F.Mask" "F.Paste")
			(net "M_H_CPU0_SA_CB<2>")
		)
		(pad "197" smd rect
			(at 2.050034 -19.12493 270)
			(size 0.519938 1.4986)
			(layers "F.Cu" "F.Mask" "F.Paste")
			(net "GND")
		)
		(pad "198" smd rect
			(at 2.050034 -18.275046 270)
			(size 0.519938 1.4986)
			(layers "F.Cu" "F.Mask" "F.Paste")
			(net "M_H_CPU0_SA_CB<3>")
		)
		(pad "199" smd rect
			(at 2.050034 -17.424908 270)
			(size 0.519938 1.4986)
			(layers "F.Cu" "F.Mask" "F.Paste")
			(net "GND")
		)
		(pad "200" smd rect
			(at 2.050034 -16.575024 270)
			(size 0.519938 1.4986)
			(layers "F.Cu" "F.Mask" "F.Paste")
			(net "M_H_CPU0_SA_DQS_DN<9>")
		)
		(pad "201" smd rect
			(at 2.050034 -15.724886 270)
			(size 0.519938 1.4986)
			(layers "F.Cu" "F.Mask" "F.Paste")
			(net "M_H_CPU0_SA_DQS_DP<9>")
		)
		(pad "202" smd rect
			(at 2.050034 -14.875002 270)
			(size 0.519938 1.4986)
			(layers "F.Cu" "F.Mask" "F.Paste")
			(net "GND")
		)
		(pad "203" smd rect
			(at 2.050034 -14.025118 270)
			(size 0.519938 1.4986)
			(layers "F.Cu" "F.Mask" "F.Paste")
			(net "M_H_CPU0_SA_CB<6>")
		)
		(pad "204" smd rect
			(at 2.050034 -13.17498 270)
			(size 0.519938 1.4986)
			(layers "F.Cu" "F.Mask" "F.Paste")
			(net "GND")
		)
		(pad "205" smd rect
			(at 2.050034 -12.325096 270)
			(size 0.519938 1.4986)
			(layers "F.Cu" "F.Mask" "F.Paste")
			(net "M_H_CPU0_SA_CB<7>")
		)
		(pad "206" smd rect
			(at 2.050034 -11.474958 270)
			(size 0.519938 1.4986)
			(layers "F.Cu" "F.Mask" "F.Paste")
			(net "GND")
		)
		(pad "207" smd rect
			(at 2.050034 -10.625074 270)
			(size 0.519938 1.4986)
			(layers "F.Cu" "F.Mask" "F.Paste")
			(net "RST_M_GH_CPU0_FPGA_N")
		)
		(pad "208" smd rect
			(at 2.050034 -9.774936 270)
			(size 0.519938 1.4986)
			(layers "F.Cu" "F.Mask" "F.Paste")
			(net "GND")
		)
		(pad "209" smd rect
			(at 2.050034 -8.925052 270)
			(size 0.519938 1.4986)
			(layers "F.Cu" "F.Mask" "F.Paste")
			(net "M_H_CPU0_SA_CS_N<1>")
		)
		(pad "210" smd rect
			(at 2.050034 -8.074914 270)
			(size 0.519938 1.4986)
			(layers "F.Cu" "F.Mask" "F.Paste")
			(net "GND")
		)
		(pad "211" smd rect
			(at 2.050034 -7.22503 270)
			(size 0.519938 1.4986)
			(layers "F.Cu" "F.Mask" "F.Paste")
			(net "M_H_CPU0_SA_CA<1>")
		)
		(pad "212" smd rect
			(at 2.050034 -6.374892 270)
			(size 0.519938 1.4986)
			(layers "F.Cu" "F.Mask" "F.Paste")
			(net "GND")
		)
		(pad "213" smd rect
			(at 2.050034 -5.525008 270)
			(size 0.519938 1.4986)
			(layers "F.Cu" "F.Mask" "F.Paste")
			(net "M_H_CPU0_SA_CA<3>")
		)
		(pad "214" smd rect
			(at 2.050034 -4.675124 270)
			(size 0.519938 1.4986)
			(layers "F.Cu" "F.Mask" "F.Paste")
			(net "GND")
		)
		(pad "215" smd rect
			(at 2.050034 -3.824986 270)
			(size 0.519938 1.4986)
			(layers "F.Cu" "F.Mask" "F.Paste")
			(net "M_H_CPU0_SA_CA<5>")
		)
		(pad "216" smd rect
			(at 2.050034 -2.975102 270)
			(size 0.519938 1.4986)
			(layers "F.Cu" "F.Mask" "F.Paste")
			(net "GND")
		)
		(pad "217" smd rect
			(at 2.050034 -2.124964 270)
			(size 0.519938 1.4986)
			(layers "F.Cu" "F.Mask" "F.Paste")
			(net "M_H_CPU0_CLK_DP<0>")
		)
		(pad "218" smd rect
			(at 2.050034 -1.27508 270)
			(size 0.519938 1.4986)
			(layers "F.Cu" "F.Mask" "F.Paste")
			(net "M_H_CPU0_CLK_DN<0>")
		)
		(pad "219" smd rect
			(at 2.050034 -0.424942 270)
			(size 0.519938 1.4986)
			(layers "F.Cu" "F.Mask" "F.Paste")
			(net "GND")
		)
		(pad "220" smd rect
			(at 2.050034 5.525008 270)
			(size 0.519938 1.4986)
			(layers "F.Cu" "F.Mask" "F.Paste")
			(net "TP_CHH_CPU0_DIMM1_FRU_4")
		)
		(pad "221" smd rect
			(at 2.050034 6.374892 270)
			(size 0.519938 1.4986)
			(layers "F.Cu" "F.Mask" "F.Paste")
			(net "M_H_CPU0_SB_CA<1>")
		)
		(pad "222" smd rect
			(at 2.050034 7.22503 270)
			(size 0.519938 1.4986)
			(layers "F.Cu" "F.Mask" "F.Paste")
			(net "GND")
		)
		(pad "223" smd rect
			(at 2.050034 8.074914 270)
			(size 0.519938 1.4986)
			(layers "F.Cu" "F.Mask" "F.Paste")
			(net "M_H_CPU0_SB_CA<3>")
		)
		(pad "224" smd rect
			(at 2.050034 8.925052 270)
			(size 0.519938 1.4986)
			(layers "F.Cu" "F.Mask" "F.Paste")
			(net "GND")
		)
		(pad "225" smd rect
			(at 2.050034 9.774936 270)
			(size 0.519938 1.4986)
			(layers "F.Cu" "F.Mask" "F.Paste")
			(net "M_H_CPU0_SB_CA<5>")
		)
		(pad "226" smd rect
			(at 2.050034 10.625074 270)
			(size 0.519938 1.4986)
			(layers "F.Cu" "F.Mask" "F.Paste")
			(net "GND")
		)
		(pad "227" smd rect
			(at 2.050034 11.474958 270)
			(size 0.519938 1.4986)
			(layers "F.Cu" "F.Mask" "F.Paste")
			(net "M_H_CPU0_SB_PAR")
		)
		(pad "228" smd rect
			(at 2.050034 12.325096 270)
			(size 0.519938 1.4986)
			(layers "F.Cu" "F.Mask" "F.Paste")
			(net "GND")
		)
		(pad "229" smd rect
			(at 2.050034 13.17498 270)
			(size 0.519938 1.4986)
			(layers "F.Cu" "F.Mask" "F.Paste")
			(net "M_H_CPU0_SB_CS_N<1>")
		)
		(pad "230" smd rect
			(at 2.050034 14.025118 270)
			(size 0.519938 1.4986)
			(layers "F.Cu" "F.Mask" "F.Paste")
			(net "GND")
		)
		(pad "231" smd rect
			(at 2.050034 14.875002 270)
			(size 0.519938 1.4986)
			(layers "F.Cu" "F.Mask" "F.Paste")
			(net "TP_CHH_CPU0_DIMM1_FRU_5")
		)
		(pad "232" smd rect
			(at 2.050034 15.724886 270)
			(size 0.519938 1.4986)
			(layers "F.Cu" "F.Mask" "F.Paste")
			(net "TP_CHH_CPU0_DIMM1_FRU_6")
		)
		(pad "233" smd rect
			(at 2.050034 16.575024 270)
			(size 0.519938 1.4986)
			(layers "F.Cu" "F.Mask" "F.Paste")
			(net "GND")
		)
		(pad "234" smd rect
			(at 2.050034 17.424908 270)
			(size 0.519938 1.4986)
			(layers "F.Cu" "F.Mask" "F.Paste")
			(net "M_H_CPU0_SB_CB<6>")
		)
		(pad "235" smd rect
			(at 2.050034 18.275046 270)
			(size 0.519938 1.4986)
			(layers "F.Cu" "F.Mask" "F.Paste")
			(net "GND")
		)
		(pad "236" smd rect
			(at 2.050034 19.12493 270)
			(size 0.519938 1.4986)
			(layers "F.Cu" "F.Mask" "F.Paste")
			(net "M_H_CPU0_SB_CB<7>")
		)
		(pad "237" smd rect
			(at 2.050034 19.975068 270)
			(size 0.519938 1.4986)
			(layers "F.Cu" "F.Mask" "F.Paste")
			(net "GND")
		)
		(pad "238" smd rect
			(at 2.050034 20.824952 270)
			(size 0.519938 1.4986)
			(layers "F.Cu" "F.Mask" "F.Paste")
			(net "M_H_CPU0_SB_DQS_DN<4>")
		)
		(pad "239" smd rect
			(at 2.050034 21.67509 270)
			(size 0.519938 1.4986)
			(layers "F.Cu" "F.Mask" "F.Paste")
			(net "M_H_CPU0_SB_DQS_DP<4>")
		)
		(pad "240" smd rect
			(at 2.050034 22.524974 270)
			(size 0.519938 1.4986)
			(layers "F.Cu" "F.Mask" "F.Paste")
			(net "GND")
		)
		(pad "241" smd rect
			(at 2.050034 23.375112 270)
			(size 0.519938 1.4986)
			(layers "F.Cu" "F.Mask" "F.Paste")
			(net "M_H_CPU0_SB_CB<2>")
		)
		(pad "242" smd rect
			(at 2.050034 24.224996 270)
			(size 0.519938 1.4986)
			(layers "F.Cu" "F.Mask" "F.Paste")
			(net "GND")
		)
		(pad "243" smd rect
			(at 2.050034 25.07488 270)
			(size 0.519938 1.4986)
			(layers "F.Cu" "F.Mask" "F.Paste")
			(net "M_H_CPU0_SB_CB<3>")
		)
		(pad "244" smd rect
			(at 2.050034 25.925018 270)
			(size 0.519938 1.4986)
			(layers "F.Cu" "F.Mask" "F.Paste")
			(net "GND")
		)
		(pad "245" smd rect
			(at 2.050034 26.774902 270)
			(size 0.519938 1.4986)
			(layers "F.Cu" "F.Mask" "F.Paste")
			(net "M_H_CPU0_SB_DQ<2>")
		)
		(pad "246" smd rect
			(at 2.050034 27.62504 270)
			(size 0.519938 1.4986)
			(layers "F.Cu" "F.Mask" "F.Paste")
			(net "GND")
		)
		(pad "247" smd rect
			(at 2.050034 28.474924 270)
			(size 0.519938 1.4986)
			(layers "F.Cu" "F.Mask" "F.Paste")
			(net "M_H_CPU0_SB_DQ<3>")
		)
		(pad "248" smd rect
			(at 2.050034 29.325062 270)
			(size 0.519938 1.4986)
			(layers "F.Cu" "F.Mask" "F.Paste")
			(net "GND")
		)
		(pad "249" smd rect
			(at 2.050034 30.174946 270)
			(size 0.519938 1.4986)
			(layers "F.Cu" "F.Mask" "F.Paste")
			(net "M_H_CPU0_SB_DQS_DN<5>")
		)
		(pad "250" smd rect
			(at 2.050034 31.025084 270)
			(size 0.519938 1.4986)
			(layers "F.Cu" "F.Mask" "F.Paste")
			(net "M_H_CPU0_SB_DQS_DP<5>")
		)
		(pad "251" smd rect
			(at 2.050034 31.874968 270)
			(size 0.519938 1.4986)
			(layers "F.Cu" "F.Mask" "F.Paste")
			(net "GND")
		)
		(pad "252" smd rect
			(at 2.050034 32.725106 270)
			(size 0.519938 1.4986)
			(layers "F.Cu" "F.Mask" "F.Paste")
			(net "M_H_CPU0_SB_DQ<6>")
		)
		(pad "253" smd rect
			(at 2.050034 33.57499 270)
			(size 0.519938 1.4986)
			(layers "F.Cu" "F.Mask" "F.Paste")
			(net "GND")
		)
		(pad "254" smd rect
			(at 2.050034 34.425128 270)
			(size 0.519938 1.4986)
			(layers "F.Cu" "F.Mask" "F.Paste")
			(net "M_H_CPU0_SB_DQ<7>")
		)
		(pad "255" smd rect
			(at 2.050034 35.275012 270)
			(size 0.519938 1.4986)
			(layers "F.Cu" "F.Mask" "F.Paste")
			(net "GND")
		)
		(pad "256" smd rect
			(at 2.050034 36.124896 270)
			(size 0.519938 1.4986)
			(layers "F.Cu" "F.Mask" "F.Paste")
			(net "M_H_CPU0_SB_DQ<10>")
		)
		(pad "257" smd rect
			(at 2.050034 36.975034 270)
			(size 0.519938 1.4986)
			(layers "F.Cu" "F.Mask" "F.Paste")
			(net "GND")
		)
		(pad "258" smd rect
			(at 2.050034 37.824918 270)
			(size 0.519938 1.4986)
			(layers "F.Cu" "F.Mask" "F.Paste")
			(net "M_H_CPU0_SB_DQ<11>")
		)
		(pad "259" smd rect
			(at 2.050034 38.675056 270)
			(size 0.519938 1.4986)
			(layers "F.Cu" "F.Mask" "F.Paste")
			(net "GND")
		)
		(pad "260" smd rect
			(at 2.050034 39.52494 270)
			(size 0.519938 1.4986)
			(layers "F.Cu" "F.Mask" "F.Paste")
			(net "M_H_CPU0_SB_DQS_DN<6>")
		)
		(pad "261" smd rect
			(at 2.050034 40.375078 270)
			(size 0.519938 1.4986)
			(layers "F.Cu" "F.Mask" "F.Paste")
			(net "M_H_CPU0_SB_DQS_DP<6>")
		)
		(pad "262" smd rect
			(at 2.050034 41.224962 270)
			(size 0.519938 1.4986)
			(layers "F.Cu" "F.Mask" "F.Paste")
			(net "GND")
		)
		(pad "263" smd rect
			(at 2.050034 42.0751 270)
			(size 0.519938 1.4986)
			(layers "F.Cu" "F.Mask" "F.Paste")
			(net "M_H_CPU0_SB_DQ<14>")
		)
		(pad "264" smd rect
			(at 2.050034 42.924984 270)
			(size 0.519938 1.4986)
			(layers "F.Cu" "F.Mask" "F.Paste")
			(net "GND")
		)
		(pad "265" smd rect
			(at 2.050034 43.775122 270)
			(size 0.519938 1.4986)
			(layers "F.Cu" "F.Mask" "F.Paste")
			(net "M_H_CPU0_SB_DQ<15>")
		)
		(pad "266" smd rect
			(at 2.050034 44.625006 270)
			(size 0.519938 1.4986)
			(layers "F.Cu" "F.Mask" "F.Paste")
			(net "GND")
		)
		(pad "267" smd rect
			(at 2.050034 45.47489 270)
			(size 0.519938 1.4986)
			(layers "F.Cu" "F.Mask" "F.Paste")
			(net "M_H_CPU0_SB_DQ<18>")
		)
		(pad "268" smd rect
			(at 2.050034 46.325028 270)
			(size 0.519938 1.4986)
			(layers "F.Cu" "F.Mask" "F.Paste")
			(net "GND")
		)
		(pad "269" smd rect
			(at 2.050034 47.174912 270)
			(size 0.519938 1.4986)
			(layers "F.Cu" "F.Mask" "F.Paste")
			(net "M_H_CPU0_SB_DQ<19>")
		)
		(pad "270" smd rect
			(at 2.050034 48.02505 270)
			(size 0.519938 1.4986)
			(layers "F.Cu" "F.Mask" "F.Paste")
			(net "GND")
		)
		(pad "271" smd rect
			(at 2.050034 48.874934 270)
			(size 0.519938 1.4986)
			(layers "F.Cu" "F.Mask" "F.Paste")
			(net "M_H_CPU0_SB_DQS_DN<7>")
		)
		(pad "272" smd rect
			(at 2.050034 49.725072 270)
			(size 0.519938 1.4986)
			(layers "F.Cu" "F.Mask" "F.Paste")
			(net "M_H_CPU0_SB_DQS_DP<7>")
		)
		(pad "273" smd rect
			(at 2.050034 50.574956 270)
			(size 0.519938 1.4986)
			(layers "F.Cu" "F.Mask" "F.Paste")
			(net "GND")
		)
		(pad "274" smd rect
			(at 2.050034 51.425094 270)
			(size 0.519938 1.4986)
			(layers "F.Cu" "F.Mask" "F.Paste")
			(net "M_H_CPU0_SB_DQ<22>")
		)
		(pad "275" smd rect
			(at 2.050034 52.274978 270)
			(size 0.519938 1.4986)
			(layers "F.Cu" "F.Mask" "F.Paste")
			(net "GND")
		)
		(pad "276" smd rect
			(at 2.050034 53.125116 270)
			(size 0.519938 1.4986)
			(layers "F.Cu" "F.Mask" "F.Paste")
			(net "M_H_CPU0_SB_DQ<23>")
		)
		(pad "277" smd rect
			(at 2.050034 53.975 270)
			(size 0.519938 1.4986)
			(layers "F.Cu" "F.Mask" "F.Paste")
			(net "GND")
		)
		(pad "278" smd rect
			(at 2.050034 54.824884 270)
			(size 0.519938 1.4986)
			(layers "F.Cu" "F.Mask" "F.Paste")
			(net "M_H_CPU0_SB_DQ<26>")
		)
		(pad "279" smd rect
			(at 2.050034 55.675022 270)
			(size 0.519938 1.4986)
			(layers "F.Cu" "F.Mask" "F.Paste")
			(net "GND")
		)
		(pad "280" smd rect
			(at 2.050034 56.524906 270)
			(size 0.519938 1.4986)
			(layers "F.Cu" "F.Mask" "F.Paste")
			(net "M_H_CPU0_SB_DQ<27>")
		)
		(pad "281" smd rect
			(at 2.050034 57.375044 270)
			(size 0.519938 1.4986)
			(layers "F.Cu" "F.Mask" "F.Paste")
			(net "GND")
		)
		(pad "282" smd rect
			(at 2.050034 58.224928 270)
			(size 0.519938 1.4986)
			(layers "F.Cu" "F.Mask" "F.Paste")
			(net "M_H_CPU0_SB_DQS_DN<8>")
		)
		(pad "283" smd rect
			(at 2.050034 59.075066 270)
			(size 0.519938 1.4986)
			(layers "F.Cu" "F.Mask" "F.Paste")
			(net "M_H_CPU0_SB_DQS_DP<8>")
		)
		(pad "284" smd rect
			(at 2.050034 59.92495 270)
			(size 0.519938 1.4986)
			(layers "F.Cu" "F.Mask" "F.Paste")
			(net "GND")
		)
		(pad "285" smd rect
			(at 2.050034 60.775088 270)
			(size 0.519938 1.4986)
			(layers "F.Cu" "F.Mask" "F.Paste")
			(net "M_H_CPU0_SB_DQ<30>")
		)
		(pad "286" smd rect
			(at 2.050034 61.624972 270)
			(size 0.519938 1.4986)
			(layers "F.Cu" "F.Mask" "F.Paste")
			(net "GND")
		)
		(pad "287" smd rect
			(at 2.050034 62.47511 270)
			(size 0.519938 1.4986)
			(layers "F.Cu" "F.Mask" "F.Paste")
			(net "M_H_CPU0_SB_DQ<31>")
		)
		(pad "288" smd rect
			(at 2.050034 63.324994 270)
			(size 0.519938 1.4986)
			(layers "F.Cu" "F.Mask" "F.Paste")
			(net "GND")
		)
		(pad "G1" thru_hole oval
			(at 0 -68.97497)
			(size 2.8194 1.5748)
			(drill oval 2.4384 1.1938)
			(layers "*.Cu" "*.Mask")
			(remove_unused_layers no)
			(net "GND")
			(clearance 0.127)
			(thermal_gap 0.127)
		)
		(pad "G2" thru_hole oval
			(at 0 3.875024)
			(size 2.8194 1.5748)
			(drill oval 2.4384 1.1938)
			(layers "*.Cu" "*.Mask")
			(remove_unused_layers no)
			(net "GND")
			(clearance 0.127)
			(thermal_gap 0.127)
		)
		(pad "G3" thru_hole oval
			(at 0 68.97497)
			(size 2.8194 1.5748)
			(drill oval 2.4384 1.1938)
			(layers "*.Cu" "*.Mask")
			(remove_unused_layers no)
			(net "GND")
			(clearance 0.127)
			(thermal_gap 0.127)
		)
	)
	(footprint ""
		(layer "F.Cu")
		(at 61.90488 -18.252948)
		(property "Reference" "R3217"
			(at 0 0 0)
			(layer "F.SilkS")
			(hide yes)
			(effects
				(font
					(size 1.27 1.27)
				)
			)
		)
		(property "Value" ""
			(at 0 0 0)
			(layer "F.Fab")
			(effects
				(font
					(size 1.27 1.27)
				)
			)
		)
		(duplicate_pad_numbers_are_jumpers no)
		(fp_line
			(start -0.7874 -0.4064)
			(end 0.7874 -0.4064)
			(stroke
				(width 0.1524)
				(type default)
			)
			(layer "F.SilkS")
		)
		(fp_line
			(start -0.7874 0.4064)
			(end -0.7874 -0.4064)
			(stroke
				(width 0.1524)
				(type default)
			)
			(layer "F.SilkS")
		)
		(fp_line
			(start 0.7874 -0.4064)
			(end 0.7874 0.4064)
			(stroke
				(width 0.1524)
				(type default)
			)
			(layer "F.SilkS")
		)
		(fp_line
			(start 0.7874 0.4064)
			(end -0.7874 0.4064)
			(stroke
				(width 0.1524)
				(type default)
			)
			(layer "F.SilkS")
		)
		(fp_line
			(start -0.67945 -0.305054)
			(end -0.12065 -0.305054)
			(stroke
				(width 0.1)
				(type default)
			)
			(layer "F.Fab")
		)
		(fp_line
			(start -0.67945 0.3048)
			(end -0.67945 -0.305054)
			(stroke
				(width 0.1)
				(type default)
			)
			(layer "F.Fab")
		)
		(fp_line
			(start -0.12065 -0.305054)
			(end -0.12065 -0.2794)
			(stroke
				(width 0.1)
				(type default)
			)
			(layer "F.Fab")
		)
		(fp_line
			(start -0.12065 -0.2794)
			(end 0.12065 -0.2794)
			(stroke
				(width 0.1)
				(type default)
			)
			(layer "F.Fab")
		)
		(fp_line
			(start -0.12065 0.2794)
			(end -0.12065 0.3048)
			(stroke
				(width 0.1)
				(type default)
			)
			(layer "F.Fab")
		)
		(fp_line
			(start -0.12065 0.3048)
			(end -0.67945 0.3048)
			(stroke
				(width 0.1)
				(type default)
			)
			(layer "F.Fab")
		)
		(fp_line
			(start 0.120396 0.2794)
			(end -0.12065 0.2794)
			(stroke
				(width 0.1)
				(type default)
			)
			(layer "F.Fab")
		)
		(fp_line
			(start 0.120396 0.3048)
			(end 0.120396 0.2794)
			(stroke
				(width 0.1)
				(type default)
			)
			(layer "F.Fab")
		)
		(fp_line
			(start 0.12065 -0.3048)
			(end 0.67945 -0.3048)
			(stroke
				(width 0.1)
				(type default)
			)
			(layer "F.Fab")
		)
		(fp_line
			(start 0.12065 -0.2794)
			(end 0.12065 -0.3048)
			(stroke
				(width 0.1)
				(type default)
			)
			(layer "F.Fab")
		)
		(fp_line
			(start 0.67945 -0.3048)
			(end 0.67945 0.3048)
			(stroke
				(width 0.1)
				(type default)
			)
			(layer "F.Fab")
		)
		(fp_line
			(start 0.67945 0.3048)
			(end 0.120396 0.3048)
			(stroke
				(width 0.1)
				(type default)
			)
			(layer "F.Fab")
		)
		(pad "1" smd circle
			(at -0.40005 0)
			(size 0 0)
			(layers "F.Cu" "F.Mask" "F.Paste")
			(net "OCP_V3_2_ISO_BIF2_EN")
		)
		(pad "2" smd circle
			(at 0.40005 0)
			(size 0 0)
			(layers "F.Cu" "F.Mask" "F.Paste")
			(net "GND")
		)
	)
	(footprint ""
		(layer "F.Cu")
		(at 68.085716 -108.39069)
		(property "Reference" "R3721"
			(at 0 0 0)
			(layer "F.SilkS")
			(hide yes)
			(effects
				(font
					(size 1.27 1.27)
				)
			)
		)
		(property "Value" ""
			(at 0 0 0)
			(layer "F.Fab")
			(effects
				(font
					(size 1.27 1.27)
				)
			)
		)
		(duplicate_pad_numbers_are_jumpers no)
		(fp_line
			(start -0.7874 -0.4064)
			(end 0.7874 -0.4064)
			(stroke
				(width 0.1524)
				(type default)
			)
			(layer "F.SilkS")
		)
		(fp_line
			(start -0.7874 0.4064)
			(end -0.7874 -0.4064)
			(stroke
				(width 0.1524)
				(type default)
			)
			(layer "F.SilkS")
		)
		(fp_line
			(start 0.7874 -0.4064)
			(end 0.7874 0.4064)
			(stroke
				(width 0.1524)
				(type default)
			)
			(layer "F.SilkS")
		)
		(fp_line
			(start 0.7874 0.4064)
			(end -0.7874 0.4064)
			(stroke
				(width 0.1524)
				(type default)
			)
			(layer "F.SilkS")
		)
		(fp_line
			(start -0.67945 -0.305054)
			(end -0.12065 -0.305054)
			(stroke
				(width 0.1)
				(type default)
			)
			(layer "F.Fab")
		)
		(fp_line
			(start -0.67945 0.3048)
			(end -0.67945 -0.305054)
			(stroke
				(width 0.1)
				(type default)
			)
			(layer "F.Fab")
		)
		(fp_line
			(start -0.12065 -0.305054)
			(end -0.12065 -0.2794)
			(stroke
				(width 0.1)
				(type default)
			)
			(layer "F.Fab")
		)
		(fp_line
			(start -0.12065 -0.2794)
			(end 0.12065 -0.2794)
			(stroke
				(width 0.1)
				(type default)
			)
			(layer "F.Fab")
		)
		(fp_line
			(start -0.12065 0.2794)
			(end -0.12065 0.3048)
			(stroke
				(width 0.1)
				(type default)
			)
			(layer "F.Fab")
		)
		(fp_line
			(start -0.12065 0.3048)
			(end -0.67945 0.3048)
			(stroke
				(width 0.1)
				(type default)
			)
			(layer "F.Fab")
		)
		(fp_line
			(start 0.120396 0.2794)
			(end -0.12065 0.2794)
			(stroke
				(width 0.1)
				(type default)
			)
			(layer "F.Fab")
		)
		(fp_line
			(start 0.120396 0.3048)
			(end 0.120396 0.2794)
			(stroke
				(width 0.1)
				(type default)
			)
			(layer "F.Fab")
		)
		(fp_line
			(start 0.12065 -0.3048)
			(end 0.67945 -0.3048)
			(stroke
				(width 0.1)
				(type default)
			)
			(layer "F.Fab")
		)
		(fp_line
			(start 0.12065 -0.2794)
			(end 0.12065 -0.3048)
			(stroke
				(width 0.1)
				(type default)
			)
			(layer "F.Fab")
		)
		(fp_line
			(start 0.67945 -0.3048)
			(end 0.67945 0.3048)
			(stroke
				(width 0.1)
				(type default)
			)
			(layer "F.Fab")
		)
		(fp_line
			(start 0.67945 0.3048)
			(end 0.120396 0.3048)
			(stroke
				(width 0.1)
				(type default)
			)
			(layer "F.Fab")
		)
		(pad "1" smd circle
			(at -0.40005 0)
			(size 0 0)
			(layers "F.Cu" "F.Mask" "F.Paste")
			(net "SMB_LM75_3_3V3AUX_SCL_R")
		)
		(pad "2" smd circle
			(at 0.40005 0)
			(size 0 0)
			(layers "F.Cu" "F.Mask" "F.Paste")
			(net "SMB_LM75_3_3V3AUX_SCL")
		)
	)
	(footprint ""
		(layer "F.Cu")
		(at 214.43188 -50.637948 90)
		(property "Reference" "R3754"
			(at 0 0 90)
			(layer "F.SilkS")
			(hide yes)
			(effects
				(font
					(size 1.27 1.27)
				)
			)
		)
		(property "Value" ""
			(at 0 0 90)
			(layer "F.Fab")
			(effects
				(font
					(size 1.27 1.27)
				)
			)
		)
		(duplicate_pad_numbers_are_jumpers no)
		(fp_line
			(start 0.7874 -0.4064)
			(end 0.7874 0.4064)
			(stroke
				(width 0.1524)
				(type default)
			)
			(layer "F.SilkS")
		)
		(fp_line
			(start -0.7874 -0.4064)
			(end 0.7874 -0.4064)
			(stroke
				(width 0.1524)
				(type default)
			)
			(layer "F.SilkS")
		)
		(fp_line
			(start 0.7874 0.4064)
			(end -0.7874 0.4064)
			(stroke
				(width 0.1524)
				(type default)
			)
			(layer "F.SilkS")
		)
		(fp_line
			(start -0.7874 0.4064)
			(end -0.7874 -0.4064)
			(stroke
				(width 0.1524)
				(type default)
			)
			(layer "F.SilkS")
		)
		(fp_line
			(start -0.12065 -0.305054)
			(end -0.12065 -0.2794)
			(stroke
				(width 0.1)
				(type default)
			)
			(layer "F.Fab")
		)
		(fp_line
			(start -0.67945 -0.305054)
			(end -0.12065 -0.305054)
			(stroke
				(width 0.1)
				(type default)
			)
			(layer "F.Fab")
		)
		(fp_line
			(start 0.67945 -0.3048)
			(end 0.67945 0.3048)
			(stroke
				(width 0.1)
				(type default)
			)
			(layer "F.Fab")
		)
		(fp_line
			(start 0.12065 -0.3048)
			(end 0.67945 -0.3048)
			(stroke
				(width 0.1)
				(type default)
			)
			(layer "F.Fab")
		)
		(fp_line
			(start 0.12065 -0.2794)
			(end 0.12065 -0.3048)
			(stroke
				(width 0.1)
				(type default)
			)
			(layer "F.Fab")
		)
		(fp_line
			(start -0.12065 -0.2794)
			(end 0.12065 -0.2794)
			(stroke
				(width 0.1)
				(type default)
			)
			(layer "F.Fab")
		)
		(fp_line
			(start 0.120396 0.2794)
			(end -0.12065 0.2794)
			(stroke
				(width 0.1)
				(type default)
			)
			(layer "F.Fab")
		)
		(fp_line
			(start -0.12065 0.2794)
			(end -0.12065 0.3048)
			(stroke
				(width 0.1)
				(type default)
			)
			(layer "F.Fab")
		)
		(fp_line
			(start 0.67945 0.3048)
			(end 0.120396 0.3048)
			(stroke
				(width 0.1)
				(type default)
			)
			(layer "F.Fab")
		)
		(fp_line
			(start 0.120396 0.3048)
			(end 0.120396 0.2794)
			(stroke
				(width 0.1)
				(type default)
			)
			(layer "F.Fab")
		)
		(fp_line
			(start -0.12065 0.3048)
			(end -0.67945 0.3048)
			(stroke
				(width 0.1)
				(type default)
			)
			(layer "F.Fab")
		)
		(fp_line
			(start -0.67945 0.3048)
			(end -0.67945 -0.305054)
			(stroke
				(width 0.1)
				(type default)
			)
			(layer "F.Fab")
		)
		(pad "1" smd circle
			(at -0.40005 0 90)
			(size 0 0)
			(layers "F.Cu" "F.Mask" "F.Paste")
			(net "SMB_INA230_2_3V3AUX_SCL_R")
		)
		(pad "2" smd circle
			(at 0.40005 0 90)
			(size 0 0)
			(layers "F.Cu" "F.Mask" "F.Paste")
			(net "SMB_INA230_2_3V3AUX_SCL_R1")
		)
	)
	(footprint ""
		(layer "F.Cu")
		(at 185.59272 -418.06876 90)
		(property "Reference" "R4797"
			(at 0 0 90)
			(layer "F.SilkS")
			(hide yes)
			(effects
				(font
					(size 1.27 1.27)
				)
			)
		)
		(property "Value" ""
			(at 0 0 90)
			(layer "F.Fab")
			(effects
				(font
					(size 1.27 1.27)
				)
			)
		)
		(duplicate_pad_numbers_are_jumpers no)
		(fp_line
			(start 0.7874 -0.4064)
			(end 0.7874 0.4064)
			(stroke
				(width 0.1524)
				(type default)
			)
			(layer "F.SilkS")
		)
		(fp_line
			(start -0.7874 -0.4064)
			(end 0.7874 -0.4064)
			(stroke
				(width 0.1524)
				(type default)
			)
			(layer "F.SilkS")
		)
		(fp_line
			(start 0.7874 0.4064)
			(end -0.7874 0.4064)
			(stroke
				(width 0.1524)
				(type default)
			)
			(layer "F.SilkS")
		)
		(fp_line
			(start -0.7874 0.4064)
			(end -0.7874 -0.4064)
			(stroke
				(width 0.1524)
				(type default)
			)
			(layer "F.SilkS")
		)
		(fp_line
			(start -0.12065 -0.305054)
			(end -0.12065 -0.2794)
			(stroke
				(width 0.1)
				(type default)
			)
			(layer "F.Fab")
		)
		(fp_line
			(start -0.67945 -0.305054)
			(end -0.12065 -0.305054)
			(stroke
				(width 0.1)
				(type default)
			)
			(layer "F.Fab")
		)
		(fp_line
			(start 0.67945 -0.3048)
			(end 0.67945 0.3048)
			(stroke
				(width 0.1)
				(type default)
			)
			(layer "F.Fab")
		)
		(fp_line
			(start 0.12065 -0.3048)
			(end 0.67945 -0.3048)
			(stroke
				(width 0.1)
				(type default)
			)
			(layer "F.Fab")
		)
		(fp_line
			(start 0.12065 -0.2794)
			(end 0.12065 -0.3048)
			(stroke
				(width 0.1)
				(type default)
			)
			(layer "F.Fab")
		)
		(fp_line
			(start -0.12065 -0.2794)
			(end 0.12065 -0.2794)
			(stroke
				(width 0.1)
				(type default)
			)
			(layer "F.Fab")
		)
		(fp_line
			(start 0.120396 0.2794)
			(end -0.12065 0.2794)
			(stroke
				(width 0.1)
				(type default)
			)
			(layer "F.Fab")
		)
		(fp_line
			(start -0.12065 0.2794)
			(end -0.12065 0.3048)
			(stroke
				(width 0.1)
				(type default)
			)
			(layer "F.Fab")
		)
		(fp_line
			(start 0.67945 0.3048)
			(end 0.120396 0.3048)
			(stroke
				(width 0.1)
				(type default)
			)
			(layer "F.Fab")
		)
		(fp_line
			(start 0.120396 0.3048)
			(end 0.120396 0.2794)
			(stroke
				(width 0.1)
				(type default)
			)
			(layer "F.Fab")
		)
		(fp_line
			(start -0.12065 0.3048)
			(end -0.67945 0.3048)
			(stroke
				(width 0.1)
				(type default)
			)
			(layer "F.Fab")
		)
		(fp_line
			(start -0.67945 0.3048)
			(end -0.67945 -0.305054)
			(stroke
				(width 0.1)
				(type default)
			)
			(layer "F.Fab")
		)
		(pad "1" smd circle
			(at -0.40005 0 90)
			(size 0 0)
			(layers "F.Cu" "F.Mask" "F.Paste")
			(net "P3V3_AUX")
		)
		(pad "2" smd circle
			(at 0.40005 0 90)
			(size 0 0)
			(layers "F.Cu" "F.Mask" "F.Paste")
			(net "A_HSC_LOW_GATE")
		)
	)
	(footprint ""
		(layer "F.Cu")
		(at 277.9014 -398.78 90)
		(property "Reference" "PPQ9"
			(at -8.190992 -2.0828 0)
			(unlocked yes)
			(layer "F.SilkS")
			(effects
				(font
					(size 0.7874 0.5842)
					(thickness 0.1524)
				)
				(justify left)
			)
		)
		(property "Value" ""
			(at 0 0 90)
			(layer "F.Fab")
			(effects
				(font
					(size 1.27 1.27)
				)
			)
		)
		(duplicate_pad_numbers_are_jumpers no)
		(fp_line
			(start 2.350008 -2.649982)
			(end 2.350008 -2.4892)
			(stroke
				(width 0.1524)
				(type default)
			)
			(layer "F.SilkS")
		)
		(fp_line
			(start -2.350008 -2.649982)
			(end 2.350008 -2.649982)
			(stroke
				(width 0.1524)
				(type default)
			)
			(layer "F.SilkS")
		)
		(fp_line
			(start -2.350008 -2.4384)
			(end -2.350008 -2.649982)
			(stroke
				(width 0.1524)
				(type default)
			)
			(layer "F.SilkS")
		)
		(fp_line
			(start 2.350008 2.4892)
			(end 2.350008 2.649982)
			(stroke
				(width 0.1524)
				(type default)
			)
			(layer "F.SilkS")
		)
		(fp_line
			(start 2.350008 2.649982)
			(end -2.350008 2.649982)
			(stroke
				(width 0.1524)
				(type default)
			)
			(layer "F.SilkS")
		)
		(fp_line
			(start -2.350008 2.649982)
			(end -2.350008 2.413)
			(stroke
				(width 0.1524)
				(type default)
			)
			(layer "F.SilkS")
		)
		(fp_poly
			(pts
				(xy -3.717544 -1.905) (xy -4.758944 -2.3241) (xy -4.758944 -1.524)
			)
			(stroke
				(width 0)
				(type default)
			)
			(fill yes)
			(layer "F.SilkS")
		)
		(fp_line
			(start 2.350008 -2.649982)
			(end 2.350008 2.649982)
			(stroke
				(width 0.1)
				(type default)
			)
			(layer "F.Fab")
		)
		(fp_line
			(start -2.350008 -2.649982)
			(end 2.350008 -2.649982)
			(stroke
				(width 0.1)
				(type default)
			)
			(layer "F.Fab")
		)
		(fp_line
			(start 2.350008 2.649982)
			(end -2.350008 2.649982)
			(stroke
				(width 0.1)
				(type default)
			)
			(layer "F.Fab")
		)
		(fp_line
			(start -2.350008 2.649982)
			(end -2.350008 -2.649982)
			(stroke
				(width 0.1)
				(type default)
			)
			(layer "F.Fab")
		)
		(fp_poly
			(pts
				(xy -3.717544 -1.905) (xy -4.758944 -2.3241) (xy -4.758944 -1.524)
			)
			(stroke
				(width 0)
				(type default)
			)
			(fill yes)
			(layer "F.Fab")
		)
		(pad "1" smd rect
			(at -2.999994 -1.905)
			(size 0.7112 1.1684)
			(layers "F.Cu" "F.Mask" "F.Paste")
			(net "P12V_AUX")
		)
		(pad "2" smd rect
			(at -2.999994 -0.635)
			(size 0.7112 1.1684)
			(layers "F.Cu" "F.Mask" "F.Paste")
			(net "P12V_AUX")
		)
		(pad "3" smd rect
			(at -2.999994 0.635)
			(size 0.7112 1.1684)
			(layers "F.Cu" "F.Mask" "F.Paste")
			(net "P12V_AUX")
		)
		(pad "4" smd rect
			(at -2.999994 1.905)
			(size 0.7112 1.1684)
			(layers "F.Cu" "F.Mask" "F.Paste")
			(net "MB0_CM_GATE_G0")
		)
		(pad "5" smd circle
			(at 0.925068 0)
			(size 0 0)
			(layers "F.Cu" "F.Mask" "F.Paste")
			(net "P12V_MAIN_R_0")
		)
		(zone
			(layer "F.Cu")
			(hatch none 0.5)
			(connect_pads
				(clearance 0)
			)
			(min_thickness 0.25)
			(keepout
				(tracks not_allowed)
				(vias allowed)
				(pads allowed)
				(copperpour not_allowed)
				(footprints allowed)
			)
			(placement
				(enabled no)
				(sheetname "")
			)
			(fill
				(thermal_gap 0.5)
				(thermal_bridge_width 0.5)
				(island_removal_mode 0)
			)
			(polygon
				(pts
					(xy 275.7424 -397.3322) (xy 280.0604 -397.3322) (xy 280.543 -397.3322) (xy 280.543 -396.4305) (xy 275.2598 -396.4305)
					(xy 275.2598 -397.3322)
				)
			)
		)
	)
	(footprint ""
		(layer "F.Cu")
		(at 223.868488 -232.77957 90)
		(property "Reference" "C570"
			(at 0 0 90)
			(layer "F.SilkS")
			(hide yes)
			(effects
				(font
					(size 1.27 1.27)
				)
			)
		)
		(property "Value" ""
			(at 0 0 90)
			(layer "F.Fab")
			(effects
				(font
					(size 1.27 1.27)
				)
			)
		)
		(duplicate_pad_numbers_are_jumpers no)
		(fp_line
			(start 0.7874 -0.4064)
			(end 0.7874 0.4064)
			(stroke
				(width 0.1524)
				(type default)
			)
			(layer "F.SilkS")
		)
		(fp_line
			(start -0.7874 -0.4064)
			(end 0.7874 -0.4064)
			(stroke
				(width 0.1524)
				(type default)
			)
			(layer "F.SilkS")
		)
		(fp_line
			(start 0.7874 0.4064)
			(end -0.7874 0.4064)
			(stroke
				(width 0.1524)
				(type default)
			)
			(layer "F.SilkS")
		)
		(fp_line
			(start -0.7874 0.4064)
			(end -0.7874 -0.4064)
			(stroke
				(width 0.1524)
				(type default)
			)
			(layer "F.SilkS")
		)
		(fp_line
			(start -0.12065 -0.305054)
			(end -0.12065 -0.2794)
			(stroke
				(width 0.1)
				(type default)
			)
			(layer "F.Fab")
		)
		(fp_line
			(start -0.67945 -0.305054)
			(end -0.12065 -0.305054)
			(stroke
				(width 0.1)
				(type default)
			)
			(layer "F.Fab")
		)
		(fp_line
			(start 0.67945 -0.3048)
			(end 0.67945 0.3048)
			(stroke
				(width 0.1)
				(type default)
			)
			(layer "F.Fab")
		)
		(fp_line
			(start 0.12065 -0.3048)
			(end 0.67945 -0.3048)
			(stroke
				(width 0.1)
				(type default)
			)
			(layer "F.Fab")
		)
		(fp_line
			(start 0.12065 -0.2794)
			(end 0.12065 -0.3048)
			(stroke
				(width 0.1)
				(type default)
			)
			(layer "F.Fab")
		)
		(fp_line
			(start -0.12065 -0.2794)
			(end 0.12065 -0.2794)
			(stroke
				(width 0.1)
				(type default)
			)
			(layer "F.Fab")
		)
		(fp_line
			(start 0.120396 0.2794)
			(end -0.12065 0.2794)
			(stroke
				(width 0.1)
				(type default)
			)
			(layer "F.Fab")
		)
		(fp_line
			(start -0.12065 0.2794)
			(end -0.12065 0.3048)
			(stroke
				(width 0.1)
				(type default)
			)
			(layer "F.Fab")
		)
		(fp_line
			(start 0.67945 0.3048)
			(end 0.120396 0.3048)
			(stroke
				(width 0.1)
				(type default)
			)
			(layer "F.Fab")
		)
		(fp_line
			(start 0.120396 0.3048)
			(end 0.120396 0.2794)
			(stroke
				(width 0.1)
				(type default)
			)
			(layer "F.Fab")
		)
		(fp_line
			(start -0.12065 0.3048)
			(end -0.67945 0.3048)
			(stroke
				(width 0.1)
				(type default)
			)
			(layer "F.Fab")
		)
		(fp_line
			(start -0.67945 0.3048)
			(end -0.67945 -0.305054)
			(stroke
				(width 0.1)
				(type default)
			)
			(layer "F.Fab")
		)
		(pad "1" smd circle
			(at -0.40005 0 90)
			(size 0 0)
			(layers "F.Cu" "F.Mask" "F.Paste")
			(net "P3V3_AUX")
		)
		(pad "2" smd circle
			(at 0.40005 0 90)
			(size 0 0)
			(layers "F.Cu" "F.Mask" "F.Paste")
			(net "GND")
		)
	)
	(footprint ""
		(layer "F.Cu")
		(at 374.336056 -352.812858)
		(property "Reference" "PC1247"
			(at 0 0 0)
			(layer "F.SilkS")
			(hide yes)
			(effects
				(font
					(size 1.27 1.27)
				)
			)
		)
		(property "Value" ""
			(at 0 0 0)
			(layer "F.Fab")
			(effects
				(font
					(size 1.27 1.27)
				)
			)
		)
		(duplicate_pad_numbers_are_jumpers no)
		(fp_line
			(start -1.524 -0.762)
			(end 1.524 -0.762)
			(stroke
				(width 0.1524)
				(type default)
			)
			(layer "F.SilkS")
		)
		(fp_line
			(start -1.524 0.762)
			(end -1.524 -0.762)
			(stroke
				(width 0.1524)
				(type default)
			)
			(layer "F.SilkS")
		)
		(fp_line
			(start 1.524 -0.762)
			(end 1.524 0.762)
			(stroke
				(width 0.1524)
				(type default)
			)
			(layer "F.SilkS")
		)
		(fp_line
			(start 1.524 0.762)
			(end -1.524 0.762)
			(stroke
				(width 0.1524)
				(type default)
			)
			(layer "F.SilkS")
		)
		(fp_line
			(start -1.1049 -0.724916)
			(end -1.1049 0.724916)
			(stroke
				(width 0.1)
				(type default)
			)
			(layer "F.Fab")
		)
		(fp_line
			(start -1.1049 0.724916)
			(end 1.1049 0.724916)
			(stroke
				(width 0.1)
				(type default)
			)
			(layer "F.Fab")
		)
		(fp_line
			(start 1.1049 -0.724916)
			(end -1.1049 -0.724916)
			(stroke
				(width 0.1)
				(type default)
			)
			(layer "F.Fab")
		)
		(fp_line
			(start 1.1049 0.724916)
			(end 1.1049 -0.724916)
			(stroke
				(width 0.1)
				(type default)
			)
			(layer "F.Fab")
		)
		(pad "1" smd rect
			(at -0.889 0 180)
			(size 1.016 1.27)
			(layers "F.Cu" "F.Mask" "F.Paste")
			(net "SW_P12V_PVCCIN_CPU0_FLT")
		)
		(pad "2" smd rect
			(at 0.889 0 180)
			(size 1.016 1.27)
			(layers "F.Cu" "F.Mask" "F.Paste")
			(net "GND")
		)
	)
	(footprint ""
		(layer "F.Cu")
		(at 354.93071 -338.180172 -90)
		(property "Reference" "PC300"
			(at 0 0 270)
			(layer "F.SilkS")
			(hide yes)
			(effects
				(font
					(size 1.27 1.27)
				)
			)
		)
		(property "Value" ""
			(at 0 0 270)
			(layer "F.Fab")
			(effects
				(font
					(size 1.27 1.27)
				)
			)
		)
		(duplicate_pad_numbers_are_jumpers no)
		(fp_line
			(start -0.7874 0.4064)
			(end -0.7874 -0.4064)
			(stroke
				(width 0.1524)
				(type default)
			)
			(layer "F.SilkS")
		)
		(fp_line
			(start 0.7874 0.4064)
			(end -0.7874 0.4064)
			(stroke
				(width 0.1524)
				(type default)
			)
			(layer "F.SilkS")
		)
		(fp_line
			(start -0.7874 -0.4064)
			(end 0.7874 -0.4064)
			(stroke
				(width 0.1524)
				(type default)
			)
			(layer "F.SilkS")
		)
		(fp_line
			(start 0.7874 -0.4064)
			(end 0.7874 0.4064)
			(stroke
				(width 0.1524)
				(type default)
			)
			(layer "F.SilkS")
		)
		(fp_line
			(start -0.67945 0.3048)
			(end -0.67945 -0.305054)
			(stroke
				(width 0.1)
				(type default)
			)
			(layer "F.Fab")
		)
		(fp_line
			(start -0.12065 0.3048)
			(end -0.67945 0.3048)
			(stroke
				(width 0.1)
				(type default)
			)
			(layer "F.Fab")
		)
		(fp_line
			(start 0.120396 0.3048)
			(end 0.120396 0.2794)
			(stroke
				(width 0.1)
				(type default)
			)
			(layer "F.Fab")
		)
		(fp_line
			(start 0.67945 0.3048)
			(end 0.120396 0.3048)
			(stroke
				(width 0.1)
				(type default)
			)
			(layer "F.Fab")
		)
		(fp_line
			(start -0.12065 0.2794)
			(end -0.12065 0.3048)
			(stroke
				(width 0.1)
				(type default)
			)
			(layer "F.Fab")
		)
		(fp_line
			(start 0.120396 0.2794)
			(end -0.12065 0.2794)
			(stroke
				(width 0.1)
				(type default)
			)
			(layer "F.Fab")
		)
		(fp_line
			(start -0.12065 -0.2794)
			(end 0.12065 -0.2794)
			(stroke
				(width 0.1)
				(type default)
			)
			(layer "F.Fab")
		)
		(fp_line
			(start 0.12065 -0.2794)
			(end 0.12065 -0.3048)
			(stroke
				(width 0.1)
				(type default)
			)
			(layer "F.Fab")
		)
		(fp_line
			(start 0.12065 -0.3048)
			(end 0.67945 -0.3048)
			(stroke
				(width 0.1)
				(type default)
			)
			(layer "F.Fab")
		)
		(fp_line
			(start 0.67945 -0.3048)
			(end 0.67945 0.3048)
			(stroke
				(width 0.1)
				(type default)
			)
			(layer "F.Fab")
		)
		(fp_line
			(start -0.67945 -0.305054)
			(end -0.12065 -0.305054)
			(stroke
				(width 0.1)
				(type default)
			)
			(layer "F.Fab")
		)
		(fp_line
			(start -0.12065 -0.305054)
			(end -0.12065 -0.2794)
			(stroke
				(width 0.1)
				(type default)
			)
			(layer "F.Fab")
		)
		(pad "1" smd circle
			(at -0.40005 0 270)
			(size 0 0)
			(layers "F.Cu" "F.Mask" "F.Paste")
			(net "SW_PVCCIN_CPU0_BOOT2_R")
		)
		(pad "2" smd circle
			(at 0.40005 0 270)
			(size 0 0)
			(layers "F.Cu" "F.Mask" "F.Paste")
			(net "SW_PVCCIN_CPU0_BOOTR2")
		)
	)
	(footprint ""
		(layer "F.Cu")
		(at 29.13888 -427.192948 -90)
		(property "Reference" "C1957"
			(at 0 0 270)
			(layer "F.SilkS")
			(hide yes)
			(effects
				(font
					(size 1.27 1.27)
				)
			)
		)
		(property "Value" ""
			(at 0 0 270)
			(layer "F.Fab")
			(effects
				(font
					(size 1.27 1.27)
				)
			)
		)
		(duplicate_pad_numbers_are_jumpers no)
		(fp_line
			(start -0.7874 0.4064)
			(end -0.7874 -0.4064)
			(stroke
				(width 0.1524)
				(type default)
			)
			(layer "F.SilkS")
		)
		(fp_line
			(start 0.7874 0.4064)
			(end -0.7874 0.4064)
			(stroke
				(width 0.1524)
				(type default)
			)
			(layer "F.SilkS")
		)
		(fp_line
			(start -0.7874 -0.4064)
			(end 0.7874 -0.4064)
			(stroke
				(width 0.1524)
				(type default)
			)
			(layer "F.SilkS")
		)
		(fp_line
			(start 0.7874 -0.4064)
			(end 0.7874 0.4064)
			(stroke
				(width 0.1524)
				(type default)
			)
			(layer "F.SilkS")
		)
		(fp_line
			(start -0.67945 0.3048)
			(end -0.67945 -0.305054)
			(stroke
				(width 0.1)
				(type default)
			)
			(layer "F.Fab")
		)
		(fp_line
			(start -0.12065 0.3048)
			(end -0.67945 0.3048)
			(stroke
				(width 0.1)
				(type default)
			)
			(layer "F.Fab")
		)
		(fp_line
			(start 0.120396 0.3048)
			(end 0.120396 0.2794)
			(stroke
				(width 0.1)
				(type default)
			)
			(layer "F.Fab")
		)
		(fp_line
			(start 0.67945 0.3048)
			(end 0.120396 0.3048)
			(stroke
				(width 0.1)
				(type default)
			)
			(layer "F.Fab")
		)
		(fp_line
			(start -0.12065 0.2794)
			(end -0.12065 0.3048)
			(stroke
				(width 0.1)
				(type default)
			)
			(layer "F.Fab")
		)
		(fp_line
			(start 0.120396 0.2794)
			(end -0.12065 0.2794)
			(stroke
				(width 0.1)
				(type default)
			)
			(layer "F.Fab")
		)
		(fp_line
			(start -0.12065 -0.2794)
			(end 0.12065 -0.2794)
			(stroke
				(width 0.1)
				(type default)
			)
			(layer "F.Fab")
		)
		(fp_line
			(start 0.12065 -0.2794)
			(end 0.12065 -0.3048)
			(stroke
				(width 0.1)
				(type default)
			)
			(layer "F.Fab")
		)
		(fp_line
			(start 0.12065 -0.3048)
			(end 0.67945 -0.3048)
			(stroke
				(width 0.1)
				(type default)
			)
			(layer "F.Fab")
		)
		(fp_line
			(start 0.67945 -0.3048)
			(end 0.67945 0.3048)
			(stroke
				(width 0.1)
				(type default)
			)
			(layer "F.Fab")
		)
		(fp_line
			(start -0.67945 -0.305054)
			(end -0.12065 -0.305054)
			(stroke
				(width 0.1)
				(type default)
			)
			(layer "F.Fab")
		)
		(fp_line
			(start -0.12065 -0.305054)
			(end -0.12065 -0.2794)
			(stroke
				(width 0.1)
				(type default)
			)
			(layer "F.Fab")
		)
		(pad "1" smd circle
			(at -0.40005 0 270)
			(size 0 0)
			(layers "F.Cu" "F.Mask" "F.Paste")
			(net "P3V3_AUX")
		)
		(pad "2" smd circle
			(at 0.40005 0 270)
			(size 0 0)
			(layers "F.Cu" "F.Mask" "F.Paste")
			(net "GND")
		)
	)
	(footprint ""
		(layer "F.Cu")
		(at 249.643646 -70.204076)
		(property "Reference" "PC1650"
			(at 0 0 0)
			(layer "F.SilkS")
			(hide yes)
			(effects
				(font
					(size 1.27 1.27)
				)
			)
		)
		(property "Value" ""
			(at 0 0 0)
			(layer "F.Fab")
			(effects
				(font
					(size 1.27 1.27)
				)
			)
		)
		(duplicate_pad_numbers_are_jumpers no)
		(fp_line
			(start -0.7874 -0.4064)
			(end 0.7874 -0.4064)
			(stroke
				(width 0.1524)
				(type default)
			)
			(layer "F.SilkS")
		)
		(fp_line
			(start -0.7874 0.4064)
			(end -0.7874 -0.4064)
			(stroke
				(width 0.1524)
				(type default)
			)
			(layer "F.SilkS")
		)
		(fp_line
			(start 0.7874 -0.4064)
			(end 0.7874 0.4064)
			(stroke
				(width 0.1524)
				(type default)
			)
			(layer "F.SilkS")
		)
		(fp_line
			(start 0.7874 0.4064)
			(end -0.7874 0.4064)
			(stroke
				(width 0.1524)
				(type default)
			)
			(layer "F.SilkS")
		)
		(fp_line
			(start -0.67945 -0.305054)
			(end -0.12065 -0.305054)
			(stroke
				(width 0.1)
				(type default)
			)
			(layer "F.Fab")
		)
		(fp_line
			(start -0.67945 0.3048)
			(end -0.67945 -0.305054)
			(stroke
				(width 0.1)
				(type default)
			)
			(layer "F.Fab")
		)
		(fp_line
			(start -0.12065 -0.305054)
			(end -0.12065 -0.2794)
			(stroke
				(width 0.1)
				(type default)
			)
			(layer "F.Fab")
		)
		(fp_line
			(start -0.12065 -0.2794)
			(end 0.12065 -0.2794)
			(stroke
				(width 0.1)
				(type default)
			)
			(layer "F.Fab")
		)
		(fp_line
			(start -0.12065 0.2794)
			(end -0.12065 0.3048)
			(stroke
				(width 0.1)
				(type default)
			)
			(layer "F.Fab")
		)
		(fp_line
			(start -0.12065 0.3048)
			(end -0.67945 0.3048)
			(stroke
				(width 0.1)
				(type default)
			)
			(layer "F.Fab")
		)
		(fp_line
			(start 0.120396 0.2794)
			(end -0.12065 0.2794)
			(stroke
				(width 0.1)
				(type default)
			)
			(layer "F.Fab")
		)
		(fp_line
			(start 0.120396 0.3048)
			(end 0.120396 0.2794)
			(stroke
				(width 0.1)
				(type default)
			)
			(layer "F.Fab")
		)
		(fp_line
			(start 0.12065 -0.3048)
			(end 0.67945 -0.3048)
			(stroke
				(width 0.1)
				(type default)
			)
			(layer "F.Fab")
		)
		(fp_line
			(start 0.12065 -0.2794)
			(end 0.12065 -0.3048)
			(stroke
				(width 0.1)
				(type default)
			)
			(layer "F.Fab")
		)
		(fp_line
			(start 0.67945 -0.3048)
			(end 0.67945 0.3048)
			(stroke
				(width 0.1)
				(type default)
			)
			(layer "F.Fab")
		)
		(fp_line
			(start 0.67945 0.3048)
			(end 0.120396 0.3048)
			(stroke
				(width 0.1)
				(type default)
			)
			(layer "F.Fab")
		)
		(pad "1" smd circle
			(at -0.40005 0)
			(size 0 0)
			(layers "F.Cu" "F.Mask" "F.Paste")
			(net "P12V_AUX")
		)
		(pad "2" smd circle
			(at 0.40005 0)
			(size 0 0)
			(layers "F.Cu" "F.Mask" "F.Paste")
			(net "GND")
		)
	)
	(footprint ""
		(layer "F.Cu")
		(at 442.828172 -33.062418 90)
		(property "Reference" "PR3835"
			(at 0 0 90)
			(layer "F.SilkS")
			(hide yes)
			(effects
				(font
					(size 1.27 1.27)
				)
			)
		)
		(property "Value" ""
			(at 0 0 90)
			(layer "F.Fab")
			(effects
				(font
					(size 1.27 1.27)
				)
			)
		)
		(duplicate_pad_numbers_are_jumpers no)
		(fp_line
			(start 0.7874 -0.4064)
			(end 0.7874 0.4064)
			(stroke
				(width 0.1524)
				(type default)
			)
			(layer "F.SilkS")
		)
		(fp_line
			(start -0.7874 -0.4064)
			(end 0.7874 -0.4064)
			(stroke
				(width 0.1524)
				(type default)
			)
			(layer "F.SilkS")
		)
		(fp_line
			(start 0.7874 0.4064)
			(end -0.7874 0.4064)
			(stroke
				(width 0.1524)
				(type default)
			)
			(layer "F.SilkS")
		)
		(fp_line
			(start -0.7874 0.4064)
			(end -0.7874 -0.4064)
			(stroke
				(width 0.1524)
				(type default)
			)
			(layer "F.SilkS")
		)
		(fp_line
			(start -0.12065 -0.305054)
			(end -0.12065 -0.2794)
			(stroke
				(width 0.1)
				(type default)
			)
			(layer "F.Fab")
		)
		(fp_line
			(start -0.67945 -0.305054)
			(end -0.12065 -0.305054)
			(stroke
				(width 0.1)
				(type default)
			)
			(layer "F.Fab")
		)
		(fp_line
			(start 0.67945 -0.3048)
			(end 0.67945 0.3048)
			(stroke
				(width 0.1)
				(type default)
			)
			(layer "F.Fab")
		)
		(fp_line
			(start 0.12065 -0.3048)
			(end 0.67945 -0.3048)
			(stroke
				(width 0.1)
				(type default)
			)
			(layer "F.Fab")
		)
		(fp_line
			(start 0.12065 -0.2794)
			(end 0.12065 -0.3048)
			(stroke
				(width 0.1)
				(type default)
			)
			(layer "F.Fab")
		)
		(fp_line
			(start -0.12065 -0.2794)
			(end 0.12065 -0.2794)
			(stroke
				(width 0.1)
				(type default)
			)
			(layer "F.Fab")
		)
		(fp_line
			(start 0.120396 0.2794)
			(end -0.12065 0.2794)
			(stroke
				(width 0.1)
				(type default)
			)
			(layer "F.Fab")
		)
		(fp_line
			(start -0.12065 0.2794)
			(end -0.12065 0.3048)
			(stroke
				(width 0.1)
				(type default)
			)
			(layer "F.Fab")
		)
		(fp_line
			(start 0.67945 0.3048)
			(end 0.120396 0.3048)
			(stroke
				(width 0.1)
				(type default)
			)
			(layer "F.Fab")
		)
		(fp_line
			(start 0.120396 0.3048)
			(end 0.120396 0.2794)
			(stroke
				(width 0.1)
				(type default)
			)
			(layer "F.Fab")
		)
		(fp_line
			(start -0.12065 0.3048)
			(end -0.67945 0.3048)
			(stroke
				(width 0.1)
				(type default)
			)
			(layer "F.Fab")
		)
		(fp_line
			(start -0.67945 0.3048)
			(end -0.67945 -0.305054)
			(stroke
				(width 0.1)
				(type default)
			)
			(layer "F.Fab")
		)
		(pad "1" smd circle
			(at -0.40005 0 90)
			(size 0 0)
			(layers "F.Cu" "F.Mask" "F.Paste")
			(net "P12V_OCP_ISET_1")
		)
		(pad "2" smd circle
			(at 0.40005 0 90)
			(size 0 0)
			(layers "F.Cu" "F.Mask" "F.Paste")
			(net "GND")
		)
	)
	(footprint ""
		(layer "F.Cu")
		(at 350.790764 -360.934762 -90)
		(property "Reference" "R2365"
			(at 0 0 270)
			(layer "F.SilkS")
			(hide yes)
			(effects
				(font
					(size 1.27 1.27)
				)
			)
		)
		(property "Value" ""
			(at 0 0 270)
			(layer "F.Fab")
			(effects
				(font
					(size 1.27 1.27)
				)
			)
		)
		(duplicate_pad_numbers_are_jumpers no)
		(fp_line
			(start -0.7874 0.4064)
			(end -0.7874 -0.4064)
			(stroke
				(width 0.1524)
				(type default)
			)
			(layer "F.SilkS")
		)
		(fp_line
			(start 0.7874 0.4064)
			(end -0.7874 0.4064)
			(stroke
				(width 0.1524)
				(type default)
			)
			(layer "F.SilkS")
		)
		(fp_line
			(start -0.7874 -0.4064)
			(end 0.7874 -0.4064)
			(stroke
				(width 0.1524)
				(type default)
			)
			(layer "F.SilkS")
		)
		(fp_line
			(start 0.7874 -0.4064)
			(end 0.7874 0.4064)
			(stroke
				(width 0.1524)
				(type default)
			)
			(layer "F.SilkS")
		)
		(fp_line
			(start -0.67945 0.3048)
			(end -0.67945 -0.305054)
			(stroke
				(width 0.1)
				(type default)
			)
			(layer "F.Fab")
		)
		(fp_line
			(start -0.12065 0.3048)
			(end -0.67945 0.3048)
			(stroke
				(width 0.1)
				(type default)
			)
			(layer "F.Fab")
		)
		(fp_line
			(start 0.120396 0.3048)
			(end 0.120396 0.2794)
			(stroke
				(width 0.1)
				(type default)
			)
			(layer "F.Fab")
		)
		(fp_line
			(start 0.67945 0.3048)
			(end 0.120396 0.3048)
			(stroke
				(width 0.1)
				(type default)
			)
			(layer "F.Fab")
		)
		(fp_line
			(start -0.12065 0.2794)
			(end -0.12065 0.3048)
			(stroke
				(width 0.1)
				(type default)
			)
			(layer "F.Fab")
		)
		(fp_line
			(start 0.120396 0.2794)
			(end -0.12065 0.2794)
			(stroke
				(width 0.1)
				(type default)
			)
			(layer "F.Fab")
		)
		(fp_line
			(start -0.12065 -0.2794)
			(end 0.12065 -0.2794)
			(stroke
				(width 0.1)
				(type default)
			)
			(layer "F.Fab")
		)
		(fp_line
			(start 0.12065 -0.2794)
			(end 0.12065 -0.3048)
			(stroke
				(width 0.1)
				(type default)
			)
			(layer "F.Fab")
		)
		(fp_line
			(start 0.12065 -0.3048)
			(end 0.67945 -0.3048)
			(stroke
				(width 0.1)
				(type default)
			)
			(layer "F.Fab")
		)
		(fp_line
			(start 0.67945 -0.3048)
			(end 0.67945 0.3048)
			(stroke
				(width 0.1)
				(type default)
			)
			(layer "F.Fab")
		)
		(fp_line
			(start -0.67945 -0.305054)
			(end -0.12065 -0.305054)
			(stroke
				(width 0.1)
				(type default)
			)
			(layer "F.Fab")
		)
		(fp_line
			(start -0.12065 -0.305054)
			(end -0.12065 -0.2794)
			(stroke
				(width 0.1)
				(type default)
			)
			(layer "F.Fab")
		)
		(pad "1" smd circle
			(at -0.40005 0 270)
			(size 0 0)
			(layers "F.Cu" "F.Mask" "F.Paste")
			(net "P3V3_AUX")
		)
		(pad "2" smd circle
			(at 0.40005 0 270)
			(size 0 0)
			(layers "F.Cu" "F.Mask" "F.Paste")
			(net "PWRGD_PVCCIN_CPU0_R")
		)
	)
	(footprint ""
		(layer "F.Cu")
		(at 365.46663 -255.053846 90)
		(property "Reference" "C1004"
			(at 0 0 90)
			(layer "F.SilkS")
			(hide yes)
			(effects
				(font
					(size 1.27 1.27)
				)
			)
		)
		(property "Value" ""
			(at 0 0 90)
			(layer "F.Fab")
			(effects
				(font
					(size 1.27 1.27)
				)
			)
		)
		(duplicate_pad_numbers_are_jumpers no)
		(fp_line
			(start 0.7874 -0.4064)
			(end 0.7874 0.4064)
			(stroke
				(width 0.1524)
				(type default)
			)
			(layer "F.SilkS")
		)
		(fp_line
			(start -0.7874 -0.4064)
			(end 0.7874 -0.4064)
			(stroke
				(width 0.1524)
				(type default)
			)
			(layer "F.SilkS")
		)
		(fp_line
			(start 0.7874 0.4064)
			(end -0.7874 0.4064)
			(stroke
				(width 0.1524)
				(type default)
			)
			(layer "F.SilkS")
		)
		(fp_line
			(start -0.7874 0.4064)
			(end -0.7874 -0.4064)
			(stroke
				(width 0.1524)
				(type default)
			)
			(layer "F.SilkS")
		)
		(fp_line
			(start -0.12065 -0.305054)
			(end -0.12065 -0.2794)
			(stroke
				(width 0.1)
				(type default)
			)
			(layer "F.Fab")
		)
		(fp_line
			(start -0.67945 -0.305054)
			(end -0.12065 -0.305054)
			(stroke
				(width 0.1)
				(type default)
			)
			(layer "F.Fab")
		)
		(fp_line
			(start 0.67945 -0.3048)
			(end 0.67945 0.3048)
			(stroke
				(width 0.1)
				(type default)
			)
			(layer "F.Fab")
		)
		(fp_line
			(start 0.12065 -0.3048)
			(end 0.67945 -0.3048)
			(stroke
				(width 0.1)
				(type default)
			)
			(layer "F.Fab")
		)
		(fp_line
			(start 0.12065 -0.2794)
			(end 0.12065 -0.3048)
			(stroke
				(width 0.1)
				(type default)
			)
			(layer "F.Fab")
		)
		(fp_line
			(start -0.12065 -0.2794)
			(end 0.12065 -0.2794)
			(stroke
				(width 0.1)
				(type default)
			)
			(layer "F.Fab")
		)
		(fp_line
			(start 0.120396 0.2794)
			(end -0.12065 0.2794)
			(stroke
				(width 0.1)
				(type default)
			)
			(layer "F.Fab")
		)
		(fp_line
			(start -0.12065 0.2794)
			(end -0.12065 0.3048)
			(stroke
				(width 0.1)
				(type default)
			)
			(layer "F.Fab")
		)
		(fp_line
			(start 0.67945 0.3048)
			(end 0.120396 0.3048)
			(stroke
				(width 0.1)
				(type default)
			)
			(layer "F.Fab")
		)
		(fp_line
			(start 0.120396 0.3048)
			(end 0.120396 0.2794)
			(stroke
				(width 0.1)
				(type default)
			)
			(layer "F.Fab")
		)
		(fp_line
			(start -0.12065 0.3048)
			(end -0.67945 0.3048)
			(stroke
				(width 0.1)
				(type default)
			)
			(layer "F.Fab")
		)
		(fp_line
			(start -0.67945 0.3048)
			(end -0.67945 -0.305054)
			(stroke
				(width 0.1)
				(type default)
			)
			(layer "F.Fab")
		)
		(pad "1" smd circle
			(at -0.40005 0 90)
			(size 0 0)
			(layers "F.Cu" "F.Mask" "F.Paste")
			(net "PVCCIN_CPU0")
		)
		(pad "2" smd circle
			(at 0.40005 0 90)
			(size 0 0)
			(layers "F.Cu" "F.Mask" "F.Paste")
			(net "GND")
		)
	)
	(footprint ""
		(layer "F.Cu")
		(at 452.486522 -75.093322)
		(property "Reference" "PR835"
			(at 0 0 0)
			(layer "F.SilkS")
			(hide yes)
			(effects
				(font
					(size 1.27 1.27)
				)
			)
		)
		(property "Value" ""
			(at 0 0 0)
			(layer "F.Fab")
			(effects
				(font
					(size 1.27 1.27)
				)
			)
		)
		(duplicate_pad_numbers_are_jumpers no)
		(fp_line
			(start -0.7874 -0.4064)
			(end 0.7874 -0.4064)
			(stroke
				(width 0.1524)
				(type default)
			)
			(layer "F.SilkS")
		)
		(fp_line
			(start -0.7874 0.4064)
			(end -0.7874 -0.4064)
			(stroke
				(width 0.1524)
				(type default)
			)
			(layer "F.SilkS")
		)
		(fp_line
			(start 0.7874 -0.4064)
			(end 0.7874 0.4064)
			(stroke
				(width 0.1524)
				(type default)
			)
			(layer "F.SilkS")
		)
		(fp_line
			(start 0.7874 0.4064)
			(end -0.7874 0.4064)
			(stroke
				(width 0.1524)
				(type default)
			)
			(layer "F.SilkS")
		)
		(fp_line
			(start -0.67945 -0.305054)
			(end -0.12065 -0.305054)
			(stroke
				(width 0.1)
				(type default)
			)
			(layer "F.Fab")
		)
		(fp_line
			(start -0.67945 0.3048)
			(end -0.67945 -0.305054)
			(stroke
				(width 0.1)
				(type default)
			)
			(layer "F.Fab")
		)
		(fp_line
			(start -0.12065 -0.305054)
			(end -0.12065 -0.2794)
			(stroke
				(width 0.1)
				(type default)
			)
			(layer "F.Fab")
		)
		(fp_line
			(start -0.12065 -0.2794)
			(end 0.12065 -0.2794)
			(stroke
				(width 0.1)
				(type default)
			)
			(layer "F.Fab")
		)
		(fp_line
			(start -0.12065 0.2794)
			(end -0.12065 0.3048)
			(stroke
				(width 0.1)
				(type default)
			)
			(layer "F.Fab")
		)
		(fp_line
			(start -0.12065 0.3048)
			(end -0.67945 0.3048)
			(stroke
				(width 0.1)
				(type default)
			)
			(layer "F.Fab")
		)
		(fp_line
			(start 0.120396 0.2794)
			(end -0.12065 0.2794)
			(stroke
				(width 0.1)
				(type default)
			)
			(layer "F.Fab")
		)
		(fp_line
			(start 0.120396 0.3048)
			(end 0.120396 0.2794)
			(stroke
				(width 0.1)
				(type default)
			)
			(layer "F.Fab")
		)
		(fp_line
			(start 0.12065 -0.3048)
			(end 0.67945 -0.3048)
			(stroke
				(width 0.1)
				(type default)
			)
			(layer "F.Fab")
		)
		(fp_line
			(start 0.12065 -0.2794)
			(end 0.12065 -0.3048)
			(stroke
				(width 0.1)
				(type default)
			)
			(layer "F.Fab")
		)
		(fp_line
			(start 0.67945 -0.3048)
			(end 0.67945 0.3048)
			(stroke
				(width 0.1)
				(type default)
			)
			(layer "F.Fab")
		)
		(fp_line
			(start 0.67945 0.3048)
			(end 0.120396 0.3048)
			(stroke
				(width 0.1)
				(type default)
			)
			(layer "F.Fab")
		)
		(pad "1" smd circle
			(at -0.40005 0)
			(size 0 0)
			(layers "F.Cu" "F.Mask" "F.Paste")
			(net "SW_P3V3_AUX_BOOT")
		)
		(pad "2" smd circle
			(at 0.40005 0)
			(size 0 0)
			(layers "F.Cu" "F.Mask" "F.Paste")
			(net "SW_P3V3_AUX_BOOT_R")
		)
	)
	(footprint ""
		(layer "F.Cu")
		(at 157.802834 -402.371052 -90)
		(property "Reference" "C766"
			(at 0 0 270)
			(layer "F.SilkS")
			(hide yes)
			(effects
				(font
					(size 1.27 1.27)
				)
			)
		)
		(property "Value" ""
			(at 0 0 270)
			(layer "F.Fab")
			(effects
				(font
					(size 1.27 1.27)
				)
			)
		)
		(duplicate_pad_numbers_are_jumpers no)
		(fp_line
			(start -0.299974 0.150114)
			(end -0.299974 -0.150114)
			(stroke
				(width 0.1)
				(type default)
			)
			(layer "F.Fab")
		)
		(fp_line
			(start 0.299974 0.150114)
			(end -0.299974 0.150114)
			(stroke
				(width 0.1)
				(type default)
			)
			(layer "F.Fab")
		)
		(fp_line
			(start -0.299974 -0.150114)
			(end 0.299974 -0.150114)
			(stroke
				(width 0.1)
				(type default)
			)
			(layer "F.Fab")
		)
		(fp_line
			(start 0.299974 -0.150114)
			(end 0.299974 0.150114)
			(stroke
				(width 0.1)
				(type default)
			)
			(layer "F.Fab")
		)
		(pad "1" smd rect
			(at -0.2667 0 270)
			(size 0.3048 0.381)
			(layers "F.Cu" "F.Mask" "F.Paste")
			(net "P5E_CPU1_PE2_TX_C_DN<3>")
		)
		(pad "2" smd rect
			(at 0.2667 0 270)
			(size 0.3048 0.381)
			(layers "F.Cu" "F.Mask" "F.Paste")
			(net "P5E_CPU1_PE2_TX_DN<3>")
		)
	)
	(footprint ""
		(layer "F.Cu")
		(at 235.413042 -245.402608 90)
		(property "Reference" "R4078"
			(at 0 0 90)
			(layer "F.SilkS")
			(hide yes)
			(effects
				(font
					(size 1.27 1.27)
				)
			)
		)
		(property "Value" ""
			(at 0 0 90)
			(layer "F.Fab")
			(effects
				(font
					(size 1.27 1.27)
				)
			)
		)
		(duplicate_pad_numbers_are_jumpers no)
		(fp_line
			(start 0.7874 -0.4064)
			(end 0.7874 0.4064)
			(stroke
				(width 0.1524)
				(type default)
			)
			(layer "F.SilkS")
		)
		(fp_line
			(start -0.7874 -0.4064)
			(end 0.7874 -0.4064)
			(stroke
				(width 0.1524)
				(type default)
			)
			(layer "F.SilkS")
		)
		(fp_line
			(start 0.7874 0.4064)
			(end -0.7874 0.4064)
			(stroke
				(width 0.1524)
				(type default)
			)
			(layer "F.SilkS")
		)
		(fp_line
			(start -0.7874 0.4064)
			(end -0.7874 -0.4064)
			(stroke
				(width 0.1524)
				(type default)
			)
			(layer "F.SilkS")
		)
		(fp_line
			(start -0.12065 -0.305054)
			(end -0.12065 -0.2794)
			(stroke
				(width 0.1)
				(type default)
			)
			(layer "F.Fab")
		)
		(fp_line
			(start -0.67945 -0.305054)
			(end -0.12065 -0.305054)
			(stroke
				(width 0.1)
				(type default)
			)
			(layer "F.Fab")
		)
		(fp_line
			(start 0.67945 -0.3048)
			(end 0.67945 0.3048)
			(stroke
				(width 0.1)
				(type default)
			)
			(layer "F.Fab")
		)
		(fp_line
			(start 0.12065 -0.3048)
			(end 0.67945 -0.3048)
			(stroke
				(width 0.1)
				(type default)
			)
			(layer "F.Fab")
		)
		(fp_line
			(start 0.12065 -0.2794)
			(end 0.12065 -0.3048)
			(stroke
				(width 0.1)
				(type default)
			)
			(layer "F.Fab")
		)
		(fp_line
			(start -0.12065 -0.2794)
			(end 0.12065 -0.2794)
			(stroke
				(width 0.1)
				(type default)
			)
			(layer "F.Fab")
		)
		(fp_line
			(start 0.120396 0.2794)
			(end -0.12065 0.2794)
			(stroke
				(width 0.1)
				(type default)
			)
			(layer "F.Fab")
		)
		(fp_line
			(start -0.12065 0.2794)
			(end -0.12065 0.3048)
			(stroke
				(width 0.1)
				(type default)
			)
			(layer "F.Fab")
		)
		(fp_line
			(start 0.67945 0.3048)
			(end 0.120396 0.3048)
			(stroke
				(width 0.1)
				(type default)
			)
			(layer "F.Fab")
		)
		(fp_line
			(start 0.120396 0.3048)
			(end 0.120396 0.2794)
			(stroke
				(width 0.1)
				(type default)
			)
			(layer "F.Fab")
		)
		(fp_line
			(start -0.12065 0.3048)
			(end -0.67945 0.3048)
			(stroke
				(width 0.1)
				(type default)
			)
			(layer "F.Fab")
		)
		(fp_line
			(start -0.67945 0.3048)
			(end -0.67945 -0.305054)
			(stroke
				(width 0.1)
				(type default)
			)
			(layer "F.Fab")
		)
		(pad "1" smd circle
			(at -0.40005 0 90)
			(size 0 0)
			(layers "F.Cu" "F.Mask" "F.Paste")
			(net "P3V3_AUX")
		)
		(pad "2" smd circle
			(at 0.40005 0 90)
			(size 0 0)
			(layers "F.Cu" "F.Mask" "F.Paste")
			(net "FG_SS_EN")
		)
	)
	(footprint ""
		(layer "F.Cu")
		(at 90.623136 -341.729822 -90)
		(property "Reference" "PC509"
			(at 0 0 270)
			(layer "F.SilkS")
			(hide yes)
			(effects
				(font
					(size 1.27 1.27)
				)
			)
		)
		(property "Value" ""
			(at 0 0 270)
			(layer "F.Fab")
			(effects
				(font
					(size 1.27 1.27)
				)
			)
		)
		(duplicate_pad_numbers_are_jumpers no)
		(fp_line
			(start -0.7874 0.4064)
			(end -0.7874 -0.4064)
			(stroke
				(width 0.1524)
				(type default)
			)
			(layer "F.SilkS")
		)
		(fp_line
			(start 0.7874 0.4064)
			(end -0.7874 0.4064)
			(stroke
				(width 0.1524)
				(type default)
			)
			(layer "F.SilkS")
		)
		(fp_line
			(start -0.7874 -0.4064)
			(end 0.7874 -0.4064)
			(stroke
				(width 0.1524)
				(type default)
			)
			(layer "F.SilkS")
		)
		(fp_line
			(start 0.7874 -0.4064)
			(end 0.7874 0.4064)
			(stroke
				(width 0.1524)
				(type default)
			)
			(layer "F.SilkS")
		)
		(fp_line
			(start -0.67945 0.3048)
			(end -0.67945 -0.305054)
			(stroke
				(width 0.1)
				(type default)
			)
			(layer "F.Fab")
		)
		(fp_line
			(start -0.12065 0.3048)
			(end -0.67945 0.3048)
			(stroke
				(width 0.1)
				(type default)
			)
			(layer "F.Fab")
		)
		(fp_line
			(start 0.120396 0.3048)
			(end 0.120396 0.2794)
			(stroke
				(width 0.1)
				(type default)
			)
			(layer "F.Fab")
		)
		(fp_line
			(start 0.67945 0.3048)
			(end 0.120396 0.3048)
			(stroke
				(width 0.1)
				(type default)
			)
			(layer "F.Fab")
		)
		(fp_line
			(start -0.12065 0.2794)
			(end -0.12065 0.3048)
			(stroke
				(width 0.1)
				(type default)
			)
			(layer "F.Fab")
		)
		(fp_line
			(start 0.120396 0.2794)
			(end -0.12065 0.2794)
			(stroke
				(width 0.1)
				(type default)
			)
			(layer "F.Fab")
		)
		(fp_line
			(start -0.12065 -0.2794)
			(end 0.12065 -0.2794)
			(stroke
				(width 0.1)
				(type default)
			)
			(layer "F.Fab")
		)
		(fp_line
			(start 0.12065 -0.2794)
			(end 0.12065 -0.3048)
			(stroke
				(width 0.1)
				(type default)
			)
			(layer "F.Fab")
		)
		(fp_line
			(start 0.12065 -0.3048)
			(end 0.67945 -0.3048)
			(stroke
				(width 0.1)
				(type default)
			)
			(layer "F.Fab")
		)
		(fp_line
			(start 0.67945 -0.3048)
			(end 0.67945 0.3048)
			(stroke
				(width 0.1)
				(type default)
			)
			(layer "F.Fab")
		)
		(fp_line
			(start -0.67945 -0.305054)
			(end -0.12065 -0.305054)
			(stroke
				(width 0.1)
				(type default)
			)
			(layer "F.Fab")
		)
		(fp_line
			(start -0.12065 -0.305054)
			(end -0.12065 -0.2794)
			(stroke
				(width 0.1)
				(type default)
			)
			(layer "F.Fab")
		)
		(pad "1" smd circle
			(at -0.40005 0 270)
			(size 0 0)
			(layers "F.Cu" "F.Mask" "F.Paste")
			(net "SW_PVCCIN_CPU1_BOOT6_R")
		)
		(pad "2" smd circle
			(at 0.40005 0 270)
			(size 0 0)
			(layers "F.Cu" "F.Mask" "F.Paste")
			(net "SW_PVCCIN_CPU1_BOOTR6")
		)
	)
	(footprint ""
		(layer "F.Cu")
		(at 375.255536 -105.483152 -90)
		(property "Reference" "R1366"
			(at 0 0 270)
			(layer "F.SilkS")
			(hide yes)
			(effects
				(font
					(size 1.27 1.27)
				)
			)
		)
		(property "Value" ""
			(at 0 0 270)
			(layer "F.Fab")
			(effects
				(font
					(size 1.27 1.27)
				)
			)
		)
		(duplicate_pad_numbers_are_jumpers no)
		(fp_line
			(start -0.7874 0.4064)
			(end -0.7874 -0.4064)
			(stroke
				(width 0.1524)
				(type default)
			)
			(layer "F.SilkS")
		)
		(fp_line
			(start 0.7874 0.4064)
			(end -0.7874 0.4064)
			(stroke
				(width 0.1524)
				(type default)
			)
			(layer "F.SilkS")
		)
		(fp_line
			(start -0.7874 -0.4064)
			(end 0.7874 -0.4064)
			(stroke
				(width 0.1524)
				(type default)
			)
			(layer "F.SilkS")
		)
		(fp_line
			(start 0.7874 -0.4064)
			(end 0.7874 0.4064)
			(stroke
				(width 0.1524)
				(type default)
			)
			(layer "F.SilkS")
		)
		(fp_line
			(start -0.67945 0.3048)
			(end -0.67945 -0.305054)
			(stroke
				(width 0.1)
				(type default)
			)
			(layer "F.Fab")
		)
		(fp_line
			(start -0.12065 0.3048)
			(end -0.67945 0.3048)
			(stroke
				(width 0.1)
				(type default)
			)
			(layer "F.Fab")
		)
		(fp_line
			(start 0.120396 0.3048)
			(end 0.120396 0.2794)
			(stroke
				(width 0.1)
				(type default)
			)
			(layer "F.Fab")
		)
		(fp_line
			(start 0.67945 0.3048)
			(end 0.120396 0.3048)
			(stroke
				(width 0.1)
				(type default)
			)
			(layer "F.Fab")
		)
		(fp_line
			(start -0.12065 0.2794)
			(end -0.12065 0.3048)
			(stroke
				(width 0.1)
				(type default)
			)
			(layer "F.Fab")
		)
		(fp_line
			(start 0.120396 0.2794)
			(end -0.12065 0.2794)
			(stroke
				(width 0.1)
				(type default)
			)
			(layer "F.Fab")
		)
		(fp_line
			(start -0.12065 -0.2794)
			(end 0.12065 -0.2794)
			(stroke
				(width 0.1)
				(type default)
			)
			(layer "F.Fab")
		)
		(fp_line
			(start 0.12065 -0.2794)
			(end 0.12065 -0.3048)
			(stroke
				(width 0.1)
				(type default)
			)
			(layer "F.Fab")
		)
		(fp_line
			(start 0.12065 -0.3048)
			(end 0.67945 -0.3048)
			(stroke
				(width 0.1)
				(type default)
			)
			(layer "F.Fab")
		)
		(fp_line
			(start 0.67945 -0.3048)
			(end 0.67945 0.3048)
			(stroke
				(width 0.1)
				(type default)
			)
			(layer "F.Fab")
		)
		(fp_line
			(start -0.67945 -0.305054)
			(end -0.12065 -0.305054)
			(stroke
				(width 0.1)
				(type default)
			)
			(layer "F.Fab")
		)
		(fp_line
			(start -0.12065 -0.305054)
			(end -0.12065 -0.2794)
			(stroke
				(width 0.1)
				(type default)
			)
			(layer "F.Fab")
		)
		(pad "1" smd circle
			(at -0.40005 0 270)
			(size 0 0)
			(layers "F.Cu" "F.Mask" "F.Paste")
			(net "JTAG_DBP_TDO")
		)
		(pad "2" smd circle
			(at 0.40005 0 270)
			(size 0 0)
			(layers "F.Cu" "F.Mask" "F.Paste")
			(net "JTAG_DBP_FB_TDO")
		)
	)
	(footprint ""
		(layer "F.Cu")
		(at 75.25893 -158.541974)
		(property "Reference" "R329"
			(at 0 0 0)
			(layer "F.SilkS")
			(hide yes)
			(effects
				(font
					(size 1.27 1.27)
				)
			)
		)
		(property "Value" ""
			(at 0 0 0)
			(layer "F.Fab")
			(effects
				(font
					(size 1.27 1.27)
				)
			)
		)
		(duplicate_pad_numbers_are_jumpers no)
		(fp_line
			(start -2.044192 -0.94361)
			(end -2.044192 0.898398)
			(stroke
				(width 0.1524)
				(type default)
			)
			(layer "F.SilkS")
		)
		(fp_line
			(start -2.044192 0.94361)
			(end 2.044192 0.94361)
			(stroke
				(width 0.1524)
				(type default)
			)
			(layer "F.SilkS")
		)
		(fp_line
			(start 2.044192 -0.94361)
			(end -2.044192 -0.94361)
			(stroke
				(width 0.1524)
				(type default)
			)
			(layer "F.SilkS")
		)
		(fp_line
			(start 2.044192 0.94361)
			(end 2.044192 -0.94361)
			(stroke
				(width 0.1524)
				(type default)
			)
			(layer "F.SilkS")
		)
		(fp_line
			(start -1.625092 -0.87503)
			(end -1.625092 0.87503)
			(stroke
				(width 0.1)
				(type default)
			)
			(layer "F.Fab")
		)
		(fp_line
			(start -1.625092 0.87503)
			(end 1.625092 0.87503)
			(stroke
				(width 0.1)
				(type default)
			)
			(layer "F.Fab")
		)
		(fp_line
			(start 1.625092 -0.87503)
			(end -1.625092 -0.87503)
			(stroke
				(width 0.1)
				(type default)
			)
			(layer "F.Fab")
		)
		(fp_line
			(start 1.625092 0.87503)
			(end 1.625092 -0.87503)
			(stroke
				(width 0.1)
				(type default)
			)
			(layer "F.Fab")
		)
		(pad "1" smd rect
			(at -1.450086 0)
			(size 0.9144 1.6002)
			(layers "F.Cu" "F.Mask" "F.Paste")
			(net "PVCCINFAON_CPU1")
		)
		(pad "2" smd rect
			(at 1.450086 0)
			(size 0.9144 1.6002)
			(layers "F.Cu" "F.Mask" "F.Paste")
			(net "PVNN_TERM_CPU1")
		)
	)
	(footprint ""
		(layer "F.Cu")
		(at 21.181314 -95.510604)
		(property "Reference" "R3664"
			(at 0 0 0)
			(layer "F.SilkS")
			(hide yes)
			(effects
				(font
					(size 1.27 1.27)
				)
			)
		)
		(property "Value" ""
			(at 0 0 0)
			(layer "F.Fab")
			(effects
				(font
					(size 1.27 1.27)
				)
			)
		)
		(duplicate_pad_numbers_are_jumpers no)
		(fp_line
			(start -0.7874 -0.4064)
			(end 0.7874 -0.4064)
			(stroke
				(width 0.1524)
				(type default)
			)
			(layer "F.SilkS")
		)
		(fp_line
			(start -0.7874 0.4064)
			(end -0.7874 -0.4064)
			(stroke
				(width 0.1524)
				(type default)
			)
			(layer "F.SilkS")
		)
		(fp_line
			(start 0.7874 -0.4064)
			(end 0.7874 0.4064)
			(stroke
				(width 0.1524)
				(type default)
			)
			(layer "F.SilkS")
		)
		(fp_line
			(start 0.7874 0.4064)
			(end -0.7874 0.4064)
			(stroke
				(width 0.1524)
				(type default)
			)
			(layer "F.SilkS")
		)
		(fp_line
			(start -0.67945 -0.305054)
			(end -0.12065 -0.305054)
			(stroke
				(width 0.1)
				(type default)
			)
			(layer "F.Fab")
		)
		(fp_line
			(start -0.67945 0.3048)
			(end -0.67945 -0.305054)
			(stroke
				(width 0.1)
				(type default)
			)
			(layer "F.Fab")
		)
		(fp_line
			(start -0.12065 -0.305054)
			(end -0.12065 -0.2794)
			(stroke
				(width 0.1)
				(type default)
			)
			(layer "F.Fab")
		)
		(fp_line
			(start -0.12065 -0.2794)
			(end 0.12065 -0.2794)
			(stroke
				(width 0.1)
				(type default)
			)
			(layer "F.Fab")
		)
		(fp_line
			(start -0.12065 0.2794)
			(end -0.12065 0.3048)
			(stroke
				(width 0.1)
				(type default)
			)
			(layer "F.Fab")
		)
		(fp_line
			(start -0.12065 0.3048)
			(end -0.67945 0.3048)
			(stroke
				(width 0.1)
				(type default)
			)
			(layer "F.Fab")
		)
		(fp_line
			(start 0.120396 0.2794)
			(end -0.12065 0.2794)
			(stroke
				(width 0.1)
				(type default)
			)
			(layer "F.Fab")
		)
		(fp_line
			(start 0.120396 0.3048)
			(end 0.120396 0.2794)
			(stroke
				(width 0.1)
				(type default)
			)
			(layer "F.Fab")
		)
		(fp_line
			(start 0.12065 -0.3048)
			(end 0.67945 -0.3048)
			(stroke
				(width 0.1)
				(type default)
			)
			(layer "F.Fab")
		)
		(fp_line
			(start 0.12065 -0.2794)
			(end 0.12065 -0.3048)
			(stroke
				(width 0.1)
				(type default)
			)
			(layer "F.Fab")
		)
		(fp_line
			(start 0.67945 -0.3048)
			(end 0.67945 0.3048)
			(stroke
				(width 0.1)
				(type default)
			)
			(layer "F.Fab")
		)
		(fp_line
			(start 0.67945 0.3048)
			(end 0.120396 0.3048)
			(stroke
				(width 0.1)
				(type default)
			)
			(layer "F.Fab")
		)
		(pad "1" smd circle
			(at -0.40005 0)
			(size 0 0)
			(layers "F.Cu" "F.Mask" "F.Paste")
			(net "USB_HUB_PSELF")
		)
		(pad "2" smd circle
			(at 0.40005 0)
			(size 0 0)
			(layers "F.Cu" "F.Mask" "F.Paste")
			(net "GND")
		)
	)
	(footprint ""
		(layer "F.Cu")
		(at 441.376054 -123.656598)
		(property "Reference" "C2444"
			(at 0 0 0)
			(layer "F.SilkS")
			(hide yes)
			(effects
				(font
					(size 1.27 1.27)
				)
			)
		)
		(property "Value" ""
			(at 0 0 0)
			(layer "F.Fab")
			(effects
				(font
					(size 1.27 1.27)
				)
			)
		)
		(duplicate_pad_numbers_are_jumpers no)
		(fp_line
			(start -0.7874 -0.4064)
			(end 0.7874 -0.4064)
			(stroke
				(width 0.1524)
				(type default)
			)
			(layer "F.SilkS")
		)
		(fp_line
			(start -0.7874 0.4064)
			(end -0.7874 -0.4064)
			(stroke
				(width 0.1524)
				(type default)
			)
			(layer "F.SilkS")
		)
		(fp_line
			(start 0.7874 -0.4064)
			(end 0.7874 0.4064)
			(stroke
				(width 0.1524)
				(type default)
			)
			(layer "F.SilkS")
		)
		(fp_line
			(start 0.7874 0.4064)
			(end -0.7874 0.4064)
			(stroke
				(width 0.1524)
				(type default)
			)
			(layer "F.SilkS")
		)
		(fp_line
			(start -0.67945 -0.305054)
			(end -0.12065 -0.305054)
			(stroke
				(width 0.1)
				(type default)
			)
			(layer "F.Fab")
		)
		(fp_line
			(start -0.67945 0.3048)
			(end -0.67945 -0.305054)
			(stroke
				(width 0.1)
				(type default)
			)
			(layer "F.Fab")
		)
		(fp_line
			(start -0.12065 -0.305054)
			(end -0.12065 -0.2794)
			(stroke
				(width 0.1)
				(type default)
			)
			(layer "F.Fab")
		)
		(fp_line
			(start -0.12065 -0.2794)
			(end 0.12065 -0.2794)
			(stroke
				(width 0.1)
				(type default)
			)
			(layer "F.Fab")
		)
		(fp_line
			(start -0.12065 0.2794)
			(end -0.12065 0.3048)
			(stroke
				(width 0.1)
				(type default)
			)
			(layer "F.Fab")
		)
		(fp_line
			(start -0.12065 0.3048)
			(end -0.67945 0.3048)
			(stroke
				(width 0.1)
				(type default)
			)
			(layer "F.Fab")
		)
		(fp_line
			(start 0.120396 0.2794)
			(end -0.12065 0.2794)
			(stroke
				(width 0.1)
				(type default)
			)
			(layer "F.Fab")
		)
		(fp_line
			(start 0.120396 0.3048)
			(end 0.120396 0.2794)
			(stroke
				(width 0.1)
				(type default)
			)
			(layer "F.Fab")
		)
		(fp_line
			(start 0.12065 -0.3048)
			(end 0.67945 -0.3048)
			(stroke
				(width 0.1)
				(type default)
			)
			(layer "F.Fab")
		)
		(fp_line
			(start 0.12065 -0.2794)
			(end 0.12065 -0.3048)
			(stroke
				(width 0.1)
				(type default)
			)
			(layer "F.Fab")
		)
		(fp_line
			(start 0.67945 -0.3048)
			(end 0.67945 0.3048)
			(stroke
				(width 0.1)
				(type default)
			)
			(layer "F.Fab")
		)
		(fp_line
			(start 0.67945 0.3048)
			(end 0.120396 0.3048)
			(stroke
				(width 0.1)
				(type default)
			)
			(layer "F.Fab")
		)
		(pad "1" smd circle
			(at -0.40005 0)
			(size 0 0)
			(layers "F.Cu" "F.Mask" "F.Paste")
			(net "PVNN_TERM_CPU0")
		)
		(pad "2" smd circle
			(at 0.40005 0)
			(size 0 0)
			(layers "F.Cu" "F.Mask" "F.Paste")
			(net "GND")
		)
	)
	(footprint ""
		(layer "F.Cu")
		(at 294.62222 -419.02761 -90)
		(property "Reference" "R4154"
			(at 0 0 270)
			(layer "F.SilkS")
			(hide yes)
			(effects
				(font
					(size 1.27 1.27)
				)
			)
		)
		(property "Value" ""
			(at 0 0 270)
			(layer "F.Fab")
			(effects
				(font
					(size 1.27 1.27)
				)
			)
		)
		(duplicate_pad_numbers_are_jumpers no)
		(fp_line
			(start -0.7874 0.4064)
			(end -0.7874 -0.4064)
			(stroke
				(width 0.1524)
				(type default)
			)
			(layer "F.SilkS")
		)
		(fp_line
			(start 0.7874 0.4064)
			(end -0.7874 0.4064)
			(stroke
				(width 0.1524)
				(type default)
			)
			(layer "F.SilkS")
		)
		(fp_line
			(start -0.7874 -0.4064)
			(end 0.7874 -0.4064)
			(stroke
				(width 0.1524)
				(type default)
			)
			(layer "F.SilkS")
		)
		(fp_line
			(start 0.7874 -0.4064)
			(end 0.7874 0.4064)
			(stroke
				(width 0.1524)
				(type default)
			)
			(layer "F.SilkS")
		)
		(fp_line
			(start -0.67945 0.3048)
			(end -0.67945 -0.305054)
			(stroke
				(width 0.1)
				(type default)
			)
			(layer "F.Fab")
		)
		(fp_line
			(start -0.12065 0.3048)
			(end -0.67945 0.3048)
			(stroke
				(width 0.1)
				(type default)
			)
			(layer "F.Fab")
		)
		(fp_line
			(start 0.120396 0.3048)
			(end 0.120396 0.2794)
			(stroke
				(width 0.1)
				(type default)
			)
			(layer "F.Fab")
		)
		(fp_line
			(start 0.67945 0.3048)
			(end 0.120396 0.3048)
			(stroke
				(width 0.1)
				(type default)
			)
			(layer "F.Fab")
		)
		(fp_line
			(start -0.12065 0.2794)
			(end -0.12065 0.3048)
			(stroke
				(width 0.1)
				(type default)
			)
			(layer "F.Fab")
		)
		(fp_line
			(start 0.120396 0.2794)
			(end -0.12065 0.2794)
			(stroke
				(width 0.1)
				(type default)
			)
			(layer "F.Fab")
		)
		(fp_line
			(start -0.12065 -0.2794)
			(end 0.12065 -0.2794)
			(stroke
				(width 0.1)
				(type default)
			)
			(layer "F.Fab")
		)
		(fp_line
			(start 0.12065 -0.2794)
			(end 0.12065 -0.3048)
			(stroke
				(width 0.1)
				(type default)
			)
			(layer "F.Fab")
		)
		(fp_line
			(start 0.12065 -0.3048)
			(end 0.67945 -0.3048)
			(stroke
				(width 0.1)
				(type default)
			)
			(layer "F.Fab")
		)
		(fp_line
			(start 0.67945 -0.3048)
			(end 0.67945 0.3048)
			(stroke
				(width 0.1)
				(type default)
			)
			(layer "F.Fab")
		)
		(fp_line
			(start -0.67945 -0.305054)
			(end -0.12065 -0.305054)
			(stroke
				(width 0.1)
				(type default)
			)
			(layer "F.Fab")
		)
		(fp_line
			(start -0.12065 -0.305054)
			(end -0.12065 -0.2794)
			(stroke
				(width 0.1)
				(type default)
			)
			(layer "F.Fab")
		)
		(pad "1" smd circle
			(at -0.40005 0 270)
			(size 0 0)
			(layers "F.Cu" "F.Mask" "F.Paste")
			(net "PRSNT_CABLE_GPU_A1_N")
		)
		(pad "2" smd circle
			(at 0.40005 0 270)
			(size 0 0)
			(layers "F.Cu" "F.Mask" "F.Paste")
			(net "GND")
		)
	)
	(footprint ""
		(layer "F.Cu")
		(at 350.78543 -356.668578)
		(property "Reference" "R2369"
			(at 0 0 0)
			(layer "F.SilkS")
			(hide yes)
			(effects
				(font
					(size 1.27 1.27)
				)
			)
		)
		(property "Value" ""
			(at 0 0 0)
			(layer "F.Fab")
			(effects
				(font
					(size 1.27 1.27)
				)
			)
		)
		(duplicate_pad_numbers_are_jumpers no)
		(fp_line
			(start -0.7874 -0.4064)
			(end 0.7874 -0.4064)
			(stroke
				(width 0.1524)
				(type default)
			)
			(layer "F.SilkS")
		)
		(fp_line
			(start -0.7874 0.4064)
			(end -0.7874 -0.4064)
			(stroke
				(width 0.1524)
				(type default)
			)
			(layer "F.SilkS")
		)
		(fp_line
			(start 0.7874 -0.4064)
			(end 0.7874 0.4064)
			(stroke
				(width 0.1524)
				(type default)
			)
			(layer "F.SilkS")
		)
		(fp_line
			(start 0.7874 0.4064)
			(end -0.7874 0.4064)
			(stroke
				(width 0.1524)
				(type default)
			)
			(layer "F.SilkS")
		)
		(fp_line
			(start -0.67945 -0.305054)
			(end -0.12065 -0.305054)
			(stroke
				(width 0.1)
				(type default)
			)
			(layer "F.Fab")
		)
		(fp_line
			(start -0.67945 0.3048)
			(end -0.67945 -0.305054)
			(stroke
				(width 0.1)
				(type default)
			)
			(layer "F.Fab")
		)
		(fp_line
			(start -0.12065 -0.305054)
			(end -0.12065 -0.2794)
			(stroke
				(width 0.1)
				(type default)
			)
			(layer "F.Fab")
		)
		(fp_line
			(start -0.12065 -0.2794)
			(end 0.12065 -0.2794)
			(stroke
				(width 0.1)
				(type default)
			)
			(layer "F.Fab")
		)
		(fp_line
			(start -0.12065 0.2794)
			(end -0.12065 0.3048)
			(stroke
				(width 0.1)
				(type default)
			)
			(layer "F.Fab")
		)
		(fp_line
			(start -0.12065 0.3048)
			(end -0.67945 0.3048)
			(stroke
				(width 0.1)
				(type default)
			)
			(layer "F.Fab")
		)
		(fp_line
			(start 0.120396 0.2794)
			(end -0.12065 0.2794)
			(stroke
				(width 0.1)
				(type default)
			)
			(layer "F.Fab")
		)
		(fp_line
			(start 0.120396 0.3048)
			(end 0.120396 0.2794)
			(stroke
				(width 0.1)
				(type default)
			)
			(layer "F.Fab")
		)
		(fp_line
			(start 0.12065 -0.3048)
			(end 0.67945 -0.3048)
			(stroke
				(width 0.1)
				(type default)
			)
			(layer "F.Fab")
		)
		(fp_line
			(start 0.12065 -0.2794)
			(end 0.12065 -0.3048)
			(stroke
				(width 0.1)
				(type default)
			)
			(layer "F.Fab")
		)
		(fp_line
			(start 0.67945 -0.3048)
			(end 0.67945 0.3048)
			(stroke
				(width 0.1)
				(type default)
			)
			(layer "F.Fab")
		)
		(fp_line
			(start 0.67945 0.3048)
			(end 0.120396 0.3048)
			(stroke
				(width 0.1)
				(type default)
			)
			(layer "F.Fab")
		)
		(pad "1" smd circle
			(at -0.40005 0)
			(size 0 0)
			(layers "F.Cu" "F.Mask" "F.Paste")
			(net "SVID_DIO0_CPU0_R")
		)
		(pad "2" smd circle
			(at 0.40005 0)
			(size 0 0)
			(layers "F.Cu" "F.Mask" "F.Paste")
			(net "SVID_DIO_PVCCIN_CPU0_R")
		)
	)
	(footprint ""
		(layer "F.Cu")
		(at 75.416918 -17.148302 180)
		(property "Reference" "PR3828"
			(at 0 0 180)
			(layer "F.SilkS")
			(hide yes)
			(effects
				(font
					(size 1.27 1.27)
				)
			)
		)
		(property "Value" ""
			(at 0 0 180)
			(layer "F.Fab")
			(effects
				(font
					(size 1.27 1.27)
				)
			)
		)
		(duplicate_pad_numbers_are_jumpers no)
		(fp_line
			(start 0.7874 0.4064)
			(end -0.7874 0.4064)
			(stroke
				(width 0.1524)
				(type default)
			)
			(layer "F.SilkS")
		)
		(fp_line
			(start 0.7874 -0.4064)
			(end 0.7874 0.4064)
			(stroke
				(width 0.1524)
				(type default)
			)
			(layer "F.SilkS")
		)
		(fp_line
			(start -0.7874 0.4064)
			(end -0.7874 -0.4064)
			(stroke
				(width 0.1524)
				(type default)
			)
			(layer "F.SilkS")
		)
		(fp_line
			(start -0.7874 -0.4064)
			(end 0.7874 -0.4064)
			(stroke
				(width 0.1524)
				(type default)
			)
			(layer "F.SilkS")
		)
		(fp_line
			(start 0.67945 0.3048)
			(end 0.120396 0.3048)
			(stroke
				(width 0.1)
				(type default)
			)
			(layer "F.Fab")
		)
		(fp_line
			(start 0.67945 -0.3048)
			(end 0.67945 0.3048)
			(stroke
				(width 0.1)
				(type default)
			)
			(layer "F.Fab")
		)
		(fp_line
			(start 0.12065 -0.2794)
			(end 0.12065 -0.3048)
			(stroke
				(width 0.1)
				(type default)
			)
			(layer "F.Fab")
		)
		(fp_line
			(start 0.12065 -0.3048)
			(end 0.67945 -0.3048)
			(stroke
				(width 0.1)
				(type default)
			)
			(layer "F.Fab")
		)
		(fp_line
			(start 0.120396 0.3048)
			(end 0.120396 0.2794)
			(stroke
				(width 0.1)
				(type default)
			)
			(layer "F.Fab")
		)
		(fp_line
			(start 0.120396 0.2794)
			(end -0.12065 0.2794)
			(stroke
				(width 0.1)
				(type default)
			)
			(layer "F.Fab")
		)
		(fp_line
			(start -0.12065 0.3048)
			(end -0.67945 0.3048)
			(stroke
				(width 0.1)
				(type default)
			)
			(layer "F.Fab")
		)
		(fp_line
			(start -0.12065 0.2794)
			(end -0.12065 0.3048)
			(stroke
				(width 0.1)
				(type default)
			)
			(layer "F.Fab")
		)
		(fp_line
			(start -0.12065 -0.2794)
			(end 0.12065 -0.2794)
			(stroke
				(width 0.1)
				(type default)
			)
			(layer "F.Fab")
		)
		(fp_line
			(start -0.12065 -0.305054)
			(end -0.12065 -0.2794)
			(stroke
				(width 0.1)
				(type default)
			)
			(layer "F.Fab")
		)
		(fp_line
			(start -0.67945 0.3048)
			(end -0.67945 -0.305054)
			(stroke
				(width 0.1)
				(type default)
			)
			(layer "F.Fab")
		)
		(fp_line
			(start -0.67945 -0.305054)
			(end -0.12065 -0.305054)
			(stroke
				(width 0.1)
				(type default)
			)
			(layer "F.Fab")
		)
		(pad "1" smd circle
			(at -0.40005 0 180)
			(size 0 0)
			(layers "F.Cu" "F.Mask" "F.Paste")
			(net "P12V_OCP_OV_2")
		)
		(pad "2" smd circle
			(at 0.40005 0 180)
			(size 0 0)
			(layers "F.Cu" "F.Mask" "F.Paste")
			(net "GND")
		)
	)
	(footprint ""
		(layer "F.Cu")
		(at 395.603984 -16.088614 90)
		(property "Reference" "C843"
			(at 0 0 90)
			(layer "F.SilkS")
			(hide yes)
			(effects
				(font
					(size 1.27 1.27)
				)
			)
		)
		(property "Value" ""
			(at 0 0 90)
			(layer "F.Fab")
			(effects
				(font
					(size 1.27 1.27)
				)
			)
		)
		(duplicate_pad_numbers_are_jumpers no)
		(fp_line
			(start 0.299974 -0.150114)
			(end 0.299974 0.150114)
			(stroke
				(width 0.1)
				(type default)
			)
			(layer "F.Fab")
		)
		(fp_line
			(start -0.299974 -0.150114)
			(end 0.299974 -0.150114)
			(stroke
				(width 0.1)
				(type default)
			)
			(layer "F.Fab")
		)
		(fp_line
			(start 0.299974 0.150114)
			(end -0.299974 0.150114)
			(stroke
				(width 0.1)
				(type default)
			)
			(layer "F.Fab")
		)
		(fp_line
			(start -0.299974 0.150114)
			(end -0.299974 -0.150114)
			(stroke
				(width 0.1)
				(type default)
			)
			(layer "F.Fab")
		)
		(pad "1" smd rect
			(at -0.2667 0 90)
			(size 0.3048 0.381)
			(layers "F.Cu" "F.Mask" "F.Paste")
			(net "P5E_CPU0_PE1_TX_C_DP<13>")
		)
		(pad "2" smd rect
			(at 0.2667 0 90)
			(size 0.3048 0.381)
			(layers "F.Cu" "F.Mask" "F.Paste")
			(net "P5E_CPU0_PE1_TX_DP<13>")
		)
	)
	(footprint ""
		(layer "F.Cu")
		(at 350.691196 -60.591954)
		(property "Reference" "C139"
			(at 0 0 0)
			(layer "F.SilkS")
			(hide yes)
			(effects
				(font
					(size 1.27 1.27)
				)
			)
		)
		(property "Value" ""
			(at 0 0 0)
			(layer "F.Fab")
			(effects
				(font
					(size 1.27 1.27)
				)
			)
		)
		(duplicate_pad_numbers_are_jumpers no)
		(fp_line
			(start -0.299974 -0.150114)
			(end 0.299974 -0.150114)
			(stroke
				(width 0.1)
				(type default)
			)
			(layer "F.Fab")
		)
		(fp_line
			(start -0.299974 0.150114)
			(end -0.299974 -0.150114)
			(stroke
				(width 0.1)
				(type default)
			)
			(layer "F.Fab")
		)
		(fp_line
			(start 0.299974 -0.150114)
			(end 0.299974 0.150114)
			(stroke
				(width 0.1)
				(type default)
			)
			(layer "F.Fab")
		)
		(fp_line
			(start 0.299974 0.150114)
			(end -0.299974 0.150114)
			(stroke
				(width 0.1)
				(type default)
			)
			(layer "F.Fab")
		)
		(pad "1" smd rect
			(at -0.2667 0)
			(size 0.3048 0.381)
			(layers "F.Cu" "F.Mask" "F.Paste")
			(net "DMI_CPU0_PCH_TX_C_DN<7>")
		)
		(pad "2" smd rect
			(at 0.2667 0)
			(size 0.3048 0.381)
			(layers "F.Cu" "F.Mask" "F.Paste")
			(net "DMI_CPU0_PCH_TX_DN<7>")
		)
		(zone
			(layer "In1.Cu")
			(hatch none 0.5)
			(connect_pads
				(clearance 0)
			)
			(min_thickness 0.25)
			(keepout
				(tracks not_allowed)
				(vias allowed)
				(pads allowed)
				(copperpour not_allowed)
				(footprints allowed)
			)
			(placement
				(enabled no)
				(sheetname "")
			)
			(fill
				(thermal_gap 0.5)
				(thermal_bridge_width 0.5)
				(island_removal_mode 0)
			)
			(polygon
				(pts
					(arc
						(start 350.297496 -60.350654)
						(mid 350.243614 -60.372972)
						(end 350.221296 -60.426854)
					)
					(arc
						(start 350.221296 -60.757054)
						(mid 350.243614 -60.810936)
						(end 350.297496 -60.833254)
					)
					(arc
						(start 350.551496 -60.833254)
						(mid 350.605378 -60.810936)
						(end 350.627696 -60.757054)
					)
					(arc
						(start 350.627696 -60.426854)
						(mid 350.605378 -60.372972)
						(end 350.551496 -60.350654)
					)
				)
			)
		)
		(zone
			(layer "In1.Cu")
			(hatch none 0.5)
			(connect_pads
				(clearance 0)
			)
			(min_thickness 0.25)
			(keepout
				(tracks not_allowed)
				(vias allowed)
				(pads allowed)
				(copperpour not_allowed)
				(footprints allowed)
			)
			(placement
				(enabled no)
				(sheetname "")
			)
			(fill
				(thermal_gap 0.5)
				(thermal_bridge_width 0.5)
				(island_removal_mode 0)
			)
			(polygon
				(pts
					(arc
						(start 350.830896 -60.350654)
						(mid 350.777014 -60.372972)
						(end 350.754696 -60.426854)
					)
					(arc
						(start 350.754696 -60.757054)
						(mid 350.777014 -60.810936)
						(end 350.830896 -60.833254)
					)
					(arc
						(start 351.084896 -60.833254)
						(mid 351.138778 -60.810936)
						(end 351.161096 -60.757054)
					)
					(arc
						(start 351.161096 -60.426854)
						(mid 351.138778 -60.372972)
						(end 351.084896 -60.350654)
					)
				)
			)
		)
	)
	(footprint ""
		(layer "F.Cu")
		(at 337.142328 -19.434556 -90)
		(property "Reference" "U60"
			(at 2.376678 -2.681732 0)
			(unlocked yes)
			(layer "F.SilkS")
			(effects
				(font
					(size 0.7874 0.5842)
					(thickness 0.1524)
				)
			)
		)
		(property "Value" ""
			(at 0 0 270)
			(layer "F.Fab")
			(effects
				(font
					(size 1.27 1.27)
				)
			)
		)
		(duplicate_pad_numbers_are_jumpers no)
		(fp_line
			(start -1.7272 1.1176)
			(end -1.7272 -1.1176)
			(stroke
				(width 0.1524)
				(type default)
			)
			(layer "F.SilkS")
		)
		(fp_line
			(start 1.7272 1.1176)
			(end -1.7272 1.1176)
			(stroke
				(width 0.1524)
				(type default)
			)
			(layer "F.SilkS")
		)
		(fp_line
			(start 0 -0.7366)
			(end -0.254 -1.1176)
			(stroke
				(width 0.1524)
				(type default)
			)
			(layer "F.SilkS")
		)
		(fp_line
			(start -0.254 -1.1176)
			(end -1.7272 -1.1176)
			(stroke
				(width 0.1524)
				(type default)
			)
			(layer "F.SilkS")
		)
		(fp_line
			(start 0.254 -1.1176)
			(end 0 -0.7366)
			(stroke
				(width 0.1524)
				(type default)
			)
			(layer "F.SilkS")
		)
		(fp_line
			(start 1.7272 -1.1176)
			(end 1.7272 1.1176)
			(stroke
				(width 0.1524)
				(type default)
			)
			(layer "F.SilkS")
		)
		(fp_line
			(start 1.7272 -1.1176)
			(end 0.254 -1.1176)
			(stroke
				(width 0.1524)
				(type default)
			)
			(layer "F.SilkS")
		)
		(fp_poly
			(pts
				(xy -1.458214 -2.053336) (xy -0.696214 -2.053336) (xy -1.077214 -1.291336)
			)
			(stroke
				(width 0)
				(type default)
			)
			(fill yes)
			(layer "F.SilkS")
		)
		(fp_line
			(start -1.5748 1.1176)
			(end 1.5748 1.1176)
			(stroke
				(width 0.1)
				(type default)
			)
			(layer "F.Fab")
		)
		(fp_line
			(start 1.5748 1.1176)
			(end 1.5748 -1.1176)
			(stroke
				(width 0.1)
				(type default)
			)
			(layer "F.Fab")
		)
		(fp_line
			(start -1.5748 -1.1176)
			(end -1.5748 1.1176)
			(stroke
				(width 0.1)
				(type default)
			)
			(layer "F.Fab")
		)
		(fp_line
			(start 1.5748 -1.1176)
			(end -1.5748 -1.1176)
			(stroke
				(width 0.1)
				(type default)
			)
			(layer "F.Fab")
		)
		(fp_poly
			(pts
				(xy -1.9558 -0.649986) (xy -2.7178 -0.268986) (xy -2.7178 -1.030986)
			)
			(stroke
				(width 0)
				(type default)
			)
			(fill yes)
			(layer "F.Fab")
		)
		(pad "1" smd rect
			(at -0.999998 -0.649986 180)
			(size 0.3556 1.1176)
			(layers "F.Cu" "F.Mask" "F.Paste")
			(net "IRQ_LPC_PIRQA_N_ESPI_ALERT0_R_N")
		)
		(pad "2" smd rect
			(at -0.999998 0 180)
			(size 0.3556 1.1176)
			(layers "F.Cu" "F.Mask" "F.Paste")
			(net "GND")
		)
		(pad "3" smd rect
			(at -0.999998 0.649986 180)
			(size 0.3556 1.1176)
			(layers "F.Cu" "F.Mask" "F.Paste")
			(net "IRQ_LPC_SERIRQ_ESPI_CS1_R_N")
		)
		(pad "4" smd rect
			(at 0.999998 0.649986 180)
			(size 0.3556 1.1176)
			(layers "F.Cu" "F.Mask" "F.Paste")
			(net "IRQ_ESPI_LPC_SERIRQ_ALERT_N")
		)
		(pad "5" smd rect
			(at 0.999998 0 180)
			(size 0.3556 1.1176)
			(layers "F.Cu" "F.Mask" "F.Paste")
			(net "PGPPA_AUX")
		)
		(pad "6" smd rect
			(at 0.999998 -0.649986 180)
			(size 0.3556 1.1176)
			(layers "F.Cu" "F.Mask" "F.Paste")
			(net "FM_ESPI_PLD_EN")
		)
	)
	(footprint ""
		(layer "F.Cu")
		(at 249.713496 -47.078138)
		(property "Reference" "PC2217"
			(at 0 0 0)
			(layer "F.SilkS")
			(hide yes)
			(effects
				(font
					(size 1.27 1.27)
				)
			)
		)
		(property "Value" ""
			(at 0 0 0)
			(layer "F.Fab")
			(effects
				(font
					(size 1.27 1.27)
				)
			)
		)
		(duplicate_pad_numbers_are_jumpers no)
		(fp_line
			(start -0.7874 -0.4064)
			(end 0.7874 -0.4064)
			(stroke
				(width 0.1524)
				(type default)
			)
			(layer "F.SilkS")
		)
		(fp_line
			(start -0.7874 0.4064)
			(end -0.7874 -0.4064)
			(stroke
				(width 0.1524)
				(type default)
			)
			(layer "F.SilkS")
		)
		(fp_line
			(start 0.7874 -0.4064)
			(end 0.7874 0.4064)
			(stroke
				(width 0.1524)
				(type default)
			)
			(layer "F.SilkS")
		)
		(fp_line
			(start 0.7874 0.4064)
			(end -0.7874 0.4064)
			(stroke
				(width 0.1524)
				(type default)
			)
			(layer "F.SilkS")
		)
		(fp_line
			(start -0.67945 -0.305054)
			(end -0.12065 -0.305054)
			(stroke
				(width 0.1)
				(type default)
			)
			(layer "F.Fab")
		)
		(fp_line
			(start -0.67945 0.3048)
			(end -0.67945 -0.305054)
			(stroke
				(width 0.1)
				(type default)
			)
			(layer "F.Fab")
		)
		(fp_line
			(start -0.12065 -0.305054)
			(end -0.12065 -0.2794)
			(stroke
				(width 0.1)
				(type default)
			)
			(layer "F.Fab")
		)
		(fp_line
			(start -0.12065 -0.2794)
			(end 0.12065 -0.2794)
			(stroke
				(width 0.1)
				(type default)
			)
			(layer "F.Fab")
		)
		(fp_line
			(start -0.12065 0.2794)
			(end -0.12065 0.3048)
			(stroke
				(width 0.1)
				(type default)
			)
			(layer "F.Fab")
		)
		(fp_line
			(start -0.12065 0.3048)
			(end -0.67945 0.3048)
			(stroke
				(width 0.1)
				(type default)
			)
			(layer "F.Fab")
		)
		(fp_line
			(start 0.120396 0.2794)
			(end -0.12065 0.2794)
			(stroke
				(width 0.1)
				(type default)
			)
			(layer "F.Fab")
		)
		(fp_line
			(start 0.120396 0.3048)
			(end 0.120396 0.2794)
			(stroke
				(width 0.1)
				(type default)
			)
			(layer "F.Fab")
		)
		(fp_line
			(start 0.12065 -0.3048)
			(end 0.67945 -0.3048)
			(stroke
				(width 0.1)
				(type default)
			)
			(layer "F.Fab")
		)
		(fp_line
			(start 0.12065 -0.2794)
			(end 0.12065 -0.3048)
			(stroke
				(width 0.1)
				(type default)
			)
			(layer "F.Fab")
		)
		(fp_line
			(start 0.67945 -0.3048)
			(end 0.67945 0.3048)
			(stroke
				(width 0.1)
				(type default)
			)
			(layer "F.Fab")
		)
		(fp_line
			(start 0.67945 0.3048)
			(end 0.120396 0.3048)
			(stroke
				(width 0.1)
				(type default)
			)
			(layer "F.Fab")
		)
		(pad "1" smd circle
			(at -0.40005 0)
			(size 0 0)
			(layers "F.Cu" "F.Mask" "F.Paste")
			(net "P12V_E1S_0")
		)
		(pad "2" smd circle
			(at 0.40005 0)
			(size 0 0)
			(layers "F.Cu" "F.Mask" "F.Paste")
			(net "GND")
		)
	)
	(footprint ""
		(layer "F.Cu")
		(at 287.2994 -346.700348)
		(property "Reference" "PC621"
			(at 0 0 0)
			(layer "F.SilkS")
			(hide yes)
			(effects
				(font
					(size 1.27 1.27)
				)
			)
		)
		(property "Value" ""
			(at 0 0 0)
			(layer "F.Fab")
			(effects
				(font
					(size 1.27 1.27)
				)
			)
		)
		(duplicate_pad_numbers_are_jumpers no)
		(fp_line
			(start 2.750058 0.999998)
			(end -2.750058 0.999998)
			(stroke
				(width 0.1524)
				(type default)
			)
			(layer "F.SilkS")
		)
		(fp_circle
			(center 0 0.999998)
			(end 2.750058 0.999998)
			(stroke
				(width 0.1524)
				(type default)
			)
			(fill no)
			(layer "F.SilkS")
		)
		(fp_poly
			(pts
				(arc
					(start 2.750058 0.999998)
					(mid 0 3.750056)
					(end -2.750058 0.999998)
				)
			)
			(stroke
				(width 0)
				(type default)
			)
			(fill yes)
			(layer "F.SilkS")
		)
		(fp_circle
			(center 0 0.999998)
			(end 2.750058 0.999998)
			(stroke
				(width 0.1)
				(type default)
			)
			(fill no)
			(layer "F.Fab")
		)
		(pad "1" thru_hole rect
			(at 0 0)
			(size 1.5748 1.5748)
			(drill 1.0668)
			(layers "*.Cu" "*.Mask")
			(remove_unused_layers no)
			(net "PVCCFA_EHV_FIVRA_CPU0")
			(clearance 0)
			(padstack
				(mode front_inner_back)
				(layer "Inner"
					(shape circle)
					(size 1.5748 1.5748)
					(clearance 0)
				)
				(layer "B.Cu"
					(shape rect)
					(size 1.5748 1.5748)
					(clearance 0)
				)
			)
		)
		(pad "2" thru_hole circle
			(at 0 1.999996)
			(size 1.5748 1.5748)
			(drill 1.0668)
			(layers "*.Cu" "*.Mask")
			(remove_unused_layers no)
			(net "GND")
			(clearance 0)
		)
	)
	(footprint ""
		(layer "F.Cu")
		(at 393.37488 -148.808948 90)
		(property "Reference" "R977"
			(at 0 0 90)
			(layer "F.SilkS")
			(hide yes)
			(effects
				(font
					(size 1.27 1.27)
				)
			)
		)
		(property "Value" ""
			(at 0 0 90)
			(layer "F.Fab")
			(effects
				(font
					(size 1.27 1.27)
				)
			)
		)
		(duplicate_pad_numbers_are_jumpers no)
		(fp_line
			(start 0.7874 -0.4064)
			(end 0.7874 0.4064)
			(stroke
				(width 0.1524)
				(type default)
			)
			(layer "F.SilkS")
		)
		(fp_line
			(start -0.7874 -0.4064)
			(end 0.7874 -0.4064)
			(stroke
				(width 0.1524)
				(type default)
			)
			(layer "F.SilkS")
		)
		(fp_line
			(start 0.7874 0.4064)
			(end -0.7874 0.4064)
			(stroke
				(width 0.1524)
				(type default)
			)
			(layer "F.SilkS")
		)
		(fp_line
			(start -0.7874 0.4064)
			(end -0.7874 -0.4064)
			(stroke
				(width 0.1524)
				(type default)
			)
			(layer "F.SilkS")
		)
		(fp_line
			(start -0.12065 -0.305054)
			(end -0.12065 -0.2794)
			(stroke
				(width 0.1)
				(type default)
			)
			(layer "F.Fab")
		)
		(fp_line
			(start -0.67945 -0.305054)
			(end -0.12065 -0.305054)
			(stroke
				(width 0.1)
				(type default)
			)
			(layer "F.Fab")
		)
		(fp_line
			(start 0.67945 -0.3048)
			(end 0.67945 0.3048)
			(stroke
				(width 0.1)
				(type default)
			)
			(layer "F.Fab")
		)
		(fp_line
			(start 0.12065 -0.3048)
			(end 0.67945 -0.3048)
			(stroke
				(width 0.1)
				(type default)
			)
			(layer "F.Fab")
		)
		(fp_line
			(start 0.12065 -0.2794)
			(end 0.12065 -0.3048)
			(stroke
				(width 0.1)
				(type default)
			)
			(layer "F.Fab")
		)
		(fp_line
			(start -0.12065 -0.2794)
			(end 0.12065 -0.2794)
			(stroke
				(width 0.1)
				(type default)
			)
			(layer "F.Fab")
		)
		(fp_line
			(start 0.120396 0.2794)
			(end -0.12065 0.2794)
			(stroke
				(width 0.1)
				(type default)
			)
			(layer "F.Fab")
		)
		(fp_line
			(start -0.12065 0.2794)
			(end -0.12065 0.3048)
			(stroke
				(width 0.1)
				(type default)
			)
			(layer "F.Fab")
		)
		(fp_line
			(start 0.67945 0.3048)
			(end 0.120396 0.3048)
			(stroke
				(width 0.1)
				(type default)
			)
			(layer "F.Fab")
		)
		(fp_line
			(start 0.120396 0.3048)
			(end 0.120396 0.2794)
			(stroke
				(width 0.1)
				(type default)
			)
			(layer "F.Fab")
		)
		(fp_line
			(start -0.12065 0.3048)
			(end -0.67945 0.3048)
			(stroke
				(width 0.1)
				(type default)
			)
			(layer "F.Fab")
		)
		(fp_line
			(start -0.67945 0.3048)
			(end -0.67945 -0.305054)
			(stroke
				(width 0.1)
				(type default)
			)
			(layer "F.Fab")
		)
		(pad "1" smd circle
			(at -0.40005 0 90)
			(size 0 0)
			(layers "F.Cu" "F.Mask" "F.Paste")
			(net "P3V3_AUX")
		)
		(pad "2" smd circle
			(at 0.40005 0 90)
			(size 0 0)
			(layers "F.Cu" "F.Mask" "F.Paste")
			(net "SMB_S3M_CPU0_3V3AUX_SCL")
		)
	)
	(footprint ""
		(layer "F.Cu")
		(at 41.573958 -344.77325 -90)
		(property "Reference" "PL113"
			(at 2.130552 8.226298 0)
			(unlocked yes)
			(layer "F.SilkS")
			(effects
				(font
					(size 0.7874 0.5842)
					(thickness 0.1524)
				)
				(justify left)
			)
		)
		(property "Value" ""
			(at 0 0 270)
			(layer "F.Fab")
			(effects
				(font
					(size 1.27 1.27)
				)
			)
		)
		(duplicate_pad_numbers_are_jumpers no)
		(fp_line
			(start -4.99999 3.750056)
			(end -4.99999 2.2479)
			(stroke
				(width 0.1524)
				(type default)
			)
			(layer "F.SilkS")
		)
		(fp_line
			(start 0 3.750056)
			(end -4.99999 3.750056)
			(stroke
				(width 0.1524)
				(type default)
			)
			(layer "F.SilkS")
		)
		(fp_line
			(start 4.99999 3.750056)
			(end 0 3.750056)
			(stroke
				(width 0.1524)
				(type default)
			)
			(layer "F.SilkS")
		)
		(fp_line
			(start 4.99999 2.2352)
			(end 4.99999 3.750056)
			(stroke
				(width 0.1524)
				(type default)
			)
			(layer "F.SilkS")
		)
		(fp_line
			(start -4.99999 -2.2479)
			(end -4.99999 -3.750056)
			(stroke
				(width 0.1524)
				(type default)
			)
			(layer "F.SilkS")
		)
		(fp_line
			(start -4.99999 -3.750056)
			(end 4.99999 -3.750056)
			(stroke
				(width 0.1524)
				(type default)
			)
			(layer "F.SilkS")
		)
		(fp_line
			(start 4.99999 -3.750056)
			(end 4.99999 -2.2479)
			(stroke
				(width 0.1524)
				(type default)
			)
			(layer "F.SilkS")
		)
		(fp_line
			(start -4.99999 3.750056)
			(end -4.99999 -3.750056)
			(stroke
				(width 0.1)
				(type default)
			)
			(layer "F.Fab")
		)
		(fp_line
			(start 0 3.750056)
			(end -4.99999 3.750056)
			(stroke
				(width 0.1)
				(type default)
			)
			(layer "F.Fab")
		)
		(fp_line
			(start 4.99999 3.750056)
			(end 0 3.750056)
			(stroke
				(width 0.1)
				(type default)
			)
			(layer "F.Fab")
		)
		(fp_line
			(start -4.99999 -3.750056)
			(end 4.99999 -3.750056)
			(stroke
				(width 0.1)
				(type default)
			)
			(layer "F.Fab")
		)
		(fp_line
			(start 4.99999 -3.750056)
			(end 4.99999 3.750056)
			(stroke
				(width 0.1)
				(type default)
			)
			(layer "F.Fab")
		)
		(pad "1" smd rect
			(at -3.299968 0 270)
			(size 3.302 4.2164)
			(layers "F.Cu" "F.Mask" "F.Paste")
			(net "SW_PVCCFA_EHV_FIVRA_CPU1_SW4")
		)
		(pad "2" smd rect
			(at 3.299968 0 270)
			(size 3.302 4.2164)
			(layers "F.Cu" "F.Mask" "F.Paste")
			(net "PVCCFA_EHV_FIVRA_CPU1")
		)
	)
	(footprint ""
		(layer "F.Cu")
		(at 113.494312 -132.456682 180)
		(property "Reference" "R3393"
			(at 0 0 180)
			(layer "F.SilkS")
			(hide yes)
			(effects
				(font
					(size 1.27 1.27)
				)
			)
		)
		(property "Value" ""
			(at 0 0 180)
			(layer "F.Fab")
			(effects
				(font
					(size 1.27 1.27)
				)
			)
		)
		(duplicate_pad_numbers_are_jumpers no)
		(fp_line
			(start 0.7874 0.4064)
			(end -0.7874 0.4064)
			(stroke
				(width 0.1524)
				(type default)
			)
			(layer "F.SilkS")
		)
		(fp_line
			(start 0.7874 -0.4064)
			(end 0.7874 0.4064)
			(stroke
				(width 0.1524)
				(type default)
			)
			(layer "F.SilkS")
		)
		(fp_line
			(start -0.7874 0.4064)
			(end -0.7874 -0.4064)
			(stroke
				(width 0.1524)
				(type default)
			)
			(layer "F.SilkS")
		)
		(fp_line
			(start -0.7874 -0.4064)
			(end 0.7874 -0.4064)
			(stroke
				(width 0.1524)
				(type default)
			)
			(layer "F.SilkS")
		)
		(fp_line
			(start 0.67945 0.3048)
			(end 0.120396 0.3048)
			(stroke
				(width 0.1)
				(type default)
			)
			(layer "F.Fab")
		)
		(fp_line
			(start 0.67945 -0.3048)
			(end 0.67945 0.3048)
			(stroke
				(width 0.1)
				(type default)
			)
			(layer "F.Fab")
		)
		(fp_line
			(start 0.12065 -0.2794)
			(end 0.12065 -0.3048)
			(stroke
				(width 0.1)
				(type default)
			)
			(layer "F.Fab")
		)
		(fp_line
			(start 0.12065 -0.3048)
			(end 0.67945 -0.3048)
			(stroke
				(width 0.1)
				(type default)
			)
			(layer "F.Fab")
		)
		(fp_line
			(start 0.120396 0.3048)
			(end 0.120396 0.2794)
			(stroke
				(width 0.1)
				(type default)
			)
			(layer "F.Fab")
		)
		(fp_line
			(start 0.120396 0.2794)
			(end -0.12065 0.2794)
			(stroke
				(width 0.1)
				(type default)
			)
			(layer "F.Fab")
		)
		(fp_line
			(start -0.12065 0.3048)
			(end -0.67945 0.3048)
			(stroke
				(width 0.1)
				(type default)
			)
			(layer "F.Fab")
		)
		(fp_line
			(start -0.12065 0.2794)
			(end -0.12065 0.3048)
			(stroke
				(width 0.1)
				(type default)
			)
			(layer "F.Fab")
		)
		(fp_line
			(start -0.12065 -0.2794)
			(end 0.12065 -0.2794)
			(stroke
				(width 0.1)
				(type default)
			)
			(layer "F.Fab")
		)
		(fp_line
			(start -0.12065 -0.305054)
			(end -0.12065 -0.2794)
			(stroke
				(width 0.1)
				(type default)
			)
			(layer "F.Fab")
		)
		(fp_line
			(start -0.67945 0.3048)
			(end -0.67945 -0.305054)
			(stroke
				(width 0.1)
				(type default)
			)
			(layer "F.Fab")
		)
		(fp_line
			(start -0.67945 -0.305054)
			(end -0.12065 -0.305054)
			(stroke
				(width 0.1)
				(type default)
			)
			(layer "F.Fab")
		)
		(pad "1" smd circle
			(at -0.40005 0 180)
			(size 0 0)
			(layers "F.Cu" "F.Mask" "F.Paste")
			(net "SMB_IOEXP_3V3AUX_SCL_R")
		)
		(pad "2" smd circle
			(at 0.40005 0 180)
			(size 0 0)
			(layers "F.Cu" "F.Mask" "F.Paste")
			(net "SMB_IOEXP_3V3AUX_SCL")
		)
	)
	(footprint ""
		(layer "F.Cu")
		(at 430.600104 -135.510778)
		(property "Reference" "R2597"
			(at 0 0 0)
			(layer "F.SilkS")
			(hide yes)
			(effects
				(font
					(size 1.27 1.27)
				)
			)
		)
		(property "Value" ""
			(at 0 0 0)
			(layer "F.Fab")
			(effects
				(font
					(size 1.27 1.27)
				)
			)
		)
		(duplicate_pad_numbers_are_jumpers no)
		(fp_line
			(start -0.7874 -0.4064)
			(end 0.7874 -0.4064)
			(stroke
				(width 0.1524)
				(type default)
			)
			(layer "F.SilkS")
		)
		(fp_line
			(start -0.7874 0.4064)
			(end -0.7874 -0.4064)
			(stroke
				(width 0.1524)
				(type default)
			)
			(layer "F.SilkS")
		)
		(fp_line
			(start 0.7874 -0.4064)
			(end 0.7874 0.4064)
			(stroke
				(width 0.1524)
				(type default)
			)
			(layer "F.SilkS")
		)
		(fp_line
			(start 0.7874 0.4064)
			(end -0.7874 0.4064)
			(stroke
				(width 0.1524)
				(type default)
			)
			(layer "F.SilkS")
		)
		(fp_line
			(start -0.67945 -0.305054)
			(end -0.12065 -0.305054)
			(stroke
				(width 0.1)
				(type default)
			)
			(layer "F.Fab")
		)
		(fp_line
			(start -0.67945 0.3048)
			(end -0.67945 -0.305054)
			(stroke
				(width 0.1)
				(type default)
			)
			(layer "F.Fab")
		)
		(fp_line
			(start -0.12065 -0.305054)
			(end -0.12065 -0.2794)
			(stroke
				(width 0.1)
				(type default)
			)
			(layer "F.Fab")
		)
		(fp_line
			(start -0.12065 -0.2794)
			(end 0.12065 -0.2794)
			(stroke
				(width 0.1)
				(type default)
			)
			(layer "F.Fab")
		)
		(fp_line
			(start -0.12065 0.2794)
			(end -0.12065 0.3048)
			(stroke
				(width 0.1)
				(type default)
			)
			(layer "F.Fab")
		)
		(fp_line
			(start -0.12065 0.3048)
			(end -0.67945 0.3048)
			(stroke
				(width 0.1)
				(type default)
			)
			(layer "F.Fab")
		)
		(fp_line
			(start 0.120396 0.2794)
			(end -0.12065 0.2794)
			(stroke
				(width 0.1)
				(type default)
			)
			(layer "F.Fab")
		)
		(fp_line
			(start 0.120396 0.3048)
			(end 0.120396 0.2794)
			(stroke
				(width 0.1)
				(type default)
			)
			(layer "F.Fab")
		)
		(fp_line
			(start 0.12065 -0.3048)
			(end 0.67945 -0.3048)
			(stroke
				(width 0.1)
				(type default)
			)
			(layer "F.Fab")
		)
		(fp_line
			(start 0.12065 -0.2794)
			(end 0.12065 -0.3048)
			(stroke
				(width 0.1)
				(type default)
			)
			(layer "F.Fab")
		)
		(fp_line
			(start 0.67945 -0.3048)
			(end 0.67945 0.3048)
			(stroke
				(width 0.1)
				(type default)
			)
			(layer "F.Fab")
		)
		(fp_line
			(start 0.67945 0.3048)
			(end 0.120396 0.3048)
			(stroke
				(width 0.1)
				(type default)
			)
			(layer "F.Fab")
		)
		(pad "1" smd circle
			(at -0.40005 0)
			(size 0 0)
			(layers "F.Cu" "F.Mask" "F.Paste")
			(net "IRQ_PVCCFA_CPU0_VRHOT_N")
		)
		(pad "2" smd circle
			(at 0.40005 0)
			(size 0 0)
			(layers "F.Cu" "F.Mask" "F.Paste")
			(net "IRQ_PVCCFA_CPU0_VRHOT_R_N")
		)
	)
	(footprint ""
		(layer "F.Cu")
		(at 495.422936 -427.608238 180)
		(property "Reference" "DB4"
			(at -2.717546 -0.136906 90)
			(unlocked yes)
			(layer "F.SilkS")
			(effects
				(font
					(size 0.7874 0.5842)
					(thickness 0.1524)
				)
				(justify left)
			)
		)
		(property "Value" ""
			(at 0 0 180)
			(layer "F.Fab")
			(effects
				(font
					(size 1.27 1.27)
				)
			)
		)
		(duplicate_pad_numbers_are_jumpers no)
		(fp_line
			(start 3.330702 -4.771136)
			(end 3.21564 -4.46786)
			(stroke
				(width 0.1524)
				(type default)
			)
			(layer "F.SilkS")
		)
		(fp_line
			(start 2.502916 -2.588514)
			(end 0 4.011168)
			(stroke
				(width 0.1524)
				(type default)
			)
			(layer "F.SilkS")
		)
		(fp_line
			(start 0 4.011168)
			(end -3.330702 -4.771136)
			(stroke
				(width 0.1524)
				(type default)
			)
			(layer "F.SilkS")
		)
		(fp_line
			(start -3.330702 -4.771136)
			(end 3.330702 -4.771136)
			(stroke
				(width 0.1524)
				(type default)
			)
			(layer "F.SilkS")
		)
		(fp_line
			(start 3.330702 -4.771136)
			(end 0 4.011168)
			(stroke
				(width 0.1)
				(type default)
			)
			(layer "F.Fab")
		)
		(fp_line
			(start 0 4.011168)
			(end -3.330702 -4.771136)
			(stroke
				(width 0.1)
				(type default)
			)
			(layer "F.Fab")
		)
		(fp_line
			(start -3.330702 -4.771136)
			(end 3.330702 -4.771136)
			(stroke
				(width 0.1)
				(type default)
			)
			(layer "F.Fab")
		)
		(pad "1" thru_hole circle
			(at 0 0 180)
			(size 2.159 2.159)
			(drill 1.7018)
			(layers "*.Cu" "*.Mask")
			(remove_unused_layers no)
			(net "T1_GND")
			(clearance 0.0254)
			(thermal_gap 0.0254)
		)
		(pad "2" thru_hole circle
			(at -1.27 -3.348736 180)
			(size 2.159 2.159)
			(drill 1.7018)
			(layers "*.Cu" "*.Mask")
			(remove_unused_layers no)
			(net "TDR_SE_40_OHM_IN3")
			(clearance 0.0254)
			(thermal_gap 0.0254)
		)
		(pad "3" thru_hole circle
			(at 1.27 -3.348736 180)
			(size 2.159 2.159)
			(drill 1.7018)
			(layers "*.Cu" "*.Mask")
			(remove_unused_layers no)
			(net "TDR_SE_40_OHM_IN3")
			(clearance 0.0254)
			(thermal_gap 0.0254)
		)
	)
	(footprint ""
		(layer "F.Cu")
		(at 392.163808 -38.829742)
		(property "Reference" "C581"
			(at 0 0 0)
			(layer "F.SilkS")
			(hide yes)
			(effects
				(font
					(size 1.27 1.27)
				)
			)
		)
		(property "Value" ""
			(at 0 0 0)
			(layer "F.Fab")
			(effects
				(font
					(size 1.27 1.27)
				)
			)
		)
		(duplicate_pad_numbers_are_jumpers no)
		(fp_line
			(start -0.7874 -0.4064)
			(end 0.7874 -0.4064)
			(stroke
				(width 0.1524)
				(type default)
			)
			(layer "F.SilkS")
		)
		(fp_line
			(start -0.7874 0.4064)
			(end -0.7874 -0.4064)
			(stroke
				(width 0.1524)
				(type default)
			)
			(layer "F.SilkS")
		)
		(fp_line
			(start 0.7874 -0.4064)
			(end 0.7874 0.4064)
			(stroke
				(width 0.1524)
				(type default)
			)
			(layer "F.SilkS")
		)
		(fp_line
			(start 0.7874 0.4064)
			(end -0.7874 0.4064)
			(stroke
				(width 0.1524)
				(type default)
			)
			(layer "F.SilkS")
		)
		(fp_line
			(start -0.67945 -0.305054)
			(end -0.12065 -0.305054)
			(stroke
				(width 0.1)
				(type default)
			)
			(layer "F.Fab")
		)
		(fp_line
			(start -0.67945 0.3048)
			(end -0.67945 -0.305054)
			(stroke
				(width 0.1)
				(type default)
			)
			(layer "F.Fab")
		)
		(fp_line
			(start -0.12065 -0.305054)
			(end -0.12065 -0.2794)
			(stroke
				(width 0.1)
				(type default)
			)
			(layer "F.Fab")
		)
		(fp_line
			(start -0.12065 -0.2794)
			(end 0.12065 -0.2794)
			(stroke
				(width 0.1)
				(type default)
			)
			(layer "F.Fab")
		)
		(fp_line
			(start -0.12065 0.2794)
			(end -0.12065 0.3048)
			(stroke
				(width 0.1)
				(type default)
			)
			(layer "F.Fab")
		)
		(fp_line
			(start -0.12065 0.3048)
			(end -0.67945 0.3048)
			(stroke
				(width 0.1)
				(type default)
			)
			(layer "F.Fab")
		)
		(fp_line
			(start 0.120396 0.2794)
			(end -0.12065 0.2794)
			(stroke
				(width 0.1)
				(type default)
			)
			(layer "F.Fab")
		)
		(fp_line
			(start 0.120396 0.3048)
			(end 0.120396 0.2794)
			(stroke
				(width 0.1)
				(type default)
			)
			(layer "F.Fab")
		)
		(fp_line
			(start 0.12065 -0.3048)
			(end 0.67945 -0.3048)
			(stroke
				(width 0.1)
				(type default)
			)
			(layer "F.Fab")
		)
		(fp_line
			(start 0.12065 -0.2794)
			(end 0.12065 -0.3048)
			(stroke
				(width 0.1)
				(type default)
			)
			(layer "F.Fab")
		)
		(fp_line
			(start 0.67945 -0.3048)
			(end 0.67945 0.3048)
			(stroke
				(width 0.1)
				(type default)
			)
			(layer "F.Fab")
		)
		(fp_line
			(start 0.67945 0.3048)
			(end 0.120396 0.3048)
			(stroke
				(width 0.1)
				(type default)
			)
			(layer "F.Fab")
		)
		(pad "1" smd circle
			(at -0.40005 0)
			(size 0 0)
			(layers "F.Cu" "F.Mask" "F.Paste")
			(net "P3V3_AUX")
		)
		(pad "2" smd circle
			(at 0.40005 0)
			(size 0 0)
			(layers "F.Cu" "F.Mask" "F.Paste")
			(net "GND")
		)
	)
	(footprint ""
		(layer "F.Cu")
		(at 250.53163 -394.17117)
		(property "Reference" "PR2536"
			(at 0 0 0)
			(layer "F.SilkS")
			(hide yes)
			(effects
				(font
					(size 1.27 1.27)
				)
			)
		)
		(property "Value" ""
			(at 0 0 0)
			(layer "F.Fab")
			(effects
				(font
					(size 1.27 1.27)
				)
			)
		)
		(duplicate_pad_numbers_are_jumpers no)
		(fp_line
			(start -0.7874 -0.4064)
			(end 0.7874 -0.4064)
			(stroke
				(width 0.1524)
				(type default)
			)
			(layer "F.SilkS")
		)
		(fp_line
			(start -0.7874 0.4064)
			(end -0.7874 -0.4064)
			(stroke
				(width 0.1524)
				(type default)
			)
			(layer "F.SilkS")
		)
		(fp_line
			(start 0.7874 -0.4064)
			(end 0.7874 0.4064)
			(stroke
				(width 0.1524)
				(type default)
			)
			(layer "F.SilkS")
		)
		(fp_line
			(start 0.7874 0.4064)
			(end -0.7874 0.4064)
			(stroke
				(width 0.1524)
				(type default)
			)
			(layer "F.SilkS")
		)
		(fp_line
			(start -0.67945 -0.305054)
			(end -0.12065 -0.305054)
			(stroke
				(width 0.1)
				(type default)
			)
			(layer "F.Fab")
		)
		(fp_line
			(start -0.67945 0.3048)
			(end -0.67945 -0.305054)
			(stroke
				(width 0.1)
				(type default)
			)
			(layer "F.Fab")
		)
		(fp_line
			(start -0.12065 -0.305054)
			(end -0.12065 -0.2794)
			(stroke
				(width 0.1)
				(type default)
			)
			(layer "F.Fab")
		)
		(fp_line
			(start -0.12065 -0.2794)
			(end 0.12065 -0.2794)
			(stroke
				(width 0.1)
				(type default)
			)
			(layer "F.Fab")
		)
		(fp_line
			(start -0.12065 0.2794)
			(end -0.12065 0.3048)
			(stroke
				(width 0.1)
				(type default)
			)
			(layer "F.Fab")
		)
		(fp_line
			(start -0.12065 0.3048)
			(end -0.67945 0.3048)
			(stroke
				(width 0.1)
				(type default)
			)
			(layer "F.Fab")
		)
		(fp_line
			(start 0.120396 0.2794)
			(end -0.12065 0.2794)
			(stroke
				(width 0.1)
				(type default)
			)
			(layer "F.Fab")
		)
		(fp_line
			(start 0.120396 0.3048)
			(end 0.120396 0.2794)
			(stroke
				(width 0.1)
				(type default)
			)
			(layer "F.Fab")
		)
		(fp_line
			(start 0.12065 -0.3048)
			(end 0.67945 -0.3048)
			(stroke
				(width 0.1)
				(type default)
			)
			(layer "F.Fab")
		)
		(fp_line
			(start 0.12065 -0.2794)
			(end 0.12065 -0.3048)
			(stroke
				(width 0.1)
				(type default)
			)
			(layer "F.Fab")
		)
		(fp_line
			(start 0.67945 -0.3048)
			(end 0.67945 0.3048)
			(stroke
				(width 0.1)
				(type default)
			)
			(layer "F.Fab")
		)
		(fp_line
			(start 0.67945 0.3048)
			(end 0.120396 0.3048)
			(stroke
				(width 0.1)
				(type default)
			)
			(layer "F.Fab")
		)
		(pad "1" smd circle
			(at -0.40005 0)
			(size 0 0)
			(layers "F.Cu" "F.Mask" "F.Paste")
			(net "P12V_HSC_GATE_G6")
		)
		(pad "2" smd circle
			(at 0.40005 0)
			(size 0 0)
			(layers "F.Cu" "F.Mask" "F.Paste")
			(net "P12V_HSC_GATE2")
		)
	)
	(footprint ""
		(layer "F.Cu")
		(at 104.352852 -255.0541 90)
		(property "Reference" "C241"
			(at 0 0 90)
			(layer "F.SilkS")
			(hide yes)
			(effects
				(font
					(size 1.27 1.27)
				)
			)
		)
		(property "Value" ""
			(at 0 0 90)
			(layer "F.Fab")
			(effects
				(font
					(size 1.27 1.27)
				)
			)
		)
		(duplicate_pad_numbers_are_jumpers no)
		(fp_line
			(start 0.7874 -0.4064)
			(end 0.7874 0.4064)
			(stroke
				(width 0.1524)
				(type default)
			)
			(layer "F.SilkS")
		)
		(fp_line
			(start -0.7874 -0.4064)
			(end 0.7874 -0.4064)
			(stroke
				(width 0.1524)
				(type default)
			)
			(layer "F.SilkS")
		)
		(fp_line
			(start 0.7874 0.4064)
			(end -0.7874 0.4064)
			(stroke
				(width 0.1524)
				(type default)
			)
			(layer "F.SilkS")
		)
		(fp_line
			(start -0.7874 0.4064)
			(end -0.7874 -0.4064)
			(stroke
				(width 0.1524)
				(type default)
			)
			(layer "F.SilkS")
		)
		(fp_line
			(start -0.12065 -0.305054)
			(end -0.12065 -0.2794)
			(stroke
				(width 0.1)
				(type default)
			)
			(layer "F.Fab")
		)
		(fp_line
			(start -0.67945 -0.305054)
			(end -0.12065 -0.305054)
			(stroke
				(width 0.1)
				(type default)
			)
			(layer "F.Fab")
		)
		(fp_line
			(start 0.67945 -0.3048)
			(end 0.67945 0.3048)
			(stroke
				(width 0.1)
				(type default)
			)
			(layer "F.Fab")
		)
		(fp_line
			(start 0.12065 -0.3048)
			(end 0.67945 -0.3048)
			(stroke
				(width 0.1)
				(type default)
			)
			(layer "F.Fab")
		)
		(fp_line
			(start 0.12065 -0.2794)
			(end 0.12065 -0.3048)
			(stroke
				(width 0.1)
				(type default)
			)
			(layer "F.Fab")
		)
		(fp_line
			(start -0.12065 -0.2794)
			(end 0.12065 -0.2794)
			(stroke
				(width 0.1)
				(type default)
			)
			(layer "F.Fab")
		)
		(fp_line
			(start 0.120396 0.2794)
			(end -0.12065 0.2794)
			(stroke
				(width 0.1)
				(type default)
			)
			(layer "F.Fab")
		)
		(fp_line
			(start -0.12065 0.2794)
			(end -0.12065 0.3048)
			(stroke
				(width 0.1)
				(type default)
			)
			(layer "F.Fab")
		)
		(fp_line
			(start 0.67945 0.3048)
			(end 0.120396 0.3048)
			(stroke
				(width 0.1)
				(type default)
			)
			(layer "F.Fab")
		)
		(fp_line
			(start 0.120396 0.3048)
			(end 0.120396 0.2794)
			(stroke
				(width 0.1)
				(type default)
			)
			(layer "F.Fab")
		)
		(fp_line
			(start -0.12065 0.3048)
			(end -0.67945 0.3048)
			(stroke
				(width 0.1)
				(type default)
			)
			(layer "F.Fab")
		)
		(fp_line
			(start -0.67945 0.3048)
			(end -0.67945 -0.305054)
			(stroke
				(width 0.1)
				(type default)
			)
			(layer "F.Fab")
		)
		(pad "1" smd circle
			(at -0.40005 0 90)
			(size 0 0)
			(layers "F.Cu" "F.Mask" "F.Paste")
			(net "PVCCIN_CPU1")
		)
		(pad "2" smd circle
			(at 0.40005 0 90)
			(size 0 0)
			(layers "F.Cu" "F.Mask" "F.Paste")
			(net "GND")
		)
	)
	(footprint ""
		(layer "F.Cu")
		(at 179.09032 -409.199588)
		(property "Reference" "R4530"
			(at 0 0 0)
			(layer "F.SilkS")
			(hide yes)
			(effects
				(font
					(size 1.27 1.27)
				)
			)
		)
		(property "Value" ""
			(at 0 0 0)
			(layer "F.Fab")
			(effects
				(font
					(size 1.27 1.27)
				)
			)
		)
		(duplicate_pad_numbers_are_jumpers no)
		(fp_line
			(start -0.7874 -0.4064)
			(end 0.7874 -0.4064)
			(stroke
				(width 0.1524)
				(type default)
			)
			(layer "F.SilkS")
		)
		(fp_line
			(start -0.7874 0.4064)
			(end -0.7874 -0.4064)
			(stroke
				(width 0.1524)
				(type default)
			)
			(layer "F.SilkS")
		)
		(fp_line
			(start 0.7874 -0.4064)
			(end 0.7874 0.4064)
			(stroke
				(width 0.1524)
				(type default)
			)
			(layer "F.SilkS")
		)
		(fp_line
			(start 0.7874 0.4064)
			(end -0.7874 0.4064)
			(stroke
				(width 0.1524)
				(type default)
			)
			(layer "F.SilkS")
		)
		(fp_line
			(start -0.67945 -0.305054)
			(end -0.12065 -0.305054)
			(stroke
				(width 0.1)
				(type default)
			)
			(layer "F.Fab")
		)
		(fp_line
			(start -0.67945 0.3048)
			(end -0.67945 -0.305054)
			(stroke
				(width 0.1)
				(type default)
			)
			(layer "F.Fab")
		)
		(fp_line
			(start -0.12065 -0.305054)
			(end -0.12065 -0.2794)
			(stroke
				(width 0.1)
				(type default)
			)
			(layer "F.Fab")
		)
		(fp_line
			(start -0.12065 -0.2794)
			(end 0.12065 -0.2794)
			(stroke
				(width 0.1)
				(type default)
			)
			(layer "F.Fab")
		)
		(fp_line
			(start -0.12065 0.2794)
			(end -0.12065 0.3048)
			(stroke
				(width 0.1)
				(type default)
			)
			(layer "F.Fab")
		)
		(fp_line
			(start -0.12065 0.3048)
			(end -0.67945 0.3048)
			(stroke
				(width 0.1)
				(type default)
			)
			(layer "F.Fab")
		)
		(fp_line
			(start 0.120396 0.2794)
			(end -0.12065 0.2794)
			(stroke
				(width 0.1)
				(type default)
			)
			(layer "F.Fab")
		)
		(fp_line
			(start 0.120396 0.3048)
			(end 0.120396 0.2794)
			(stroke
				(width 0.1)
				(type default)
			)
			(layer "F.Fab")
		)
		(fp_line
			(start 0.12065 -0.3048)
			(end 0.67945 -0.3048)
			(stroke
				(width 0.1)
				(type default)
			)
			(layer "F.Fab")
		)
		(fp_line
			(start 0.12065 -0.2794)
			(end 0.12065 -0.3048)
			(stroke
				(width 0.1)
				(type default)
			)
			(layer "F.Fab")
		)
		(fp_line
			(start 0.67945 -0.3048)
			(end 0.67945 0.3048)
			(stroke
				(width 0.1)
				(type default)
			)
			(layer "F.Fab")
		)
		(fp_line
			(start 0.67945 0.3048)
			(end 0.120396 0.3048)
			(stroke
				(width 0.1)
				(type default)
			)
			(layer "F.Fab")
		)
		(pad "1" smd circle
			(at -0.40005 0)
			(size 0 0)
			(layers "F.Cu" "F.Mask" "F.Paste")
			(net "SMB_SML1_PMBUS_HSC_SCL_R3")
		)
		(pad "2" smd circle
			(at 0.40005 0)
			(size 0 0)
			(layers "F.Cu" "F.Mask" "F.Paste")
			(net "SMB_SML1_PMBUS_HSC_SCL")
		)
	)
	(footprint ""
		(layer "F.Cu")
		(at 365.844328 -333.525368 -90)
		(property "Reference" "PC272_P0_4"
			(at 0 0 270)
			(layer "F.SilkS")
			(hide yes)
			(effects
				(font
					(size 1.27 1.27)
				)
			)
		)
		(property "Value" ""
			(at 0 0 270)
			(layer "F.Fab")
			(effects
				(font
					(size 1.27 1.27)
				)
			)
		)
		(duplicate_pad_numbers_are_jumpers no)
		(fp_line
			(start -0.7874 0.4064)
			(end -0.7874 -0.4064)
			(stroke
				(width 0.1524)
				(type default)
			)
			(layer "F.SilkS")
		)
		(fp_line
			(start 0.7874 0.4064)
			(end -0.7874 0.4064)
			(stroke
				(width 0.1524)
				(type default)
			)
			(layer "F.SilkS")
		)
		(fp_line
			(start -0.7874 -0.4064)
			(end 0.7874 -0.4064)
			(stroke
				(width 0.1524)
				(type default)
			)
			(layer "F.SilkS")
		)
		(fp_line
			(start 0.7874 -0.4064)
			(end 0.7874 0.4064)
			(stroke
				(width 0.1524)
				(type default)
			)
			(layer "F.SilkS")
		)
		(fp_line
			(start -0.67945 0.3048)
			(end -0.67945 -0.305054)
			(stroke
				(width 0.1)
				(type default)
			)
			(layer "F.Fab")
		)
		(fp_line
			(start -0.12065 0.3048)
			(end -0.67945 0.3048)
			(stroke
				(width 0.1)
				(type default)
			)
			(layer "F.Fab")
		)
		(fp_line
			(start 0.120396 0.3048)
			(end 0.120396 0.2794)
			(stroke
				(width 0.1)
				(type default)
			)
			(layer "F.Fab")
		)
		(fp_line
			(start 0.67945 0.3048)
			(end 0.120396 0.3048)
			(stroke
				(width 0.1)
				(type default)
			)
			(layer "F.Fab")
		)
		(fp_line
			(start -0.12065 0.2794)
			(end -0.12065 0.3048)
			(stroke
				(width 0.1)
				(type default)
			)
			(layer "F.Fab")
		)
		(fp_line
			(start 0.120396 0.2794)
			(end -0.12065 0.2794)
			(stroke
				(width 0.1)
				(type default)
			)
			(layer "F.Fab")
		)
		(fp_line
			(start -0.12065 -0.2794)
			(end 0.12065 -0.2794)
			(stroke
				(width 0.1)
				(type default)
			)
			(layer "F.Fab")
		)
		(fp_line
			(start 0.12065 -0.2794)
			(end 0.12065 -0.3048)
			(stroke
				(width 0.1)
				(type default)
			)
			(layer "F.Fab")
		)
		(fp_line
			(start 0.12065 -0.3048)
			(end 0.67945 -0.3048)
			(stroke
				(width 0.1)
				(type default)
			)
			(layer "F.Fab")
		)
		(fp_line
			(start 0.67945 -0.3048)
			(end 0.67945 0.3048)
			(stroke
				(width 0.1)
				(type default)
			)
			(layer "F.Fab")
		)
		(fp_line
			(start -0.67945 -0.305054)
			(end -0.12065 -0.305054)
			(stroke
				(width 0.1)
				(type default)
			)
			(layer "F.Fab")
		)
		(fp_line
			(start -0.12065 -0.305054)
			(end -0.12065 -0.2794)
			(stroke
				(width 0.1)
				(type default)
			)
			(layer "F.Fab")
		)
		(pad "1" smd circle
			(at -0.40005 0 270)
			(size 0 0)
			(layers "F.Cu" "F.Mask" "F.Paste")
			(net "PVCCIN_CPU0_PVCC")
		)
		(pad "2" smd circle
			(at 0.40005 0 270)
			(size 0 0)
			(layers "F.Cu" "F.Mask" "F.Paste")
			(net "GND")
		)
	)
	(footprint ""
		(layer "F.Cu")
		(at 128.016 -60.416948)
		(property "Reference" "R4635"
			(at 0 0 0)
			(layer "F.SilkS")
			(hide yes)
			(effects
				(font
					(size 1.27 1.27)
				)
			)
		)
		(property "Value" ""
			(at 0 0 0)
			(layer "F.Fab")
			(effects
				(font
					(size 1.27 1.27)
				)
			)
		)
		(duplicate_pad_numbers_are_jumpers no)
		(fp_line
			(start -0.7874 -0.4064)
			(end 0.7874 -0.4064)
			(stroke
				(width 0.1524)
				(type default)
			)
			(layer "F.SilkS")
		)
		(fp_line
			(start -0.7874 0.4064)
			(end -0.7874 -0.4064)
			(stroke
				(width 0.1524)
				(type default)
			)
			(layer "F.SilkS")
		)
		(fp_line
			(start 0.7874 -0.4064)
			(end 0.7874 0.4064)
			(stroke
				(width 0.1524)
				(type default)
			)
			(layer "F.SilkS")
		)
		(fp_line
			(start 0.7874 0.4064)
			(end -0.7874 0.4064)
			(stroke
				(width 0.1524)
				(type default)
			)
			(layer "F.SilkS")
		)
		(fp_line
			(start -0.67945 -0.305054)
			(end -0.12065 -0.305054)
			(stroke
				(width 0.1)
				(type default)
			)
			(layer "F.Fab")
		)
		(fp_line
			(start -0.67945 0.3048)
			(end -0.67945 -0.305054)
			(stroke
				(width 0.1)
				(type default)
			)
			(layer "F.Fab")
		)
		(fp_line
			(start -0.12065 -0.305054)
			(end -0.12065 -0.2794)
			(stroke
				(width 0.1)
				(type default)
			)
			(layer "F.Fab")
		)
		(fp_line
			(start -0.12065 -0.2794)
			(end 0.12065 -0.2794)
			(stroke
				(width 0.1)
				(type default)
			)
			(layer "F.Fab")
		)
		(fp_line
			(start -0.12065 0.2794)
			(end -0.12065 0.3048)
			(stroke
				(width 0.1)
				(type default)
			)
			(layer "F.Fab")
		)
		(fp_line
			(start -0.12065 0.3048)
			(end -0.67945 0.3048)
			(stroke
				(width 0.1)
				(type default)
			)
			(layer "F.Fab")
		)
		(fp_line
			(start 0.120396 0.2794)
			(end -0.12065 0.2794)
			(stroke
				(width 0.1)
				(type default)
			)
			(layer "F.Fab")
		)
		(fp_line
			(start 0.120396 0.3048)
			(end 0.120396 0.2794)
			(stroke
				(width 0.1)
				(type default)
			)
			(layer "F.Fab")
		)
		(fp_line
			(start 0.12065 -0.3048)
			(end 0.67945 -0.3048)
			(stroke
				(width 0.1)
				(type default)
			)
			(layer "F.Fab")
		)
		(fp_line
			(start 0.12065 -0.2794)
			(end 0.12065 -0.3048)
			(stroke
				(width 0.1)
				(type default)
			)
			(layer "F.Fab")
		)
		(fp_line
			(start 0.67945 -0.3048)
			(end 0.67945 0.3048)
			(stroke
				(width 0.1)
				(type default)
			)
			(layer "F.Fab")
		)
		(fp_line
			(start 0.67945 0.3048)
			(end 0.120396 0.3048)
			(stroke
				(width 0.1)
				(type default)
			)
			(layer "F.Fab")
		)
		(pad "1" smd circle
			(at -0.40005 0)
			(size 0 0)
			(layers "F.Cu" "F.Mask" "F.Paste")
			(net "JTAG_BMC_SW_OE")
		)
		(pad "2" smd circle
			(at 0.40005 0)
			(size 0 0)
			(layers "F.Cu" "F.Mask" "F.Paste")
			(net "GND")
		)
	)
	(footprint ""
		(layer "F.Cu")
		(at 12.786106 -105.50398 90)
		(property "Reference" "R2787"
			(at 0 0 90)
			(layer "F.SilkS")
			(hide yes)
			(effects
				(font
					(size 1.27 1.27)
				)
			)
		)
		(property "Value" ""
			(at 0 0 90)
			(layer "F.Fab")
			(effects
				(font
					(size 1.27 1.27)
				)
			)
		)
		(duplicate_pad_numbers_are_jumpers no)
		(fp_line
			(start 0.7874 -0.4064)
			(end 0.7874 0.4064)
			(stroke
				(width 0.1524)
				(type default)
			)
			(layer "F.SilkS")
		)
		(fp_line
			(start -0.7874 -0.4064)
			(end 0.06604 -0.4064)
			(stroke
				(width 0.1524)
				(type default)
			)
			(layer "F.SilkS")
		)
		(fp_line
			(start 0.7874 0.4064)
			(end -0.7874 0.4064)
			(stroke
				(width 0.1524)
				(type default)
			)
			(layer "F.SilkS")
		)
		(fp_line
			(start -0.12065 -0.305054)
			(end -0.12065 -0.2794)
			(stroke
				(width 0.1)
				(type default)
			)
			(layer "F.Fab")
		)
		(fp_line
			(start -0.67945 -0.305054)
			(end -0.12065 -0.305054)
			(stroke
				(width 0.1)
				(type default)
			)
			(layer "F.Fab")
		)
		(fp_line
			(start 0.67945 -0.3048)
			(end 0.67945 0.3048)
			(stroke
				(width 0.1)
				(type default)
			)
			(layer "F.Fab")
		)
		(fp_line
			(start 0.12065 -0.3048)
			(end 0.67945 -0.3048)
			(stroke
				(width 0.1)
				(type default)
			)
			(layer "F.Fab")
		)
		(fp_line
			(start 0.12065 -0.2794)
			(end 0.12065 -0.3048)
			(stroke
				(width 0.1)
				(type default)
			)
			(layer "F.Fab")
		)
		(fp_line
			(start -0.12065 -0.2794)
			(end 0.12065 -0.2794)
			(stroke
				(width 0.1)
				(type default)
			)
			(layer "F.Fab")
		)
		(fp_line
			(start 0.120396 0.2794)
			(end -0.12065 0.2794)
			(stroke
				(width 0.1)
				(type default)
			)
			(layer "F.Fab")
		)
		(fp_line
			(start -0.12065 0.2794)
			(end -0.12065 0.3048)
			(stroke
				(width 0.1)
				(type default)
			)
			(layer "F.Fab")
		)
		(fp_line
			(start 0.67945 0.3048)
			(end 0.120396 0.3048)
			(stroke
				(width 0.1)
				(type default)
			)
			(layer "F.Fab")
		)
		(fp_line
			(start 0.120396 0.3048)
			(end 0.120396 0.2794)
			(stroke
				(width 0.1)
				(type default)
			)
			(layer "F.Fab")
		)
		(fp_line
			(start -0.12065 0.3048)
			(end -0.67945 0.3048)
			(stroke
				(width 0.1)
				(type default)
			)
			(layer "F.Fab")
		)
		(fp_line
			(start -0.67945 0.3048)
			(end -0.67945 -0.305054)
			(stroke
				(width 0.1)
				(type default)
			)
			(layer "F.Fab")
		)
		(pad "1" smd rect
			(at -0.40005 0 270)
			(size 0.4572 0.508)
			(layers "F.Cu" "F.Mask" "F.Paste")
			(net "USB2_HUB_SWB_DN")
		)
		(pad "2" smd rect
			(at 0.40005 0 270)
			(size 0.4572 0.508)
			(layers "F.Cu" "F.Mask" "F.Paste")
			(net "USB2_HUB_BUF_SWB_R_DN")
		)
	)
	(footprint ""
		(layer "F.Cu")
		(at 121.47931 -333.716122)
		(property "Reference" "PU27_P1_4"
			(at 3.92049 -12.962636 0)
			(unlocked yes)
			(layer "F.SilkS")
			(effects
				(font
					(size 0.7874 0.5842)
					(thickness 0.1524)
				)
				(justify left)
			)
		)
		(property "Value" ""
			(at 0 0 0)
			(layer "F.Fab")
			(effects
				(font
					(size 1.27 1.27)
				)
			)
		)
		(duplicate_pad_numbers_are_jumpers no)
		(fp_line
			(start -2.500122 -2.999994)
			(end -2.24409 -2.999994)
			(stroke
				(width 0.1524)
				(type default)
			)
			(layer "F.SilkS")
		)
		(fp_line
			(start -2.500122 -2.529078)
			(end -2.500122 -2.999994)
			(stroke
				(width 0.1524)
				(type default)
			)
			(layer "F.SilkS")
		)
		(fp_line
			(start -2.500122 0.6604)
			(end -2.500122 0.229108)
			(stroke
				(width 0.1524)
				(type default)
			)
			(layer "F.SilkS")
		)
		(fp_line
			(start -2.500122 2.999994)
			(end -2.500122 2.339594)
			(stroke
				(width 0.1524)
				(type default)
			)
			(layer "F.SilkS")
		)
		(fp_line
			(start -2.2987 2.999994)
			(end -2.500122 2.999994)
			(stroke
				(width 0.1524)
				(type default)
			)
			(layer "F.SilkS")
		)
		(fp_line
			(start 2.31394 -2.999994)
			(end 2.500122 -2.999994)
			(stroke
				(width 0.1524)
				(type default)
			)
			(layer "F.SilkS")
		)
		(fp_line
			(start 2.500122 -2.999994)
			(end 2.500122 -2.44348)
			(stroke
				(width 0.1524)
				(type default)
			)
			(layer "F.SilkS")
		)
		(fp_line
			(start 2.500122 2.339594)
			(end 2.500122 2.999994)
			(stroke
				(width 0.1524)
				(type default)
			)
			(layer "F.SilkS")
		)
		(fp_line
			(start 2.500122 2.999994)
			(end 2.2987 2.999994)
			(stroke
				(width 0.1524)
				(type default)
			)
			(layer "F.SilkS")
		)
		(fp_poly
			(pts
				(xy -2.226818 -3.642868) (xy -2.734818 -2.626868) (xy -3.242818 -3.642868)
			)
			(stroke
				(width 0)
				(type default)
			)
			(fill yes)
			(layer "F.SilkS")
		)
		(fp_line
			(start -2.500122 -2.999994)
			(end 2.500122 -2.999994)
			(stroke
				(width 0.1)
				(type default)
			)
			(layer "F.Fab")
		)
		(fp_line
			(start -2.500122 2.999994)
			(end -2.500122 -2.999994)
			(stroke
				(width 0.1)
				(type default)
			)
			(layer "F.Fab")
		)
		(fp_line
			(start 2.500122 -2.999994)
			(end 2.500122 2.999994)
			(stroke
				(width 0.1)
				(type default)
			)
			(layer "F.Fab")
		)
		(fp_line
			(start 2.500122 2.999994)
			(end -2.500122 2.999994)
			(stroke
				(width 0.1)
				(type default)
			)
			(layer "F.Fab")
		)
		(fp_poly
			(pts
				(xy -4.218432 -2.783078) (xy -4.218432 -1.767078) (xy -3.202432 -2.275078)
			)
			(stroke
				(width 0)
				(type default)
			)
			(fill yes)
			(layer "F.Fab")
		)
		(pad "1" smd rect
			(at -2.400046 -2.275078 90)
			(size 0.2286 0.6096)
			(layers "F.Cu" "F.Mask" "F.Paste")
			(net "PVCCIN_CPU1_VOS4")
		)
		(pad "2" smd rect
			(at -2.400046 -1.82499 90)
			(size 0.2286 0.6096)
			(layers "F.Cu" "F.Mask" "F.Paste")
			(net "GND")
		)
		(pad "3" smd rect
			(at -2.400046 -1.374902 90)
			(size 0.2286 0.6096)
			(layers "F.Cu" "F.Mask" "F.Paste")
			(net "PVCCIN_CPU1_VDD4")
		)
		(pad "4" smd rect
			(at -2.400046 -0.925068 90)
			(size 0.2286 0.6096)
			(layers "F.Cu" "F.Mask" "F.Paste")
			(net "PVCCIN_CPU1_PVCC")
		)
		(pad "5" smd rect
			(at -2.400046 -0.47498 90)
			(size 0.2286 0.6096)
			(layers "F.Cu" "F.Mask" "F.Paste")
			(net "GND")
		)
		(pad "6" smd rect
			(at -2.400046 -0.024892 90)
			(size 0.2286 0.6096)
			(layers "F.Cu" "F.Mask" "F.Paste")
			(net "Net_8529")
		)
		(pad "7_9-20_24" smd circle
			(at 0 1.150112 90)
			(size 0 0)
			(layers "F.Cu" "F.Mask" "F.Paste")
			(net "GND")
		)
		(pad "10_19" smd rect
			(at 0 2.899918 90)
			(size 0.6096 4.318)
			(layers "F.Cu" "F.Mask" "F.Paste")
			(net "SW_PVCCIN_CPU1_SW4")
		)
		(pad "25_29" smd rect
			(at 1.549908 -1.279906 270)
			(size 2.0574 2.3114)
			(layers "F.Cu" "F.Mask" "F.Paste")
			(net "SW_P12V_PVCCIN_CPU1_FLT")
		)
		(pad "30" smd rect
			(at 2.05994 -2.899918)
			(size 0.2286 0.6096)
			(layers "F.Cu" "F.Mask" "F.Paste")
			(net "SW_P12V_PVCCIN_CPU1_FLT")
		)
		(pad "31" smd rect
			(at 1.610106 -2.899918)
			(size 0.2286 0.6096)
			(layers "F.Cu" "F.Mask" "F.Paste")
			(net "Net_8530")
		)
		(pad "32" smd rect
			(at 1.160018 -2.899918)
			(size 0.2286 0.6096)
			(layers "F.Cu" "F.Mask" "F.Paste")
			(net "SW_PVCCIN_CPU1_BOOTR4")
		)
		(pad "33" smd rect
			(at 0.70993 -2.899918)
			(size 0.2286 0.6096)
			(layers "F.Cu" "F.Mask" "F.Paste")
			(net "SW_PVCCIN_CPU1_BOOT4")
		)
		(pad "34" smd rect
			(at 0.260096 -2.899918)
			(size 0.2286 0.6096)
			(layers "F.Cu" "F.Mask" "F.Paste")
			(net "PVCCIN_CPU1_PWM4")
		)
		(pad "35" smd rect
			(at -0.189992 -2.899918)
			(size 0.2286 0.6096)
			(layers "F.Cu" "F.Mask" "F.Paste")
			(net "PVCCIN_CPU1_VDD4")
		)
		(pad "36" smd rect
			(at -0.64008 -2.899918)
			(size 0.2286 0.6096)
			(layers "F.Cu" "F.Mask" "F.Paste")
			(net "PVCCIN_CPU1_ATSEN")
		)
		(pad "37" smd rect
			(at -1.089914 -2.899918)
			(size 0.2286 0.6096)
			(layers "F.Cu" "F.Mask" "F.Paste")
			(net "PVCCIN_CPU1_LSET4")
		)
		(pad "38" smd rect
			(at -1.540002 -2.899918)
			(size 0.2286 0.6096)
			(layers "F.Cu" "F.Mask" "F.Paste")
			(net "PVCCIN_CPU1_IMON4")
		)
		(pad "39" smd rect
			(at -1.99009 -2.899918)
			(size 0.2286 0.6096)
			(layers "F.Cu" "F.Mask" "F.Paste")
			(net "PVCCIN_CPU1_VREF")
		)
		(pad "40" smd rect
			(at -0.87503 -1.27508)
			(size 1.7526 1.9558)
			(layers "F.Cu" "F.Mask" "F.Paste")
			(net "GND")
		)
		(pad "41" smd rect
			(at -1.525016 0.249936 270)
			(size 0.3048 0.4572)
			(layers "F.Cu" "F.Mask" "F.Paste")
			(net "Net_8528")
		)
		(zone
			(layer "F.Cu")
			(hatch none 0.5)
			(connect_pads
				(clearance 0)
			)
			(min_thickness 0.25)
			(keepout
				(tracks not_allowed)
				(vias allowed)
				(pads allowed)
				(copperpour not_allowed)
				(footprints allowed)
			)
			(placement
				(enabled no)
				(sheetname "")
			)
			(fill
				(thermal_gap 0.5)
				(thermal_bridge_width 0.5)
				(island_removal_mode 0)
			)
			(polygon
				(pts
					(xy 118.979188 -330.716128) (xy 118.979188 -331.465428) (xy 123.979432 -331.465428) (xy 123.979432 -330.716128)
					(xy 123.68911 -330.716128) (xy 123.68911 -331.171804) (xy 119.26951 -331.171804) (xy 119.26951 -330.716128)
				)
			)
		)
		(zone
			(layer "F.Cu")
			(hatch none 0.5)
			(connect_pads
				(clearance 0)
			)
			(min_thickness 0.25)
			(keepout
				(tracks not_allowed)
				(vias allowed)
				(pads allowed)
				(copperpour not_allowed)
				(footprints allowed)
			)
			(placement
				(enabled no)
				(sheetname "")
			)
			(fill
				(thermal_gap 0.5)
				(thermal_bridge_width 0.5)
				(island_removal_mode 0)
			)
			(polygon
				(pts
					(xy 119.434864 -334.020668) (xy 119.67718 -334.020668) (xy 119.67718 -333.962502) (xy 120.46458 -333.962502)
					(xy 120.46458 -333.619348) (xy 120.528588 -333.619348) (xy 120.528588 -332.966822) (xy 118.979188 -332.966822)
					(xy 118.979188 -333.423514) (xy 119.674894 -333.423514) (xy 119.674894 -333.262986) (xy 120.233694 -333.262986)
					(xy 120.233694 -333.669386) (xy 119.674894 -333.669386) (xy 119.674894 -333.448914) (xy 118.979188 -333.448914)
					(xy 118.979188 -333.575914) (xy 119.434864 -333.575914)
				)
			)
		)
	)
	(footprint ""
		(layer "F.Cu")
		(at 441.36564 -100.27158 90)
		(property "Reference" "R4747"
			(at 0 0 90)
			(layer "F.SilkS")
			(hide yes)
			(effects
				(font
					(size 1.27 1.27)
				)
			)
		)
		(property "Value" ""
			(at 0 0 90)
			(layer "F.Fab")
			(effects
				(font
					(size 1.27 1.27)
				)
			)
		)
		(duplicate_pad_numbers_are_jumpers no)
		(fp_line
			(start 0.7874 -0.4064)
			(end 0.7874 0.4064)
			(stroke
				(width 0.1524)
				(type default)
			)
			(layer "F.SilkS")
		)
		(fp_line
			(start -0.7874 -0.4064)
			(end 0.7874 -0.4064)
			(stroke
				(width 0.1524)
				(type default)
			)
			(layer "F.SilkS")
		)
		(fp_line
			(start 0.7874 0.4064)
			(end -0.7874 0.4064)
			(stroke
				(width 0.1524)
				(type default)
			)
			(layer "F.SilkS")
		)
		(fp_line
			(start -0.7874 0.4064)
			(end -0.7874 -0.4064)
			(stroke
				(width 0.1524)
				(type default)
			)
			(layer "F.SilkS")
		)
		(fp_line
			(start -0.12065 -0.305054)
			(end -0.12065 -0.2794)
			(stroke
				(width 0.1)
				(type default)
			)
			(layer "F.Fab")
		)
		(fp_line
			(start -0.67945 -0.305054)
			(end -0.12065 -0.305054)
			(stroke
				(width 0.1)
				(type default)
			)
			(layer "F.Fab")
		)
		(fp_line
			(start 0.67945 -0.3048)
			(end 0.67945 0.3048)
			(stroke
				(width 0.1)
				(type default)
			)
			(layer "F.Fab")
		)
		(fp_line
			(start 0.12065 -0.3048)
			(end 0.67945 -0.3048)
			(stroke
				(width 0.1)
				(type default)
			)
			(layer "F.Fab")
		)
		(fp_line
			(start 0.12065 -0.2794)
			(end 0.12065 -0.3048)
			(stroke
				(width 0.1)
				(type default)
			)
			(layer "F.Fab")
		)
		(fp_line
			(start -0.12065 -0.2794)
			(end 0.12065 -0.2794)
			(stroke
				(width 0.1)
				(type default)
			)
			(layer "F.Fab")
		)
		(fp_line
			(start 0.120396 0.2794)
			(end -0.12065 0.2794)
			(stroke
				(width 0.1)
				(type default)
			)
			(layer "F.Fab")
		)
		(fp_line
			(start -0.12065 0.2794)
			(end -0.12065 0.3048)
			(stroke
				(width 0.1)
				(type default)
			)
			(layer "F.Fab")
		)
		(fp_line
			(start 0.67945 0.3048)
			(end 0.120396 0.3048)
			(stroke
				(width 0.1)
				(type default)
			)
			(layer "F.Fab")
		)
		(fp_line
			(start 0.120396 0.3048)
			(end 0.120396 0.2794)
			(stroke
				(width 0.1)
				(type default)
			)
			(layer "F.Fab")
		)
		(fp_line
			(start -0.12065 0.3048)
			(end -0.67945 0.3048)
			(stroke
				(width 0.1)
				(type default)
			)
			(layer "F.Fab")
		)
		(fp_line
			(start -0.67945 0.3048)
			(end -0.67945 -0.305054)
			(stroke
				(width 0.1)
				(type default)
			)
			(layer "F.Fab")
		)
		(pad "1" smd circle
			(at -0.40005 0 90)
			(size 0 0)
			(layers "F.Cu" "F.Mask" "F.Paste")
			(net "OCP_SFF_AUX_PWR_PLD_EN")
		)
		(pad "2" smd circle
			(at 0.40005 0 90)
			(size 0 0)
			(layers "F.Cu" "F.Mask" "F.Paste")
			(net "OCP_SFF_AUX_PWR_PLD_EN_R")
		)
	)
	(footprint ""
		(layer "F.Cu")
		(at 436.608474 -103.768398 90)
		(property "Reference" "PR4525"
			(at 0 0 90)
			(layer "F.SilkS")
			(hide yes)
			(effects
				(font
					(size 1.27 1.27)
				)
			)
		)
		(property "Value" ""
			(at 0 0 90)
			(layer "F.Fab")
			(effects
				(font
					(size 1.27 1.27)
				)
			)
		)
		(duplicate_pad_numbers_are_jumpers no)
		(fp_line
			(start 0.7874 -0.4064)
			(end 0.7874 0.4064)
			(stroke
				(width 0.1524)
				(type default)
			)
			(layer "F.SilkS")
		)
		(fp_line
			(start -0.7874 -0.4064)
			(end 0.7874 -0.4064)
			(stroke
				(width 0.1524)
				(type default)
			)
			(layer "F.SilkS")
		)
		(fp_line
			(start 0.7874 0.4064)
			(end -0.7874 0.4064)
			(stroke
				(width 0.1524)
				(type default)
			)
			(layer "F.SilkS")
		)
		(fp_line
			(start -0.7874 0.4064)
			(end -0.7874 -0.4064)
			(stroke
				(width 0.1524)
				(type default)
			)
			(layer "F.SilkS")
		)
		(fp_line
			(start -0.12065 -0.305054)
			(end -0.12065 -0.2794)
			(stroke
				(width 0.1)
				(type default)
			)
			(layer "F.Fab")
		)
		(fp_line
			(start -0.67945 -0.305054)
			(end -0.12065 -0.305054)
			(stroke
				(width 0.1)
				(type default)
			)
			(layer "F.Fab")
		)
		(fp_line
			(start 0.67945 -0.3048)
			(end 0.67945 0.3048)
			(stroke
				(width 0.1)
				(type default)
			)
			(layer "F.Fab")
		)
		(fp_line
			(start 0.12065 -0.3048)
			(end 0.67945 -0.3048)
			(stroke
				(width 0.1)
				(type default)
			)
			(layer "F.Fab")
		)
		(fp_line
			(start 0.12065 -0.2794)
			(end 0.12065 -0.3048)
			(stroke
				(width 0.1)
				(type default)
			)
			(layer "F.Fab")
		)
		(fp_line
			(start -0.12065 -0.2794)
			(end 0.12065 -0.2794)
			(stroke
				(width 0.1)
				(type default)
			)
			(layer "F.Fab")
		)
		(fp_line
			(start 0.120396 0.2794)
			(end -0.12065 0.2794)
			(stroke
				(width 0.1)
				(type default)
			)
			(layer "F.Fab")
		)
		(fp_line
			(start -0.12065 0.2794)
			(end -0.12065 0.3048)
			(stroke
				(width 0.1)
				(type default)
			)
			(layer "F.Fab")
		)
		(fp_line
			(start 0.67945 0.3048)
			(end 0.120396 0.3048)
			(stroke
				(width 0.1)
				(type default)
			)
			(layer "F.Fab")
		)
		(fp_line
			(start 0.120396 0.3048)
			(end 0.120396 0.2794)
			(stroke
				(width 0.1)
				(type default)
			)
			(layer "F.Fab")
		)
		(fp_line
			(start -0.12065 0.3048)
			(end -0.67945 0.3048)
			(stroke
				(width 0.1)
				(type default)
			)
			(layer "F.Fab")
		)
		(fp_line
			(start -0.67945 0.3048)
			(end -0.67945 -0.305054)
			(stroke
				(width 0.1)
				(type default)
			)
			(layer "F.Fab")
		)
		(pad "1" smd circle
			(at -0.40005 0 90)
			(size 0 0)
			(layers "F.Cu" "F.Mask" "F.Paste")
			(net "P3V3_OCP_SFF_R")
		)
		(pad "2" smd circle
			(at 0.40005 0 90)
			(size 0 0)
			(layers "F.Cu" "F.Mask" "F.Paste")
			(net "P3V3_OCP_GATE_PU202_1")
		)
	)
	(footprint ""
		(layer "F.Cu")
		(at 174.613062 -32.935672 90)
		(property "Reference" "PC2235"
			(at 0 0 90)
			(layer "F.SilkS")
			(hide yes)
			(effects
				(font
					(size 1.27 1.27)
				)
			)
		)
		(property "Value" ""
			(at 0 0 90)
			(layer "F.Fab")
			(effects
				(font
					(size 1.27 1.27)
				)
			)
		)
		(duplicate_pad_numbers_are_jumpers no)
		(fp_line
			(start 0.7874 -0.4064)
			(end 0.7874 0.4064)
			(stroke
				(width 0.1524)
				(type default)
			)
			(layer "F.SilkS")
		)
		(fp_line
			(start -0.7874 -0.4064)
			(end 0.7874 -0.4064)
			(stroke
				(width 0.1524)
				(type default)
			)
			(layer "F.SilkS")
		)
		(fp_line
			(start 0.7874 0.4064)
			(end -0.7874 0.4064)
			(stroke
				(width 0.1524)
				(type default)
			)
			(layer "F.SilkS")
		)
		(fp_line
			(start -0.7874 0.4064)
			(end -0.7874 -0.4064)
			(stroke
				(width 0.1524)
				(type default)
			)
			(layer "F.SilkS")
		)
		(fp_line
			(start -0.12065 -0.305054)
			(end -0.12065 -0.2794)
			(stroke
				(width 0.1)
				(type default)
			)
			(layer "F.Fab")
		)
		(fp_line
			(start -0.67945 -0.305054)
			(end -0.12065 -0.305054)
			(stroke
				(width 0.1)
				(type default)
			)
			(layer "F.Fab")
		)
		(fp_line
			(start 0.67945 -0.3048)
			(end 0.67945 0.3048)
			(stroke
				(width 0.1)
				(type default)
			)
			(layer "F.Fab")
		)
		(fp_line
			(start 0.12065 -0.3048)
			(end 0.67945 -0.3048)
			(stroke
				(width 0.1)
				(type default)
			)
			(layer "F.Fab")
		)
		(fp_line
			(start 0.12065 -0.2794)
			(end 0.12065 -0.3048)
			(stroke
				(width 0.1)
				(type default)
			)
			(layer "F.Fab")
		)
		(fp_line
			(start -0.12065 -0.2794)
			(end 0.12065 -0.2794)
			(stroke
				(width 0.1)
				(type default)
			)
			(layer "F.Fab")
		)
		(fp_line
			(start 0.120396 0.2794)
			(end -0.12065 0.2794)
			(stroke
				(width 0.1)
				(type default)
			)
			(layer "F.Fab")
		)
		(fp_line
			(start -0.12065 0.2794)
			(end -0.12065 0.3048)
			(stroke
				(width 0.1)
				(type default)
			)
			(layer "F.Fab")
		)
		(fp_line
			(start 0.67945 0.3048)
			(end 0.120396 0.3048)
			(stroke
				(width 0.1)
				(type default)
			)
			(layer "F.Fab")
		)
		(fp_line
			(start 0.120396 0.3048)
			(end 0.120396 0.2794)
			(stroke
				(width 0.1)
				(type default)
			)
			(layer "F.Fab")
		)
		(fp_line
			(start -0.12065 0.3048)
			(end -0.67945 0.3048)
			(stroke
				(width 0.1)
				(type default)
			)
			(layer "F.Fab")
		)
		(fp_line
			(start -0.67945 0.3048)
			(end -0.67945 -0.305054)
			(stroke
				(width 0.1)
				(type default)
			)
			(layer "F.Fab")
		)
		(pad "1" smd circle
			(at -0.40005 0 90)
			(size 0 0)
			(layers "F.Cu" "F.Mask" "F.Paste")
			(net "P12V_SCM_IMON")
		)
		(pad "2" smd circle
			(at 0.40005 0 90)
			(size 0 0)
			(layers "F.Cu" "F.Mask" "F.Paste")
			(net "GND")
		)
	)
	(footprint ""
		(layer "F.Cu")
		(at 132.08 -70.749922 -90)
		(property "Reference" "J43"
			(at -1.860296 7.31012 0)
			(unlocked yes)
			(layer "F.SilkS")
			(effects
				(font
					(size 0.7874 0.5842)
					(thickness 0.1524)
				)
				(justify left)
			)
		)
		(property "Value" ""
			(at 0 0 270)
			(layer "F.Fab")
			(effects
				(font
					(size 1.27 1.27)
				)
			)
		)
		(duplicate_pad_numbers_are_jumpers no)
		(fp_line
			(start -1.249934 19.100038)
			(end -1.249934 -1.320038)
			(stroke
				(width 0.1524)
				(type default)
			)
			(layer "F.SilkS")
		)
		(fp_line
			(start 1.249934 19.100038)
			(end -1.249934 19.100038)
			(stroke
				(width 0.1524)
				(type default)
			)
			(layer "F.SilkS")
		)
		(fp_line
			(start -1.249934 -1.320038)
			(end 1.249934 -1.320038)
			(stroke
				(width 0.1524)
				(type default)
			)
			(layer "F.SilkS")
		)
		(fp_line
			(start 1.249934 -1.320038)
			(end 1.249934 19.100038)
			(stroke
				(width 0.1524)
				(type default)
			)
			(layer "F.SilkS")
		)
		(fp_poly
			(pts
				(xy 2.807208 0.48641) (xy 1.529842 -0.1524) (xy 2.807208 -0.79121)
			)
			(stroke
				(width 0)
				(type default)
			)
			(fill yes)
			(layer "F.SilkS")
		)
		(fp_line
			(start -1.249934 19.100038)
			(end -1.249934 -1.320038)
			(stroke
				(width 0.1)
				(type default)
			)
			(layer "F.Fab")
		)
		(fp_line
			(start 1.249934 19.100038)
			(end -1.249934 19.100038)
			(stroke
				(width 0.1)
				(type default)
			)
			(layer "F.Fab")
		)
		(fp_line
			(start -1.249934 -1.320038)
			(end 1.249934 -1.320038)
			(stroke
				(width 0.1)
				(type default)
			)
			(layer "F.Fab")
		)
		(fp_line
			(start 1.249934 -1.320038)
			(end 1.249934 19.100038)
			(stroke
				(width 0.1)
				(type default)
			)
			(layer "F.Fab")
		)
		(fp_poly
			(pts
				(xy -2.7432 0.63881) (xy -2.7432 -0.63881) (xy -1.465834 0)
			)
			(stroke
				(width 0)
				(type default)
			)
			(fill yes)
			(layer "F.Fab")
		)
		(fp_text user "8"
			(at -1.7526 17.80667 270)
			(unlocked yes)
			(layer "F.SilkS")
			(effects
				(font
					(size 0.7874 0.5842)
					(thickness 0.1524)
				)
			)
		)
		(fp_text user "8"
			(at 1.881124 17.759934 0)
			(unlocked yes)
			(layer "B.SilkS")
			(effects
				(font
					(size 0.7874 0.5842)
					(thickness 0.1524)
				)
				(justify mirror)
			)
		)
		(fp_text user "1"
			(at 1.878584 -0.068326 0)
			(unlocked yes)
			(layer "B.SilkS")
			(effects
				(font
					(size 0.7874 0.5842)
					(thickness 0.1524)
				)
				(justify mirror)
			)
		)
		(fp_text user "8"
			(at -1.1938 17.80667 270)
			(unlocked yes)
			(layer "B.Fab")
			(effects
				(font
					(size 0.7874 0.5842)
					(thickness 0.1524)
				)
				(justify mirror)
			)
		)
		(fp_text user "1"
			(at -1.1176 -0.02413 270)
			(unlocked yes)
			(layer "B.Fab")
			(effects
				(font
					(size 0.7874 0.5842)
					(thickness 0.1524)
				)
				(justify mirror)
			)
		)
		(fp_text user "8"
			(at -1.7526 17.80667 270)
			(unlocked yes)
			(layer "F.Fab")
			(effects
				(font
					(size 0.7874 0.5842)
					(thickness 0.1524)
				)
			)
		)
		(pad "1" thru_hole rect
			(at 0 0 270)
			(size 1.5494 1.5494)
			(drill 1.0414)
			(layers "*.Cu" "*.Mask")
			(remove_unused_layers no)
			(net "P3V3_AUX_BMC_D")
			(clearance 0)
			(padstack
				(mode front_inner_back)
				(layer "Inner"
					(shape circle)
					(size 1.5494 1.5494)
					(clearance 0)
				)
				(layer "B.Cu"
					(shape rect)
					(size 1.5494 1.5494)
					(clearance 0)
				)
			)
		)
		(pad "2" thru_hole circle
			(at 0 2.54 270)
			(size 1.5494 1.5494)
			(drill 1.0414)
			(layers "*.Cu" "*.Mask")
			(remove_unused_layers no)
			(net "JTAG_BMC_PLD_TDO")
			(clearance 0)
		)
		(pad "3" thru_hole circle
			(at 0 5.08 270)
			(size 1.5494 1.5494)
			(drill 1.0414)
			(layers "*.Cu" "*.Mask")
			(remove_unused_layers no)
			(net "JTAG_BMC_PLD_TDI")
			(clearance 0)
		)
		(pad "4" thru_hole circle
			(at 0 7.62 270)
			(size 1.5494 1.5494)
			(drill 1.0414)
			(layers "*.Cu" "*.Mask")
			(remove_unused_layers no)
			(net "TP_PLD_CONN_P4")
			(clearance 0)
		)
		(pad "5" thru_hole circle
			(at 0 10.16 270)
			(size 1.5494 1.5494)
			(drill 1.0414)
			(layers "*.Cu" "*.Mask")
			(remove_unused_layers no)
			(net "TP_PLD_CONN_P5")
			(clearance 0)
		)
		(pad "6" thru_hole circle
			(at 0 12.7 270)
			(size 1.5494 1.5494)
			(drill 1.0414)
			(layers "*.Cu" "*.Mask")
			(remove_unused_layers no)
			(net "JTAG_BMC_PLD_TMS")
			(clearance 0)
		)
		(pad "7" thru_hole circle
			(at 0 15.24 270)
			(size 1.5494 1.5494)
			(drill 1.0414)
			(layers "*.Cu" "*.Mask")
			(remove_unused_layers no)
			(net "GND")
			(clearance 0)
		)
		(pad "8" thru_hole circle
			(at 0 17.78 270)
			(size 1.5494 1.5494)
			(drill 1.0414)
			(layers "*.Cu" "*.Mask")
			(remove_unused_layers no)
			(net "JTAG_BMC_PLD_TCK")
			(clearance 0)
		)
	)
	(footprint ""
		(layer "F.Cu")
		(at 225.933 -227.929948 90)
		(property "Reference" "U31"
			(at 0.22733 -5.08 0)
			(unlocked yes)
			(layer "F.SilkS")
			(effects
				(font
					(size 0.7874 0.5842)
					(thickness 0.1524)
				)
				(justify left)
			)
		)
		(property "Value" ""
			(at 0 0 90)
			(layer "F.Fab")
			(effects
				(font
					(size 1.27 1.27)
				)
			)
		)
		(duplicate_pad_numbers_are_jumpers no)
		(fp_line
			(start 1.4224 -2.5146)
			(end 0.4572 -2.5146)
			(stroke
				(width 0.1524)
				(type default)
			)
			(layer "F.SilkS")
		)
		(fp_line
			(start 0.4572 -2.5146)
			(end 0 -2.0574)
			(stroke
				(width 0.1524)
				(type default)
			)
			(layer "F.SilkS")
		)
		(fp_line
			(start -0.4572 -2.5146)
			(end -1.4224 -2.5146)
			(stroke
				(width 0.1524)
				(type default)
			)
			(layer "F.SilkS")
		)
		(fp_line
			(start -1.4224 -2.5146)
			(end -1.4224 2.5146)
			(stroke
				(width 0.1524)
				(type default)
			)
			(layer "F.SilkS")
		)
		(fp_line
			(start 0 -2.0574)
			(end -0.4572 -2.5146)
			(stroke
				(width 0.1524)
				(type default)
			)
			(layer "F.SilkS")
		)
		(fp_line
			(start 1.4224 2.5146)
			(end 1.4224 -2.5146)
			(stroke
				(width 0.1524)
				(type default)
			)
			(layer "F.SilkS")
		)
		(fp_line
			(start -1.4224 2.5146)
			(end 1.4224 2.5146)
			(stroke
				(width 0.1524)
				(type default)
			)
			(layer "F.SilkS")
		)
		(fp_poly
			(pts
				(xy -3.069844 -3.694938) (xy -2.307844 -3.694938) (xy -2.688844 -2.932938)
			)
			(stroke
				(width 0)
				(type default)
			)
			(fill yes)
			(layer "F.SilkS")
		)
		(fp_line
			(start 2.0066 -2.5146)
			(end -2.0066 -2.5146)
			(stroke
				(width 0.1)
				(type default)
			)
			(layer "F.Fab")
		)
		(fp_line
			(start -2.0066 -2.5146)
			(end -2.0066 -2.114804)
			(stroke
				(width 0.1)
				(type default)
			)
			(layer "F.Fab")
		)
		(fp_line
			(start -2.0066 -2.114804)
			(end -2.648712 -2.114804)
			(stroke
				(width 0.1)
				(type default)
			)
			(layer "F.Fab")
		)
		(fp_line
			(start -2.648712 -2.114804)
			(end -2.648712 2.112264)
			(stroke
				(width 0.1)
				(type default)
			)
			(layer "F.Fab")
		)
		(fp_line
			(start 2.642616 -2.112264)
			(end 2.0066 -2.112264)
			(stroke
				(width 0.1)
				(type default)
			)
			(layer "F.Fab")
		)
		(fp_line
			(start 2.0066 -2.112264)
			(end 2.0066 -2.5146)
			(stroke
				(width 0.1)
				(type default)
			)
			(layer "F.Fab")
		)
		(fp_line
			(start 2.642616 2.112264)
			(end 2.642616 -2.112264)
			(stroke
				(width 0.1)
				(type default)
			)
			(layer "F.Fab")
		)
		(fp_line
			(start 2.0066 2.112264)
			(end 2.642616 2.112264)
			(stroke
				(width 0.1)
				(type default)
			)
			(layer "F.Fab")
		)
		(fp_line
			(start -2.0066 2.112264)
			(end -2.0066 2.5146)
			(stroke
				(width 0.1)
				(type default)
			)
			(layer "F.Fab")
		)
		(fp_line
			(start -2.648712 2.112264)
			(end -2.0066 2.112264)
			(stroke
				(width 0.1)
				(type default)
			)
			(layer "F.Fab")
		)
		(fp_line
			(start 2.0066 2.5146)
			(end 2.0066 2.112264)
			(stroke
				(width 0.1)
				(type default)
			)
			(layer "F.Fab")
		)
		(fp_line
			(start -2.0066 2.5146)
			(end 2.0066 2.5146)
			(stroke
				(width 0.1)
				(type default)
			)
			(layer "F.Fab")
		)
		(fp_poly
			(pts
				(xy -3.6322 -1.869186) (xy -4.3942 -1.488186) (xy -4.3942 -2.250186)
			)
			(stroke
				(width 0)
				(type default)
			)
			(fill yes)
			(layer "F.Fab")
		)
		(pad "1" smd rect
			(at -2.6416 -1.905)
			(size 0.5588 1.7272)
			(layers "F.Cu" "F.Mask" "F.Paste")
			(net "PVNN_TERM_CPU1")
		)
		(pad "2" smd rect
			(at -2.6416 -0.635)
			(size 0.5588 1.7272)
			(layers "F.Cu" "F.Mask" "F.Paste")
			(net "SMB_S3M_CPU1_R_SCL")
		)
		(pad "3" smd rect
			(at -2.6416 0.635)
			(size 0.5588 1.7272)
			(layers "F.Cu" "F.Mask" "F.Paste")
			(net "SMB_S3M_CPU1_R_SDA")
		)
		(pad "4" smd rect
			(at -2.6416 1.905)
			(size 0.5588 1.7272)
			(layers "F.Cu" "F.Mask" "F.Paste")
			(net "GND")
		)
		(pad "5" smd rect
			(at 2.6416 1.905)
			(size 0.5588 1.7272)
			(layers "F.Cu" "F.Mask" "F.Paste")
			(net "TP_SMB_S3M_CPU1_EN")
		)
		(pad "6" smd rect
			(at 2.6416 0.635)
			(size 0.5588 1.7272)
			(layers "F.Cu" "F.Mask" "F.Paste")
			(net "SMB_S3M_CPU1_3V3AUX_SDA")
		)
		(pad "7" smd rect
			(at 2.6416 -0.635)
			(size 0.5588 1.7272)
			(layers "F.Cu" "F.Mask" "F.Paste")
			(net "SMB_S3M_CPU1_3V3AUX_SCL")
		)
		(pad "8" smd rect
			(at 2.6416 -1.905)
			(size 0.5588 1.7272)
			(layers "F.Cu" "F.Mask" "F.Paste")
			(net "P3V3_AUX")
		)
	)
	(footprint ""
		(layer "F.Cu")
		(at 62.48273 -40.031162)
		(property "Reference" "Q119"
			(at -0.89789 -2.121916 0)
			(unlocked yes)
			(layer "F.SilkS")
			(effects
				(font
					(size 0.7874 0.5842)
					(thickness 0.1524)
				)
				(justify left)
			)
		)
		(property "Value" ""
			(at 0 0 0)
			(layer "F.Fab")
			(effects
				(font
					(size 1.27 1.27)
				)
			)
		)
		(duplicate_pad_numbers_are_jumpers no)
		(fp_line
			(start -1.332738 -1.100074)
			(end -0.4826 -1.100074)
			(stroke
				(width 0.1524)
				(type default)
			)
			(layer "F.SilkS")
		)
		(fp_line
			(start -1.332738 1.100074)
			(end -1.332738 -1.100074)
			(stroke
				(width 0.1524)
				(type default)
			)
			(layer "F.SilkS")
		)
		(fp_line
			(start -0.4826 -1.100074)
			(end 0 -0.541274)
			(stroke
				(width 0.1524)
				(type default)
			)
			(layer "F.SilkS")
		)
		(fp_line
			(start 0 -0.541274)
			(end 0.4826 -1.100074)
			(stroke
				(width 0.1524)
				(type default)
			)
			(layer "F.SilkS")
		)
		(fp_line
			(start 0.4826 -1.100074)
			(end 1.332738 -1.100074)
			(stroke
				(width 0.1524)
				(type default)
			)
			(layer "F.SilkS")
		)
		(fp_line
			(start 1.332738 -1.100074)
			(end 1.332738 1.100074)
			(stroke
				(width 0.1524)
				(type default)
			)
			(layer "F.SilkS")
		)
		(fp_line
			(start 1.332738 1.100074)
			(end -1.332738 1.100074)
			(stroke
				(width 0.1524)
				(type default)
			)
			(layer "F.SilkS")
		)
		(fp_poly
			(pts
				(xy -2.2352 -1.001014) (xy -1.533144 -0.649986) (xy -2.2352 -0.298958)
			)
			(stroke
				(width 0)
				(type default)
			)
			(fill yes)
			(layer "F.SilkS")
		)
		(fp_line
			(start -0.674878 -1.100074)
			(end 0.674878 -1.100074)
			(stroke
				(width 0.1)
				(type default)
			)
			(layer "F.Fab")
		)
		(fp_line
			(start -0.674878 1.100074)
			(end -0.674878 -1.100074)
			(stroke
				(width 0.1)
				(type default)
			)
			(layer "F.Fab")
		)
		(fp_line
			(start 0.674878 -1.100074)
			(end 0.674878 1.100074)
			(stroke
				(width 0.1)
				(type default)
			)
			(layer "F.Fab")
		)
		(fp_line
			(start 0.674878 1.100074)
			(end -0.674878 1.100074)
			(stroke
				(width 0.1)
				(type default)
			)
			(layer "F.Fab")
		)
		(fp_poly
			(pts
				(xy -2.2352 -0.298958) (xy -2.2352 -1.001014) (xy -1.533144 -0.649986)
			)
			(stroke
				(width 0)
				(type default)
			)
			(fill yes)
			(layer "F.Fab")
		)
		(pad "1" smd rect
			(at -0.94996 -0.649986 90)
			(size 0.4318 0.508)
			(layers "F.Cu" "F.Mask" "F.Paste")
			(net "GND")
		)
		(pad "2" smd rect
			(at -0.94996 0 90)
			(size 0.4318 0.508)
			(layers "F.Cu" "F.Mask" "F.Paste")
			(net "P3V3_OCP_EN_2_R")
		)
		(pad "3" smd rect
			(at -0.94996 0.649986 90)
			(size 0.4318 0.508)
			(layers "F.Cu" "F.Mask" "F.Paste")
			(net "P3V3_OCP_UV_2_R1")
		)
		(pad "4" smd rect
			(at 0.94996 0.649986 90)
			(size 0.4318 0.508)
			(layers "F.Cu" "F.Mask" "F.Paste")
			(net "GND")
		)
		(pad "5" smd rect
			(at 0.94996 0 90)
			(size 0.4318 0.508)
			(layers "F.Cu" "F.Mask" "F.Paste")
			(net "P3V3_OCP_2_EN_G")
		)
		(pad "6" smd rect
			(at 0.94996 -0.649986 90)
			(size 0.4318 0.508)
			(layers "F.Cu" "F.Mask" "F.Paste")
			(net "P3V3_OCP_2_EN_G")
		)
	)
	(footprint ""
		(layer "F.Cu")
		(at 32.145732 -412.069534 180)
		(property "Reference" "R3474"
			(at 0 0 180)
			(layer "F.SilkS")
			(hide yes)
			(effects
				(font
					(size 1.27 1.27)
				)
			)
		)
		(property "Value" ""
			(at 0 0 180)
			(layer "F.Fab")
			(effects
				(font
					(size 1.27 1.27)
				)
			)
		)
		(duplicate_pad_numbers_are_jumpers no)
		(fp_line
			(start 0.7874 0.4064)
			(end -0.7874 0.4064)
			(stroke
				(width 0.1524)
				(type default)
			)
			(layer "F.SilkS")
		)
		(fp_line
			(start 0.7874 -0.4064)
			(end 0.7874 0.4064)
			(stroke
				(width 0.1524)
				(type default)
			)
			(layer "F.SilkS")
		)
		(fp_line
			(start -0.7874 0.4064)
			(end -0.7874 -0.4064)
			(stroke
				(width 0.1524)
				(type default)
			)
			(layer "F.SilkS")
		)
		(fp_line
			(start -0.7874 -0.4064)
			(end 0.7874 -0.4064)
			(stroke
				(width 0.1524)
				(type default)
			)
			(layer "F.SilkS")
		)
		(fp_line
			(start 0.67945 0.3048)
			(end 0.120396 0.3048)
			(stroke
				(width 0.1)
				(type default)
			)
			(layer "F.Fab")
		)
		(fp_line
			(start 0.67945 -0.3048)
			(end 0.67945 0.3048)
			(stroke
				(width 0.1)
				(type default)
			)
			(layer "F.Fab")
		)
		(fp_line
			(start 0.12065 -0.2794)
			(end 0.12065 -0.3048)
			(stroke
				(width 0.1)
				(type default)
			)
			(layer "F.Fab")
		)
		(fp_line
			(start 0.12065 -0.3048)
			(end 0.67945 -0.3048)
			(stroke
				(width 0.1)
				(type default)
			)
			(layer "F.Fab")
		)
		(fp_line
			(start 0.120396 0.3048)
			(end 0.120396 0.2794)
			(stroke
				(width 0.1)
				(type default)
			)
			(layer "F.Fab")
		)
		(fp_line
			(start 0.120396 0.2794)
			(end -0.12065 0.2794)
			(stroke
				(width 0.1)
				(type default)
			)
			(layer "F.Fab")
		)
		(fp_line
			(start -0.12065 0.3048)
			(end -0.67945 0.3048)
			(stroke
				(width 0.1)
				(type default)
			)
			(layer "F.Fab")
		)
		(fp_line
			(start -0.12065 0.2794)
			(end -0.12065 0.3048)
			(stroke
				(width 0.1)
				(type default)
			)
			(layer "F.Fab")
		)
		(fp_line
			(start -0.12065 -0.2794)
			(end 0.12065 -0.2794)
			(stroke
				(width 0.1)
				(type default)
			)
			(layer "F.Fab")
		)
		(fp_line
			(start -0.12065 -0.305054)
			(end -0.12065 -0.2794)
			(stroke
				(width 0.1)
				(type default)
			)
			(layer "F.Fab")
		)
		(fp_line
			(start -0.67945 0.3048)
			(end -0.67945 -0.305054)
			(stroke
				(width 0.1)
				(type default)
			)
			(layer "F.Fab")
		)
		(fp_line
			(start -0.67945 -0.305054)
			(end -0.12065 -0.305054)
			(stroke
				(width 0.1)
				(type default)
			)
			(layer "F.Fab")
		)
		(pad "1" smd circle
			(at -0.40005 0 180)
			(size 0 0)
			(layers "F.Cu" "F.Mask" "F.Paste")
			(net "P3V3_AUX")
		)
		(pad "2" smd circle
			(at 0.40005 0 180)
			(size 0 0)
			(layers "F.Cu" "F.Mask" "F.Paste")
			(net "GPU_PRSNT")
		)
	)
	(footprint ""
		(layer "F.Cu")
		(at 372.988332 -333.804514 -90)
		(property "Reference" "PC276_P0_4"
			(at 0 0 270)
			(layer "F.SilkS")
			(hide yes)
			(effects
				(font
					(size 1.27 1.27)
				)
			)
		)
		(property "Value" ""
			(at 0 0 270)
			(layer "F.Fab")
			(effects
				(font
					(size 1.27 1.27)
				)
			)
		)
		(duplicate_pad_numbers_are_jumpers no)
		(fp_line
			(start -0.7874 0.4064)
			(end -0.7874 -0.4064)
			(stroke
				(width 0.1524)
				(type default)
			)
			(layer "F.SilkS")
		)
		(fp_line
			(start 0.7874 0.4064)
			(end -0.7874 0.4064)
			(stroke
				(width 0.1524)
				(type default)
			)
			(layer "F.SilkS")
		)
		(fp_line
			(start -0.7874 -0.4064)
			(end 0.7874 -0.4064)
			(stroke
				(width 0.1524)
				(type default)
			)
			(layer "F.SilkS")
		)
		(fp_line
			(start 0.7874 -0.4064)
			(end 0.7874 0.4064)
			(stroke
				(width 0.1524)
				(type default)
			)
			(layer "F.SilkS")
		)
		(fp_line
			(start -0.67945 0.3048)
			(end -0.67945 -0.305054)
			(stroke
				(width 0.1)
				(type default)
			)
			(layer "F.Fab")
		)
		(fp_line
			(start -0.12065 0.3048)
			(end -0.67945 0.3048)
			(stroke
				(width 0.1)
				(type default)
			)
			(layer "F.Fab")
		)
		(fp_line
			(start 0.120396 0.3048)
			(end 0.120396 0.2794)
			(stroke
				(width 0.1)
				(type default)
			)
			(layer "F.Fab")
		)
		(fp_line
			(start 0.67945 0.3048)
			(end 0.120396 0.3048)
			(stroke
				(width 0.1)
				(type default)
			)
			(layer "F.Fab")
		)
		(fp_line
			(start -0.12065 0.2794)
			(end -0.12065 0.3048)
			(stroke
				(width 0.1)
				(type default)
			)
			(layer "F.Fab")
		)
		(fp_line
			(start 0.120396 0.2794)
			(end -0.12065 0.2794)
			(stroke
				(width 0.1)
				(type default)
			)
			(layer "F.Fab")
		)
		(fp_line
			(start -0.12065 -0.2794)
			(end 0.12065 -0.2794)
			(stroke
				(width 0.1)
				(type default)
			)
			(layer "F.Fab")
		)
		(fp_line
			(start 0.12065 -0.2794)
			(end 0.12065 -0.3048)
			(stroke
				(width 0.1)
				(type default)
			)
			(layer "F.Fab")
		)
		(fp_line
			(start 0.12065 -0.3048)
			(end 0.67945 -0.3048)
			(stroke
				(width 0.1)
				(type default)
			)
			(layer "F.Fab")
		)
		(fp_line
			(start 0.67945 -0.3048)
			(end 0.67945 0.3048)
			(stroke
				(width 0.1)
				(type default)
			)
			(layer "F.Fab")
		)
		(fp_line
			(start -0.67945 -0.305054)
			(end -0.12065 -0.305054)
			(stroke
				(width 0.1)
				(type default)
			)
			(layer "F.Fab")
		)
		(fp_line
			(start -0.12065 -0.305054)
			(end -0.12065 -0.2794)
			(stroke
				(width 0.1)
				(type default)
			)
			(layer "F.Fab")
		)
		(pad "1" smd circle
			(at -0.40005 0 270)
			(size 0 0)
			(layers "F.Cu" "F.Mask" "F.Paste")
			(net "SW_P12V_PVCCIN_CPU0_FLT")
		)
		(pad "2" smd circle
			(at 0.40005 0 270)
			(size 0 0)
			(layers "F.Cu" "F.Mask" "F.Paste")
			(net "GND")
		)
	)
	(footprint ""
		(layer "F.Cu")
		(at 292.273228 -413.07512 180)
		(property "Reference" "R4553"
			(at 0 0 180)
			(layer "F.SilkS")
			(hide yes)
			(effects
				(font
					(size 1.27 1.27)
				)
			)
		)
		(property "Value" ""
			(at 0 0 180)
			(layer "F.Fab")
			(effects
				(font
					(size 1.27 1.27)
				)
			)
		)
		(duplicate_pad_numbers_are_jumpers no)
		(fp_line
			(start 0.7874 0.4064)
			(end -0.7874 0.4064)
			(stroke
				(width 0.1524)
				(type default)
			)
			(layer "F.SilkS")
		)
		(fp_line
			(start 0.7874 -0.4064)
			(end 0.7874 0.4064)
			(stroke
				(width 0.1524)
				(type default)
			)
			(layer "F.SilkS")
		)
		(fp_line
			(start -0.7874 0.4064)
			(end -0.7874 -0.4064)
			(stroke
				(width 0.1524)
				(type default)
			)
			(layer "F.SilkS")
		)
		(fp_line
			(start -0.7874 -0.4064)
			(end 0.7874 -0.4064)
			(stroke
				(width 0.1524)
				(type default)
			)
			(layer "F.SilkS")
		)
		(fp_line
			(start 0.67945 0.3048)
			(end 0.120396 0.3048)
			(stroke
				(width 0.1)
				(type default)
			)
			(layer "F.Fab")
		)
		(fp_line
			(start 0.67945 -0.3048)
			(end 0.67945 0.3048)
			(stroke
				(width 0.1)
				(type default)
			)
			(layer "F.Fab")
		)
		(fp_line
			(start 0.12065 -0.2794)
			(end 0.12065 -0.3048)
			(stroke
				(width 0.1)
				(type default)
			)
			(layer "F.Fab")
		)
		(fp_line
			(start 0.12065 -0.3048)
			(end 0.67945 -0.3048)
			(stroke
				(width 0.1)
				(type default)
			)
			(layer "F.Fab")
		)
		(fp_line
			(start 0.120396 0.3048)
			(end 0.120396 0.2794)
			(stroke
				(width 0.1)
				(type default)
			)
			(layer "F.Fab")
		)
		(fp_line
			(start 0.120396 0.2794)
			(end -0.12065 0.2794)
			(stroke
				(width 0.1)
				(type default)
			)
			(layer "F.Fab")
		)
		(fp_line
			(start -0.12065 0.3048)
			(end -0.67945 0.3048)
			(stroke
				(width 0.1)
				(type default)
			)
			(layer "F.Fab")
		)
		(fp_line
			(start -0.12065 0.2794)
			(end -0.12065 0.3048)
			(stroke
				(width 0.1)
				(type default)
			)
			(layer "F.Fab")
		)
		(fp_line
			(start -0.12065 -0.2794)
			(end 0.12065 -0.2794)
			(stroke
				(width 0.1)
				(type default)
			)
			(layer "F.Fab")
		)
		(fp_line
			(start -0.12065 -0.305054)
			(end -0.12065 -0.2794)
			(stroke
				(width 0.1)
				(type default)
			)
			(layer "F.Fab")
		)
		(fp_line
			(start -0.67945 0.3048)
			(end -0.67945 -0.305054)
			(stroke
				(width 0.1)
				(type default)
			)
			(layer "F.Fab")
		)
		(fp_line
			(start -0.67945 -0.305054)
			(end -0.12065 -0.305054)
			(stroke
				(width 0.1)
				(type default)
			)
			(layer "F.Fab")
		)
		(pad "1" smd circle
			(at -0.40005 0 180)
			(size 0 0)
			(layers "F.Cu" "F.Mask" "F.Paste")
			(net "P3V3_AUX")
		)
		(pad "2" smd circle
			(at 0.40005 0 180)
			(size 0 0)
			(layers "F.Cu" "F.Mask" "F.Paste")
			(net "HPDB_HSC_PWRGD_N")
		)
	)
	(footprint ""
		(layer "F.Cu")
		(at 169.436288 -417.237418)
		(property "Reference" "R3434"
			(at 0 0 0)
			(layer "F.SilkS")
			(hide yes)
			(effects
				(font
					(size 1.27 1.27)
				)
			)
		)
		(property "Value" ""
			(at 0 0 0)
			(layer "F.Fab")
			(effects
				(font
					(size 1.27 1.27)
				)
			)
		)
		(duplicate_pad_numbers_are_jumpers no)
		(fp_line
			(start -0.7874 -0.4064)
			(end 0.7874 -0.4064)
			(stroke
				(width 0.1524)
				(type default)
			)
			(layer "F.SilkS")
		)
		(fp_line
			(start -0.7874 0.4064)
			(end -0.7874 -0.4064)
			(stroke
				(width 0.1524)
				(type default)
			)
			(layer "F.SilkS")
		)
		(fp_line
			(start 0.7874 -0.4064)
			(end 0.7874 0.4064)
			(stroke
				(width 0.1524)
				(type default)
			)
			(layer "F.SilkS")
		)
		(fp_line
			(start 0.7874 0.4064)
			(end -0.7874 0.4064)
			(stroke
				(width 0.1524)
				(type default)
			)
			(layer "F.SilkS")
		)
		(fp_line
			(start -0.67945 -0.305054)
			(end -0.12065 -0.305054)
			(stroke
				(width 0.1)
				(type default)
			)
			(layer "F.Fab")
		)
		(fp_line
			(start -0.67945 0.3048)
			(end -0.67945 -0.305054)
			(stroke
				(width 0.1)
				(type default)
			)
			(layer "F.Fab")
		)
		(fp_line
			(start -0.12065 -0.305054)
			(end -0.12065 -0.2794)
			(stroke
				(width 0.1)
				(type default)
			)
			(layer "F.Fab")
		)
		(fp_line
			(start -0.12065 -0.2794)
			(end 0.12065 -0.2794)
			(stroke
				(width 0.1)
				(type default)
			)
			(layer "F.Fab")
		)
		(fp_line
			(start -0.12065 0.2794)
			(end -0.12065 0.3048)
			(stroke
				(width 0.1)
				(type default)
			)
			(layer "F.Fab")
		)
		(fp_line
			(start -0.12065 0.3048)
			(end -0.67945 0.3048)
			(stroke
				(width 0.1)
				(type default)
			)
			(layer "F.Fab")
		)
		(fp_line
			(start 0.120396 0.2794)
			(end -0.12065 0.2794)
			(stroke
				(width 0.1)
				(type default)
			)
			(layer "F.Fab")
		)
		(fp_line
			(start 0.120396 0.3048)
			(end 0.120396 0.2794)
			(stroke
				(width 0.1)
				(type default)
			)
			(layer "F.Fab")
		)
		(fp_line
			(start 0.12065 -0.3048)
			(end 0.67945 -0.3048)
			(stroke
				(width 0.1)
				(type default)
			)
			(layer "F.Fab")
		)
		(fp_line
			(start 0.12065 -0.2794)
			(end 0.12065 -0.3048)
			(stroke
				(width 0.1)
				(type default)
			)
			(layer "F.Fab")
		)
		(fp_line
			(start 0.67945 -0.3048)
			(end 0.67945 0.3048)
			(stroke
				(width 0.1)
				(type default)
			)
			(layer "F.Fab")
		)
		(fp_line
			(start 0.67945 0.3048)
			(end 0.120396 0.3048)
			(stroke
				(width 0.1)
				(type default)
			)
			(layer "F.Fab")
		)
		(pad "1" smd circle
			(at -0.40005 0)
			(size 0 0)
			(layers "F.Cu" "F.Mask" "F.Paste")
			(net "P3V3_AUX")
		)
		(pad "2" smd circle
			(at 0.40005 0)
			(size 0 0)
			(layers "F.Cu" "F.Mask" "F.Paste")
			(net "GPU_HMC_PRSNT")
		)
	)
	(footprint ""
		(layer "F.Cu")
		(at 329.795378 -27.042618 -90)
		(property "Reference" "R1872"
			(at 0 0 270)
			(layer "F.SilkS")
			(hide yes)
			(effects
				(font
					(size 1.27 1.27)
				)
			)
		)
		(property "Value" ""
			(at 0 0 270)
			(layer "F.Fab")
			(effects
				(font
					(size 1.27 1.27)
				)
			)
		)
		(duplicate_pad_numbers_are_jumpers no)
		(fp_line
			(start -0.7874 0.4064)
			(end -0.7874 -0.4064)
			(stroke
				(width 0.1524)
				(type default)
			)
			(layer "F.SilkS")
		)
		(fp_line
			(start 0.7874 0.4064)
			(end -0.7874 0.4064)
			(stroke
				(width 0.1524)
				(type default)
			)
			(layer "F.SilkS")
		)
		(fp_line
			(start -0.7874 -0.4064)
			(end 0.7874 -0.4064)
			(stroke
				(width 0.1524)
				(type default)
			)
			(layer "F.SilkS")
		)
		(fp_line
			(start 0.7874 -0.4064)
			(end 0.7874 0.4064)
			(stroke
				(width 0.1524)
				(type default)
			)
			(layer "F.SilkS")
		)
		(fp_line
			(start -0.67945 0.3048)
			(end -0.67945 -0.305054)
			(stroke
				(width 0.1)
				(type default)
			)
			(layer "F.Fab")
		)
		(fp_line
			(start -0.12065 0.3048)
			(end -0.67945 0.3048)
			(stroke
				(width 0.1)
				(type default)
			)
			(layer "F.Fab")
		)
		(fp_line
			(start 0.120396 0.3048)
			(end 0.120396 0.2794)
			(stroke
				(width 0.1)
				(type default)
			)
			(layer "F.Fab")
		)
		(fp_line
			(start 0.67945 0.3048)
			(end 0.120396 0.3048)
			(stroke
				(width 0.1)
				(type default)
			)
			(layer "F.Fab")
		)
		(fp_line
			(start -0.12065 0.2794)
			(end -0.12065 0.3048)
			(stroke
				(width 0.1)
				(type default)
			)
			(layer "F.Fab")
		)
		(fp_line
			(start 0.120396 0.2794)
			(end -0.12065 0.2794)
			(stroke
				(width 0.1)
				(type default)
			)
			(layer "F.Fab")
		)
		(fp_line
			(start -0.12065 -0.2794)
			(end 0.12065 -0.2794)
			(stroke
				(width 0.1)
				(type default)
			)
			(layer "F.Fab")
		)
		(fp_line
			(start 0.12065 -0.2794)
			(end 0.12065 -0.3048)
			(stroke
				(width 0.1)
				(type default)
			)
			(layer "F.Fab")
		)
		(fp_line
			(start 0.12065 -0.3048)
			(end 0.67945 -0.3048)
			(stroke
				(width 0.1)
				(type default)
			)
			(layer "F.Fab")
		)
		(fp_line
			(start 0.67945 -0.3048)
			(end 0.67945 0.3048)
			(stroke
				(width 0.1)
				(type default)
			)
			(layer "F.Fab")
		)
		(fp_line
			(start -0.67945 -0.305054)
			(end -0.12065 -0.305054)
			(stroke
				(width 0.1)
				(type default)
			)
			(layer "F.Fab")
		)
		(fp_line
			(start -0.12065 -0.305054)
			(end -0.12065 -0.2794)
			(stroke
				(width 0.1)
				(type default)
			)
			(layer "F.Fab")
		)
		(pad "1" smd circle
			(at -0.40005 0 270)
			(size 0 0)
			(layers "F.Cu" "F.Mask" "F.Paste")
			(net "CLK_24M_66M_LPC0_ESPI")
		)
		(pad "2" smd circle
			(at 0.40005 0 270)
			(size 0 0)
			(layers "F.Cu" "F.Mask" "F.Paste")
			(net "ESPI_HOST_LPC_BMC_CLK")
		)
	)
	(footprint ""
		(layer "F.Cu")
		(at 80.913478 -23.317962)
		(property "Reference" "PC2150"
			(at 0 0 0)
			(layer "F.SilkS")
			(hide yes)
			(effects
				(font
					(size 1.27 1.27)
				)
			)
		)
		(property "Value" ""
			(at 0 0 0)
			(layer "F.Fab")
			(effects
				(font
					(size 1.27 1.27)
				)
			)
		)
		(duplicate_pad_numbers_are_jumpers no)
		(fp_line
			(start -0.7874 -0.4064)
			(end 0.7874 -0.4064)
			(stroke
				(width 0.1524)
				(type default)
			)
			(layer "F.SilkS")
		)
		(fp_line
			(start -0.7874 0.4064)
			(end -0.7874 -0.4064)
			(stroke
				(width 0.1524)
				(type default)
			)
			(layer "F.SilkS")
		)
		(fp_line
			(start 0.7874 -0.4064)
			(end 0.7874 0.4064)
			(stroke
				(width 0.1524)
				(type default)
			)
			(layer "F.SilkS")
		)
		(fp_line
			(start 0.7874 0.4064)
			(end -0.7874 0.4064)
			(stroke
				(width 0.1524)
				(type default)
			)
			(layer "F.SilkS")
		)
		(fp_line
			(start -0.67945 -0.305054)
			(end -0.12065 -0.305054)
			(stroke
				(width 0.1)
				(type default)
			)
			(layer "F.Fab")
		)
		(fp_line
			(start -0.67945 0.3048)
			(end -0.67945 -0.305054)
			(stroke
				(width 0.1)
				(type default)
			)
			(layer "F.Fab")
		)
		(fp_line
			(start -0.12065 -0.305054)
			(end -0.12065 -0.2794)
			(stroke
				(width 0.1)
				(type default)
			)
			(layer "F.Fab")
		)
		(fp_line
			(start -0.12065 -0.2794)
			(end 0.12065 -0.2794)
			(stroke
				(width 0.1)
				(type default)
			)
			(layer "F.Fab")
		)
		(fp_line
			(start -0.12065 0.2794)
			(end -0.12065 0.3048)
			(stroke
				(width 0.1)
				(type default)
			)
			(layer "F.Fab")
		)
		(fp_line
			(start -0.12065 0.3048)
			(end -0.67945 0.3048)
			(stroke
				(width 0.1)
				(type default)
			)
			(layer "F.Fab")
		)
		(fp_line
			(start 0.120396 0.2794)
			(end -0.12065 0.2794)
			(stroke
				(width 0.1)
				(type default)
			)
			(layer "F.Fab")
		)
		(fp_line
			(start 0.120396 0.3048)
			(end 0.120396 0.2794)
			(stroke
				(width 0.1)
				(type default)
			)
			(layer "F.Fab")
		)
		(fp_line
			(start 0.12065 -0.3048)
			(end 0.67945 -0.3048)
			(stroke
				(width 0.1)
				(type default)
			)
			(layer "F.Fab")
		)
		(fp_line
			(start 0.12065 -0.2794)
			(end 0.12065 -0.3048)
			(stroke
				(width 0.1)
				(type default)
			)
			(layer "F.Fab")
		)
		(fp_line
			(start 0.67945 -0.3048)
			(end 0.67945 0.3048)
			(stroke
				(width 0.1)
				(type default)
			)
			(layer "F.Fab")
		)
		(fp_line
			(start 0.67945 0.3048)
			(end 0.120396 0.3048)
			(stroke
				(width 0.1)
				(type default)
			)
			(layer "F.Fab")
		)
		(pad "1" smd circle
			(at -0.40005 0)
			(size 0 0)
			(layers "F.Cu" "F.Mask" "F.Paste")
			(net "P12V_OCP_GATE_2")
		)
		(pad "2" smd circle
			(at 0.40005 0)
			(size 0 0)
			(layers "F.Cu" "F.Mask" "F.Paste")
			(net "GND")
		)
	)
	(footprint ""
		(layer "F.Cu")
		(at 433.076858 -166.405814)
		(property "Reference" "PC1655"
			(at 0 0 0)
			(layer "F.SilkS")
			(hide yes)
			(effects
				(font
					(size 1.27 1.27)
				)
			)
		)
		(property "Value" ""
			(at 0 0 0)
			(layer "F.Fab")
			(effects
				(font
					(size 1.27 1.27)
				)
			)
		)
		(duplicate_pad_numbers_are_jumpers no)
		(fp_line
			(start -0.7874 -0.4064)
			(end 0.7874 -0.4064)
			(stroke
				(width 0.1524)
				(type default)
			)
			(layer "F.SilkS")
		)
		(fp_line
			(start -0.7874 0.4064)
			(end -0.7874 -0.4064)
			(stroke
				(width 0.1524)
				(type default)
			)
			(layer "F.SilkS")
		)
		(fp_line
			(start 0.7874 -0.4064)
			(end 0.7874 0.4064)
			(stroke
				(width 0.1524)
				(type default)
			)
			(layer "F.SilkS")
		)
		(fp_line
			(start 0.7874 0.4064)
			(end -0.7874 0.4064)
			(stroke
				(width 0.1524)
				(type default)
			)
			(layer "F.SilkS")
		)
		(fp_line
			(start -0.67945 -0.305054)
			(end -0.12065 -0.305054)
			(stroke
				(width 0.1)
				(type default)
			)
			(layer "F.Fab")
		)
		(fp_line
			(start -0.67945 0.3048)
			(end -0.67945 -0.305054)
			(stroke
				(width 0.1)
				(type default)
			)
			(layer "F.Fab")
		)
		(fp_line
			(start -0.12065 -0.305054)
			(end -0.12065 -0.2794)
			(stroke
				(width 0.1)
				(type default)
			)
			(layer "F.Fab")
		)
		(fp_line
			(start -0.12065 -0.2794)
			(end 0.12065 -0.2794)
			(stroke
				(width 0.1)
				(type default)
			)
			(layer "F.Fab")
		)
		(fp_line
			(start -0.12065 0.2794)
			(end -0.12065 0.3048)
			(stroke
				(width 0.1)
				(type default)
			)
			(layer "F.Fab")
		)
		(fp_line
			(start -0.12065 0.3048)
			(end -0.67945 0.3048)
			(stroke
				(width 0.1)
				(type default)
			)
			(layer "F.Fab")
		)
		(fp_line
			(start 0.120396 0.2794)
			(end -0.12065 0.2794)
			(stroke
				(width 0.1)
				(type default)
			)
			(layer "F.Fab")
		)
		(fp_line
			(start 0.120396 0.3048)
			(end 0.120396 0.2794)
			(stroke
				(width 0.1)
				(type default)
			)
			(layer "F.Fab")
		)
		(fp_line
			(start 0.12065 -0.3048)
			(end 0.67945 -0.3048)
			(stroke
				(width 0.1)
				(type default)
			)
			(layer "F.Fab")
		)
		(fp_line
			(start 0.12065 -0.2794)
			(end 0.12065 -0.3048)
			(stroke
				(width 0.1)
				(type default)
			)
			(layer "F.Fab")
		)
		(fp_line
			(start 0.67945 -0.3048)
			(end 0.67945 0.3048)
			(stroke
				(width 0.1)
				(type default)
			)
			(layer "F.Fab")
		)
		(fp_line
			(start 0.67945 0.3048)
			(end 0.120396 0.3048)
			(stroke
				(width 0.1)
				(type default)
			)
			(layer "F.Fab")
		)
		(pad "1" smd circle
			(at -0.40005 0)
			(size 0 0)
			(layers "F.Cu" "F.Mask" "F.Paste")
			(net "P12V_AUX")
		)
		(pad "2" smd circle
			(at 0.40005 0)
			(size 0 0)
			(layers "F.Cu" "F.Mask" "F.Paste")
			(net "GND")
		)
	)
	(footprint ""
		(layer "F.Cu")
		(at 158.138368 -31.341568 90)
		(property "Reference" "R4459"
			(at 0 0 90)
			(layer "F.SilkS")
			(hide yes)
			(effects
				(font
					(size 1.27 1.27)
				)
			)
		)
		(property "Value" ""
			(at 0 0 90)
			(layer "F.Fab")
			(effects
				(font
					(size 1.27 1.27)
				)
			)
		)
		(duplicate_pad_numbers_are_jumpers no)
		(fp_line
			(start 0.7874 -0.4064)
			(end 0.7874 0.4064)
			(stroke
				(width 0.1524)
				(type default)
			)
			(layer "F.SilkS")
		)
		(fp_line
			(start -0.7874 -0.4064)
			(end 0.7874 -0.4064)
			(stroke
				(width 0.1524)
				(type default)
			)
			(layer "F.SilkS")
		)
		(fp_line
			(start 0.7874 0.4064)
			(end -0.7874 0.4064)
			(stroke
				(width 0.1524)
				(type default)
			)
			(layer "F.SilkS")
		)
		(fp_line
			(start -0.7874 0.4064)
			(end -0.7874 -0.4064)
			(stroke
				(width 0.1524)
				(type default)
			)
			(layer "F.SilkS")
		)
		(fp_line
			(start -0.12065 -0.305054)
			(end -0.12065 -0.2794)
			(stroke
				(width 0.1)
				(type default)
			)
			(layer "F.Fab")
		)
		(fp_line
			(start -0.67945 -0.305054)
			(end -0.12065 -0.305054)
			(stroke
				(width 0.1)
				(type default)
			)
			(layer "F.Fab")
		)
		(fp_line
			(start 0.67945 -0.3048)
			(end 0.67945 0.3048)
			(stroke
				(width 0.1)
				(type default)
			)
			(layer "F.Fab")
		)
		(fp_line
			(start 0.12065 -0.3048)
			(end 0.67945 -0.3048)
			(stroke
				(width 0.1)
				(type default)
			)
			(layer "F.Fab")
		)
		(fp_line
			(start 0.12065 -0.2794)
			(end 0.12065 -0.3048)
			(stroke
				(width 0.1)
				(type default)
			)
			(layer "F.Fab")
		)
		(fp_line
			(start -0.12065 -0.2794)
			(end 0.12065 -0.2794)
			(stroke
				(width 0.1)
				(type default)
			)
			(layer "F.Fab")
		)
		(fp_line
			(start 0.120396 0.2794)
			(end -0.12065 0.2794)
			(stroke
				(width 0.1)
				(type default)
			)
			(layer "F.Fab")
		)
		(fp_line
			(start -0.12065 0.2794)
			(end -0.12065 0.3048)
			(stroke
				(width 0.1)
				(type default)
			)
			(layer "F.Fab")
		)
		(fp_line
			(start 0.67945 0.3048)
			(end 0.120396 0.3048)
			(stroke
				(width 0.1)
				(type default)
			)
			(layer "F.Fab")
		)
		(fp_line
			(start 0.120396 0.3048)
			(end 0.120396 0.2794)
			(stroke
				(width 0.1)
				(type default)
			)
			(layer "F.Fab")
		)
		(fp_line
			(start -0.12065 0.3048)
			(end -0.67945 0.3048)
			(stroke
				(width 0.1)
				(type default)
			)
			(layer "F.Fab")
		)
		(fp_line
			(start -0.67945 0.3048)
			(end -0.67945 -0.305054)
			(stroke
				(width 0.1)
				(type default)
			)
			(layer "F.Fab")
		)
		(pad "1" smd circle
			(at -0.40005 0 90)
			(size 0 0)
			(layers "F.Cu" "F.Mask" "F.Paste")
			(net "P3V3_AUX")
		)
		(pad "2" smd circle
			(at 0.40005 0 90)
			(size 0 0)
			(layers "F.Cu" "F.Mask" "F.Paste")
			(net "USB_HUB_2_OVCUR4")
		)
	)
	(footprint ""
		(layer "F.Cu")
		(at 90.09888 -56.352948)
		(property "Reference" "R1370"
			(at 0 0 0)
			(layer "F.SilkS")
			(hide yes)
			(effects
				(font
					(size 1.27 1.27)
				)
			)
		)
		(property "Value" ""
			(at 0 0 0)
			(layer "F.Fab")
			(effects
				(font
					(size 1.27 1.27)
				)
			)
		)
		(duplicate_pad_numbers_are_jumpers no)
		(fp_line
			(start -0.7874 -0.4064)
			(end 0.7874 -0.4064)
			(stroke
				(width 0.1524)
				(type default)
			)
			(layer "F.SilkS")
		)
		(fp_line
			(start -0.7874 0.4064)
			(end -0.7874 -0.4064)
			(stroke
				(width 0.1524)
				(type default)
			)
			(layer "F.SilkS")
		)
		(fp_line
			(start 0.7874 -0.4064)
			(end 0.7874 0.4064)
			(stroke
				(width 0.1524)
				(type default)
			)
			(layer "F.SilkS")
		)
		(fp_line
			(start 0.7874 0.4064)
			(end -0.7874 0.4064)
			(stroke
				(width 0.1524)
				(type default)
			)
			(layer "F.SilkS")
		)
		(fp_line
			(start -0.67945 -0.305054)
			(end -0.12065 -0.305054)
			(stroke
				(width 0.1)
				(type default)
			)
			(layer "F.Fab")
		)
		(fp_line
			(start -0.67945 0.3048)
			(end -0.67945 -0.305054)
			(stroke
				(width 0.1)
				(type default)
			)
			(layer "F.Fab")
		)
		(fp_line
			(start -0.12065 -0.305054)
			(end -0.12065 -0.2794)
			(stroke
				(width 0.1)
				(type default)
			)
			(layer "F.Fab")
		)
		(fp_line
			(start -0.12065 -0.2794)
			(end 0.12065 -0.2794)
			(stroke
				(width 0.1)
				(type default)
			)
			(layer "F.Fab")
		)
		(fp_line
			(start -0.12065 0.2794)
			(end -0.12065 0.3048)
			(stroke
				(width 0.1)
				(type default)
			)
			(layer "F.Fab")
		)
		(fp_line
			(start -0.12065 0.3048)
			(end -0.67945 0.3048)
			(stroke
				(width 0.1)
				(type default)
			)
			(layer "F.Fab")
		)
		(fp_line
			(start 0.120396 0.2794)
			(end -0.12065 0.2794)
			(stroke
				(width 0.1)
				(type default)
			)
			(layer "F.Fab")
		)
		(fp_line
			(start 0.120396 0.3048)
			(end 0.120396 0.2794)
			(stroke
				(width 0.1)
				(type default)
			)
			(layer "F.Fab")
		)
		(fp_line
			(start 0.12065 -0.3048)
			(end 0.67945 -0.3048)
			(stroke
				(width 0.1)
				(type default)
			)
			(layer "F.Fab")
		)
		(fp_line
			(start 0.12065 -0.2794)
			(end 0.12065 -0.3048)
			(stroke
				(width 0.1)
				(type default)
			)
			(layer "F.Fab")
		)
		(fp_line
			(start 0.67945 -0.3048)
			(end 0.67945 0.3048)
			(stroke
				(width 0.1)
				(type default)
			)
			(layer "F.Fab")
		)
		(fp_line
			(start 0.67945 0.3048)
			(end 0.120396 0.3048)
			(stroke
				(width 0.1)
				(type default)
			)
			(layer "F.Fab")
		)
		(pad "1" smd circle
			(at -0.40005 0)
			(size 0 0)
			(layers "F.Cu" "F.Mask" "F.Paste")
			(net "P3V3_AUX")
		)
		(pad "2" smd circle
			(at 0.40005 0)
			(size 0 0)
			(layers "F.Cu" "F.Mask" "F.Paste")
			(net "FM_REMOTE_DEBUG_DET_R")
		)
	)
	(footprint ""
		(layer "F.Cu")
		(at 23.767034 -384.978148 90)
		(property "Reference" "C2353"
			(at 0 0 90)
			(layer "F.SilkS")
			(hide yes)
			(effects
				(font
					(size 1.27 1.27)
				)
			)
		)
		(property "Value" ""
			(at 0 0 90)
			(layer "F.Fab")
			(effects
				(font
					(size 1.27 1.27)
				)
			)
		)
		(duplicate_pad_numbers_are_jumpers no)
		(fp_line
			(start 0.7874 -0.4064)
			(end 0.7874 0.4064)
			(stroke
				(width 0.1524)
				(type default)
			)
			(layer "F.SilkS")
		)
		(fp_line
			(start -0.7874 -0.4064)
			(end -0.036068 -0.4064)
			(stroke
				(width 0.1524)
				(type default)
			)
			(layer "F.SilkS")
		)
		(fp_line
			(start 0.7874 0.4064)
			(end -0.7874 0.4064)
			(stroke
				(width 0.1524)
				(type default)
			)
			(layer "F.SilkS")
		)
		(fp_line
			(start 0.6858 -0.3048)
			(end 0.6858 0.3048)
			(stroke
				(width 0.1)
				(type default)
			)
			(layer "F.Fab")
		)
		(fp_line
			(start 0.1016 -0.3048)
			(end 0.6858 -0.3048)
			(stroke
				(width 0.1)
				(type default)
			)
			(layer "F.Fab")
		)
		(fp_line
			(start -0.1016 -0.3048)
			(end -0.1016 -0.2794)
			(stroke
				(width 0.1)
				(type default)
			)
			(layer "F.Fab")
		)
		(fp_line
			(start -0.6858 -0.3048)
			(end -0.1016 -0.3048)
			(stroke
				(width 0.1)
				(type default)
			)
			(layer "F.Fab")
		)
		(fp_line
			(start 0.1016 -0.2794)
			(end 0.1016 -0.3048)
			(stroke
				(width 0.1)
				(type default)
			)
			(layer "F.Fab")
		)
		(fp_line
			(start -0.1016 -0.2794)
			(end 0.1016 -0.2794)
			(stroke
				(width 0.1)
				(type default)
			)
			(layer "F.Fab")
		)
		(fp_line
			(start 0.1016 0.2794)
			(end -0.1016 0.2794)
			(stroke
				(width 0.1)
				(type default)
			)
			(layer "F.Fab")
		)
		(fp_line
			(start -0.1016 0.2794)
			(end -0.1016 0.3048)
			(stroke
				(width 0.1)
				(type default)
			)
			(layer "F.Fab")
		)
		(fp_line
			(start 0.6858 0.3048)
			(end 0.1016 0.3048)
			(stroke
				(width 0.1)
				(type default)
			)
			(layer "F.Fab")
		)
		(fp_line
			(start 0.1016 0.3048)
			(end 0.1016 0.2794)
			(stroke
				(width 0.1)
				(type default)
			)
			(layer "F.Fab")
		)
		(fp_line
			(start -0.1016 0.3048)
			(end -0.6858 0.3048)
			(stroke
				(width 0.1)
				(type default)
			)
			(layer "F.Fab")
		)
		(fp_line
			(start -0.6858 0.3048)
			(end -0.6858 -0.3048)
			(stroke
				(width 0.1)
				(type default)
			)
			(layer "F.Fab")
		)
		(pad "1" smd rect
			(at -0.40005 0 270)
			(size 0.4572 0.508)
			(layers "F.Cu" "F.Mask" "F.Paste")
			(net "P2E_MB_BMC_RX_BUF2_C_DP<0>")
		)
		(pad "2" smd rect
			(at 0.40005 0 270)
			(size 0.4572 0.508)
			(layers "F.Cu" "F.Mask" "F.Paste")
			(net "P2E_MB_BMC_RX_BUF_DP<0>")
		)
	)
	(footprint ""
		(layer "F.Cu")
		(at 401.62988 -189.067948)
		(property "Reference" "R324"
			(at 0 0 0)
			(layer "F.SilkS")
			(hide yes)
			(effects
				(font
					(size 1.27 1.27)
				)
			)
		)
		(property "Value" ""
			(at 0 0 0)
			(layer "F.Fab")
			(effects
				(font
					(size 1.27 1.27)
				)
			)
		)
		(duplicate_pad_numbers_are_jumpers no)
		(fp_line
			(start -2.044192 -0.94361)
			(end -2.044192 0.898398)
			(stroke
				(width 0.1524)
				(type default)
			)
			(layer "F.SilkS")
		)
		(fp_line
			(start -2.044192 0.94361)
			(end 2.044192 0.94361)
			(stroke
				(width 0.1524)
				(type default)
			)
			(layer "F.SilkS")
		)
		(fp_line
			(start 2.044192 -0.94361)
			(end -2.044192 -0.94361)
			(stroke
				(width 0.1524)
				(type default)
			)
			(layer "F.SilkS")
		)
		(fp_line
			(start 2.044192 0.94361)
			(end 2.044192 -0.94361)
			(stroke
				(width 0.1524)
				(type default)
			)
			(layer "F.SilkS")
		)
		(fp_line
			(start -1.625092 -0.87503)
			(end -1.625092 0.87503)
			(stroke
				(width 0.1)
				(type default)
			)
			(layer "F.Fab")
		)
		(fp_line
			(start -1.625092 0.87503)
			(end 1.625092 0.87503)
			(stroke
				(width 0.1)
				(type default)
			)
			(layer "F.Fab")
		)
		(fp_line
			(start 1.625092 -0.87503)
			(end -1.625092 -0.87503)
			(stroke
				(width 0.1)
				(type default)
			)
			(layer "F.Fab")
		)
		(fp_line
			(start 1.625092 0.87503)
			(end 1.625092 -0.87503)
			(stroke
				(width 0.1)
				(type default)
			)
			(layer "F.Fab")
		)
		(pad "1" smd rect
			(at -1.450086 0)
			(size 0.9144 1.6002)
			(layers "F.Cu" "F.Mask" "F.Paste")
			(net "PVNN_MAIN_CPU0")
		)
		(pad "2" smd rect
			(at 1.450086 0)
			(size 0.9144 1.6002)
			(layers "F.Cu" "F.Mask" "F.Paste")
			(net "PVNN_TERM_CPU0")
		)
	)
	(footprint ""
		(layer "F.Cu")
		(at 166.078154 -402.371052 -90)
		(property "Reference" "C773"
			(at 0 0 270)
			(layer "F.SilkS")
			(hide yes)
			(effects
				(font
					(size 1.27 1.27)
				)
			)
		)
		(property "Value" ""
			(at 0 0 270)
			(layer "F.Fab")
			(effects
				(font
					(size 1.27 1.27)
				)
			)
		)
		(duplicate_pad_numbers_are_jumpers no)
		(fp_line
			(start -0.299974 0.150114)
			(end -0.299974 -0.150114)
			(stroke
				(width 0.1)
				(type default)
			)
			(layer "F.Fab")
		)
		(fp_line
			(start 0.299974 0.150114)
			(end -0.299974 0.150114)
			(stroke
				(width 0.1)
				(type default)
			)
			(layer "F.Fab")
		)
		(fp_line
			(start -0.299974 -0.150114)
			(end 0.299974 -0.150114)
			(stroke
				(width 0.1)
				(type default)
			)
			(layer "F.Fab")
		)
		(fp_line
			(start 0.299974 -0.150114)
			(end 0.299974 0.150114)
			(stroke
				(width 0.1)
				(type default)
			)
			(layer "F.Fab")
		)
		(pad "1" smd rect
			(at -0.2667 0 270)
			(size 0.3048 0.381)
			(layers "F.Cu" "F.Mask" "F.Paste")
			(net "P5E_CPU1_PE2_TX_C_DP<0>")
		)
		(pad "2" smd rect
			(at 0.2667 0 270)
			(size 0.3048 0.381)
			(layers "F.Cu" "F.Mask" "F.Paste")
			(net "P5E_CPU1_PE2_TX_DP<0>")
		)
	)
	(footprint ""
		(layer "F.Cu")
		(at 264.801858 -73.94067)
		(property "Reference" "PC1222"
			(at 0 0 0)
			(layer "F.SilkS")
			(hide yes)
			(effects
				(font
					(size 1.27 1.27)
				)
			)
		)
		(property "Value" ""
			(at 0 0 0)
			(layer "F.Fab")
			(effects
				(font
					(size 1.27 1.27)
				)
			)
		)
		(duplicate_pad_numbers_are_jumpers no)
		(fp_line
			(start -0.7874 -0.4064)
			(end 0.7874 -0.4064)
			(stroke
				(width 0.1524)
				(type default)
			)
			(layer "F.SilkS")
		)
		(fp_line
			(start -0.7874 0.4064)
			(end -0.7874 -0.4064)
			(stroke
				(width 0.1524)
				(type default)
			)
			(layer "F.SilkS")
		)
		(fp_line
			(start 0.7874 -0.4064)
			(end 0.7874 0.4064)
			(stroke
				(width 0.1524)
				(type default)
			)
			(layer "F.SilkS")
		)
		(fp_line
			(start 0.7874 0.4064)
			(end -0.7874 0.4064)
			(stroke
				(width 0.1524)
				(type default)
			)
			(layer "F.SilkS")
		)
		(fp_line
			(start -0.67945 -0.305054)
			(end -0.12065 -0.305054)
			(stroke
				(width 0.1)
				(type default)
			)
			(layer "F.Fab")
		)
		(fp_line
			(start -0.67945 0.3048)
			(end -0.67945 -0.305054)
			(stroke
				(width 0.1)
				(type default)
			)
			(layer "F.Fab")
		)
		(fp_line
			(start -0.12065 -0.305054)
			(end -0.12065 -0.2794)
			(stroke
				(width 0.1)
				(type default)
			)
			(layer "F.Fab")
		)
		(fp_line
			(start -0.12065 -0.2794)
			(end 0.12065 -0.2794)
			(stroke
				(width 0.1)
				(type default)
			)
			(layer "F.Fab")
		)
		(fp_line
			(start -0.12065 0.2794)
			(end -0.12065 0.3048)
			(stroke
				(width 0.1)
				(type default)
			)
			(layer "F.Fab")
		)
		(fp_line
			(start -0.12065 0.3048)
			(end -0.67945 0.3048)
			(stroke
				(width 0.1)
				(type default)
			)
			(layer "F.Fab")
		)
		(fp_line
			(start 0.120396 0.2794)
			(end -0.12065 0.2794)
			(stroke
				(width 0.1)
				(type default)
			)
			(layer "F.Fab")
		)
		(fp_line
			(start 0.120396 0.3048)
			(end 0.120396 0.2794)
			(stroke
				(width 0.1)
				(type default)
			)
			(layer "F.Fab")
		)
		(fp_line
			(start 0.12065 -0.3048)
			(end 0.67945 -0.3048)
			(stroke
				(width 0.1)
				(type default)
			)
			(layer "F.Fab")
		)
		(fp_line
			(start 0.12065 -0.2794)
			(end 0.12065 -0.3048)
			(stroke
				(width 0.1)
				(type default)
			)
			(layer "F.Fab")
		)
		(fp_line
			(start 0.67945 -0.3048)
			(end 0.67945 0.3048)
			(stroke
				(width 0.1)
				(type default)
			)
			(layer "F.Fab")
		)
		(fp_line
			(start 0.67945 0.3048)
			(end 0.120396 0.3048)
			(stroke
				(width 0.1)
				(type default)
			)
			(layer "F.Fab")
		)
		(pad "1" smd circle
			(at -0.40005 0)
			(size 0 0)
			(layers "F.Cu" "F.Mask" "F.Paste")
			(net "SW_P1V05_PCH_AUX_BST")
		)
		(pad "2" smd circle
			(at 0.40005 0)
			(size 0 0)
			(layers "F.Cu" "F.Mask" "F.Paste")
			(net "SW_P1V05_PCH_AUX_SW")
		)
	)
	(footprint ""
		(layer "F.Cu")
		(at 182.17388 -126.964948 -90)
		(property "Reference" "R274"
			(at 0 0 270)
			(layer "F.SilkS")
			(hide yes)
			(effects
				(font
					(size 1.27 1.27)
				)
			)
		)
		(property "Value" ""
			(at 0 0 270)
			(layer "F.Fab")
			(effects
				(font
					(size 1.27 1.27)
				)
			)
		)
		(duplicate_pad_numbers_are_jumpers no)
		(fp_line
			(start -0.7874 0.4064)
			(end -0.7874 -0.4064)
			(stroke
				(width 0.1524)
				(type default)
			)
			(layer "F.SilkS")
		)
		(fp_line
			(start 0.7874 0.4064)
			(end -0.7874 0.4064)
			(stroke
				(width 0.1524)
				(type default)
			)
			(layer "F.SilkS")
		)
		(fp_line
			(start -0.7874 -0.4064)
			(end 0.7874 -0.4064)
			(stroke
				(width 0.1524)
				(type default)
			)
			(layer "F.SilkS")
		)
		(fp_line
			(start 0.7874 -0.4064)
			(end 0.7874 0.4064)
			(stroke
				(width 0.1524)
				(type default)
			)
			(layer "F.SilkS")
		)
		(fp_line
			(start -0.67945 0.3048)
			(end -0.67945 -0.305054)
			(stroke
				(width 0.1)
				(type default)
			)
			(layer "F.Fab")
		)
		(fp_line
			(start -0.12065 0.3048)
			(end -0.67945 0.3048)
			(stroke
				(width 0.1)
				(type default)
			)
			(layer "F.Fab")
		)
		(fp_line
			(start 0.120396 0.3048)
			(end 0.120396 0.2794)
			(stroke
				(width 0.1)
				(type default)
			)
			(layer "F.Fab")
		)
		(fp_line
			(start 0.67945 0.3048)
			(end 0.120396 0.3048)
			(stroke
				(width 0.1)
				(type default)
			)
			(layer "F.Fab")
		)
		(fp_line
			(start -0.12065 0.2794)
			(end -0.12065 0.3048)
			(stroke
				(width 0.1)
				(type default)
			)
			(layer "F.Fab")
		)
		(fp_line
			(start 0.120396 0.2794)
			(end -0.12065 0.2794)
			(stroke
				(width 0.1)
				(type default)
			)
			(layer "F.Fab")
		)
		(fp_line
			(start -0.12065 -0.2794)
			(end 0.12065 -0.2794)
			(stroke
				(width 0.1)
				(type default)
			)
			(layer "F.Fab")
		)
		(fp_line
			(start 0.12065 -0.2794)
			(end 0.12065 -0.3048)
			(stroke
				(width 0.1)
				(type default)
			)
			(layer "F.Fab")
		)
		(fp_line
			(start 0.12065 -0.3048)
			(end 0.67945 -0.3048)
			(stroke
				(width 0.1)
				(type default)
			)
			(layer "F.Fab")
		)
		(fp_line
			(start 0.67945 -0.3048)
			(end 0.67945 0.3048)
			(stroke
				(width 0.1)
				(type default)
			)
			(layer "F.Fab")
		)
		(fp_line
			(start -0.67945 -0.305054)
			(end -0.12065 -0.305054)
			(stroke
				(width 0.1)
				(type default)
			)
			(layer "F.Fab")
		)
		(fp_line
			(start -0.12065 -0.305054)
			(end -0.12065 -0.2794)
			(stroke
				(width 0.1)
				(type default)
			)
			(layer "F.Fab")
		)
		(pad "1" smd circle
			(at -0.40005 0 270)
			(size 0 0)
			(layers "F.Cu" "F.Mask" "F.Paste")
			(net "P3V3_AUX")
		)
		(pad "2" smd circle
			(at 0.40005 0 270)
			(size 0 0)
			(layers "F.Cu" "F.Mask" "F.Paste")
			(net "FM_CPU1_PROC_ID1")
		)
	)
	(footprint ""
		(layer "F.Cu")
		(at 329.375008 -402.371052 -90)
		(property "Reference" "C1563"
			(at 0 0 270)
			(layer "F.SilkS")
			(hide yes)
			(effects
				(font
					(size 1.27 1.27)
				)
			)
		)
		(property "Value" ""
			(at 0 0 270)
			(layer "F.Fab")
			(effects
				(font
					(size 1.27 1.27)
				)
			)
		)
		(duplicate_pad_numbers_are_jumpers no)
		(fp_line
			(start -0.299974 0.150114)
			(end -0.299974 -0.150114)
			(stroke
				(width 0.1)
				(type default)
			)
			(layer "F.Fab")
		)
		(fp_line
			(start 0.299974 0.150114)
			(end -0.299974 0.150114)
			(stroke
				(width 0.1)
				(type default)
			)
			(layer "F.Fab")
		)
		(fp_line
			(start -0.299974 -0.150114)
			(end 0.299974 -0.150114)
			(stroke
				(width 0.1)
				(type default)
			)
			(layer "F.Fab")
		)
		(fp_line
			(start 0.299974 -0.150114)
			(end 0.299974 0.150114)
			(stroke
				(width 0.1)
				(type default)
			)
			(layer "F.Fab")
		)
		(pad "1" smd rect
			(at -0.2667 0 270)
			(size 0.3048 0.381)
			(layers "F.Cu" "F.Mask" "F.Paste")
			(net "P5E_CPU0_PE4_TX_C_DP<8>")
		)
		(pad "2" smd rect
			(at 0.2667 0 270)
			(size 0.3048 0.381)
			(layers "F.Cu" "F.Mask" "F.Paste")
			(net "P5E_CPU0_PE4_TX_DP<8>")
		)
	)
	(footprint ""
		(layer "F.Cu")
		(at 31.540196 -168.02481)
		(property "Reference" "PC391"
			(at 0 0 0)
			(layer "F.SilkS")
			(hide yes)
			(effects
				(font
					(size 1.27 1.27)
				)
			)
		)
		(property "Value" ""
			(at 0 0 0)
			(layer "F.Fab")
			(effects
				(font
					(size 1.27 1.27)
				)
			)
		)
		(duplicate_pad_numbers_are_jumpers no)
		(fp_line
			(start -0.7874 -0.4064)
			(end 0.7874 -0.4064)
			(stroke
				(width 0.1524)
				(type default)
			)
			(layer "F.SilkS")
		)
		(fp_line
			(start -0.7874 0.4064)
			(end -0.7874 -0.4064)
			(stroke
				(width 0.1524)
				(type default)
			)
			(layer "F.SilkS")
		)
		(fp_line
			(start 0.7874 -0.4064)
			(end 0.7874 0.4064)
			(stroke
				(width 0.1524)
				(type default)
			)
			(layer "F.SilkS")
		)
		(fp_line
			(start 0.7874 0.4064)
			(end -0.7874 0.4064)
			(stroke
				(width 0.1524)
				(type default)
			)
			(layer "F.SilkS")
		)
		(fp_line
			(start -0.67945 -0.305054)
			(end -0.12065 -0.305054)
			(stroke
				(width 0.1)
				(type default)
			)
			(layer "F.Fab")
		)
		(fp_line
			(start -0.67945 0.3048)
			(end -0.67945 -0.305054)
			(stroke
				(width 0.1)
				(type default)
			)
			(layer "F.Fab")
		)
		(fp_line
			(start -0.12065 -0.305054)
			(end -0.12065 -0.2794)
			(stroke
				(width 0.1)
				(type default)
			)
			(layer "F.Fab")
		)
		(fp_line
			(start -0.12065 -0.2794)
			(end 0.12065 -0.2794)
			(stroke
				(width 0.1)
				(type default)
			)
			(layer "F.Fab")
		)
		(fp_line
			(start -0.12065 0.2794)
			(end -0.12065 0.3048)
			(stroke
				(width 0.1)
				(type default)
			)
			(layer "F.Fab")
		)
		(fp_line
			(start -0.12065 0.3048)
			(end -0.67945 0.3048)
			(stroke
				(width 0.1)
				(type default)
			)
			(layer "F.Fab")
		)
		(fp_line
			(start 0.120396 0.2794)
			(end -0.12065 0.2794)
			(stroke
				(width 0.1)
				(type default)
			)
			(layer "F.Fab")
		)
		(fp_line
			(start 0.120396 0.3048)
			(end 0.120396 0.2794)
			(stroke
				(width 0.1)
				(type default)
			)
			(layer "F.Fab")
		)
		(fp_line
			(start 0.12065 -0.3048)
			(end 0.67945 -0.3048)
			(stroke
				(width 0.1)
				(type default)
			)
			(layer "F.Fab")
		)
		(fp_line
			(start 0.12065 -0.2794)
			(end 0.12065 -0.3048)
			(stroke
				(width 0.1)
				(type default)
			)
			(layer "F.Fab")
		)
		(fp_line
			(start 0.67945 -0.3048)
			(end 0.67945 0.3048)
			(stroke
				(width 0.1)
				(type default)
			)
			(layer "F.Fab")
		)
		(fp_line
			(start 0.67945 0.3048)
			(end 0.120396 0.3048)
			(stroke
				(width 0.1)
				(type default)
			)
			(layer "F.Fab")
		)
		(pad "1" smd circle
			(at -0.40005 0)
			(size 0 0)
			(layers "F.Cu" "F.Mask" "F.Paste")
			(net "PVCCD_HV_CPU1_VCC")
		)
		(pad "2" smd circle
			(at 0.40005 0)
			(size 0 0)
			(layers "F.Cu" "F.Mask" "F.Paste")
			(net "GND")
		)
	)
	(footprint ""
		(layer "F.Cu")
		(at 88.655652 -36.288726 180)
		(property "Reference" "R1520"
			(at 0 0 180)
			(layer "F.SilkS")
			(hide yes)
			(effects
				(font
					(size 1.27 1.27)
				)
			)
		)
		(property "Value" ""
			(at 0 0 180)
			(layer "F.Fab")
			(effects
				(font
					(size 1.27 1.27)
				)
			)
		)
		(duplicate_pad_numbers_are_jumpers no)
		(fp_line
			(start 0.7874 0.4064)
			(end -0.7874 0.4064)
			(stroke
				(width 0.1524)
				(type default)
			)
			(layer "F.SilkS")
		)
		(fp_line
			(start 0.7874 -0.4064)
			(end 0.7874 0.4064)
			(stroke
				(width 0.1524)
				(type default)
			)
			(layer "F.SilkS")
		)
		(fp_line
			(start -0.7874 0.4064)
			(end -0.7874 -0.4064)
			(stroke
				(width 0.1524)
				(type default)
			)
			(layer "F.SilkS")
		)
		(fp_line
			(start -0.7874 -0.4064)
			(end 0.7874 -0.4064)
			(stroke
				(width 0.1524)
				(type default)
			)
			(layer "F.SilkS")
		)
		(fp_line
			(start 0.67945 0.3048)
			(end 0.120396 0.3048)
			(stroke
				(width 0.1)
				(type default)
			)
			(layer "F.Fab")
		)
		(fp_line
			(start 0.67945 -0.3048)
			(end 0.67945 0.3048)
			(stroke
				(width 0.1)
				(type default)
			)
			(layer "F.Fab")
		)
		(fp_line
			(start 0.12065 -0.2794)
			(end 0.12065 -0.3048)
			(stroke
				(width 0.1)
				(type default)
			)
			(layer "F.Fab")
		)
		(fp_line
			(start 0.12065 -0.3048)
			(end 0.67945 -0.3048)
			(stroke
				(width 0.1)
				(type default)
			)
			(layer "F.Fab")
		)
		(fp_line
			(start 0.120396 0.3048)
			(end 0.120396 0.2794)
			(stroke
				(width 0.1)
				(type default)
			)
			(layer "F.Fab")
		)
		(fp_line
			(start 0.120396 0.2794)
			(end -0.12065 0.2794)
			(stroke
				(width 0.1)
				(type default)
			)
			(layer "F.Fab")
		)
		(fp_line
			(start -0.12065 0.3048)
			(end -0.67945 0.3048)
			(stroke
				(width 0.1)
				(type default)
			)
			(layer "F.Fab")
		)
		(fp_line
			(start -0.12065 0.2794)
			(end -0.12065 0.3048)
			(stroke
				(width 0.1)
				(type default)
			)
			(layer "F.Fab")
		)
		(fp_line
			(start -0.12065 -0.2794)
			(end 0.12065 -0.2794)
			(stroke
				(width 0.1)
				(type default)
			)
			(layer "F.Fab")
		)
		(fp_line
			(start -0.12065 -0.305054)
			(end -0.12065 -0.2794)
			(stroke
				(width 0.1)
				(type default)
			)
			(layer "F.Fab")
		)
		(fp_line
			(start -0.67945 0.3048)
			(end -0.67945 -0.305054)
			(stroke
				(width 0.1)
				(type default)
			)
			(layer "F.Fab")
		)
		(fp_line
			(start -0.67945 -0.305054)
			(end -0.12065 -0.305054)
			(stroke
				(width 0.1)
				(type default)
			)
			(layer "F.Fab")
		)
		(pad "1" smd circle
			(at -0.40005 0 180)
			(size 0 0)
			(layers "F.Cu" "F.Mask" "F.Paste")
			(net "RST_PCIE_CPU1_DEV_PERST_N")
		)
		(pad "2" smd circle
			(at 0.40005 0 180)
			(size 0 0)
			(layers "F.Cu" "F.Mask" "F.Paste")
			(net "RST_OCP_V3_2_N")
		)
	)
	(footprint ""
		(layer "F.Cu")
		(at 292.62832 -92.260674 180)
		(property "Reference" "R1332"
			(at 0 0 180)
			(layer "F.SilkS")
			(hide yes)
			(effects
				(font
					(size 1.27 1.27)
				)
			)
		)
		(property "Value" ""
			(at 0 0 180)
			(layer "F.Fab")
			(effects
				(font
					(size 1.27 1.27)
				)
			)
		)
		(duplicate_pad_numbers_are_jumpers no)
		(fp_line
			(start 0.7874 0.4064)
			(end -0.7874 0.4064)
			(stroke
				(width 0.1524)
				(type default)
			)
			(layer "F.SilkS")
		)
		(fp_line
			(start 0.7874 -0.4064)
			(end 0.7874 0.4064)
			(stroke
				(width 0.1524)
				(type default)
			)
			(layer "F.SilkS")
		)
		(fp_line
			(start -0.7874 0.4064)
			(end -0.7874 -0.4064)
			(stroke
				(width 0.1524)
				(type default)
			)
			(layer "F.SilkS")
		)
		(fp_line
			(start -0.7874 -0.4064)
			(end 0.7874 -0.4064)
			(stroke
				(width 0.1524)
				(type default)
			)
			(layer "F.SilkS")
		)
		(fp_line
			(start 0.67945 0.3048)
			(end 0.120396 0.3048)
			(stroke
				(width 0.1)
				(type default)
			)
			(layer "F.Fab")
		)
		(fp_line
			(start 0.67945 -0.3048)
			(end 0.67945 0.3048)
			(stroke
				(width 0.1)
				(type default)
			)
			(layer "F.Fab")
		)
		(fp_line
			(start 0.12065 -0.2794)
			(end 0.12065 -0.3048)
			(stroke
				(width 0.1)
				(type default)
			)
			(layer "F.Fab")
		)
		(fp_line
			(start 0.12065 -0.3048)
			(end 0.67945 -0.3048)
			(stroke
				(width 0.1)
				(type default)
			)
			(layer "F.Fab")
		)
		(fp_line
			(start 0.120396 0.3048)
			(end 0.120396 0.2794)
			(stroke
				(width 0.1)
				(type default)
			)
			(layer "F.Fab")
		)
		(fp_line
			(start 0.120396 0.2794)
			(end -0.12065 0.2794)
			(stroke
				(width 0.1)
				(type default)
			)
			(layer "F.Fab")
		)
		(fp_line
			(start -0.12065 0.3048)
			(end -0.67945 0.3048)
			(stroke
				(width 0.1)
				(type default)
			)
			(layer "F.Fab")
		)
		(fp_line
			(start -0.12065 0.2794)
			(end -0.12065 0.3048)
			(stroke
				(width 0.1)
				(type default)
			)
			(layer "F.Fab")
		)
		(fp_line
			(start -0.12065 -0.2794)
			(end 0.12065 -0.2794)
			(stroke
				(width 0.1)
				(type default)
			)
			(layer "F.Fab")
		)
		(fp_line
			(start -0.12065 -0.305054)
			(end -0.12065 -0.2794)
			(stroke
				(width 0.1)
				(type default)
			)
			(layer "F.Fab")
		)
		(fp_line
			(start -0.67945 0.3048)
			(end -0.67945 -0.305054)
			(stroke
				(width 0.1)
				(type default)
			)
			(layer "F.Fab")
		)
		(fp_line
			(start -0.67945 -0.305054)
			(end -0.12065 -0.305054)
			(stroke
				(width 0.1)
				(type default)
			)
			(layer "F.Fab")
		)
		(pad "1" smd circle
			(at -0.40005 0 180)
			(size 0 0)
			(layers "F.Cu" "F.Mask" "F.Paste")
			(net "P3V3_AUX")
		)
		(pad "2" smd circle
			(at 0.40005 0 180)
			(size 0 0)
			(layers "F.Cu" "F.Mask" "F.Paste")
			(net "SMB_FRU_3V3AUX_SDA")
		)
	)
	(footprint ""
		(layer "F.Cu")
		(at 415.818828 -183.032654 180)
		(property "Reference" "PC2946"
			(at 0 0 180)
			(layer "F.SilkS")
			(hide yes)
			(effects
				(font
					(size 1.27 1.27)
				)
			)
		)
		(property "Value" ""
			(at 0 0 180)
			(layer "F.Fab")
			(effects
				(font
					(size 1.27 1.27)
				)
			)
		)
		(duplicate_pad_numbers_are_jumpers no)
		(fp_line
			(start 0.7874 0.4064)
			(end -0.7874 0.4064)
			(stroke
				(width 0.1524)
				(type default)
			)
			(layer "F.SilkS")
		)
		(fp_line
			(start 0.7874 -0.4064)
			(end 0.7874 0.4064)
			(stroke
				(width 0.1524)
				(type default)
			)
			(layer "F.SilkS")
		)
		(fp_line
			(start -0.7874 0.4064)
			(end -0.7874 -0.4064)
			(stroke
				(width 0.1524)
				(type default)
			)
			(layer "F.SilkS")
		)
		(fp_line
			(start -0.7874 -0.4064)
			(end 0.7874 -0.4064)
			(stroke
				(width 0.1524)
				(type default)
			)
			(layer "F.SilkS")
		)
		(fp_line
			(start 0.67945 0.3048)
			(end 0.120396 0.3048)
			(stroke
				(width 0.1)
				(type default)
			)
			(layer "F.Fab")
		)
		(fp_line
			(start 0.67945 -0.3048)
			(end 0.67945 0.3048)
			(stroke
				(width 0.1)
				(type default)
			)
			(layer "F.Fab")
		)
		(fp_line
			(start 0.12065 -0.2794)
			(end 0.12065 -0.3048)
			(stroke
				(width 0.1)
				(type default)
			)
			(layer "F.Fab")
		)
		(fp_line
			(start 0.12065 -0.3048)
			(end 0.67945 -0.3048)
			(stroke
				(width 0.1)
				(type default)
			)
			(layer "F.Fab")
		)
		(fp_line
			(start 0.120396 0.3048)
			(end 0.120396 0.2794)
			(stroke
				(width 0.1)
				(type default)
			)
			(layer "F.Fab")
		)
		(fp_line
			(start 0.120396 0.2794)
			(end -0.12065 0.2794)
			(stroke
				(width 0.1)
				(type default)
			)
			(layer "F.Fab")
		)
		(fp_line
			(start -0.12065 0.3048)
			(end -0.67945 0.3048)
			(stroke
				(width 0.1)
				(type default)
			)
			(layer "F.Fab")
		)
		(fp_line
			(start -0.12065 0.2794)
			(end -0.12065 0.3048)
			(stroke
				(width 0.1)
				(type default)
			)
			(layer "F.Fab")
		)
		(fp_line
			(start -0.12065 -0.2794)
			(end 0.12065 -0.2794)
			(stroke
				(width 0.1)
				(type default)
			)
			(layer "F.Fab")
		)
		(fp_line
			(start -0.12065 -0.305054)
			(end -0.12065 -0.2794)
			(stroke
				(width 0.1)
				(type default)
			)
			(layer "F.Fab")
		)
		(fp_line
			(start -0.67945 0.3048)
			(end -0.67945 -0.305054)
			(stroke
				(width 0.1)
				(type default)
			)
			(layer "F.Fab")
		)
		(fp_line
			(start -0.67945 -0.305054)
			(end -0.12065 -0.305054)
			(stroke
				(width 0.1)
				(type default)
			)
			(layer "F.Fab")
		)
		(pad "1" smd circle
			(at -0.40005 0 180)
			(size 0 0)
			(layers "F.Cu" "F.Mask" "F.Paste")
			(net "PVCCFA_EHV_CPU0_PVCC")
		)
		(pad "2" smd circle
			(at 0.40005 0 180)
			(size 0 0)
			(layers "F.Cu" "F.Mask" "F.Paste")
			(net "GND")
		)
	)
	(footprint ""
		(layer "F.Cu")
		(at 408.554682 -170.821858 180)
		(property "Reference" "PL4"
			(at 3.264662 3.982212 0)
			(unlocked yes)
			(layer "F.SilkS")
			(effects
				(font
					(size 0.7874 0.5842)
					(thickness 0.1524)
				)
				(justify left)
			)
		)
		(property "Value" ""
			(at 0 0 180)
			(layer "F.Fab")
			(effects
				(font
					(size 1.27 1.27)
				)
			)
		)
		(duplicate_pad_numbers_are_jumpers no)
		(fp_line
			(start 3.24993 3.24993)
			(end -3.24993 3.24993)
			(stroke
				(width 0.1524)
				(type default)
			)
			(layer "F.SilkS")
		)
		(fp_line
			(start 3.24993 2.2352)
			(end 3.24993 3.24993)
			(stroke
				(width 0.1524)
				(type default)
			)
			(layer "F.SilkS")
		)
		(fp_line
			(start 3.24993 -3.24993)
			(end 3.24993 -2.2352)
			(stroke
				(width 0.1524)
				(type default)
			)
			(layer "F.SilkS")
		)
		(fp_line
			(start -3.24993 3.24993)
			(end -3.24993 2.2352)
			(stroke
				(width 0.1524)
				(type default)
			)
			(layer "F.SilkS")
		)
		(fp_line
			(start -3.24993 -2.2352)
			(end -3.24993 -3.24993)
			(stroke
				(width 0.1524)
				(type default)
			)
			(layer "F.SilkS")
		)
		(fp_line
			(start -3.24993 -3.24993)
			(end 3.24993 -3.24993)
			(stroke
				(width 0.1524)
				(type default)
			)
			(layer "F.SilkS")
		)
		(fp_line
			(start 3.24993 3.24993)
			(end -3.24993 3.24993)
			(stroke
				(width 0.1)
				(type default)
			)
			(layer "F.Fab")
		)
		(fp_line
			(start 3.24993 -3.24993)
			(end 3.24993 3.24993)
			(stroke
				(width 0.1)
				(type default)
			)
			(layer "F.Fab")
		)
		(fp_line
			(start -3.24993 3.24993)
			(end -3.24993 -3.24993)
			(stroke
				(width 0.1)
				(type default)
			)
			(layer "F.Fab")
		)
		(fp_line
			(start -3.24993 -3.24993)
			(end 3.24993 -3.24993)
			(stroke
				(width 0.1)
				(type default)
			)
			(layer "F.Fab")
		)
		(pad "1" smd rect
			(at -2.29997 0 180)
			(size 2.0066 4.2164)
			(layers "F.Cu" "F.Mask" "F.Paste")
			(net "SW_PVCCINFAON_CPU0_SW1")
		)
		(pad "2" smd rect
			(at 2.29997 0 180)
			(size 2.0066 4.2164)
			(layers "F.Cu" "F.Mask" "F.Paste")
			(net "PVCCINFAON_CPU0")
		)
	)
	(footprint ""
		(layer "F.Cu")
		(at 73.374758 -402.371052 -90)
		(property "Reference" "C727"
			(at 0 0 270)
			(layer "F.SilkS")
			(hide yes)
			(effects
				(font
					(size 1.27 1.27)
				)
			)
		)
		(property "Value" ""
			(at 0 0 270)
			(layer "F.Fab")
			(effects
				(font
					(size 1.27 1.27)
				)
			)
		)
		(duplicate_pad_numbers_are_jumpers no)
		(fp_line
			(start -0.299974 0.150114)
			(end -0.299974 -0.150114)
			(stroke
				(width 0.1)
				(type default)
			)
			(layer "F.Fab")
		)
		(fp_line
			(start 0.299974 0.150114)
			(end -0.299974 0.150114)
			(stroke
				(width 0.1)
				(type default)
			)
			(layer "F.Fab")
		)
		(fp_line
			(start -0.299974 -0.150114)
			(end 0.299974 -0.150114)
			(stroke
				(width 0.1)
				(type default)
			)
			(layer "F.Fab")
		)
		(fp_line
			(start 0.299974 -0.150114)
			(end 0.299974 0.150114)
			(stroke
				(width 0.1)
				(type default)
			)
			(layer "F.Fab")
		)
		(pad "1" smd rect
			(at -0.2667 0 270)
			(size 0.3048 0.381)
			(layers "F.Cu" "F.Mask" "F.Paste")
			(net "P5E_CPU1_PE0_TX_C_DP<7>")
		)
		(pad "2" smd rect
			(at 0.2667 0 270)
			(size 0.3048 0.381)
			(layers "F.Cu" "F.Mask" "F.Paste")
			(net "P5E_CPU1_PE0_TX_DP<7>")
		)
	)
	(footprint ""
		(layer "F.Cu")
		(at 209.74558 -126.512828)
		(property "Reference" "C1319"
			(at 0 0 0)
			(layer "F.SilkS")
			(hide yes)
			(effects
				(font
					(size 1.27 1.27)
				)
			)
		)
		(property "Value" ""
			(at 0 0 0)
			(layer "F.Fab")
			(effects
				(font
					(size 1.27 1.27)
				)
			)
		)
		(duplicate_pad_numbers_are_jumpers no)
		(fp_line
			(start -0.7874 -0.4064)
			(end 0.7874 -0.4064)
			(stroke
				(width 0.1524)
				(type default)
			)
			(layer "F.SilkS")
		)
		(fp_line
			(start -0.7874 0.4064)
			(end -0.7874 -0.4064)
			(stroke
				(width 0.1524)
				(type default)
			)
			(layer "F.SilkS")
		)
		(fp_line
			(start 0.7874 -0.4064)
			(end 0.7874 0.4064)
			(stroke
				(width 0.1524)
				(type default)
			)
			(layer "F.SilkS")
		)
		(fp_line
			(start 0.7874 0.4064)
			(end -0.7874 0.4064)
			(stroke
				(width 0.1524)
				(type default)
			)
			(layer "F.SilkS")
		)
		(fp_line
			(start -0.67945 -0.305054)
			(end -0.12065 -0.305054)
			(stroke
				(width 0.1)
				(type default)
			)
			(layer "F.Fab")
		)
		(fp_line
			(start -0.67945 0.3048)
			(end -0.67945 -0.305054)
			(stroke
				(width 0.1)
				(type default)
			)
			(layer "F.Fab")
		)
		(fp_line
			(start -0.12065 -0.305054)
			(end -0.12065 -0.2794)
			(stroke
				(width 0.1)
				(type default)
			)
			(layer "F.Fab")
		)
		(fp_line
			(start -0.12065 -0.2794)
			(end 0.12065 -0.2794)
			(stroke
				(width 0.1)
				(type default)
			)
			(layer "F.Fab")
		)
		(fp_line
			(start -0.12065 0.2794)
			(end -0.12065 0.3048)
			(stroke
				(width 0.1)
				(type default)
			)
			(layer "F.Fab")
		)
		(fp_line
			(start -0.12065 0.3048)
			(end -0.67945 0.3048)
			(stroke
				(width 0.1)
				(type default)
			)
			(layer "F.Fab")
		)
		(fp_line
			(start 0.120396 0.2794)
			(end -0.12065 0.2794)
			(stroke
				(width 0.1)
				(type default)
			)
			(layer "F.Fab")
		)
		(fp_line
			(start 0.120396 0.3048)
			(end 0.120396 0.2794)
			(stroke
				(width 0.1)
				(type default)
			)
			(layer "F.Fab")
		)
		(fp_line
			(start 0.12065 -0.3048)
			(end 0.67945 -0.3048)
			(stroke
				(width 0.1)
				(type default)
			)
			(layer "F.Fab")
		)
		(fp_line
			(start 0.12065 -0.2794)
			(end 0.12065 -0.3048)
			(stroke
				(width 0.1)
				(type default)
			)
			(layer "F.Fab")
		)
		(fp_line
			(start 0.67945 -0.3048)
			(end 0.67945 0.3048)
			(stroke
				(width 0.1)
				(type default)
			)
			(layer "F.Fab")
		)
		(fp_line
			(start 0.67945 0.3048)
			(end 0.120396 0.3048)
			(stroke
				(width 0.1)
				(type default)
			)
			(layer "F.Fab")
		)
		(pad "1" smd circle
			(at -0.40005 0)
			(size 0 0)
			(layers "F.Cu" "F.Mask" "F.Paste")
			(net "PWRGD_DSW_PWROK")
		)
		(pad "2" smd circle
			(at 0.40005 0)
			(size 0 0)
			(layers "F.Cu" "F.Mask" "F.Paste")
			(net "GND")
		)
	)
	(footprint ""
		(layer "F.Cu")
		(at 90.397076 -79.078836)
		(property "Reference" "D98"
			(at -45.69841 38.649402 90)
			(unlocked yes)
			(layer "F.SilkS")
			(effects
				(font
					(size 0.635 0.4064)
					(thickness 0.1524)
				)
				(justify left)
			)
		)
		(property "Value" ""
			(at 0 0 0)
			(layer "F.Fab")
			(effects
				(font
					(size 1.27 1.27)
				)
			)
		)
		(duplicate_pad_numbers_are_jumpers no)
		(fp_line
			(start -0.90678 0.4826)
			(end -0.90678 -0.4699)
			(stroke
				(width 0.1524)
				(type default)
			)
			(layer "F.SilkS")
		)
		(fp_line
			(start -0.89408 -0.4826)
			(end 0.90678 -0.4826)
			(stroke
				(width 0.1524)
				(type default)
			)
			(layer "F.SilkS")
		)
		(fp_line
			(start -0.79248 -0.4826)
			(end 1.03378 -0.4826)
			(stroke
				(width 0.1524)
				(type default)
			)
			(layer "F.SilkS")
		)
		(fp_line
			(start -0.64008 -0.4826)
			(end 1.16078 -0.4826)
			(stroke
				(width 0.1524)
				(type default)
			)
			(layer "F.SilkS")
		)
		(fp_line
			(start 0.90678 -0.4826)
			(end 0.90678 0.4826)
			(stroke
				(width 0.1524)
				(type default)
			)
			(layer "F.SilkS")
		)
		(fp_line
			(start 0.90678 0.4826)
			(end -0.90678 0.4826)
			(stroke
				(width 0.1524)
				(type default)
			)
			(layer "F.SilkS")
		)
		(fp_line
			(start 1.03378 -0.4826)
			(end 1.03378 0.4826)
			(stroke
				(width 0.1524)
				(type default)
			)
			(layer "F.SilkS")
		)
		(fp_line
			(start 1.03378 0.4826)
			(end -0.79248 0.4826)
			(stroke
				(width 0.1524)
				(type default)
			)
			(layer "F.SilkS")
		)
		(fp_line
			(start 1.16078 -0.4826)
			(end 1.16078 0.4826)
			(stroke
				(width 0.1524)
				(type default)
			)
			(layer "F.SilkS")
		)
		(fp_line
			(start 1.16078 0.4826)
			(end -0.64008 0.4826)
			(stroke
				(width 0.1524)
				(type default)
			)
			(layer "F.SilkS")
		)
		(fp_line
			(start -0.499872 -0.249936)
			(end 0.499872 -0.249936)
			(stroke
				(width 0.1)
				(type default)
			)
			(layer "F.Fab")
		)
		(fp_line
			(start -0.499872 0.249936)
			(end -0.499872 -0.249936)
			(stroke
				(width 0.1)
				(type default)
			)
			(layer "F.Fab")
		)
		(fp_line
			(start 0.499872 -0.249936)
			(end 0.499872 0.249936)
			(stroke
				(width 0.1)
				(type default)
			)
			(layer "F.Fab")
		)
		(fp_line
			(start 0.499872 0.249936)
			(end -0.499872 0.249936)
			(stroke
				(width 0.1)
				(type default)
			)
			(layer "F.Fab")
		)
		(pad "A" smd rect
			(at -0.47498 0)
			(size 0.6096 0.7112)
			(layers "F.Cu" "F.Mask" "F.Paste")
			(net "LED_P5V")
		)
		(pad "C" smd rect
			(at 0.47498 0)
			(size 0.6096 0.7112)
			(layers "F.Cu" "F.Mask" "F.Paste")
			(net "GND")
		)
	)
	(footprint ""
		(layer "F.Cu")
		(at 377.668536 -99.133152 -90)
		(property "Reference" "U83"
			(at -1.032002 -3.3909 0)
			(unlocked yes)
			(layer "F.SilkS")
			(effects
				(font
					(size 0.7874 0.5842)
					(thickness 0.1524)
				)
				(justify left)
			)
		)
		(property "Value" ""
			(at 0 0 270)
			(layer "F.Fab")
			(effects
				(font
					(size 1.27 1.27)
				)
			)
		)
		(duplicate_pad_numbers_are_jumpers no)
		(fp_line
			(start -2.0066 2.5527)
			(end -2.0066 -2.5527)
			(stroke
				(width 0.1524)
				(type default)
			)
			(layer "F.SilkS")
		)
		(fp_line
			(start 2.0066 2.5527)
			(end -2.0066 2.5527)
			(stroke
				(width 0.1524)
				(type default)
			)
			(layer "F.SilkS")
		)
		(fp_line
			(start 0 -1.9812)
			(end 0.5715 -2.5527)
			(stroke
				(width 0.1524)
				(type default)
			)
			(layer "F.SilkS")
		)
		(fp_line
			(start -2.0066 -2.5527)
			(end -0.5715 -2.5527)
			(stroke
				(width 0.1524)
				(type default)
			)
			(layer "F.SilkS")
		)
		(fp_line
			(start -0.5715 -2.5527)
			(end 0 -1.9812)
			(stroke
				(width 0.1524)
				(type default)
			)
			(layer "F.SilkS")
		)
		(fp_line
			(start 0.5715 -2.5527)
			(end 2.0066 -2.5527)
			(stroke
				(width 0.1524)
				(type default)
			)
			(layer "F.SilkS")
		)
		(fp_line
			(start 2.0066 -2.5527)
			(end 2.0066 2.5527)
			(stroke
				(width 0.1524)
				(type default)
			)
			(layer "F.SilkS")
		)
		(fp_poly
			(pts
				(xy -2.712212 -2.987548) (xy -3.04038 -2.433828) (xy -3.337052 -2.987548)
			)
			(stroke
				(width 0)
				(type default)
			)
			(fill yes)
			(layer "F.SilkS")
		)
		(fp_line
			(start -2.249932 2.549906)
			(end -2.249932 -2.549906)
			(stroke
				(width 0.1)
				(type default)
			)
			(layer "F.Fab")
		)
		(fp_line
			(start 2.249932 2.549906)
			(end -2.249932 2.549906)
			(stroke
				(width 0.1)
				(type default)
			)
			(layer "F.Fab")
		)
		(fp_line
			(start -2.249932 -2.549906)
			(end 2.249932 -2.549906)
			(stroke
				(width 0.1)
				(type default)
			)
			(layer "F.Fab")
		)
		(fp_line
			(start 2.249932 -2.549906)
			(end 2.249932 2.549906)
			(stroke
				(width 0.1)
				(type default)
			)
			(layer "F.Fab")
		)
		(fp_poly
			(pts
				(xy -4.36372 -1.608328) (xy -4.36372 -2.233168) (xy -3.81 -1.905)
			)
			(stroke
				(width 0)
				(type default)
			)
			(fill yes)
			(layer "F.Fab")
		)
		(pad "1" smd rect
			(at -2.921 -1.949958 180)
			(size 0.3556 1.4986)
			(layers "F.Cu" "F.Mask" "F.Paste")
			(net "PD_GTL2014_BMC_JTAG_DIR_2")
		)
		(pad "2" smd rect
			(at -2.921 -1.299972 180)
			(size 0.3556 1.4986)
			(layers "F.Cu" "F.Mask" "F.Paste")
			(net "PD_JTAG_DBP_B0")
		)
		(pad "3" smd rect
			(at -2.921 -0.649986 180)
			(size 0.3556 1.4986)
			(layers "F.Cu" "F.Mask" "F.Paste")
			(net "JTAG_DBP_PRDY_R_N")
		)
		(pad "4" smd rect
			(at -2.921 0 180)
			(size 0.3556 1.4986)
			(layers "F.Cu" "F.Mask" "F.Paste")
			(net "P0V7_JTAG_VREF_2")
		)
		(pad "5" smd rect
			(at -2.921 0.649986 180)
			(size 0.3556 1.4986)
			(layers "F.Cu" "F.Mask" "F.Paste")
			(net "PD_JTAG_DBP_B2")
		)
		(pad "6" smd rect
			(at -2.921 1.299972 180)
			(size 0.3556 1.4986)
			(layers "F.Cu" "F.Mask" "F.Paste")
			(net "JTAG_DBP_FB_TDO")
		)
		(pad "7" smd rect
			(at -2.921 1.949958 180)
			(size 0.3556 1.4986)
			(layers "F.Cu" "F.Mask" "F.Paste")
			(net "GND")
		)
		(pad "8" smd rect
			(at 2.921 1.949958 180)
			(size 0.3556 1.4986)
			(layers "F.Cu" "F.Mask" "F.Paste")
			(net "GND")
		)
		(pad "9" smd rect
			(at 2.921 1.299972 180)
			(size 0.3556 1.4986)
			(layers "F.Cu" "F.Mask" "F.Paste")
			(net "JTAG_BMC_DBP_TDO_R")
		)
		(pad "10" smd rect
			(at 2.921 0.649986 180)
			(size 0.3556 1.4986)
			(layers "F.Cu" "F.Mask" "F.Paste")
			(net "TP_JTAG_BMC_A2")
		)
		(pad "11" smd rect
			(at 2.921 0 180)
			(size 0.3556 1.4986)
			(layers "F.Cu" "F.Mask" "F.Paste")
			(net "GND")
		)
		(pad "12" smd rect
			(at 2.921 -0.649986 180)
			(size 0.3556 1.4986)
			(layers "F.Cu" "F.Mask" "F.Paste")
			(net "JTAG_DBP_BMC_PRDY_R1_N")
		)
		(pad "13" smd rect
			(at 2.921 -1.299972 180)
			(size 0.3556 1.4986)
			(layers "F.Cu" "F.Mask" "F.Paste")
			(net "TP_JTAG_BMC_A0")
		)
		(pad "14" smd rect
			(at 2.921 -1.949958 180)
			(size 0.3556 1.4986)
			(layers "F.Cu" "F.Mask" "F.Paste")
			(net "P3V3_AUX")
		)
	)
	(footprint ""
		(layer "F.Cu")
		(at 432.74488 -128.361948 90)
		(property "Reference" "PR4230"
			(at 0 0 90)
			(layer "F.SilkS")
			(hide yes)
			(effects
				(font
					(size 1.27 1.27)
				)
			)
		)
		(property "Value" ""
			(at 0 0 90)
			(layer "F.Fab")
			(effects
				(font
					(size 1.27 1.27)
				)
			)
		)
		(duplicate_pad_numbers_are_jumpers no)
		(fp_line
			(start 0.7874 -0.4064)
			(end 0.7874 0.4064)
			(stroke
				(width 0.1524)
				(type default)
			)
			(layer "F.SilkS")
		)
		(fp_line
			(start -0.7874 -0.4064)
			(end 0.7874 -0.4064)
			(stroke
				(width 0.1524)
				(type default)
			)
			(layer "F.SilkS")
		)
		(fp_line
			(start 0.7874 0.4064)
			(end -0.7874 0.4064)
			(stroke
				(width 0.1524)
				(type default)
			)
			(layer "F.SilkS")
		)
		(fp_line
			(start -0.7874 0.4064)
			(end -0.7874 -0.4064)
			(stroke
				(width 0.1524)
				(type default)
			)
			(layer "F.SilkS")
		)
		(fp_line
			(start -0.12065 -0.305054)
			(end -0.12065 -0.2794)
			(stroke
				(width 0.1)
				(type default)
			)
			(layer "F.Fab")
		)
		(fp_line
			(start -0.67945 -0.305054)
			(end -0.12065 -0.305054)
			(stroke
				(width 0.1)
				(type default)
			)
			(layer "F.Fab")
		)
		(fp_line
			(start 0.67945 -0.3048)
			(end 0.67945 0.3048)
			(stroke
				(width 0.1)
				(type default)
			)
			(layer "F.Fab")
		)
		(fp_line
			(start 0.12065 -0.3048)
			(end 0.67945 -0.3048)
			(stroke
				(width 0.1)
				(type default)
			)
			(layer "F.Fab")
		)
		(fp_line
			(start 0.12065 -0.2794)
			(end 0.12065 -0.3048)
			(stroke
				(width 0.1)
				(type default)
			)
			(layer "F.Fab")
		)
		(fp_line
			(start -0.12065 -0.2794)
			(end 0.12065 -0.2794)
			(stroke
				(width 0.1)
				(type default)
			)
			(layer "F.Fab")
		)
		(fp_line
			(start 0.120396 0.2794)
			(end -0.12065 0.2794)
			(stroke
				(width 0.1)
				(type default)
			)
			(layer "F.Fab")
		)
		(fp_line
			(start -0.12065 0.2794)
			(end -0.12065 0.3048)
			(stroke
				(width 0.1)
				(type default)
			)
			(layer "F.Fab")
		)
		(fp_line
			(start 0.67945 0.3048)
			(end 0.120396 0.3048)
			(stroke
				(width 0.1)
				(type default)
			)
			(layer "F.Fab")
		)
		(fp_line
			(start 0.120396 0.3048)
			(end 0.120396 0.2794)
			(stroke
				(width 0.1)
				(type default)
			)
			(layer "F.Fab")
		)
		(fp_line
			(start -0.12065 0.3048)
			(end -0.67945 0.3048)
			(stroke
				(width 0.1)
				(type default)
			)
			(layer "F.Fab")
		)
		(fp_line
			(start -0.67945 0.3048)
			(end -0.67945 -0.305054)
			(stroke
				(width 0.1)
				(type default)
			)
			(layer "F.Fab")
		)
		(pad "1" smd circle
			(at -0.40005 0 90)
			(size 0 0)
			(layers "F.Cu" "F.Mask" "F.Paste")
			(net "NC_PVCCD_HV_CPU0_ACSP2")
		)
		(pad "2" smd circle
			(at 0.40005 0 90)
			(size 0 0)
			(layers "F.Cu" "F.Mask" "F.Paste")
			(net "GND")
		)
	)
	(footprint ""
		(layer "F.Cu")
		(at 100.566982 -333.804514 -90)
		(property "Reference" "PC563_P1_1"
			(at 0 0 270)
			(layer "F.SilkS")
			(hide yes)
			(effects
				(font
					(size 1.27 1.27)
				)
			)
		)
		(property "Value" ""
			(at 0 0 270)
			(layer "F.Fab")
			(effects
				(font
					(size 1.27 1.27)
				)
			)
		)
		(duplicate_pad_numbers_are_jumpers no)
		(fp_line
			(start -0.7874 0.4064)
			(end -0.7874 -0.4064)
			(stroke
				(width 0.1524)
				(type default)
			)
			(layer "F.SilkS")
		)
		(fp_line
			(start 0.7874 0.4064)
			(end -0.7874 0.4064)
			(stroke
				(width 0.1524)
				(type default)
			)
			(layer "F.SilkS")
		)
		(fp_line
			(start -0.7874 -0.4064)
			(end 0.7874 -0.4064)
			(stroke
				(width 0.1524)
				(type default)
			)
			(layer "F.SilkS")
		)
		(fp_line
			(start 0.7874 -0.4064)
			(end 0.7874 0.4064)
			(stroke
				(width 0.1524)
				(type default)
			)
			(layer "F.SilkS")
		)
		(fp_line
			(start -0.67945 0.3048)
			(end -0.67945 -0.305054)
			(stroke
				(width 0.1)
				(type default)
			)
			(layer "F.Fab")
		)
		(fp_line
			(start -0.12065 0.3048)
			(end -0.67945 0.3048)
			(stroke
				(width 0.1)
				(type default)
			)
			(layer "F.Fab")
		)
		(fp_line
			(start 0.120396 0.3048)
			(end 0.120396 0.2794)
			(stroke
				(width 0.1)
				(type default)
			)
			(layer "F.Fab")
		)
		(fp_line
			(start 0.67945 0.3048)
			(end 0.120396 0.3048)
			(stroke
				(width 0.1)
				(type default)
			)
			(layer "F.Fab")
		)
		(fp_line
			(start -0.12065 0.2794)
			(end -0.12065 0.3048)
			(stroke
				(width 0.1)
				(type default)
			)
			(layer "F.Fab")
		)
		(fp_line
			(start 0.120396 0.2794)
			(end -0.12065 0.2794)
			(stroke
				(width 0.1)
				(type default)
			)
			(layer "F.Fab")
		)
		(fp_line
			(start -0.12065 -0.2794)
			(end 0.12065 -0.2794)
			(stroke
				(width 0.1)
				(type default)
			)
			(layer "F.Fab")
		)
		(fp_line
			(start 0.12065 -0.2794)
			(end 0.12065 -0.3048)
			(stroke
				(width 0.1)
				(type default)
			)
			(layer "F.Fab")
		)
		(fp_line
			(start 0.12065 -0.3048)
			(end 0.67945 -0.3048)
			(stroke
				(width 0.1)
				(type default)
			)
			(layer "F.Fab")
		)
		(fp_line
			(start 0.67945 -0.3048)
			(end 0.67945 0.3048)
			(stroke
				(width 0.1)
				(type default)
			)
			(layer "F.Fab")
		)
		(fp_line
			(start -0.67945 -0.305054)
			(end -0.12065 -0.305054)
			(stroke
				(width 0.1)
				(type default)
			)
			(layer "F.Fab")
		)
		(fp_line
			(start -0.12065 -0.305054)
			(end -0.12065 -0.2794)
			(stroke
				(width 0.1)
				(type default)
			)
			(layer "F.Fab")
		)
		(pad "1" smd circle
			(at -0.40005 0 270)
			(size 0 0)
			(layers "F.Cu" "F.Mask" "F.Paste")
			(net "SW_P12V_PVCCIN_CPU1_FLT")
		)
		(pad "2" smd circle
			(at 0.40005 0 270)
			(size 0 0)
			(layers "F.Cu" "F.Mask" "F.Paste")
			(net "GND")
		)
	)
	(footprint ""
		(layer "F.Cu")
		(at 421.15359 -180.749194 -90)
		(property "Reference" "PR1707"
			(at 0 0 270)
			(layer "F.SilkS")
			(hide yes)
			(effects
				(font
					(size 1.27 1.27)
				)
			)
		)
		(property "Value" ""
			(at 0 0 270)
			(layer "F.Fab")
			(effects
				(font
					(size 1.27 1.27)
				)
			)
		)
		(duplicate_pad_numbers_are_jumpers no)
		(fp_line
			(start -0.7874 0.4064)
			(end -0.7874 -0.4064)
			(stroke
				(width 0.1524)
				(type default)
			)
			(layer "F.SilkS")
		)
		(fp_line
			(start 0.7874 0.4064)
			(end -0.7874 0.4064)
			(stroke
				(width 0.1524)
				(type default)
			)
			(layer "F.SilkS")
		)
		(fp_line
			(start -0.7874 -0.4064)
			(end 0.7874 -0.4064)
			(stroke
				(width 0.1524)
				(type default)
			)
			(layer "F.SilkS")
		)
		(fp_line
			(start 0.7874 -0.4064)
			(end 0.7874 0.4064)
			(stroke
				(width 0.1524)
				(type default)
			)
			(layer "F.SilkS")
		)
		(fp_line
			(start -0.67945 0.3048)
			(end -0.67945 -0.305054)
			(stroke
				(width 0.1)
				(type default)
			)
			(layer "F.Fab")
		)
		(fp_line
			(start -0.12065 0.3048)
			(end -0.67945 0.3048)
			(stroke
				(width 0.1)
				(type default)
			)
			(layer "F.Fab")
		)
		(fp_line
			(start 0.120396 0.3048)
			(end 0.120396 0.2794)
			(stroke
				(width 0.1)
				(type default)
			)
			(layer "F.Fab")
		)
		(fp_line
			(start 0.67945 0.3048)
			(end 0.120396 0.3048)
			(stroke
				(width 0.1)
				(type default)
			)
			(layer "F.Fab")
		)
		(fp_line
			(start -0.12065 0.2794)
			(end -0.12065 0.3048)
			(stroke
				(width 0.1)
				(type default)
			)
			(layer "F.Fab")
		)
		(fp_line
			(start 0.120396 0.2794)
			(end -0.12065 0.2794)
			(stroke
				(width 0.1)
				(type default)
			)
			(layer "F.Fab")
		)
		(fp_line
			(start -0.12065 -0.2794)
			(end 0.12065 -0.2794)
			(stroke
				(width 0.1)
				(type default)
			)
			(layer "F.Fab")
		)
		(fp_line
			(start 0.12065 -0.2794)
			(end 0.12065 -0.3048)
			(stroke
				(width 0.1)
				(type default)
			)
			(layer "F.Fab")
		)
		(fp_line
			(start 0.12065 -0.3048)
			(end 0.67945 -0.3048)
			(stroke
				(width 0.1)
				(type default)
			)
			(layer "F.Fab")
		)
		(fp_line
			(start 0.67945 -0.3048)
			(end 0.67945 0.3048)
			(stroke
				(width 0.1)
				(type default)
			)
			(layer "F.Fab")
		)
		(fp_line
			(start -0.67945 -0.305054)
			(end -0.12065 -0.305054)
			(stroke
				(width 0.1)
				(type default)
			)
			(layer "F.Fab")
		)
		(fp_line
			(start -0.12065 -0.305054)
			(end -0.12065 -0.2794)
			(stroke
				(width 0.1)
				(type default)
			)
			(layer "F.Fab")
		)
		(pad "1" smd circle
			(at -0.40005 0 270)
			(size 0 0)
			(layers "F.Cu" "F.Mask" "F.Paste")
			(net "PVCCINFAON_CPU0_LSET2")
		)
		(pad "2" smd circle
			(at 0.40005 0 270)
			(size 0 0)
			(layers "F.Cu" "F.Mask" "F.Paste")
			(net "GND")
		)
	)
	(footprint ""
		(layer "F.Cu")
		(at 259.89788 -46.634146 90)
		(property "Reference" "PC2198"
			(at 0 0 90)
			(layer "F.SilkS")
			(hide yes)
			(effects
				(font
					(size 1.27 1.27)
				)
			)
		)
		(property "Value" ""
			(at 0 0 90)
			(layer "F.Fab")
			(effects
				(font
					(size 1.27 1.27)
				)
			)
		)
		(duplicate_pad_numbers_are_jumpers no)
		(fp_line
			(start 0.7874 -0.4064)
			(end 0.7874 0.4064)
			(stroke
				(width 0.1524)
				(type default)
			)
			(layer "F.SilkS")
		)
		(fp_line
			(start -0.7874 -0.4064)
			(end 0.7874 -0.4064)
			(stroke
				(width 0.1524)
				(type default)
			)
			(layer "F.SilkS")
		)
		(fp_line
			(start 0.7874 0.4064)
			(end -0.7874 0.4064)
			(stroke
				(width 0.1524)
				(type default)
			)
			(layer "F.SilkS")
		)
		(fp_line
			(start -0.7874 0.4064)
			(end -0.7874 -0.4064)
			(stroke
				(width 0.1524)
				(type default)
			)
			(layer "F.SilkS")
		)
		(fp_line
			(start -0.12065 -0.305054)
			(end -0.12065 -0.2794)
			(stroke
				(width 0.1)
				(type default)
			)
			(layer "F.Fab")
		)
		(fp_line
			(start -0.67945 -0.305054)
			(end -0.12065 -0.305054)
			(stroke
				(width 0.1)
				(type default)
			)
			(layer "F.Fab")
		)
		(fp_line
			(start 0.67945 -0.3048)
			(end 0.67945 0.3048)
			(stroke
				(width 0.1)
				(type default)
			)
			(layer "F.Fab")
		)
		(fp_line
			(start 0.12065 -0.3048)
			(end 0.67945 -0.3048)
			(stroke
				(width 0.1)
				(type default)
			)
			(layer "F.Fab")
		)
		(fp_line
			(start 0.12065 -0.2794)
			(end 0.12065 -0.3048)
			(stroke
				(width 0.1)
				(type default)
			)
			(layer "F.Fab")
		)
		(fp_line
			(start -0.12065 -0.2794)
			(end 0.12065 -0.2794)
			(stroke
				(width 0.1)
				(type default)
			)
			(layer "F.Fab")
		)
		(fp_line
			(start 0.120396 0.2794)
			(end -0.12065 0.2794)
			(stroke
				(width 0.1)
				(type default)
			)
			(layer "F.Fab")
		)
		(fp_line
			(start -0.12065 0.2794)
			(end -0.12065 0.3048)
			(stroke
				(width 0.1)
				(type default)
			)
			(layer "F.Fab")
		)
		(fp_line
			(start 0.67945 0.3048)
			(end 0.120396 0.3048)
			(stroke
				(width 0.1)
				(type default)
			)
			(layer "F.Fab")
		)
		(fp_line
			(start 0.120396 0.3048)
			(end 0.120396 0.2794)
			(stroke
				(width 0.1)
				(type default)
			)
			(layer "F.Fab")
		)
		(fp_line
			(start -0.12065 0.3048)
			(end -0.67945 0.3048)
			(stroke
				(width 0.1)
				(type default)
			)
			(layer "F.Fab")
		)
		(fp_line
			(start -0.67945 0.3048)
			(end -0.67945 -0.305054)
			(stroke
				(width 0.1)
				(type default)
			)
			(layer "F.Fab")
		)
		(pad "1" smd circle
			(at -0.40005 0 90)
			(size 0 0)
			(layers "F.Cu" "F.Mask" "F.Paste")
			(net "P12V_AUX")
		)
		(pad "2" smd circle
			(at 0.40005 0 90)
			(size 0 0)
			(layers "F.Cu" "F.Mask" "F.Paste")
			(net "GND")
		)
	)
	(footprint ""
		(layer "F.Cu")
		(at 104.723438 -315.66739 90)
		(property "Reference" "PC589"
			(at 0 0 90)
			(layer "F.SilkS")
			(hide yes)
			(effects
				(font
					(size 1.27 1.27)
				)
			)
		)
		(property "Value" ""
			(at 0 0 90)
			(layer "F.Fab")
			(effects
				(font
					(size 1.27 1.27)
				)
			)
		)
		(duplicate_pad_numbers_are_jumpers no)
		(fp_line
			(start 2.750058 0.999998)
			(end -2.750058 0.999998)
			(stroke
				(width 0.1524)
				(type default)
			)
			(layer "F.SilkS")
		)
		(fp_circle
			(center 0 0.999998)
			(end 0 3.750056)
			(stroke
				(width 0.1524)
				(type default)
			)
			(fill no)
			(layer "F.SilkS")
		)
		(fp_poly
			(pts
				(arc
					(start 2.750058 0.999998)
					(mid 0 3.750056)
					(end -2.750058 0.999998)
				)
			)
			(stroke
				(width 0)
				(type default)
			)
			(fill yes)
			(layer "F.SilkS")
		)
		(fp_circle
			(center 0 0.999998)
			(end 0 3.750056)
			(stroke
				(width 0.1)
				(type default)
			)
			(fill no)
			(layer "F.Fab")
		)
		(pad "1" thru_hole rect
			(at 0 0 90)
			(size 1.5748 1.5748)
			(drill 1.0668)
			(layers "*.Cu" "*.Mask")
			(remove_unused_layers no)
			(net "PVCCIN_CPU1")
			(clearance 0)
			(padstack
				(mode front_inner_back)
				(layer "Inner"
					(shape circle)
					(size 1.5748 1.5748)
					(clearance 0)
				)
				(layer "B.Cu"
					(shape rect)
					(size 1.5748 1.5748)
					(clearance 0)
				)
			)
		)
		(pad "2" thru_hole circle
			(at 0 1.999996 90)
			(size 1.5748 1.5748)
			(drill 1.0668)
			(layers "*.Cu" "*.Mask")
			(remove_unused_layers no)
			(net "GND")
			(clearance 0)
		)
	)
	(footprint ""
		(layer "F.Cu")
		(at 386.544312 -76.39685 90)
		(property "Reference" "PC1234"
			(at 0 0 90)
			(layer "F.SilkS")
			(hide yes)
			(effects
				(font
					(size 1.27 1.27)
				)
			)
		)
		(property "Value" ""
			(at 0 0 90)
			(layer "F.Fab")
			(effects
				(font
					(size 1.27 1.27)
				)
			)
		)
		(duplicate_pad_numbers_are_jumpers no)
		(fp_line
			(start 0.7874 -0.4064)
			(end 0.7874 0.4064)
			(stroke
				(width 0.1524)
				(type default)
			)
			(layer "F.SilkS")
		)
		(fp_line
			(start -0.7874 -0.4064)
			(end 0.7874 -0.4064)
			(stroke
				(width 0.1524)
				(type default)
			)
			(layer "F.SilkS")
		)
		(fp_line
			(start 0.7874 0.4064)
			(end -0.7874 0.4064)
			(stroke
				(width 0.1524)
				(type default)
			)
			(layer "F.SilkS")
		)
		(fp_line
			(start -0.7874 0.4064)
			(end -0.7874 -0.4064)
			(stroke
				(width 0.1524)
				(type default)
			)
			(layer "F.SilkS")
		)
		(fp_line
			(start -0.12065 -0.305054)
			(end -0.12065 -0.2794)
			(stroke
				(width 0.1)
				(type default)
			)
			(layer "F.Fab")
		)
		(fp_line
			(start -0.67945 -0.305054)
			(end -0.12065 -0.305054)
			(stroke
				(width 0.1)
				(type default)
			)
			(layer "F.Fab")
		)
		(fp_line
			(start 0.67945 -0.3048)
			(end 0.67945 0.3048)
			(stroke
				(width 0.1)
				(type default)
			)
			(layer "F.Fab")
		)
		(fp_line
			(start 0.12065 -0.3048)
			(end 0.67945 -0.3048)
			(stroke
				(width 0.1)
				(type default)
			)
			(layer "F.Fab")
		)
		(fp_line
			(start 0.12065 -0.2794)
			(end 0.12065 -0.3048)
			(stroke
				(width 0.1)
				(type default)
			)
			(layer "F.Fab")
		)
		(fp_line
			(start -0.12065 -0.2794)
			(end 0.12065 -0.2794)
			(stroke
				(width 0.1)
				(type default)
			)
			(layer "F.Fab")
		)
		(fp_line
			(start 0.120396 0.2794)
			(end -0.12065 0.2794)
			(stroke
				(width 0.1)
				(type default)
			)
			(layer "F.Fab")
		)
		(fp_line
			(start -0.12065 0.2794)
			(end -0.12065 0.3048)
			(stroke
				(width 0.1)
				(type default)
			)
			(layer "F.Fab")
		)
		(fp_line
			(start 0.67945 0.3048)
			(end 0.120396 0.3048)
			(stroke
				(width 0.1)
				(type default)
			)
			(layer "F.Fab")
		)
		(fp_line
			(start 0.120396 0.3048)
			(end 0.120396 0.2794)
			(stroke
				(width 0.1)
				(type default)
			)
			(layer "F.Fab")
		)
		(fp_line
			(start -0.12065 0.3048)
			(end -0.67945 0.3048)
			(stroke
				(width 0.1)
				(type default)
			)
			(layer "F.Fab")
		)
		(fp_line
			(start -0.67945 0.3048)
			(end -0.67945 -0.305054)
			(stroke
				(width 0.1)
				(type default)
			)
			(layer "F.Fab")
		)
		(pad "1" smd circle
			(at -0.40005 0 90)
			(size 0 0)
			(layers "F.Cu" "F.Mask" "F.Paste")
			(net "SW_P1V8_PCH_AUX_FLT")
		)
		(pad "2" smd circle
			(at 0.40005 0 90)
			(size 0 0)
			(layers "F.Cu" "F.Mask" "F.Paste")
			(net "GND")
		)
	)
	(footprint ""
		(layer "F.Cu")
		(at 99.589082 -74.911966 -90)
		(property "Reference" "R3073"
			(at 0 0 270)
			(layer "F.SilkS")
			(hide yes)
			(effects
				(font
					(size 1.27 1.27)
				)
			)
		)
		(property "Value" ""
			(at 0 0 270)
			(layer "F.Fab")
			(effects
				(font
					(size 1.27 1.27)
				)
			)
		)
		(duplicate_pad_numbers_are_jumpers no)
		(fp_line
			(start -0.7874 0.4064)
			(end -0.7874 -0.4064)
			(stroke
				(width 0.1524)
				(type default)
			)
			(layer "F.SilkS")
		)
		(fp_line
			(start 0.7874 0.4064)
			(end -0.7874 0.4064)
			(stroke
				(width 0.1524)
				(type default)
			)
			(layer "F.SilkS")
		)
		(fp_line
			(start -0.7874 -0.4064)
			(end 0.7874 -0.4064)
			(stroke
				(width 0.1524)
				(type default)
			)
			(layer "F.SilkS")
		)
		(fp_line
			(start 0.7874 -0.4064)
			(end 0.7874 0.4064)
			(stroke
				(width 0.1524)
				(type default)
			)
			(layer "F.SilkS")
		)
		(fp_line
			(start -0.67945 0.3048)
			(end -0.67945 -0.305054)
			(stroke
				(width 0.1)
				(type default)
			)
			(layer "F.Fab")
		)
		(fp_line
			(start -0.12065 0.3048)
			(end -0.67945 0.3048)
			(stroke
				(width 0.1)
				(type default)
			)
			(layer "F.Fab")
		)
		(fp_line
			(start 0.120396 0.3048)
			(end 0.120396 0.2794)
			(stroke
				(width 0.1)
				(type default)
			)
			(layer "F.Fab")
		)
		(fp_line
			(start 0.67945 0.3048)
			(end 0.120396 0.3048)
			(stroke
				(width 0.1)
				(type default)
			)
			(layer "F.Fab")
		)
		(fp_line
			(start -0.12065 0.2794)
			(end -0.12065 0.3048)
			(stroke
				(width 0.1)
				(type default)
			)
			(layer "F.Fab")
		)
		(fp_line
			(start 0.120396 0.2794)
			(end -0.12065 0.2794)
			(stroke
				(width 0.1)
				(type default)
			)
			(layer "F.Fab")
		)
		(fp_line
			(start -0.12065 -0.2794)
			(end 0.12065 -0.2794)
			(stroke
				(width 0.1)
				(type default)
			)
			(layer "F.Fab")
		)
		(fp_line
			(start 0.12065 -0.2794)
			(end 0.12065 -0.3048)
			(stroke
				(width 0.1)
				(type default)
			)
			(layer "F.Fab")
		)
		(fp_line
			(start 0.12065 -0.3048)
			(end 0.67945 -0.3048)
			(stroke
				(width 0.1)
				(type default)
			)
			(layer "F.Fab")
		)
		(fp_line
			(start 0.67945 -0.3048)
			(end 0.67945 0.3048)
			(stroke
				(width 0.1)
				(type default)
			)
			(layer "F.Fab")
		)
		(fp_line
			(start -0.67945 -0.305054)
			(end -0.12065 -0.305054)
			(stroke
				(width 0.1)
				(type default)
			)
			(layer "F.Fab")
		)
		(fp_line
			(start -0.12065 -0.305054)
			(end -0.12065 -0.2794)
			(stroke
				(width 0.1)
				(type default)
			)
			(layer "F.Fab")
		)
		(pad "1" smd circle
			(at -0.40005 0 270)
			(size 0 0)
			(layers "F.Cu" "F.Mask" "F.Paste")
			(net "LED_FM_PCH_SLP_S4_N")
		)
		(pad "2" smd circle
			(at 0.40005 0 270)
			(size 0 0)
			(layers "F.Cu" "F.Mask" "F.Paste")
			(net "P3V3_AUX")
		)
	)
	(footprint ""
		(layer "F.Cu")
		(at 122.390154 -408.517344 -90)
		(property "Reference" "C1517"
			(at 0 0 270)
			(layer "F.SilkS")
			(hide yes)
			(effects
				(font
					(size 1.27 1.27)
				)
			)
		)
		(property "Value" ""
			(at 0 0 270)
			(layer "F.Fab")
			(effects
				(font
					(size 1.27 1.27)
				)
			)
		)
		(duplicate_pad_numbers_are_jumpers no)
		(fp_line
			(start -0.299974 0.150114)
			(end -0.299974 -0.150114)
			(stroke
				(width 0.1)
				(type default)
			)
			(layer "F.Fab")
		)
		(fp_line
			(start 0.299974 0.150114)
			(end -0.299974 0.150114)
			(stroke
				(width 0.1)
				(type default)
			)
			(layer "F.Fab")
		)
		(fp_line
			(start -0.299974 -0.150114)
			(end 0.299974 -0.150114)
			(stroke
				(width 0.1)
				(type default)
			)
			(layer "F.Fab")
		)
		(fp_line
			(start 0.299974 -0.150114)
			(end 0.299974 0.150114)
			(stroke
				(width 0.1)
				(type default)
			)
			(layer "F.Fab")
		)
		(pad "1" smd rect
			(at -0.2667 0 270)
			(size 0.3048 0.381)
			(layers "F.Cu" "F.Mask" "F.Paste")
			(net "P5E_CPU1_PE3_TX_C_DP<15>")
		)
		(pad "2" smd rect
			(at 0.2667 0 270)
			(size 0.3048 0.381)
			(layers "F.Cu" "F.Mask" "F.Paste")
			(net "P5E_CPU1_PE3_TX_DP<15>")
		)
	)
	(footprint ""
		(layer "F.Cu")
		(at 54.242716 -116.134388 180)
		(property "Reference" "R3707"
			(at 0 0 180)
			(layer "F.SilkS")
			(hide yes)
			(effects
				(font
					(size 1.27 1.27)
				)
			)
		)
		(property "Value" ""
			(at 0 0 180)
			(layer "F.Fab")
			(effects
				(font
					(size 1.27 1.27)
				)
			)
		)
		(duplicate_pad_numbers_are_jumpers no)
		(fp_line
			(start 0.7874 0.4064)
			(end -0.7874 0.4064)
			(stroke
				(width 0.1524)
				(type default)
			)
			(layer "F.SilkS")
		)
		(fp_line
			(start 0.7874 -0.4064)
			(end 0.7874 0.4064)
			(stroke
				(width 0.1524)
				(type default)
			)
			(layer "F.SilkS")
		)
		(fp_line
			(start -0.7874 0.4064)
			(end -0.7874 -0.4064)
			(stroke
				(width 0.1524)
				(type default)
			)
			(layer "F.SilkS")
		)
		(fp_line
			(start -0.7874 -0.4064)
			(end 0.7874 -0.4064)
			(stroke
				(width 0.1524)
				(type default)
			)
			(layer "F.SilkS")
		)
		(fp_line
			(start 0.67945 0.3048)
			(end 0.120396 0.3048)
			(stroke
				(width 0.1)
				(type default)
			)
			(layer "F.Fab")
		)
		(fp_line
			(start 0.67945 -0.3048)
			(end 0.67945 0.3048)
			(stroke
				(width 0.1)
				(type default)
			)
			(layer "F.Fab")
		)
		(fp_line
			(start 0.12065 -0.2794)
			(end 0.12065 -0.3048)
			(stroke
				(width 0.1)
				(type default)
			)
			(layer "F.Fab")
		)
		(fp_line
			(start 0.12065 -0.3048)
			(end 0.67945 -0.3048)
			(stroke
				(width 0.1)
				(type default)
			)
			(layer "F.Fab")
		)
		(fp_line
			(start 0.120396 0.3048)
			(end 0.120396 0.2794)
			(stroke
				(width 0.1)
				(type default)
			)
			(layer "F.Fab")
		)
		(fp_line
			(start 0.120396 0.2794)
			(end -0.12065 0.2794)
			(stroke
				(width 0.1)
				(type default)
			)
			(layer "F.Fab")
		)
		(fp_line
			(start -0.12065 0.3048)
			(end -0.67945 0.3048)
			(stroke
				(width 0.1)
				(type default)
			)
			(layer "F.Fab")
		)
		(fp_line
			(start -0.12065 0.2794)
			(end -0.12065 0.3048)
			(stroke
				(width 0.1)
				(type default)
			)
			(layer "F.Fab")
		)
		(fp_line
			(start -0.12065 -0.2794)
			(end 0.12065 -0.2794)
			(stroke
				(width 0.1)
				(type default)
			)
			(layer "F.Fab")
		)
		(fp_line
			(start -0.12065 -0.305054)
			(end -0.12065 -0.2794)
			(stroke
				(width 0.1)
				(type default)
			)
			(layer "F.Fab")
		)
		(fp_line
			(start -0.67945 0.3048)
			(end -0.67945 -0.305054)
			(stroke
				(width 0.1)
				(type default)
			)
			(layer "F.Fab")
		)
		(fp_line
			(start -0.67945 -0.305054)
			(end -0.12065 -0.305054)
			(stroke
				(width 0.1)
				(type default)
			)
			(layer "F.Fab")
		)
		(pad "1" smd circle
			(at -0.40005 0 180)
			(size 0 0)
			(layers "F.Cu" "F.Mask" "F.Paste")
			(net "PCA9548_PCIE0_ADDR1")
		)
		(pad "2" smd circle
			(at 0.40005 0 180)
			(size 0 0)
			(layers "F.Cu" "F.Mask" "F.Paste")
			(net "GND")
		)
	)
	(footprint ""
		(layer "F.Cu")
		(at 185.806842 -24.170132)
		(property "Reference" "PC2234"
			(at 0 0 0)
			(layer "F.SilkS")
			(hide yes)
			(effects
				(font
					(size 1.27 1.27)
				)
			)
		)
		(property "Value" ""
			(at 0 0 0)
			(layer "F.Fab")
			(effects
				(font
					(size 1.27 1.27)
				)
			)
		)
		(duplicate_pad_numbers_are_jumpers no)
		(fp_line
			(start -0.7874 -0.4064)
			(end 0.7874 -0.4064)
			(stroke
				(width 0.1524)
				(type default)
			)
			(layer "F.SilkS")
		)
		(fp_line
			(start -0.7874 0.4064)
			(end -0.7874 -0.4064)
			(stroke
				(width 0.1524)
				(type default)
			)
			(layer "F.SilkS")
		)
		(fp_line
			(start 0.7874 -0.4064)
			(end 0.7874 0.4064)
			(stroke
				(width 0.1524)
				(type default)
			)
			(layer "F.SilkS")
		)
		(fp_line
			(start 0.7874 0.4064)
			(end -0.7874 0.4064)
			(stroke
				(width 0.1524)
				(type default)
			)
			(layer "F.SilkS")
		)
		(fp_line
			(start -0.67945 -0.305054)
			(end -0.12065 -0.305054)
			(stroke
				(width 0.1)
				(type default)
			)
			(layer "F.Fab")
		)
		(fp_line
			(start -0.67945 0.3048)
			(end -0.67945 -0.305054)
			(stroke
				(width 0.1)
				(type default)
			)
			(layer "F.Fab")
		)
		(fp_line
			(start -0.12065 -0.305054)
			(end -0.12065 -0.2794)
			(stroke
				(width 0.1)
				(type default)
			)
			(layer "F.Fab")
		)
		(fp_line
			(start -0.12065 -0.2794)
			(end 0.12065 -0.2794)
			(stroke
				(width 0.1)
				(type default)
			)
			(layer "F.Fab")
		)
		(fp_line
			(start -0.12065 0.2794)
			(end -0.12065 0.3048)
			(stroke
				(width 0.1)
				(type default)
			)
			(layer "F.Fab")
		)
		(fp_line
			(start -0.12065 0.3048)
			(end -0.67945 0.3048)
			(stroke
				(width 0.1)
				(type default)
			)
			(layer "F.Fab")
		)
		(fp_line
			(start 0.120396 0.2794)
			(end -0.12065 0.2794)
			(stroke
				(width 0.1)
				(type default)
			)
			(layer "F.Fab")
		)
		(fp_line
			(start 0.120396 0.3048)
			(end 0.120396 0.2794)
			(stroke
				(width 0.1)
				(type default)
			)
			(layer "F.Fab")
		)
		(fp_line
			(start 0.12065 -0.3048)
			(end 0.67945 -0.3048)
			(stroke
				(width 0.1)
				(type default)
			)
			(layer "F.Fab")
		)
		(fp_line
			(start 0.12065 -0.2794)
			(end 0.12065 -0.3048)
			(stroke
				(width 0.1)
				(type default)
			)
			(layer "F.Fab")
		)
		(fp_line
			(start 0.67945 -0.3048)
			(end 0.67945 0.3048)
			(stroke
				(width 0.1)
				(type default)
			)
			(layer "F.Fab")
		)
		(fp_line
			(start 0.67945 0.3048)
			(end 0.120396 0.3048)
			(stroke
				(width 0.1)
				(type default)
			)
			(layer "F.Fab")
		)
		(pad "1" smd circle
			(at -0.40005 0)
			(size 0 0)
			(layers "F.Cu" "F.Mask" "F.Paste")
			(net "GND")
		)
		(pad "2" smd circle
			(at 0.40005 0)
			(size 0 0)
			(layers "F.Cu" "F.Mask" "F.Paste")
			(net "P12V_SCM_REG")
		)
	)
	(footprint ""
		(layer "F.Cu")
		(at 357.587042 -392.04265 180)
		(property "Reference" "C2272"
			(at 0 0 180)
			(layer "F.SilkS")
			(hide yes)
			(effects
				(font
					(size 1.27 1.27)
				)
			)
		)
		(property "Value" ""
			(at 0 0 180)
			(layer "F.Fab")
			(effects
				(font
					(size 1.27 1.27)
				)
			)
		)
		(duplicate_pad_numbers_are_jumpers no)
		(fp_line
			(start 0.7874 0.4064)
			(end -0.7874 0.4064)
			(stroke
				(width 0.1524)
				(type default)
			)
			(layer "F.SilkS")
		)
		(fp_line
			(start 0.7874 -0.4064)
			(end 0.7874 0.4064)
			(stroke
				(width 0.1524)
				(type default)
			)
			(layer "F.SilkS")
		)
		(fp_line
			(start -0.7874 0.4064)
			(end -0.7874 -0.4064)
			(stroke
				(width 0.1524)
				(type default)
			)
			(layer "F.SilkS")
		)
		(fp_line
			(start -0.7874 -0.4064)
			(end 0.7874 -0.4064)
			(stroke
				(width 0.1524)
				(type default)
			)
			(layer "F.SilkS")
		)
		(fp_line
			(start 0.67945 0.3048)
			(end 0.120396 0.3048)
			(stroke
				(width 0.1)
				(type default)
			)
			(layer "F.Fab")
		)
		(fp_line
			(start 0.67945 -0.3048)
			(end 0.67945 0.3048)
			(stroke
				(width 0.1)
				(type default)
			)
			(layer "F.Fab")
		)
		(fp_line
			(start 0.12065 -0.2794)
			(end 0.12065 -0.3048)
			(stroke
				(width 0.1)
				(type default)
			)
			(layer "F.Fab")
		)
		(fp_line
			(start 0.12065 -0.3048)
			(end 0.67945 -0.3048)
			(stroke
				(width 0.1)
				(type default)
			)
			(layer "F.Fab")
		)
		(fp_line
			(start 0.120396 0.3048)
			(end 0.120396 0.2794)
			(stroke
				(width 0.1)
				(type default)
			)
			(layer "F.Fab")
		)
		(fp_line
			(start 0.120396 0.2794)
			(end -0.12065 0.2794)
			(stroke
				(width 0.1)
				(type default)
			)
			(layer "F.Fab")
		)
		(fp_line
			(start -0.12065 0.3048)
			(end -0.67945 0.3048)
			(stroke
				(width 0.1)
				(type default)
			)
			(layer "F.Fab")
		)
		(fp_line
			(start -0.12065 0.2794)
			(end -0.12065 0.3048)
			(stroke
				(width 0.1)
				(type default)
			)
			(layer "F.Fab")
		)
		(fp_line
			(start -0.12065 -0.2794)
			(end 0.12065 -0.2794)
			(stroke
				(width 0.1)
				(type default)
			)
			(layer "F.Fab")
		)
		(fp_line
			(start -0.12065 -0.305054)
			(end -0.12065 -0.2794)
			(stroke
				(width 0.1)
				(type default)
			)
			(layer "F.Fab")
		)
		(fp_line
			(start -0.67945 0.3048)
			(end -0.67945 -0.305054)
			(stroke
				(width 0.1)
				(type default)
			)
			(layer "F.Fab")
		)
		(fp_line
			(start -0.67945 -0.305054)
			(end -0.12065 -0.305054)
			(stroke
				(width 0.1)
				(type default)
			)
			(layer "F.Fab")
		)
		(pad "1" smd circle
			(at -0.40005 0 180)
			(size 0 0)
			(layers "F.Cu" "F.Mask" "F.Paste")
			(net "GPU_3V3IO_RSVD4_ISO")
		)
		(pad "2" smd circle
			(at 0.40005 0 180)
			(size 0 0)
			(layers "F.Cu" "F.Mask" "F.Paste")
			(net "GND")
		)
	)
	(footprint ""
		(layer "F.Cu")
		(at 182.82158 -411.20568 -90)
		(property "Reference" "C2389"
			(at 0 0 270)
			(layer "F.SilkS")
			(hide yes)
			(effects
				(font
					(size 1.27 1.27)
				)
			)
		)
		(property "Value" ""
			(at 0 0 270)
			(layer "F.Fab")
			(effects
				(font
					(size 1.27 1.27)
				)
			)
		)
		(duplicate_pad_numbers_are_jumpers no)
		(fp_line
			(start -0.7874 0.4064)
			(end -0.7874 -0.4064)
			(stroke
				(width 0.1524)
				(type default)
			)
			(layer "F.SilkS")
		)
		(fp_line
			(start 0.7874 0.4064)
			(end -0.7874 0.4064)
			(stroke
				(width 0.1524)
				(type default)
			)
			(layer "F.SilkS")
		)
		(fp_line
			(start -0.7874 -0.4064)
			(end 0.7874 -0.4064)
			(stroke
				(width 0.1524)
				(type default)
			)
			(layer "F.SilkS")
		)
		(fp_line
			(start 0.7874 -0.4064)
			(end 0.7874 0.4064)
			(stroke
				(width 0.1524)
				(type default)
			)
			(layer "F.SilkS")
		)
		(fp_line
			(start -0.67945 0.3048)
			(end -0.67945 -0.305054)
			(stroke
				(width 0.1)
				(type default)
			)
			(layer "F.Fab")
		)
		(fp_line
			(start -0.12065 0.3048)
			(end -0.67945 0.3048)
			(stroke
				(width 0.1)
				(type default)
			)
			(layer "F.Fab")
		)
		(fp_line
			(start 0.120396 0.3048)
			(end 0.120396 0.2794)
			(stroke
				(width 0.1)
				(type default)
			)
			(layer "F.Fab")
		)
		(fp_line
			(start 0.67945 0.3048)
			(end 0.120396 0.3048)
			(stroke
				(width 0.1)
				(type default)
			)
			(layer "F.Fab")
		)
		(fp_line
			(start -0.12065 0.2794)
			(end -0.12065 0.3048)
			(stroke
				(width 0.1)
				(type default)
			)
			(layer "F.Fab")
		)
		(fp_line
			(start 0.120396 0.2794)
			(end -0.12065 0.2794)
			(stroke
				(width 0.1)
				(type default)
			)
			(layer "F.Fab")
		)
		(fp_line
			(start -0.12065 -0.2794)
			(end 0.12065 -0.2794)
			(stroke
				(width 0.1)
				(type default)
			)
			(layer "F.Fab")
		)
		(fp_line
			(start 0.12065 -0.2794)
			(end 0.12065 -0.3048)
			(stroke
				(width 0.1)
				(type default)
			)
			(layer "F.Fab")
		)
		(fp_line
			(start 0.12065 -0.3048)
			(end 0.67945 -0.3048)
			(stroke
				(width 0.1)
				(type default)
			)
			(layer "F.Fab")
		)
		(fp_line
			(start 0.67945 -0.3048)
			(end 0.67945 0.3048)
			(stroke
				(width 0.1)
				(type default)
			)
			(layer "F.Fab")
		)
		(fp_line
			(start -0.67945 -0.305054)
			(end -0.12065 -0.305054)
			(stroke
				(width 0.1)
				(type default)
			)
			(layer "F.Fab")
		)
		(fp_line
			(start -0.12065 -0.305054)
			(end -0.12065 -0.2794)
			(stroke
				(width 0.1)
				(type default)
			)
			(layer "F.Fab")
		)
		(pad "1" smd circle
			(at -0.40005 0 270)
			(size 0 0)
			(layers "F.Cu" "F.Mask" "F.Paste")
			(net "HSC_OC_VOL")
		)
		(pad "2" smd circle
			(at 0.40005 0 270)
			(size 0 0)
			(layers "F.Cu" "F.Mask" "F.Paste")
			(net "GND")
		)
	)
	(footprint ""
		(layer "F.Cu")
		(at 256.473452 -92.292424)
		(property "Reference" "R3641"
			(at 0 0 0)
			(layer "F.SilkS")
			(hide yes)
			(effects
				(font
					(size 1.27 1.27)
				)
			)
		)
		(property "Value" ""
			(at 0 0 0)
			(layer "F.Fab")
			(effects
				(font
					(size 1.27 1.27)
				)
			)
		)
		(duplicate_pad_numbers_are_jumpers no)
		(fp_line
			(start -0.7874 -0.4064)
			(end 0.7874 -0.4064)
			(stroke
				(width 0.1524)
				(type default)
			)
			(layer "F.SilkS")
		)
		(fp_line
			(start -0.7874 0.4064)
			(end -0.7874 -0.4064)
			(stroke
				(width 0.1524)
				(type default)
			)
			(layer "F.SilkS")
		)
		(fp_line
			(start 0.7874 -0.4064)
			(end 0.7874 0.4064)
			(stroke
				(width 0.1524)
				(type default)
			)
			(layer "F.SilkS")
		)
		(fp_line
			(start 0.7874 0.4064)
			(end -0.7874 0.4064)
			(stroke
				(width 0.1524)
				(type default)
			)
			(layer "F.SilkS")
		)
		(fp_line
			(start -0.67945 -0.305054)
			(end -0.12065 -0.305054)
			(stroke
				(width 0.1)
				(type default)
			)
			(layer "F.Fab")
		)
		(fp_line
			(start -0.67945 0.3048)
			(end -0.67945 -0.305054)
			(stroke
				(width 0.1)
				(type default)
			)
			(layer "F.Fab")
		)
		(fp_line
			(start -0.12065 -0.305054)
			(end -0.12065 -0.2794)
			(stroke
				(width 0.1)
				(type default)
			)
			(layer "F.Fab")
		)
		(fp_line
			(start -0.12065 -0.2794)
			(end 0.12065 -0.2794)
			(stroke
				(width 0.1)
				(type default)
			)
			(layer "F.Fab")
		)
		(fp_line
			(start -0.12065 0.2794)
			(end -0.12065 0.3048)
			(stroke
				(width 0.1)
				(type default)
			)
			(layer "F.Fab")
		)
		(fp_line
			(start -0.12065 0.3048)
			(end -0.67945 0.3048)
			(stroke
				(width 0.1)
				(type default)
			)
			(layer "F.Fab")
		)
		(fp_line
			(start 0.120396 0.2794)
			(end -0.12065 0.2794)
			(stroke
				(width 0.1)
				(type default)
			)
			(layer "F.Fab")
		)
		(fp_line
			(start 0.120396 0.3048)
			(end 0.120396 0.2794)
			(stroke
				(width 0.1)
				(type default)
			)
			(layer "F.Fab")
		)
		(fp_line
			(start 0.12065 -0.3048)
			(end 0.67945 -0.3048)
			(stroke
				(width 0.1)
				(type default)
			)
			(layer "F.Fab")
		)
		(fp_line
			(start 0.12065 -0.2794)
			(end 0.12065 -0.3048)
			(stroke
				(width 0.1)
				(type default)
			)
			(layer "F.Fab")
		)
		(fp_line
			(start 0.67945 -0.3048)
			(end 0.67945 0.3048)
			(stroke
				(width 0.1)
				(type default)
			)
			(layer "F.Fab")
		)
		(fp_line
			(start 0.67945 0.3048)
			(end 0.120396 0.3048)
			(stroke
				(width 0.1)
				(type default)
			)
			(layer "F.Fab")
		)
		(pad "1" smd circle
			(at -0.40005 0)
			(size 0 0)
			(layers "F.Cu" "F.Mask" "F.Paste")
			(net "P3V3_AUX")
		)
		(pad "2" smd circle
			(at 0.40005 0)
			(size 0 0)
			(layers "F.Cu" "F.Mask" "F.Paste")
			(net "CK440Q_OE_4")
		)
	)
	(footprint ""
		(layer "F.Cu")
		(at 350.1517 -30.520894 -90)
		(property "Reference" "R496"
			(at 0 0 270)
			(layer "F.SilkS")
			(hide yes)
			(effects
				(font
					(size 1.27 1.27)
				)
			)
		)
		(property "Value" ""
			(at 0 0 270)
			(layer "F.Fab")
			(effects
				(font
					(size 1.27 1.27)
				)
			)
		)
		(duplicate_pad_numbers_are_jumpers no)
		(fp_line
			(start -0.7874 0.4064)
			(end -0.7874 -0.4064)
			(stroke
				(width 0.1524)
				(type default)
			)
			(layer "F.SilkS")
		)
		(fp_line
			(start 0.7874 0.4064)
			(end -0.7874 0.4064)
			(stroke
				(width 0.1524)
				(type default)
			)
			(layer "F.SilkS")
		)
		(fp_line
			(start -0.7874 -0.4064)
			(end 0.7874 -0.4064)
			(stroke
				(width 0.1524)
				(type default)
			)
			(layer "F.SilkS")
		)
		(fp_line
			(start 0.7874 -0.4064)
			(end 0.7874 0.4064)
			(stroke
				(width 0.1524)
				(type default)
			)
			(layer "F.SilkS")
		)
		(fp_line
			(start -0.67945 0.3048)
			(end -0.67945 -0.305054)
			(stroke
				(width 0.1)
				(type default)
			)
			(layer "F.Fab")
		)
		(fp_line
			(start -0.12065 0.3048)
			(end -0.67945 0.3048)
			(stroke
				(width 0.1)
				(type default)
			)
			(layer "F.Fab")
		)
		(fp_line
			(start 0.120396 0.3048)
			(end 0.120396 0.2794)
			(stroke
				(width 0.1)
				(type default)
			)
			(layer "F.Fab")
		)
		(fp_line
			(start 0.67945 0.3048)
			(end 0.120396 0.3048)
			(stroke
				(width 0.1)
				(type default)
			)
			(layer "F.Fab")
		)
		(fp_line
			(start -0.12065 0.2794)
			(end -0.12065 0.3048)
			(stroke
				(width 0.1)
				(type default)
			)
			(layer "F.Fab")
		)
		(fp_line
			(start 0.120396 0.2794)
			(end -0.12065 0.2794)
			(stroke
				(width 0.1)
				(type default)
			)
			(layer "F.Fab")
		)
		(fp_line
			(start -0.12065 -0.2794)
			(end 0.12065 -0.2794)
			(stroke
				(width 0.1)
				(type default)
			)
			(layer "F.Fab")
		)
		(fp_line
			(start 0.12065 -0.2794)
			(end 0.12065 -0.3048)
			(stroke
				(width 0.1)
				(type default)
			)
			(layer "F.Fab")
		)
		(fp_line
			(start 0.12065 -0.3048)
			(end 0.67945 -0.3048)
			(stroke
				(width 0.1)
				(type default)
			)
			(layer "F.Fab")
		)
		(fp_line
			(start 0.67945 -0.3048)
			(end 0.67945 0.3048)
			(stroke
				(width 0.1)
				(type default)
			)
			(layer "F.Fab")
		)
		(fp_line
			(start -0.67945 -0.305054)
			(end -0.12065 -0.305054)
			(stroke
				(width 0.1)
				(type default)
			)
			(layer "F.Fab")
		)
		(fp_line
			(start -0.12065 -0.305054)
			(end -0.12065 -0.2794)
			(stroke
				(width 0.1)
				(type default)
			)
			(layer "F.Fab")
		)
		(pad "1" smd circle
			(at -0.40005 0 270)
			(size 0 0)
			(layers "F.Cu" "F.Mask" "F.Paste")
			(net "PD_PCH_USB2_COMP")
		)
		(pad "2" smd circle
			(at 0.40005 0 270)
			(size 0 0)
			(layers "F.Cu" "F.Mask" "F.Paste")
			(net "GND")
		)
	)
	(footprint ""
		(layer "F.Cu")
		(at 93.090492 -74.736706 -90)
		(property "Reference" "R3075"
			(at 0 0 270)
			(layer "F.SilkS")
			(hide yes)
			(effects
				(font
					(size 1.27 1.27)
				)
			)
		)
		(property "Value" ""
			(at 0 0 270)
			(layer "F.Fab")
			(effects
				(font
					(size 1.27 1.27)
				)
			)
		)
		(duplicate_pad_numbers_are_jumpers no)
		(fp_line
			(start -0.7874 0.4064)
			(end -0.7874 -0.4064)
			(stroke
				(width 0.1524)
				(type default)
			)
			(layer "F.SilkS")
		)
		(fp_line
			(start 0.7874 0.4064)
			(end -0.7874 0.4064)
			(stroke
				(width 0.1524)
				(type default)
			)
			(layer "F.SilkS")
		)
		(fp_line
			(start -0.7874 -0.4064)
			(end 0.7874 -0.4064)
			(stroke
				(width 0.1524)
				(type default)
			)
			(layer "F.SilkS")
		)
		(fp_line
			(start 0.7874 -0.4064)
			(end 0.7874 0.4064)
			(stroke
				(width 0.1524)
				(type default)
			)
			(layer "F.SilkS")
		)
		(fp_line
			(start -0.67945 0.3048)
			(end -0.67945 -0.305054)
			(stroke
				(width 0.1)
				(type default)
			)
			(layer "F.Fab")
		)
		(fp_line
			(start -0.12065 0.3048)
			(end -0.67945 0.3048)
			(stroke
				(width 0.1)
				(type default)
			)
			(layer "F.Fab")
		)
		(fp_line
			(start 0.120396 0.3048)
			(end 0.120396 0.2794)
			(stroke
				(width 0.1)
				(type default)
			)
			(layer "F.Fab")
		)
		(fp_line
			(start 0.67945 0.3048)
			(end 0.120396 0.3048)
			(stroke
				(width 0.1)
				(type default)
			)
			(layer "F.Fab")
		)
		(fp_line
			(start -0.12065 0.2794)
			(end -0.12065 0.3048)
			(stroke
				(width 0.1)
				(type default)
			)
			(layer "F.Fab")
		)
		(fp_line
			(start 0.120396 0.2794)
			(end -0.12065 0.2794)
			(stroke
				(width 0.1)
				(type default)
			)
			(layer "F.Fab")
		)
		(fp_line
			(start -0.12065 -0.2794)
			(end 0.12065 -0.2794)
			(stroke
				(width 0.1)
				(type default)
			)
			(layer "F.Fab")
		)
		(fp_line
			(start 0.12065 -0.2794)
			(end 0.12065 -0.3048)
			(stroke
				(width 0.1)
				(type default)
			)
			(layer "F.Fab")
		)
		(fp_line
			(start 0.12065 -0.3048)
			(end 0.67945 -0.3048)
			(stroke
				(width 0.1)
				(type default)
			)
			(layer "F.Fab")
		)
		(fp_line
			(start 0.67945 -0.3048)
			(end 0.67945 0.3048)
			(stroke
				(width 0.1)
				(type default)
			)
			(layer "F.Fab")
		)
		(fp_line
			(start -0.67945 -0.305054)
			(end -0.12065 -0.305054)
			(stroke
				(width 0.1)
				(type default)
			)
			(layer "F.Fab")
		)
		(fp_line
			(start -0.12065 -0.305054)
			(end -0.12065 -0.2794)
			(stroke
				(width 0.1)
				(type default)
			)
			(layer "F.Fab")
		)
		(pad "1" smd circle
			(at -0.40005 0 270)
			(size 0 0)
			(layers "F.Cu" "F.Mask" "F.Paste")
			(net "LED_PWRGD_PS_PWROK_PLD")
		)
		(pad "2" smd circle
			(at 0.40005 0 270)
			(size 0 0)
			(layers "F.Cu" "F.Mask" "F.Paste")
			(net "P3V3_AUX")
		)
	)
	(footprint ""
		(layer "F.Cu")
		(at 183.37403 -397.278352 180)
		(property "Reference" "C2179"
			(at 0 0 180)
			(layer "F.SilkS")
			(hide yes)
			(effects
				(font
					(size 1.27 1.27)
				)
			)
		)
		(property "Value" ""
			(at 0 0 180)
			(layer "F.Fab")
			(effects
				(font
					(size 1.27 1.27)
				)
			)
		)
		(duplicate_pad_numbers_are_jumpers no)
		(fp_line
			(start 0.7874 0.4064)
			(end -0.7874 0.4064)
			(stroke
				(width 0.1524)
				(type default)
			)
			(layer "F.SilkS")
		)
		(fp_line
			(start 0.7874 -0.4064)
			(end 0.7874 0.4064)
			(stroke
				(width 0.1524)
				(type default)
			)
			(layer "F.SilkS")
		)
		(fp_line
			(start -0.7874 0.4064)
			(end -0.7874 -0.4064)
			(stroke
				(width 0.1524)
				(type default)
			)
			(layer "F.SilkS")
		)
		(fp_line
			(start -0.7874 -0.4064)
			(end 0.7874 -0.4064)
			(stroke
				(width 0.1524)
				(type default)
			)
			(layer "F.SilkS")
		)
		(fp_line
			(start 0.67945 0.3048)
			(end 0.120396 0.3048)
			(stroke
				(width 0.1)
				(type default)
			)
			(layer "F.Fab")
		)
		(fp_line
			(start 0.67945 -0.3048)
			(end 0.67945 0.3048)
			(stroke
				(width 0.1)
				(type default)
			)
			(layer "F.Fab")
		)
		(fp_line
			(start 0.12065 -0.2794)
			(end 0.12065 -0.3048)
			(stroke
				(width 0.1)
				(type default)
			)
			(layer "F.Fab")
		)
		(fp_line
			(start 0.12065 -0.3048)
			(end 0.67945 -0.3048)
			(stroke
				(width 0.1)
				(type default)
			)
			(layer "F.Fab")
		)
		(fp_line
			(start 0.120396 0.3048)
			(end 0.120396 0.2794)
			(stroke
				(width 0.1)
				(type default)
			)
			(layer "F.Fab")
		)
		(fp_line
			(start 0.120396 0.2794)
			(end -0.12065 0.2794)
			(stroke
				(width 0.1)
				(type default)
			)
			(layer "F.Fab")
		)
		(fp_line
			(start -0.12065 0.3048)
			(end -0.67945 0.3048)
			(stroke
				(width 0.1)
				(type default)
			)
			(layer "F.Fab")
		)
		(fp_line
			(start -0.12065 0.2794)
			(end -0.12065 0.3048)
			(stroke
				(width 0.1)
				(type default)
			)
			(layer "F.Fab")
		)
		(fp_line
			(start -0.12065 -0.2794)
			(end 0.12065 -0.2794)
			(stroke
				(width 0.1)
				(type default)
			)
			(layer "F.Fab")
		)
		(fp_line
			(start -0.12065 -0.305054)
			(end -0.12065 -0.2794)
			(stroke
				(width 0.1)
				(type default)
			)
			(layer "F.Fab")
		)
		(fp_line
			(start -0.67945 0.3048)
			(end -0.67945 -0.305054)
			(stroke
				(width 0.1)
				(type default)
			)
			(layer "F.Fab")
		)
		(fp_line
			(start -0.67945 -0.305054)
			(end -0.12065 -0.305054)
			(stroke
				(width 0.1)
				(type default)
			)
			(layer "F.Fab")
		)
		(pad "1" smd circle
			(at -0.40005 0 180)
			(size 0 0)
			(layers "F.Cu" "F.Mask" "F.Paste")
			(net "HSC_EN")
		)
		(pad "2" smd circle
			(at 0.40005 0 180)
			(size 0 0)
			(layers "F.Cu" "F.Mask" "F.Paste")
			(net "AGND_HSC")
		)
	)
	(footprint ""
		(layer "F.Cu")
		(at 407.570432 -36.48837)
		(property "Reference" "SW5"
			(at -5.793232 4.106672 0)
			(unlocked yes)
			(layer "F.SilkS")
			(effects
				(font
					(size 0.7874 0.5842)
					(thickness 0.1524)
				)
				(justify left)
			)
		)
		(property "Value" ""
			(at 0 0 0)
			(layer "F.Fab")
			(effects
				(font
					(size 1.27 1.27)
				)
			)
		)
		(duplicate_pad_numbers_are_jumpers no)
		(fp_line
			(start -3.10007 -3.10007)
			(end -3.10007 3.10007)
			(stroke
				(width 0.1524)
				(type default)
			)
			(layer "F.SilkS")
		)
		(fp_line
			(start -3.10007 3.10007)
			(end -3.048 3.10007)
			(stroke
				(width 0.1524)
				(type default)
			)
			(layer "F.SilkS")
		)
		(fp_line
			(start -3.048 -3.10007)
			(end -3.10007 -3.10007)
			(stroke
				(width 0.1524)
				(type default)
			)
			(layer "F.SilkS")
		)
		(fp_line
			(start -1.4478 3.10007)
			(end 1.4478 3.10007)
			(stroke
				(width 0.1524)
				(type default)
			)
			(layer "F.SilkS")
		)
		(fp_line
			(start 1.4478 -3.10007)
			(end -1.4478 -3.10007)
			(stroke
				(width 0.1524)
				(type default)
			)
			(layer "F.SilkS")
		)
		(fp_line
			(start 3.048 3.10007)
			(end 3.10007 3.10007)
			(stroke
				(width 0.1524)
				(type default)
			)
			(layer "F.SilkS")
		)
		(fp_line
			(start 3.10007 -3.10007)
			(end 3.048 -3.10007)
			(stroke
				(width 0.1524)
				(type default)
			)
			(layer "F.SilkS")
		)
		(fp_line
			(start 3.10007 3.10007)
			(end 3.10007 -3.10007)
			(stroke
				(width 0.1524)
				(type default)
			)
			(layer "F.SilkS")
		)
		(fp_circle
			(center 0 0)
			(end 1.75006 0)
			(stroke
				(width 0.1524)
				(type default)
			)
			(fill no)
			(layer "F.SilkS")
		)
		(fp_poly
			(pts
				(xy 2.757932 -5.969) (xy 2.249932 -4.953) (xy 1.741932 -5.969)
			)
			(stroke
				(width 0)
				(type default)
			)
			(fill yes)
			(layer "F.SilkS")
		)
		(fp_line
			(start -3.10007 -3.10007)
			(end -3.10007 3.10007)
			(stroke
				(width 0.1)
				(type default)
			)
			(layer "F.Fab")
		)
		(fp_line
			(start -3.10007 3.10007)
			(end 3.10007 3.10007)
			(stroke
				(width 0.1)
				(type default)
			)
			(layer "F.Fab")
		)
		(fp_line
			(start 3.10007 -3.10007)
			(end -3.10007 -3.10007)
			(stroke
				(width 0.1)
				(type default)
			)
			(layer "F.Fab")
		)
		(fp_line
			(start 3.10007 3.10007)
			(end 3.10007 -3.10007)
			(stroke
				(width 0.1)
				(type default)
			)
			(layer "F.Fab")
		)
		(fp_poly
			(pts
				(xy 2.757932 -5.969) (xy 1.741932 -5.969) (xy 2.249932 -4.953)
			)
			(stroke
				(width 0)
				(type default)
			)
			(fill yes)
			(layer "F.Fab")
		)
		(pad "1" smd rect
			(at 2.249932 -3.9751)
			(size 1.3208 1.5494)
			(layers "F.Cu" "F.Mask" "F.Paste")
			(net "PD_RST_RTCRST_N")
		)
		(pad "2" smd rect
			(at 2.249932 3.9751)
			(size 1.3208 1.5494)
			(layers "F.Cu" "F.Mask" "F.Paste")
			(net "PD_RST_RTCRST_N")
		)
		(pad "3" smd rect
			(at -2.249932 -3.9751)
			(size 1.3208 1.5494)
			(layers "F.Cu" "F.Mask" "F.Paste")
			(net "RST_RTCRST_N")
		)
		(pad "4" smd rect
			(at -2.249932 3.9751)
			(size 1.3208 1.5494)
			(layers "F.Cu" "F.Mask" "F.Paste")
			(net "RST_RTCRST_N")
		)
	)
	(footprint ""
		(layer "F.Cu")
		(at 96.57588 -57.241948 180)
		(property "Reference" "R1374"
			(at 0 0 180)
			(layer "F.SilkS")
			(hide yes)
			(effects
				(font
					(size 1.27 1.27)
				)
			)
		)
		(property "Value" ""
			(at 0 0 180)
			(layer "F.Fab")
			(effects
				(font
					(size 1.27 1.27)
				)
			)
		)
		(duplicate_pad_numbers_are_jumpers no)
		(fp_line
			(start 0.7874 0.4064)
			(end -0.7874 0.4064)
			(stroke
				(width 0.1524)
				(type default)
			)
			(layer "F.SilkS")
		)
		(fp_line
			(start 0.7874 -0.4064)
			(end 0.7874 0.4064)
			(stroke
				(width 0.1524)
				(type default)
			)
			(layer "F.SilkS")
		)
		(fp_line
			(start -0.7874 0.4064)
			(end -0.7874 -0.4064)
			(stroke
				(width 0.1524)
				(type default)
			)
			(layer "F.SilkS")
		)
		(fp_line
			(start -0.7874 -0.4064)
			(end 0.7874 -0.4064)
			(stroke
				(width 0.1524)
				(type default)
			)
			(layer "F.SilkS")
		)
		(fp_line
			(start 0.67945 0.3048)
			(end 0.120396 0.3048)
			(stroke
				(width 0.1)
				(type default)
			)
			(layer "F.Fab")
		)
		(fp_line
			(start 0.67945 -0.3048)
			(end 0.67945 0.3048)
			(stroke
				(width 0.1)
				(type default)
			)
			(layer "F.Fab")
		)
		(fp_line
			(start 0.12065 -0.2794)
			(end 0.12065 -0.3048)
			(stroke
				(width 0.1)
				(type default)
			)
			(layer "F.Fab")
		)
		(fp_line
			(start 0.12065 -0.3048)
			(end 0.67945 -0.3048)
			(stroke
				(width 0.1)
				(type default)
			)
			(layer "F.Fab")
		)
		(fp_line
			(start 0.120396 0.3048)
			(end 0.120396 0.2794)
			(stroke
				(width 0.1)
				(type default)
			)
			(layer "F.Fab")
		)
		(fp_line
			(start 0.120396 0.2794)
			(end -0.12065 0.2794)
			(stroke
				(width 0.1)
				(type default)
			)
			(layer "F.Fab")
		)
		(fp_line
			(start -0.12065 0.3048)
			(end -0.67945 0.3048)
			(stroke
				(width 0.1)
				(type default)
			)
			(layer "F.Fab")
		)
		(fp_line
			(start -0.12065 0.2794)
			(end -0.12065 0.3048)
			(stroke
				(width 0.1)
				(type default)
			)
			(layer "F.Fab")
		)
		(fp_line
			(start -0.12065 -0.2794)
			(end 0.12065 -0.2794)
			(stroke
				(width 0.1)
				(type default)
			)
			(layer "F.Fab")
		)
		(fp_line
			(start -0.12065 -0.305054)
			(end -0.12065 -0.2794)
			(stroke
				(width 0.1)
				(type default)
			)
			(layer "F.Fab")
		)
		(fp_line
			(start -0.67945 0.3048)
			(end -0.67945 -0.305054)
			(stroke
				(width 0.1)
				(type default)
			)
			(layer "F.Fab")
		)
		(fp_line
			(start -0.67945 -0.305054)
			(end -0.12065 -0.305054)
			(stroke
				(width 0.1)
				(type default)
			)
			(layer "F.Fab")
		)
		(pad "1" smd circle
			(at -0.40005 0 180)
			(size 0 0)
			(layers "F.Cu" "F.Mask" "F.Paste")
			(net "PD_JTAG_BMC_NTRST_N")
		)
		(pad "2" smd circle
			(at 0.40005 0 180)
			(size 0 0)
			(layers "F.Cu" "F.Mask" "F.Paste")
			(net "GND")
		)
	)
	(footprint ""
		(layer "F.Cu")
		(at 100.158296 -423.579798 -90)
		(property "Reference" "U272"
			(at 1.16078 -3.199384 0)
			(unlocked yes)
			(layer "F.SilkS")
			(effects
				(font
					(size 0.7874 0.5842)
					(thickness 0.1524)
				)
				(justify left)
			)
		)
		(property "Value" ""
			(at 0 0 270)
			(layer "F.Fab")
			(effects
				(font
					(size 1.27 1.27)
				)
			)
		)
		(duplicate_pad_numbers_are_jumpers no)
		(fp_line
			(start -3.447796 2.500122)
			(end 3.447796 2.500122)
			(stroke
				(width 0.1524)
				(type default)
			)
			(layer "F.SilkS")
		)
		(fp_line
			(start 3.447796 2.500122)
			(end 3.447796 -2.500122)
			(stroke
				(width 0.1524)
				(type default)
			)
			(layer "F.SilkS")
		)
		(fp_line
			(start 0 -1.016)
			(end -1.484122 -2.500122)
			(stroke
				(width 0.1524)
				(type default)
			)
			(layer "F.SilkS")
		)
		(fp_line
			(start -3.447796 -2.500122)
			(end -3.447796 2.500122)
			(stroke
				(width 0.1524)
				(type default)
			)
			(layer "F.SilkS")
		)
		(fp_line
			(start -1.484122 -2.500122)
			(end -3.447796 -2.500122)
			(stroke
				(width 0.1524)
				(type default)
			)
			(layer "F.SilkS")
		)
		(fp_line
			(start 1.484122 -2.500122)
			(end 0 -1.016)
			(stroke
				(width 0.1524)
				(type default)
			)
			(layer "F.SilkS")
		)
		(fp_line
			(start 3.447796 -2.500122)
			(end 1.484122 -2.500122)
			(stroke
				(width 0.1524)
				(type default)
			)
			(layer "F.SilkS")
		)
		(fp_poly
			(pts
				(xy -4.6609 -2.47396) (xy -3.6449 -1.96596) (xy -4.6609 -1.45796)
			)
			(stroke
				(width 0)
				(type default)
			)
			(fill yes)
			(layer "F.SilkS")
		)
		(fp_line
			(start -1.999996 2.500122)
			(end 1.999996 2.500122)
			(stroke
				(width 0.1)
				(type default)
			)
			(layer "F.Fab")
		)
		(fp_line
			(start 1.999996 2.500122)
			(end 1.999996 -2.500122)
			(stroke
				(width 0.1)
				(type default)
			)
			(layer "F.Fab")
		)
		(fp_line
			(start -1.999996 -2.500122)
			(end -1.999996 2.500122)
			(stroke
				(width 0.1)
				(type default)
			)
			(layer "F.Fab")
		)
		(fp_line
			(start 1.999996 -2.500122)
			(end -1.999996 -2.500122)
			(stroke
				(width 0.1)
				(type default)
			)
			(layer "F.Fab")
		)
		(fp_poly
			(pts
				(xy -4.5974 -2.413) (xy -4.5974 -1.397) (xy -3.5814 -1.905)
			)
			(stroke
				(width 0)
				(type default)
			)
			(fill yes)
			(layer "F.Fab")
		)
		(pad "1" smd rect
			(at -2.649982 -1.905 180)
			(size 0.6096 1.3208)
			(layers "F.Cu" "F.Mask" "F.Paste")
			(net "SMB_LM75_2_3V3AUX_SDA_R1")
		)
		(pad "2" smd rect
			(at -2.649982 -0.635 180)
			(size 0.6096 1.3208)
			(layers "F.Cu" "F.Mask" "F.Paste")
			(net "SMB_LM75_2_3V3AUX_SCL_R1")
		)
		(pad "3" smd rect
			(at -2.649982 0.635 180)
			(size 0.6096 1.3208)
			(layers "F.Cu" "F.Mask" "F.Paste")
			(net "FM_LM75_2_ALERT_N")
		)
		(pad "4" smd rect
			(at -2.649982 1.905 180)
			(size 0.6096 1.3208)
			(layers "F.Cu" "F.Mask" "F.Paste")
			(net "GND")
		)
		(pad "5" smd rect
			(at 2.649982 1.905 180)
			(size 0.6096 1.3208)
			(layers "F.Cu" "F.Mask" "F.Paste")
			(net "U272_2_ADD2")
		)
		(pad "6" smd rect
			(at 2.649982 0.635 180)
			(size 0.6096 1.3208)
			(layers "F.Cu" "F.Mask" "F.Paste")
			(net "U272_2_ADD1")
		)
		(pad "7" smd rect
			(at 2.649982 -0.635 180)
			(size 0.6096 1.3208)
			(layers "F.Cu" "F.Mask" "F.Paste")
			(net "U272_2_ADD0")
		)
		(pad "8" smd rect
			(at 2.649982 -1.905 180)
			(size 0.6096 1.3208)
			(layers "F.Cu" "F.Mask" "F.Paste")
			(net "P3V3_AUX")
		)
	)
	(footprint ""
		(layer "F.Cu")
		(at 331.099668 -76.153518 90)
		(property "Reference" "R4305"
			(at 0 0 90)
			(layer "F.SilkS")
			(hide yes)
			(effects
				(font
					(size 1.27 1.27)
				)
			)
		)
		(property "Value" ""
			(at 0 0 90)
			(layer "F.Fab")
			(effects
				(font
					(size 1.27 1.27)
				)
			)
		)
		(duplicate_pad_numbers_are_jumpers no)
		(fp_line
			(start 0.7874 -0.4064)
			(end 0.7874 0.4064)
			(stroke
				(width 0.1524)
				(type default)
			)
			(layer "F.SilkS")
		)
		(fp_line
			(start -0.7874 -0.4064)
			(end 0.7874 -0.4064)
			(stroke
				(width 0.1524)
				(type default)
			)
			(layer "F.SilkS")
		)
		(fp_line
			(start 0.7874 0.4064)
			(end -0.7874 0.4064)
			(stroke
				(width 0.1524)
				(type default)
			)
			(layer "F.SilkS")
		)
		(fp_line
			(start -0.7874 0.4064)
			(end -0.7874 -0.4064)
			(stroke
				(width 0.1524)
				(type default)
			)
			(layer "F.SilkS")
		)
		(fp_line
			(start -0.12065 -0.305054)
			(end -0.12065 -0.2794)
			(stroke
				(width 0.1)
				(type default)
			)
			(layer "F.Fab")
		)
		(fp_line
			(start -0.67945 -0.305054)
			(end -0.12065 -0.305054)
			(stroke
				(width 0.1)
				(type default)
			)
			(layer "F.Fab")
		)
		(fp_line
			(start 0.67945 -0.3048)
			(end 0.67945 0.3048)
			(stroke
				(width 0.1)
				(type default)
			)
			(layer "F.Fab")
		)
		(fp_line
			(start 0.12065 -0.3048)
			(end 0.67945 -0.3048)
			(stroke
				(width 0.1)
				(type default)
			)
			(layer "F.Fab")
		)
		(fp_line
			(start 0.12065 -0.2794)
			(end 0.12065 -0.3048)
			(stroke
				(width 0.1)
				(type default)
			)
			(layer "F.Fab")
		)
		(fp_line
			(start -0.12065 -0.2794)
			(end 0.12065 -0.2794)
			(stroke
				(width 0.1)
				(type default)
			)
			(layer "F.Fab")
		)
		(fp_line
			(start 0.120396 0.2794)
			(end -0.12065 0.2794)
			(stroke
				(width 0.1)
				(type default)
			)
			(layer "F.Fab")
		)
		(fp_line
			(start -0.12065 0.2794)
			(end -0.12065 0.3048)
			(stroke
				(width 0.1)
				(type default)
			)
			(layer "F.Fab")
		)
		(fp_line
			(start 0.67945 0.3048)
			(end 0.120396 0.3048)
			(stroke
				(width 0.1)
				(type default)
			)
			(layer "F.Fab")
		)
		(fp_line
			(start 0.120396 0.3048)
			(end 0.120396 0.2794)
			(stroke
				(width 0.1)
				(type default)
			)
			(layer "F.Fab")
		)
		(fp_line
			(start -0.12065 0.3048)
			(end -0.67945 0.3048)
			(stroke
				(width 0.1)
				(type default)
			)
			(layer "F.Fab")
		)
		(fp_line
			(start -0.67945 0.3048)
			(end -0.67945 -0.305054)
			(stroke
				(width 0.1)
				(type default)
			)
			(layer "F.Fab")
		)
		(pad "1" smd circle
			(at -0.40005 0 90)
			(size 0 0)
			(layers "F.Cu" "F.Mask" "F.Paste")
			(net "CLK_100M_PE_M2_0_R_DP")
		)
		(pad "2" smd circle
			(at 0.40005 0 90)
			(size 0 0)
			(layers "F.Cu" "F.Mask" "F.Paste")
			(net "CLK_100M_PE_M2_0_DP")
		)
	)
	(footprint ""
		(layer "F.Cu")
		(at 144.88541 -126.630684)
		(property "Reference" "C1817"
			(at 0 0 0)
			(layer "F.SilkS")
			(hide yes)
			(effects
				(font
					(size 1.27 1.27)
				)
			)
		)
		(property "Value" ""
			(at 0 0 0)
			(layer "F.Fab")
			(effects
				(font
					(size 1.27 1.27)
				)
			)
		)
		(duplicate_pad_numbers_are_jumpers no)
		(fp_line
			(start -0.7874 -0.4064)
			(end 0.7874 -0.4064)
			(stroke
				(width 0.1524)
				(type default)
			)
			(layer "F.SilkS")
		)
		(fp_line
			(start -0.7874 0.4064)
			(end -0.7874 -0.4064)
			(stroke
				(width 0.1524)
				(type default)
			)
			(layer "F.SilkS")
		)
		(fp_line
			(start 0.7874 -0.4064)
			(end 0.7874 0.4064)
			(stroke
				(width 0.1524)
				(type default)
			)
			(layer "F.SilkS")
		)
		(fp_line
			(start 0.7874 0.4064)
			(end -0.7874 0.4064)
			(stroke
				(width 0.1524)
				(type default)
			)
			(layer "F.SilkS")
		)
		(fp_line
			(start -0.67945 -0.305054)
			(end -0.12065 -0.305054)
			(stroke
				(width 0.1)
				(type default)
			)
			(layer "F.Fab")
		)
		(fp_line
			(start -0.67945 0.3048)
			(end -0.67945 -0.305054)
			(stroke
				(width 0.1)
				(type default)
			)
			(layer "F.Fab")
		)
		(fp_line
			(start -0.12065 -0.305054)
			(end -0.12065 -0.2794)
			(stroke
				(width 0.1)
				(type default)
			)
			(layer "F.Fab")
		)
		(fp_line
			(start -0.12065 -0.2794)
			(end 0.12065 -0.2794)
			(stroke
				(width 0.1)
				(type default)
			)
			(layer "F.Fab")
		)
		(fp_line
			(start -0.12065 0.2794)
			(end -0.12065 0.3048)
			(stroke
				(width 0.1)
				(type default)
			)
			(layer "F.Fab")
		)
		(fp_line
			(start -0.12065 0.3048)
			(end -0.67945 0.3048)
			(stroke
				(width 0.1)
				(type default)
			)
			(layer "F.Fab")
		)
		(fp_line
			(start 0.120396 0.2794)
			(end -0.12065 0.2794)
			(stroke
				(width 0.1)
				(type default)
			)
			(layer "F.Fab")
		)
		(fp_line
			(start 0.120396 0.3048)
			(end 0.120396 0.2794)
			(stroke
				(width 0.1)
				(type default)
			)
			(layer "F.Fab")
		)
		(fp_line
			(start 0.12065 -0.3048)
			(end 0.67945 -0.3048)
			(stroke
				(width 0.1)
				(type default)
			)
			(layer "F.Fab")
		)
		(fp_line
			(start 0.12065 -0.2794)
			(end 0.12065 -0.3048)
			(stroke
				(width 0.1)
				(type default)
			)
			(layer "F.Fab")
		)
		(fp_line
			(start 0.67945 -0.3048)
			(end 0.67945 0.3048)
			(stroke
				(width 0.1)
				(type default)
			)
			(layer "F.Fab")
		)
		(fp_line
			(start 0.67945 0.3048)
			(end 0.120396 0.3048)
			(stroke
				(width 0.1)
				(type default)
			)
			(layer "F.Fab")
		)
		(pad "1" smd circle
			(at -0.40005 0)
			(size 0 0)
			(layers "F.Cu" "F.Mask" "F.Paste")
			(net "P3V3_AUX")
		)
		(pad "2" smd circle
			(at 0.40005 0)
			(size 0 0)
			(layers "F.Cu" "F.Mask" "F.Paste")
			(net "GND")
		)
	)
	(footprint ""
		(layer "F.Cu")
		(at 129.7559 -24.775668 180)
		(property "Reference" "C2284"
			(at 0 0 180)
			(layer "F.SilkS")
			(hide yes)
			(effects
				(font
					(size 1.27 1.27)
				)
			)
		)
		(property "Value" ""
			(at 0 0 180)
			(layer "F.Fab")
			(effects
				(font
					(size 1.27 1.27)
				)
			)
		)
		(duplicate_pad_numbers_are_jumpers no)
		(fp_line
			(start 1.524 0.762)
			(end -1.524 0.762)
			(stroke
				(width 0.1524)
				(type default)
			)
			(layer "F.SilkS")
		)
		(fp_line
			(start 1.524 -0.762)
			(end 1.524 0.762)
			(stroke
				(width 0.1524)
				(type default)
			)
			(layer "F.SilkS")
		)
		(fp_line
			(start -1.524 0.762)
			(end -1.524 -0.762)
			(stroke
				(width 0.1524)
				(type default)
			)
			(layer "F.SilkS")
		)
		(fp_line
			(start -1.524 -0.762)
			(end 1.524 -0.762)
			(stroke
				(width 0.1524)
				(type default)
			)
			(layer "F.SilkS")
		)
		(fp_line
			(start 1.1049 0.724916)
			(end 1.1049 -0.724916)
			(stroke
				(width 0.1)
				(type default)
			)
			(layer "F.Fab")
		)
		(fp_line
			(start 1.1049 -0.724916)
			(end -1.1049 -0.724916)
			(stroke
				(width 0.1)
				(type default)
			)
			(layer "F.Fab")
		)
		(fp_line
			(start -1.1049 0.724916)
			(end 1.1049 0.724916)
			(stroke
				(width 0.1)
				(type default)
			)
			(layer "F.Fab")
		)
		(fp_line
			(start -1.1049 -0.724916)
			(end -1.1049 0.724916)
			(stroke
				(width 0.1)
				(type default)
			)
			(layer "F.Fab")
		)
		(pad "1" smd rect
			(at -0.889 0)
			(size 1.016 1.27)
			(layers "F.Cu" "F.Mask" "F.Paste")
			(net "P3V3_AUX_USB_BUF")
		)
		(pad "2" smd rect
			(at 0.889 0)
			(size 1.016 1.27)
			(layers "F.Cu" "F.Mask" "F.Paste")
			(net "GND")
		)
	)
	(footprint ""
		(layer "F.Cu")
		(at 307.77688 -53.050948 90)
		(property "Reference" "R145"
			(at 0 0 90)
			(layer "F.SilkS")
			(hide yes)
			(effects
				(font
					(size 1.27 1.27)
				)
			)
		)
		(property "Value" ""
			(at 0 0 90)
			(layer "F.Fab")
			(effects
				(font
					(size 1.27 1.27)
				)
			)
		)
		(duplicate_pad_numbers_are_jumpers no)
		(fp_line
			(start 0.7874 -0.4064)
			(end 0.7874 0.4064)
			(stroke
				(width 0.1524)
				(type default)
			)
			(layer "F.SilkS")
		)
		(fp_line
			(start -0.7874 -0.4064)
			(end 0.7874 -0.4064)
			(stroke
				(width 0.1524)
				(type default)
			)
			(layer "F.SilkS")
		)
		(fp_line
			(start 0.7874 0.4064)
			(end -0.7874 0.4064)
			(stroke
				(width 0.1524)
				(type default)
			)
			(layer "F.SilkS")
		)
		(fp_line
			(start -0.7874 0.4064)
			(end -0.7874 -0.4064)
			(stroke
				(width 0.1524)
				(type default)
			)
			(layer "F.SilkS")
		)
		(fp_line
			(start -0.12065 -0.305054)
			(end -0.12065 -0.2794)
			(stroke
				(width 0.1)
				(type default)
			)
			(layer "F.Fab")
		)
		(fp_line
			(start -0.67945 -0.305054)
			(end -0.12065 -0.305054)
			(stroke
				(width 0.1)
				(type default)
			)
			(layer "F.Fab")
		)
		(fp_line
			(start 0.67945 -0.3048)
			(end 0.67945 0.3048)
			(stroke
				(width 0.1)
				(type default)
			)
			(layer "F.Fab")
		)
		(fp_line
			(start 0.12065 -0.3048)
			(end 0.67945 -0.3048)
			(stroke
				(width 0.1)
				(type default)
			)
			(layer "F.Fab")
		)
		(fp_line
			(start 0.12065 -0.2794)
			(end 0.12065 -0.3048)
			(stroke
				(width 0.1)
				(type default)
			)
			(layer "F.Fab")
		)
		(fp_line
			(start -0.12065 -0.2794)
			(end 0.12065 -0.2794)
			(stroke
				(width 0.1)
				(type default)
			)
			(layer "F.Fab")
		)
		(fp_line
			(start 0.120396 0.2794)
			(end -0.12065 0.2794)
			(stroke
				(width 0.1)
				(type default)
			)
			(layer "F.Fab")
		)
		(fp_line
			(start -0.12065 0.2794)
			(end -0.12065 0.3048)
			(stroke
				(width 0.1)
				(type default)
			)
			(layer "F.Fab")
		)
		(fp_line
			(start 0.67945 0.3048)
			(end 0.120396 0.3048)
			(stroke
				(width 0.1)
				(type default)
			)
			(layer "F.Fab")
		)
		(fp_line
			(start 0.120396 0.3048)
			(end 0.120396 0.2794)
			(stroke
				(width 0.1)
				(type default)
			)
			(layer "F.Fab")
		)
		(fp_line
			(start -0.12065 0.3048)
			(end -0.67945 0.3048)
			(stroke
				(width 0.1)
				(type default)
			)
			(layer "F.Fab")
		)
		(fp_line
			(start -0.67945 0.3048)
			(end -0.67945 -0.305054)
			(stroke
				(width 0.1)
				(type default)
			)
			(layer "F.Fab")
		)
		(pad "1" smd circle
			(at -0.40005 0 90)
			(size 0 0)
			(layers "F.Cu" "F.Mask" "F.Paste")
			(net "PVNN_TERM_CPU0")
		)
		(pad "2" smd circle
			(at 0.40005 0 90)
			(size 0 0)
			(layers "F.Cu" "F.Mask" "F.Paste")
			(net "PECI_PCH_R")
		)
	)
	(footprint ""
		(layer "F.Cu")
		(at 324.919594 -32.371538 135)
		(property "Reference" "R120"
			(at 0 0 135)
			(layer "F.SilkS")
			(hide yes)
			(effects
				(font
					(size 1.27 1.27)
				)
			)
		)
		(property "Value" ""
			(at 0 0 135)
			(layer "F.Fab")
			(effects
				(font
					(size 1.27 1.27)
				)
			)
		)
		(duplicate_pad_numbers_are_jumpers no)
		(fp_line
			(start 1.295492 -0.584255)
			(end 1.295492 0.584255)
			(stroke
				(width 0.1524)
				(type default)
			)
			(layer "F.SilkS")
		)
		(fp_line
			(start 1.295492 0.584255)
			(end -1.295492 0.584255)
			(stroke
				(width 0.1524)
				(type default)
			)
			(layer "F.SilkS")
		)
		(fp_line
			(start -1.295492 -0.584255)
			(end 1.295492 -0.584255)
			(stroke
				(width 0.1524)
				(type default)
			)
			(layer "F.SilkS")
		)
		(fp_line
			(start -1.295492 0.584255)
			(end -1.295492 -0.584255)
			(stroke
				(width 0.1524)
				(type default)
			)
			(layer "F.SilkS")
		)
		(fp_line
			(start 1.193656 -0.406626)
			(end 1.193835 0.406446)
			(stroke
				(width 0.1)
				(type default)
			)
			(layer "F.Fab")
		)
		(fp_line
			(start 0.863541 -0.457275)
			(end 0.863541 -0.406626)
			(stroke
				(width 0.1)
				(type default)
			)
			(layer "F.Fab")
		)
		(fp_line
			(start 0.863541 -0.406626)
			(end 1.193656 -0.406626)
			(stroke
				(width 0.1)
				(type default)
			)
			(layer "F.Fab")
		)
		(fp_line
			(start 1.193835 0.406446)
			(end 0.863721 0.406446)
			(stroke
				(width 0.1)
				(type default)
			)
			(layer "F.Fab")
		)
		(fp_line
			(start 0.863721 0.406446)
			(end 0.863541 0.457275)
			(stroke
				(width 0.1)
				(type default)
			)
			(layer "F.Fab")
		)
		(fp_line
			(start 0.863541 0.457275)
			(end -0.863541 0.457275)
			(stroke
				(width 0.1)
				(type default)
			)
			(layer "F.Fab")
		)
		(fp_line
			(start -0.863541 -0.457275)
			(end 0.863541 -0.457275)
			(stroke
				(width 0.1)
				(type default)
			)
			(layer "F.Fab")
		)
		(fp_line
			(start -0.863541 -0.406626)
			(end -0.863541 -0.457275)
			(stroke
				(width 0.1)
				(type default)
			)
			(layer "F.Fab")
		)
		(fp_line
			(start -1.193656 -0.406626)
			(end -0.863541 -0.406626)
			(stroke
				(width 0.1)
				(type default)
			)
			(layer "F.Fab")
		)
		(fp_line
			(start -0.863721 0.406446)
			(end -1.193835 0.406446)
			(stroke
				(width 0.1)
				(type default)
			)
			(layer "F.Fab")
		)
		(fp_line
			(start -0.863541 0.431771)
			(end -0.863721 0.406446)
			(stroke
				(width 0.1)
				(type default)
			)
			(layer "F.Fab")
		)
		(fp_line
			(start -0.863541 0.457275)
			(end -0.863541 0.431771)
			(stroke
				(width 0.1)
				(type default)
			)
			(layer "F.Fab")
		)
		(fp_line
			(start -1.193835 0.406446)
			(end -1.193656 -0.406626)
			(stroke
				(width 0.1)
				(type default)
			)
			(layer "F.Fab")
		)
		(pad "1" smd rect
			(at -0.7366 0 45)
			(size 0.7112 0.8128)
			(layers "F.Cu" "F.Mask" "F.Paste")
			(net "XTAL_PCH_RTC2_R")
		)
		(pad "2" smd rect
			(at 0.7366 0 45)
			(size 0.7112 0.8128)
			(layers "F.Cu" "F.Mask" "F.Paste")
			(net "XTAL_PCH_RTC1")
		)
	)
	(footprint ""
		(layer "F.Cu")
		(at 258.21386 -48.304704 180)
		(property "Reference" "R3943"
			(at 0 0 180)
			(layer "F.SilkS")
			(hide yes)
			(effects
				(font
					(size 1.27 1.27)
				)
			)
		)
		(property "Value" ""
			(at 0 0 180)
			(layer "F.Fab")
			(effects
				(font
					(size 1.27 1.27)
				)
			)
		)
		(duplicate_pad_numbers_are_jumpers no)
		(fp_line
			(start 0.7874 0.4064)
			(end -0.7874 0.4064)
			(stroke
				(width 0.1524)
				(type default)
			)
			(layer "F.SilkS")
		)
		(fp_line
			(start 0.7874 -0.4064)
			(end 0.7874 0.4064)
			(stroke
				(width 0.1524)
				(type default)
			)
			(layer "F.SilkS")
		)
		(fp_line
			(start -0.7874 0.4064)
			(end -0.7874 -0.4064)
			(stroke
				(width 0.1524)
				(type default)
			)
			(layer "F.SilkS")
		)
		(fp_line
			(start -0.7874 -0.4064)
			(end 0.7874 -0.4064)
			(stroke
				(width 0.1524)
				(type default)
			)
			(layer "F.SilkS")
		)
		(fp_line
			(start 0.67945 0.3048)
			(end 0.120396 0.3048)
			(stroke
				(width 0.1)
				(type default)
			)
			(layer "F.Fab")
		)
		(fp_line
			(start 0.67945 -0.3048)
			(end 0.67945 0.3048)
			(stroke
				(width 0.1)
				(type default)
			)
			(layer "F.Fab")
		)
		(fp_line
			(start 0.12065 -0.2794)
			(end 0.12065 -0.3048)
			(stroke
				(width 0.1)
				(type default)
			)
			(layer "F.Fab")
		)
		(fp_line
			(start 0.12065 -0.3048)
			(end 0.67945 -0.3048)
			(stroke
				(width 0.1)
				(type default)
			)
			(layer "F.Fab")
		)
		(fp_line
			(start 0.120396 0.3048)
			(end 0.120396 0.2794)
			(stroke
				(width 0.1)
				(type default)
			)
			(layer "F.Fab")
		)
		(fp_line
			(start 0.120396 0.2794)
			(end -0.12065 0.2794)
			(stroke
				(width 0.1)
				(type default)
			)
			(layer "F.Fab")
		)
		(fp_line
			(start -0.12065 0.3048)
			(end -0.67945 0.3048)
			(stroke
				(width 0.1)
				(type default)
			)
			(layer "F.Fab")
		)
		(fp_line
			(start -0.12065 0.2794)
			(end -0.12065 0.3048)
			(stroke
				(width 0.1)
				(type default)
			)
			(layer "F.Fab")
		)
		(fp_line
			(start -0.12065 -0.2794)
			(end 0.12065 -0.2794)
			(stroke
				(width 0.1)
				(type default)
			)
			(layer "F.Fab")
		)
		(fp_line
			(start -0.12065 -0.305054)
			(end -0.12065 -0.2794)
			(stroke
				(width 0.1)
				(type default)
			)
			(layer "F.Fab")
		)
		(fp_line
			(start -0.67945 0.3048)
			(end -0.67945 -0.305054)
			(stroke
				(width 0.1)
				(type default)
			)
			(layer "F.Fab")
		)
		(fp_line
			(start -0.67945 -0.305054)
			(end -0.12065 -0.305054)
			(stroke
				(width 0.1)
				(type default)
			)
			(layer "F.Fab")
		)
		(pad "1" smd circle
			(at -0.40005 0 180)
			(size 0 0)
			(layers "F.Cu" "F.Mask" "F.Paste")
			(net "E1S_0_EN")
		)
		(pad "2" smd circle
			(at 0.40005 0 180)
			(size 0 0)
			(layers "F.Cu" "F.Mask" "F.Paste")
			(net "P12V_E1S_EN_0_R2")
		)
	)
	(footprint ""
		(layer "F.Cu")
		(at 24.777446 -174.51451 90)
		(property "Reference" "PR4700"
			(at 0 0 90)
			(layer "F.SilkS")
			(hide yes)
			(effects
				(font
					(size 1.27 1.27)
				)
			)
		)
		(property "Value" ""
			(at 0 0 90)
			(layer "F.Fab")
			(effects
				(font
					(size 1.27 1.27)
				)
			)
		)
		(duplicate_pad_numbers_are_jumpers no)
		(fp_line
			(start 0.7874 -0.4064)
			(end 0.7874 0.4064)
			(stroke
				(width 0.1524)
				(type default)
			)
			(layer "F.SilkS")
		)
		(fp_line
			(start -0.7874 -0.4064)
			(end 0.7874 -0.4064)
			(stroke
				(width 0.1524)
				(type default)
			)
			(layer "F.SilkS")
		)
		(fp_line
			(start 0.7874 0.4064)
			(end -0.7874 0.4064)
			(stroke
				(width 0.1524)
				(type default)
			)
			(layer "F.SilkS")
		)
		(fp_line
			(start -0.7874 0.4064)
			(end -0.7874 -0.4064)
			(stroke
				(width 0.1524)
				(type default)
			)
			(layer "F.SilkS")
		)
		(fp_line
			(start -0.12065 -0.305054)
			(end -0.12065 -0.2794)
			(stroke
				(width 0.1)
				(type default)
			)
			(layer "F.Fab")
		)
		(fp_line
			(start -0.67945 -0.305054)
			(end -0.12065 -0.305054)
			(stroke
				(width 0.1)
				(type default)
			)
			(layer "F.Fab")
		)
		(fp_line
			(start 0.67945 -0.3048)
			(end 0.67945 0.3048)
			(stroke
				(width 0.1)
				(type default)
			)
			(layer "F.Fab")
		)
		(fp_line
			(start 0.12065 -0.3048)
			(end 0.67945 -0.3048)
			(stroke
				(width 0.1)
				(type default)
			)
			(layer "F.Fab")
		)
		(fp_line
			(start 0.12065 -0.2794)
			(end 0.12065 -0.3048)
			(stroke
				(width 0.1)
				(type default)
			)
			(layer "F.Fab")
		)
		(fp_line
			(start -0.12065 -0.2794)
			(end 0.12065 -0.2794)
			(stroke
				(width 0.1)
				(type default)
			)
			(layer "F.Fab")
		)
		(fp_line
			(start 0.120396 0.2794)
			(end -0.12065 0.2794)
			(stroke
				(width 0.1)
				(type default)
			)
			(layer "F.Fab")
		)
		(fp_line
			(start -0.12065 0.2794)
			(end -0.12065 0.3048)
			(stroke
				(width 0.1)
				(type default)
			)
			(layer "F.Fab")
		)
		(fp_line
			(start 0.67945 0.3048)
			(end 0.120396 0.3048)
			(stroke
				(width 0.1)
				(type default)
			)
			(layer "F.Fab")
		)
		(fp_line
			(start 0.120396 0.3048)
			(end 0.120396 0.2794)
			(stroke
				(width 0.1)
				(type default)
			)
			(layer "F.Fab")
		)
		(fp_line
			(start -0.12065 0.3048)
			(end -0.67945 0.3048)
			(stroke
				(width 0.1)
				(type default)
			)
			(layer "F.Fab")
		)
		(fp_line
			(start -0.67945 0.3048)
			(end -0.67945 -0.305054)
			(stroke
				(width 0.1)
				(type default)
			)
			(layer "F.Fab")
		)
		(pad "1" smd circle
			(at -0.40005 0 90)
			(size 0 0)
			(layers "F.Cu" "F.Mask" "F.Paste")
			(net "PVNN_MAIN_CPU1_FB_RC")
		)
		(pad "2" smd circle
			(at 0.40005 0 90)
			(size 0 0)
			(layers "F.Cu" "F.Mask" "F.Paste")
			(net "PVNN_MAIN_CPU1")
		)
	)
	(footprint ""
		(layer "F.Cu")
		(at 354.268278 -238.162338 -90)
		(property "Reference" "C1039"
			(at 0 0 270)
			(layer "F.SilkS")
			(hide yes)
			(effects
				(font
					(size 1.27 1.27)
				)
			)
		)
		(property "Value" ""
			(at 0 0 270)
			(layer "F.Fab")
			(effects
				(font
					(size 1.27 1.27)
				)
			)
		)
		(duplicate_pad_numbers_are_jumpers no)
		(fp_line
			(start -0.7874 0.4064)
			(end -0.7874 -0.4064)
			(stroke
				(width 0.1524)
				(type default)
			)
			(layer "F.SilkS")
		)
		(fp_line
			(start 0.7874 0.4064)
			(end -0.7874 0.4064)
			(stroke
				(width 0.1524)
				(type default)
			)
			(layer "F.SilkS")
		)
		(fp_line
			(start -0.7874 -0.4064)
			(end 0.7874 -0.4064)
			(stroke
				(width 0.1524)
				(type default)
			)
			(layer "F.SilkS")
		)
		(fp_line
			(start 0.7874 -0.4064)
			(end 0.7874 0.4064)
			(stroke
				(width 0.1524)
				(type default)
			)
			(layer "F.SilkS")
		)
		(fp_line
			(start -0.67945 0.3048)
			(end -0.67945 -0.305054)
			(stroke
				(width 0.1)
				(type default)
			)
			(layer "F.Fab")
		)
		(fp_line
			(start -0.12065 0.3048)
			(end -0.67945 0.3048)
			(stroke
				(width 0.1)
				(type default)
			)
			(layer "F.Fab")
		)
		(fp_line
			(start 0.120396 0.3048)
			(end 0.120396 0.2794)
			(stroke
				(width 0.1)
				(type default)
			)
			(layer "F.Fab")
		)
		(fp_line
			(start 0.67945 0.3048)
			(end 0.120396 0.3048)
			(stroke
				(width 0.1)
				(type default)
			)
			(layer "F.Fab")
		)
		(fp_line
			(start -0.12065 0.2794)
			(end -0.12065 0.3048)
			(stroke
				(width 0.1)
				(type default)
			)
			(layer "F.Fab")
		)
		(fp_line
			(start 0.120396 0.2794)
			(end -0.12065 0.2794)
			(stroke
				(width 0.1)
				(type default)
			)
			(layer "F.Fab")
		)
		(fp_line
			(start -0.12065 -0.2794)
			(end 0.12065 -0.2794)
			(stroke
				(width 0.1)
				(type default)
			)
			(layer "F.Fab")
		)
		(fp_line
			(start 0.12065 -0.2794)
			(end 0.12065 -0.3048)
			(stroke
				(width 0.1)
				(type default)
			)
			(layer "F.Fab")
		)
		(fp_line
			(start 0.12065 -0.3048)
			(end 0.67945 -0.3048)
			(stroke
				(width 0.1)
				(type default)
			)
			(layer "F.Fab")
		)
		(fp_line
			(start 0.67945 -0.3048)
			(end 0.67945 0.3048)
			(stroke
				(width 0.1)
				(type default)
			)
			(layer "F.Fab")
		)
		(fp_line
			(start -0.67945 -0.305054)
			(end -0.12065 -0.305054)
			(stroke
				(width 0.1)
				(type default)
			)
			(layer "F.Fab")
		)
		(fp_line
			(start -0.12065 -0.305054)
			(end -0.12065 -0.2794)
			(stroke
				(width 0.1)
				(type default)
			)
			(layer "F.Fab")
		)
		(pad "1" smd circle
			(at -0.40005 0 270)
			(size 0 0)
			(layers "F.Cu" "F.Mask" "F.Paste")
			(net "PVCCIN_CPU0")
		)
		(pad "2" smd circle
			(at 0.40005 0 270)
			(size 0 0)
			(layers "F.Cu" "F.Mask" "F.Paste")
			(net "GND")
		)
	)
	(footprint ""
		(layer "F.Cu")
		(at 21.176996 -98.171508)
		(property "Reference" "R3665"
			(at 0 0 0)
			(layer "F.SilkS")
			(hide yes)
			(effects
				(font
					(size 1.27 1.27)
				)
			)
		)
		(property "Value" ""
			(at 0 0 0)
			(layer "F.Fab")
			(effects
				(font
					(size 1.27 1.27)
				)
			)
		)
		(duplicate_pad_numbers_are_jumpers no)
		(fp_line
			(start -0.7874 -0.4064)
			(end 0.7874 -0.4064)
			(stroke
				(width 0.1524)
				(type default)
			)
			(layer "F.SilkS")
		)
		(fp_line
			(start -0.7874 0.4064)
			(end -0.7874 -0.4064)
			(stroke
				(width 0.1524)
				(type default)
			)
			(layer "F.SilkS")
		)
		(fp_line
			(start 0.7874 -0.4064)
			(end 0.7874 0.4064)
			(stroke
				(width 0.1524)
				(type default)
			)
			(layer "F.SilkS")
		)
		(fp_line
			(start 0.7874 0.4064)
			(end -0.7874 0.4064)
			(stroke
				(width 0.1524)
				(type default)
			)
			(layer "F.SilkS")
		)
		(fp_line
			(start -0.67945 -0.305054)
			(end -0.12065 -0.305054)
			(stroke
				(width 0.1)
				(type default)
			)
			(layer "F.Fab")
		)
		(fp_line
			(start -0.67945 0.3048)
			(end -0.67945 -0.305054)
			(stroke
				(width 0.1)
				(type default)
			)
			(layer "F.Fab")
		)
		(fp_line
			(start -0.12065 -0.305054)
			(end -0.12065 -0.2794)
			(stroke
				(width 0.1)
				(type default)
			)
			(layer "F.Fab")
		)
		(fp_line
			(start -0.12065 -0.2794)
			(end 0.12065 -0.2794)
			(stroke
				(width 0.1)
				(type default)
			)
			(layer "F.Fab")
		)
		(fp_line
			(start -0.12065 0.2794)
			(end -0.12065 0.3048)
			(stroke
				(width 0.1)
				(type default)
			)
			(layer "F.Fab")
		)
		(fp_line
			(start -0.12065 0.3048)
			(end -0.67945 0.3048)
			(stroke
				(width 0.1)
				(type default)
			)
			(layer "F.Fab")
		)
		(fp_line
			(start 0.120396 0.2794)
			(end -0.12065 0.2794)
			(stroke
				(width 0.1)
				(type default)
			)
			(layer "F.Fab")
		)
		(fp_line
			(start 0.120396 0.3048)
			(end 0.120396 0.2794)
			(stroke
				(width 0.1)
				(type default)
			)
			(layer "F.Fab")
		)
		(fp_line
			(start 0.12065 -0.3048)
			(end 0.67945 -0.3048)
			(stroke
				(width 0.1)
				(type default)
			)
			(layer "F.Fab")
		)
		(fp_line
			(start 0.12065 -0.2794)
			(end 0.12065 -0.3048)
			(stroke
				(width 0.1)
				(type default)
			)
			(layer "F.Fab")
		)
		(fp_line
			(start 0.67945 -0.3048)
			(end 0.67945 0.3048)
			(stroke
				(width 0.1)
				(type default)
			)
			(layer "F.Fab")
		)
		(fp_line
			(start 0.67945 0.3048)
			(end 0.120396 0.3048)
			(stroke
				(width 0.1)
				(type default)
			)
			(layer "F.Fab")
		)
		(pad "1" smd circle
			(at -0.40005 0)
			(size 0 0)
			(layers "F.Cu" "F.Mask" "F.Paste")
			(net "USB_HUB_PGANG")
		)
		(pad "2" smd circle
			(at 0.40005 0)
			(size 0 0)
			(layers "F.Cu" "F.Mask" "F.Paste")
			(net "GND")
		)
	)
	(footprint ""
		(layer "F.Cu")
		(at 149.75078 -124.005848)
		(property "Reference" "R3154"
			(at 0 0 0)
			(layer "F.SilkS")
			(hide yes)
			(effects
				(font
					(size 1.27 1.27)
				)
			)
		)
		(property "Value" ""
			(at 0 0 0)
			(layer "F.Fab")
			(effects
				(font
					(size 1.27 1.27)
				)
			)
		)
		(duplicate_pad_numbers_are_jumpers no)
		(fp_line
			(start -0.7874 -0.4064)
			(end 0.7874 -0.4064)
			(stroke
				(width 0.1524)
				(type default)
			)
			(layer "F.SilkS")
		)
		(fp_line
			(start -0.7874 0.4064)
			(end -0.7874 -0.4064)
			(stroke
				(width 0.1524)
				(type default)
			)
			(layer "F.SilkS")
		)
		(fp_line
			(start 0.7874 -0.4064)
			(end 0.7874 0.4064)
			(stroke
				(width 0.1524)
				(type default)
			)
			(layer "F.SilkS")
		)
		(fp_line
			(start 0.7874 0.4064)
			(end -0.7874 0.4064)
			(stroke
				(width 0.1524)
				(type default)
			)
			(layer "F.SilkS")
		)
		(fp_line
			(start -0.67945 -0.305054)
			(end -0.12065 -0.305054)
			(stroke
				(width 0.1)
				(type default)
			)
			(layer "F.Fab")
		)
		(fp_line
			(start -0.67945 0.3048)
			(end -0.67945 -0.305054)
			(stroke
				(width 0.1)
				(type default)
			)
			(layer "F.Fab")
		)
		(fp_line
			(start -0.12065 -0.305054)
			(end -0.12065 -0.2794)
			(stroke
				(width 0.1)
				(type default)
			)
			(layer "F.Fab")
		)
		(fp_line
			(start -0.12065 -0.2794)
			(end 0.12065 -0.2794)
			(stroke
				(width 0.1)
				(type default)
			)
			(layer "F.Fab")
		)
		(fp_line
			(start -0.12065 0.2794)
			(end -0.12065 0.3048)
			(stroke
				(width 0.1)
				(type default)
			)
			(layer "F.Fab")
		)
		(fp_line
			(start -0.12065 0.3048)
			(end -0.67945 0.3048)
			(stroke
				(width 0.1)
				(type default)
			)
			(layer "F.Fab")
		)
		(fp_line
			(start 0.120396 0.2794)
			(end -0.12065 0.2794)
			(stroke
				(width 0.1)
				(type default)
			)
			(layer "F.Fab")
		)
		(fp_line
			(start 0.120396 0.3048)
			(end 0.120396 0.2794)
			(stroke
				(width 0.1)
				(type default)
			)
			(layer "F.Fab")
		)
		(fp_line
			(start 0.12065 -0.3048)
			(end 0.67945 -0.3048)
			(stroke
				(width 0.1)
				(type default)
			)
			(layer "F.Fab")
		)
		(fp_line
			(start 0.12065 -0.2794)
			(end 0.12065 -0.3048)
			(stroke
				(width 0.1)
				(type default)
			)
			(layer "F.Fab")
		)
		(fp_line
			(start 0.67945 -0.3048)
			(end 0.67945 0.3048)
			(stroke
				(width 0.1)
				(type default)
			)
			(layer "F.Fab")
		)
		(fp_line
			(start 0.67945 0.3048)
			(end 0.120396 0.3048)
			(stroke
				(width 0.1)
				(type default)
			)
			(layer "F.Fab")
		)
		(pad "1" smd circle
			(at -0.40005 0)
			(size 0 0)
			(layers "F.Cu" "F.Mask" "F.Paste")
			(net "PD_SMB_OCP2_HP_ADD0")
		)
		(pad "2" smd circle
			(at 0.40005 0)
			(size 0 0)
			(layers "F.Cu" "F.Mask" "F.Paste")
			(net "GND")
		)
	)
	(footprint ""
		(layer "F.Cu")
		(at 106.476038 -39.996364)
		(property "Reference" "R3186"
			(at 0 0 0)
			(layer "F.SilkS")
			(hide yes)
			(effects
				(font
					(size 1.27 1.27)
				)
			)
		)
		(property "Value" ""
			(at 0 0 0)
			(layer "F.Fab")
			(effects
				(font
					(size 1.27 1.27)
				)
			)
		)
		(duplicate_pad_numbers_are_jumpers no)
		(fp_line
			(start -0.7874 -0.4064)
			(end 0.7874 -0.4064)
			(stroke
				(width 0.1524)
				(type default)
			)
			(layer "F.SilkS")
		)
		(fp_line
			(start -0.7874 0.4064)
			(end -0.7874 -0.4064)
			(stroke
				(width 0.1524)
				(type default)
			)
			(layer "F.SilkS")
		)
		(fp_line
			(start 0.7874 -0.4064)
			(end 0.7874 0.4064)
			(stroke
				(width 0.1524)
				(type default)
			)
			(layer "F.SilkS")
		)
		(fp_line
			(start 0.7874 0.4064)
			(end -0.7874 0.4064)
			(stroke
				(width 0.1524)
				(type default)
			)
			(layer "F.SilkS")
		)
		(fp_line
			(start -0.67945 -0.305054)
			(end -0.12065 -0.305054)
			(stroke
				(width 0.1)
				(type default)
			)
			(layer "F.Fab")
		)
		(fp_line
			(start -0.67945 0.3048)
			(end -0.67945 -0.305054)
			(stroke
				(width 0.1)
				(type default)
			)
			(layer "F.Fab")
		)
		(fp_line
			(start -0.12065 -0.305054)
			(end -0.12065 -0.2794)
			(stroke
				(width 0.1)
				(type default)
			)
			(layer "F.Fab")
		)
		(fp_line
			(start -0.12065 -0.2794)
			(end 0.12065 -0.2794)
			(stroke
				(width 0.1)
				(type default)
			)
			(layer "F.Fab")
		)
		(fp_line
			(start -0.12065 0.2794)
			(end -0.12065 0.3048)
			(stroke
				(width 0.1)
				(type default)
			)
			(layer "F.Fab")
		)
		(fp_line
			(start -0.12065 0.3048)
			(end -0.67945 0.3048)
			(stroke
				(width 0.1)
				(type default)
			)
			(layer "F.Fab")
		)
		(fp_line
			(start 0.120396 0.2794)
			(end -0.12065 0.2794)
			(stroke
				(width 0.1)
				(type default)
			)
			(layer "F.Fab")
		)
		(fp_line
			(start 0.120396 0.3048)
			(end 0.120396 0.2794)
			(stroke
				(width 0.1)
				(type default)
			)
			(layer "F.Fab")
		)
		(fp_line
			(start 0.12065 -0.3048)
			(end 0.67945 -0.3048)
			(stroke
				(width 0.1)
				(type default)
			)
			(layer "F.Fab")
		)
		(fp_line
			(start 0.12065 -0.2794)
			(end 0.12065 -0.3048)
			(stroke
				(width 0.1)
				(type default)
			)
			(layer "F.Fab")
		)
		(fp_line
			(start 0.67945 -0.3048)
			(end 0.67945 0.3048)
			(stroke
				(width 0.1)
				(type default)
			)
			(layer "F.Fab")
		)
		(fp_line
			(start 0.67945 0.3048)
			(end 0.120396 0.3048)
			(stroke
				(width 0.1)
				(type default)
			)
			(layer "F.Fab")
		)
		(pad "1" smd circle
			(at -0.40005 0)
			(size 0 0)
			(layers "F.Cu" "F.Mask" "F.Paste")
			(net "RST_OCP_V3_2_BUF_N")
		)
		(pad "2" smd circle
			(at 0.40005 0)
			(size 0 0)
			(layers "F.Cu" "F.Mask" "F.Paste")
			(net "RST_PERST0_OCP_V3_2_N")
		)
	)
	(footprint ""
		(layer "F.Cu")
		(at 65.90411 -17.941544 180)
		(property "Reference" "C1829"
			(at 0 0 180)
			(layer "F.SilkS")
			(hide yes)
			(effects
				(font
					(size 1.27 1.27)
				)
			)
		)
		(property "Value" ""
			(at 0 0 180)
			(layer "F.Fab")
			(effects
				(font
					(size 1.27 1.27)
				)
			)
		)
		(duplicate_pad_numbers_are_jumpers no)
		(fp_line
			(start 1.524 0.762)
			(end -1.524 0.762)
			(stroke
				(width 0.1524)
				(type default)
			)
			(layer "F.SilkS")
		)
		(fp_line
			(start 1.524 -0.762)
			(end 1.524 0.762)
			(stroke
				(width 0.1524)
				(type default)
			)
			(layer "F.SilkS")
		)
		(fp_line
			(start -1.524 0.762)
			(end -1.524 -0.762)
			(stroke
				(width 0.1524)
				(type default)
			)
			(layer "F.SilkS")
		)
		(fp_line
			(start -1.524 -0.762)
			(end 1.524 -0.762)
			(stroke
				(width 0.1524)
				(type default)
			)
			(layer "F.SilkS")
		)
		(fp_line
			(start 1.1049 0.724916)
			(end 1.1049 -0.724916)
			(stroke
				(width 0.1)
				(type default)
			)
			(layer "F.Fab")
		)
		(fp_line
			(start 1.1049 -0.724916)
			(end -1.1049 -0.724916)
			(stroke
				(width 0.1)
				(type default)
			)
			(layer "F.Fab")
		)
		(fp_line
			(start -1.1049 0.724916)
			(end 1.1049 0.724916)
			(stroke
				(width 0.1)
				(type default)
			)
			(layer "F.Fab")
		)
		(fp_line
			(start -1.1049 -0.724916)
			(end -1.1049 0.724916)
			(stroke
				(width 0.1)
				(type default)
			)
			(layer "F.Fab")
		)
		(pad "1" smd rect
			(at -0.889 0)
			(size 1.016 1.27)
			(layers "F.Cu" "F.Mask" "F.Paste")
			(net "P12V_OCP_V3_2")
		)
		(pad "2" smd rect
			(at 0.889 0)
			(size 1.016 1.27)
			(layers "F.Cu" "F.Mask" "F.Paste")
			(net "GND")
		)
	)
	(footprint ""
		(layer "F.Cu")
		(at 114.70386 -363.508036)
		(property "Reference" "PC2366"
			(at 0 0 0)
			(layer "F.SilkS")
			(hide yes)
			(effects
				(font
					(size 1.27 1.27)
				)
			)
		)
		(property "Value" ""
			(at 0 0 0)
			(layer "F.Fab")
			(effects
				(font
					(size 1.27 1.27)
				)
			)
		)
		(duplicate_pad_numbers_are_jumpers no)
		(fp_line
			(start -0.7874 -0.4064)
			(end 0.7874 -0.4064)
			(stroke
				(width 0.1524)
				(type default)
			)
			(layer "F.SilkS")
		)
		(fp_line
			(start -0.7874 0.4064)
			(end -0.7874 -0.4064)
			(stroke
				(width 0.1524)
				(type default)
			)
			(layer "F.SilkS")
		)
		(fp_line
			(start 0.7874 -0.4064)
			(end 0.7874 0.4064)
			(stroke
				(width 0.1524)
				(type default)
			)
			(layer "F.SilkS")
		)
		(fp_line
			(start 0.7874 0.4064)
			(end -0.7874 0.4064)
			(stroke
				(width 0.1524)
				(type default)
			)
			(layer "F.SilkS")
		)
		(fp_line
			(start -0.67945 -0.305054)
			(end -0.12065 -0.305054)
			(stroke
				(width 0.1)
				(type default)
			)
			(layer "F.Fab")
		)
		(fp_line
			(start -0.67945 0.3048)
			(end -0.67945 -0.305054)
			(stroke
				(width 0.1)
				(type default)
			)
			(layer "F.Fab")
		)
		(fp_line
			(start -0.12065 -0.305054)
			(end -0.12065 -0.2794)
			(stroke
				(width 0.1)
				(type default)
			)
			(layer "F.Fab")
		)
		(fp_line
			(start -0.12065 -0.2794)
			(end 0.12065 -0.2794)
			(stroke
				(width 0.1)
				(type default)
			)
			(layer "F.Fab")
		)
		(fp_line
			(start -0.12065 0.2794)
			(end -0.12065 0.3048)
			(stroke
				(width 0.1)
				(type default)
			)
			(layer "F.Fab")
		)
		(fp_line
			(start -0.12065 0.3048)
			(end -0.67945 0.3048)
			(stroke
				(width 0.1)
				(type default)
			)
			(layer "F.Fab")
		)
		(fp_line
			(start 0.120396 0.2794)
			(end -0.12065 0.2794)
			(stroke
				(width 0.1)
				(type default)
			)
			(layer "F.Fab")
		)
		(fp_line
			(start 0.120396 0.3048)
			(end 0.120396 0.2794)
			(stroke
				(width 0.1)
				(type default)
			)
			(layer "F.Fab")
		)
		(fp_line
			(start 0.12065 -0.3048)
			(end 0.67945 -0.3048)
			(stroke
				(width 0.1)
				(type default)
			)
			(layer "F.Fab")
		)
		(fp_line
			(start 0.12065 -0.2794)
			(end 0.12065 -0.3048)
			(stroke
				(width 0.1)
				(type default)
			)
			(layer "F.Fab")
		)
		(fp_line
			(start 0.67945 -0.3048)
			(end 0.67945 0.3048)
			(stroke
				(width 0.1)
				(type default)
			)
			(layer "F.Fab")
		)
		(fp_line
			(start 0.67945 0.3048)
			(end 0.120396 0.3048)
			(stroke
				(width 0.1)
				(type default)
			)
			(layer "F.Fab")
		)
		(pad "1" smd circle
			(at -0.40005 0)
			(size 0 0)
			(layers "F.Cu" "F.Mask" "F.Paste")
			(net "PVCCIN_CPU1_VCC")
		)
		(pad "2" smd circle
			(at 0.40005 0)
			(size 0 0)
			(layers "F.Cu" "F.Mask" "F.Paste")
			(net "GND")
		)
	)
	(footprint ""
		(layer "F.Cu")
		(at 418.485828 -183.032654)
		(property "Reference" "PC188"
			(at 0 0 0)
			(layer "F.SilkS")
			(hide yes)
			(effects
				(font
					(size 1.27 1.27)
				)
			)
		)
		(property "Value" ""
			(at 0 0 0)
			(layer "F.Fab")
			(effects
				(font
					(size 1.27 1.27)
				)
			)
		)
		(duplicate_pad_numbers_are_jumpers no)
		(fp_line
			(start -0.7874 -0.4064)
			(end 0.7874 -0.4064)
			(stroke
				(width 0.1524)
				(type default)
			)
			(layer "F.SilkS")
		)
		(fp_line
			(start -0.7874 0.4064)
			(end -0.7874 -0.4064)
			(stroke
				(width 0.1524)
				(type default)
			)
			(layer "F.SilkS")
		)
		(fp_line
			(start 0.7874 -0.4064)
			(end 0.7874 0.4064)
			(stroke
				(width 0.1524)
				(type default)
			)
			(layer "F.SilkS")
		)
		(fp_line
			(start 0.7874 0.4064)
			(end -0.7874 0.4064)
			(stroke
				(width 0.1524)
				(type default)
			)
			(layer "F.SilkS")
		)
		(fp_line
			(start -0.67945 -0.305054)
			(end -0.12065 -0.305054)
			(stroke
				(width 0.1)
				(type default)
			)
			(layer "F.Fab")
		)
		(fp_line
			(start -0.67945 0.3048)
			(end -0.67945 -0.305054)
			(stroke
				(width 0.1)
				(type default)
			)
			(layer "F.Fab")
		)
		(fp_line
			(start -0.12065 -0.305054)
			(end -0.12065 -0.2794)
			(stroke
				(width 0.1)
				(type default)
			)
			(layer "F.Fab")
		)
		(fp_line
			(start -0.12065 -0.2794)
			(end 0.12065 -0.2794)
			(stroke
				(width 0.1)
				(type default)
			)
			(layer "F.Fab")
		)
		(fp_line
			(start -0.12065 0.2794)
			(end -0.12065 0.3048)
			(stroke
				(width 0.1)
				(type default)
			)
			(layer "F.Fab")
		)
		(fp_line
			(start -0.12065 0.3048)
			(end -0.67945 0.3048)
			(stroke
				(width 0.1)
				(type default)
			)
			(layer "F.Fab")
		)
		(fp_line
			(start 0.120396 0.2794)
			(end -0.12065 0.2794)
			(stroke
				(width 0.1)
				(type default)
			)
			(layer "F.Fab")
		)
		(fp_line
			(start 0.120396 0.3048)
			(end 0.120396 0.2794)
			(stroke
				(width 0.1)
				(type default)
			)
			(layer "F.Fab")
		)
		(fp_line
			(start 0.12065 -0.3048)
			(end 0.67945 -0.3048)
			(stroke
				(width 0.1)
				(type default)
			)
			(layer "F.Fab")
		)
		(fp_line
			(start 0.12065 -0.2794)
			(end 0.12065 -0.3048)
			(stroke
				(width 0.1)
				(type default)
			)
			(layer "F.Fab")
		)
		(fp_line
			(start 0.67945 -0.3048)
			(end 0.67945 0.3048)
			(stroke
				(width 0.1)
				(type default)
			)
			(layer "F.Fab")
		)
		(fp_line
			(start 0.67945 0.3048)
			(end 0.120396 0.3048)
			(stroke
				(width 0.1)
				(type default)
			)
			(layer "F.Fab")
		)
		(pad "1" smd circle
			(at -0.40005 0)
			(size 0 0)
			(layers "F.Cu" "F.Mask" "F.Paste")
			(net "PVCCINFAON_CPU0_VDD2")
		)
		(pad "2" smd circle
			(at 0.40005 0)
			(size 0 0)
			(layers "F.Cu" "F.Mask" "F.Paste")
			(net "GND")
		)
	)
	(footprint ""
		(layer "F.Cu")
		(at 398.270476 -148.010118 90)
		(property "Reference" "PR522"
			(at 0 0 90)
			(layer "F.SilkS")
			(hide yes)
			(effects
				(font
					(size 1.27 1.27)
				)
			)
		)
		(property "Value" ""
			(at 0 0 90)
			(layer "F.Fab")
			(effects
				(font
					(size 1.27 1.27)
				)
			)
		)
		(duplicate_pad_numbers_are_jumpers no)
		(fp_line
			(start 0.7874 -0.4064)
			(end 0.7874 0.4064)
			(stroke
				(width 0.1524)
				(type default)
			)
			(layer "F.SilkS")
		)
		(fp_line
			(start -0.7874 -0.4064)
			(end 0.7874 -0.4064)
			(stroke
				(width 0.1524)
				(type default)
			)
			(layer "F.SilkS")
		)
		(fp_line
			(start 0.7874 0.4064)
			(end -0.7874 0.4064)
			(stroke
				(width 0.1524)
				(type default)
			)
			(layer "F.SilkS")
		)
		(fp_line
			(start -0.7874 0.4064)
			(end -0.7874 -0.4064)
			(stroke
				(width 0.1524)
				(type default)
			)
			(layer "F.SilkS")
		)
		(fp_line
			(start -0.12065 -0.305054)
			(end -0.12065 -0.2794)
			(stroke
				(width 0.1)
				(type default)
			)
			(layer "F.Fab")
		)
		(fp_line
			(start -0.67945 -0.305054)
			(end -0.12065 -0.305054)
			(stroke
				(width 0.1)
				(type default)
			)
			(layer "F.Fab")
		)
		(fp_line
			(start 0.67945 -0.3048)
			(end 0.67945 0.3048)
			(stroke
				(width 0.1)
				(type default)
			)
			(layer "F.Fab")
		)
		(fp_line
			(start 0.12065 -0.3048)
			(end 0.67945 -0.3048)
			(stroke
				(width 0.1)
				(type default)
			)
			(layer "F.Fab")
		)
		(fp_line
			(start 0.12065 -0.2794)
			(end 0.12065 -0.3048)
			(stroke
				(width 0.1)
				(type default)
			)
			(layer "F.Fab")
		)
		(fp_line
			(start -0.12065 -0.2794)
			(end 0.12065 -0.2794)
			(stroke
				(width 0.1)
				(type default)
			)
			(layer "F.Fab")
		)
		(fp_line
			(start 0.120396 0.2794)
			(end -0.12065 0.2794)
			(stroke
				(width 0.1)
				(type default)
			)
			(layer "F.Fab")
		)
		(fp_line
			(start -0.12065 0.2794)
			(end -0.12065 0.3048)
			(stroke
				(width 0.1)
				(type default)
			)
			(layer "F.Fab")
		)
		(fp_line
			(start 0.67945 0.3048)
			(end 0.120396 0.3048)
			(stroke
				(width 0.1)
				(type default)
			)
			(layer "F.Fab")
		)
		(fp_line
			(start 0.120396 0.3048)
			(end 0.120396 0.2794)
			(stroke
				(width 0.1)
				(type default)
			)
			(layer "F.Fab")
		)
		(fp_line
			(start -0.12065 0.3048)
			(end -0.67945 0.3048)
			(stroke
				(width 0.1)
				(type default)
			)
			(layer "F.Fab")
		)
		(fp_line
			(start -0.67945 0.3048)
			(end -0.67945 -0.305054)
			(stroke
				(width 0.1)
				(type default)
			)
			(layer "F.Fab")
		)
		(pad "1" smd circle
			(at -0.40005 0 90)
			(size 0 0)
			(layers "F.Cu" "F.Mask" "F.Paste")
			(net "VSENSE_PVCCFA_EHV_CPU0_DP")
		)
		(pad "2" smd circle
			(at 0.40005 0 90)
			(size 0 0)
			(layers "F.Cu" "F.Mask" "F.Paste")
			(net "PVCCFA_EHV_CPU0")
		)
	)
	(footprint ""
		(layer "F.Cu")
		(at 108.05668 -61.102748)
		(property "Reference" "R1365"
			(at 0 0 0)
			(layer "F.SilkS")
			(hide yes)
			(effects
				(font
					(size 1.27 1.27)
				)
			)
		)
		(property "Value" ""
			(at 0 0 0)
			(layer "F.Fab")
			(effects
				(font
					(size 1.27 1.27)
				)
			)
		)
		(duplicate_pad_numbers_are_jumpers no)
		(fp_line
			(start -0.7874 -0.4064)
			(end 0.7874 -0.4064)
			(stroke
				(width 0.1524)
				(type default)
			)
			(layer "F.SilkS")
		)
		(fp_line
			(start -0.7874 0.4064)
			(end -0.7874 -0.4064)
			(stroke
				(width 0.1524)
				(type default)
			)
			(layer "F.SilkS")
		)
		(fp_line
			(start 0.7874 -0.4064)
			(end 0.7874 0.4064)
			(stroke
				(width 0.1524)
				(type default)
			)
			(layer "F.SilkS")
		)
		(fp_line
			(start 0.7874 0.4064)
			(end -0.7874 0.4064)
			(stroke
				(width 0.1524)
				(type default)
			)
			(layer "F.SilkS")
		)
		(fp_line
			(start -0.67945 -0.305054)
			(end -0.12065 -0.305054)
			(stroke
				(width 0.1)
				(type default)
			)
			(layer "F.Fab")
		)
		(fp_line
			(start -0.67945 0.3048)
			(end -0.67945 -0.305054)
			(stroke
				(width 0.1)
				(type default)
			)
			(layer "F.Fab")
		)
		(fp_line
			(start -0.12065 -0.305054)
			(end -0.12065 -0.2794)
			(stroke
				(width 0.1)
				(type default)
			)
			(layer "F.Fab")
		)
		(fp_line
			(start -0.12065 -0.2794)
			(end 0.12065 -0.2794)
			(stroke
				(width 0.1)
				(type default)
			)
			(layer "F.Fab")
		)
		(fp_line
			(start -0.12065 0.2794)
			(end -0.12065 0.3048)
			(stroke
				(width 0.1)
				(type default)
			)
			(layer "F.Fab")
		)
		(fp_line
			(start -0.12065 0.3048)
			(end -0.67945 0.3048)
			(stroke
				(width 0.1)
				(type default)
			)
			(layer "F.Fab")
		)
		(fp_line
			(start 0.120396 0.2794)
			(end -0.12065 0.2794)
			(stroke
				(width 0.1)
				(type default)
			)
			(layer "F.Fab")
		)
		(fp_line
			(start 0.120396 0.3048)
			(end 0.120396 0.2794)
			(stroke
				(width 0.1)
				(type default)
			)
			(layer "F.Fab")
		)
		(fp_line
			(start 0.12065 -0.3048)
			(end 0.67945 -0.3048)
			(stroke
				(width 0.1)
				(type default)
			)
			(layer "F.Fab")
		)
		(fp_line
			(start 0.12065 -0.2794)
			(end 0.12065 -0.3048)
			(stroke
				(width 0.1)
				(type default)
			)
			(layer "F.Fab")
		)
		(fp_line
			(start 0.67945 -0.3048)
			(end 0.67945 0.3048)
			(stroke
				(width 0.1)
				(type default)
			)
			(layer "F.Fab")
		)
		(fp_line
			(start 0.67945 0.3048)
			(end 0.120396 0.3048)
			(stroke
				(width 0.1)
				(type default)
			)
			(layer "F.Fab")
		)
		(pad "1" smd circle
			(at -0.40005 0)
			(size 0 0)
			(layers "F.Cu" "F.Mask" "F.Paste")
			(net "FM_JTAG_TCK_MUX_SEL")
		)
		(pad "2" smd circle
			(at 0.40005 0)
			(size 0 0)
			(layers "F.Cu" "F.Mask" "F.Paste")
			(net "GND")
		)
	)
	(footprint ""
		(layer "F.Cu")
		(at 343.776808 -402.371052 -90)
		(property "Reference" "C1552"
			(at 0 0 270)
			(layer "F.SilkS")
			(hide yes)
			(effects
				(font
					(size 1.27 1.27)
				)
			)
		)
		(property "Value" ""
			(at 0 0 270)
			(layer "F.Fab")
			(effects
				(font
					(size 1.27 1.27)
				)
			)
		)
		(duplicate_pad_numbers_are_jumpers no)
		(fp_line
			(start -0.299974 0.150114)
			(end -0.299974 -0.150114)
			(stroke
				(width 0.1)
				(type default)
			)
			(layer "F.Fab")
		)
		(fp_line
			(start 0.299974 0.150114)
			(end -0.299974 0.150114)
			(stroke
				(width 0.1)
				(type default)
			)
			(layer "F.Fab")
		)
		(fp_line
			(start -0.299974 -0.150114)
			(end 0.299974 -0.150114)
			(stroke
				(width 0.1)
				(type default)
			)
			(layer "F.Fab")
		)
		(fp_line
			(start 0.299974 -0.150114)
			(end 0.299974 0.150114)
			(stroke
				(width 0.1)
				(type default)
			)
			(layer "F.Fab")
		)
		(pad "1" smd rect
			(at -0.2667 0 270)
			(size 0.3048 0.381)
			(layers "F.Cu" "F.Mask" "F.Paste")
			(net "P5E_CPU0_PE4_TX_C_DN<13>")
		)
		(pad "2" smd rect
			(at 0.2667 0 270)
			(size 0.3048 0.381)
			(layers "F.Cu" "F.Mask" "F.Paste")
			(net "P5E_CPU0_PE4_TX_DN<13>")
		)
	)
	(footprint ""
		(layer "F.Cu")
		(at 120.066054 -357.11638 90)
		(property "Reference" "PR1340"
			(at 0 0 90)
			(layer "F.SilkS")
			(hide yes)
			(effects
				(font
					(size 1.27 1.27)
				)
			)
		)
		(property "Value" ""
			(at 0 0 90)
			(layer "F.Fab")
			(effects
				(font
					(size 1.27 1.27)
				)
			)
		)
		(duplicate_pad_numbers_are_jumpers no)
		(fp_line
			(start 0.7874 -0.4064)
			(end 0.7874 0.4064)
			(stroke
				(width 0.1524)
				(type default)
			)
			(layer "F.SilkS")
		)
		(fp_line
			(start -0.7874 -0.4064)
			(end 0.7874 -0.4064)
			(stroke
				(width 0.1524)
				(type default)
			)
			(layer "F.SilkS")
		)
		(fp_line
			(start 0.7874 0.4064)
			(end -0.7874 0.4064)
			(stroke
				(width 0.1524)
				(type default)
			)
			(layer "F.SilkS")
		)
		(fp_line
			(start -0.7874 0.4064)
			(end -0.7874 -0.4064)
			(stroke
				(width 0.1524)
				(type default)
			)
			(layer "F.SilkS")
		)
		(fp_line
			(start -0.12065 -0.305054)
			(end -0.12065 -0.2794)
			(stroke
				(width 0.1)
				(type default)
			)
			(layer "F.Fab")
		)
		(fp_line
			(start -0.67945 -0.305054)
			(end -0.12065 -0.305054)
			(stroke
				(width 0.1)
				(type default)
			)
			(layer "F.Fab")
		)
		(fp_line
			(start 0.67945 -0.3048)
			(end 0.67945 0.3048)
			(stroke
				(width 0.1)
				(type default)
			)
			(layer "F.Fab")
		)
		(fp_line
			(start 0.12065 -0.3048)
			(end 0.67945 -0.3048)
			(stroke
				(width 0.1)
				(type default)
			)
			(layer "F.Fab")
		)
		(fp_line
			(start 0.12065 -0.2794)
			(end 0.12065 -0.3048)
			(stroke
				(width 0.1)
				(type default)
			)
			(layer "F.Fab")
		)
		(fp_line
			(start -0.12065 -0.2794)
			(end 0.12065 -0.2794)
			(stroke
				(width 0.1)
				(type default)
			)
			(layer "F.Fab")
		)
		(fp_line
			(start 0.120396 0.2794)
			(end -0.12065 0.2794)
			(stroke
				(width 0.1)
				(type default)
			)
			(layer "F.Fab")
		)
		(fp_line
			(start -0.12065 0.2794)
			(end -0.12065 0.3048)
			(stroke
				(width 0.1)
				(type default)
			)
			(layer "F.Fab")
		)
		(fp_line
			(start 0.67945 0.3048)
			(end 0.120396 0.3048)
			(stroke
				(width 0.1)
				(type default)
			)
			(layer "F.Fab")
		)
		(fp_line
			(start 0.120396 0.3048)
			(end 0.120396 0.2794)
			(stroke
				(width 0.1)
				(type default)
			)
			(layer "F.Fab")
		)
		(fp_line
			(start -0.12065 0.3048)
			(end -0.67945 0.3048)
			(stroke
				(width 0.1)
				(type default)
			)
			(layer "F.Fab")
		)
		(fp_line
			(start -0.67945 0.3048)
			(end -0.67945 -0.305054)
			(stroke
				(width 0.1)
				(type default)
			)
			(layer "F.Fab")
		)
		(pad "1" smd circle
			(at -0.40005 0 90)
			(size 0 0)
			(layers "F.Cu" "F.Mask" "F.Paste")
			(net "PVPP_HBM_CPU1_FB")
		)
		(pad "2" smd circle
			(at 0.40005 0 90)
			(size 0 0)
			(layers "F.Cu" "F.Mask" "F.Paste")
			(net "SH_PVPP_HBM_CPU1_P")
		)
	)
	(footprint ""
		(layer "F.Cu")
		(at 402.02993 -402.371052 -90)
		(property "Reference" "C955"
			(at 0 0 270)
			(layer "F.SilkS")
			(hide yes)
			(effects
				(font
					(size 1.27 1.27)
				)
			)
		)
		(property "Value" ""
			(at 0 0 270)
			(layer "F.Fab")
			(effects
				(font
					(size 1.27 1.27)
				)
			)
		)
		(duplicate_pad_numbers_are_jumpers no)
		(fp_line
			(start -0.299974 0.150114)
			(end -0.299974 -0.150114)
			(stroke
				(width 0.1)
				(type default)
			)
			(layer "F.Fab")
		)
		(fp_line
			(start 0.299974 0.150114)
			(end -0.299974 0.150114)
			(stroke
				(width 0.1)
				(type default)
			)
			(layer "F.Fab")
		)
		(fp_line
			(start -0.299974 -0.150114)
			(end 0.299974 -0.150114)
			(stroke
				(width 0.1)
				(type default)
			)
			(layer "F.Fab")
		)
		(fp_line
			(start 0.299974 -0.150114)
			(end 0.299974 0.150114)
			(stroke
				(width 0.1)
				(type default)
			)
			(layer "F.Fab")
		)
		(pad "1" smd rect
			(at -0.2667 0 270)
			(size 0.3048 0.381)
			(layers "F.Cu" "F.Mask" "F.Paste")
			(net "P5E_CPU0_PE2_TX_C_DP<5>")
		)
		(pad "2" smd rect
			(at 0.2667 0 270)
			(size 0.3048 0.381)
			(layers "F.Cu" "F.Mask" "F.Paste")
			(net "P5E_CPU0_PE2_TX_DP<5>")
		)
	)
	(footprint ""
		(layer "F.Cu")
		(at 124.931424 -361.704382 180)
		(property "Reference" "PC1262"
			(at 0 0 180)
			(layer "F.SilkS")
			(hide yes)
			(effects
				(font
					(size 1.27 1.27)
				)
			)
		)
		(property "Value" ""
			(at 0 0 180)
			(layer "F.Fab")
			(effects
				(font
					(size 1.27 1.27)
				)
			)
		)
		(duplicate_pad_numbers_are_jumpers no)
		(fp_line
			(start 0.7874 0.4064)
			(end -0.7874 0.4064)
			(stroke
				(width 0.1524)
				(type default)
			)
			(layer "F.SilkS")
		)
		(fp_line
			(start 0.7874 -0.4064)
			(end 0.7874 0.4064)
			(stroke
				(width 0.1524)
				(type default)
			)
			(layer "F.SilkS")
		)
		(fp_line
			(start -0.7874 0.4064)
			(end -0.7874 -0.4064)
			(stroke
				(width 0.1524)
				(type default)
			)
			(layer "F.SilkS")
		)
		(fp_line
			(start -0.7874 -0.4064)
			(end 0.7874 -0.4064)
			(stroke
				(width 0.1524)
				(type default)
			)
			(layer "F.SilkS")
		)
		(fp_line
			(start 0.67945 0.3048)
			(end 0.120396 0.3048)
			(stroke
				(width 0.1)
				(type default)
			)
			(layer "F.Fab")
		)
		(fp_line
			(start 0.67945 -0.3048)
			(end 0.67945 0.3048)
			(stroke
				(width 0.1)
				(type default)
			)
			(layer "F.Fab")
		)
		(fp_line
			(start 0.12065 -0.2794)
			(end 0.12065 -0.3048)
			(stroke
				(width 0.1)
				(type default)
			)
			(layer "F.Fab")
		)
		(fp_line
			(start 0.12065 -0.3048)
			(end 0.67945 -0.3048)
			(stroke
				(width 0.1)
				(type default)
			)
			(layer "F.Fab")
		)
		(fp_line
			(start 0.120396 0.3048)
			(end 0.120396 0.2794)
			(stroke
				(width 0.1)
				(type default)
			)
			(layer "F.Fab")
		)
		(fp_line
			(start 0.120396 0.2794)
			(end -0.12065 0.2794)
			(stroke
				(width 0.1)
				(type default)
			)
			(layer "F.Fab")
		)
		(fp_line
			(start -0.12065 0.3048)
			(end -0.67945 0.3048)
			(stroke
				(width 0.1)
				(type default)
			)
			(layer "F.Fab")
		)
		(fp_line
			(start -0.12065 0.2794)
			(end -0.12065 0.3048)
			(stroke
				(width 0.1)
				(type default)
			)
			(layer "F.Fab")
		)
		(fp_line
			(start -0.12065 -0.2794)
			(end 0.12065 -0.2794)
			(stroke
				(width 0.1)
				(type default)
			)
			(layer "F.Fab")
		)
		(fp_line
			(start -0.12065 -0.305054)
			(end -0.12065 -0.2794)
			(stroke
				(width 0.1)
				(type default)
			)
			(layer "F.Fab")
		)
		(fp_line
			(start -0.67945 0.3048)
			(end -0.67945 -0.305054)
			(stroke
				(width 0.1)
				(type default)
			)
			(layer "F.Fab")
		)
		(fp_line
			(start -0.67945 -0.305054)
			(end -0.12065 -0.305054)
			(stroke
				(width 0.1)
				(type default)
			)
			(layer "F.Fab")
		)
		(pad "1" smd circle
			(at -0.40005 0 180)
			(size 0 0)
			(layers "F.Cu" "F.Mask" "F.Paste")
			(net "SW_P12V_PVCCIN_CPU1_FLT")
		)
		(pad "2" smd circle
			(at 0.40005 0 180)
			(size 0 0)
			(layers "F.Cu" "F.Mask" "F.Paste")
			(net "GND")
		)
	)
	(footprint ""
		(layer "F.Cu")
		(at 31.937452 -161.582862 180)
		(property "Reference" "PR203"
			(at 0 0 180)
			(layer "F.SilkS")
			(hide yes)
			(effects
				(font
					(size 1.27 1.27)
				)
			)
		)
		(property "Value" ""
			(at 0 0 180)
			(layer "F.Fab")
			(effects
				(font
					(size 1.27 1.27)
				)
			)
		)
		(duplicate_pad_numbers_are_jumpers no)
		(fp_line
			(start 0.7874 0.4064)
			(end -0.7874 0.4064)
			(stroke
				(width 0.1524)
				(type default)
			)
			(layer "F.SilkS")
		)
		(fp_line
			(start 0.7874 -0.4064)
			(end 0.7874 0.4064)
			(stroke
				(width 0.1524)
				(type default)
			)
			(layer "F.SilkS")
		)
		(fp_line
			(start -0.7874 0.4064)
			(end -0.7874 -0.4064)
			(stroke
				(width 0.1524)
				(type default)
			)
			(layer "F.SilkS")
		)
		(fp_line
			(start -0.7874 -0.4064)
			(end 0.7874 -0.4064)
			(stroke
				(width 0.1524)
				(type default)
			)
			(layer "F.SilkS")
		)
		(fp_line
			(start 0.67945 0.3048)
			(end 0.120396 0.3048)
			(stroke
				(width 0.1)
				(type default)
			)
			(layer "F.Fab")
		)
		(fp_line
			(start 0.67945 -0.3048)
			(end 0.67945 0.3048)
			(stroke
				(width 0.1)
				(type default)
			)
			(layer "F.Fab")
		)
		(fp_line
			(start 0.12065 -0.2794)
			(end 0.12065 -0.3048)
			(stroke
				(width 0.1)
				(type default)
			)
			(layer "F.Fab")
		)
		(fp_line
			(start 0.12065 -0.3048)
			(end 0.67945 -0.3048)
			(stroke
				(width 0.1)
				(type default)
			)
			(layer "F.Fab")
		)
		(fp_line
			(start 0.120396 0.3048)
			(end 0.120396 0.2794)
			(stroke
				(width 0.1)
				(type default)
			)
			(layer "F.Fab")
		)
		(fp_line
			(start 0.120396 0.2794)
			(end -0.12065 0.2794)
			(stroke
				(width 0.1)
				(type default)
			)
			(layer "F.Fab")
		)
		(fp_line
			(start -0.12065 0.3048)
			(end -0.67945 0.3048)
			(stroke
				(width 0.1)
				(type default)
			)
			(layer "F.Fab")
		)
		(fp_line
			(start -0.12065 0.2794)
			(end -0.12065 0.3048)
			(stroke
				(width 0.1)
				(type default)
			)
			(layer "F.Fab")
		)
		(fp_line
			(start -0.12065 -0.2794)
			(end 0.12065 -0.2794)
			(stroke
				(width 0.1)
				(type default)
			)
			(layer "F.Fab")
		)
		(fp_line
			(start -0.12065 -0.305054)
			(end -0.12065 -0.2794)
			(stroke
				(width 0.1)
				(type default)
			)
			(layer "F.Fab")
		)
		(fp_line
			(start -0.67945 0.3048)
			(end -0.67945 -0.305054)
			(stroke
				(width 0.1)
				(type default)
			)
			(layer "F.Fab")
		)
		(fp_line
			(start -0.67945 -0.305054)
			(end -0.12065 -0.305054)
			(stroke
				(width 0.1)
				(type default)
			)
			(layer "F.Fab")
		)
		(pad "1" smd circle
			(at -0.40005 0 180)
			(size 0 0)
			(layers "F.Cu" "F.Mask" "F.Paste")
			(net "GND")
		)
		(pad "2" smd circle
			(at 0.40005 0 180)
			(size 0 0)
			(layers "F.Cu" "F.Mask" "F.Paste")
			(net "PVCCD_HV_CPU1_ADDR")
		)
	)
	(footprint ""
		(layer "F.Cu")
		(at 323.248528 -402.371052 -90)
		(property "Reference" "C1567"
			(at 0 0 270)
			(layer "F.SilkS")
			(hide yes)
			(effects
				(font
					(size 1.27 1.27)
				)
			)
		)
		(property "Value" ""
			(at 0 0 270)
			(layer "F.Fab")
			(effects
				(font
					(size 1.27 1.27)
				)
			)
		)
		(duplicate_pad_numbers_are_jumpers no)
		(fp_line
			(start -0.299974 0.150114)
			(end -0.299974 -0.150114)
			(stroke
				(width 0.1)
				(type default)
			)
			(layer "F.Fab")
		)
		(fp_line
			(start 0.299974 0.150114)
			(end -0.299974 0.150114)
			(stroke
				(width 0.1)
				(type default)
			)
			(layer "F.Fab")
		)
		(fp_line
			(start -0.299974 -0.150114)
			(end 0.299974 -0.150114)
			(stroke
				(width 0.1)
				(type default)
			)
			(layer "F.Fab")
		)
		(fp_line
			(start 0.299974 -0.150114)
			(end 0.299974 0.150114)
			(stroke
				(width 0.1)
				(type default)
			)
			(layer "F.Fab")
		)
		(pad "1" smd rect
			(at -0.2667 0 270)
			(size 0.3048 0.381)
			(layers "F.Cu" "F.Mask" "F.Paste")
			(net "P5E_CPU0_PE4_TX_C_DP<6>")
		)
		(pad "2" smd rect
			(at 0.2667 0 270)
			(size 0.3048 0.381)
			(layers "F.Cu" "F.Mask" "F.Paste")
			(net "P5E_CPU0_PE4_TX_DP<6>")
		)
	)
	(footprint ""
		(layer "F.Cu")
		(at 131.466844 -129.913126 180)
		(property "Reference" "R652"
			(at 0 0 180)
			(layer "F.SilkS")
			(hide yes)
			(effects
				(font
					(size 1.27 1.27)
				)
			)
		)
		(property "Value" ""
			(at 0 0 180)
			(layer "F.Fab")
			(effects
				(font
					(size 1.27 1.27)
				)
			)
		)
		(duplicate_pad_numbers_are_jumpers no)
		(fp_line
			(start 0.7874 0.4064)
			(end -0.7874 0.4064)
			(stroke
				(width 0.1524)
				(type default)
			)
			(layer "F.SilkS")
		)
		(fp_line
			(start 0.7874 -0.4064)
			(end 0.7874 0.4064)
			(stroke
				(width 0.1524)
				(type default)
			)
			(layer "F.SilkS")
		)
		(fp_line
			(start -0.7874 0.4064)
			(end -0.7874 -0.4064)
			(stroke
				(width 0.1524)
				(type default)
			)
			(layer "F.SilkS")
		)
		(fp_line
			(start -0.7874 -0.4064)
			(end 0.7874 -0.4064)
			(stroke
				(width 0.1524)
				(type default)
			)
			(layer "F.SilkS")
		)
		(fp_line
			(start 0.67945 0.3048)
			(end 0.120396 0.3048)
			(stroke
				(width 0.1)
				(type default)
			)
			(layer "F.Fab")
		)
		(fp_line
			(start 0.67945 -0.3048)
			(end 0.67945 0.3048)
			(stroke
				(width 0.1)
				(type default)
			)
			(layer "F.Fab")
		)
		(fp_line
			(start 0.12065 -0.2794)
			(end 0.12065 -0.3048)
			(stroke
				(width 0.1)
				(type default)
			)
			(layer "F.Fab")
		)
		(fp_line
			(start 0.12065 -0.3048)
			(end 0.67945 -0.3048)
			(stroke
				(width 0.1)
				(type default)
			)
			(layer "F.Fab")
		)
		(fp_line
			(start 0.120396 0.3048)
			(end 0.120396 0.2794)
			(stroke
				(width 0.1)
				(type default)
			)
			(layer "F.Fab")
		)
		(fp_line
			(start 0.120396 0.2794)
			(end -0.12065 0.2794)
			(stroke
				(width 0.1)
				(type default)
			)
			(layer "F.Fab")
		)
		(fp_line
			(start -0.12065 0.3048)
			(end -0.67945 0.3048)
			(stroke
				(width 0.1)
				(type default)
			)
			(layer "F.Fab")
		)
		(fp_line
			(start -0.12065 0.2794)
			(end -0.12065 0.3048)
			(stroke
				(width 0.1)
				(type default)
			)
			(layer "F.Fab")
		)
		(fp_line
			(start -0.12065 -0.2794)
			(end 0.12065 -0.2794)
			(stroke
				(width 0.1)
				(type default)
			)
			(layer "F.Fab")
		)
		(fp_line
			(start -0.12065 -0.305054)
			(end -0.12065 -0.2794)
			(stroke
				(width 0.1)
				(type default)
			)
			(layer "F.Fab")
		)
		(fp_line
			(start -0.67945 0.3048)
			(end -0.67945 -0.305054)
			(stroke
				(width 0.1)
				(type default)
			)
			(layer "F.Fab")
		)
		(fp_line
			(start -0.67945 -0.305054)
			(end -0.12065 -0.305054)
			(stroke
				(width 0.1)
				(type default)
			)
			(layer "F.Fab")
		)
		(pad "1" smd circle
			(at -0.40005 0 180)
			(size 0 0)
			(layers "F.Cu" "F.Mask" "F.Paste")
			(net "P3V3_AUX")
		)
		(pad "2" smd circle
			(at 0.40005 0 180)
			(size 0 0)
			(layers "F.Cu" "F.Mask" "F.Paste")
			(net "SMB_FRU_3V3AUX_SDA")
		)
	)
	(footprint ""
		(layer "F.Cu")
		(at 203.326492 -105.315004 -90)
		(property "Reference" "R1840"
			(at 0 0 270)
			(layer "F.SilkS")
			(hide yes)
			(effects
				(font
					(size 1.27 1.27)
				)
			)
		)
		(property "Value" ""
			(at 0 0 270)
			(layer "F.Fab")
			(effects
				(font
					(size 1.27 1.27)
				)
			)
		)
		(duplicate_pad_numbers_are_jumpers no)
		(fp_line
			(start -0.7874 0.4064)
			(end -0.7874 -0.4064)
			(stroke
				(width 0.1524)
				(type default)
			)
			(layer "F.SilkS")
		)
		(fp_line
			(start 0.7874 0.4064)
			(end -0.7874 0.4064)
			(stroke
				(width 0.1524)
				(type default)
			)
			(layer "F.SilkS")
		)
		(fp_line
			(start -0.7874 -0.4064)
			(end 0.7874 -0.4064)
			(stroke
				(width 0.1524)
				(type default)
			)
			(layer "F.SilkS")
		)
		(fp_line
			(start 0.7874 -0.4064)
			(end 0.7874 0.4064)
			(stroke
				(width 0.1524)
				(type default)
			)
			(layer "F.SilkS")
		)
		(fp_line
			(start -0.67945 0.3048)
			(end -0.67945 -0.305054)
			(stroke
				(width 0.1)
				(type default)
			)
			(layer "F.Fab")
		)
		(fp_line
			(start -0.12065 0.3048)
			(end -0.67945 0.3048)
			(stroke
				(width 0.1)
				(type default)
			)
			(layer "F.Fab")
		)
		(fp_line
			(start 0.120396 0.3048)
			(end 0.120396 0.2794)
			(stroke
				(width 0.1)
				(type default)
			)
			(layer "F.Fab")
		)
		(fp_line
			(start 0.67945 0.3048)
			(end 0.120396 0.3048)
			(stroke
				(width 0.1)
				(type default)
			)
			(layer "F.Fab")
		)
		(fp_line
			(start -0.12065 0.2794)
			(end -0.12065 0.3048)
			(stroke
				(width 0.1)
				(type default)
			)
			(layer "F.Fab")
		)
		(fp_line
			(start 0.120396 0.2794)
			(end -0.12065 0.2794)
			(stroke
				(width 0.1)
				(type default)
			)
			(layer "F.Fab")
		)
		(fp_line
			(start -0.12065 -0.2794)
			(end 0.12065 -0.2794)
			(stroke
				(width 0.1)
				(type default)
			)
			(layer "F.Fab")
		)
		(fp_line
			(start 0.12065 -0.2794)
			(end 0.12065 -0.3048)
			(stroke
				(width 0.1)
				(type default)
			)
			(layer "F.Fab")
		)
		(fp_line
			(start 0.12065 -0.3048)
			(end 0.67945 -0.3048)
			(stroke
				(width 0.1)
				(type default)
			)
			(layer "F.Fab")
		)
		(fp_line
			(start 0.67945 -0.3048)
			(end 0.67945 0.3048)
			(stroke
				(width 0.1)
				(type default)
			)
			(layer "F.Fab")
		)
		(fp_line
			(start -0.67945 -0.305054)
			(end -0.12065 -0.305054)
			(stroke
				(width 0.1)
				(type default)
			)
			(layer "F.Fab")
		)
		(fp_line
			(start -0.12065 -0.305054)
			(end -0.12065 -0.2794)
			(stroke
				(width 0.1)
				(type default)
			)
			(layer "F.Fab")
		)
		(pad "1" smd circle
			(at -0.40005 0 270)
			(size 0 0)
			(layers "F.Cu" "F.Mask" "F.Paste")
			(net "RST_PFR_OVR_SRTC")
		)
		(pad "2" smd circle
			(at 0.40005 0 270)
			(size 0 0)
			(layers "F.Cu" "F.Mask" "F.Paste")
			(net "RST_SRTCRST_N")
		)
	)
	(footprint ""
		(layer "F.Cu")
		(at 483.210108 -427.547024 180)
		(property "Reference" "DB8"
			(at -2.931668 -0.465836 90)
			(unlocked yes)
			(layer "F.SilkS")
			(effects
				(font
					(size 0.7874 0.5842)
					(thickness 0.1524)
				)
				(justify left)
			)
		)
		(property "Value" ""
			(at 0 0 180)
			(layer "F.Fab")
			(effects
				(font
					(size 1.27 1.27)
				)
			)
		)
		(duplicate_pad_numbers_are_jumpers no)
		(fp_line
			(start 2.71653 -3.151378)
			(end 0 4.011168)
			(stroke
				(width 0.1524)
				(type default)
			)
			(layer "F.SilkS")
		)
		(fp_line
			(start 0 4.011168)
			(end -3.330702 -4.771136)
			(stroke
				(width 0.1524)
				(type default)
			)
			(layer "F.SilkS")
		)
		(fp_line
			(start -3.330702 -4.771136)
			(end 3.330702 -4.771136)
			(stroke
				(width 0.1524)
				(type default)
			)
			(layer "F.SilkS")
		)
		(fp_line
			(start 3.330702 -4.771136)
			(end 0 4.011168)
			(stroke
				(width 0.1)
				(type default)
			)
			(layer "F.Fab")
		)
		(fp_line
			(start 0 4.011168)
			(end -3.330702 -4.771136)
			(stroke
				(width 0.1)
				(type default)
			)
			(layer "F.Fab")
		)
		(fp_line
			(start -3.330702 -4.771136)
			(end 3.330702 -4.771136)
			(stroke
				(width 0.1)
				(type default)
			)
			(layer "F.Fab")
		)
		(pad "1" thru_hole circle
			(at 0 0 180)
			(size 2.159 2.159)
			(drill 1.7018)
			(layers "*.Cu" "*.Mask")
			(remove_unused_layers no)
			(net "T1_GND")
			(clearance 0.0254)
			(thermal_gap 0.0254)
		)
		(pad "2" thru_hole circle
			(at -1.27 -3.348736 180)
			(size 2.159 2.159)
			(drill 1.7018)
			(layers "*.Cu" "*.Mask")
			(remove_unused_layers no)
			(net "TDR_SE_50_OHM_IN1")
			(clearance 0.0254)
			(thermal_gap 0.0254)
		)
		(pad "3" thru_hole circle
			(at 1.27 -3.348736 180)
			(size 2.159 2.159)
			(drill 1.7018)
			(layers "*.Cu" "*.Mask")
			(remove_unused_layers no)
			(net "TDR_SE_50_OHM_IN1")
			(clearance 0.0254)
			(thermal_gap 0.0254)
		)
	)
	(footprint ""
		(layer "F.Cu")
		(at 44.905422 -401.567396 90)
		(property "Reference" "R2656"
			(at 0 0 90)
			(layer "F.SilkS")
			(hide yes)
			(effects
				(font
					(size 1.27 1.27)
				)
			)
		)
		(property "Value" ""
			(at 0 0 90)
			(layer "F.Fab")
			(effects
				(font
					(size 1.27 1.27)
				)
			)
		)
		(duplicate_pad_numbers_are_jumpers no)
		(fp_line
			(start 0.7874 -0.4064)
			(end 0.7874 0.4064)
			(stroke
				(width 0.1524)
				(type default)
			)
			(layer "F.SilkS")
		)
		(fp_line
			(start -0.7874 -0.4064)
			(end 0.7874 -0.4064)
			(stroke
				(width 0.1524)
				(type default)
			)
			(layer "F.SilkS")
		)
		(fp_line
			(start 0.7874 0.4064)
			(end -0.7874 0.4064)
			(stroke
				(width 0.1524)
				(type default)
			)
			(layer "F.SilkS")
		)
		(fp_line
			(start -0.7874 0.4064)
			(end -0.7874 -0.4064)
			(stroke
				(width 0.1524)
				(type default)
			)
			(layer "F.SilkS")
		)
		(fp_line
			(start -0.12065 -0.305054)
			(end -0.12065 -0.2794)
			(stroke
				(width 0.1)
				(type default)
			)
			(layer "F.Fab")
		)
		(fp_line
			(start -0.67945 -0.305054)
			(end -0.12065 -0.305054)
			(stroke
				(width 0.1)
				(type default)
			)
			(layer "F.Fab")
		)
		(fp_line
			(start 0.67945 -0.3048)
			(end 0.67945 0.3048)
			(stroke
				(width 0.1)
				(type default)
			)
			(layer "F.Fab")
		)
		(fp_line
			(start 0.12065 -0.3048)
			(end 0.67945 -0.3048)
			(stroke
				(width 0.1)
				(type default)
			)
			(layer "F.Fab")
		)
		(fp_line
			(start 0.12065 -0.2794)
			(end 0.12065 -0.3048)
			(stroke
				(width 0.1)
				(type default)
			)
			(layer "F.Fab")
		)
		(fp_line
			(start -0.12065 -0.2794)
			(end 0.12065 -0.2794)
			(stroke
				(width 0.1)
				(type default)
			)
			(layer "F.Fab")
		)
		(fp_line
			(start 0.120396 0.2794)
			(end -0.12065 0.2794)
			(stroke
				(width 0.1)
				(type default)
			)
			(layer "F.Fab")
		)
		(fp_line
			(start -0.12065 0.2794)
			(end -0.12065 0.3048)
			(stroke
				(width 0.1)
				(type default)
			)
			(layer "F.Fab")
		)
		(fp_line
			(start 0.67945 0.3048)
			(end 0.120396 0.3048)
			(stroke
				(width 0.1)
				(type default)
			)
			(layer "F.Fab")
		)
		(fp_line
			(start 0.120396 0.3048)
			(end 0.120396 0.2794)
			(stroke
				(width 0.1)
				(type default)
			)
			(layer "F.Fab")
		)
		(fp_line
			(start -0.12065 0.3048)
			(end -0.67945 0.3048)
			(stroke
				(width 0.1)
				(type default)
			)
			(layer "F.Fab")
		)
		(fp_line
			(start -0.67945 0.3048)
			(end -0.67945 -0.305054)
			(stroke
				(width 0.1)
				(type default)
			)
			(layer "F.Fab")
		)
		(pad "1" smd circle
			(at -0.40005 0 90)
			(size 0 0)
			(layers "F.Cu" "F.Mask" "F.Paste")
			(net "HGX_DETECT_N_ISO")
		)
		(pad "2" smd circle
			(at 0.40005 0 90)
			(size 0 0)
			(layers "F.Cu" "F.Mask" "F.Paste")
			(net "GND")
		)
	)
	(footprint ""
		(layer "F.Cu")
		(at 139.02182 -92.644468 -90)
		(property "Reference" "R4050"
			(at 0 0 270)
			(layer "F.SilkS")
			(hide yes)
			(effects
				(font
					(size 1.27 1.27)
				)
			)
		)
		(property "Value" ""
			(at 0 0 270)
			(layer "F.Fab")
			(effects
				(font
					(size 1.27 1.27)
				)
			)
		)
		(duplicate_pad_numbers_are_jumpers no)
		(fp_line
			(start -0.7874 0.4064)
			(end -0.7874 -0.4064)
			(stroke
				(width 0.1524)
				(type default)
			)
			(layer "F.SilkS")
		)
		(fp_line
			(start 0.7874 0.4064)
			(end -0.7874 0.4064)
			(stroke
				(width 0.1524)
				(type default)
			)
			(layer "F.SilkS")
		)
		(fp_line
			(start -0.7874 -0.4064)
			(end 0.7874 -0.4064)
			(stroke
				(width 0.1524)
				(type default)
			)
			(layer "F.SilkS")
		)
		(fp_line
			(start 0.7874 -0.4064)
			(end 0.7874 0.4064)
			(stroke
				(width 0.1524)
				(type default)
			)
			(layer "F.SilkS")
		)
		(fp_line
			(start -0.67945 0.3048)
			(end -0.67945 -0.305054)
			(stroke
				(width 0.1)
				(type default)
			)
			(layer "F.Fab")
		)
		(fp_line
			(start -0.12065 0.3048)
			(end -0.67945 0.3048)
			(stroke
				(width 0.1)
				(type default)
			)
			(layer "F.Fab")
		)
		(fp_line
			(start 0.120396 0.3048)
			(end 0.120396 0.2794)
			(stroke
				(width 0.1)
				(type default)
			)
			(layer "F.Fab")
		)
		(fp_line
			(start 0.67945 0.3048)
			(end 0.120396 0.3048)
			(stroke
				(width 0.1)
				(type default)
			)
			(layer "F.Fab")
		)
		(fp_line
			(start -0.12065 0.2794)
			(end -0.12065 0.3048)
			(stroke
				(width 0.1)
				(type default)
			)
			(layer "F.Fab")
		)
		(fp_line
			(start 0.120396 0.2794)
			(end -0.12065 0.2794)
			(stroke
				(width 0.1)
				(type default)
			)
			(layer "F.Fab")
		)
		(fp_line
			(start -0.12065 -0.2794)
			(end 0.12065 -0.2794)
			(stroke
				(width 0.1)
				(type default)
			)
			(layer "F.Fab")
		)
		(fp_line
			(start 0.12065 -0.2794)
			(end 0.12065 -0.3048)
			(stroke
				(width 0.1)
				(type default)
			)
			(layer "F.Fab")
		)
		(fp_line
			(start 0.12065 -0.3048)
			(end 0.67945 -0.3048)
			(stroke
				(width 0.1)
				(type default)
			)
			(layer "F.Fab")
		)
		(fp_line
			(start 0.67945 -0.3048)
			(end 0.67945 0.3048)
			(stroke
				(width 0.1)
				(type default)
			)
			(layer "F.Fab")
		)
		(fp_line
			(start -0.67945 -0.305054)
			(end -0.12065 -0.305054)
			(stroke
				(width 0.1)
				(type default)
			)
			(layer "F.Fab")
		)
		(fp_line
			(start -0.12065 -0.305054)
			(end -0.12065 -0.2794)
			(stroke
				(width 0.1)
				(type default)
			)
			(layer "F.Fab")
		)
		(pad "1" smd circle
			(at -0.40005 0 270)
			(size 0 0)
			(layers "F.Cu" "F.Mask" "F.Paste")
			(net "H_CPU_ERR0_LVC2_R_N")
		)
		(pad "2" smd circle
			(at 0.40005 0 270)
			(size 0 0)
			(layers "F.Cu" "F.Mask" "F.Paste")
			(net "H_CPU_ERR0_LVC2_N")
		)
	)
	(footprint ""
		(layer "F.Cu")
		(at 273.091656 -129.44983)
		(property "Reference" "C2337"
			(at 0 0 0)
			(layer "F.SilkS")
			(hide yes)
			(effects
				(font
					(size 1.27 1.27)
				)
			)
		)
		(property "Value" ""
			(at 0 0 0)
			(layer "F.Fab")
			(effects
				(font
					(size 1.27 1.27)
				)
			)
		)
		(duplicate_pad_numbers_are_jumpers no)
		(fp_line
			(start -0.7874 -0.4064)
			(end 0.7874 -0.4064)
			(stroke
				(width 0.1524)
				(type default)
			)
			(layer "F.SilkS")
		)
		(fp_line
			(start -0.7874 0.4064)
			(end -0.7874 -0.4064)
			(stroke
				(width 0.1524)
				(type default)
			)
			(layer "F.SilkS")
		)
		(fp_line
			(start 0.7874 -0.4064)
			(end 0.7874 0.4064)
			(stroke
				(width 0.1524)
				(type default)
			)
			(layer "F.SilkS")
		)
		(fp_line
			(start 0.7874 0.4064)
			(end -0.7874 0.4064)
			(stroke
				(width 0.1524)
				(type default)
			)
			(layer "F.SilkS")
		)
		(fp_line
			(start -0.67945 -0.305054)
			(end -0.12065 -0.305054)
			(stroke
				(width 0.1)
				(type default)
			)
			(layer "F.Fab")
		)
		(fp_line
			(start -0.67945 0.3048)
			(end -0.67945 -0.305054)
			(stroke
				(width 0.1)
				(type default)
			)
			(layer "F.Fab")
		)
		(fp_line
			(start -0.12065 -0.305054)
			(end -0.12065 -0.2794)
			(stroke
				(width 0.1)
				(type default)
			)
			(layer "F.Fab")
		)
		(fp_line
			(start -0.12065 -0.2794)
			(end 0.12065 -0.2794)
			(stroke
				(width 0.1)
				(type default)
			)
			(layer "F.Fab")
		)
		(fp_line
			(start -0.12065 0.2794)
			(end -0.12065 0.3048)
			(stroke
				(width 0.1)
				(type default)
			)
			(layer "F.Fab")
		)
		(fp_line
			(start -0.12065 0.3048)
			(end -0.67945 0.3048)
			(stroke
				(width 0.1)
				(type default)
			)
			(layer "F.Fab")
		)
		(fp_line
			(start 0.120396 0.2794)
			(end -0.12065 0.2794)
			(stroke
				(width 0.1)
				(type default)
			)
			(layer "F.Fab")
		)
		(fp_line
			(start 0.120396 0.3048)
			(end 0.120396 0.2794)
			(stroke
				(width 0.1)
				(type default)
			)
			(layer "F.Fab")
		)
		(fp_line
			(start 0.12065 -0.3048)
			(end 0.67945 -0.3048)
			(stroke
				(width 0.1)
				(type default)
			)
			(layer "F.Fab")
		)
		(fp_line
			(start 0.12065 -0.2794)
			(end 0.12065 -0.3048)
			(stroke
				(width 0.1)
				(type default)
			)
			(layer "F.Fab")
		)
		(fp_line
			(start 0.67945 -0.3048)
			(end 0.67945 0.3048)
			(stroke
				(width 0.1)
				(type default)
			)
			(layer "F.Fab")
		)
		(fp_line
			(start 0.67945 0.3048)
			(end 0.120396 0.3048)
			(stroke
				(width 0.1)
				(type default)
			)
			(layer "F.Fab")
		)
		(pad "1" smd circle
			(at -0.40005 0)
			(size 0 0)
			(layers "F.Cu" "F.Mask" "F.Paste")
			(net "P3V3_AUX")
		)
		(pad "2" smd circle
			(at 0.40005 0)
			(size 0 0)
			(layers "F.Cu" "F.Mask" "F.Paste")
			(net "GND")
		)
	)
	(footprint ""
		(layer "F.Cu")
		(at 97.338896 -344.029284 90)
		(property "Reference" "PC579"
			(at 0 0 90)
			(layer "F.SilkS")
			(hide yes)
			(effects
				(font
					(size 1.27 1.27)
				)
			)
		)
		(property "Value" ""
			(at 0 0 90)
			(layer "F.Fab")
			(effects
				(font
					(size 1.27 1.27)
				)
			)
		)
		(duplicate_pad_numbers_are_jumpers no)
		(fp_line
			(start -3.400044 1.249934)
			(end 3.400044 1.249934)
			(stroke
				(width 0.1524)
				(type default)
			)
			(layer "F.SilkS")
		)
		(fp_circle
			(center 0 1.249934)
			(end 0 4.649978)
			(stroke
				(width 0.1524)
				(type default)
			)
			(fill no)
			(layer "F.SilkS")
		)
		(fp_poly
			(pts
				(arc
					(start -3.400044 1.249934)
					(mid 0 4.649978)
					(end 3.400044 1.249934)
				)
			)
			(stroke
				(width 0)
				(type default)
			)
			(fill yes)
			(layer "F.SilkS")
		)
		(fp_circle
			(center 0 1.249934)
			(end 0 4.649978)
			(stroke
				(width 0.1)
				(type default)
			)
			(fill no)
			(layer "F.Fab")
		)
		(pad "1" thru_hole rect
			(at 0 0 90)
			(size 1.524 1.524)
			(drill 1.016)
			(layers "*.Cu" "*.Mask")
			(remove_unused_layers no)
			(net "SW_P12V_PVCCIN_CPU1_FLT")
			(clearance 0)
			(padstack
				(mode front_inner_back)
				(layer "Inner"
					(shape circle)
					(size 1.524 1.524)
					(clearance 0)
				)
				(layer "B.Cu"
					(shape rect)
					(size 1.524 1.524)
					(clearance 0)
				)
			)
		)
		(pad "2" thru_hole circle
			(at 0 2.500122 90)
			(size 1.524 1.524)
			(drill 1.016)
			(layers "*.Cu" "*.Mask")
			(remove_unused_layers no)
			(net "GND")
			(clearance 0)
		)
	)
	(footprint ""
		(layer "F.Cu")
		(at 104.3432 -251.375672 90)
		(property "Reference" "C256"
			(at 0 0 90)
			(layer "F.SilkS")
			(hide yes)
			(effects
				(font
					(size 1.27 1.27)
				)
			)
		)
		(property "Value" ""
			(at 0 0 90)
			(layer "F.Fab")
			(effects
				(font
					(size 1.27 1.27)
				)
			)
		)
		(duplicate_pad_numbers_are_jumpers no)
		(fp_line
			(start 0.7874 -0.4064)
			(end 0.7874 0.4064)
			(stroke
				(width 0.1524)
				(type default)
			)
			(layer "F.SilkS")
		)
		(fp_line
			(start -0.7874 -0.4064)
			(end 0.7874 -0.4064)
			(stroke
				(width 0.1524)
				(type default)
			)
			(layer "F.SilkS")
		)
		(fp_line
			(start 0.7874 0.4064)
			(end -0.7874 0.4064)
			(stroke
				(width 0.1524)
				(type default)
			)
			(layer "F.SilkS")
		)
		(fp_line
			(start -0.7874 0.4064)
			(end -0.7874 -0.4064)
			(stroke
				(width 0.1524)
				(type default)
			)
			(layer "F.SilkS")
		)
		(fp_line
			(start -0.12065 -0.305054)
			(end -0.12065 -0.2794)
			(stroke
				(width 0.1)
				(type default)
			)
			(layer "F.Fab")
		)
		(fp_line
			(start -0.67945 -0.305054)
			(end -0.12065 -0.305054)
			(stroke
				(width 0.1)
				(type default)
			)
			(layer "F.Fab")
		)
		(fp_line
			(start 0.67945 -0.3048)
			(end 0.67945 0.3048)
			(stroke
				(width 0.1)
				(type default)
			)
			(layer "F.Fab")
		)
		(fp_line
			(start 0.12065 -0.3048)
			(end 0.67945 -0.3048)
			(stroke
				(width 0.1)
				(type default)
			)
			(layer "F.Fab")
		)
		(fp_line
			(start 0.12065 -0.2794)
			(end 0.12065 -0.3048)
			(stroke
				(width 0.1)
				(type default)
			)
			(layer "F.Fab")
		)
		(fp_line
			(start -0.12065 -0.2794)
			(end 0.12065 -0.2794)
			(stroke
				(width 0.1)
				(type default)
			)
			(layer "F.Fab")
		)
		(fp_line
			(start 0.120396 0.2794)
			(end -0.12065 0.2794)
			(stroke
				(width 0.1)
				(type default)
			)
			(layer "F.Fab")
		)
		(fp_line
			(start -0.12065 0.2794)
			(end -0.12065 0.3048)
			(stroke
				(width 0.1)
				(type default)
			)
			(layer "F.Fab")
		)
		(fp_line
			(start 0.67945 0.3048)
			(end 0.120396 0.3048)
			(stroke
				(width 0.1)
				(type default)
			)
			(layer "F.Fab")
		)
		(fp_line
			(start 0.120396 0.3048)
			(end 0.120396 0.2794)
			(stroke
				(width 0.1)
				(type default)
			)
			(layer "F.Fab")
		)
		(fp_line
			(start -0.12065 0.3048)
			(end -0.67945 0.3048)
			(stroke
				(width 0.1)
				(type default)
			)
			(layer "F.Fab")
		)
		(fp_line
			(start -0.67945 0.3048)
			(end -0.67945 -0.305054)
			(stroke
				(width 0.1)
				(type default)
			)
			(layer "F.Fab")
		)
		(pad "1" smd circle
			(at -0.40005 0 90)
			(size 0 0)
			(layers "F.Cu" "F.Mask" "F.Paste")
			(net "PVCCIN_CPU1")
		)
		(pad "2" smd circle
			(at 0.40005 0 90)
			(size 0 0)
			(layers "F.Cu" "F.Mask" "F.Paste")
			(net "GND")
		)
	)
	(footprint ""
		(layer "F.Cu")
		(at 141.240256 -65.329308)
		(property "Reference" "R2350"
			(at 0 0 0)
			(layer "F.SilkS")
			(hide yes)
			(effects
				(font
					(size 1.27 1.27)
				)
			)
		)
		(property "Value" ""
			(at 0 0 0)
			(layer "F.Fab")
			(effects
				(font
					(size 1.27 1.27)
				)
			)
		)
		(duplicate_pad_numbers_are_jumpers no)
		(fp_line
			(start -0.7874 -0.4064)
			(end 0.7874 -0.4064)
			(stroke
				(width 0.1524)
				(type default)
			)
			(layer "F.SilkS")
		)
		(fp_line
			(start -0.7874 0.4064)
			(end -0.7874 -0.4064)
			(stroke
				(width 0.1524)
				(type default)
			)
			(layer "F.SilkS")
		)
		(fp_line
			(start 0.7874 -0.4064)
			(end 0.7874 0.4064)
			(stroke
				(width 0.1524)
				(type default)
			)
			(layer "F.SilkS")
		)
		(fp_line
			(start 0.7874 0.4064)
			(end -0.7874 0.4064)
			(stroke
				(width 0.1524)
				(type default)
			)
			(layer "F.SilkS")
		)
		(fp_line
			(start -0.67945 -0.305054)
			(end -0.12065 -0.305054)
			(stroke
				(width 0.1)
				(type default)
			)
			(layer "F.Fab")
		)
		(fp_line
			(start -0.67945 0.3048)
			(end -0.67945 -0.305054)
			(stroke
				(width 0.1)
				(type default)
			)
			(layer "F.Fab")
		)
		(fp_line
			(start -0.12065 -0.305054)
			(end -0.12065 -0.2794)
			(stroke
				(width 0.1)
				(type default)
			)
			(layer "F.Fab")
		)
		(fp_line
			(start -0.12065 -0.2794)
			(end 0.12065 -0.2794)
			(stroke
				(width 0.1)
				(type default)
			)
			(layer "F.Fab")
		)
		(fp_line
			(start -0.12065 0.2794)
			(end -0.12065 0.3048)
			(stroke
				(width 0.1)
				(type default)
			)
			(layer "F.Fab")
		)
		(fp_line
			(start -0.12065 0.3048)
			(end -0.67945 0.3048)
			(stroke
				(width 0.1)
				(type default)
			)
			(layer "F.Fab")
		)
		(fp_line
			(start 0.120396 0.2794)
			(end -0.12065 0.2794)
			(stroke
				(width 0.1)
				(type default)
			)
			(layer "F.Fab")
		)
		(fp_line
			(start 0.120396 0.3048)
			(end 0.120396 0.2794)
			(stroke
				(width 0.1)
				(type default)
			)
			(layer "F.Fab")
		)
		(fp_line
			(start 0.12065 -0.3048)
			(end 0.67945 -0.3048)
			(stroke
				(width 0.1)
				(type default)
			)
			(layer "F.Fab")
		)
		(fp_line
			(start 0.12065 -0.2794)
			(end 0.12065 -0.3048)
			(stroke
				(width 0.1)
				(type default)
			)
			(layer "F.Fab")
		)
		(fp_line
			(start 0.67945 -0.3048)
			(end 0.67945 0.3048)
			(stroke
				(width 0.1)
				(type default)
			)
			(layer "F.Fab")
		)
		(fp_line
			(start 0.67945 0.3048)
			(end 0.120396 0.3048)
			(stroke
				(width 0.1)
				(type default)
			)
			(layer "F.Fab")
		)
		(pad "1" smd circle
			(at -0.40005 0)
			(size 0 0)
			(layers "F.Cu" "F.Mask" "F.Paste")
			(net "FM_PS_EN_PLD_BUF1")
		)
		(pad "2" smd circle
			(at 0.40005 0)
			(size 0 0)
			(layers "F.Cu" "F.Mask" "F.Paste")
			(net "FM_PS_EN_PLD_BUF1_R1")
		)
	)
	(footprint ""
		(layer "F.Cu")
		(at 50.43551 -165.808914 180)
		(property "Reference" "PR1804"
			(at 0 0 180)
			(layer "F.SilkS")
			(hide yes)
			(effects
				(font
					(size 1.27 1.27)
				)
			)
		)
		(property "Value" ""
			(at 0 0 180)
			(layer "F.Fab")
			(effects
				(font
					(size 1.27 1.27)
				)
			)
		)
		(duplicate_pad_numbers_are_jumpers no)
		(fp_line
			(start 0.7874 0.4064)
			(end -0.7874 0.4064)
			(stroke
				(width 0.1524)
				(type default)
			)
			(layer "F.SilkS")
		)
		(fp_line
			(start 0.7874 -0.4064)
			(end 0.7874 0.4064)
			(stroke
				(width 0.1524)
				(type default)
			)
			(layer "F.SilkS")
		)
		(fp_line
			(start -0.7874 0.4064)
			(end -0.7874 -0.4064)
			(stroke
				(width 0.1524)
				(type default)
			)
			(layer "F.SilkS")
		)
		(fp_line
			(start -0.7874 -0.4064)
			(end 0.7874 -0.4064)
			(stroke
				(width 0.1524)
				(type default)
			)
			(layer "F.SilkS")
		)
		(fp_line
			(start 0.67945 0.3048)
			(end 0.120396 0.3048)
			(stroke
				(width 0.1)
				(type default)
			)
			(layer "F.Fab")
		)
		(fp_line
			(start 0.67945 -0.3048)
			(end 0.67945 0.3048)
			(stroke
				(width 0.1)
				(type default)
			)
			(layer "F.Fab")
		)
		(fp_line
			(start 0.12065 -0.2794)
			(end 0.12065 -0.3048)
			(stroke
				(width 0.1)
				(type default)
			)
			(layer "F.Fab")
		)
		(fp_line
			(start 0.12065 -0.3048)
			(end 0.67945 -0.3048)
			(stroke
				(width 0.1)
				(type default)
			)
			(layer "F.Fab")
		)
		(fp_line
			(start 0.120396 0.3048)
			(end 0.120396 0.2794)
			(stroke
				(width 0.1)
				(type default)
			)
			(layer "F.Fab")
		)
		(fp_line
			(start 0.120396 0.2794)
			(end -0.12065 0.2794)
			(stroke
				(width 0.1)
				(type default)
			)
			(layer "F.Fab")
		)
		(fp_line
			(start -0.12065 0.3048)
			(end -0.67945 0.3048)
			(stroke
				(width 0.1)
				(type default)
			)
			(layer "F.Fab")
		)
		(fp_line
			(start -0.12065 0.2794)
			(end -0.12065 0.3048)
			(stroke
				(width 0.1)
				(type default)
			)
			(layer "F.Fab")
		)
		(fp_line
			(start -0.12065 -0.2794)
			(end 0.12065 -0.2794)
			(stroke
				(width 0.1)
				(type default)
			)
			(layer "F.Fab")
		)
		(fp_line
			(start -0.12065 -0.305054)
			(end -0.12065 -0.2794)
			(stroke
				(width 0.1)
				(type default)
			)
			(layer "F.Fab")
		)
		(fp_line
			(start -0.67945 0.3048)
			(end -0.67945 -0.305054)
			(stroke
				(width 0.1)
				(type default)
			)
			(layer "F.Fab")
		)
		(fp_line
			(start -0.67945 -0.305054)
			(end -0.12065 -0.305054)
			(stroke
				(width 0.1)
				(type default)
			)
			(layer "F.Fab")
		)
		(pad "1" smd circle
			(at -0.40005 0 180)
			(size 0 0)
			(layers "F.Cu" "F.Mask" "F.Paste")
			(net "SW_PVCCD_HV_CPU1_BOOT1")
		)
		(pad "2" smd circle
			(at 0.40005 0 180)
			(size 0 0)
			(layers "F.Cu" "F.Mask" "F.Paste")
			(net "SW_PVCCD_HV_CPU1_BOOT1_R")
		)
	)
	(footprint ""
		(layer "F.Cu")
		(at 378.349256 -92.887292 -90)
		(property "Reference" "R3056"
			(at 0 0 270)
			(layer "F.SilkS")
			(hide yes)
			(effects
				(font
					(size 1.27 1.27)
				)
			)
		)
		(property "Value" ""
			(at 0 0 270)
			(layer "F.Fab")
			(effects
				(font
					(size 1.27 1.27)
				)
			)
		)
		(duplicate_pad_numbers_are_jumpers no)
		(fp_line
			(start -0.7874 0.4064)
			(end -0.7874 -0.4064)
			(stroke
				(width 0.1524)
				(type default)
			)
			(layer "F.SilkS")
		)
		(fp_line
			(start 0.7874 0.4064)
			(end -0.7874 0.4064)
			(stroke
				(width 0.1524)
				(type default)
			)
			(layer "F.SilkS")
		)
		(fp_line
			(start -0.7874 -0.4064)
			(end 0.7874 -0.4064)
			(stroke
				(width 0.1524)
				(type default)
			)
			(layer "F.SilkS")
		)
		(fp_line
			(start 0.7874 -0.4064)
			(end 0.7874 0.4064)
			(stroke
				(width 0.1524)
				(type default)
			)
			(layer "F.SilkS")
		)
		(fp_line
			(start -0.67945 0.3048)
			(end -0.67945 -0.305054)
			(stroke
				(width 0.1)
				(type default)
			)
			(layer "F.Fab")
		)
		(fp_line
			(start -0.12065 0.3048)
			(end -0.67945 0.3048)
			(stroke
				(width 0.1)
				(type default)
			)
			(layer "F.Fab")
		)
		(fp_line
			(start 0.120396 0.3048)
			(end 0.120396 0.2794)
			(stroke
				(width 0.1)
				(type default)
			)
			(layer "F.Fab")
		)
		(fp_line
			(start 0.67945 0.3048)
			(end 0.120396 0.3048)
			(stroke
				(width 0.1)
				(type default)
			)
			(layer "F.Fab")
		)
		(fp_line
			(start -0.12065 0.2794)
			(end -0.12065 0.3048)
			(stroke
				(width 0.1)
				(type default)
			)
			(layer "F.Fab")
		)
		(fp_line
			(start 0.120396 0.2794)
			(end -0.12065 0.2794)
			(stroke
				(width 0.1)
				(type default)
			)
			(layer "F.Fab")
		)
		(fp_line
			(start -0.12065 -0.2794)
			(end 0.12065 -0.2794)
			(stroke
				(width 0.1)
				(type default)
			)
			(layer "F.Fab")
		)
		(fp_line
			(start 0.12065 -0.2794)
			(end 0.12065 -0.3048)
			(stroke
				(width 0.1)
				(type default)
			)
			(layer "F.Fab")
		)
		(fp_line
			(start 0.12065 -0.3048)
			(end 0.67945 -0.3048)
			(stroke
				(width 0.1)
				(type default)
			)
			(layer "F.Fab")
		)
		(fp_line
			(start 0.67945 -0.3048)
			(end 0.67945 0.3048)
			(stroke
				(width 0.1)
				(type default)
			)
			(layer "F.Fab")
		)
		(fp_line
			(start -0.67945 -0.305054)
			(end -0.12065 -0.305054)
			(stroke
				(width 0.1)
				(type default)
			)
			(layer "F.Fab")
		)
		(fp_line
			(start -0.12065 -0.305054)
			(end -0.12065 -0.2794)
			(stroke
				(width 0.1)
				(type default)
			)
			(layer "F.Fab")
		)
		(pad "1" smd circle
			(at -0.40005 0 270)
			(size 0 0)
			(layers "F.Cu" "F.Mask" "F.Paste")
			(net "JTAG_DBP_BMC_PRDY_R1_N")
		)
		(pad "2" smd circle
			(at 0.40005 0 270)
			(size 0 0)
			(layers "F.Cu" "F.Mask" "F.Paste")
			(net "JTAG_DBP_BMC_PRDY_N")
		)
	)
	(footprint ""
		(layer "F.Cu")
		(at 329.524868 -73.509378 90)
		(property "Reference" "R4304"
			(at 0 0 90)
			(layer "F.SilkS")
			(hide yes)
			(effects
				(font
					(size 1.27 1.27)
				)
			)
		)
		(property "Value" ""
			(at 0 0 90)
			(layer "F.Fab")
			(effects
				(font
					(size 1.27 1.27)
				)
			)
		)
		(duplicate_pad_numbers_are_jumpers no)
		(fp_line
			(start 0.7874 -0.4064)
			(end 0.7874 0.4064)
			(stroke
				(width 0.1524)
				(type default)
			)
			(layer "F.SilkS")
		)
		(fp_line
			(start -0.7874 -0.4064)
			(end 0.7874 -0.4064)
			(stroke
				(width 0.1524)
				(type default)
			)
			(layer "F.SilkS")
		)
		(fp_line
			(start 0.7874 0.4064)
			(end -0.7874 0.4064)
			(stroke
				(width 0.1524)
				(type default)
			)
			(layer "F.SilkS")
		)
		(fp_line
			(start -0.7874 0.4064)
			(end -0.7874 -0.4064)
			(stroke
				(width 0.1524)
				(type default)
			)
			(layer "F.SilkS")
		)
		(fp_line
			(start -0.12065 -0.305054)
			(end -0.12065 -0.2794)
			(stroke
				(width 0.1)
				(type default)
			)
			(layer "F.Fab")
		)
		(fp_line
			(start -0.67945 -0.305054)
			(end -0.12065 -0.305054)
			(stroke
				(width 0.1)
				(type default)
			)
			(layer "F.Fab")
		)
		(fp_line
			(start 0.67945 -0.3048)
			(end 0.67945 0.3048)
			(stroke
				(width 0.1)
				(type default)
			)
			(layer "F.Fab")
		)
		(fp_line
			(start 0.12065 -0.3048)
			(end 0.67945 -0.3048)
			(stroke
				(width 0.1)
				(type default)
			)
			(layer "F.Fab")
		)
		(fp_line
			(start 0.12065 -0.2794)
			(end 0.12065 -0.3048)
			(stroke
				(width 0.1)
				(type default)
			)
			(layer "F.Fab")
		)
		(fp_line
			(start -0.12065 -0.2794)
			(end 0.12065 -0.2794)
			(stroke
				(width 0.1)
				(type default)
			)
			(layer "F.Fab")
		)
		(fp_line
			(start 0.120396 0.2794)
			(end -0.12065 0.2794)
			(stroke
				(width 0.1)
				(type default)
			)
			(layer "F.Fab")
		)
		(fp_line
			(start -0.12065 0.2794)
			(end -0.12065 0.3048)
			(stroke
				(width 0.1)
				(type default)
			)
			(layer "F.Fab")
		)
		(fp_line
			(start 0.67945 0.3048)
			(end 0.120396 0.3048)
			(stroke
				(width 0.1)
				(type default)
			)
			(layer "F.Fab")
		)
		(fp_line
			(start 0.120396 0.3048)
			(end 0.120396 0.2794)
			(stroke
				(width 0.1)
				(type default)
			)
			(layer "F.Fab")
		)
		(fp_line
			(start -0.12065 0.3048)
			(end -0.67945 0.3048)
			(stroke
				(width 0.1)
				(type default)
			)
			(layer "F.Fab")
		)
		(fp_line
			(start -0.67945 0.3048)
			(end -0.67945 -0.305054)
			(stroke
				(width 0.1)
				(type default)
			)
			(layer "F.Fab")
		)
		(pad "1" smd circle
			(at -0.40005 0 90)
			(size 0 0)
			(layers "F.Cu" "F.Mask" "F.Paste")
			(net "CLK_100M_E1S_0_R_DN")
		)
		(pad "2" smd circle
			(at 0.40005 0 90)
			(size 0 0)
			(layers "F.Cu" "F.Mask" "F.Paste")
			(net "CLK_100M_E1S_0_DN")
		)
	)
	(footprint ""
		(layer "F.Cu")
		(at 463.90687 -75.960224 90)
		(property "Reference" "PC566"
			(at 0 0 90)
			(layer "F.SilkS")
			(hide yes)
			(effects
				(font
					(size 1.27 1.27)
				)
			)
		)
		(property "Value" ""
			(at 0 0 90)
			(layer "F.Fab")
			(effects
				(font
					(size 1.27 1.27)
				)
			)
		)
		(duplicate_pad_numbers_are_jumpers no)
		(fp_line
			(start -3.400044 1.249934)
			(end 3.400044 1.249934)
			(stroke
				(width 0.1524)
				(type default)
			)
			(layer "F.SilkS")
		)
		(fp_circle
			(center 0 1.249934)
			(end 0 4.649978)
			(stroke
				(width 0.1524)
				(type default)
			)
			(fill no)
			(layer "F.SilkS")
		)
		(fp_poly
			(pts
				(arc
					(start -3.400044 1.249934)
					(mid 0 4.649978)
					(end 3.400044 1.249934)
				)
			)
			(stroke
				(width 0)
				(type default)
			)
			(fill yes)
			(layer "F.SilkS")
		)
		(fp_circle
			(center 0 1.249934)
			(end 0 4.649978)
			(stroke
				(width 0.1)
				(type default)
			)
			(fill no)
			(layer "F.Fab")
		)
		(pad "1" thru_hole rect
			(at 0 0 90)
			(size 1.524 1.524)
			(drill 1.016)
			(layers "*.Cu" "*.Mask")
			(remove_unused_layers no)
			(net "SW_P3V3_AUX_FLT")
			(clearance 0)
			(padstack
				(mode front_inner_back)
				(layer "Inner"
					(shape circle)
					(size 1.524 1.524)
					(clearance 0)
				)
				(layer "B.Cu"
					(shape rect)
					(size 1.524 1.524)
					(clearance 0)
				)
			)
		)
		(pad "2" thru_hole circle
			(at 0 2.500122 90)
			(size 1.524 1.524)
			(drill 1.016)
			(layers "*.Cu" "*.Mask")
			(remove_unused_layers no)
			(net "GND")
			(clearance 0)
		)
	)
	(footprint ""
		(layer "F.Cu")
		(at 155.634944 -44.64685 90)
		(property "Reference" "R4454"
			(at 0 0 90)
			(layer "F.SilkS")
			(hide yes)
			(effects
				(font
					(size 1.27 1.27)
				)
			)
		)
		(property "Value" ""
			(at 0 0 90)
			(layer "F.Fab")
			(effects
				(font
					(size 1.27 1.27)
				)
			)
		)
		(duplicate_pad_numbers_are_jumpers no)
		(fp_line
			(start 0.7874 -0.4064)
			(end 0.7874 0.4064)
			(stroke
				(width 0.1524)
				(type default)
			)
			(layer "F.SilkS")
		)
		(fp_line
			(start -0.7874 -0.4064)
			(end 0.7874 -0.4064)
			(stroke
				(width 0.1524)
				(type default)
			)
			(layer "F.SilkS")
		)
		(fp_line
			(start -0.12065 -0.305054)
			(end -0.12065 -0.2794)
			(stroke
				(width 0.1)
				(type default)
			)
			(layer "F.Fab")
		)
		(fp_line
			(start -0.67945 -0.305054)
			(end -0.12065 -0.305054)
			(stroke
				(width 0.1)
				(type default)
			)
			(layer "F.Fab")
		)
		(fp_line
			(start 0.67945 -0.3048)
			(end 0.67945 0.3048)
			(stroke
				(width 0.1)
				(type default)
			)
			(layer "F.Fab")
		)
		(fp_line
			(start 0.12065 -0.3048)
			(end 0.67945 -0.3048)
			(stroke
				(width 0.1)
				(type default)
			)
			(layer "F.Fab")
		)
		(fp_line
			(start 0.12065 -0.2794)
			(end 0.12065 -0.3048)
			(stroke
				(width 0.1)
				(type default)
			)
			(layer "F.Fab")
		)
		(fp_line
			(start -0.12065 -0.2794)
			(end 0.12065 -0.2794)
			(stroke
				(width 0.1)
				(type default)
			)
			(layer "F.Fab")
		)
		(fp_line
			(start 0.120396 0.2794)
			(end -0.12065 0.2794)
			(stroke
				(width 0.1)
				(type default)
			)
			(layer "F.Fab")
		)
		(fp_line
			(start -0.12065 0.2794)
			(end -0.12065 0.3048)
			(stroke
				(width 0.1)
				(type default)
			)
			(layer "F.Fab")
		)
		(fp_line
			(start 0.67945 0.3048)
			(end 0.120396 0.3048)
			(stroke
				(width 0.1)
				(type default)
			)
			(layer "F.Fab")
		)
		(fp_line
			(start 0.120396 0.3048)
			(end 0.120396 0.2794)
			(stroke
				(width 0.1)
				(type default)
			)
			(layer "F.Fab")
		)
		(fp_line
			(start -0.12065 0.3048)
			(end -0.67945 0.3048)
			(stroke
				(width 0.1)
				(type default)
			)
			(layer "F.Fab")
		)
		(fp_line
			(start -0.67945 0.3048)
			(end -0.67945 -0.305054)
			(stroke
				(width 0.1)
				(type default)
			)
			(layer "F.Fab")
		)
		(pad "1" smd rect
			(at -0.40005 0 270)
			(size 0.4572 0.508)
			(layers "F.Cu" "F.Mask" "F.Paste")
			(net "USB2_HUB_2_EXT_DP")
		)
		(pad "2" smd rect
			(at 0.40005 0 270)
			(size 0.4572 0.508)
			(layers "F.Cu" "F.Mask" "F.Paste")
			(net "USB2_HUB_2_BUF_EXT_R_DP")
		)
	)
	(footprint ""
		(layer "F.Cu")
		(at 457.529946 -41.01211 180)
		(property "Reference" "R4069"
			(at 0 0 180)
			(layer "F.SilkS")
			(hide yes)
			(effects
				(font
					(size 1.27 1.27)
				)
			)
		)
		(property "Value" ""
			(at 0 0 180)
			(layer "F.Fab")
			(effects
				(font
					(size 1.27 1.27)
				)
			)
		)
		(duplicate_pad_numbers_are_jumpers no)
		(fp_line
			(start 0.7874 0.4064)
			(end -0.7874 0.4064)
			(stroke
				(width 0.1524)
				(type default)
			)
			(layer "F.SilkS")
		)
		(fp_line
			(start 0.7874 -0.4064)
			(end 0.7874 0.4064)
			(stroke
				(width 0.1524)
				(type default)
			)
			(layer "F.SilkS")
		)
		(fp_line
			(start -0.7874 0.4064)
			(end -0.7874 -0.4064)
			(stroke
				(width 0.1524)
				(type default)
			)
			(layer "F.SilkS")
		)
		(fp_line
			(start -0.7874 -0.4064)
			(end 0.7874 -0.4064)
			(stroke
				(width 0.1524)
				(type default)
			)
			(layer "F.SilkS")
		)
		(fp_line
			(start 0.67945 0.3048)
			(end 0.120396 0.3048)
			(stroke
				(width 0.1)
				(type default)
			)
			(layer "F.Fab")
		)
		(fp_line
			(start 0.67945 -0.3048)
			(end 0.67945 0.3048)
			(stroke
				(width 0.1)
				(type default)
			)
			(layer "F.Fab")
		)
		(fp_line
			(start 0.12065 -0.2794)
			(end 0.12065 -0.3048)
			(stroke
				(width 0.1)
				(type default)
			)
			(layer "F.Fab")
		)
		(fp_line
			(start 0.12065 -0.3048)
			(end 0.67945 -0.3048)
			(stroke
				(width 0.1)
				(type default)
			)
			(layer "F.Fab")
		)
		(fp_line
			(start 0.120396 0.3048)
			(end 0.120396 0.2794)
			(stroke
				(width 0.1)
				(type default)
			)
			(layer "F.Fab")
		)
		(fp_line
			(start 0.120396 0.2794)
			(end -0.12065 0.2794)
			(stroke
				(width 0.1)
				(type default)
			)
			(layer "F.Fab")
		)
		(fp_line
			(start -0.12065 0.3048)
			(end -0.67945 0.3048)
			(stroke
				(width 0.1)
				(type default)
			)
			(layer "F.Fab")
		)
		(fp_line
			(start -0.12065 0.2794)
			(end -0.12065 0.3048)
			(stroke
				(width 0.1)
				(type default)
			)
			(layer "F.Fab")
		)
		(fp_line
			(start -0.12065 -0.2794)
			(end 0.12065 -0.2794)
			(stroke
				(width 0.1)
				(type default)
			)
			(layer "F.Fab")
		)
		(fp_line
			(start -0.12065 -0.305054)
			(end -0.12065 -0.2794)
			(stroke
				(width 0.1)
				(type default)
			)
			(layer "F.Fab")
		)
		(fp_line
			(start -0.67945 0.3048)
			(end -0.67945 -0.305054)
			(stroke
				(width 0.1)
				(type default)
			)
			(layer "F.Fab")
		)
		(fp_line
			(start -0.67945 -0.305054)
			(end -0.12065 -0.305054)
			(stroke
				(width 0.1)
				(type default)
			)
			(layer "F.Fab")
		)
		(pad "1" smd circle
			(at -0.40005 0 180)
			(size 0 0)
			(layers "F.Cu" "F.Mask" "F.Paste")
			(net "P3V3_OCP_EN_1_R")
		)
		(pad "2" smd circle
			(at 0.40005 0 180)
			(size 0 0)
			(layers "F.Cu" "F.Mask" "F.Paste")
			(net "GND")
		)
	)
	(footprint ""
		(layer "F.Cu")
		(at 311.021476 -28.951428 180)
		(property "Reference" "R1452"
			(at 0 0 180)
			(layer "F.SilkS")
			(hide yes)
			(effects
				(font
					(size 1.27 1.27)
				)
			)
		)
		(property "Value" ""
			(at 0 0 180)
			(layer "F.Fab")
			(effects
				(font
					(size 1.27 1.27)
				)
			)
		)
		(duplicate_pad_numbers_are_jumpers no)
		(fp_line
			(start 0.7874 0.4064)
			(end -0.7874 0.4064)
			(stroke
				(width 0.1524)
				(type default)
			)
			(layer "F.SilkS")
		)
		(fp_line
			(start 0.7874 -0.4064)
			(end 0.7874 0.4064)
			(stroke
				(width 0.1524)
				(type default)
			)
			(layer "F.SilkS")
		)
		(fp_line
			(start -0.7874 0.4064)
			(end -0.7874 -0.4064)
			(stroke
				(width 0.1524)
				(type default)
			)
			(layer "F.SilkS")
		)
		(fp_line
			(start -0.7874 -0.4064)
			(end 0.7874 -0.4064)
			(stroke
				(width 0.1524)
				(type default)
			)
			(layer "F.SilkS")
		)
		(fp_line
			(start 0.67945 0.3048)
			(end 0.120396 0.3048)
			(stroke
				(width 0.1)
				(type default)
			)
			(layer "F.Fab")
		)
		(fp_line
			(start 0.67945 -0.3048)
			(end 0.67945 0.3048)
			(stroke
				(width 0.1)
				(type default)
			)
			(layer "F.Fab")
		)
		(fp_line
			(start 0.12065 -0.2794)
			(end 0.12065 -0.3048)
			(stroke
				(width 0.1)
				(type default)
			)
			(layer "F.Fab")
		)
		(fp_line
			(start 0.12065 -0.3048)
			(end 0.67945 -0.3048)
			(stroke
				(width 0.1)
				(type default)
			)
			(layer "F.Fab")
		)
		(fp_line
			(start 0.120396 0.3048)
			(end 0.120396 0.2794)
			(stroke
				(width 0.1)
				(type default)
			)
			(layer "F.Fab")
		)
		(fp_line
			(start 0.120396 0.2794)
			(end -0.12065 0.2794)
			(stroke
				(width 0.1)
				(type default)
			)
			(layer "F.Fab")
		)
		(fp_line
			(start -0.12065 0.3048)
			(end -0.67945 0.3048)
			(stroke
				(width 0.1)
				(type default)
			)
			(layer "F.Fab")
		)
		(fp_line
			(start -0.12065 0.2794)
			(end -0.12065 0.3048)
			(stroke
				(width 0.1)
				(type default)
			)
			(layer "F.Fab")
		)
		(fp_line
			(start -0.12065 -0.2794)
			(end 0.12065 -0.2794)
			(stroke
				(width 0.1)
				(type default)
			)
			(layer "F.Fab")
		)
		(fp_line
			(start -0.12065 -0.305054)
			(end -0.12065 -0.2794)
			(stroke
				(width 0.1)
				(type default)
			)
			(layer "F.Fab")
		)
		(fp_line
			(start -0.67945 0.3048)
			(end -0.67945 -0.305054)
			(stroke
				(width 0.1)
				(type default)
			)
			(layer "F.Fab")
		)
		(fp_line
			(start -0.67945 -0.305054)
			(end -0.12065 -0.305054)
			(stroke
				(width 0.1)
				(type default)
			)
			(layer "F.Fab")
		)
		(pad "1" smd circle
			(at -0.40005 0 180)
			(size 0 0)
			(layers "F.Cu" "F.Mask" "F.Paste")
			(net "PU_SMB_SML3_3V3AUX_PCH_SDA")
		)
		(pad "2" smd circle
			(at 0.40005 0 180)
			(size 0 0)
			(layers "F.Cu" "F.Mask" "F.Paste")
			(net "P3V3_AUX")
		)
	)
	(footprint ""
		(layer "F.Cu")
		(at 64.979296 -70.78599)
		(property "Reference" "D70"
			(at -34.630106 50.178462 90)
			(unlocked yes)
			(layer "F.SilkS")
			(effects
				(font
					(size 0.635 0.4064)
					(thickness 0.1524)
				)
				(justify left)
			)
		)
		(property "Value" ""
			(at 0 0 0)
			(layer "F.Fab")
			(effects
				(font
					(size 1.27 1.27)
				)
			)
		)
		(duplicate_pad_numbers_are_jumpers no)
		(fp_line
			(start -0.90678 0.4826)
			(end -0.90678 -0.4699)
			(stroke
				(width 0.1524)
				(type default)
			)
			(layer "F.SilkS")
		)
		(fp_line
			(start -0.89408 -0.4826)
			(end 0.90678 -0.4826)
			(stroke
				(width 0.1524)
				(type default)
			)
			(layer "F.SilkS")
		)
		(fp_line
			(start -0.79248 -0.4826)
			(end 1.03378 -0.4826)
			(stroke
				(width 0.1524)
				(type default)
			)
			(layer "F.SilkS")
		)
		(fp_line
			(start -0.64008 -0.4826)
			(end 1.16078 -0.4826)
			(stroke
				(width 0.1524)
				(type default)
			)
			(layer "F.SilkS")
		)
		(fp_line
			(start 0.90678 -0.4826)
			(end 0.90678 0.4826)
			(stroke
				(width 0.1524)
				(type default)
			)
			(layer "F.SilkS")
		)
		(fp_line
			(start 0.90678 0.4826)
			(end -0.90678 0.4826)
			(stroke
				(width 0.1524)
				(type default)
			)
			(layer "F.SilkS")
		)
		(fp_line
			(start 1.03378 -0.4826)
			(end 1.03378 0.4826)
			(stroke
				(width 0.1524)
				(type default)
			)
			(layer "F.SilkS")
		)
		(fp_line
			(start 1.03378 0.4826)
			(end -0.79248 0.4826)
			(stroke
				(width 0.1524)
				(type default)
			)
			(layer "F.SilkS")
		)
		(fp_line
			(start 1.16078 -0.4826)
			(end 1.16078 0.4826)
			(stroke
				(width 0.1524)
				(type default)
			)
			(layer "F.SilkS")
		)
		(fp_line
			(start 1.16078 0.4826)
			(end -0.64008 0.4826)
			(stroke
				(width 0.1524)
				(type default)
			)
			(layer "F.SilkS")
		)
		(fp_line
			(start -0.499872 -0.249936)
			(end 0.499872 -0.249936)
			(stroke
				(width 0.1)
				(type default)
			)
			(layer "F.Fab")
		)
		(fp_line
			(start -0.499872 0.249936)
			(end -0.499872 -0.249936)
			(stroke
				(width 0.1)
				(type default)
			)
			(layer "F.Fab")
		)
		(fp_line
			(start 0.499872 -0.249936)
			(end 0.499872 0.249936)
			(stroke
				(width 0.1)
				(type default)
			)
			(layer "F.Fab")
		)
		(fp_line
			(start 0.499872 0.249936)
			(end -0.499872 0.249936)
			(stroke
				(width 0.1)
				(type default)
			)
			(layer "F.Fab")
		)
		(pad "A" smd rect
			(at -0.47498 0)
			(size 0.6096 0.7112)
			(layers "F.Cu" "F.Mask" "F.Paste")
			(net "LED_RST_PLD_CPU1_DRAM_CD_N")
		)
		(pad "C" smd rect
			(at 0.47498 0)
			(size 0.6096 0.7112)
			(layers "F.Cu" "F.Mask" "F.Paste")
			(net "LED_RST_PLD_CPU1_DRAM_CD_N_D")
		)
	)
	(footprint ""
		(layer "F.Cu")
		(at 216.065608 -400.759422)
		(property "Reference" "PR3921"
			(at 0 0 0)
			(layer "F.SilkS")
			(hide yes)
			(effects
				(font
					(size 1.27 1.27)
				)
			)
		)
		(property "Value" ""
			(at 0 0 0)
			(layer "F.Fab")
			(effects
				(font
					(size 1.27 1.27)
				)
			)
		)
		(duplicate_pad_numbers_are_jumpers no)
		(fp_line
			(start -0.7874 -0.4064)
			(end 0.7874 -0.4064)
			(stroke
				(width 0.1524)
				(type default)
			)
			(layer "F.SilkS")
		)
		(fp_line
			(start -0.7874 0.4064)
			(end -0.7874 -0.4064)
			(stroke
				(width 0.1524)
				(type default)
			)
			(layer "F.SilkS")
		)
		(fp_line
			(start 0.7874 -0.4064)
			(end 0.7874 0.4064)
			(stroke
				(width 0.1524)
				(type default)
			)
			(layer "F.SilkS")
		)
		(fp_line
			(start 0.7874 0.4064)
			(end -0.7874 0.4064)
			(stroke
				(width 0.1524)
				(type default)
			)
			(layer "F.SilkS")
		)
		(fp_line
			(start -0.67945 -0.305054)
			(end -0.12065 -0.305054)
			(stroke
				(width 0.1)
				(type default)
			)
			(layer "F.Fab")
		)
		(fp_line
			(start -0.67945 0.3048)
			(end -0.67945 -0.305054)
			(stroke
				(width 0.1)
				(type default)
			)
			(layer "F.Fab")
		)
		(fp_line
			(start -0.12065 -0.305054)
			(end -0.12065 -0.2794)
			(stroke
				(width 0.1)
				(type default)
			)
			(layer "F.Fab")
		)
		(fp_line
			(start -0.12065 -0.2794)
			(end 0.12065 -0.2794)
			(stroke
				(width 0.1)
				(type default)
			)
			(layer "F.Fab")
		)
		(fp_line
			(start -0.12065 0.2794)
			(end -0.12065 0.3048)
			(stroke
				(width 0.1)
				(type default)
			)
			(layer "F.Fab")
		)
		(fp_line
			(start -0.12065 0.3048)
			(end -0.67945 0.3048)
			(stroke
				(width 0.1)
				(type default)
			)
			(layer "F.Fab")
		)
		(fp_line
			(start 0.120396 0.2794)
			(end -0.12065 0.2794)
			(stroke
				(width 0.1)
				(type default)
			)
			(layer "F.Fab")
		)
		(fp_line
			(start 0.120396 0.3048)
			(end 0.120396 0.2794)
			(stroke
				(width 0.1)
				(type default)
			)
			(layer "F.Fab")
		)
		(fp_line
			(start 0.12065 -0.3048)
			(end 0.67945 -0.3048)
			(stroke
				(width 0.1)
				(type default)
			)
			(layer "F.Fab")
		)
		(fp_line
			(start 0.12065 -0.2794)
			(end 0.12065 -0.3048)
			(stroke
				(width 0.1)
				(type default)
			)
			(layer "F.Fab")
		)
		(fp_line
			(start 0.67945 -0.3048)
			(end 0.67945 0.3048)
			(stroke
				(width 0.1)
				(type default)
			)
			(layer "F.Fab")
		)
		(fp_line
			(start 0.67945 0.3048)
			(end 0.120396 0.3048)
			(stroke
				(width 0.1)
				(type default)
			)
			(layer "F.Fab")
		)
		(pad "1" smd circle
			(at -0.40005 0)
			(size 0 0)
			(layers "F.Cu" "F.Mask" "F.Paste")
			(net "HSC_D_OC_2")
		)
		(pad "2" smd circle
			(at 0.40005 0)
			(size 0 0)
			(layers "F.Cu" "F.Mask" "F.Paste")
			(net "HSC_D_OC_R")
		)
	)
	(footprint ""
		(layer "F.Cu")
		(at 458.799946 -435.600094)
		(property "Reference" "H87"
			(at -5.13588 -4.694428 0)
			(unlocked yes)
			(layer "F.SilkS")
			(effects
				(font
					(size 0.7874 0.5842)
					(thickness 0.1524)
				)
				(justify left)
			)
		)
		(property "Value" ""
			(at 0 0 0)
			(layer "F.Fab")
			(effects
				(font
					(size 1.27 1.27)
				)
			)
		)
		(duplicate_pad_numbers_are_jumpers no)
		(pad "1" thru_hole circle
			(at 0 0)
			(size 10.0076 10.0076)
			(drill 5.6134)
			(layers "*.Cu" "*.Mask")
			(remove_unused_layers no)
			(net "GND")
			(clearance -1.9431)
		)
	)
	(footprint ""
		(layer "F.Cu")
		(at 140.00988 -40.985948 180)
		(property "Reference" "R2121"
			(at 0 0 180)
			(layer "F.SilkS")
			(hide yes)
			(effects
				(font
					(size 1.27 1.27)
				)
			)
		)
		(property "Value" ""
			(at 0 0 180)
			(layer "F.Fab")
			(effects
				(font
					(size 1.27 1.27)
				)
			)
		)
		(duplicate_pad_numbers_are_jumpers no)
		(fp_line
			(start 0.7874 0.4064)
			(end -0.7874 0.4064)
			(stroke
				(width 0.1524)
				(type default)
			)
			(layer "F.SilkS")
		)
		(fp_line
			(start 0.7874 -0.4064)
			(end 0.7874 0.4064)
			(stroke
				(width 0.1524)
				(type default)
			)
			(layer "F.SilkS")
		)
		(fp_line
			(start -0.7874 0.4064)
			(end -0.7874 -0.4064)
			(stroke
				(width 0.1524)
				(type default)
			)
			(layer "F.SilkS")
		)
		(fp_line
			(start -0.7874 -0.4064)
			(end 0.7874 -0.4064)
			(stroke
				(width 0.1524)
				(type default)
			)
			(layer "F.SilkS")
		)
		(fp_line
			(start 0.67945 0.3048)
			(end 0.120396 0.3048)
			(stroke
				(width 0.1)
				(type default)
			)
			(layer "F.Fab")
		)
		(fp_line
			(start 0.67945 -0.3048)
			(end 0.67945 0.3048)
			(stroke
				(width 0.1)
				(type default)
			)
			(layer "F.Fab")
		)
		(fp_line
			(start 0.12065 -0.2794)
			(end 0.12065 -0.3048)
			(stroke
				(width 0.1)
				(type default)
			)
			(layer "F.Fab")
		)
		(fp_line
			(start 0.12065 -0.3048)
			(end 0.67945 -0.3048)
			(stroke
				(width 0.1)
				(type default)
			)
			(layer "F.Fab")
		)
		(fp_line
			(start 0.120396 0.3048)
			(end 0.120396 0.2794)
			(stroke
				(width 0.1)
				(type default)
			)
			(layer "F.Fab")
		)
		(fp_line
			(start 0.120396 0.2794)
			(end -0.12065 0.2794)
			(stroke
				(width 0.1)
				(type default)
			)
			(layer "F.Fab")
		)
		(fp_line
			(start -0.12065 0.3048)
			(end -0.67945 0.3048)
			(stroke
				(width 0.1)
				(type default)
			)
			(layer "F.Fab")
		)
		(fp_line
			(start -0.12065 0.2794)
			(end -0.12065 0.3048)
			(stroke
				(width 0.1)
				(type default)
			)
			(layer "F.Fab")
		)
		(fp_line
			(start -0.12065 -0.2794)
			(end 0.12065 -0.2794)
			(stroke
				(width 0.1)
				(type default)
			)
			(layer "F.Fab")
		)
		(fp_line
			(start -0.12065 -0.305054)
			(end -0.12065 -0.2794)
			(stroke
				(width 0.1)
				(type default)
			)
			(layer "F.Fab")
		)
		(fp_line
			(start -0.67945 0.3048)
			(end -0.67945 -0.305054)
			(stroke
				(width 0.1)
				(type default)
			)
			(layer "F.Fab")
		)
		(fp_line
			(start -0.67945 -0.305054)
			(end -0.12065 -0.305054)
			(stroke
				(width 0.1)
				(type default)
			)
			(layer "F.Fab")
		)
		(pad "1" smd circle
			(at -0.40005 0 180)
			(size 0 0)
			(layers "F.Cu" "F.Mask" "F.Paste")
			(net "P3V3_AUX")
		)
		(pad "2" smd circle
			(at 0.40005 0 180)
			(size 0 0)
			(layers "F.Cu" "F.Mask" "F.Paste")
			(net "RST_PCIE_PCH_DEV_BUF_M2_0_PERST")
		)
	)
	(footprint ""
		(layer "F.Cu")
		(at 24.069802 -410.418534)
		(property "Reference" "R3504"
			(at 0 0 0)
			(layer "F.SilkS")
			(hide yes)
			(effects
				(font
					(size 1.27 1.27)
				)
			)
		)
		(property "Value" ""
			(at 0 0 0)
			(layer "F.Fab")
			(effects
				(font
					(size 1.27 1.27)
				)
			)
		)
		(duplicate_pad_numbers_are_jumpers no)
		(fp_line
			(start -0.7874 -0.4064)
			(end 0.7874 -0.4064)
			(stroke
				(width 0.1524)
				(type default)
			)
			(layer "F.SilkS")
		)
		(fp_line
			(start -0.7874 0.4064)
			(end -0.7874 -0.4064)
			(stroke
				(width 0.1524)
				(type default)
			)
			(layer "F.SilkS")
		)
		(fp_line
			(start 0.7874 -0.4064)
			(end 0.7874 0.4064)
			(stroke
				(width 0.1524)
				(type default)
			)
			(layer "F.SilkS")
		)
		(fp_line
			(start 0.7874 0.4064)
			(end -0.7874 0.4064)
			(stroke
				(width 0.1524)
				(type default)
			)
			(layer "F.SilkS")
		)
		(fp_line
			(start -0.67945 -0.305054)
			(end -0.12065 -0.305054)
			(stroke
				(width 0.1)
				(type default)
			)
			(layer "F.Fab")
		)
		(fp_line
			(start -0.67945 0.3048)
			(end -0.67945 -0.305054)
			(stroke
				(width 0.1)
				(type default)
			)
			(layer "F.Fab")
		)
		(fp_line
			(start -0.12065 -0.305054)
			(end -0.12065 -0.2794)
			(stroke
				(width 0.1)
				(type default)
			)
			(layer "F.Fab")
		)
		(fp_line
			(start -0.12065 -0.2794)
			(end 0.12065 -0.2794)
			(stroke
				(width 0.1)
				(type default)
			)
			(layer "F.Fab")
		)
		(fp_line
			(start -0.12065 0.2794)
			(end -0.12065 0.3048)
			(stroke
				(width 0.1)
				(type default)
			)
			(layer "F.Fab")
		)
		(fp_line
			(start -0.12065 0.3048)
			(end -0.67945 0.3048)
			(stroke
				(width 0.1)
				(type default)
			)
			(layer "F.Fab")
		)
		(fp_line
			(start 0.120396 0.2794)
			(end -0.12065 0.2794)
			(stroke
				(width 0.1)
				(type default)
			)
			(layer "F.Fab")
		)
		(fp_line
			(start 0.120396 0.3048)
			(end 0.120396 0.2794)
			(stroke
				(width 0.1)
				(type default)
			)
			(layer "F.Fab")
		)
		(fp_line
			(start 0.12065 -0.3048)
			(end 0.67945 -0.3048)
			(stroke
				(width 0.1)
				(type default)
			)
			(layer "F.Fab")
		)
		(fp_line
			(start 0.12065 -0.2794)
			(end 0.12065 -0.3048)
			(stroke
				(width 0.1)
				(type default)
			)
			(layer "F.Fab")
		)
		(fp_line
			(start 0.67945 -0.3048)
			(end 0.67945 0.3048)
			(stroke
				(width 0.1)
				(type default)
			)
			(layer "F.Fab")
		)
		(fp_line
			(start 0.67945 0.3048)
			(end 0.120396 0.3048)
			(stroke
				(width 0.1)
				(type default)
			)
			(layer "F.Fab")
		)
		(pad "1" smd circle
			(at -0.40005 0)
			(size 0 0)
			(layers "F.Cu" "F.Mask" "F.Paste")
			(net "P3V3_AUX")
		)
		(pad "2" smd circle
			(at 0.40005 0)
			(size 0 0)
			(layers "F.Cu" "F.Mask" "F.Paste")
			(net "GPU_FPGA_EROT_FATALERR_ISO_N")
		)
	)
	(footprint ""
		(layer "F.Cu")
		(at 40.273732 -358.691942)
		(property "Reference" "PR1304"
			(at 0 0 0)
			(layer "F.SilkS")
			(hide yes)
			(effects
				(font
					(size 1.27 1.27)
				)
			)
		)
		(property "Value" ""
			(at 0 0 0)
			(layer "F.Fab")
			(effects
				(font
					(size 1.27 1.27)
				)
			)
		)
		(duplicate_pad_numbers_are_jumpers no)
		(fp_line
			(start -0.7874 -0.4064)
			(end 0.7874 -0.4064)
			(stroke
				(width 0.1524)
				(type default)
			)
			(layer "F.SilkS")
		)
		(fp_line
			(start -0.7874 0.4064)
			(end -0.7874 -0.4064)
			(stroke
				(width 0.1524)
				(type default)
			)
			(layer "F.SilkS")
		)
		(fp_line
			(start 0.7874 -0.4064)
			(end 0.7874 0.4064)
			(stroke
				(width 0.1524)
				(type default)
			)
			(layer "F.SilkS")
		)
		(fp_line
			(start 0.7874 0.4064)
			(end -0.7874 0.4064)
			(stroke
				(width 0.1524)
				(type default)
			)
			(layer "F.SilkS")
		)
		(fp_line
			(start -0.67945 -0.305054)
			(end -0.12065 -0.305054)
			(stroke
				(width 0.1)
				(type default)
			)
			(layer "F.Fab")
		)
		(fp_line
			(start -0.67945 0.3048)
			(end -0.67945 -0.305054)
			(stroke
				(width 0.1)
				(type default)
			)
			(layer "F.Fab")
		)
		(fp_line
			(start -0.12065 -0.305054)
			(end -0.12065 -0.2794)
			(stroke
				(width 0.1)
				(type default)
			)
			(layer "F.Fab")
		)
		(fp_line
			(start -0.12065 -0.2794)
			(end 0.12065 -0.2794)
			(stroke
				(width 0.1)
				(type default)
			)
			(layer "F.Fab")
		)
		(fp_line
			(start -0.12065 0.2794)
			(end -0.12065 0.3048)
			(stroke
				(width 0.1)
				(type default)
			)
			(layer "F.Fab")
		)
		(fp_line
			(start -0.12065 0.3048)
			(end -0.67945 0.3048)
			(stroke
				(width 0.1)
				(type default)
			)
			(layer "F.Fab")
		)
		(fp_line
			(start 0.120396 0.2794)
			(end -0.12065 0.2794)
			(stroke
				(width 0.1)
				(type default)
			)
			(layer "F.Fab")
		)
		(fp_line
			(start 0.120396 0.3048)
			(end 0.120396 0.2794)
			(stroke
				(width 0.1)
				(type default)
			)
			(layer "F.Fab")
		)
		(fp_line
			(start 0.12065 -0.3048)
			(end 0.67945 -0.3048)
			(stroke
				(width 0.1)
				(type default)
			)
			(layer "F.Fab")
		)
		(fp_line
			(start 0.12065 -0.2794)
			(end 0.12065 -0.3048)
			(stroke
				(width 0.1)
				(type default)
			)
			(layer "F.Fab")
		)
		(fp_line
			(start 0.67945 -0.3048)
			(end 0.67945 0.3048)
			(stroke
				(width 0.1)
				(type default)
			)
			(layer "F.Fab")
		)
		(fp_line
			(start 0.67945 0.3048)
			(end 0.120396 0.3048)
			(stroke
				(width 0.1)
				(type default)
			)
			(layer "F.Fab")
		)
		(pad "1" smd circle
			(at -0.40005 0)
			(size 0 0)
			(layers "F.Cu" "F.Mask" "F.Paste")
			(net "PVCCFA_EHV_FIVRA_CPU1_LSET4")
		)
		(pad "2" smd circle
			(at 0.40005 0)
			(size 0 0)
			(layers "F.Cu" "F.Mask" "F.Paste")
			(net "GND")
		)
	)
	(footprint ""
		(layer "F.Cu")
		(at 120.37822 -421.447468)
		(property "Reference" "R2925"
			(at 0 0 0)
			(layer "F.SilkS")
			(hide yes)
			(effects
				(font
					(size 1.27 1.27)
				)
			)
		)
		(property "Value" ""
			(at 0 0 0)
			(layer "F.Fab")
			(effects
				(font
					(size 1.27 1.27)
				)
			)
		)
		(duplicate_pad_numbers_are_jumpers no)
		(fp_line
			(start -0.7874 -0.4064)
			(end 0.7874 -0.4064)
			(stroke
				(width 0.1524)
				(type default)
			)
			(layer "F.SilkS")
		)
		(fp_line
			(start -0.7874 0.4064)
			(end -0.7874 -0.4064)
			(stroke
				(width 0.1524)
				(type default)
			)
			(layer "F.SilkS")
		)
		(fp_line
			(start 0.7874 -0.4064)
			(end 0.7874 0.4064)
			(stroke
				(width 0.1524)
				(type default)
			)
			(layer "F.SilkS")
		)
		(fp_line
			(start 0.7874 0.4064)
			(end -0.7874 0.4064)
			(stroke
				(width 0.1524)
				(type default)
			)
			(layer "F.SilkS")
		)
		(fp_line
			(start -0.67945 -0.305054)
			(end -0.12065 -0.305054)
			(stroke
				(width 0.1)
				(type default)
			)
			(layer "F.Fab")
		)
		(fp_line
			(start -0.67945 0.3048)
			(end -0.67945 -0.305054)
			(stroke
				(width 0.1)
				(type default)
			)
			(layer "F.Fab")
		)
		(fp_line
			(start -0.12065 -0.305054)
			(end -0.12065 -0.2794)
			(stroke
				(width 0.1)
				(type default)
			)
			(layer "F.Fab")
		)
		(fp_line
			(start -0.12065 -0.2794)
			(end 0.12065 -0.2794)
			(stroke
				(width 0.1)
				(type default)
			)
			(layer "F.Fab")
		)
		(fp_line
			(start -0.12065 0.2794)
			(end -0.12065 0.3048)
			(stroke
				(width 0.1)
				(type default)
			)
			(layer "F.Fab")
		)
		(fp_line
			(start -0.12065 0.3048)
			(end -0.67945 0.3048)
			(stroke
				(width 0.1)
				(type default)
			)
			(layer "F.Fab")
		)
		(fp_line
			(start 0.120396 0.2794)
			(end -0.12065 0.2794)
			(stroke
				(width 0.1)
				(type default)
			)
			(layer "F.Fab")
		)
		(fp_line
			(start 0.120396 0.3048)
			(end 0.120396 0.2794)
			(stroke
				(width 0.1)
				(type default)
			)
			(layer "F.Fab")
		)
		(fp_line
			(start 0.12065 -0.3048)
			(end 0.67945 -0.3048)
			(stroke
				(width 0.1)
				(type default)
			)
			(layer "F.Fab")
		)
		(fp_line
			(start 0.12065 -0.2794)
			(end 0.12065 -0.3048)
			(stroke
				(width 0.1)
				(type default)
			)
			(layer "F.Fab")
		)
		(fp_line
			(start 0.67945 -0.3048)
			(end 0.67945 0.3048)
			(stroke
				(width 0.1)
				(type default)
			)
			(layer "F.Fab")
		)
		(fp_line
			(start 0.67945 0.3048)
			(end 0.120396 0.3048)
			(stroke
				(width 0.1)
				(type default)
			)
			(layer "F.Fab")
		)
		(pad "1" smd circle
			(at -0.40005 0)
			(size 0 0)
			(layers "F.Cu" "F.Mask" "F.Paste")
			(net "FM_GPU_PWR_EN_R1")
		)
		(pad "2" smd circle
			(at 0.40005 0)
			(size 0 0)
			(layers "F.Cu" "F.Mask" "F.Paste")
			(net "FM_GPU_PWR_EN_R_BUF")
		)
	)
	(footprint ""
		(layer "F.Cu")
		(at 211.99729 -69.86143)
		(property "Reference" "R1355"
			(at 0 0 0)
			(layer "F.SilkS")
			(hide yes)
			(effects
				(font
					(size 1.27 1.27)
				)
			)
		)
		(property "Value" ""
			(at 0 0 0)
			(layer "F.Fab")
			(effects
				(font
					(size 1.27 1.27)
				)
			)
		)
		(duplicate_pad_numbers_are_jumpers no)
		(fp_line
			(start -0.7874 -0.4064)
			(end 0.7874 -0.4064)
			(stroke
				(width 0.1524)
				(type default)
			)
			(layer "F.SilkS")
		)
		(fp_line
			(start -0.7874 0.4064)
			(end -0.7874 -0.4064)
			(stroke
				(width 0.1524)
				(type default)
			)
			(layer "F.SilkS")
		)
		(fp_line
			(start 0.7874 -0.4064)
			(end 0.7874 0.4064)
			(stroke
				(width 0.1524)
				(type default)
			)
			(layer "F.SilkS")
		)
		(fp_line
			(start 0.7874 0.4064)
			(end -0.7874 0.4064)
			(stroke
				(width 0.1524)
				(type default)
			)
			(layer "F.SilkS")
		)
		(fp_line
			(start -0.67945 -0.305054)
			(end -0.12065 -0.305054)
			(stroke
				(width 0.1)
				(type default)
			)
			(layer "F.Fab")
		)
		(fp_line
			(start -0.67945 0.3048)
			(end -0.67945 -0.305054)
			(stroke
				(width 0.1)
				(type default)
			)
			(layer "F.Fab")
		)
		(fp_line
			(start -0.12065 -0.305054)
			(end -0.12065 -0.2794)
			(stroke
				(width 0.1)
				(type default)
			)
			(layer "F.Fab")
		)
		(fp_line
			(start -0.12065 -0.2794)
			(end 0.12065 -0.2794)
			(stroke
				(width 0.1)
				(type default)
			)
			(layer "F.Fab")
		)
		(fp_line
			(start -0.12065 0.2794)
			(end -0.12065 0.3048)
			(stroke
				(width 0.1)
				(type default)
			)
			(layer "F.Fab")
		)
		(fp_line
			(start -0.12065 0.3048)
			(end -0.67945 0.3048)
			(stroke
				(width 0.1)
				(type default)
			)
			(layer "F.Fab")
		)
		(fp_line
			(start 0.120396 0.2794)
			(end -0.12065 0.2794)
			(stroke
				(width 0.1)
				(type default)
			)
			(layer "F.Fab")
		)
		(fp_line
			(start 0.120396 0.3048)
			(end 0.120396 0.2794)
			(stroke
				(width 0.1)
				(type default)
			)
			(layer "F.Fab")
		)
		(fp_line
			(start 0.12065 -0.3048)
			(end 0.67945 -0.3048)
			(stroke
				(width 0.1)
				(type default)
			)
			(layer "F.Fab")
		)
		(fp_line
			(start 0.12065 -0.2794)
			(end 0.12065 -0.3048)
			(stroke
				(width 0.1)
				(type default)
			)
			(layer "F.Fab")
		)
		(fp_line
			(start 0.67945 -0.3048)
			(end 0.67945 0.3048)
			(stroke
				(width 0.1)
				(type default)
			)
			(layer "F.Fab")
		)
		(fp_line
			(start 0.67945 0.3048)
			(end 0.120396 0.3048)
			(stroke
				(width 0.1)
				(type default)
			)
			(layer "F.Fab")
		)
		(pad "1" smd circle
			(at -0.40005 0)
			(size 0 0)
			(layers "F.Cu" "F.Mask" "F.Paste")
			(net "RMII_BMC_OCP_TXD_1")
		)
		(pad "2" smd circle
			(at 0.40005 0)
			(size 0 0)
			(layers "F.Cu" "F.Mask" "F.Paste")
			(net "GND")
		)
	)
	(footprint ""
		(layer "F.Cu")
		(at 175.31588 -130.266948 90)
		(property "Reference" "C1211"
			(at 0 0 90)
			(layer "F.SilkS")
			(hide yes)
			(effects
				(font
					(size 1.27 1.27)
				)
			)
		)
		(property "Value" ""
			(at 0 0 90)
			(layer "F.Fab")
			(effects
				(font
					(size 1.27 1.27)
				)
			)
		)
		(duplicate_pad_numbers_are_jumpers no)
		(fp_line
			(start 0.7874 -0.4064)
			(end 0.7874 0.4064)
			(stroke
				(width 0.1524)
				(type default)
			)
			(layer "F.SilkS")
		)
		(fp_line
			(start -0.7874 -0.4064)
			(end 0.7874 -0.4064)
			(stroke
				(width 0.1524)
				(type default)
			)
			(layer "F.SilkS")
		)
		(fp_line
			(start 0.7874 0.4064)
			(end -0.7874 0.4064)
			(stroke
				(width 0.1524)
				(type default)
			)
			(layer "F.SilkS")
		)
		(fp_line
			(start -0.7874 0.4064)
			(end -0.7874 -0.4064)
			(stroke
				(width 0.1524)
				(type default)
			)
			(layer "F.SilkS")
		)
		(fp_line
			(start -0.12065 -0.305054)
			(end -0.12065 -0.2794)
			(stroke
				(width 0.1)
				(type default)
			)
			(layer "F.Fab")
		)
		(fp_line
			(start -0.67945 -0.305054)
			(end -0.12065 -0.305054)
			(stroke
				(width 0.1)
				(type default)
			)
			(layer "F.Fab")
		)
		(fp_line
			(start 0.67945 -0.3048)
			(end 0.67945 0.3048)
			(stroke
				(width 0.1)
				(type default)
			)
			(layer "F.Fab")
		)
		(fp_line
			(start 0.12065 -0.3048)
			(end 0.67945 -0.3048)
			(stroke
				(width 0.1)
				(type default)
			)
			(layer "F.Fab")
		)
		(fp_line
			(start 0.12065 -0.2794)
			(end 0.12065 -0.3048)
			(stroke
				(width 0.1)
				(type default)
			)
			(layer "F.Fab")
		)
		(fp_line
			(start -0.12065 -0.2794)
			(end 0.12065 -0.2794)
			(stroke
				(width 0.1)
				(type default)
			)
			(layer "F.Fab")
		)
		(fp_line
			(start 0.120396 0.2794)
			(end -0.12065 0.2794)
			(stroke
				(width 0.1)
				(type default)
			)
			(layer "F.Fab")
		)
		(fp_line
			(start -0.12065 0.2794)
			(end -0.12065 0.3048)
			(stroke
				(width 0.1)
				(type default)
			)
			(layer "F.Fab")
		)
		(fp_line
			(start 0.67945 0.3048)
			(end 0.120396 0.3048)
			(stroke
				(width 0.1)
				(type default)
			)
			(layer "F.Fab")
		)
		(fp_line
			(start 0.120396 0.3048)
			(end 0.120396 0.2794)
			(stroke
				(width 0.1)
				(type default)
			)
			(layer "F.Fab")
		)
		(fp_line
			(start -0.12065 0.3048)
			(end -0.67945 0.3048)
			(stroke
				(width 0.1)
				(type default)
			)
			(layer "F.Fab")
		)
		(fp_line
			(start -0.67945 0.3048)
			(end -0.67945 -0.305054)
			(stroke
				(width 0.1)
				(type default)
			)
			(layer "F.Fab")
		)
		(pad "1" smd circle
			(at -0.40005 0 90)
			(size 0 0)
			(layers "F.Cu" "F.Mask" "F.Paste")
			(net "PWRGD_PCH_PWROK_R")
		)
		(pad "2" smd circle
			(at 0.40005 0 90)
			(size 0 0)
			(layers "F.Cu" "F.Mask" "F.Paste")
			(net "GND")
		)
	)
	(footprint ""
		(layer "F.Cu")
		(at 465.036408 -382.750314 90)
		(property "Reference" "PL64"
			(at 0 0 90)
			(layer "F.SilkS")
			(hide yes)
			(effects
				(font
					(size 1.27 1.27)
				)
			)
		)
		(property "Value" ""
			(at 0 0 90)
			(layer "F.Fab")
			(effects
				(font
					(size 1.27 1.27)
				)
			)
		)
		(duplicate_pad_numbers_are_jumpers no)
		(fp_line
			(start -1.27 -0.5842)
			(end 1.27 -0.5842)
			(stroke
				(width 0.1524)
				(type default)
			)
			(layer "F.SilkS")
		)
		(fp_line
			(start -1.27 -0.5588)
			(end -1.27 -0.5842)
			(stroke
				(width 0.1524)
				(type default)
			)
			(layer "F.SilkS")
		)
		(fp_line
			(start 1.27 0.5842)
			(end 1.27 -0.5842)
			(stroke
				(width 0.1524)
				(type default)
			)
			(layer "F.SilkS")
		)
		(fp_line
			(start 1.27 0.5842)
			(end -1.27 0.5842)
			(stroke
				(width 0.1524)
				(type default)
			)
			(layer "F.SilkS")
		)
		(fp_line
			(start 0.127 0.5842)
			(end 0.127 -0.5842)
			(stroke
				(width 0.1524)
				(type default)
			)
			(layer "F.SilkS")
		)
		(fp_line
			(start -0.127 0.5842)
			(end -0.127 -0.5842)
			(stroke
				(width 0.1524)
				(type default)
			)
			(layer "F.SilkS")
		)
		(fp_line
			(start -1.27 0.5842)
			(end -1.27 -0.5842)
			(stroke
				(width 0.1524)
				(type default)
			)
			(layer "F.SilkS")
		)
		(fp_line
			(start 0.9144 -0.508)
			(end 0.9144 -0.406654)
			(stroke
				(width 0.1)
				(type default)
			)
			(layer "F.Fab")
		)
		(fp_line
			(start -0.9144 -0.508)
			(end 0.9144 -0.508)
			(stroke
				(width 0.1)
				(type default)
			)
			(layer "F.Fab")
		)
		(fp_line
			(start 1.1938 -0.406654)
			(end 1.1938 0.4064)
			(stroke
				(width 0.1)
				(type default)
			)
			(layer "F.Fab")
		)
		(fp_line
			(start 0.9144 -0.406654)
			(end 1.1938 -0.406654)
			(stroke
				(width 0.1)
				(type default)
			)
			(layer "F.Fab")
		)
		(fp_line
			(start -0.9144 -0.406654)
			(end -0.9144 -0.508)
			(stroke
				(width 0.1)
				(type default)
			)
			(layer "F.Fab")
		)
		(fp_line
			(start -1.194308 -0.406654)
			(end -0.9144 -0.406654)
			(stroke
				(width 0.1)
				(type default)
			)
			(layer "F.Fab")
		)
		(fp_line
			(start 1.1938 0.4064)
			(end 0.9144 0.4064)
			(stroke
				(width 0.1)
				(type default)
			)
			(layer "F.Fab")
		)
		(fp_line
			(start 0.9144 0.4064)
			(end 0.9144 0.508)
			(stroke
				(width 0.1)
				(type default)
			)
			(layer "F.Fab")
		)
		(fp_line
			(start -0.9144 0.406654)
			(end -1.194308 0.406654)
			(stroke
				(width 0.1)
				(type default)
			)
			(layer "F.Fab")
		)
		(fp_line
			(start -1.194308 0.406654)
			(end -1.194308 -0.406654)
			(stroke
				(width 0.1)
				(type default)
			)
			(layer "F.Fab")
		)
		(fp_line
			(start 0.9144 0.508)
			(end -0.9144 0.508)
			(stroke
				(width 0.1)
				(type default)
			)
			(layer "F.Fab")
		)
		(fp_line
			(start -0.9144 0.508)
			(end -0.9144 0.406654)
			(stroke
				(width 0.1)
				(type default)
			)
			(layer "F.Fab")
		)
		(pad "1" smd rect
			(at -0.7366 0)
			(size 0.7112 0.8128)
			(layers "F.Cu" "F.Mask" "F.Paste")
			(net "P12V_AUX")
		)
		(pad "2" smd rect
			(at 0.7366 0)
			(size 0.7112 0.8128)
			(layers "F.Cu" "F.Mask" "F.Paste")
			(net "SW_P5V_AUX_FLT")
		)
	)
	(footprint ""
		(layer "F.Cu")
		(at 260.731508 5.463794)
		(property "Reference" "J78"
			(at -4.164838 1.013206 90)
			(unlocked yes)
			(layer "F.SilkS")
			(effects
				(font
					(size 0.7874 0.5842)
					(thickness 0.1524)
				)
				(justify left)
			)
		)
		(property "Value" ""
			(at 0 0 0)
			(layer "F.Fab")
			(effects
				(font
					(size 1.27 1.27)
				)
			)
		)
		(duplicate_pad_numbers_are_jumpers no)
		(fp_line
			(start -1.2192 -2.1082)
			(end 1.2192 -2.1082)
			(stroke
				(width 0.1524)
				(type default)
			)
			(layer "F.SilkS")
		)
		(fp_line
			(start -1.2192 2.1082)
			(end -1.2192 -2.1082)
			(stroke
				(width 0.1524)
				(type default)
			)
			(layer "F.SilkS")
		)
		(fp_line
			(start 1.2192 -2.1082)
			(end 1.2192 2.1082)
			(stroke
				(width 0.1524)
				(type default)
			)
			(layer "F.SilkS")
		)
		(fp_line
			(start 1.2192 2.1082)
			(end -1.2192 2.1082)
			(stroke
				(width 0.1524)
				(type default)
			)
			(layer "F.SilkS")
		)
		(pad "" np_thru_hole circle
			(at -2.8829 -1.27 270)
			(size 1.0414 1.0414)
			(drill 1.0414)
			(layers "*.Cu" "*.Mask")
			(clearance 0.381)
			(thermal_gap 0.381)
		)
		(pad "" np_thru_hole circle
			(at -2.8829 1.27 270)
			(size 1.0414 1.0414)
			(drill 1.0414)
			(layers "*.Cu" "*.Mask")
			(clearance 0.381)
			(thermal_gap 0.381)
		)
		(pad "" np_thru_hole circle
			(at 3.4671 -1.27 270)
			(size 1.0414 1.0414)
			(drill 1.0414)
			(layers "*.Cu" "*.Mask")
			(clearance 0.381)
			(thermal_gap 0.381)
		)
		(pad "" np_thru_hole circle
			(at 3.4671 1.27 270)
			(size 1.0414 1.0414)
			(drill 1.0414)
			(layers "*.Cu" "*.Mask")
			(clearance 0.381)
			(thermal_gap 0.381)
		)
		(pad "1" smd rect
			(at 0.8255 -0.249936 270)
			(size 0.3048 0.508)
			(layers "F.Cu" "F.Mask" "F.Paste")
			(net "DELTA_L_85_10INCH_IN2_DP")
		)
		(pad "2" smd rect
			(at 0.8255 0.249936 270)
			(size 0.3048 0.508)
			(layers "F.Cu" "F.Mask" "F.Paste")
			(net "DELTA_L_85_10INCH_IN2_DN")
		)
		(pad "3" smd circle
			(at 0 0)
			(size 0 0)
			(layers "F.Cu" "F.Mask" "F.Paste")
			(net "DELTA_L_GND_1")
		)
		(zone
			(layer "F.Cu")
			(hatch none 0.5)
			(connect_pads
				(clearance 0)
			)
			(min_thickness 0.25)
			(keepout
				(tracks not_allowed)
				(vias allowed)
				(pads allowed)
				(copperpour not_allowed)
				(footprints allowed)
			)
			(placement
				(enabled no)
				(sheetname "")
			)
			(fill
				(thermal_gap 0.5)
				(thermal_bridge_width 0.5)
				(island_removal_mode 0)
			)
			(polygon
				(pts
					(xy 261.849108 4.915154) (xy 261.849108 5.010658) (xy 261.252208 5.010658) (xy 261.252208 5.417058)
					(xy 261.849108 5.417058) (xy 261.849108 5.51053) (xy 261.252208 5.51053) (xy 261.252208 5.91693)
					(xy 261.849108 5.91693) (xy 261.849108 6.012434) (xy 261.150608 6.012434) (xy 261.150608 4.915154)
				)
			)
		)
		(zone
			(layers "F.Cu" "B.Cu" "In1.Cu" "In2.Cu" "In3.Cu" "In4.Cu" "In5.Cu" "In6.Cu"
				"In7.Cu" "In8.Cu" "In9.Cu" "In10.Cu" "In11.Cu" "In12.Cu" "In13.Cu" "In14.Cu"
				"In15.Cu" "In16.Cu"
			)
			(hatch none 0.5)
			(connect_pads
				(clearance 0)
			)
			(min_thickness 0.25)
			(keepout
				(tracks not_allowed)
				(vias allowed)
				(pads allowed)
				(copperpour not_allowed)
				(footprints allowed)
			)
			(placement
				(enabled no)
				(sheetname "")
			)
			(fill
				(thermal_gap 0.5)
				(thermal_bridge_width 0.5)
				(island_removal_mode 0)
			)
			(polygon
				(pts
					(arc
						(start 258.775708 4.193794)
						(mid 256.921508 4.193794)
						(end 258.775708 4.193794)
					)
				)
			)
		)
		(zone
			(layers "F.Cu" "B.Cu" "In1.Cu" "In2.Cu" "In3.Cu" "In4.Cu" "In5.Cu" "In6.Cu"
				"In7.Cu" "In8.Cu" "In9.Cu" "In10.Cu" "In11.Cu" "In12.Cu" "In13.Cu" "In14.Cu"
				"In15.Cu" "In16.Cu"
			)
			(hatch none 0.5)
			(connect_pads
				(clearance 0)
			)
			(min_thickness 0.25)
			(keepout
				(tracks not_allowed)
				(vias allowed)
				(pads allowed)
				(copperpour not_allowed)
				(footprints allowed)
			)
			(placement
				(enabled no)
				(sheetname "")
			)
			(fill
				(thermal_gap 0.5)
				(thermal_bridge_width 0.5)
				(island_removal_mode 0)
			)
			(polygon
				(pts
					(arc
						(start 258.775708 6.733794)
						(mid 256.921508 6.733794)
						(end 258.775708 6.733794)
					)
				)
			)
		)
		(zone
			(layers "F.Cu" "B.Cu" "In1.Cu" "In2.Cu" "In3.Cu" "In4.Cu" "In5.Cu" "In6.Cu"
				"In7.Cu" "In8.Cu" "In9.Cu" "In10.Cu" "In11.Cu" "In12.Cu" "In13.Cu" "In14.Cu"
				"In15.Cu" "In16.Cu"
			)
			(hatch none 0.5)
			(connect_pads
				(clearance 0)
			)
			(min_thickness 0.25)
			(keepout
				(tracks not_allowed)
				(vias allowed)
				(pads allowed)
				(copperpour not_allowed)
				(footprints allowed)
			)
			(placement
				(enabled no)
				(sheetname "")
			)
			(fill
				(thermal_gap 0.5)
				(thermal_bridge_width 0.5)
				(island_removal_mode 0)
			)
			(polygon
				(pts
					(arc
						(start 265.125708 4.193794)
						(mid 263.271508 4.193794)
						(end 265.125708 4.193794)
					)
				)
			)
		)
		(zone
			(layers "F.Cu" "B.Cu" "In1.Cu" "In2.Cu" "In3.Cu" "In4.Cu" "In5.Cu" "In6.Cu"
				"In7.Cu" "In8.Cu" "In9.Cu" "In10.Cu" "In11.Cu" "In12.Cu" "In13.Cu" "In14.Cu"
				"In15.Cu" "In16.Cu"
			)
			(hatch none 0.5)
			(connect_pads
				(clearance 0)
			)
			(min_thickness 0.25)
			(keepout
				(tracks not_allowed)
				(vias allowed)
				(pads allowed)
				(copperpour not_allowed)
				(footprints allowed)
			)
			(placement
				(enabled no)
				(sheetname "")
			)
			(fill
				(thermal_gap 0.5)
				(thermal_bridge_width 0.5)
				(island_removal_mode 0)
			)
			(polygon
				(pts
					(arc
						(start 265.125708 6.733794)
						(mid 263.271508 6.733794)
						(end 265.125708 6.733794)
					)
				)
			)
		)
	)
	(footprint ""
		(layer "F.Cu")
		(at 294.045894 -415.00552)
		(property "Reference" "R4687"
			(at 0 0 0)
			(layer "F.SilkS")
			(hide yes)
			(effects
				(font
					(size 1.27 1.27)
				)
			)
		)
		(property "Value" ""
			(at 0 0 0)
			(layer "F.Fab")
			(effects
				(font
					(size 1.27 1.27)
				)
			)
		)
		(duplicate_pad_numbers_are_jumpers no)
		(fp_line
			(start -0.7874 -0.4064)
			(end 0.7874 -0.4064)
			(stroke
				(width 0.1524)
				(type default)
			)
			(layer "F.SilkS")
		)
		(fp_line
			(start -0.7874 0.4064)
			(end -0.7874 -0.4064)
			(stroke
				(width 0.1524)
				(type default)
			)
			(layer "F.SilkS")
		)
		(fp_line
			(start 0.7874 -0.4064)
			(end 0.7874 0.4064)
			(stroke
				(width 0.1524)
				(type default)
			)
			(layer "F.SilkS")
		)
		(fp_line
			(start 0.7874 0.4064)
			(end -0.7874 0.4064)
			(stroke
				(width 0.1524)
				(type default)
			)
			(layer "F.SilkS")
		)
		(fp_line
			(start -0.67945 -0.305054)
			(end -0.12065 -0.305054)
			(stroke
				(width 0.1)
				(type default)
			)
			(layer "F.Fab")
		)
		(fp_line
			(start -0.67945 0.3048)
			(end -0.67945 -0.305054)
			(stroke
				(width 0.1)
				(type default)
			)
			(layer "F.Fab")
		)
		(fp_line
			(start -0.12065 -0.305054)
			(end -0.12065 -0.2794)
			(stroke
				(width 0.1)
				(type default)
			)
			(layer "F.Fab")
		)
		(fp_line
			(start -0.12065 -0.2794)
			(end 0.12065 -0.2794)
			(stroke
				(width 0.1)
				(type default)
			)
			(layer "F.Fab")
		)
		(fp_line
			(start -0.12065 0.2794)
			(end -0.12065 0.3048)
			(stroke
				(width 0.1)
				(type default)
			)
			(layer "F.Fab")
		)
		(fp_line
			(start -0.12065 0.3048)
			(end -0.67945 0.3048)
			(stroke
				(width 0.1)
				(type default)
			)
			(layer "F.Fab")
		)
		(fp_line
			(start 0.120396 0.2794)
			(end -0.12065 0.2794)
			(stroke
				(width 0.1)
				(type default)
			)
			(layer "F.Fab")
		)
		(fp_line
			(start 0.120396 0.3048)
			(end 0.120396 0.2794)
			(stroke
				(width 0.1)
				(type default)
			)
			(layer "F.Fab")
		)
		(fp_line
			(start 0.12065 -0.3048)
			(end 0.67945 -0.3048)
			(stroke
				(width 0.1)
				(type default)
			)
			(layer "F.Fab")
		)
		(fp_line
			(start 0.12065 -0.2794)
			(end 0.12065 -0.3048)
			(stroke
				(width 0.1)
				(type default)
			)
			(layer "F.Fab")
		)
		(fp_line
			(start 0.67945 -0.3048)
			(end 0.67945 0.3048)
			(stroke
				(width 0.1)
				(type default)
			)
			(layer "F.Fab")
		)
		(fp_line
			(start 0.67945 0.3048)
			(end 0.120396 0.3048)
			(stroke
				(width 0.1)
				(type default)
			)
			(layer "F.Fab")
		)
		(pad "1" smd circle
			(at -0.40005 0)
			(size 0 0)
			(layers "F.Cu" "F.Mask" "F.Paste")
			(net "GND")
		)
		(pad "2" smd circle
			(at 0.40005 0)
			(size 0 0)
			(layers "F.Cu" "F.Mask" "F.Paste")
			(net "HSC_TYPE_ADC_A1")
		)
	)
	(footprint ""
		(layer "F.Cu")
		(at 178.960272 -358.135936 -90)
		(property "Reference" "PC1369"
			(at 0 0 270)
			(layer "F.SilkS")
			(hide yes)
			(effects
				(font
					(size 1.27 1.27)
				)
			)
		)
		(property "Value" ""
			(at 0 0 270)
			(layer "F.Fab")
			(effects
				(font
					(size 1.27 1.27)
				)
			)
		)
		(duplicate_pad_numbers_are_jumpers no)
		(fp_line
			(start -0.7874 0.4064)
			(end -0.7874 -0.4064)
			(stroke
				(width 0.1524)
				(type default)
			)
			(layer "F.SilkS")
		)
		(fp_line
			(start 0.7874 0.4064)
			(end -0.7874 0.4064)
			(stroke
				(width 0.1524)
				(type default)
			)
			(layer "F.SilkS")
		)
		(fp_line
			(start -0.7874 -0.4064)
			(end 0.7874 -0.4064)
			(stroke
				(width 0.1524)
				(type default)
			)
			(layer "F.SilkS")
		)
		(fp_line
			(start 0.7874 -0.4064)
			(end 0.7874 0.4064)
			(stroke
				(width 0.1524)
				(type default)
			)
			(layer "F.SilkS")
		)
		(fp_line
			(start -0.67945 0.3048)
			(end -0.67945 -0.305054)
			(stroke
				(width 0.1)
				(type default)
			)
			(layer "F.Fab")
		)
		(fp_line
			(start -0.12065 0.3048)
			(end -0.67945 0.3048)
			(stroke
				(width 0.1)
				(type default)
			)
			(layer "F.Fab")
		)
		(fp_line
			(start 0.120396 0.3048)
			(end 0.120396 0.2794)
			(stroke
				(width 0.1)
				(type default)
			)
			(layer "F.Fab")
		)
		(fp_line
			(start 0.67945 0.3048)
			(end 0.120396 0.3048)
			(stroke
				(width 0.1)
				(type default)
			)
			(layer "F.Fab")
		)
		(fp_line
			(start -0.12065 0.2794)
			(end -0.12065 0.3048)
			(stroke
				(width 0.1)
				(type default)
			)
			(layer "F.Fab")
		)
		(fp_line
			(start 0.120396 0.2794)
			(end -0.12065 0.2794)
			(stroke
				(width 0.1)
				(type default)
			)
			(layer "F.Fab")
		)
		(fp_line
			(start -0.12065 -0.2794)
			(end 0.12065 -0.2794)
			(stroke
				(width 0.1)
				(type default)
			)
			(layer "F.Fab")
		)
		(fp_line
			(start 0.12065 -0.2794)
			(end 0.12065 -0.3048)
			(stroke
				(width 0.1)
				(type default)
			)
			(layer "F.Fab")
		)
		(fp_line
			(start 0.12065 -0.3048)
			(end 0.67945 -0.3048)
			(stroke
				(width 0.1)
				(type default)
			)
			(layer "F.Fab")
		)
		(fp_line
			(start 0.67945 -0.3048)
			(end 0.67945 0.3048)
			(stroke
				(width 0.1)
				(type default)
			)
			(layer "F.Fab")
		)
		(fp_line
			(start -0.67945 -0.305054)
			(end -0.12065 -0.305054)
			(stroke
				(width 0.1)
				(type default)
			)
			(layer "F.Fab")
		)
		(fp_line
			(start -0.12065 -0.305054)
			(end -0.12065 -0.2794)
			(stroke
				(width 0.1)
				(type default)
			)
			(layer "F.Fab")
		)
		(pad "1" smd circle
			(at -0.40005 0 270)
			(size 0 0)
			(layers "F.Cu" "F.Mask" "F.Paste")
			(net "GND")
		)
		(pad "2" smd circle
			(at 0.40005 0 270)
			(size 0 0)
			(layers "F.Cu" "F.Mask" "F.Paste")
			(net "PVCCIN_CPU1_VREF")
		)
	)
	(footprint ""
		(layer "F.Cu")
		(at 94.045278 -93.063314)
		(property "Reference" "Q98"
			(at 0.57658 1.975612 0)
			(unlocked yes)
			(layer "F.SilkS")
			(effects
				(font
					(size 0.7874 0.5842)
					(thickness 0.1524)
				)
			)
		)
		(property "Value" ""
			(at 0 0 0)
			(layer "F.Fab")
			(effects
				(font
					(size 1.27 1.27)
				)
			)
		)
		(duplicate_pad_numbers_are_jumpers no)
		(fp_line
			(start -1.376172 -1.199896)
			(end -0.508 -1.199896)
			(stroke
				(width 0.1524)
				(type default)
			)
			(layer "F.SilkS")
		)
		(fp_line
			(start -1.376172 1.199896)
			(end -1.376172 -1.199896)
			(stroke
				(width 0.1524)
				(type default)
			)
			(layer "F.SilkS")
		)
		(fp_line
			(start -0.508 -1.199896)
			(end 0 -0.762)
			(stroke
				(width 0.1524)
				(type default)
			)
			(layer "F.SilkS")
		)
		(fp_line
			(start 0 -0.762)
			(end 0.508 -1.199896)
			(stroke
				(width 0.1524)
				(type default)
			)
			(layer "F.SilkS")
		)
		(fp_line
			(start 0.508 -1.199896)
			(end 1.376172 -1.199896)
			(stroke
				(width 0.1524)
				(type default)
			)
			(layer "F.SilkS")
		)
		(fp_line
			(start 1.376172 -1.199896)
			(end 1.376172 1.199896)
			(stroke
				(width 0.1524)
				(type default)
			)
			(layer "F.SilkS")
		)
		(fp_line
			(start 1.376172 1.199896)
			(end -1.376172 1.199896)
			(stroke
				(width 0.1524)
				(type default)
			)
			(layer "F.SilkS")
		)
		(fp_poly
			(pts
				(xy -1.4605 -0.7493) (xy -2.2225 -0.3683) (xy -2.2225 -1.1303)
			)
			(stroke
				(width 0)
				(type default)
			)
			(fill yes)
			(layer "F.SilkS")
		)
		(fp_line
			(start -0.674878 -1.100074)
			(end 0.674878 -1.100074)
			(stroke
				(width 0.1)
				(type default)
			)
			(layer "F.Fab")
		)
		(fp_line
			(start -0.674878 1.100074)
			(end -0.674878 -1.100074)
			(stroke
				(width 0.1)
				(type default)
			)
			(layer "F.Fab")
		)
		(fp_line
			(start 0.674878 -1.100074)
			(end 0.674878 1.100074)
			(stroke
				(width 0.1)
				(type default)
			)
			(layer "F.Fab")
		)
		(fp_line
			(start 0.674878 1.100074)
			(end -0.674878 1.100074)
			(stroke
				(width 0.1)
				(type default)
			)
			(layer "F.Fab")
		)
		(fp_poly
			(pts
				(xy -1.4605 -0.7493) (xy -2.2225 -1.1303) (xy -2.2225 -0.3683)
			)
			(stroke
				(width 0)
				(type default)
			)
			(fill yes)
			(layer "F.Fab")
		)
		(pad "1" smd rect
			(at -0.899922 -0.750062 270)
			(size 0.6096 0.6096)
			(layers "F.Cu" "F.Mask" "F.Paste")
			(net "GND")
		)
		(pad "2" smd rect
			(at -0.899922 0 270)
			(size 0.4064 0.6096)
			(layers "F.Cu" "F.Mask" "F.Paste")
			(net "RST_PLD_CPU0_DRAM_AB_N")
		)
		(pad "3" smd rect
			(at -0.899922 0.750062 270)
			(size 0.6096 0.6096)
			(layers "F.Cu" "F.Mask" "F.Paste")
			(net "LED_RST_PLD_CPU0_DRAM_CD_N_D")
		)
		(pad "4" smd rect
			(at 0.899922 0.750062 270)
			(size 0.6096 0.6096)
			(layers "F.Cu" "F.Mask" "F.Paste")
			(net "GND")
		)
		(pad "5" smd rect
			(at 0.899922 0 270)
			(size 0.4064 0.6096)
			(layers "F.Cu" "F.Mask" "F.Paste")
			(net "RST_PLD_CPU0_DRAM_CD_N")
		)
		(pad "6" smd rect
			(at 0.899922 -0.750062 270)
			(size 0.6096 0.6096)
			(layers "F.Cu" "F.Mask" "F.Paste")
			(net "LED_RST_PLD_CPU0_DRAM_AB_N_D")
		)
	)
	(footprint ""
		(layer "F.Cu")
		(at 279.40762 -425.69638)
		(property "Reference" "C2393"
			(at 0 0 0)
			(layer "F.SilkS")
			(hide yes)
			(effects
				(font
					(size 1.27 1.27)
				)
			)
		)
		(property "Value" ""
			(at 0 0 0)
			(layer "F.Fab")
			(effects
				(font
					(size 1.27 1.27)
				)
			)
		)
		(duplicate_pad_numbers_are_jumpers no)
		(fp_line
			(start -0.7874 -0.4064)
			(end 0.7874 -0.4064)
			(stroke
				(width 0.1524)
				(type default)
			)
			(layer "F.SilkS")
		)
		(fp_line
			(start -0.7874 0.4064)
			(end -0.7874 -0.4064)
			(stroke
				(width 0.1524)
				(type default)
			)
			(layer "F.SilkS")
		)
		(fp_line
			(start 0.7874 -0.4064)
			(end 0.7874 0.4064)
			(stroke
				(width 0.1524)
				(type default)
			)
			(layer "F.SilkS")
		)
		(fp_line
			(start 0.7874 0.4064)
			(end -0.7874 0.4064)
			(stroke
				(width 0.1524)
				(type default)
			)
			(layer "F.SilkS")
		)
		(fp_line
			(start -0.67945 -0.305054)
			(end -0.12065 -0.305054)
			(stroke
				(width 0.1)
				(type default)
			)
			(layer "F.Fab")
		)
		(fp_line
			(start -0.67945 0.3048)
			(end -0.67945 -0.305054)
			(stroke
				(width 0.1)
				(type default)
			)
			(layer "F.Fab")
		)
		(fp_line
			(start -0.12065 -0.305054)
			(end -0.12065 -0.2794)
			(stroke
				(width 0.1)
				(type default)
			)
			(layer "F.Fab")
		)
		(fp_line
			(start -0.12065 -0.2794)
			(end 0.12065 -0.2794)
			(stroke
				(width 0.1)
				(type default)
			)
			(layer "F.Fab")
		)
		(fp_line
			(start -0.12065 0.2794)
			(end -0.12065 0.3048)
			(stroke
				(width 0.1)
				(type default)
			)
			(layer "F.Fab")
		)
		(fp_line
			(start -0.12065 0.3048)
			(end -0.67945 0.3048)
			(stroke
				(width 0.1)
				(type default)
			)
			(layer "F.Fab")
		)
		(fp_line
			(start 0.120396 0.2794)
			(end -0.12065 0.2794)
			(stroke
				(width 0.1)
				(type default)
			)
			(layer "F.Fab")
		)
		(fp_line
			(start 0.120396 0.3048)
			(end 0.120396 0.2794)
			(stroke
				(width 0.1)
				(type default)
			)
			(layer "F.Fab")
		)
		(fp_line
			(start 0.12065 -0.3048)
			(end 0.67945 -0.3048)
			(stroke
				(width 0.1)
				(type default)
			)
			(layer "F.Fab")
		)
		(fp_line
			(start 0.12065 -0.2794)
			(end 0.12065 -0.3048)
			(stroke
				(width 0.1)
				(type default)
			)
			(layer "F.Fab")
		)
		(fp_line
			(start 0.67945 -0.3048)
			(end 0.67945 0.3048)
			(stroke
				(width 0.1)
				(type default)
			)
			(layer "F.Fab")
		)
		(fp_line
			(start 0.67945 0.3048)
			(end 0.120396 0.3048)
			(stroke
				(width 0.1)
				(type default)
			)
			(layer "F.Fab")
		)
		(pad "1" smd circle
			(at -0.40005 0)
			(size 0 0)
			(layers "F.Cu" "F.Mask" "F.Paste")
			(net "U369_VDD")
		)
		(pad "2" smd circle
			(at 0.40005 0)
			(size 0 0)
			(layers "F.Cu" "F.Mask" "F.Paste")
			(net "GND")
		)
	)
	(footprint ""
		(layer "F.Cu")
		(at 446.675002 -77.829918 90)
		(property "Reference" "PR832"
			(at 0 0 90)
			(layer "F.SilkS")
			(hide yes)
			(effects
				(font
					(size 1.27 1.27)
				)
			)
		)
		(property "Value" ""
			(at 0 0 90)
			(layer "F.Fab")
			(effects
				(font
					(size 1.27 1.27)
				)
			)
		)
		(duplicate_pad_numbers_are_jumpers no)
		(fp_line
			(start 0.7874 -0.4064)
			(end 0.7874 0.4064)
			(stroke
				(width 0.1524)
				(type default)
			)
			(layer "F.SilkS")
		)
		(fp_line
			(start -0.7874 -0.4064)
			(end 0.7874 -0.4064)
			(stroke
				(width 0.1524)
				(type default)
			)
			(layer "F.SilkS")
		)
		(fp_line
			(start 0.7874 0.4064)
			(end -0.7874 0.4064)
			(stroke
				(width 0.1524)
				(type default)
			)
			(layer "F.SilkS")
		)
		(fp_line
			(start -0.7874 0.4064)
			(end -0.7874 -0.4064)
			(stroke
				(width 0.1524)
				(type default)
			)
			(layer "F.SilkS")
		)
		(fp_line
			(start -0.12065 -0.305054)
			(end -0.12065 -0.2794)
			(stroke
				(width 0.1)
				(type default)
			)
			(layer "F.Fab")
		)
		(fp_line
			(start -0.67945 -0.305054)
			(end -0.12065 -0.305054)
			(stroke
				(width 0.1)
				(type default)
			)
			(layer "F.Fab")
		)
		(fp_line
			(start 0.67945 -0.3048)
			(end 0.67945 0.3048)
			(stroke
				(width 0.1)
				(type default)
			)
			(layer "F.Fab")
		)
		(fp_line
			(start 0.12065 -0.3048)
			(end 0.67945 -0.3048)
			(stroke
				(width 0.1)
				(type default)
			)
			(layer "F.Fab")
		)
		(fp_line
			(start 0.12065 -0.2794)
			(end 0.12065 -0.3048)
			(stroke
				(width 0.1)
				(type default)
			)
			(layer "F.Fab")
		)
		(fp_line
			(start -0.12065 -0.2794)
			(end 0.12065 -0.2794)
			(stroke
				(width 0.1)
				(type default)
			)
			(layer "F.Fab")
		)
		(fp_line
			(start 0.120396 0.2794)
			(end -0.12065 0.2794)
			(stroke
				(width 0.1)
				(type default)
			)
			(layer "F.Fab")
		)
		(fp_line
			(start -0.12065 0.2794)
			(end -0.12065 0.3048)
			(stroke
				(width 0.1)
				(type default)
			)
			(layer "F.Fab")
		)
		(fp_line
			(start 0.67945 0.3048)
			(end 0.120396 0.3048)
			(stroke
				(width 0.1)
				(type default)
			)
			(layer "F.Fab")
		)
		(fp_line
			(start 0.120396 0.3048)
			(end 0.120396 0.2794)
			(stroke
				(width 0.1)
				(type default)
			)
			(layer "F.Fab")
		)
		(fp_line
			(start -0.12065 0.3048)
			(end -0.67945 0.3048)
			(stroke
				(width 0.1)
				(type default)
			)
			(layer "F.Fab")
		)
		(fp_line
			(start -0.67945 0.3048)
			(end -0.67945 -0.305054)
			(stroke
				(width 0.1)
				(type default)
			)
			(layer "F.Fab")
		)
		(pad "1" smd circle
			(at -0.40005 0 90)
			(size 0 0)
			(layers "F.Cu" "F.Mask" "F.Paste")
			(net "P3V3_AUX_MODE")
		)
		(pad "2" smd circle
			(at 0.40005 0 90)
			(size 0 0)
			(layers "F.Cu" "F.Mask" "F.Paste")
			(net "GND")
		)
	)
	(footprint ""
		(layer "F.Cu")
		(at 27.0383 -129.380996 180)
		(property "Reference" "PC467"
			(at 0 0 180)
			(layer "F.SilkS")
			(hide yes)
			(effects
				(font
					(size 1.27 1.27)
				)
			)
		)
		(property "Value" ""
			(at 0 0 180)
			(layer "F.Fab")
			(effects
				(font
					(size 1.27 1.27)
				)
			)
		)
		(duplicate_pad_numbers_are_jumpers no)
		(fp_line
			(start 0.7874 0.4064)
			(end -0.7874 0.4064)
			(stroke
				(width 0.1524)
				(type default)
			)
			(layer "F.SilkS")
		)
		(fp_line
			(start 0.7874 -0.4064)
			(end 0.7874 0.4064)
			(stroke
				(width 0.1524)
				(type default)
			)
			(layer "F.SilkS")
		)
		(fp_line
			(start -0.7874 0.4064)
			(end -0.7874 -0.4064)
			(stroke
				(width 0.1524)
				(type default)
			)
			(layer "F.SilkS")
		)
		(fp_line
			(start -0.7874 -0.4064)
			(end 0.7874 -0.4064)
			(stroke
				(width 0.1524)
				(type default)
			)
			(layer "F.SilkS")
		)
		(fp_line
			(start 0.67945 0.3048)
			(end 0.120396 0.3048)
			(stroke
				(width 0.1)
				(type default)
			)
			(layer "F.Fab")
		)
		(fp_line
			(start 0.67945 -0.3048)
			(end 0.67945 0.3048)
			(stroke
				(width 0.1)
				(type default)
			)
			(layer "F.Fab")
		)
		(fp_line
			(start 0.12065 -0.2794)
			(end 0.12065 -0.3048)
			(stroke
				(width 0.1)
				(type default)
			)
			(layer "F.Fab")
		)
		(fp_line
			(start 0.12065 -0.3048)
			(end 0.67945 -0.3048)
			(stroke
				(width 0.1)
				(type default)
			)
			(layer "F.Fab")
		)
		(fp_line
			(start 0.120396 0.3048)
			(end 0.120396 0.2794)
			(stroke
				(width 0.1)
				(type default)
			)
			(layer "F.Fab")
		)
		(fp_line
			(start 0.120396 0.2794)
			(end -0.12065 0.2794)
			(stroke
				(width 0.1)
				(type default)
			)
			(layer "F.Fab")
		)
		(fp_line
			(start -0.12065 0.3048)
			(end -0.67945 0.3048)
			(stroke
				(width 0.1)
				(type default)
			)
			(layer "F.Fab")
		)
		(fp_line
			(start -0.12065 0.2794)
			(end -0.12065 0.3048)
			(stroke
				(width 0.1)
				(type default)
			)
			(layer "F.Fab")
		)
		(fp_line
			(start -0.12065 -0.2794)
			(end 0.12065 -0.2794)
			(stroke
				(width 0.1)
				(type default)
			)
			(layer "F.Fab")
		)
		(fp_line
			(start -0.12065 -0.305054)
			(end -0.12065 -0.2794)
			(stroke
				(width 0.1)
				(type default)
			)
			(layer "F.Fab")
		)
		(fp_line
			(start -0.67945 0.3048)
			(end -0.67945 -0.305054)
			(stroke
				(width 0.1)
				(type default)
			)
			(layer "F.Fab")
		)
		(fp_line
			(start -0.67945 -0.305054)
			(end -0.12065 -0.305054)
			(stroke
				(width 0.1)
				(type default)
			)
			(layer "F.Fab")
		)
		(pad "1" smd circle
			(at -0.40005 0 180)
			(size 0 0)
			(layers "F.Cu" "F.Mask" "F.Paste")
			(net "PVCCINFAON_CPU1_CSPIN")
		)
		(pad "2" smd circle
			(at 0.40005 0 180)
			(size 0 0)
			(layers "F.Cu" "F.Mask" "F.Paste")
			(net "GND")
		)
	)
	(footprint ""
		(layer "F.Cu")
		(at 116.561616 -260.36524 -90)
		(property "Reference" "C439"
			(at 0 0 270)
			(layer "F.SilkS")
			(hide yes)
			(effects
				(font
					(size 1.27 1.27)
				)
			)
		)
		(property "Value" ""
			(at 0 0 270)
			(layer "F.Fab")
			(effects
				(font
					(size 1.27 1.27)
				)
			)
		)
		(duplicate_pad_numbers_are_jumpers no)
		(fp_line
			(start -0.7874 0.4064)
			(end -0.7874 -0.4064)
			(stroke
				(width 0.1524)
				(type default)
			)
			(layer "F.SilkS")
		)
		(fp_line
			(start 0.7874 0.4064)
			(end -0.7874 0.4064)
			(stroke
				(width 0.1524)
				(type default)
			)
			(layer "F.SilkS")
		)
		(fp_line
			(start -0.7874 -0.4064)
			(end 0.7874 -0.4064)
			(stroke
				(width 0.1524)
				(type default)
			)
			(layer "F.SilkS")
		)
		(fp_line
			(start 0.7874 -0.4064)
			(end 0.7874 0.4064)
			(stroke
				(width 0.1524)
				(type default)
			)
			(layer "F.SilkS")
		)
		(fp_line
			(start -0.67945 0.3048)
			(end -0.67945 -0.305054)
			(stroke
				(width 0.1)
				(type default)
			)
			(layer "F.Fab")
		)
		(fp_line
			(start -0.12065 0.3048)
			(end -0.67945 0.3048)
			(stroke
				(width 0.1)
				(type default)
			)
			(layer "F.Fab")
		)
		(fp_line
			(start 0.120396 0.3048)
			(end 0.120396 0.2794)
			(stroke
				(width 0.1)
				(type default)
			)
			(layer "F.Fab")
		)
		(fp_line
			(start 0.67945 0.3048)
			(end 0.120396 0.3048)
			(stroke
				(width 0.1)
				(type default)
			)
			(layer "F.Fab")
		)
		(fp_line
			(start -0.12065 0.2794)
			(end -0.12065 0.3048)
			(stroke
				(width 0.1)
				(type default)
			)
			(layer "F.Fab")
		)
		(fp_line
			(start 0.120396 0.2794)
			(end -0.12065 0.2794)
			(stroke
				(width 0.1)
				(type default)
			)
			(layer "F.Fab")
		)
		(fp_line
			(start -0.12065 -0.2794)
			(end 0.12065 -0.2794)
			(stroke
				(width 0.1)
				(type default)
			)
			(layer "F.Fab")
		)
		(fp_line
			(start 0.12065 -0.2794)
			(end 0.12065 -0.3048)
			(stroke
				(width 0.1)
				(type default)
			)
			(layer "F.Fab")
		)
		(fp_line
			(start 0.12065 -0.3048)
			(end 0.67945 -0.3048)
			(stroke
				(width 0.1)
				(type default)
			)
			(layer "F.Fab")
		)
		(fp_line
			(start 0.67945 -0.3048)
			(end 0.67945 0.3048)
			(stroke
				(width 0.1)
				(type default)
			)
			(layer "F.Fab")
		)
		(fp_line
			(start -0.67945 -0.305054)
			(end -0.12065 -0.305054)
			(stroke
				(width 0.1)
				(type default)
			)
			(layer "F.Fab")
		)
		(fp_line
			(start -0.12065 -0.305054)
			(end -0.12065 -0.2794)
			(stroke
				(width 0.1)
				(type default)
			)
			(layer "F.Fab")
		)
		(pad "1" smd circle
			(at -0.40005 0 270)
			(size 0 0)
			(layers "F.Cu" "F.Mask" "F.Paste")
			(net "PVCCFA_EHV_FIVRA_CPU1")
		)
		(pad "2" smd circle
			(at 0.40005 0 270)
			(size 0 0)
			(layers "F.Cu" "F.Mask" "F.Paste")
			(net "GND")
		)
	)
	(footprint ""
		(layer "F.Cu")
		(at 483.383844 -334.829912 180)
		(property "Reference" "DB9"
			(at -2.448052 0.158496 90)
			(unlocked yes)
			(layer "F.SilkS")
			(effects
				(font
					(size 0.7874 0.5842)
					(thickness 0.1524)
				)
				(justify left)
			)
		)
		(property "Value" ""
			(at 0 0 180)
			(layer "F.Fab")
			(effects
				(font
					(size 1.27 1.27)
				)
			)
		)
		(duplicate_pad_numbers_are_jumpers no)
		(fp_line
			(start 3.330702 -4.771136)
			(end 0 4.011168)
			(stroke
				(width 0.1524)
				(type default)
			)
			(layer "F.SilkS")
		)
		(fp_line
			(start 0 4.011168)
			(end -3.330702 -4.771136)
			(stroke
				(width 0.1524)
				(type default)
			)
			(layer "F.SilkS")
		)
		(fp_line
			(start -3.330702 -4.771136)
			(end 3.330702 -4.771136)
			(stroke
				(width 0.1524)
				(type default)
			)
			(layer "F.SilkS")
		)
		(fp_line
			(start 3.330702 -4.771136)
			(end 0 4.011168)
			(stroke
				(width 0.1)
				(type default)
			)
			(layer "F.Fab")
		)
		(fp_line
			(start 0 4.011168)
			(end -3.330702 -4.771136)
			(stroke
				(width 0.1)
				(type default)
			)
			(layer "F.Fab")
		)
		(fp_line
			(start -3.330702 -4.771136)
			(end 3.330702 -4.771136)
			(stroke
				(width 0.1)
				(type default)
			)
			(layer "F.Fab")
		)
		(pad "1" thru_hole circle
			(at 0 0 180)
			(size 2.159 2.159)
			(drill 1.7018)
			(layers "*.Cu" "*.Mask")
			(remove_unused_layers no)
			(net "T1_GND")
			(clearance 0.0254)
			(thermal_gap 0.0254)
		)
		(pad "2" thru_hole circle
			(at -1.27 -3.348736 180)
			(size 2.159 2.159)
			(drill 1.7018)
			(layers "*.Cu" "*.Mask")
			(remove_unused_layers no)
			(net "TDR_SE_50_OHM_IN2")
			(clearance 0.0254)
			(thermal_gap 0.0254)
		)
		(pad "3" thru_hole circle
			(at 1.27 -3.348736 180)
			(size 2.159 2.159)
			(drill 1.7018)
			(layers "*.Cu" "*.Mask")
			(remove_unused_layers no)
			(net "TDR_SE_50_OHM_IN2")
			(clearance 0.0254)
			(thermal_gap 0.0254)
		)
	)
	(footprint ""
		(layer "F.Cu")
		(at 133.65988 -103.723948 -90)
		(property "Reference" "Q140"
			(at -0.035052 -2.76479 90)
			(unlocked yes)
			(layer "F.SilkS")
			(effects
				(font
					(size 0.7874 0.5842)
					(thickness 0.1524)
				)
			)
		)
		(property "Value" ""
			(at 0 0 270)
			(layer "F.Fab")
			(effects
				(font
					(size 1.27 1.27)
				)
			)
		)
		(duplicate_pad_numbers_are_jumpers no)
		(fp_line
			(start -1.376172 1.199896)
			(end -1.376172 -1.199896)
			(stroke
				(width 0.1524)
				(type default)
			)
			(layer "F.SilkS")
		)
		(fp_line
			(start 1.376172 1.199896)
			(end -1.376172 1.199896)
			(stroke
				(width 0.1524)
				(type default)
			)
			(layer "F.SilkS")
		)
		(fp_line
			(start 0 -0.762)
			(end 0.508 -1.199896)
			(stroke
				(width 0.1524)
				(type default)
			)
			(layer "F.SilkS")
		)
		(fp_line
			(start -1.376172 -1.199896)
			(end -0.508 -1.199896)
			(stroke
				(width 0.1524)
				(type default)
			)
			(layer "F.SilkS")
		)
		(fp_line
			(start -0.508 -1.199896)
			(end 0 -0.762)
			(stroke
				(width 0.1524)
				(type default)
			)
			(layer "F.SilkS")
		)
		(fp_line
			(start 0.508 -1.199896)
			(end 1.376172 -1.199896)
			(stroke
				(width 0.1524)
				(type default)
			)
			(layer "F.SilkS")
		)
		(fp_line
			(start 1.376172 -1.199896)
			(end 1.376172 1.199896)
			(stroke
				(width 0.1524)
				(type default)
			)
			(layer "F.SilkS")
		)
		(fp_poly
			(pts
				(xy -0.880872 -1.369568) (xy -0.499872 -2.131568) (xy -1.261872 -2.131568)
			)
			(stroke
				(width 0)
				(type default)
			)
			(fill yes)
			(layer "F.SilkS")
		)
		(fp_line
			(start -0.674878 1.100074)
			(end -0.674878 -1.100074)
			(stroke
				(width 0.1)
				(type default)
			)
			(layer "F.Fab")
		)
		(fp_line
			(start 0.674878 1.100074)
			(end -0.674878 1.100074)
			(stroke
				(width 0.1)
				(type default)
			)
			(layer "F.Fab")
		)
		(fp_line
			(start -0.674878 -1.100074)
			(end 0.674878 -1.100074)
			(stroke
				(width 0.1)
				(type default)
			)
			(layer "F.Fab")
		)
		(fp_line
			(start 0.674878 -1.100074)
			(end 0.674878 1.100074)
			(stroke
				(width 0.1)
				(type default)
			)
			(layer "F.Fab")
		)
		(fp_poly
			(pts
				(xy -1.4605 -0.7493) (xy -2.2225 -1.1303) (xy -2.2225 -0.3683)
			)
			(stroke
				(width 0)
				(type default)
			)
			(fill yes)
			(layer "F.Fab")
		)
		(pad "1" smd rect
			(at -0.899922 -0.750062 180)
			(size 0.6096 0.6096)
			(layers "F.Cu" "F.Mask" "F.Paste")
			(net "GND")
		)
		(pad "2" smd rect
			(at -0.899922 0 180)
			(size 0.4064 0.6096)
			(layers "F.Cu" "F.Mask" "F.Paste")
			(net "H_CPU1_MEMTRIP_R")
		)
		(pad "3" smd rect
			(at -0.899922 0.750062 180)
			(size 0.6096 0.6096)
			(layers "F.Cu" "F.Mask" "F.Paste")
			(net "H_CPU1_MEMTRIP")
		)
		(pad "4" smd rect
			(at 0.899922 0.750062 180)
			(size 0.6096 0.6096)
			(layers "F.Cu" "F.Mask" "F.Paste")
			(net "PVNN_TERM_CPU1")
		)
		(pad "5" smd rect
			(at 0.899922 0 180)
			(size 0.4064 0.6096)
			(layers "F.Cu" "F.Mask" "F.Paste")
			(net "H_CPU1_MEMTRIP_OUT_VT_R_N")
		)
		(pad "6" smd rect
			(at 0.899922 -0.750062 180)
			(size 0.6096 0.6096)
			(layers "F.Cu" "F.Mask" "F.Paste")
			(net "H_CPU1_MEMTRIP_VT_N")
		)
	)
	(footprint ""
		(layer "F.Cu")
		(at 322.287138 -15.855188)
		(property "Reference" "R1747"
			(at 0 0 0)
			(layer "F.SilkS")
			(hide yes)
			(effects
				(font
					(size 1.27 1.27)
				)
			)
		)
		(property "Value" ""
			(at 0 0 0)
			(layer "F.Fab")
			(effects
				(font
					(size 1.27 1.27)
				)
			)
		)
		(duplicate_pad_numbers_are_jumpers no)
		(fp_line
			(start -1.651 -0.8382)
			(end 1.651 -0.8382)
			(stroke
				(width 0.1524)
				(type default)
			)
			(layer "F.SilkS")
		)
		(fp_line
			(start -1.651 0.8382)
			(end -1.651 -0.8382)
			(stroke
				(width 0.1524)
				(type default)
			)
			(layer "F.SilkS")
		)
		(fp_line
			(start 1.651 -0.8382)
			(end 1.651 0.8382)
			(stroke
				(width 0.1524)
				(type default)
			)
			(layer "F.SilkS")
		)
		(fp_line
			(start 1.651 0.8382)
			(end -1.651 0.8382)
			(stroke
				(width 0.1524)
				(type default)
			)
			(layer "F.SilkS")
		)
		(fp_line
			(start -1.559814 -0.7366)
			(end -1.559814 0.7366)
			(stroke
				(width 0.1)
				(type default)
			)
			(layer "F.Fab")
		)
		(fp_line
			(start -1.559814 0.7366)
			(end -1.524 0.7366)
			(stroke
				(width 0.1)
				(type default)
			)
			(layer "F.Fab")
		)
		(fp_line
			(start -1.524 -0.7366)
			(end -1.559814 -0.7366)
			(stroke
				(width 0.1)
				(type default)
			)
			(layer "F.Fab")
		)
		(fp_line
			(start -1.524 0.7366)
			(end 1.524 0.7366)
			(stroke
				(width 0.1)
				(type default)
			)
			(layer "F.Fab")
		)
		(fp_line
			(start 1.524 -0.7366)
			(end -1.524 -0.7366)
			(stroke
				(width 0.1)
				(type default)
			)
			(layer "F.Fab")
		)
		(fp_line
			(start 1.524 0.7366)
			(end 1.560576 0.7366)
			(stroke
				(width 0.1)
				(type default)
			)
			(layer "F.Fab")
		)
		(fp_line
			(start 1.560576 -0.7366)
			(end 1.524 -0.7366)
			(stroke
				(width 0.1)
				(type default)
			)
			(layer "F.Fab")
		)
		(fp_line
			(start 1.560576 0.7366)
			(end 1.560576 -0.7366)
			(stroke
				(width 0.1)
				(type default)
			)
			(layer "F.Fab")
		)
		(pad "1" smd rect
			(at -0.94996 0 180)
			(size 1.1176 1.3716)
			(layers "F.Cu" "F.Mask" "F.Paste")
			(net "P1V8_PCH_AUX")
		)
		(pad "2" smd rect
			(at 0.94996 0 180)
			(size 1.1176 1.3716)
			(layers "F.Cu" "F.Mask" "F.Paste")
			(net "PGPPA_AUX")
		)
	)
	(footprint ""
		(layer "F.Cu")
		(at 38.72738 -128.108202 -90)
		(property "Reference" "R2573"
			(at 0 0 270)
			(layer "F.SilkS")
			(hide yes)
			(effects
				(font
					(size 1.27 1.27)
				)
			)
		)
		(property "Value" ""
			(at 0 0 270)
			(layer "F.Fab")
			(effects
				(font
					(size 1.27 1.27)
				)
			)
		)
		(duplicate_pad_numbers_are_jumpers no)
		(fp_line
			(start -0.7874 0.4064)
			(end -0.7874 -0.4064)
			(stroke
				(width 0.1524)
				(type default)
			)
			(layer "F.SilkS")
		)
		(fp_line
			(start 0.7874 0.4064)
			(end -0.7874 0.4064)
			(stroke
				(width 0.1524)
				(type default)
			)
			(layer "F.SilkS")
		)
		(fp_line
			(start -0.7874 -0.4064)
			(end 0.7874 -0.4064)
			(stroke
				(width 0.1524)
				(type default)
			)
			(layer "F.SilkS")
		)
		(fp_line
			(start 0.7874 -0.4064)
			(end 0.7874 0.4064)
			(stroke
				(width 0.1524)
				(type default)
			)
			(layer "F.SilkS")
		)
		(fp_line
			(start -0.67945 0.3048)
			(end -0.67945 -0.305054)
			(stroke
				(width 0.1)
				(type default)
			)
			(layer "F.Fab")
		)
		(fp_line
			(start -0.12065 0.3048)
			(end -0.67945 0.3048)
			(stroke
				(width 0.1)
				(type default)
			)
			(layer "F.Fab")
		)
		(fp_line
			(start 0.120396 0.3048)
			(end 0.120396 0.2794)
			(stroke
				(width 0.1)
				(type default)
			)
			(layer "F.Fab")
		)
		(fp_line
			(start 0.67945 0.3048)
			(end 0.120396 0.3048)
			(stroke
				(width 0.1)
				(type default)
			)
			(layer "F.Fab")
		)
		(fp_line
			(start -0.12065 0.2794)
			(end -0.12065 0.3048)
			(stroke
				(width 0.1)
				(type default)
			)
			(layer "F.Fab")
		)
		(fp_line
			(start 0.120396 0.2794)
			(end -0.12065 0.2794)
			(stroke
				(width 0.1)
				(type default)
			)
			(layer "F.Fab")
		)
		(fp_line
			(start -0.12065 -0.2794)
			(end 0.12065 -0.2794)
			(stroke
				(width 0.1)
				(type default)
			)
			(layer "F.Fab")
		)
		(fp_line
			(start 0.12065 -0.2794)
			(end 0.12065 -0.3048)
			(stroke
				(width 0.1)
				(type default)
			)
			(layer "F.Fab")
		)
		(fp_line
			(start 0.12065 -0.3048)
			(end 0.67945 -0.3048)
			(stroke
				(width 0.1)
				(type default)
			)
			(layer "F.Fab")
		)
		(fp_line
			(start 0.67945 -0.3048)
			(end 0.67945 0.3048)
			(stroke
				(width 0.1)
				(type default)
			)
			(layer "F.Fab")
		)
		(fp_line
			(start -0.67945 -0.305054)
			(end -0.12065 -0.305054)
			(stroke
				(width 0.1)
				(type default)
			)
			(layer "F.Fab")
		)
		(fp_line
			(start -0.12065 -0.305054)
			(end -0.12065 -0.2794)
			(stroke
				(width 0.1)
				(type default)
			)
			(layer "F.Fab")
		)
		(pad "1" smd circle
			(at -0.40005 0 270)
			(size 0 0)
			(layers "F.Cu" "F.Mask" "F.Paste")
			(net "P3V3_AUX")
		)
		(pad "2" smd circle
			(at 0.40005 0 270)
			(size 0 0)
			(layers "F.Cu" "F.Mask" "F.Paste")
			(net "IRQ_PVCCFA_CPU1_VRHOT_R_N")
		)
	)
	(footprint ""
		(layer "F.Cu")
		(at 447.687192 -22.125178 180)
		(property "Reference" "PR3781"
			(at 0 0 180)
			(layer "F.SilkS")
			(hide yes)
			(effects
				(font
					(size 1.27 1.27)
				)
			)
		)
		(property "Value" ""
			(at 0 0 180)
			(layer "F.Fab")
			(effects
				(font
					(size 1.27 1.27)
				)
			)
		)
		(duplicate_pad_numbers_are_jumpers no)
		(fp_line
			(start 0.7874 0.4064)
			(end -0.7874 0.4064)
			(stroke
				(width 0.1524)
				(type default)
			)
			(layer "F.SilkS")
		)
		(fp_line
			(start 0.7874 -0.4064)
			(end 0.7874 0.4064)
			(stroke
				(width 0.1524)
				(type default)
			)
			(layer "F.SilkS")
		)
		(fp_line
			(start -0.7874 0.4064)
			(end -0.7874 -0.4064)
			(stroke
				(width 0.1524)
				(type default)
			)
			(layer "F.SilkS")
		)
		(fp_line
			(start -0.7874 -0.4064)
			(end 0.7874 -0.4064)
			(stroke
				(width 0.1524)
				(type default)
			)
			(layer "F.SilkS")
		)
		(fp_line
			(start 0.67945 0.3048)
			(end 0.120396 0.3048)
			(stroke
				(width 0.1)
				(type default)
			)
			(layer "F.Fab")
		)
		(fp_line
			(start 0.67945 -0.3048)
			(end 0.67945 0.3048)
			(stroke
				(width 0.1)
				(type default)
			)
			(layer "F.Fab")
		)
		(fp_line
			(start 0.12065 -0.2794)
			(end 0.12065 -0.3048)
			(stroke
				(width 0.1)
				(type default)
			)
			(layer "F.Fab")
		)
		(fp_line
			(start 0.12065 -0.3048)
			(end 0.67945 -0.3048)
			(stroke
				(width 0.1)
				(type default)
			)
			(layer "F.Fab")
		)
		(fp_line
			(start 0.120396 0.3048)
			(end 0.120396 0.2794)
			(stroke
				(width 0.1)
				(type default)
			)
			(layer "F.Fab")
		)
		(fp_line
			(start 0.120396 0.2794)
			(end -0.12065 0.2794)
			(stroke
				(width 0.1)
				(type default)
			)
			(layer "F.Fab")
		)
		(fp_line
			(start -0.12065 0.3048)
			(end -0.67945 0.3048)
			(stroke
				(width 0.1)
				(type default)
			)
			(layer "F.Fab")
		)
		(fp_line
			(start -0.12065 0.2794)
			(end -0.12065 0.3048)
			(stroke
				(width 0.1)
				(type default)
			)
			(layer "F.Fab")
		)
		(fp_line
			(start -0.12065 -0.2794)
			(end 0.12065 -0.2794)
			(stroke
				(width 0.1)
				(type default)
			)
			(layer "F.Fab")
		)
		(fp_line
			(start -0.12065 -0.305054)
			(end -0.12065 -0.2794)
			(stroke
				(width 0.1)
				(type default)
			)
			(layer "F.Fab")
		)
		(fp_line
			(start -0.67945 0.3048)
			(end -0.67945 -0.305054)
			(stroke
				(width 0.1)
				(type default)
			)
			(layer "F.Fab")
		)
		(fp_line
			(start -0.67945 -0.305054)
			(end -0.12065 -0.305054)
			(stroke
				(width 0.1)
				(type default)
			)
			(layer "F.Fab")
		)
		(pad "1" smd circle
			(at -0.40005 0 180)
			(size 0 0)
			(layers "F.Cu" "F.Mask" "F.Paste")
			(net "P12V_OCP_SENSE_1")
		)
		(pad "2" smd circle
			(at 0.40005 0 180)
			(size 0 0)
			(layers "F.Cu" "F.Mask" "F.Paste")
			(net "GND")
		)
	)
	(footprint ""
		(layer "F.Cu")
		(at 292.98011 -390.459976 -90)
		(property "Reference" "PJ42"
			(at 2.072132 -8.52297 90)
			(unlocked yes)
			(layer "F.SilkS")
			(effects
				(font
					(size 0.7874 0.5842)
					(thickness 0.1524)
				)
				(justify left)
			)
		)
		(property "Value" ""
			(at 0 0 270)
			(layer "F.Fab")
			(effects
				(font
					(size 1.27 1.27)
				)
			)
		)
		(duplicate_pad_numbers_are_jumpers no)
		(fp_line
			(start -2.500122 7.649972)
			(end -2.500122 7.570978)
			(stroke
				(width 0.1524)
				(type default)
			)
			(layer "F.SilkS")
		)
		(fp_line
			(start 2.500122 7.649972)
			(end -2.500122 7.649972)
			(stroke
				(width 0.1524)
				(type default)
			)
			(layer "F.SilkS")
		)
		(fp_line
			(start 2.500122 7.570978)
			(end 2.500122 7.649972)
			(stroke
				(width 0.1524)
				(type default)
			)
			(layer "F.SilkS")
		)
		(fp_line
			(start -2.500122 5.869178)
			(end -2.500122 5.44449)
			(stroke
				(width 0.1524)
				(type default)
			)
			(layer "F.SilkS")
		)
		(fp_line
			(start 2.500122 4.944618)
			(end 2.500122 5.869178)
			(stroke
				(width 0.1524)
				(type default)
			)
			(layer "F.SilkS")
		)
		(fp_line
			(start -2.500122 -5.44449)
			(end -2.500122 -5.869178)
			(stroke
				(width 0.1524)
				(type default)
			)
			(layer "F.SilkS")
		)
		(fp_line
			(start 2.500122 -5.869178)
			(end 2.500122 -4.944618)
			(stroke
				(width 0.1524)
				(type default)
			)
			(layer "F.SilkS")
		)
		(fp_line
			(start -2.500122 -7.570978)
			(end -2.500122 -7.649972)
			(stroke
				(width 0.1524)
				(type default)
			)
			(layer "F.SilkS")
		)
		(fp_line
			(start -2.500122 -7.649972)
			(end 2.500122 -7.649972)
			(stroke
				(width 0.1524)
				(type default)
			)
			(layer "F.SilkS")
		)
		(fp_line
			(start 2.500122 -7.649972)
			(end 2.500122 -7.570978)
			(stroke
				(width 0.1524)
				(type default)
			)
			(layer "F.SilkS")
		)
		(fp_poly
			(pts
				(xy -4.094988 -5.50799) (xy -4.094988 -4.49199) (xy -3.078988 -4.99999)
			)
			(stroke
				(width 0)
				(type default)
			)
			(fill yes)
			(layer "F.SilkS")
		)
		(fp_line
			(start -2.500122 7.649972)
			(end -2.500122 -7.649972)
			(stroke
				(width 0.1)
				(type default)
			)
			(layer "F.Fab")
		)
		(fp_line
			(start 2.500122 7.649972)
			(end -2.500122 7.649972)
			(stroke
				(width 0.1)
				(type default)
			)
			(layer "F.Fab")
		)
		(fp_line
			(start -2.500122 -7.649972)
			(end 2.500122 -7.649972)
			(stroke
				(width 0.1)
				(type default)
			)
			(layer "F.Fab")
		)
		(fp_line
			(start 2.500122 -7.649972)
			(end 2.500122 7.649972)
			(stroke
				(width 0.1)
				(type default)
			)
			(layer "F.Fab")
		)
		(fp_poly
			(pts
				(xy -4.094988 -5.50799) (xy -4.094988 -4.49199) (xy -3.078988 -4.99999)
			)
			(stroke
				(width 0)
				(type default)
			)
			(fill yes)
			(layer "F.Fab")
		)
		(pad "" np_thru_hole circle
			(at 1.100074 -5.5245 180)
			(size 0.762 0.762)
			(drill 0.762)
			(layers "*.Cu" "*.Mask")
			(clearance 0.381)
			(thermal_gap 0.381)
		)
		(pad "" np_thru_hole circle
			(at 1.100074 5.5245 180)
			(size 0.762 0.762)
			(drill 0.762)
			(layers "*.Cu" "*.Mask")
			(clearance 0.381)
			(thermal_gap 0.381)
		)
		(pad "1" smd rect
			(at -2.109978 -4.99999)
			(size 0.6096 1.651)
			(layers "F.Cu" "F.Mask" "F.Paste")
			(net "P12V_PSU")
		)
		(pad "2" smd rect
			(at -2.109978 -3.999992)
			(size 0.6096 1.651)
			(layers "F.Cu" "F.Mask" "F.Paste")
			(net "P12V_HSC_SENSE1_P")
		)
		(pad "3" smd rect
			(at -2.109978 -2.999994)
			(size 0.6096 1.651)
			(layers "F.Cu" "F.Mask" "F.Paste")
			(net "P12V_HSC_SENSE1_N")
		)
		(pad "4" smd rect
			(at -2.109978 -1.999996)
			(size 0.6096 1.651)
			(layers "F.Cu" "F.Mask" "F.Paste")
			(net "P12V_HSC_SENSE2_P")
		)
		(pad "5" smd rect
			(at -2.109978 -0.999998)
			(size 0.6096 1.651)
			(layers "F.Cu" "F.Mask" "F.Paste")
			(net "P12V_HSC_SENSE2_N")
		)
		(pad "6" smd rect
			(at -2.109978 0)
			(size 0.6096 1.651)
			(layers "F.Cu" "F.Mask" "F.Paste")
			(net "P12V_HSC_ADC_N")
		)
		(pad "7" smd rect
			(at -2.109978 0.999998)
			(size 0.6096 1.651)
			(layers "F.Cu" "F.Mask" "F.Paste")
			(net "P12V_HSC_ADC_P")
		)
		(pad "8" smd rect
			(at -2.109978 1.999996)
			(size 0.6096 1.651)
			(layers "F.Cu" "F.Mask" "F.Paste")
			(net "P12V_HSC_GATE1")
		)
		(pad "9" smd rect
			(at -2.109978 2.999994)
			(size 0.6096 1.651)
			(layers "F.Cu" "F.Mask" "F.Paste")
			(net "P12V_HSC_GATE2")
		)
		(pad "10" smd rect
			(at -2.109978 3.999992)
			(size 0.6096 1.651)
			(layers "F.Cu" "F.Mask" "F.Paste")
			(net "P12V_AUX")
		)
		(pad "11" smd rect
			(at -2.109978 4.99999)
			(size 0.6096 1.651)
			(layers "F.Cu" "F.Mask" "F.Paste")
			(net "GND")
		)
		(pad "12" smd rect
			(at 2.109978 -4.500118 180)
			(size 0.6096 1.651)
			(layers "F.Cu" "F.Mask" "F.Paste")
			(net "P3V3_AUX")
		)
		(pad "13" smd rect
			(at 2.109978 -3.50012 180)
			(size 0.6096 1.651)
			(layers "F.Cu" "F.Mask" "F.Paste")
			(net "IRQ_HSC_FAULT_N")
		)
		(pad "14" smd rect
			(at 2.109978 -2.500122 180)
			(size 0.6096 1.651)
			(layers "F.Cu" "F.Mask" "F.Paste")
			(net "HSC_EN")
		)
		(pad "15" smd rect
			(at 2.109978 -1.500124 180)
			(size 0.6096 1.651)
			(layers "F.Cu" "F.Mask" "F.Paste")
			(net "MB0_P12V_STBY_PWRGD")
		)
		(pad "16" smd rect
			(at 2.109978 -0.499872 180)
			(size 0.6096 1.651)
			(layers "F.Cu" "F.Mask" "F.Paste")
			(net "HSC_CSOUT")
		)
		(pad "17" smd rect
			(at 2.109978 0.499872 180)
			(size 0.6096 1.651)
			(layers "F.Cu" "F.Mask" "F.Paste")
			(net "HSC_TYPE_ADC")
		)
		(pad "18" smd rect
			(at 2.109978 1.500124 180)
			(size 0.6096 1.651)
			(layers "F.Cu" "F.Mask" "F.Paste")
			(net "SMB_SML1_PMBUS_HSC_MODULE_SCL")
		)
		(pad "19" smd rect
			(at 2.109978 2.500122 180)
			(size 0.6096 1.651)
			(layers "F.Cu" "F.Mask" "F.Paste")
			(net "SMB_SML1_PMBUS_HSC_MODULE_SDA")
		)
		(pad "20" smd rect
			(at 2.109978 3.50012 180)
			(size 0.6096 1.651)
			(layers "F.Cu" "F.Mask" "F.Paste")
			(net "IRQ_SML1_PMBUS_ALERT_N")
		)
		(pad "21" smd rect
			(at 2.109978 4.500118 180)
			(size 0.6096 1.651)
			(layers "F.Cu" "F.Mask" "F.Paste")
			(net "GND")
		)
		(pad "G1" smd circle
			(at 0 -6.720078 180)
			(size 0 0)
			(layers "F.Cu" "F.Mask" "F.Paste")
			(net "GND")
		)
		(pad "G2" smd circle
			(at 0 6.720078 180)
			(size 0 0)
			(layers "F.Cu" "F.Mask" "F.Paste")
			(net "GND")
		)
		(zone
			(layers "F.Cu" "B.Cu" "In1.Cu" "In2.Cu" "In3.Cu" "In4.Cu" "In5.Cu" "In6.Cu"
				"In7.Cu" "In8.Cu" "In9.Cu" "In10.Cu" "In11.Cu" "In12.Cu" "In13.Cu" "In14.Cu"
				"In15.Cu" "In16.Cu"
			)
			(hatch none 0.5)
			(connect_pads
				(clearance 0)
			)
			(min_thickness 0.25)
			(keepout
				(tracks not_allowed)
				(vias allowed)
				(pads allowed)
				(copperpour not_allowed)
				(footprints allowed)
			)
			(placement
				(enabled no)
				(sheetname "")
			)
			(fill
				(thermal_gap 0.5)
				(thermal_bridge_width 0.5)
				(island_removal_mode 0)
			)
			(polygon
				(pts
					(arc
						(start 288.34461 -389.359902)
						(mid 286.56661 -389.359902)
						(end 288.34461 -389.359902)
					)
				)
			)
		)
		(zone
			(layers "F.Cu" "B.Cu" "In1.Cu" "In2.Cu" "In3.Cu" "In4.Cu" "In5.Cu" "In6.Cu"
				"In7.Cu" "In8.Cu" "In9.Cu" "In10.Cu" "In11.Cu" "In12.Cu" "In13.Cu" "In14.Cu"
				"In15.Cu" "In16.Cu"
			)
			(hatch none 0.5)
			(connect_pads
				(clearance 0)
			)
			(min_thickness 0.25)
			(keepout
				(tracks not_allowed)
				(vias allowed)
				(pads allowed)
				(copperpour not_allowed)
				(footprints allowed)
			)
			(placement
				(enabled no)
				(sheetname "")
			)
			(fill
				(thermal_gap 0.5)
				(thermal_bridge_width 0.5)
				(island_removal_mode 0)
			)
			(polygon
				(pts
					(arc
						(start 299.39361 -389.359902)
						(mid 297.61561 -389.359902)
						(end 299.39361 -389.359902)
					)
				)
			)
		)
	)
	(footprint ""
		(layer "F.Cu")
		(at 49.375314 -391.078212 180)
		(property "Reference" "R4644"
			(at 0 0 180)
			(layer "F.SilkS")
			(hide yes)
			(effects
				(font
					(size 1.27 1.27)
				)
			)
		)
		(property "Value" ""
			(at 0 0 180)
			(layer "F.Fab")
			(effects
				(font
					(size 1.27 1.27)
				)
			)
		)
		(duplicate_pad_numbers_are_jumpers no)
		(fp_line
			(start 0.7874 0.4064)
			(end -0.7874 0.4064)
			(stroke
				(width 0.1524)
				(type default)
			)
			(layer "F.SilkS")
		)
		(fp_line
			(start 0.7874 -0.4064)
			(end 0.7874 0.4064)
			(stroke
				(width 0.1524)
				(type default)
			)
			(layer "F.SilkS")
		)
		(fp_line
			(start -0.7874 0.4064)
			(end -0.7874 -0.4064)
			(stroke
				(width 0.1524)
				(type default)
			)
			(layer "F.SilkS")
		)
		(fp_line
			(start -0.7874 -0.4064)
			(end 0.7874 -0.4064)
			(stroke
				(width 0.1524)
				(type default)
			)
			(layer "F.SilkS")
		)
		(fp_line
			(start 0.67945 0.3048)
			(end 0.120396 0.3048)
			(stroke
				(width 0.1)
				(type default)
			)
			(layer "F.Fab")
		)
		(fp_line
			(start 0.67945 -0.3048)
			(end 0.67945 0.3048)
			(stroke
				(width 0.1)
				(type default)
			)
			(layer "F.Fab")
		)
		(fp_line
			(start 0.12065 -0.2794)
			(end 0.12065 -0.3048)
			(stroke
				(width 0.1)
				(type default)
			)
			(layer "F.Fab")
		)
		(fp_line
			(start 0.12065 -0.3048)
			(end 0.67945 -0.3048)
			(stroke
				(width 0.1)
				(type default)
			)
			(layer "F.Fab")
		)
		(fp_line
			(start 0.120396 0.3048)
			(end 0.120396 0.2794)
			(stroke
				(width 0.1)
				(type default)
			)
			(layer "F.Fab")
		)
		(fp_line
			(start 0.120396 0.2794)
			(end -0.12065 0.2794)
			(stroke
				(width 0.1)
				(type default)
			)
			(layer "F.Fab")
		)
		(fp_line
			(start -0.12065 0.3048)
			(end -0.67945 0.3048)
			(stroke
				(width 0.1)
				(type default)
			)
			(layer "F.Fab")
		)
		(fp_line
			(start -0.12065 0.2794)
			(end -0.12065 0.3048)
			(stroke
				(width 0.1)
				(type default)
			)
			(layer "F.Fab")
		)
		(fp_line
			(start -0.12065 -0.2794)
			(end 0.12065 -0.2794)
			(stroke
				(width 0.1)
				(type default)
			)
			(layer "F.Fab")
		)
		(fp_line
			(start -0.12065 -0.305054)
			(end -0.12065 -0.2794)
			(stroke
				(width 0.1)
				(type default)
			)
			(layer "F.Fab")
		)
		(fp_line
			(start -0.67945 0.3048)
			(end -0.67945 -0.305054)
			(stroke
				(width 0.1)
				(type default)
			)
			(layer "F.Fab")
		)
		(fp_line
			(start -0.67945 -0.305054)
			(end -0.12065 -0.305054)
			(stroke
				(width 0.1)
				(type default)
			)
			(layer "F.Fab")
		)
		(pad "1" smd circle
			(at -0.40005 0 180)
			(size 0 0)
			(layers "F.Cu" "F.Mask" "F.Paste")
			(net "P3V3_AUX")
		)
		(pad "2" smd circle
			(at 0.40005 0 180)
			(size 0 0)
			(layers "F.Cu" "F.Mask" "F.Paste")
			(net "FM_P2E_BUF2_EQB1")
		)
	)
	(footprint ""
		(layer "F.Cu")
		(at 213.67496 -360.76382)
		(property "Reference" "H114"
			(at -6.1087 -8.006588 0)
			(unlocked yes)
			(layer "F.SilkS")
			(effects
				(font
					(size 0.7874 0.5842)
					(thickness 0.1524)
				)
				(justify left)
			)
		)
		(property "Value" ""
			(at 0 0 0)
			(layer "F.Fab")
			(effects
				(font
					(size 1.27 1.27)
				)
			)
		)
		(duplicate_pad_numbers_are_jumpers no)
		(fp_circle
			(center 0 0)
			(end 7.999984 0)
			(stroke
				(width 0.1524)
				(type default)
			)
			(fill no)
			(layer "F.SilkS")
		)
		(fp_circle
			(center 0 0)
			(end 7.999984 0)
			(stroke
				(width 0.1524)
				(type default)
			)
			(fill no)
			(layer "B.SilkS")
		)
		(fp_circle
			(center 0 0)
			(end 7.999984 0)
			(stroke
				(width 0.1)
				(type default)
			)
			(fill no)
			(layer "B.Fab")
		)
		(fp_circle
			(center 0 0)
			(end 7.999984 0)
			(stroke
				(width 0.1)
				(type default)
			)
			(fill no)
			(layer "F.Fab")
		)
		(pad "" np_thru_hole circle
			(at 0 0)
			(size 4.0132 4.0132)
			(drill 4.0132)
			(layers "*.Cu" "*.Mask")
			(clearance 0.381)
			(thermal_gap 0.381)
		)
		(pad "2" thru_hole circle
			(at 3.2639 0)
			(size 0.9144 0.9144)
			(drill 0.5588)
			(layers "*.Cu" "*.Mask")
			(remove_unused_layers no)
			(net "GND")
			(clearance 0.0762)
			(thermal_gap 0.0762)
		)
		(pad "3" thru_hole circle
			(at 2.307844 -2.307844)
			(size 0.9144 0.9144)
			(drill 0.5588)
			(layers "*.Cu" "*.Mask")
			(remove_unused_layers no)
			(net "GND")
			(clearance 0.0762)
			(thermal_gap 0.0762)
		)
		(pad "4" thru_hole circle
			(at 0 -3.2639)
			(size 0.9144 0.9144)
			(drill 0.5588)
			(layers "*.Cu" "*.Mask")
			(remove_unused_layers no)
			(net "GND")
			(clearance 0.0762)
			(thermal_gap 0.0762)
		)
		(pad "5" thru_hole circle
			(at -2.307844 -2.307844)
			(size 0.9144 0.9144)
			(drill 0.5588)
			(layers "*.Cu" "*.Mask")
			(remove_unused_layers no)
			(net "GND")
			(clearance 0.0762)
			(thermal_gap 0.0762)
		)
		(pad "6" thru_hole circle
			(at -3.2639 0)
			(size 0.9144 0.9144)
			(drill 0.5588)
			(layers "*.Cu" "*.Mask")
			(remove_unused_layers no)
			(net "GND")
			(clearance 0.0762)
			(thermal_gap 0.0762)
		)
		(pad "7" thru_hole circle
			(at -2.307844 2.307844)
			(size 0.9144 0.9144)
			(drill 0.5588)
			(layers "*.Cu" "*.Mask")
			(remove_unused_layers no)
			(net "GND")
			(clearance 0.0762)
			(thermal_gap 0.0762)
		)
		(pad "8" thru_hole circle
			(at 0 3.2639)
			(size 0.9144 0.9144)
			(drill 0.5588)
			(layers "*.Cu" "*.Mask")
			(remove_unused_layers no)
			(net "GND")
			(clearance 0.0762)
			(thermal_gap 0.0762)
		)
		(pad "9" thru_hole circle
			(at 2.307844 2.307844)
			(size 0.9144 0.9144)
			(drill 0.5588)
			(layers "*.Cu" "*.Mask")
			(remove_unused_layers no)
			(net "GND")
			(clearance 0.0762)
			(thermal_gap 0.0762)
		)
		(zone
			(layer "F.Cu")
			(hatch none 0.5)
			(connect_pads
				(clearance 0)
			)
			(min_thickness 0.25)
			(keepout
				(tracks not_allowed)
				(vias allowed)
				(pads allowed)
				(copperpour not_allowed)
				(footprints allowed)
			)
			(placement
				(enabled no)
				(sheetname "")
			)
			(fill
				(thermal_gap 0.5)
				(thermal_bridge_width 0.5)
				(island_removal_mode 0)
			)
			(polygon
				(pts
					(arc
						(start 213.67496 -356.49662)
						(mid 209.40776 -360.76382)
						(end 213.67496 -365.03102)
					)
					(arc
						(start 213.67496 -368.763804)
						(mid 208.018117 -366.420663)
						(end 205.674976 -360.76382)
					)
					(arc
						(start 205.674976 -360.76382)
						(mid 208.018117 -355.106977)
						(end 213.67496 -352.763836)
					)
				)
			)
		)
		(zone
			(layer "F.Cu")
			(hatch none 0.5)
			(connect_pads
				(clearance 0)
			)
			(min_thickness 0.25)
			(keepout
				(tracks not_allowed)
				(vias allowed)
				(pads allowed)
				(copperpour not_allowed)
				(footprints allowed)
			)
			(placement
				(enabled no)
				(sheetname "")
			)
			(fill
				(thermal_gap 0.5)
				(thermal_bridge_width 0.5)
				(island_removal_mode 0)
			)
			(polygon
				(pts
					(arc
						(start 213.67496 -356.49662)
						(mid 217.94216 -360.76382)
						(end 213.67496 -365.03102)
					)
					(arc
						(start 213.67496 -368.763804)
						(mid 219.331803 -366.420663)
						(end 221.674944 -360.76382)
					)
					(arc
						(start 221.674944 -360.76382)
						(mid 219.331803 -355.106977)
						(end 213.67496 -352.763836)
					)
				)
			)
		)
		(zone
			(layers "F.Cu" "B.Cu" "In1.Cu" "In2.Cu" "In3.Cu" "In4.Cu" "In5.Cu" "In6.Cu"
				"In7.Cu" "In8.Cu" "In9.Cu" "In10.Cu" "In11.Cu" "In12.Cu" "In13.Cu" "In14.Cu"
				"In15.Cu" "In16.Cu"
			)
			(hatch none 0.5)
			(connect_pads
				(clearance 0)
			)
			(min_thickness 0.25)
			(keepout
				(tracks not_allowed)
				(vias allowed)
				(pads allowed)
				(copperpour not_allowed)
				(footprints allowed)
			)
			(placement
				(enabled no)
				(sheetname "")
			)
			(fill
				(thermal_gap 0.5)
				(thermal_bridge_width 0.5)
				(island_removal_mode 0)
			)
			(polygon
				(pts
					(arc
						(start 216.18702 -360.76382)
						(mid 211.1629 -360.76382)
						(end 216.18702 -360.76382)
					)
				)
			)
		)
		(zone
			(layer "B.Cu")
			(hatch none 0.5)
			(connect_pads
				(clearance 0)
			)
			(min_thickness 0.25)
			(keepout
				(tracks not_allowed)
				(vias allowed)
				(pads allowed)
				(copperpour not_allowed)
				(footprints allowed)
			)
			(placement
				(enabled no)
				(sheetname "")
			)
			(fill
				(thermal_gap 0.5)
				(thermal_bridge_width 0.5)
				(island_removal_mode 0)
			)
			(polygon
				(pts
					(arc
						(start 213.67496 -365.28502)
						(mid 209.15376 -360.76382)
						(end 213.67496 -356.24262)
					)
					(arc
						(start 213.67496 -356.72522)
						(mid 209.63636 -360.76382)
						(end 213.67496 -364.80242)
					)
				)
			)
		)
		(zone
			(layer "B.Cu")
			(hatch none 0.5)
			(connect_pads
				(clearance 0)
			)
			(min_thickness 0.25)
			(keepout
				(tracks not_allowed)
				(vias allowed)
				(pads allowed)
				(copperpour not_allowed)
				(footprints allowed)
			)
			(placement
				(enabled no)
				(sheetname "")
			)
			(fill
				(thermal_gap 0.5)
				(thermal_bridge_width 0.5)
				(island_removal_mode 0)
			)
			(polygon
				(pts
					(arc
						(start 213.67496 -365.28502)
						(mid 218.19616 -360.76382)
						(end 213.67496 -356.24262)
					)
					(arc
						(start 213.67496 -356.72522)
						(mid 217.71356 -360.76382)
						(end 213.67496 -364.80242)
					)
				)
			)
		)
	)
	(footprint ""
		(layer "F.Cu")
		(at 145.549874 -402.371052 -90)
		(property "Reference" "C758"
			(at 0 0 270)
			(layer "F.SilkS")
			(hide yes)
			(effects
				(font
					(size 1.27 1.27)
				)
			)
		)
		(property "Value" ""
			(at 0 0 270)
			(layer "F.Fab")
			(effects
				(font
					(size 1.27 1.27)
				)
			)
		)
		(duplicate_pad_numbers_are_jumpers no)
		(fp_line
			(start -0.299974 0.150114)
			(end -0.299974 -0.150114)
			(stroke
				(width 0.1)
				(type default)
			)
			(layer "F.Fab")
		)
		(fp_line
			(start 0.299974 0.150114)
			(end -0.299974 0.150114)
			(stroke
				(width 0.1)
				(type default)
			)
			(layer "F.Fab")
		)
		(fp_line
			(start -0.299974 -0.150114)
			(end 0.299974 -0.150114)
			(stroke
				(width 0.1)
				(type default)
			)
			(layer "F.Fab")
		)
		(fp_line
			(start 0.299974 -0.150114)
			(end 0.299974 0.150114)
			(stroke
				(width 0.1)
				(type default)
			)
			(layer "F.Fab")
		)
		(pad "1" smd rect
			(at -0.2667 0 270)
			(size 0.3048 0.381)
			(layers "F.Cu" "F.Mask" "F.Paste")
			(net "P5E_CPU1_PE2_TX_C_DN<7>")
		)
		(pad "2" smd rect
			(at 0.2667 0 270)
			(size 0.3048 0.381)
			(layers "F.Cu" "F.Mask" "F.Paste")
			(net "P5E_CPU1_PE2_TX_DN<7>")
		)
	)
	(footprint ""
		(layer "F.Cu")
		(at 80.32115 -151.383492 180)
		(property "Reference" "R668"
			(at 0 0 180)
			(layer "F.SilkS")
			(hide yes)
			(effects
				(font
					(size 1.27 1.27)
				)
			)
		)
		(property "Value" ""
			(at 0 0 180)
			(layer "F.Fab")
			(effects
				(font
					(size 1.27 1.27)
				)
			)
		)
		(duplicate_pad_numbers_are_jumpers no)
		(fp_line
			(start 0.7874 0.4064)
			(end -0.7874 0.4064)
			(stroke
				(width 0.1524)
				(type default)
			)
			(layer "F.SilkS")
		)
		(fp_line
			(start 0.7874 -0.4064)
			(end 0.7874 0.4064)
			(stroke
				(width 0.1524)
				(type default)
			)
			(layer "F.SilkS")
		)
		(fp_line
			(start -0.7874 0.4064)
			(end -0.7874 -0.4064)
			(stroke
				(width 0.1524)
				(type default)
			)
			(layer "F.SilkS")
		)
		(fp_line
			(start -0.7874 -0.4064)
			(end 0.7874 -0.4064)
			(stroke
				(width 0.1524)
				(type default)
			)
			(layer "F.SilkS")
		)
		(fp_line
			(start 0.67945 0.3048)
			(end 0.120396 0.3048)
			(stroke
				(width 0.1)
				(type default)
			)
			(layer "F.Fab")
		)
		(fp_line
			(start 0.67945 -0.3048)
			(end 0.67945 0.3048)
			(stroke
				(width 0.1)
				(type default)
			)
			(layer "F.Fab")
		)
		(fp_line
			(start 0.12065 -0.2794)
			(end 0.12065 -0.3048)
			(stroke
				(width 0.1)
				(type default)
			)
			(layer "F.Fab")
		)
		(fp_line
			(start 0.12065 -0.3048)
			(end 0.67945 -0.3048)
			(stroke
				(width 0.1)
				(type default)
			)
			(layer "F.Fab")
		)
		(fp_line
			(start 0.120396 0.3048)
			(end 0.120396 0.2794)
			(stroke
				(width 0.1)
				(type default)
			)
			(layer "F.Fab")
		)
		(fp_line
			(start 0.120396 0.2794)
			(end -0.12065 0.2794)
			(stroke
				(width 0.1)
				(type default)
			)
			(layer "F.Fab")
		)
		(fp_line
			(start -0.12065 0.3048)
			(end -0.67945 0.3048)
			(stroke
				(width 0.1)
				(type default)
			)
			(layer "F.Fab")
		)
		(fp_line
			(start -0.12065 0.2794)
			(end -0.12065 0.3048)
			(stroke
				(width 0.1)
				(type default)
			)
			(layer "F.Fab")
		)
		(fp_line
			(start -0.12065 -0.2794)
			(end 0.12065 -0.2794)
			(stroke
				(width 0.1)
				(type default)
			)
			(layer "F.Fab")
		)
		(fp_line
			(start -0.12065 -0.305054)
			(end -0.12065 -0.2794)
			(stroke
				(width 0.1)
				(type default)
			)
			(layer "F.Fab")
		)
		(fp_line
			(start -0.67945 0.3048)
			(end -0.67945 -0.305054)
			(stroke
				(width 0.1)
				(type default)
			)
			(layer "F.Fab")
		)
		(fp_line
			(start -0.67945 -0.305054)
			(end -0.12065 -0.305054)
			(stroke
				(width 0.1)
				(type default)
			)
			(layer "F.Fab")
		)
		(pad "1" smd circle
			(at -0.40005 0 180)
			(size 0 0)
			(layers "F.Cu" "F.Mask" "F.Paste")
			(net "I3C_SPD_DDREFGH_CPU1_R_SDA")
		)
		(pad "2" smd circle
			(at 0.40005 0 180)
			(size 0 0)
			(layers "F.Cu" "F.Mask" "F.Paste")
			(net "I3C_SPD_DDREFGH_CPU1_LVC1_R_SDA")
		)
	)
	(footprint ""
		(layer "F.Cu")
		(at 66.369438 -31.887922 90)
		(property "Reference" "PC2166"
			(at 0 0 90)
			(layer "F.SilkS")
			(hide yes)
			(effects
				(font
					(size 1.27 1.27)
				)
			)
		)
		(property "Value" ""
			(at 0 0 90)
			(layer "F.Fab")
			(effects
				(font
					(size 1.27 1.27)
				)
			)
		)
		(duplicate_pad_numbers_are_jumpers no)
		(fp_line
			(start 0.7874 -0.4064)
			(end 0.7874 0.4064)
			(stroke
				(width 0.1524)
				(type default)
			)
			(layer "F.SilkS")
		)
		(fp_line
			(start -0.7874 -0.4064)
			(end 0.7874 -0.4064)
			(stroke
				(width 0.1524)
				(type default)
			)
			(layer "F.SilkS")
		)
		(fp_line
			(start 0.7874 0.4064)
			(end -0.7874 0.4064)
			(stroke
				(width 0.1524)
				(type default)
			)
			(layer "F.SilkS")
		)
		(fp_line
			(start -0.7874 0.4064)
			(end -0.7874 -0.4064)
			(stroke
				(width 0.1524)
				(type default)
			)
			(layer "F.SilkS")
		)
		(fp_line
			(start -0.12065 -0.305054)
			(end -0.12065 -0.2794)
			(stroke
				(width 0.1)
				(type default)
			)
			(layer "F.Fab")
		)
		(fp_line
			(start -0.67945 -0.305054)
			(end -0.12065 -0.305054)
			(stroke
				(width 0.1)
				(type default)
			)
			(layer "F.Fab")
		)
		(fp_line
			(start 0.67945 -0.3048)
			(end 0.67945 0.3048)
			(stroke
				(width 0.1)
				(type default)
			)
			(layer "F.Fab")
		)
		(fp_line
			(start 0.12065 -0.3048)
			(end 0.67945 -0.3048)
			(stroke
				(width 0.1)
				(type default)
			)
			(layer "F.Fab")
		)
		(fp_line
			(start 0.12065 -0.2794)
			(end 0.12065 -0.3048)
			(stroke
				(width 0.1)
				(type default)
			)
			(layer "F.Fab")
		)
		(fp_line
			(start -0.12065 -0.2794)
			(end 0.12065 -0.2794)
			(stroke
				(width 0.1)
				(type default)
			)
			(layer "F.Fab")
		)
		(fp_line
			(start 0.120396 0.2794)
			(end -0.12065 0.2794)
			(stroke
				(width 0.1)
				(type default)
			)
			(layer "F.Fab")
		)
		(fp_line
			(start -0.12065 0.2794)
			(end -0.12065 0.3048)
			(stroke
				(width 0.1)
				(type default)
			)
			(layer "F.Fab")
		)
		(fp_line
			(start 0.67945 0.3048)
			(end 0.120396 0.3048)
			(stroke
				(width 0.1)
				(type default)
			)
			(layer "F.Fab")
		)
		(fp_line
			(start 0.120396 0.3048)
			(end 0.120396 0.2794)
			(stroke
				(width 0.1)
				(type default)
			)
			(layer "F.Fab")
		)
		(fp_line
			(start -0.12065 0.3048)
			(end -0.67945 0.3048)
			(stroke
				(width 0.1)
				(type default)
			)
			(layer "F.Fab")
		)
		(fp_line
			(start -0.67945 0.3048)
			(end -0.67945 -0.305054)
			(stroke
				(width 0.1)
				(type default)
			)
			(layer "F.Fab")
		)
		(pad "1" smd circle
			(at -0.40005 0 90)
			(size 0 0)
			(layers "F.Cu" "F.Mask" "F.Paste")
			(net "P12V_OCP_SS_2")
		)
		(pad "2" smd circle
			(at 0.40005 0 90)
			(size 0 0)
			(layers "F.Cu" "F.Mask" "F.Paste")
			(net "GND")
		)
	)
	(footprint ""
		(layer "F.Cu")
		(at 371.602 -39.969948 90)
		(property "Reference" "R750"
			(at 0 0 90)
			(layer "F.SilkS")
			(hide yes)
			(effects
				(font
					(size 1.27 1.27)
				)
			)
		)
		(property "Value" ""
			(at 0 0 90)
			(layer "F.Fab")
			(effects
				(font
					(size 1.27 1.27)
				)
			)
		)
		(duplicate_pad_numbers_are_jumpers no)
		(fp_line
			(start 0.7874 -0.4064)
			(end 0.7874 0.4064)
			(stroke
				(width 0.1524)
				(type default)
			)
			(layer "F.SilkS")
		)
		(fp_line
			(start -0.7874 -0.4064)
			(end 0.7874 -0.4064)
			(stroke
				(width 0.1524)
				(type default)
			)
			(layer "F.SilkS")
		)
		(fp_line
			(start 0.7874 0.4064)
			(end -0.7874 0.4064)
			(stroke
				(width 0.1524)
				(type default)
			)
			(layer "F.SilkS")
		)
		(fp_line
			(start -0.7874 0.4064)
			(end -0.7874 -0.4064)
			(stroke
				(width 0.1524)
				(type default)
			)
			(layer "F.SilkS")
		)
		(fp_line
			(start -0.12065 -0.305054)
			(end -0.12065 -0.2794)
			(stroke
				(width 0.1)
				(type default)
			)
			(layer "F.Fab")
		)
		(fp_line
			(start -0.67945 -0.305054)
			(end -0.12065 -0.305054)
			(stroke
				(width 0.1)
				(type default)
			)
			(layer "F.Fab")
		)
		(fp_line
			(start 0.67945 -0.3048)
			(end 0.67945 0.3048)
			(stroke
				(width 0.1)
				(type default)
			)
			(layer "F.Fab")
		)
		(fp_line
			(start 0.12065 -0.3048)
			(end 0.67945 -0.3048)
			(stroke
				(width 0.1)
				(type default)
			)
			(layer "F.Fab")
		)
		(fp_line
			(start 0.12065 -0.2794)
			(end 0.12065 -0.3048)
			(stroke
				(width 0.1)
				(type default)
			)
			(layer "F.Fab")
		)
		(fp_line
			(start -0.12065 -0.2794)
			(end 0.12065 -0.2794)
			(stroke
				(width 0.1)
				(type default)
			)
			(layer "F.Fab")
		)
		(fp_line
			(start 0.120396 0.2794)
			(end -0.12065 0.2794)
			(stroke
				(width 0.1)
				(type default)
			)
			(layer "F.Fab")
		)
		(fp_line
			(start -0.12065 0.2794)
			(end -0.12065 0.3048)
			(stroke
				(width 0.1)
				(type default)
			)
			(layer "F.Fab")
		)
		(fp_line
			(start 0.67945 0.3048)
			(end 0.120396 0.3048)
			(stroke
				(width 0.1)
				(type default)
			)
			(layer "F.Fab")
		)
		(fp_line
			(start 0.120396 0.3048)
			(end 0.120396 0.2794)
			(stroke
				(width 0.1)
				(type default)
			)
			(layer "F.Fab")
		)
		(fp_line
			(start -0.12065 0.3048)
			(end -0.67945 0.3048)
			(stroke
				(width 0.1)
				(type default)
			)
			(layer "F.Fab")
		)
		(fp_line
			(start -0.67945 0.3048)
			(end -0.67945 -0.305054)
			(stroke
				(width 0.1)
				(type default)
			)
			(layer "F.Fab")
		)
		(pad "1" smd circle
			(at -0.40005 0 90)
			(size 0 0)
			(layers "F.Cu" "F.Mask" "F.Paste")
			(net "P1V05_PCH_AUX")
		)
		(pad "2" smd circle
			(at 0.40005 0 90)
			(size 0 0)
			(layers "F.Cu" "F.Mask" "F.Paste")
			(net "H_DBP_PREQ_N_PCH")
		)
	)
	(footprint ""
		(layer "F.Cu")
		(at 361.412282 -57.898792 180)
		(property "Reference" "R753"
			(at 0 0 180)
			(layer "F.SilkS")
			(hide yes)
			(effects
				(font
					(size 1.27 1.27)
				)
			)
		)
		(property "Value" ""
			(at 0 0 180)
			(layer "F.Fab")
			(effects
				(font
					(size 1.27 1.27)
				)
			)
		)
		(duplicate_pad_numbers_are_jumpers no)
		(fp_line
			(start 0.7874 0.4064)
			(end -0.7874 0.4064)
			(stroke
				(width 0.1524)
				(type default)
			)
			(layer "F.SilkS")
		)
		(fp_line
			(start 0.7874 -0.4064)
			(end 0.7874 0.4064)
			(stroke
				(width 0.1524)
				(type default)
			)
			(layer "F.SilkS")
		)
		(fp_line
			(start -0.7874 0.4064)
			(end -0.7874 -0.4064)
			(stroke
				(width 0.1524)
				(type default)
			)
			(layer "F.SilkS")
		)
		(fp_line
			(start -0.7874 -0.4064)
			(end 0.7874 -0.4064)
			(stroke
				(width 0.1524)
				(type default)
			)
			(layer "F.SilkS")
		)
		(fp_line
			(start 0.67945 0.3048)
			(end 0.120396 0.3048)
			(stroke
				(width 0.1)
				(type default)
			)
			(layer "F.Fab")
		)
		(fp_line
			(start 0.67945 -0.3048)
			(end 0.67945 0.3048)
			(stroke
				(width 0.1)
				(type default)
			)
			(layer "F.Fab")
		)
		(fp_line
			(start 0.12065 -0.2794)
			(end 0.12065 -0.3048)
			(stroke
				(width 0.1)
				(type default)
			)
			(layer "F.Fab")
		)
		(fp_line
			(start 0.12065 -0.3048)
			(end 0.67945 -0.3048)
			(stroke
				(width 0.1)
				(type default)
			)
			(layer "F.Fab")
		)
		(fp_line
			(start 0.120396 0.3048)
			(end 0.120396 0.2794)
			(stroke
				(width 0.1)
				(type default)
			)
			(layer "F.Fab")
		)
		(fp_line
			(start 0.120396 0.2794)
			(end -0.12065 0.2794)
			(stroke
				(width 0.1)
				(type default)
			)
			(layer "F.Fab")
		)
		(fp_line
			(start -0.12065 0.3048)
			(end -0.67945 0.3048)
			(stroke
				(width 0.1)
				(type default)
			)
			(layer "F.Fab")
		)
		(fp_line
			(start -0.12065 0.2794)
			(end -0.12065 0.3048)
			(stroke
				(width 0.1)
				(type default)
			)
			(layer "F.Fab")
		)
		(fp_line
			(start -0.12065 -0.2794)
			(end 0.12065 -0.2794)
			(stroke
				(width 0.1)
				(type default)
			)
			(layer "F.Fab")
		)
		(fp_line
			(start -0.12065 -0.305054)
			(end -0.12065 -0.2794)
			(stroke
				(width 0.1)
				(type default)
			)
			(layer "F.Fab")
		)
		(fp_line
			(start -0.67945 0.3048)
			(end -0.67945 -0.305054)
			(stroke
				(width 0.1)
				(type default)
			)
			(layer "F.Fab")
		)
		(fp_line
			(start -0.67945 -0.305054)
			(end -0.12065 -0.305054)
			(stroke
				(width 0.1)
				(type default)
			)
			(layer "F.Fab")
		)
		(pad "1" smd circle
			(at -0.40005 0 180)
			(size 0 0)
			(layers "F.Cu" "F.Mask" "F.Paste")
			(net "JTAG_DBP_TDI")
		)
		(pad "2" smd circle
			(at 0.40005 0 180)
			(size 0 0)
			(layers "F.Cu" "F.Mask" "F.Paste")
			(net "JTAG_DBP_TDI_PCH")
		)
	)
	(footprint ""
		(layer "F.Cu")
		(at 461.593946 -108.694728)
		(property "Reference" "R1148"
			(at 0 0 0)
			(layer "F.SilkS")
			(hide yes)
			(effects
				(font
					(size 1.27 1.27)
				)
			)
		)
		(property "Value" ""
			(at 0 0 0)
			(layer "F.Fab")
			(effects
				(font
					(size 1.27 1.27)
				)
			)
		)
		(duplicate_pad_numbers_are_jumpers no)
		(fp_line
			(start -0.7874 -0.4064)
			(end 0.7874 -0.4064)
			(stroke
				(width 0.1524)
				(type default)
			)
			(layer "F.SilkS")
		)
		(fp_line
			(start -0.7874 0.4064)
			(end -0.7874 -0.4064)
			(stroke
				(width 0.1524)
				(type default)
			)
			(layer "F.SilkS")
		)
		(fp_line
			(start 0.7874 -0.4064)
			(end 0.7874 0.4064)
			(stroke
				(width 0.1524)
				(type default)
			)
			(layer "F.SilkS")
		)
		(fp_line
			(start 0.7874 0.4064)
			(end -0.7874 0.4064)
			(stroke
				(width 0.1524)
				(type default)
			)
			(layer "F.SilkS")
		)
		(fp_line
			(start -0.67945 -0.305054)
			(end -0.12065 -0.305054)
			(stroke
				(width 0.1)
				(type default)
			)
			(layer "F.Fab")
		)
		(fp_line
			(start -0.67945 0.3048)
			(end -0.67945 -0.305054)
			(stroke
				(width 0.1)
				(type default)
			)
			(layer "F.Fab")
		)
		(fp_line
			(start -0.12065 -0.305054)
			(end -0.12065 -0.2794)
			(stroke
				(width 0.1)
				(type default)
			)
			(layer "F.Fab")
		)
		(fp_line
			(start -0.12065 -0.2794)
			(end 0.12065 -0.2794)
			(stroke
				(width 0.1)
				(type default)
			)
			(layer "F.Fab")
		)
		(fp_line
			(start -0.12065 0.2794)
			(end -0.12065 0.3048)
			(stroke
				(width 0.1)
				(type default)
			)
			(layer "F.Fab")
		)
		(fp_line
			(start -0.12065 0.3048)
			(end -0.67945 0.3048)
			(stroke
				(width 0.1)
				(type default)
			)
			(layer "F.Fab")
		)
		(fp_line
			(start 0.120396 0.2794)
			(end -0.12065 0.2794)
			(stroke
				(width 0.1)
				(type default)
			)
			(layer "F.Fab")
		)
		(fp_line
			(start 0.120396 0.3048)
			(end 0.120396 0.2794)
			(stroke
				(width 0.1)
				(type default)
			)
			(layer "F.Fab")
		)
		(fp_line
			(start 0.12065 -0.3048)
			(end 0.67945 -0.3048)
			(stroke
				(width 0.1)
				(type default)
			)
			(layer "F.Fab")
		)
		(fp_line
			(start 0.12065 -0.2794)
			(end 0.12065 -0.3048)
			(stroke
				(width 0.1)
				(type default)
			)
			(layer "F.Fab")
		)
		(fp_line
			(start 0.67945 -0.3048)
			(end 0.67945 0.3048)
			(stroke
				(width 0.1)
				(type default)
			)
			(layer "F.Fab")
		)
		(fp_line
			(start 0.67945 0.3048)
			(end 0.120396 0.3048)
			(stroke
				(width 0.1)
				(type default)
			)
			(layer "F.Fab")
		)
		(pad "1" smd circle
			(at -0.40005 0)
			(size 0 0)
			(layers "F.Cu" "F.Mask" "F.Paste")
			(net "HP_LVC3_OCP_V3_1_PRSNT2_N_R")
		)
		(pad "2" smd circle
			(at 0.40005 0)
			(size 0 0)
			(layers "F.Cu" "F.Mask" "F.Paste")
			(net "HP_LVC3_OCP_V3_1_PRSNT2_N")
		)
	)
	(footprint ""
		(layer "F.Cu")
		(at 299.02023 -51.352196)
		(property "Reference" "R2232"
			(at 0 0 0)
			(layer "F.SilkS")
			(hide yes)
			(effects
				(font
					(size 1.27 1.27)
				)
			)
		)
		(property "Value" ""
			(at 0 0 0)
			(layer "F.Fab")
			(effects
				(font
					(size 1.27 1.27)
				)
			)
		)
		(duplicate_pad_numbers_are_jumpers no)
		(fp_line
			(start -0.7874 -0.4064)
			(end 0.7874 -0.4064)
			(stroke
				(width 0.1524)
				(type default)
			)
			(layer "F.SilkS")
		)
		(fp_line
			(start -0.7874 0.4064)
			(end -0.7874 -0.4064)
			(stroke
				(width 0.1524)
				(type default)
			)
			(layer "F.SilkS")
		)
		(fp_line
			(start 0.7874 -0.4064)
			(end 0.7874 0.4064)
			(stroke
				(width 0.1524)
				(type default)
			)
			(layer "F.SilkS")
		)
		(fp_line
			(start 0.7874 0.4064)
			(end -0.7874 0.4064)
			(stroke
				(width 0.1524)
				(type default)
			)
			(layer "F.SilkS")
		)
		(fp_line
			(start -0.67945 -0.305054)
			(end -0.12065 -0.305054)
			(stroke
				(width 0.1)
				(type default)
			)
			(layer "F.Fab")
		)
		(fp_line
			(start -0.67945 0.3048)
			(end -0.67945 -0.305054)
			(stroke
				(width 0.1)
				(type default)
			)
			(layer "F.Fab")
		)
		(fp_line
			(start -0.12065 -0.305054)
			(end -0.12065 -0.2794)
			(stroke
				(width 0.1)
				(type default)
			)
			(layer "F.Fab")
		)
		(fp_line
			(start -0.12065 -0.2794)
			(end 0.12065 -0.2794)
			(stroke
				(width 0.1)
				(type default)
			)
			(layer "F.Fab")
		)
		(fp_line
			(start -0.12065 0.2794)
			(end -0.12065 0.3048)
			(stroke
				(width 0.1)
				(type default)
			)
			(layer "F.Fab")
		)
		(fp_line
			(start -0.12065 0.3048)
			(end -0.67945 0.3048)
			(stroke
				(width 0.1)
				(type default)
			)
			(layer "F.Fab")
		)
		(fp_line
			(start 0.120396 0.2794)
			(end -0.12065 0.2794)
			(stroke
				(width 0.1)
				(type default)
			)
			(layer "F.Fab")
		)
		(fp_line
			(start 0.120396 0.3048)
			(end 0.120396 0.2794)
			(stroke
				(width 0.1)
				(type default)
			)
			(layer "F.Fab")
		)
		(fp_line
			(start 0.12065 -0.3048)
			(end 0.67945 -0.3048)
			(stroke
				(width 0.1)
				(type default)
			)
			(layer "F.Fab")
		)
		(fp_line
			(start 0.12065 -0.2794)
			(end 0.12065 -0.3048)
			(stroke
				(width 0.1)
				(type default)
			)
			(layer "F.Fab")
		)
		(fp_line
			(start 0.67945 -0.3048)
			(end 0.67945 0.3048)
			(stroke
				(width 0.1)
				(type default)
			)
			(layer "F.Fab")
		)
		(fp_line
			(start 0.67945 0.3048)
			(end 0.120396 0.3048)
			(stroke
				(width 0.1)
				(type default)
			)
			(layer "F.Fab")
		)
		(pad "1" smd circle
			(at -0.40005 0)
			(size 0 0)
			(layers "F.Cu" "F.Mask" "F.Paste")
			(net "P1V05_PCH_AUX")
		)
		(pad "2" smd circle
			(at 0.40005 0)
			(size 0 0)
			(layers "F.Cu" "F.Mask" "F.Paste")
			(net "FAB_REV_ID0")
		)
	)
	(footprint ""
		(layer "F.Cu")
		(at 58.93308 -39.148004)
		(property "Reference" "R4060"
			(at 0 0 0)
			(layer "F.SilkS")
			(hide yes)
			(effects
				(font
					(size 1.27 1.27)
				)
			)
		)
		(property "Value" ""
			(at 0 0 0)
			(layer "F.Fab")
			(effects
				(font
					(size 1.27 1.27)
				)
			)
		)
		(duplicate_pad_numbers_are_jumpers no)
		(fp_line
			(start -0.7874 -0.4064)
			(end 0.7874 -0.4064)
			(stroke
				(width 0.1524)
				(type default)
			)
			(layer "F.SilkS")
		)
		(fp_line
			(start -0.7874 0.4064)
			(end -0.7874 -0.4064)
			(stroke
				(width 0.1524)
				(type default)
			)
			(layer "F.SilkS")
		)
		(fp_line
			(start 0.7874 -0.4064)
			(end 0.7874 0.4064)
			(stroke
				(width 0.1524)
				(type default)
			)
			(layer "F.SilkS")
		)
		(fp_line
			(start 0.7874 0.4064)
			(end -0.7874 0.4064)
			(stroke
				(width 0.1524)
				(type default)
			)
			(layer "F.SilkS")
		)
		(fp_line
			(start -0.67945 -0.305054)
			(end -0.12065 -0.305054)
			(stroke
				(width 0.1)
				(type default)
			)
			(layer "F.Fab")
		)
		(fp_line
			(start -0.67945 0.3048)
			(end -0.67945 -0.305054)
			(stroke
				(width 0.1)
				(type default)
			)
			(layer "F.Fab")
		)
		(fp_line
			(start -0.12065 -0.305054)
			(end -0.12065 -0.2794)
			(stroke
				(width 0.1)
				(type default)
			)
			(layer "F.Fab")
		)
		(fp_line
			(start -0.12065 -0.2794)
			(end 0.12065 -0.2794)
			(stroke
				(width 0.1)
				(type default)
			)
			(layer "F.Fab")
		)
		(fp_line
			(start -0.12065 0.2794)
			(end -0.12065 0.3048)
			(stroke
				(width 0.1)
				(type default)
			)
			(layer "F.Fab")
		)
		(fp_line
			(start -0.12065 0.3048)
			(end -0.67945 0.3048)
			(stroke
				(width 0.1)
				(type default)
			)
			(layer "F.Fab")
		)
		(fp_line
			(start 0.120396 0.2794)
			(end -0.12065 0.2794)
			(stroke
				(width 0.1)
				(type default)
			)
			(layer "F.Fab")
		)
		(fp_line
			(start 0.120396 0.3048)
			(end 0.120396 0.2794)
			(stroke
				(width 0.1)
				(type default)
			)
			(layer "F.Fab")
		)
		(fp_line
			(start 0.12065 -0.3048)
			(end 0.67945 -0.3048)
			(stroke
				(width 0.1)
				(type default)
			)
			(layer "F.Fab")
		)
		(fp_line
			(start 0.12065 -0.2794)
			(end 0.12065 -0.3048)
			(stroke
				(width 0.1)
				(type default)
			)
			(layer "F.Fab")
		)
		(fp_line
			(start 0.67945 -0.3048)
			(end 0.67945 0.3048)
			(stroke
				(width 0.1)
				(type default)
			)
			(layer "F.Fab")
		)
		(fp_line
			(start 0.67945 0.3048)
			(end 0.120396 0.3048)
			(stroke
				(width 0.1)
				(type default)
			)
			(layer "F.Fab")
		)
		(pad "1" smd circle
			(at -0.40005 0)
			(size 0 0)
			(layers "F.Cu" "F.Mask" "F.Paste")
			(net "HP_LVC3_OCP_V3_2_EN")
		)
		(pad "2" smd circle
			(at 0.40005 0)
			(size 0 0)
			(layers "F.Cu" "F.Mask" "F.Paste")
			(net "P3V3_OCP_EN_2_R")
		)
	)
	(footprint ""
		(layer "F.Cu")
		(at 180.77688 -41.112948)
		(property "Reference" "R2526"
			(at 0 0 0)
			(layer "F.SilkS")
			(hide yes)
			(effects
				(font
					(size 1.27 1.27)
				)
			)
		)
		(property "Value" ""
			(at 0 0 0)
			(layer "F.Fab")
			(effects
				(font
					(size 1.27 1.27)
				)
			)
		)
		(duplicate_pad_numbers_are_jumpers no)
		(fp_line
			(start -0.7874 -0.4064)
			(end 0.7874 -0.4064)
			(stroke
				(width 0.1524)
				(type default)
			)
			(layer "F.SilkS")
		)
		(fp_line
			(start -0.7874 0.4064)
			(end -0.7874 -0.4064)
			(stroke
				(width 0.1524)
				(type default)
			)
			(layer "F.SilkS")
		)
		(fp_line
			(start 0.7874 -0.4064)
			(end 0.7874 0.4064)
			(stroke
				(width 0.1524)
				(type default)
			)
			(layer "F.SilkS")
		)
		(fp_line
			(start 0.7874 0.4064)
			(end -0.7874 0.4064)
			(stroke
				(width 0.1524)
				(type default)
			)
			(layer "F.SilkS")
		)
		(fp_line
			(start -0.67945 -0.305054)
			(end -0.12065 -0.305054)
			(stroke
				(width 0.1)
				(type default)
			)
			(layer "F.Fab")
		)
		(fp_line
			(start -0.67945 0.3048)
			(end -0.67945 -0.305054)
			(stroke
				(width 0.1)
				(type default)
			)
			(layer "F.Fab")
		)
		(fp_line
			(start -0.12065 -0.305054)
			(end -0.12065 -0.2794)
			(stroke
				(width 0.1)
				(type default)
			)
			(layer "F.Fab")
		)
		(fp_line
			(start -0.12065 -0.2794)
			(end 0.12065 -0.2794)
			(stroke
				(width 0.1)
				(type default)
			)
			(layer "F.Fab")
		)
		(fp_line
			(start -0.12065 0.2794)
			(end -0.12065 0.3048)
			(stroke
				(width 0.1)
				(type default)
			)
			(layer "F.Fab")
		)
		(fp_line
			(start -0.12065 0.3048)
			(end -0.67945 0.3048)
			(stroke
				(width 0.1)
				(type default)
			)
			(layer "F.Fab")
		)
		(fp_line
			(start 0.120396 0.2794)
			(end -0.12065 0.2794)
			(stroke
				(width 0.1)
				(type default)
			)
			(layer "F.Fab")
		)
		(fp_line
			(start 0.120396 0.3048)
			(end 0.120396 0.2794)
			(stroke
				(width 0.1)
				(type default)
			)
			(layer "F.Fab")
		)
		(fp_line
			(start 0.12065 -0.3048)
			(end 0.67945 -0.3048)
			(stroke
				(width 0.1)
				(type default)
			)
			(layer "F.Fab")
		)
		(fp_line
			(start 0.12065 -0.2794)
			(end 0.12065 -0.3048)
			(stroke
				(width 0.1)
				(type default)
			)
			(layer "F.Fab")
		)
		(fp_line
			(start 0.67945 -0.3048)
			(end 0.67945 0.3048)
			(stroke
				(width 0.1)
				(type default)
			)
			(layer "F.Fab")
		)
		(fp_line
			(start 0.67945 0.3048)
			(end 0.120396 0.3048)
			(stroke
				(width 0.1)
				(type default)
			)
			(layer "F.Fab")
		)
		(pad "1" smd circle
			(at -0.40005 0)
			(size 0 0)
			(layers "F.Cu" "F.Mask" "F.Paste")
			(net "FM_M2_SSD_0_PEDET")
		)
		(pad "2" smd circle
			(at 0.40005 0)
			(size 0 0)
			(layers "F.Cu" "F.Mask" "F.Paste")
			(net "FM_M2_SSD0_E7_PEDET")
		)
	)
	(footprint ""
		(layer "F.Cu")
		(at 238.45012 -435.58206 -90)
		(property "Reference" "J45"
			(at 7.573772 -37.93236 0)
			(unlocked yes)
			(layer "F.SilkS")
			(effects
				(font
					(size 0.7874 0.5842)
					(thickness 0.1524)
				)
				(justify left)
			)
		)
		(property "Value" ""
			(at 0 0 270)
			(layer "F.Fab")
			(effects
				(font
					(size 1.27 1.27)
				)
			)
		)
		(duplicate_pad_numbers_are_jumpers no)
		(fp_line
			(start -18.370042 42.494962)
			(end -18.370042 -37.414962)
			(stroke
				(width 0.1524)
				(type default)
			)
			(layer "F.SilkS")
		)
		(fp_line
			(start 11.679936 42.494962)
			(end -18.370042 42.494962)
			(stroke
				(width 0.1524)
				(type default)
			)
			(layer "F.SilkS")
		)
		(fp_line
			(start -15.370048 39.494968)
			(end -15.370048 -34.414968)
			(stroke
				(width 0.1524)
				(type default)
			)
			(layer "F.SilkS")
		)
		(fp_line
			(start -0.712978 39.494968)
			(end -15.370048 39.494968)
			(stroke
				(width 0.1524)
				(type default)
			)
			(layer "F.SilkS")
		)
		(fp_line
			(start 8.24992 39.494968)
			(end 5.792978 39.494968)
			(stroke
				(width 0.1524)
				(type default)
			)
			(layer "F.SilkS")
		)
		(fp_line
			(start 8.24992 31.218632)
			(end 8.24992 39.494968)
			(stroke
				(width 0.1524)
				(type default)
			)
			(layer "F.SilkS")
		)
		(fp_line
			(start 8.24992 22.328632)
			(end 8.24992 27.201368)
			(stroke
				(width 0.1524)
				(type default)
			)
			(layer "F.SilkS")
		)
		(fp_line
			(start 8.24992 13.438632)
			(end 8.24992 18.311368)
			(stroke
				(width 0.1524)
				(type default)
			)
			(layer "F.SilkS")
		)
		(fp_line
			(start 8.24992 5.818632)
			(end 8.24992 9.421368)
			(stroke
				(width 0.1524)
				(type default)
			)
			(layer "F.SilkS")
		)
		(fp_line
			(start 8.24992 -4.341368)
			(end 8.24992 -0.738632)
			(stroke
				(width 0.1524)
				(type default)
			)
			(layer "F.SilkS")
		)
		(fp_line
			(start 8.24992 -13.231368)
			(end 8.24992 -8.358632)
			(stroke
				(width 0.1524)
				(type default)
			)
			(layer "F.SilkS")
		)
		(fp_line
			(start 8.24992 -22.121368)
			(end 8.24992 -17.248632)
			(stroke
				(width 0.1524)
				(type default)
			)
			(layer "F.SilkS")
		)
		(fp_line
			(start -15.370048 -34.414968)
			(end -0.712978 -34.414968)
			(stroke
				(width 0.1524)
				(type default)
			)
			(layer "F.SilkS")
		)
		(fp_line
			(start -5.08 -34.414968)
			(end -5.08 39.494968)
			(stroke
				(width 0.1524)
				(type default)
			)
			(layer "F.SilkS")
		)
		(fp_line
			(start 5.792978 -34.414968)
			(end 8.24992 -34.414968)
			(stroke
				(width 0.1524)
				(type default)
			)
			(layer "F.SilkS")
		)
		(fp_line
			(start 8.24992 -34.414968)
			(end 8.24992 -26.138632)
			(stroke
				(width 0.1524)
				(type default)
			)
			(layer "F.SilkS")
		)
		(fp_line
			(start -18.370042 -37.414962)
			(end 11.679936 -37.414962)
			(stroke
				(width 0.1524)
				(type default)
			)
			(layer "F.SilkS")
		)
		(fp_line
			(start 11.679936 -37.414962)
			(end 11.679936 42.494962)
			(stroke
				(width 0.1524)
				(type default)
			)
			(layer "F.SilkS")
		)
		(fp_poly
			(pts
				(xy -4.9022 -0.508) (xy -4.9022 0.508) (xy -3.8862 0)
			)
			(stroke
				(width 0)
				(type default)
			)
			(fill yes)
			(layer "F.SilkS")
		)
		(fp_line
			(start -18.370042 42.494962)
			(end -18.370042 -37.414962)
			(stroke
				(width 0.1524)
				(type default)
			)
			(layer "B.SilkS")
		)
		(fp_line
			(start 11.679936 42.494962)
			(end -18.370042 42.494962)
			(stroke
				(width 0.1524)
				(type default)
			)
			(layer "B.SilkS")
		)
		(fp_line
			(start -18.370042 -37.414962)
			(end 11.679936 -37.414962)
			(stroke
				(width 0.1524)
				(type default)
			)
			(layer "B.SilkS")
		)
		(fp_line
			(start 11.679936 -37.414962)
			(end 11.679936 42.494962)
			(stroke
				(width 0.1524)
				(type default)
			)
			(layer "B.SilkS")
		)
		(fp_line
			(start -18.370042 42.494962)
			(end -18.370042 -37.414962)
			(stroke
				(width 0.1)
				(type default)
			)
			(layer "B.Fab")
		)
		(fp_line
			(start 11.679936 42.494962)
			(end -18.370042 42.494962)
			(stroke
				(width 0.1)
				(type default)
			)
			(layer "B.Fab")
		)
		(fp_line
			(start -18.370042 -37.414962)
			(end 11.679936 -37.414962)
			(stroke
				(width 0.1)
				(type default)
			)
			(layer "B.Fab")
		)
		(fp_line
			(start 11.679936 -37.414962)
			(end 11.679936 42.494962)
			(stroke
				(width 0.1)
				(type default)
			)
			(layer "B.Fab")
		)
		(fp_line
			(start -15.370048 39.494968)
			(end -15.370048 -34.414968)
			(stroke
				(width 0.1)
				(type default)
			)
			(layer "F.Fab")
		)
		(fp_line
			(start 8.24992 39.494968)
			(end -15.370048 39.494968)
			(stroke
				(width 0.1)
				(type default)
			)
			(layer "F.Fab")
		)
		(fp_line
			(start -15.370048 -34.414968)
			(end 8.24992 -34.414968)
			(stroke
				(width 0.1)
				(type default)
			)
			(layer "F.Fab")
		)
		(fp_line
			(start 8.24992 -34.414968)
			(end 8.24992 39.494968)
			(stroke
				(width 0.1)
				(type default)
			)
			(layer "F.Fab")
		)
		(fp_poly
			(pts
				(xy -4.9022 -0.508) (xy -4.9022 0.508) (xy -3.8862 0)
			)
			(stroke
				(width 0)
				(type default)
			)
			(fill yes)
			(layer "F.Fab")
		)
		(fp_text user "PRESS-FIT"
			(at 10.12825 9.70026 0)
			(unlocked yes)
			(layer "F.SilkS")
			(effects
				(font
					(size 1.905 1.4224)
					(thickness 0.1524)
				)
				(justify left)
			)
		)
		(fp_text user "PRESS-FIT"
			(at 10.14857 -9.18464 0)
			(unlocked yes)
			(layer "B.SilkS")
			(effects
				(font
					(size 1.905 1.4224)
					(thickness 0.1524)
				)
				(justify left mirror)
			)
		)
		(fp_text user "PRESS-FIT"
			(at 10.275316 -5.7912 0)
			(unlocked yes)
			(layer "B.Fab")
			(effects
				(font
					(size 1.905 1.4224)
					(thickness 0.1524)
				)
				(justify left mirror)
			)
		)
		(fp_text user "PRESS-FIT"
			(at 10.275316 10.8712 0)
			(unlocked yes)
			(layer "F.Fab")
			(effects
				(font
					(size 1.905 1.4224)
					(thickness 0.1524)
				)
				(justify left)
			)
		)
		(pad "" np_thru_hole circle
			(at 2.54 -32.385 270)
			(size 0 0)
			(drill 3.048)
			(layers "*.Cu" "*.Mask")
			(clearance 0)
		)
		(pad "" np_thru_hole circle
			(at 2.54 37.465 270)
			(size 0 0)
			(drill 3.048)
			(layers "*.Cu" "*.Mask")
			(clearance 0)
		)
		(pad "A1" thru_hole rect
			(at 0 0 270)
			(size 1.669796 1.669796)
			(drill 1.01981)
			(layers "*.Cu" "*.Mask")
			(remove_unused_layers no)
			(net "TP_J45_A1")
			(clearance -0.070866)
			(padstack
				(mode front_inner_back)
				(layer "Inner"
					(shape circle)
					(size 1.669796 1.669796)
					(clearance -0.070866)
				)
				(layer "B.Cu"
					(shape rect)
					(size 1.669796 1.669796)
					(clearance -0.070866)
				)
			)
		)
		(pad "A2" thru_hole circle
			(at 0 2.54 270)
			(size 1.669796 1.669796)
			(drill 1.01981)
			(layers "*.Cu" "*.Mask")
			(remove_unused_layers no)
			(net "FM_AC_PWR_BTN_PDB_N")
			(clearance -0.070866)
		)
		(pad "A3" thru_hole circle
			(at 0 5.08 270)
			(size 1.669796 1.669796)
			(drill 1.01981)
			(layers "*.Cu" "*.Mask")
			(remove_unused_layers no)
			(net "P3V3_PDB_AUX_ADC")
			(clearance -0.070866)
		)
		(pad "B1" thru_hole circle
			(at 2.54 0 270)
			(size 1.669796 1.669796)
			(drill 1.01981)
			(layers "*.Cu" "*.Mask")
			(remove_unused_layers no)
			(net "RST_SMB_SWITCH_R_N")
			(clearance -0.070866)
		)
		(pad "B2" thru_hole circle
			(at 2.54 2.54 270)
			(size 1.669796 1.669796)
			(drill 1.01981)
			(layers "*.Cu" "*.Mask")
			(remove_unused_layers no)
			(net "PWRGD_P3V3_AUX_PDB_BUF")
			(clearance -0.070866)
		)
		(pad "B3" thru_hole circle
			(at 2.54 5.08 270)
			(size 1.669796 1.669796)
			(drill 1.01981)
			(layers "*.Cu" "*.Mask")
			(remove_unused_layers no)
			(net "GND")
			(clearance -0.070866)
		)
		(pad "C1" thru_hole circle
			(at 5.08 0 270)
			(size 1.669796 1.669796)
			(drill 1.01981)
			(layers "*.Cu" "*.Mask")
			(remove_unused_layers no)
			(net "SMB_FAN_3V3AUX_BUF_R_SCL")
			(clearance -0.070866)
		)
		(pad "C2" thru_hole circle
			(at 5.08 2.54 270)
			(size 1.669796 1.669796)
			(drill 1.01981)
			(layers "*.Cu" "*.Mask")
			(remove_unused_layers no)
			(net "SMB_FAN_3V3AUX_BUF_R_SDA")
			(clearance -0.070866)
		)
		(pad "C3" thru_hole circle
			(at 5.08 5.08 270)
			(size 1.669796 1.669796)
			(drill 1.01981)
			(layers "*.Cu" "*.Mask")
			(remove_unused_layers no)
			(net "HPDB_HSC_PWRGD_R")
			(clearance -0.070866)
		)
		(pad "D1" thru_hole circle
			(at 7.62 0 270)
			(size 1.669796 1.669796)
			(drill 1.01981)
			(layers "*.Cu" "*.Mask")
			(remove_unused_layers no)
			(net "FM_FAN_PWR_EN_R")
			(clearance -0.070866)
		)
		(pad "D2" thru_hole circle
			(at 7.62 2.54 270)
			(size 1.669796 1.669796)
			(drill 1.01981)
			(layers "*.Cu" "*.Mask")
			(remove_unused_layers no)
			(net "FM_GPU_HSC_EN_BUF_R1")
			(clearance -0.070866)
		)
		(pad "D3" thru_hole circle
			(at 7.62 5.08 270)
			(size 1.669796 1.669796)
			(drill 1.01981)
			(layers "*.Cu" "*.Mask")
			(remove_unused_layers no)
			(net "PDB_PRSNT_N")
			(clearance -0.070866)
		)
		(pad "P1_1" thru_hole circle
			(at 0 -25.4 270)
			(size 1.669796 1.669796)
			(drill 1.01981)
			(layers "*.Cu" "*.Mask")
			(remove_unused_layers no)
			(net "GND")
			(clearance -0.070866)
		)
		(pad "P1_2" thru_hole circle
			(at 2.54 -25.4 270)
			(size 1.669796 1.669796)
			(drill 1.01981)
			(layers "*.Cu" "*.Mask")
			(remove_unused_layers no)
			(net "GND")
			(clearance -0.070866)
		)
		(pad "P1_3" thru_hole circle
			(at 5.08 -25.4 270)
			(size 1.669796 1.669796)
			(drill 1.01981)
			(layers "*.Cu" "*.Mask")
			(remove_unused_layers no)
			(net "GND")
			(clearance -0.070866)
		)
		(pad "P1_4" thru_hole circle
			(at 7.62 -25.4 270)
			(size 1.669796 1.669796)
			(drill 1.01981)
			(layers "*.Cu" "*.Mask")
			(remove_unused_layers no)
			(net "GND")
			(clearance -0.070866)
		)
		(pad "P1_5" thru_hole circle
			(at 0 -22.86 270)
			(size 1.669796 1.669796)
			(drill 1.01981)
			(layers "*.Cu" "*.Mask")
			(remove_unused_layers no)
			(net "GND")
			(clearance -0.070866)
		)
		(pad "P1_6" thru_hole circle
			(at 2.54 -22.86 270)
			(size 1.669796 1.669796)
			(drill 1.01981)
			(layers "*.Cu" "*.Mask")
			(remove_unused_layers no)
			(net "GND")
			(clearance -0.070866)
		)
		(pad "P1_7" thru_hole circle
			(at 5.08 -22.86 270)
			(size 1.669796 1.669796)
			(drill 1.01981)
			(layers "*.Cu" "*.Mask")
			(remove_unused_layers no)
			(net "GND")
			(clearance -0.070866)
		)
		(pad "P1_8" thru_hole circle
			(at 7.62 -22.86 270)
			(size 1.669796 1.669796)
			(drill 1.01981)
			(layers "*.Cu" "*.Mask")
			(remove_unused_layers no)
			(net "GND")
			(clearance -0.070866)
		)
		(pad "P2_1" thru_hole circle
			(at 0 -16.51 270)
			(size 1.669796 1.669796)
			(drill 1.01981)
			(layers "*.Cu" "*.Mask")
			(remove_unused_layers no)
			(net "GND")
			(clearance -0.070866)
		)
		(pad "P2_2" thru_hole circle
			(at 2.54 -16.51 270)
			(size 1.669796 1.669796)
			(drill 1.01981)
			(layers "*.Cu" "*.Mask")
			(remove_unused_layers no)
			(net "GND")
			(clearance -0.070866)
		)
		(pad "P2_3" thru_hole circle
			(at 5.08 -16.51 270)
			(size 1.669796 1.669796)
			(drill 1.01981)
			(layers "*.Cu" "*.Mask")
			(remove_unused_layers no)
			(net "GND")
			(clearance -0.070866)
		)
		(pad "P2_4" thru_hole circle
			(at 7.62 -16.51 270)
			(size 1.669796 1.669796)
			(drill 1.01981)
			(layers "*.Cu" "*.Mask")
			(remove_unused_layers no)
			(net "GND")
			(clearance -0.070866)
		)
		(pad "P2_5" thru_hole circle
			(at 0 -13.97 270)
			(size 1.669796 1.669796)
			(drill 1.01981)
			(layers "*.Cu" "*.Mask")
			(remove_unused_layers no)
			(net "GND")
			(clearance -0.070866)
		)
		(pad "P2_6" thru_hole circle
			(at 2.54 -13.97 270)
			(size 1.669796 1.669796)
			(drill 1.01981)
			(layers "*.Cu" "*.Mask")
			(remove_unused_layers no)
			(net "GND")
			(clearance -0.070866)
		)
		(pad "P2_7" thru_hole circle
			(at 5.08 -13.97 270)
			(size 1.669796 1.669796)
			(drill 1.01981)
			(layers "*.Cu" "*.Mask")
			(remove_unused_layers no)
			(net "GND")
			(clearance -0.070866)
		)
		(pad "P2_8" thru_hole circle
			(at 7.62 -13.97 270)
			(size 1.669796 1.669796)
			(drill 1.01981)
			(layers "*.Cu" "*.Mask")
			(remove_unused_layers no)
			(net "GND")
			(clearance -0.070866)
		)
		(pad "P3_1" thru_hole circle
			(at 0 -7.62 270)
			(size 1.669796 1.669796)
			(drill 1.01981)
			(layers "*.Cu" "*.Mask")
			(remove_unused_layers no)
			(net "GND")
			(clearance -0.070866)
		)
		(pad "P3_2" thru_hole circle
			(at 2.54 -7.62 270)
			(size 1.669796 1.669796)
			(drill 1.01981)
			(layers "*.Cu" "*.Mask")
			(remove_unused_layers no)
			(net "GND")
			(clearance -0.070866)
		)
		(pad "P3_3" thru_hole circle
			(at 5.08 -7.62 270)
			(size 1.669796 1.669796)
			(drill 1.01981)
			(layers "*.Cu" "*.Mask")
			(remove_unused_layers no)
			(net "GND")
			(clearance -0.070866)
		)
		(pad "P3_4" thru_hole circle
			(at 7.62 -7.62 270)
			(size 1.669796 1.669796)
			(drill 1.01981)
			(layers "*.Cu" "*.Mask")
			(remove_unused_layers no)
			(net "GND")
			(clearance -0.070866)
		)
		(pad "P3_5" thru_hole circle
			(at 0 -5.08 270)
			(size 1.669796 1.669796)
			(drill 1.01981)
			(layers "*.Cu" "*.Mask")
			(remove_unused_layers no)
			(net "GND")
			(clearance -0.070866)
		)
		(pad "P3_6" thru_hole circle
			(at 2.54 -5.08 270)
			(size 1.669796 1.669796)
			(drill 1.01981)
			(layers "*.Cu" "*.Mask")
			(remove_unused_layers no)
			(net "GND")
			(clearance -0.070866)
		)
		(pad "P3_7" thru_hole circle
			(at 5.08 -5.08 270)
			(size 1.669796 1.669796)
			(drill 1.01981)
			(layers "*.Cu" "*.Mask")
			(remove_unused_layers no)
			(net "GND")
			(clearance -0.070866)
		)
		(pad "P3_8" thru_hole circle
			(at 7.62 -5.08 270)
			(size 1.669796 1.669796)
			(drill 1.01981)
			(layers "*.Cu" "*.Mask")
			(remove_unused_layers no)
			(net "GND")
			(clearance -0.070866)
		)
		(pad "P4_1" thru_hole circle
			(at 0 10.16 270)
			(size 1.669796 1.669796)
			(drill 1.01981)
			(layers "*.Cu" "*.Mask")
			(remove_unused_layers no)
			(net "P12V_PSU")
			(clearance -0.070866)
		)
		(pad "P4_2" thru_hole circle
			(at 2.54 10.16 270)
			(size 1.669796 1.669796)
			(drill 1.01981)
			(layers "*.Cu" "*.Mask")
			(remove_unused_layers no)
			(net "P12V_PSU")
			(clearance -0.070866)
		)
		(pad "P4_3" thru_hole circle
			(at 5.08 10.16 270)
			(size 1.669796 1.669796)
			(drill 1.01981)
			(layers "*.Cu" "*.Mask")
			(remove_unused_layers no)
			(net "P12V_PSU")
			(clearance -0.070866)
		)
		(pad "P4_4" thru_hole circle
			(at 7.62 10.16 270)
			(size 1.669796 1.669796)
			(drill 1.01981)
			(layers "*.Cu" "*.Mask")
			(remove_unused_layers no)
			(net "P12V_PSU")
			(clearance -0.070866)
		)
		(pad "P4_5" thru_hole circle
			(at 0 12.7 270)
			(size 1.669796 1.669796)
			(drill 1.01981)
			(layers "*.Cu" "*.Mask")
			(remove_unused_layers no)
			(net "P12V_PSU")
			(clearance -0.070866)
		)
		(pad "P4_6" thru_hole circle
			(at 2.54 12.7 270)
			(size 1.669796 1.669796)
			(drill 1.01981)
			(layers "*.Cu" "*.Mask")
			(remove_unused_layers no)
			(net "P12V_PSU")
			(clearance -0.070866)
		)
		(pad "P4_7" thru_hole circle
			(at 5.08 12.7 270)
			(size 1.669796 1.669796)
			(drill 1.01981)
			(layers "*.Cu" "*.Mask")
			(remove_unused_layers no)
			(net "P12V_PSU")
			(clearance -0.070866)
		)
		(pad "P4_8" thru_hole circle
			(at 7.62 12.7 270)
			(size 1.669796 1.669796)
			(drill 1.01981)
			(layers "*.Cu" "*.Mask")
			(remove_unused_layers no)
			(net "P12V_PSU")
			(clearance -0.070866)
		)
		(pad "P5_1" thru_hole circle
			(at 0 19.05 270)
			(size 1.669796 1.669796)
			(drill 1.01981)
			(layers "*.Cu" "*.Mask")
			(remove_unused_layers no)
			(net "P12V_PSU")
			(clearance -0.070866)
		)
		(pad "P5_2" thru_hole circle
			(at 2.54 19.05 270)
			(size 1.669796 1.669796)
			(drill 1.01981)
			(layers "*.Cu" "*.Mask")
			(remove_unused_layers no)
			(net "P12V_PSU")
			(clearance -0.070866)
		)
		(pad "P5_3" thru_hole circle
			(at 5.08 19.05 270)
			(size 1.669796 1.669796)
			(drill 1.01981)
			(layers "*.Cu" "*.Mask")
			(remove_unused_layers no)
			(net "P12V_PSU")
			(clearance -0.070866)
		)
		(pad "P5_4" thru_hole circle
			(at 7.62 19.05 270)
			(size 1.669796 1.669796)
			(drill 1.01981)
			(layers "*.Cu" "*.Mask")
			(remove_unused_layers no)
			(net "P12V_PSU")
			(clearance -0.070866)
		)
		(pad "P5_5" thru_hole circle
			(at 0 21.59 270)
			(size 1.669796 1.669796)
			(drill 1.01981)
			(layers "*.Cu" "*.Mask")
			(remove_unused_layers no)
			(net "P12V_PSU")
			(clearance -0.070866)
		)
		(pad "P5_6" thru_hole circle
			(at 2.54 21.59 270)
			(size 1.669796 1.669796)
			(drill 1.01981)
			(layers "*.Cu" "*.Mask")
			(remove_unused_layers no)
			(net "P12V_PSU")
			(clearance -0.070866)
		)
		(pad "P5_7" thru_hole circle
			(at 5.08 21.59 270)
			(size 1.669796 1.669796)
			(drill 1.01981)
			(layers "*.Cu" "*.Mask")
			(remove_unused_layers no)
			(net "P12V_PSU")
			(clearance -0.070866)
		)
		(pad "P5_8" thru_hole circle
			(at 7.62 21.59 270)
			(size 1.669796 1.669796)
			(drill 1.01981)
			(layers "*.Cu" "*.Mask")
			(remove_unused_layers no)
			(net "P12V_PSU")
			(clearance -0.070866)
		)
		(pad "P6_1" thru_hole circle
			(at 0 27.94 270)
			(size 1.669796 1.669796)
			(drill 1.01981)
			(layers "*.Cu" "*.Mask")
			(remove_unused_layers no)
			(net "P12V_PSU")
			(clearance -0.070866)
		)
		(pad "P6_2" thru_hole circle
			(at 2.54 27.94 270)
			(size 1.669796 1.669796)
			(drill 1.01981)
			(layers "*.Cu" "*.Mask")
			(remove_unused_layers no)
			(net "P12V_PSU")
			(clearance -0.070866)
		)
		(pad "P6_3" thru_hole circle
			(at 5.08 27.94 270)
			(size 1.669796 1.669796)
			(drill 1.01981)
			(layers "*.Cu" "*.Mask")
			(remove_unused_layers no)
			(net "P12V_PSU")
			(clearance -0.070866)
		)
		(pad "P6_4" thru_hole circle
			(at 7.62 27.94 270)
			(size 1.669796 1.669796)
			(drill 1.01981)
			(layers "*.Cu" "*.Mask")
			(remove_unused_layers no)
			(net "P12V_PSU")
			(clearance -0.070866)
		)
		(pad "P6_5" thru_hole circle
			(at 0 30.48 270)
			(size 1.669796 1.669796)
			(drill 1.01981)
			(layers "*.Cu" "*.Mask")
			(remove_unused_layers no)
			(net "P12V_PSU")
			(clearance -0.070866)
		)
		(pad "P6_6" thru_hole circle
			(at 2.54 30.48 270)
			(size 1.669796 1.669796)
			(drill 1.01981)
			(layers "*.Cu" "*.Mask")
			(remove_unused_layers no)
			(net "P12V_PSU")
			(clearance -0.070866)
		)
		(pad "P6_7" thru_hole circle
			(at 5.08 30.48 270)
			(size 1.669796 1.669796)
			(drill 1.01981)
			(layers "*.Cu" "*.Mask")
			(remove_unused_layers no)
			(net "P12V_PSU")
			(clearance -0.070866)
		)
		(pad "P6_8" thru_hole circle
			(at 7.62 30.48 270)
			(size 1.669796 1.669796)
			(drill 1.01981)
			(layers "*.Cu" "*.Mask")
			(remove_unused_layers no)
			(net "P12V_PSU")
			(clearance -0.070866)
		)
		(zone
			(layers "F.Cu" "B.Cu" "In1.Cu" "In2.Cu" "In3.Cu" "In4.Cu" "In5.Cu" "In6.Cu"
				"In7.Cu" "In8.Cu" "In9.Cu" "In10.Cu" "In11.Cu" "In12.Cu" "In13.Cu" "In14.Cu"
				"In15.Cu" "In16.Cu"
			)
			(hatch none 0.5)
			(connect_pads
				(clearance 0)
			)
			(min_thickness 0.25)
			(keepout
				(tracks not_allowed)
				(vias allowed)
				(pads allowed)
				(copperpour not_allowed)
				(footprints allowed)
			)
			(placement
				(enabled no)
				(sheetname "")
			)
			(fill
				(thermal_gap 0.5)
				(thermal_bridge_width 0.5)
				(island_removal_mode 0)
			)
			(polygon
				(pts
					(arc
						(start 204.68082 -433.04206)
						(mid 197.28942 -433.04206)
						(end 204.68082 -433.04206)
					)
				)
			)
		)
		(zone
			(layers "F.Cu" "B.Cu" "In1.Cu" "In2.Cu" "In3.Cu" "In4.Cu" "In5.Cu" "In6.Cu"
				"In7.Cu" "In8.Cu" "In9.Cu" "In10.Cu" "In11.Cu" "In12.Cu" "In13.Cu" "In14.Cu"
				"In15.Cu" "In16.Cu"
			)
			(hatch none 0.5)
			(connect_pads
				(clearance 0)
			)
			(min_thickness 0.25)
			(keepout
				(tracks not_allowed)
				(vias allowed)
				(pads allowed)
				(copperpour not_allowed)
				(footprints allowed)
			)
			(placement
				(enabled no)
				(sheetname "")
			)
			(fill
				(thermal_gap 0.5)
				(thermal_bridge_width 0.5)
				(island_removal_mode 0)
			)
			(polygon
				(pts
					(arc
						(start 274.53082 -433.04206)
						(mid 267.13942 -433.04206)
						(end 274.53082 -433.04206)
					)
				)
			)
		)
		(zone
			(layer "B.Cu")
			(hatch none 0.5)
			(connect_pads
				(clearance 0)
			)
			(min_thickness 0.25)
			(keepout
				(tracks allowed)
				(vias not_allowed)
				(pads allowed)
				(copperpour not_allowed)
				(footprints allowed)
			)
			(placement
				(enabled no)
				(sheetname "")
			)
			(fill
				(thermal_gap 0.5)
				(thermal_bridge_width 0.5)
				(island_removal_mode 0)
			)
			(polygon
				(pts
					(xy 207.071722 -436.480458) (xy 264.748518 -436.480458) (xy 264.748518 -427.063662) (xy 207.071722 -427.063662)
				)
			)
		)
	)
	(footprint ""
		(layer "F.Cu")
		(at 15.288006 -105.53573 90)
		(property "Reference" "R2790"
			(at 0 0 90)
			(layer "F.SilkS")
			(hide yes)
			(effects
				(font
					(size 1.27 1.27)
				)
			)
		)
		(property "Value" ""
			(at 0 0 90)
			(layer "F.Fab")
			(effects
				(font
					(size 1.27 1.27)
				)
			)
		)
		(duplicate_pad_numbers_are_jumpers no)
		(fp_line
			(start -0.02667 -0.4064)
			(end 0.7874 -0.4064)
			(stroke
				(width 0.1524)
				(type default)
			)
			(layer "F.SilkS")
		)
		(fp_line
			(start 0.7874 0.4064)
			(end 0.00127 0.4064)
			(stroke
				(width 0.1524)
				(type default)
			)
			(layer "F.SilkS")
		)
		(fp_line
			(start -0.7874 0.4064)
			(end -0.7874 -0.4064)
			(stroke
				(width 0.1524)
				(type default)
			)
			(layer "F.SilkS")
		)
		(fp_line
			(start -0.12065 -0.305054)
			(end -0.12065 -0.2794)
			(stroke
				(width 0.1)
				(type default)
			)
			(layer "F.Fab")
		)
		(fp_line
			(start -0.67945 -0.305054)
			(end -0.12065 -0.305054)
			(stroke
				(width 0.1)
				(type default)
			)
			(layer "F.Fab")
		)
		(fp_line
			(start 0.67945 -0.3048)
			(end 0.67945 0.3048)
			(stroke
				(width 0.1)
				(type default)
			)
			(layer "F.Fab")
		)
		(fp_line
			(start 0.12065 -0.3048)
			(end 0.67945 -0.3048)
			(stroke
				(width 0.1)
				(type default)
			)
			(layer "F.Fab")
		)
		(fp_line
			(start 0.12065 -0.2794)
			(end 0.12065 -0.3048)
			(stroke
				(width 0.1)
				(type default)
			)
			(layer "F.Fab")
		)
		(fp_line
			(start -0.12065 -0.2794)
			(end 0.12065 -0.2794)
			(stroke
				(width 0.1)
				(type default)
			)
			(layer "F.Fab")
		)
		(fp_line
			(start 0.120396 0.2794)
			(end -0.12065 0.2794)
			(stroke
				(width 0.1)
				(type default)
			)
			(layer "F.Fab")
		)
		(fp_line
			(start -0.12065 0.2794)
			(end -0.12065 0.3048)
			(stroke
				(width 0.1)
				(type default)
			)
			(layer "F.Fab")
		)
		(fp_line
			(start 0.67945 0.3048)
			(end 0.120396 0.3048)
			(stroke
				(width 0.1)
				(type default)
			)
			(layer "F.Fab")
		)
		(fp_line
			(start 0.120396 0.3048)
			(end 0.120396 0.2794)
			(stroke
				(width 0.1)
				(type default)
			)
			(layer "F.Fab")
		)
		(fp_line
			(start -0.12065 0.3048)
			(end -0.67945 0.3048)
			(stroke
				(width 0.1)
				(type default)
			)
			(layer "F.Fab")
		)
		(fp_line
			(start -0.67945 0.3048)
			(end -0.67945 -0.305054)
			(stroke
				(width 0.1)
				(type default)
			)
			(layer "F.Fab")
		)
		(pad "1" smd rect
			(at -0.40005 0 270)
			(size 0.4572 0.508)
			(layers "F.Cu" "F.Mask" "F.Paste")
			(net "USB2_HOST_BMC_B_DP")
		)
		(pad "2" smd rect
			(at 0.40005 0 270)
			(size 0.4572 0.508)
			(layers "F.Cu" "F.Mask" "F.Paste")
			(net "USB2_HOST_BMC_B_BUF_DP")
		)
	)
	(footprint ""
		(layer "F.Cu")
		(at 68.179696 -70.78599)
		(property "Reference" "D69"
			(at -36.052506 50.178462 90)
			(unlocked yes)
			(layer "F.SilkS")
			(effects
				(font
					(size 0.635 0.4064)
					(thickness 0.1524)
				)
				(justify left)
			)
		)
		(property "Value" ""
			(at 0 0 0)
			(layer "F.Fab")
			(effects
				(font
					(size 1.27 1.27)
				)
			)
		)
		(duplicate_pad_numbers_are_jumpers no)
		(fp_line
			(start -0.90678 0.4826)
			(end -0.90678 -0.4699)
			(stroke
				(width 0.1524)
				(type default)
			)
			(layer "F.SilkS")
		)
		(fp_line
			(start -0.89408 -0.4826)
			(end 0.90678 -0.4826)
			(stroke
				(width 0.1524)
				(type default)
			)
			(layer "F.SilkS")
		)
		(fp_line
			(start -0.79248 -0.4826)
			(end 1.03378 -0.4826)
			(stroke
				(width 0.1524)
				(type default)
			)
			(layer "F.SilkS")
		)
		(fp_line
			(start -0.64008 -0.4826)
			(end 1.16078 -0.4826)
			(stroke
				(width 0.1524)
				(type default)
			)
			(layer "F.SilkS")
		)
		(fp_line
			(start 0.90678 -0.4826)
			(end 0.90678 0.4826)
			(stroke
				(width 0.1524)
				(type default)
			)
			(layer "F.SilkS")
		)
		(fp_line
			(start 0.90678 0.4826)
			(end -0.90678 0.4826)
			(stroke
				(width 0.1524)
				(type default)
			)
			(layer "F.SilkS")
		)
		(fp_line
			(start 1.03378 -0.4826)
			(end 1.03378 0.4826)
			(stroke
				(width 0.1524)
				(type default)
			)
			(layer "F.SilkS")
		)
		(fp_line
			(start 1.03378 0.4826)
			(end -0.79248 0.4826)
			(stroke
				(width 0.1524)
				(type default)
			)
			(layer "F.SilkS")
		)
		(fp_line
			(start 1.16078 -0.4826)
			(end 1.16078 0.4826)
			(stroke
				(width 0.1524)
				(type default)
			)
			(layer "F.SilkS")
		)
		(fp_line
			(start 1.16078 0.4826)
			(end -0.64008 0.4826)
			(stroke
				(width 0.1524)
				(type default)
			)
			(layer "F.SilkS")
		)
		(fp_line
			(start -0.499872 -0.249936)
			(end 0.499872 -0.249936)
			(stroke
				(width 0.1)
				(type default)
			)
			(layer "F.Fab")
		)
		(fp_line
			(start -0.499872 0.249936)
			(end -0.499872 -0.249936)
			(stroke
				(width 0.1)
				(type default)
			)
			(layer "F.Fab")
		)
		(fp_line
			(start 0.499872 -0.249936)
			(end 0.499872 0.249936)
			(stroke
				(width 0.1)
				(type default)
			)
			(layer "F.Fab")
		)
		(fp_line
			(start 0.499872 0.249936)
			(end -0.499872 0.249936)
			(stroke
				(width 0.1)
				(type default)
			)
			(layer "F.Fab")
		)
		(pad "A" smd rect
			(at -0.47498 0)
			(size 0.6096 0.7112)
			(layers "F.Cu" "F.Mask" "F.Paste")
			(net "LED_RST_PLD_CPU1_DRAM_AB_N")
		)
		(pad "C" smd rect
			(at 0.47498 0)
			(size 0.6096 0.7112)
			(layers "F.Cu" "F.Mask" "F.Paste")
			(net "LED_RST_PLD_CPU1_DRAM_AB_N_D")
		)
	)
	(footprint ""
		(layer "F.Cu")
		(at 237.401608 -404.721822 180)
		(property "Reference" "PR3984"
			(at 0 0 180)
			(layer "F.SilkS")
			(hide yes)
			(effects
				(font
					(size 1.27 1.27)
				)
			)
		)
		(property "Value" ""
			(at 0 0 180)
			(layer "F.Fab")
			(effects
				(font
					(size 1.27 1.27)
				)
			)
		)
		(duplicate_pad_numbers_are_jumpers no)
		(fp_line
			(start 0.7874 0.4064)
			(end -0.7874 0.4064)
			(stroke
				(width 0.1524)
				(type default)
			)
			(layer "F.SilkS")
		)
		(fp_line
			(start 0.7874 -0.4064)
			(end 0.7874 0.4064)
			(stroke
				(width 0.1524)
				(type default)
			)
			(layer "F.SilkS")
		)
		(fp_line
			(start -0.7874 0.4064)
			(end -0.7874 -0.4064)
			(stroke
				(width 0.1524)
				(type default)
			)
			(layer "F.SilkS")
		)
		(fp_line
			(start -0.7874 -0.4064)
			(end 0.7874 -0.4064)
			(stroke
				(width 0.1524)
				(type default)
			)
			(layer "F.SilkS")
		)
		(fp_line
			(start 0.67945 0.3048)
			(end 0.120396 0.3048)
			(stroke
				(width 0.1)
				(type default)
			)
			(layer "F.Fab")
		)
		(fp_line
			(start 0.67945 -0.3048)
			(end 0.67945 0.3048)
			(stroke
				(width 0.1)
				(type default)
			)
			(layer "F.Fab")
		)
		(fp_line
			(start 0.12065 -0.2794)
			(end 0.12065 -0.3048)
			(stroke
				(width 0.1)
				(type default)
			)
			(layer "F.Fab")
		)
		(fp_line
			(start 0.12065 -0.3048)
			(end 0.67945 -0.3048)
			(stroke
				(width 0.1)
				(type default)
			)
			(layer "F.Fab")
		)
		(fp_line
			(start 0.120396 0.3048)
			(end 0.120396 0.2794)
			(stroke
				(width 0.1)
				(type default)
			)
			(layer "F.Fab")
		)
		(fp_line
			(start 0.120396 0.2794)
			(end -0.12065 0.2794)
			(stroke
				(width 0.1)
				(type default)
			)
			(layer "F.Fab")
		)
		(fp_line
			(start -0.12065 0.3048)
			(end -0.67945 0.3048)
			(stroke
				(width 0.1)
				(type default)
			)
			(layer "F.Fab")
		)
		(fp_line
			(start -0.12065 0.2794)
			(end -0.12065 0.3048)
			(stroke
				(width 0.1)
				(type default)
			)
			(layer "F.Fab")
		)
		(fp_line
			(start -0.12065 -0.2794)
			(end 0.12065 -0.2794)
			(stroke
				(width 0.1)
				(type default)
			)
			(layer "F.Fab")
		)
		(fp_line
			(start -0.12065 -0.305054)
			(end -0.12065 -0.2794)
			(stroke
				(width 0.1)
				(type default)
			)
			(layer "F.Fab")
		)
		(fp_line
			(start -0.67945 0.3048)
			(end -0.67945 -0.305054)
			(stroke
				(width 0.1)
				(type default)
			)
			(layer "F.Fab")
		)
		(fp_line
			(start -0.67945 -0.305054)
			(end -0.12065 -0.305054)
			(stroke
				(width 0.1)
				(type default)
			)
			(layer "F.Fab")
		)
		(pad "1" smd circle
			(at -0.40005 0 180)
			(size 0 0)
			(layers "F.Cu" "F.Mask" "F.Paste")
			(net "AGND_HSC")
		)
		(pad "2" smd circle
			(at 0.40005 0 180)
			(size 0 0)
			(layers "F.Cu" "F.Mask" "F.Paste")
			(net "HSC_MODE_4")
		)
	)
	(footprint ""
		(layer "F.Cu")
		(at 157.28188 -131.155948 -90)
		(property "Reference" "Q52"
			(at -2.55905 0.86614 0)
			(unlocked yes)
			(layer "F.SilkS")
			(effects
				(font
					(size 0.7874 0.5842)
					(thickness 0.1524)
				)
				(justify left)
			)
		)
		(property "Value" ""
			(at 0 0 270)
			(layer "F.Fab")
			(effects
				(font
					(size 1.27 1.27)
				)
			)
		)
		(duplicate_pad_numbers_are_jumpers no)
		(fp_line
			(start -1.603248 1.500124)
			(end -1.603248 -1.500124)
			(stroke
				(width 0.1524)
				(type default)
			)
			(layer "F.SilkS")
		)
		(fp_line
			(start 1.603248 1.500124)
			(end -1.603248 1.500124)
			(stroke
				(width 0.1524)
				(type default)
			)
			(layer "F.SilkS")
		)
		(fp_line
			(start -1.603248 -1.500124)
			(end 1.603248 -1.500124)
			(stroke
				(width 0.1524)
				(type default)
			)
			(layer "F.SilkS")
		)
		(fp_line
			(start 1.603248 -1.500124)
			(end 1.603248 1.500124)
			(stroke
				(width 0.1524)
				(type default)
			)
			(layer "F.SilkS")
		)
		(fp_line
			(start -0.700024 1.500124)
			(end 0.700024 1.500124)
			(stroke
				(width 0.1)
				(type default)
			)
			(layer "F.Fab")
		)
		(fp_line
			(start 0.700024 1.500124)
			(end 0.700024 0.219964)
			(stroke
				(width 0.1)
				(type default)
			)
			(layer "F.Fab")
		)
		(fp_line
			(start -1.249934 1.169924)
			(end -0.700024 1.169924)
			(stroke
				(width 0.1)
				(type default)
			)
			(layer "F.Fab")
		)
		(fp_line
			(start -0.700024 1.169924)
			(end -0.700024 1.500124)
			(stroke
				(width 0.1)
				(type default)
			)
			(layer "F.Fab")
		)
		(fp_line
			(start -1.249934 0.729996)
			(end -1.249934 1.169924)
			(stroke
				(width 0.1)
				(type default)
			)
			(layer "F.Fab")
		)
		(fp_line
			(start -0.6985 0.729996)
			(end -1.249934 0.729996)
			(stroke
				(width 0.1)
				(type default)
			)
			(layer "F.Fab")
		)
		(fp_line
			(start 0.700024 0.219964)
			(end 1.249934 0.219964)
			(stroke
				(width 0.1)
				(type default)
			)
			(layer "F.Fab")
		)
		(fp_line
			(start 1.249934 0.219964)
			(end 1.249934 -0.219964)
			(stroke
				(width 0.1)
				(type default)
			)
			(layer "F.Fab")
		)
		(fp_line
			(start 0.700024 -0.219964)
			(end 0.700024 -1.500124)
			(stroke
				(width 0.1)
				(type default)
			)
			(layer "F.Fab")
		)
		(fp_line
			(start 1.249934 -0.219964)
			(end 0.700024 -0.219964)
			(stroke
				(width 0.1)
				(type default)
			)
			(layer "F.Fab")
		)
		(fp_line
			(start -1.249934 -0.729996)
			(end -0.6985 -0.729996)
			(stroke
				(width 0.1)
				(type default)
			)
			(layer "F.Fab")
		)
		(fp_line
			(start -0.6985 -0.729996)
			(end -0.6985 0.729996)
			(stroke
				(width 0.1)
				(type default)
			)
			(layer "F.Fab")
		)
		(fp_line
			(start -1.249934 -1.169924)
			(end -1.249934 -0.729996)
			(stroke
				(width 0.1)
				(type default)
			)
			(layer "F.Fab")
		)
		(fp_line
			(start -0.700024 -1.169924)
			(end -1.249934 -1.169924)
			(stroke
				(width 0.1)
				(type default)
			)
			(layer "F.Fab")
		)
		(fp_line
			(start -0.700024 -1.500124)
			(end -0.700024 -1.169924)
			(stroke
				(width 0.1)
				(type default)
			)
			(layer "F.Fab")
		)
		(fp_line
			(start 0.700024 -1.500124)
			(end -0.700024 -1.500124)
			(stroke
				(width 0.1)
				(type default)
			)
			(layer "F.Fab")
		)
		(fp_rect
			(start -0.700024 1.500124)
			(end 0.700024 -1.500124)
			(stroke
				(width 0)
				(type default)
			)
			(fill no)
			(layer "F.Fab")
		)
		(pad "D" smd rect
			(at 0.999998 0 180)
			(size 0.8128 0.9144)
			(layers "F.Cu" "F.Mask" "F.Paste")
			(net "FM_COMP_P3V3_AUX_VIN_R")
		)
		(pad "G" smd rect
			(at -0.999998 -0.94996 180)
			(size 0.8128 0.9144)
			(layers "F.Cu" "F.Mask" "F.Paste")
			(net "PWRGD_P3V3_AUX_R2")
		)
		(pad "S" smd rect
			(at -0.999998 0.94996 180)
			(size 0.8128 0.9144)
			(layers "F.Cu" "F.Mask" "F.Paste")
			(net "GND")
		)
	)
	(footprint ""
		(layer "F.Cu")
		(at 78.586838 -402.371052 -90)
		(property "Reference" "C730"
			(at 0 0 270)
			(layer "F.SilkS")
			(hide yes)
			(effects
				(font
					(size 1.27 1.27)
				)
			)
		)
		(property "Value" ""
			(at 0 0 270)
			(layer "F.Fab")
			(effects
				(font
					(size 1.27 1.27)
				)
			)
		)
		(duplicate_pad_numbers_are_jumpers no)
		(fp_line
			(start -0.299974 0.150114)
			(end -0.299974 -0.150114)
			(stroke
				(width 0.1)
				(type default)
			)
			(layer "F.Fab")
		)
		(fp_line
			(start 0.299974 0.150114)
			(end -0.299974 0.150114)
			(stroke
				(width 0.1)
				(type default)
			)
			(layer "F.Fab")
		)
		(fp_line
			(start -0.299974 -0.150114)
			(end 0.299974 -0.150114)
			(stroke
				(width 0.1)
				(type default)
			)
			(layer "F.Fab")
		)
		(fp_line
			(start 0.299974 -0.150114)
			(end 0.299974 0.150114)
			(stroke
				(width 0.1)
				(type default)
			)
			(layer "F.Fab")
		)
		(pad "1" smd rect
			(at -0.2667 0 270)
			(size 0.3048 0.381)
			(layers "F.Cu" "F.Mask" "F.Paste")
			(net "P5E_CPU1_PE0_TX_C_DN<5>")
		)
		(pad "2" smd rect
			(at 0.2667 0 270)
			(size 0.3048 0.381)
			(layers "F.Cu" "F.Mask" "F.Paste")
			(net "P5E_CPU1_PE0_TX_DN<5>")
		)
	)
	(footprint ""
		(layer "F.Cu")
		(at 22.354032 -175.423576)
		(property "Reference" "PR502"
			(at 0 0 0)
			(layer "F.SilkS")
			(hide yes)
			(effects
				(font
					(size 1.27 1.27)
				)
			)
		)
		(property "Value" ""
			(at 0 0 0)
			(layer "F.Fab")
			(effects
				(font
					(size 1.27 1.27)
				)
			)
		)
		(duplicate_pad_numbers_are_jumpers no)
		(fp_line
			(start -0.7874 -0.4064)
			(end 0.7874 -0.4064)
			(stroke
				(width 0.1524)
				(type default)
			)
			(layer "F.SilkS")
		)
		(fp_line
			(start -0.7874 0.4064)
			(end -0.7874 -0.4064)
			(stroke
				(width 0.1524)
				(type default)
			)
			(layer "F.SilkS")
		)
		(fp_line
			(start 0.7874 -0.4064)
			(end 0.7874 0.4064)
			(stroke
				(width 0.1524)
				(type default)
			)
			(layer "F.SilkS")
		)
		(fp_line
			(start 0.7874 0.4064)
			(end -0.7874 0.4064)
			(stroke
				(width 0.1524)
				(type default)
			)
			(layer "F.SilkS")
		)
		(fp_line
			(start -0.67945 -0.305054)
			(end -0.12065 -0.305054)
			(stroke
				(width 0.1)
				(type default)
			)
			(layer "F.Fab")
		)
		(fp_line
			(start -0.67945 0.3048)
			(end -0.67945 -0.305054)
			(stroke
				(width 0.1)
				(type default)
			)
			(layer "F.Fab")
		)
		(fp_line
			(start -0.12065 -0.305054)
			(end -0.12065 -0.2794)
			(stroke
				(width 0.1)
				(type default)
			)
			(layer "F.Fab")
		)
		(fp_line
			(start -0.12065 -0.2794)
			(end 0.12065 -0.2794)
			(stroke
				(width 0.1)
				(type default)
			)
			(layer "F.Fab")
		)
		(fp_line
			(start -0.12065 0.2794)
			(end -0.12065 0.3048)
			(stroke
				(width 0.1)
				(type default)
			)
			(layer "F.Fab")
		)
		(fp_line
			(start -0.12065 0.3048)
			(end -0.67945 0.3048)
			(stroke
				(width 0.1)
				(type default)
			)
			(layer "F.Fab")
		)
		(fp_line
			(start 0.120396 0.2794)
			(end -0.12065 0.2794)
			(stroke
				(width 0.1)
				(type default)
			)
			(layer "F.Fab")
		)
		(fp_line
			(start 0.120396 0.3048)
			(end 0.120396 0.2794)
			(stroke
				(width 0.1)
				(type default)
			)
			(layer "F.Fab")
		)
		(fp_line
			(start 0.12065 -0.3048)
			(end 0.67945 -0.3048)
			(stroke
				(width 0.1)
				(type default)
			)
			(layer "F.Fab")
		)
		(fp_line
			(start 0.12065 -0.2794)
			(end 0.12065 -0.3048)
			(stroke
				(width 0.1)
				(type default)
			)
			(layer "F.Fab")
		)
		(fp_line
			(start 0.67945 -0.3048)
			(end 0.67945 0.3048)
			(stroke
				(width 0.1)
				(type default)
			)
			(layer "F.Fab")
		)
		(fp_line
			(start 0.67945 0.3048)
			(end 0.120396 0.3048)
			(stroke
				(width 0.1)
				(type default)
			)
			(layer "F.Fab")
		)
		(pad "1" smd circle
			(at -0.40005 0)
			(size 0 0)
			(layers "F.Cu" "F.Mask" "F.Paste")
			(net "PVNN_MAIN_CPU1_FB")
		)
		(pad "2" smd circle
			(at 0.40005 0)
			(size 0 0)
			(layers "F.Cu" "F.Mask" "F.Paste")
			(net "PVNN_MAIN_CPU1_FB_RC")
		)
	)
	(footprint ""
		(layer "F.Cu")
		(at 23.760938 -174.53483 90)
		(property "Reference" "PC2277"
			(at 0 0 90)
			(layer "F.SilkS")
			(hide yes)
			(effects
				(font
					(size 1.27 1.27)
				)
			)
		)
		(property "Value" ""
			(at 0 0 90)
			(layer "F.Fab")
			(effects
				(font
					(size 1.27 1.27)
				)
			)
		)
		(duplicate_pad_numbers_are_jumpers no)
		(fp_line
			(start 0.7874 -0.4064)
			(end 0.7874 0.4064)
			(stroke
				(width 0.1524)
				(type default)
			)
			(layer "F.SilkS")
		)
		(fp_line
			(start -0.7874 -0.4064)
			(end 0.7874 -0.4064)
			(stroke
				(width 0.1524)
				(type default)
			)
			(layer "F.SilkS")
		)
		(fp_line
			(start 0.7874 0.4064)
			(end -0.7874 0.4064)
			(stroke
				(width 0.1524)
				(type default)
			)
			(layer "F.SilkS")
		)
		(fp_line
			(start -0.7874 0.4064)
			(end -0.7874 -0.4064)
			(stroke
				(width 0.1524)
				(type default)
			)
			(layer "F.SilkS")
		)
		(fp_line
			(start -0.12065 -0.305054)
			(end -0.12065 -0.2794)
			(stroke
				(width 0.1)
				(type default)
			)
			(layer "F.Fab")
		)
		(fp_line
			(start -0.67945 -0.305054)
			(end -0.12065 -0.305054)
			(stroke
				(width 0.1)
				(type default)
			)
			(layer "F.Fab")
		)
		(fp_line
			(start 0.67945 -0.3048)
			(end 0.67945 0.3048)
			(stroke
				(width 0.1)
				(type default)
			)
			(layer "F.Fab")
		)
		(fp_line
			(start 0.12065 -0.3048)
			(end 0.67945 -0.3048)
			(stroke
				(width 0.1)
				(type default)
			)
			(layer "F.Fab")
		)
		(fp_line
			(start 0.12065 -0.2794)
			(end 0.12065 -0.3048)
			(stroke
				(width 0.1)
				(type default)
			)
			(layer "F.Fab")
		)
		(fp_line
			(start -0.12065 -0.2794)
			(end 0.12065 -0.2794)
			(stroke
				(width 0.1)
				(type default)
			)
			(layer "F.Fab")
		)
		(fp_line
			(start 0.120396 0.2794)
			(end -0.12065 0.2794)
			(stroke
				(width 0.1)
				(type default)
			)
			(layer "F.Fab")
		)
		(fp_line
			(start -0.12065 0.2794)
			(end -0.12065 0.3048)
			(stroke
				(width 0.1)
				(type default)
			)
			(layer "F.Fab")
		)
		(fp_line
			(start 0.67945 0.3048)
			(end 0.120396 0.3048)
			(stroke
				(width 0.1)
				(type default)
			)
			(layer "F.Fab")
		)
		(fp_line
			(start 0.120396 0.3048)
			(end 0.120396 0.2794)
			(stroke
				(width 0.1)
				(type default)
			)
			(layer "F.Fab")
		)
		(fp_line
			(start -0.12065 0.3048)
			(end -0.67945 0.3048)
			(stroke
				(width 0.1)
				(type default)
			)
			(layer "F.Fab")
		)
		(fp_line
			(start -0.67945 0.3048)
			(end -0.67945 -0.305054)
			(stroke
				(width 0.1)
				(type default)
			)
			(layer "F.Fab")
		)
		(pad "1" smd circle
			(at -0.40005 0 90)
			(size 0 0)
			(layers "F.Cu" "F.Mask" "F.Paste")
			(net "PVNN_MAIN_CPU1_FB_RC")
		)
		(pad "2" smd circle
			(at 0.40005 0 90)
			(size 0 0)
			(layers "F.Cu" "F.Mask" "F.Paste")
			(net "GND")
		)
	)
	(footprint ""
		(layer "F.Cu")
		(at 156.053536 -31.341568 90)
		(property "Reference" "R4452"
			(at 0 0 90)
			(layer "F.SilkS")
			(hide yes)
			(effects
				(font
					(size 1.27 1.27)
				)
			)
		)
		(property "Value" ""
			(at 0 0 90)
			(layer "F.Fab")
			(effects
				(font
					(size 1.27 1.27)
				)
			)
		)
		(duplicate_pad_numbers_are_jumpers no)
		(fp_line
			(start 0.7874 -0.4064)
			(end 0.7874 0.4064)
			(stroke
				(width 0.1524)
				(type default)
			)
			(layer "F.SilkS")
		)
		(fp_line
			(start -0.7874 -0.4064)
			(end 0.7874 -0.4064)
			(stroke
				(width 0.1524)
				(type default)
			)
			(layer "F.SilkS")
		)
		(fp_line
			(start 0.7874 0.4064)
			(end -0.7874 0.4064)
			(stroke
				(width 0.1524)
				(type default)
			)
			(layer "F.SilkS")
		)
		(fp_line
			(start -0.7874 0.4064)
			(end -0.7874 -0.4064)
			(stroke
				(width 0.1524)
				(type default)
			)
			(layer "F.SilkS")
		)
		(fp_line
			(start -0.12065 -0.305054)
			(end -0.12065 -0.2794)
			(stroke
				(width 0.1)
				(type default)
			)
			(layer "F.Fab")
		)
		(fp_line
			(start -0.67945 -0.305054)
			(end -0.12065 -0.305054)
			(stroke
				(width 0.1)
				(type default)
			)
			(layer "F.Fab")
		)
		(fp_line
			(start 0.67945 -0.3048)
			(end 0.67945 0.3048)
			(stroke
				(width 0.1)
				(type default)
			)
			(layer "F.Fab")
		)
		(fp_line
			(start 0.12065 -0.3048)
			(end 0.67945 -0.3048)
			(stroke
				(width 0.1)
				(type default)
			)
			(layer "F.Fab")
		)
		(fp_line
			(start 0.12065 -0.2794)
			(end 0.12065 -0.3048)
			(stroke
				(width 0.1)
				(type default)
			)
			(layer "F.Fab")
		)
		(fp_line
			(start -0.12065 -0.2794)
			(end 0.12065 -0.2794)
			(stroke
				(width 0.1)
				(type default)
			)
			(layer "F.Fab")
		)
		(fp_line
			(start 0.120396 0.2794)
			(end -0.12065 0.2794)
			(stroke
				(width 0.1)
				(type default)
			)
			(layer "F.Fab")
		)
		(fp_line
			(start -0.12065 0.2794)
			(end -0.12065 0.3048)
			(stroke
				(width 0.1)
				(type default)
			)
			(layer "F.Fab")
		)
		(fp_line
			(start 0.67945 0.3048)
			(end 0.120396 0.3048)
			(stroke
				(width 0.1)
				(type default)
			)
			(layer "F.Fab")
		)
		(fp_line
			(start 0.120396 0.3048)
			(end 0.120396 0.2794)
			(stroke
				(width 0.1)
				(type default)
			)
			(layer "F.Fab")
		)
		(fp_line
			(start -0.12065 0.3048)
			(end -0.67945 0.3048)
			(stroke
				(width 0.1)
				(type default)
			)
			(layer "F.Fab")
		)
		(fp_line
			(start -0.67945 0.3048)
			(end -0.67945 -0.305054)
			(stroke
				(width 0.1)
				(type default)
			)
			(layer "F.Fab")
		)
		(pad "1" smd circle
			(at -0.40005 0 90)
			(size 0 0)
			(layers "F.Cu" "F.Mask" "F.Paste")
			(net "P3V3_AUX")
		)
		(pad "2" smd circle
			(at 0.40005 0 90)
			(size 0 0)
			(layers "F.Cu" "F.Mask" "F.Paste")
			(net "RST_USB_HUB_2_R_N")
		)
	)
	(footprint ""
		(layer "F.Cu")
		(at 348.961964 -66.988944)
		(property "Reference" "C146"
			(at 0 0 0)
			(layer "F.SilkS")
			(hide yes)
			(effects
				(font
					(size 1.27 1.27)
				)
			)
		)
		(property "Value" ""
			(at 0 0 0)
			(layer "F.Fab")
			(effects
				(font
					(size 1.27 1.27)
				)
			)
		)
		(duplicate_pad_numbers_are_jumpers no)
		(fp_line
			(start -0.299974 -0.150114)
			(end 0.299974 -0.150114)
			(stroke
				(width 0.1)
				(type default)
			)
			(layer "F.Fab")
		)
		(fp_line
			(start -0.299974 0.150114)
			(end -0.299974 -0.150114)
			(stroke
				(width 0.1)
				(type default)
			)
			(layer "F.Fab")
		)
		(fp_line
			(start 0.299974 -0.150114)
			(end 0.299974 0.150114)
			(stroke
				(width 0.1)
				(type default)
			)
			(layer "F.Fab")
		)
		(fp_line
			(start 0.299974 0.150114)
			(end -0.299974 0.150114)
			(stroke
				(width 0.1)
				(type default)
			)
			(layer "F.Fab")
		)
		(pad "1" smd rect
			(at -0.2667 0)
			(size 0.3048 0.381)
			(layers "F.Cu" "F.Mask" "F.Paste")
			(net "DMI_CPU0_PCH_TX_C_DP<4>")
		)
		(pad "2" smd rect
			(at 0.2667 0)
			(size 0.3048 0.381)
			(layers "F.Cu" "F.Mask" "F.Paste")
			(net "DMI_CPU0_PCH_TX_DP<4>")
		)
		(zone
			(layer "In1.Cu")
			(hatch none 0.5)
			(connect_pads
				(clearance 0)
			)
			(min_thickness 0.25)
			(keepout
				(tracks not_allowed)
				(vias allowed)
				(pads allowed)
				(copperpour not_allowed)
				(footprints allowed)
			)
			(placement
				(enabled no)
				(sheetname "")
			)
			(fill
				(thermal_gap 0.5)
				(thermal_bridge_width 0.5)
				(island_removal_mode 0)
			)
			(polygon
				(pts
					(arc
						(start 348.568264 -66.747644)
						(mid 348.514382 -66.769962)
						(end 348.492064 -66.823844)
					)
					(arc
						(start 348.492064 -67.154044)
						(mid 348.514382 -67.207926)
						(end 348.568264 -67.230244)
					)
					(arc
						(start 348.822264 -67.230244)
						(mid 348.876146 -67.207926)
						(end 348.898464 -67.154044)
					)
					(arc
						(start 348.898464 -66.823844)
						(mid 348.876146 -66.769962)
						(end 348.822264 -66.747644)
					)
				)
			)
		)
		(zone
			(layer "In1.Cu")
			(hatch none 0.5)
			(connect_pads
				(clearance 0)
			)
			(min_thickness 0.25)
			(keepout
				(tracks not_allowed)
				(vias allowed)
				(pads allowed)
				(copperpour not_allowed)
				(footprints allowed)
			)
			(placement
				(enabled no)
				(sheetname "")
			)
			(fill
				(thermal_gap 0.5)
				(thermal_bridge_width 0.5)
				(island_removal_mode 0)
			)
			(polygon
				(pts
					(arc
						(start 349.101664 -66.747644)
						(mid 349.047782 -66.769962)
						(end 349.025464 -66.823844)
					)
					(arc
						(start 349.025464 -67.154044)
						(mid 349.047782 -67.207926)
						(end 349.101664 -67.230244)
					)
					(arc
						(start 349.355664 -67.230244)
						(mid 349.409546 -67.207926)
						(end 349.431864 -67.154044)
					)
					(arc
						(start 349.431864 -66.823844)
						(mid 349.409546 -66.769962)
						(end 349.355664 -66.747644)
					)
				)
			)
		)
	)
	(footprint ""
		(layer "F.Cu")
		(at 428.226474 -126.81966)
		(property "Reference" "PR358"
			(at 0 0 0)
			(layer "F.SilkS")
			(hide yes)
			(effects
				(font
					(size 1.27 1.27)
				)
			)
		)
		(property "Value" ""
			(at 0 0 0)
			(layer "F.Fab")
			(effects
				(font
					(size 1.27 1.27)
				)
			)
		)
		(duplicate_pad_numbers_are_jumpers no)
		(fp_line
			(start -0.7874 -0.4064)
			(end 0.7874 -0.4064)
			(stroke
				(width 0.1524)
				(type default)
			)
			(layer "F.SilkS")
		)
		(fp_line
			(start -0.7874 0.4064)
			(end -0.7874 -0.4064)
			(stroke
				(width 0.1524)
				(type default)
			)
			(layer "F.SilkS")
		)
		(fp_line
			(start 0.7874 -0.4064)
			(end 0.7874 0.4064)
			(stroke
				(width 0.1524)
				(type default)
			)
			(layer "F.SilkS")
		)
		(fp_line
			(start 0.7874 0.4064)
			(end -0.7874 0.4064)
			(stroke
				(width 0.1524)
				(type default)
			)
			(layer "F.SilkS")
		)
		(fp_line
			(start -0.67945 -0.305054)
			(end -0.12065 -0.305054)
			(stroke
				(width 0.1)
				(type default)
			)
			(layer "F.Fab")
		)
		(fp_line
			(start -0.67945 0.3048)
			(end -0.67945 -0.305054)
			(stroke
				(width 0.1)
				(type default)
			)
			(layer "F.Fab")
		)
		(fp_line
			(start -0.12065 -0.305054)
			(end -0.12065 -0.2794)
			(stroke
				(width 0.1)
				(type default)
			)
			(layer "F.Fab")
		)
		(fp_line
			(start -0.12065 -0.2794)
			(end 0.12065 -0.2794)
			(stroke
				(width 0.1)
				(type default)
			)
			(layer "F.Fab")
		)
		(fp_line
			(start -0.12065 0.2794)
			(end -0.12065 0.3048)
			(stroke
				(width 0.1)
				(type default)
			)
			(layer "F.Fab")
		)
		(fp_line
			(start -0.12065 0.3048)
			(end -0.67945 0.3048)
			(stroke
				(width 0.1)
				(type default)
			)
			(layer "F.Fab")
		)
		(fp_line
			(start 0.120396 0.2794)
			(end -0.12065 0.2794)
			(stroke
				(width 0.1)
				(type default)
			)
			(layer "F.Fab")
		)
		(fp_line
			(start 0.120396 0.3048)
			(end 0.120396 0.2794)
			(stroke
				(width 0.1)
				(type default)
			)
			(layer "F.Fab")
		)
		(fp_line
			(start 0.12065 -0.3048)
			(end 0.67945 -0.3048)
			(stroke
				(width 0.1)
				(type default)
			)
			(layer "F.Fab")
		)
		(fp_line
			(start 0.12065 -0.2794)
			(end 0.12065 -0.3048)
			(stroke
				(width 0.1)
				(type default)
			)
			(layer "F.Fab")
		)
		(fp_line
			(start 0.67945 -0.3048)
			(end 0.67945 0.3048)
			(stroke
				(width 0.1)
				(type default)
			)
			(layer "F.Fab")
		)
		(fp_line
			(start 0.67945 0.3048)
			(end 0.120396 0.3048)
			(stroke
				(width 0.1)
				(type default)
			)
			(layer "F.Fab")
		)
		(pad "1" smd circle
			(at -0.40005 0)
			(size 0 0)
			(layers "F.Cu" "F.Mask" "F.Paste")
			(net "GND")
		)
		(pad "2" smd circle
			(at 0.40005 0)
			(size 0 0)
			(layers "F.Cu" "F.Mask" "F.Paste")
			(net "PVCCD_HV_CPU0_ADDR")
		)
	)
	(footprint ""
		(layer "F.Cu")
		(at 167.064944 -353.76358)
		(property "Reference" "PR703"
			(at 0 0 0)
			(layer "F.SilkS")
			(hide yes)
			(effects
				(font
					(size 1.27 1.27)
				)
			)
		)
		(property "Value" ""
			(at 0 0 0)
			(layer "F.Fab")
			(effects
				(font
					(size 1.27 1.27)
				)
			)
		)
		(duplicate_pad_numbers_are_jumpers no)
		(fp_line
			(start -0.7874 -0.4064)
			(end 0.7874 -0.4064)
			(stroke
				(width 0.1524)
				(type default)
			)
			(layer "F.SilkS")
		)
		(fp_line
			(start -0.7874 0.4064)
			(end -0.7874 -0.4064)
			(stroke
				(width 0.1524)
				(type default)
			)
			(layer "F.SilkS")
		)
		(fp_line
			(start 0.7874 -0.4064)
			(end 0.7874 0.4064)
			(stroke
				(width 0.1524)
				(type default)
			)
			(layer "F.SilkS")
		)
		(fp_line
			(start 0.7874 0.4064)
			(end -0.7874 0.4064)
			(stroke
				(width 0.1524)
				(type default)
			)
			(layer "F.SilkS")
		)
		(fp_line
			(start -0.67945 -0.305054)
			(end -0.12065 -0.305054)
			(stroke
				(width 0.1)
				(type default)
			)
			(layer "F.Fab")
		)
		(fp_line
			(start -0.67945 0.3048)
			(end -0.67945 -0.305054)
			(stroke
				(width 0.1)
				(type default)
			)
			(layer "F.Fab")
		)
		(fp_line
			(start -0.12065 -0.305054)
			(end -0.12065 -0.2794)
			(stroke
				(width 0.1)
				(type default)
			)
			(layer "F.Fab")
		)
		(fp_line
			(start -0.12065 -0.2794)
			(end 0.12065 -0.2794)
			(stroke
				(width 0.1)
				(type default)
			)
			(layer "F.Fab")
		)
		(fp_line
			(start -0.12065 0.2794)
			(end -0.12065 0.3048)
			(stroke
				(width 0.1)
				(type default)
			)
			(layer "F.Fab")
		)
		(fp_line
			(start -0.12065 0.3048)
			(end -0.67945 0.3048)
			(stroke
				(width 0.1)
				(type default)
			)
			(layer "F.Fab")
		)
		(fp_line
			(start 0.120396 0.2794)
			(end -0.12065 0.2794)
			(stroke
				(width 0.1)
				(type default)
			)
			(layer "F.Fab")
		)
		(fp_line
			(start 0.120396 0.3048)
			(end 0.120396 0.2794)
			(stroke
				(width 0.1)
				(type default)
			)
			(layer "F.Fab")
		)
		(fp_line
			(start 0.12065 -0.3048)
			(end 0.67945 -0.3048)
			(stroke
				(width 0.1)
				(type default)
			)
			(layer "F.Fab")
		)
		(fp_line
			(start 0.12065 -0.2794)
			(end 0.12065 -0.3048)
			(stroke
				(width 0.1)
				(type default)
			)
			(layer "F.Fab")
		)
		(fp_line
			(start 0.67945 -0.3048)
			(end 0.67945 0.3048)
			(stroke
				(width 0.1)
				(type default)
			)
			(layer "F.Fab")
		)
		(fp_line
			(start 0.67945 0.3048)
			(end 0.120396 0.3048)
			(stroke
				(width 0.1)
				(type default)
			)
			(layer "F.Fab")
		)
		(pad "1" smd circle
			(at -0.40005 0)
			(size 0 0)
			(layers "F.Cu" "F.Mask" "F.Paste")
			(net "P3V3")
		)
		(pad "2" smd circle
			(at 0.40005 0)
			(size 0 0)
			(layers "F.Cu" "F.Mask" "F.Paste")
			(net "PVCCFA_EHV_FIVRA_CPU1_PVCC1")
		)
	)
	(footprint ""
		(layer "F.Cu")
		(at 136.07288 -46.065948)
		(property "Reference" "Q95"
			(at -1.4224 -1.768348 0)
			(unlocked yes)
			(layer "F.SilkS")
			(effects
				(font
					(size 0.7874 0.5842)
					(thickness 0.1524)
				)
				(justify left)
			)
		)
		(property "Value" ""
			(at 0 0 0)
			(layer "F.Fab")
			(effects
				(font
					(size 1.27 1.27)
				)
			)
		)
		(duplicate_pad_numbers_are_jumpers no)
		(fp_line
			(start -1.332738 -1.100074)
			(end -0.4826 -1.100074)
			(stroke
				(width 0.1524)
				(type default)
			)
			(layer "F.SilkS")
		)
		(fp_line
			(start -1.332738 1.100074)
			(end -1.332738 -1.100074)
			(stroke
				(width 0.1524)
				(type default)
			)
			(layer "F.SilkS")
		)
		(fp_line
			(start -0.4826 -1.100074)
			(end 0 -0.541274)
			(stroke
				(width 0.1524)
				(type default)
			)
			(layer "F.SilkS")
		)
		(fp_line
			(start 0 -0.541274)
			(end 0.4826 -1.100074)
			(stroke
				(width 0.1524)
				(type default)
			)
			(layer "F.SilkS")
		)
		(fp_line
			(start 0.4826 -1.100074)
			(end 1.332738 -1.100074)
			(stroke
				(width 0.1524)
				(type default)
			)
			(layer "F.SilkS")
		)
		(fp_line
			(start 1.332738 -1.100074)
			(end 1.332738 1.100074)
			(stroke
				(width 0.1524)
				(type default)
			)
			(layer "F.SilkS")
		)
		(fp_line
			(start 1.332738 1.100074)
			(end -1.332738 1.100074)
			(stroke
				(width 0.1524)
				(type default)
			)
			(layer "F.SilkS")
		)
		(fp_poly
			(pts
				(xy -2.2352 -1.001014) (xy -1.533144 -0.649986) (xy -2.2352 -0.298958)
			)
			(stroke
				(width 0)
				(type default)
			)
			(fill yes)
			(layer "F.SilkS")
		)
		(fp_line
			(start -0.674878 -1.100074)
			(end 0.674878 -1.100074)
			(stroke
				(width 0.1)
				(type default)
			)
			(layer "F.Fab")
		)
		(fp_line
			(start -0.674878 1.100074)
			(end -0.674878 -1.100074)
			(stroke
				(width 0.1)
				(type default)
			)
			(layer "F.Fab")
		)
		(fp_line
			(start 0.674878 -1.100074)
			(end 0.674878 1.100074)
			(stroke
				(width 0.1)
				(type default)
			)
			(layer "F.Fab")
		)
		(fp_line
			(start 0.674878 1.100074)
			(end -0.674878 1.100074)
			(stroke
				(width 0.1)
				(type default)
			)
			(layer "F.Fab")
		)
		(fp_poly
			(pts
				(xy -2.2352 -0.298958) (xy -2.2352 -1.001014) (xy -1.533144 -0.649986)
			)
			(stroke
				(width 0)
				(type default)
			)
			(fill yes)
			(layer "F.Fab")
		)
		(pad "1" smd rect
			(at -0.94996 -0.649986 90)
			(size 0.4318 0.508)
			(layers "F.Cu" "F.Mask" "F.Paste")
			(net "GND")
		)
		(pad "2" smd rect
			(at -0.94996 0 90)
			(size 0.4318 0.508)
			(layers "F.Cu" "F.Mask" "F.Paste")
			(net "HDD_ACTIVITY_BUF")
		)
		(pad "3" smd rect
			(at -0.94996 0.649986 90)
			(size 0.4318 0.508)
			(layers "F.Cu" "F.Mask" "F.Paste")
			(net "NC_Q95_D2")
		)
		(pad "4" smd rect
			(at 0.94996 0.649986 90)
			(size 0.4318 0.508)
			(layers "F.Cu" "F.Mask" "F.Paste")
			(net "NC_Q95_S2")
		)
		(pad "5" smd rect
			(at 0.94996 0 90)
			(size 0.4318 0.508)
			(layers "F.Cu" "F.Mask" "F.Paste")
			(net "NC_Q95_G2")
		)
		(pad "6" smd rect
			(at 0.94996 -0.649986 90)
			(size 0.4318 0.508)
			(layers "F.Cu" "F.Mask" "F.Paste")
			(net "HDD_ACTIVITY_BUF_N")
		)
	)
	(footprint ""
		(layer "F.Cu")
		(at 36.84143 -176.480978)
		(property "Reference" "PC1285"
			(at 0 0 0)
			(layer "F.SilkS")
			(hide yes)
			(effects
				(font
					(size 1.27 1.27)
				)
			)
		)
		(property "Value" ""
			(at 0 0 0)
			(layer "F.Fab")
			(effects
				(font
					(size 1.27 1.27)
				)
			)
		)
		(duplicate_pad_numbers_are_jumpers no)
		(fp_line
			(start -1.524 -0.762)
			(end 1.524 -0.762)
			(stroke
				(width 0.1524)
				(type default)
			)
			(layer "F.SilkS")
		)
		(fp_line
			(start -1.524 0.762)
			(end -1.524 -0.762)
			(stroke
				(width 0.1524)
				(type default)
			)
			(layer "F.SilkS")
		)
		(fp_line
			(start 1.524 -0.762)
			(end 1.524 0.762)
			(stroke
				(width 0.1524)
				(type default)
			)
			(layer "F.SilkS")
		)
		(fp_line
			(start 1.524 0.762)
			(end -1.524 0.762)
			(stroke
				(width 0.1524)
				(type default)
			)
			(layer "F.SilkS")
		)
		(fp_line
			(start -1.1049 -0.724916)
			(end -1.1049 0.724916)
			(stroke
				(width 0.1)
				(type default)
			)
			(layer "F.Fab")
		)
		(fp_line
			(start -1.1049 0.724916)
			(end 1.1049 0.724916)
			(stroke
				(width 0.1)
				(type default)
			)
			(layer "F.Fab")
		)
		(fp_line
			(start 1.1049 -0.724916)
			(end -1.1049 -0.724916)
			(stroke
				(width 0.1)
				(type default)
			)
			(layer "F.Fab")
		)
		(fp_line
			(start 1.1049 0.724916)
			(end 1.1049 -0.724916)
			(stroke
				(width 0.1)
				(type default)
			)
			(layer "F.Fab")
		)
		(pad "1" smd rect
			(at -0.889 0 180)
			(size 1.016 1.27)
			(layers "F.Cu" "F.Mask" "F.Paste")
			(net "PVNN_MAIN_CPU1")
		)
		(pad "2" smd rect
			(at 0.889 0 180)
			(size 1.016 1.27)
			(layers "F.Cu" "F.Mask" "F.Paste")
			(net "GND")
		)
	)
	(footprint ""
		(layer "F.Cu")
		(at 329.240388 0.383794 180)
		(property "Reference" "J83"
			(at -4.415282 -1.140206 90)
			(unlocked yes)
			(layer "F.SilkS")
			(effects
				(font
					(size 0.7874 0.5842)
					(thickness 0.1524)
				)
				(justify left)
			)
		)
		(property "Value" ""
			(at 0 0 180)
			(layer "F.Fab")
			(effects
				(font
					(size 1.27 1.27)
				)
			)
		)
		(duplicate_pad_numbers_are_jumpers no)
		(fp_line
			(start 1.2192 2.1082)
			(end -1.2192 2.1082)
			(stroke
				(width 0.1524)
				(type default)
			)
			(layer "F.SilkS")
		)
		(fp_line
			(start 1.2192 -2.1082)
			(end 1.2192 2.1082)
			(stroke
				(width 0.1524)
				(type default)
			)
			(layer "F.SilkS")
		)
		(fp_line
			(start -1.2192 2.1082)
			(end -1.2192 -2.1082)
			(stroke
				(width 0.1524)
				(type default)
			)
			(layer "F.SilkS")
		)
		(fp_line
			(start -1.2192 -2.1082)
			(end 1.2192 -2.1082)
			(stroke
				(width 0.1524)
				(type default)
			)
			(layer "F.SilkS")
		)
		(pad "" np_thru_hole circle
			(at -2.8829 -1.27 90)
			(size 1.0414 1.0414)
			(drill 1.0414)
			(layers "*.Cu" "*.Mask")
			(clearance 0.381)
			(thermal_gap 0.381)
		)
		(pad "" np_thru_hole circle
			(at -2.8829 1.27 90)
			(size 1.0414 1.0414)
			(drill 1.0414)
			(layers "*.Cu" "*.Mask")
			(clearance 0.381)
			(thermal_gap 0.381)
		)
		(pad "" np_thru_hole circle
			(at 3.4671 -1.27 90)
			(size 1.0414 1.0414)
			(drill 1.0414)
			(layers "*.Cu" "*.Mask")
			(clearance 0.381)
			(thermal_gap 0.381)
		)
		(pad "" np_thru_hole circle
			(at 3.4671 1.27 90)
			(size 1.0414 1.0414)
			(drill 1.0414)
			(layers "*.Cu" "*.Mask")
			(clearance 0.381)
			(thermal_gap 0.381)
		)
		(pad "1" smd rect
			(at 0.8255 -0.249936 90)
			(size 0.3048 0.508)
			(layers "F.Cu" "F.Mask" "F.Paste")
			(net "DELTA_L_85_10INCH_IN1_DN")
		)
		(pad "2" smd rect
			(at 0.8255 0.249936 90)
			(size 0.3048 0.508)
			(layers "F.Cu" "F.Mask" "F.Paste")
			(net "DELTA_L_85_10INCH_IN1_DP")
		)
		(pad "3" smd circle
			(at 0 0 180)
			(size 0 0)
			(layers "F.Cu" "F.Mask" "F.Paste")
			(net "DELTA_L_GND_1")
		)
		(zone
			(layer "F.Cu")
			(hatch none 0.5)
			(connect_pads
				(clearance 0)
			)
			(min_thickness 0.25)
			(keepout
				(tracks not_allowed)
				(vias allowed)
				(pads allowed)
				(copperpour not_allowed)
				(footprints allowed)
			)
			(placement
				(enabled no)
				(sheetname "")
			)
			(fill
				(thermal_gap 0.5)
				(thermal_bridge_width 0.5)
				(island_removal_mode 0)
			)
			(polygon
				(pts
					(xy 328.122788 0.932434) (xy 328.122788 0.83693) (xy 328.719688 0.83693) (xy 328.719688 0.43053)
					(xy 328.122788 0.43053) (xy 328.122788 0.337058) (xy 328.719688 0.337058) (xy 328.719688 -0.069342)
					(xy 328.122788 -0.069342) (xy 328.122788 -0.164846) (xy 328.821288 -0.164846) (xy 328.821288 0.932434)
				)
			)
		)
		(zone
			(layers "F.Cu" "B.Cu" "In1.Cu" "In2.Cu" "In3.Cu" "In4.Cu" "In5.Cu" "In6.Cu"
				"In7.Cu" "In8.Cu" "In9.Cu" "In10.Cu" "In11.Cu" "In12.Cu" "In13.Cu" "In14.Cu"
				"In15.Cu" "In16.Cu"
			)
			(hatch none 0.5)
			(connect_pads
				(clearance 0)
			)
			(min_thickness 0.25)
			(keepout
				(tracks not_allowed)
				(vias allowed)
				(pads allowed)
				(copperpour not_allowed)
				(footprints allowed)
			)
			(placement
				(enabled no)
				(sheetname "")
			)
			(fill
				(thermal_gap 0.5)
				(thermal_bridge_width 0.5)
				(island_removal_mode 0)
			)
			(polygon
				(pts
					(arc
						(start 326.700388 -0.886206)
						(mid 324.846188 -0.886206)
						(end 326.700388 -0.886206)
					)
				)
			)
		)
		(zone
			(layers "F.Cu" "B.Cu" "In1.Cu" "In2.Cu" "In3.Cu" "In4.Cu" "In5.Cu" "In6.Cu"
				"In7.Cu" "In8.Cu" "In9.Cu" "In10.Cu" "In11.Cu" "In12.Cu" "In13.Cu" "In14.Cu"
				"In15.Cu" "In16.Cu"
			)
			(hatch none 0.5)
			(connect_pads
				(clearance 0)
			)
			(min_thickness 0.25)
			(keepout
				(tracks not_allowed)
				(vias allowed)
				(pads allowed)
				(copperpour not_allowed)
				(footprints allowed)
			)
			(placement
				(enabled no)
				(sheetname "")
			)
			(fill
				(thermal_gap 0.5)
				(thermal_bridge_width 0.5)
				(island_removal_mode 0)
			)
			(polygon
				(pts
					(arc
						(start 326.700388 1.653794)
						(mid 324.846188 1.653794)
						(end 326.700388 1.653794)
					)
				)
			)
		)
		(zone
			(layers "F.Cu" "B.Cu" "In1.Cu" "In2.Cu" "In3.Cu" "In4.Cu" "In5.Cu" "In6.Cu"
				"In7.Cu" "In8.Cu" "In9.Cu" "In10.Cu" "In11.Cu" "In12.Cu" "In13.Cu" "In14.Cu"
				"In15.Cu" "In16.Cu"
			)
			(hatch none 0.5)
			(connect_pads
				(clearance 0)
			)
			(min_thickness 0.25)
			(keepout
				(tracks not_allowed)
				(vias allowed)
				(pads allowed)
				(copperpour not_allowed)
				(footprints allowed)
			)
			(placement
				(enabled no)
				(sheetname "")
			)
			(fill
				(thermal_gap 0.5)
				(thermal_bridge_width 0.5)
				(island_removal_mode 0)
			)
			(polygon
				(pts
					(arc
						(start 333.050388 -0.886206)
						(mid 331.196188 -0.886206)
						(end 333.050388 -0.886206)
					)
				)
			)
		)
		(zone
			(layers "F.Cu" "B.Cu" "In1.Cu" "In2.Cu" "In3.Cu" "In4.Cu" "In5.Cu" "In6.Cu"
				"In7.Cu" "In8.Cu" "In9.Cu" "In10.Cu" "In11.Cu" "In12.Cu" "In13.Cu" "In14.Cu"
				"In15.Cu" "In16.Cu"
			)
			(hatch none 0.5)
			(connect_pads
				(clearance 0)
			)
			(min_thickness 0.25)
			(keepout
				(tracks not_allowed)
				(vias allowed)
				(pads allowed)
				(copperpour not_allowed)
				(footprints allowed)
			)
			(placement
				(enabled no)
				(sheetname "")
			)
			(fill
				(thermal_gap 0.5)
				(thermal_bridge_width 0.5)
				(island_removal_mode 0)
			)
			(polygon
				(pts
					(arc
						(start 333.050388 1.653794)
						(mid 331.196188 1.653794)
						(end 333.050388 1.653794)
					)
				)
			)
		)
	)
	(footprint ""
		(layer "F.Cu")
		(at 24.069802 -411.434534)
		(property "Reference" "R3487"
			(at 0 0 0)
			(layer "F.SilkS")
			(hide yes)
			(effects
				(font
					(size 1.27 1.27)
				)
			)
		)
		(property "Value" ""
			(at 0 0 0)
			(layer "F.Fab")
			(effects
				(font
					(size 1.27 1.27)
				)
			)
		)
		(duplicate_pad_numbers_are_jumpers no)
		(fp_line
			(start -0.7874 -0.4064)
			(end 0.7874 -0.4064)
			(stroke
				(width 0.1524)
				(type default)
			)
			(layer "F.SilkS")
		)
		(fp_line
			(start -0.7874 0.4064)
			(end -0.7874 -0.4064)
			(stroke
				(width 0.1524)
				(type default)
			)
			(layer "F.SilkS")
		)
		(fp_line
			(start 0.7874 -0.4064)
			(end 0.7874 0.4064)
			(stroke
				(width 0.1524)
				(type default)
			)
			(layer "F.SilkS")
		)
		(fp_line
			(start 0.7874 0.4064)
			(end -0.7874 0.4064)
			(stroke
				(width 0.1524)
				(type default)
			)
			(layer "F.SilkS")
		)
		(fp_line
			(start -0.67945 -0.305054)
			(end -0.12065 -0.305054)
			(stroke
				(width 0.1)
				(type default)
			)
			(layer "F.Fab")
		)
		(fp_line
			(start -0.67945 0.3048)
			(end -0.67945 -0.305054)
			(stroke
				(width 0.1)
				(type default)
			)
			(layer "F.Fab")
		)
		(fp_line
			(start -0.12065 -0.305054)
			(end -0.12065 -0.2794)
			(stroke
				(width 0.1)
				(type default)
			)
			(layer "F.Fab")
		)
		(fp_line
			(start -0.12065 -0.2794)
			(end 0.12065 -0.2794)
			(stroke
				(width 0.1)
				(type default)
			)
			(layer "F.Fab")
		)
		(fp_line
			(start -0.12065 0.2794)
			(end -0.12065 0.3048)
			(stroke
				(width 0.1)
				(type default)
			)
			(layer "F.Fab")
		)
		(fp_line
			(start -0.12065 0.3048)
			(end -0.67945 0.3048)
			(stroke
				(width 0.1)
				(type default)
			)
			(layer "F.Fab")
		)
		(fp_line
			(start 0.120396 0.2794)
			(end -0.12065 0.2794)
			(stroke
				(width 0.1)
				(type default)
			)
			(layer "F.Fab")
		)
		(fp_line
			(start 0.120396 0.3048)
			(end 0.120396 0.2794)
			(stroke
				(width 0.1)
				(type default)
			)
			(layer "F.Fab")
		)
		(fp_line
			(start 0.12065 -0.3048)
			(end 0.67945 -0.3048)
			(stroke
				(width 0.1)
				(type default)
			)
			(layer "F.Fab")
		)
		(fp_line
			(start 0.12065 -0.2794)
			(end 0.12065 -0.3048)
			(stroke
				(width 0.1)
				(type default)
			)
			(layer "F.Fab")
		)
		(fp_line
			(start 0.67945 -0.3048)
			(end 0.67945 0.3048)
			(stroke
				(width 0.1)
				(type default)
			)
			(layer "F.Fab")
		)
		(fp_line
			(start 0.67945 0.3048)
			(end 0.120396 0.3048)
			(stroke
				(width 0.1)
				(type default)
			)
			(layer "F.Fab")
		)
		(pad "1" smd circle
			(at -0.40005 0)
			(size 0 0)
			(layers "F.Cu" "F.Mask" "F.Paste")
			(net "P3V3_AUX")
		)
		(pad "2" smd circle
			(at 0.40005 0)
			(size 0 0)
			(layers "F.Cu" "F.Mask" "F.Paste")
			(net "GPU_PRSNT_N")
		)
	)
	(footprint ""
		(layer "F.Cu")
		(at 156.888434 -402.371052 -90)
		(property "Reference" "C767"
			(at 0 0 270)
			(layer "F.SilkS")
			(hide yes)
			(effects
				(font
					(size 1.27 1.27)
				)
			)
		)
		(property "Value" ""
			(at 0 0 270)
			(layer "F.Fab")
			(effects
				(font
					(size 1.27 1.27)
				)
			)
		)
		(duplicate_pad_numbers_are_jumpers no)
		(fp_line
			(start -0.299974 0.150114)
			(end -0.299974 -0.150114)
			(stroke
				(width 0.1)
				(type default)
			)
			(layer "F.Fab")
		)
		(fp_line
			(start 0.299974 0.150114)
			(end -0.299974 0.150114)
			(stroke
				(width 0.1)
				(type default)
			)
			(layer "F.Fab")
		)
		(fp_line
			(start -0.299974 -0.150114)
			(end 0.299974 -0.150114)
			(stroke
				(width 0.1)
				(type default)
			)
			(layer "F.Fab")
		)
		(fp_line
			(start 0.299974 -0.150114)
			(end 0.299974 0.150114)
			(stroke
				(width 0.1)
				(type default)
			)
			(layer "F.Fab")
		)
		(pad "1" smd rect
			(at -0.2667 0 270)
			(size 0.3048 0.381)
			(layers "F.Cu" "F.Mask" "F.Paste")
			(net "P5E_CPU1_PE2_TX_C_DP<3>")
		)
		(pad "2" smd rect
			(at 0.2667 0 270)
			(size 0.3048 0.381)
			(layers "F.Cu" "F.Mask" "F.Paste")
			(net "P5E_CPU1_PE2_TX_DP<3>")
		)
	)
	(footprint ""
		(layer "F.Cu")
		(at 265.029696 -72.262492 90)
		(property "Reference" "PC1219"
			(at 0 0 90)
			(layer "F.SilkS")
			(hide yes)
			(effects
				(font
					(size 1.27 1.27)
				)
			)
		)
		(property "Value" ""
			(at 0 0 90)
			(layer "F.Fab")
			(effects
				(font
					(size 1.27 1.27)
				)
			)
		)
		(duplicate_pad_numbers_are_jumpers no)
		(fp_line
			(start 0.7874 -0.4064)
			(end 0.7874 0.4064)
			(stroke
				(width 0.1524)
				(type default)
			)
			(layer "F.SilkS")
		)
		(fp_line
			(start -0.7874 -0.4064)
			(end 0.7874 -0.4064)
			(stroke
				(width 0.1524)
				(type default)
			)
			(layer "F.SilkS")
		)
		(fp_line
			(start 0.7874 0.4064)
			(end -0.7874 0.4064)
			(stroke
				(width 0.1524)
				(type default)
			)
			(layer "F.SilkS")
		)
		(fp_line
			(start -0.7874 0.4064)
			(end -0.7874 -0.4064)
			(stroke
				(width 0.1524)
				(type default)
			)
			(layer "F.SilkS")
		)
		(fp_line
			(start -0.12065 -0.305054)
			(end -0.12065 -0.2794)
			(stroke
				(width 0.1)
				(type default)
			)
			(layer "F.Fab")
		)
		(fp_line
			(start -0.67945 -0.305054)
			(end -0.12065 -0.305054)
			(stroke
				(width 0.1)
				(type default)
			)
			(layer "F.Fab")
		)
		(fp_line
			(start 0.67945 -0.3048)
			(end 0.67945 0.3048)
			(stroke
				(width 0.1)
				(type default)
			)
			(layer "F.Fab")
		)
		(fp_line
			(start 0.12065 -0.3048)
			(end 0.67945 -0.3048)
			(stroke
				(width 0.1)
				(type default)
			)
			(layer "F.Fab")
		)
		(fp_line
			(start 0.12065 -0.2794)
			(end 0.12065 -0.3048)
			(stroke
				(width 0.1)
				(type default)
			)
			(layer "F.Fab")
		)
		(fp_line
			(start -0.12065 -0.2794)
			(end 0.12065 -0.2794)
			(stroke
				(width 0.1)
				(type default)
			)
			(layer "F.Fab")
		)
		(fp_line
			(start 0.120396 0.2794)
			(end -0.12065 0.2794)
			(stroke
				(width 0.1)
				(type default)
			)
			(layer "F.Fab")
		)
		(fp_line
			(start -0.12065 0.2794)
			(end -0.12065 0.3048)
			(stroke
				(width 0.1)
				(type default)
			)
			(layer "F.Fab")
		)
		(fp_line
			(start 0.67945 0.3048)
			(end 0.120396 0.3048)
			(stroke
				(width 0.1)
				(type default)
			)
			(layer "F.Fab")
		)
		(fp_line
			(start 0.120396 0.3048)
			(end 0.120396 0.2794)
			(stroke
				(width 0.1)
				(type default)
			)
			(layer "F.Fab")
		)
		(fp_line
			(start -0.12065 0.3048)
			(end -0.67945 0.3048)
			(stroke
				(width 0.1)
				(type default)
			)
			(layer "F.Fab")
		)
		(fp_line
			(start -0.67945 0.3048)
			(end -0.67945 -0.305054)
			(stroke
				(width 0.1)
				(type default)
			)
			(layer "F.Fab")
		)
		(pad "1" smd circle
			(at -0.40005 0 90)
			(size 0 0)
			(layers "F.Cu" "F.Mask" "F.Paste")
			(net "SW_P12V_AUX_P1V05_PCH_AUX_FLT")
		)
		(pad "2" smd circle
			(at 0.40005 0 90)
			(size 0 0)
			(layers "F.Cu" "F.Mask" "F.Paste")
			(net "GND")
		)
	)
	(footprint ""
		(layer "F.Cu")
		(at 143.895318 -113.463324 180)
		(property "Reference" "R4758"
			(at 0 0 180)
			(layer "F.SilkS")
			(hide yes)
			(effects
				(font
					(size 1.27 1.27)
				)
			)
		)
		(property "Value" ""
			(at 0 0 180)
			(layer "F.Fab")
			(effects
				(font
					(size 1.27 1.27)
				)
			)
		)
		(duplicate_pad_numbers_are_jumpers no)
		(fp_line
			(start 0.7874 0.4064)
			(end -0.7874 0.4064)
			(stroke
				(width 0.1524)
				(type default)
			)
			(layer "F.SilkS")
		)
		(fp_line
			(start 0.7874 -0.4064)
			(end 0.7874 0.4064)
			(stroke
				(width 0.1524)
				(type default)
			)
			(layer "F.SilkS")
		)
		(fp_line
			(start -0.7874 0.4064)
			(end -0.7874 -0.4064)
			(stroke
				(width 0.1524)
				(type default)
			)
			(layer "F.SilkS")
		)
		(fp_line
			(start -0.7874 -0.4064)
			(end 0.7874 -0.4064)
			(stroke
				(width 0.1524)
				(type default)
			)
			(layer "F.SilkS")
		)
		(fp_line
			(start 0.67945 0.3048)
			(end 0.120396 0.3048)
			(stroke
				(width 0.1)
				(type default)
			)
			(layer "F.Fab")
		)
		(fp_line
			(start 0.67945 -0.3048)
			(end 0.67945 0.3048)
			(stroke
				(width 0.1)
				(type default)
			)
			(layer "F.Fab")
		)
		(fp_line
			(start 0.12065 -0.2794)
			(end 0.12065 -0.3048)
			(stroke
				(width 0.1)
				(type default)
			)
			(layer "F.Fab")
		)
		(fp_line
			(start 0.12065 -0.3048)
			(end 0.67945 -0.3048)
			(stroke
				(width 0.1)
				(type default)
			)
			(layer "F.Fab")
		)
		(fp_line
			(start 0.120396 0.3048)
			(end 0.120396 0.2794)
			(stroke
				(width 0.1)
				(type default)
			)
			(layer "F.Fab")
		)
		(fp_line
			(start 0.120396 0.2794)
			(end -0.12065 0.2794)
			(stroke
				(width 0.1)
				(type default)
			)
			(layer "F.Fab")
		)
		(fp_line
			(start -0.12065 0.3048)
			(end -0.67945 0.3048)
			(stroke
				(width 0.1)
				(type default)
			)
			(layer "F.Fab")
		)
		(fp_line
			(start -0.12065 0.2794)
			(end -0.12065 0.3048)
			(stroke
				(width 0.1)
				(type default)
			)
			(layer "F.Fab")
		)
		(fp_line
			(start -0.12065 -0.2794)
			(end 0.12065 -0.2794)
			(stroke
				(width 0.1)
				(type default)
			)
			(layer "F.Fab")
		)
		(fp_line
			(start -0.12065 -0.305054)
			(end -0.12065 -0.2794)
			(stroke
				(width 0.1)
				(type default)
			)
			(layer "F.Fab")
		)
		(fp_line
			(start -0.67945 0.3048)
			(end -0.67945 -0.305054)
			(stroke
				(width 0.1)
				(type default)
			)
			(layer "F.Fab")
		)
		(fp_line
			(start -0.67945 -0.305054)
			(end -0.12065 -0.305054)
			(stroke
				(width 0.1)
				(type default)
			)
			(layer "F.Fab")
		)
		(pad "1" smd circle
			(at -0.40005 0 180)
			(size 0 0)
			(layers "F.Cu" "F.Mask" "F.Paste")
			(net "OCP_V3_2_AUX_PWR_PLD_EN_R")
		)
		(pad "2" smd circle
			(at 0.40005 0 180)
			(size 0 0)
			(layers "F.Cu" "F.Mask" "F.Paste")
			(net "OCP_V3_2_AUX_PWR_EN_R2")
		)
	)
	(footprint ""
		(layer "F.Cu")
		(at 117.098826 -315.66739 90)
		(property "Reference" "PC583"
			(at 0 0 90)
			(layer "F.SilkS")
			(hide yes)
			(effects
				(font
					(size 1.27 1.27)
				)
			)
		)
		(property "Value" ""
			(at 0 0 90)
			(layer "F.Fab")
			(effects
				(font
					(size 1.27 1.27)
				)
			)
		)
		(duplicate_pad_numbers_are_jumpers no)
		(fp_line
			(start 2.750058 0.999998)
			(end -2.750058 0.999998)
			(stroke
				(width 0.1524)
				(type default)
			)
			(layer "F.SilkS")
		)
		(fp_circle
			(center 0 0.999998)
			(end 0 3.750056)
			(stroke
				(width 0.1524)
				(type default)
			)
			(fill no)
			(layer "F.SilkS")
		)
		(fp_poly
			(pts
				(arc
					(start 2.750058 0.999998)
					(mid 0 3.750056)
					(end -2.750058 0.999998)
				)
			)
			(stroke
				(width 0)
				(type default)
			)
			(fill yes)
			(layer "F.SilkS")
		)
		(fp_circle
			(center 0 0.999998)
			(end 0 3.750056)
			(stroke
				(width 0.1)
				(type default)
			)
			(fill no)
			(layer "F.Fab")
		)
		(pad "1" thru_hole rect
			(at 0 0 90)
			(size 1.5748 1.5748)
			(drill 1.0668)
			(layers "*.Cu" "*.Mask")
			(remove_unused_layers no)
			(net "PVCCIN_CPU1")
			(clearance 0)
			(padstack
				(mode front_inner_back)
				(layer "Inner"
					(shape circle)
					(size 1.5748 1.5748)
					(clearance 0)
				)
				(layer "B.Cu"
					(shape rect)
					(size 1.5748 1.5748)
					(clearance 0)
				)
			)
		)
		(pad "2" thru_hole circle
			(at 0 1.999996 90)
			(size 1.5748 1.5748)
			(drill 1.0668)
			(layers "*.Cu" "*.Mask")
			(remove_unused_layers no)
			(net "GND")
			(clearance 0)
		)
	)
	(footprint ""
		(layer "F.Cu")
		(at 114.68608 -122.132598 90)
		(property "Reference" "C2252"
			(at 0 0 90)
			(layer "F.SilkS")
			(hide yes)
			(effects
				(font
					(size 1.27 1.27)
				)
			)
		)
		(property "Value" ""
			(at 0 0 90)
			(layer "F.Fab")
			(effects
				(font
					(size 1.27 1.27)
				)
			)
		)
		(duplicate_pad_numbers_are_jumpers no)
		(fp_line
			(start 0.7874 -0.4064)
			(end 0.7874 0.4064)
			(stroke
				(width 0.1524)
				(type default)
			)
			(layer "F.SilkS")
		)
		(fp_line
			(start -0.7874 -0.4064)
			(end 0.7874 -0.4064)
			(stroke
				(width 0.1524)
				(type default)
			)
			(layer "F.SilkS")
		)
		(fp_line
			(start 0.7874 0.4064)
			(end -0.7874 0.4064)
			(stroke
				(width 0.1524)
				(type default)
			)
			(layer "F.SilkS")
		)
		(fp_line
			(start -0.7874 0.4064)
			(end -0.7874 -0.4064)
			(stroke
				(width 0.1524)
				(type default)
			)
			(layer "F.SilkS")
		)
		(fp_line
			(start -0.12065 -0.305054)
			(end -0.12065 -0.2794)
			(stroke
				(width 0.1)
				(type default)
			)
			(layer "F.Fab")
		)
		(fp_line
			(start -0.67945 -0.305054)
			(end -0.12065 -0.305054)
			(stroke
				(width 0.1)
				(type default)
			)
			(layer "F.Fab")
		)
		(fp_line
			(start 0.67945 -0.3048)
			(end 0.67945 0.3048)
			(stroke
				(width 0.1)
				(type default)
			)
			(layer "F.Fab")
		)
		(fp_line
			(start 0.12065 -0.3048)
			(end 0.67945 -0.3048)
			(stroke
				(width 0.1)
				(type default)
			)
			(layer "F.Fab")
		)
		(fp_line
			(start 0.12065 -0.2794)
			(end 0.12065 -0.3048)
			(stroke
				(width 0.1)
				(type default)
			)
			(layer "F.Fab")
		)
		(fp_line
			(start -0.12065 -0.2794)
			(end 0.12065 -0.2794)
			(stroke
				(width 0.1)
				(type default)
			)
			(layer "F.Fab")
		)
		(fp_line
			(start 0.120396 0.2794)
			(end -0.12065 0.2794)
			(stroke
				(width 0.1)
				(type default)
			)
			(layer "F.Fab")
		)
		(fp_line
			(start -0.12065 0.2794)
			(end -0.12065 0.3048)
			(stroke
				(width 0.1)
				(type default)
			)
			(layer "F.Fab")
		)
		(fp_line
			(start 0.67945 0.3048)
			(end 0.120396 0.3048)
			(stroke
				(width 0.1)
				(type default)
			)
			(layer "F.Fab")
		)
		(fp_line
			(start 0.120396 0.3048)
			(end 0.120396 0.2794)
			(stroke
				(width 0.1)
				(type default)
			)
			(layer "F.Fab")
		)
		(fp_line
			(start -0.12065 0.3048)
			(end -0.67945 0.3048)
			(stroke
				(width 0.1)
				(type default)
			)
			(layer "F.Fab")
		)
		(fp_line
			(start -0.67945 0.3048)
			(end -0.67945 -0.305054)
			(stroke
				(width 0.1)
				(type default)
			)
			(layer "F.Fab")
		)
		(pad "1" smd circle
			(at -0.40005 0 90)
			(size 0 0)
			(layers "F.Cu" "F.Mask" "F.Paste")
			(net "P0V62_CPU0_RST_DDR_VREF")
		)
		(pad "2" smd circle
			(at 0.40005 0 90)
			(size 0 0)
			(layers "F.Cu" "F.Mask" "F.Paste")
			(net "GND")
		)
	)
	(footprint ""
		(layer "F.Cu")
		(at 128.401572 -131.018026)
		(property "Reference" "R2566"
			(at 0 0 0)
			(layer "F.SilkS")
			(hide yes)
			(effects
				(font
					(size 1.27 1.27)
				)
			)
		)
		(property "Value" ""
			(at 0 0 0)
			(layer "F.Fab")
			(effects
				(font
					(size 1.27 1.27)
				)
			)
		)
		(duplicate_pad_numbers_are_jumpers no)
		(fp_line
			(start -0.7874 -0.4064)
			(end 0.7874 -0.4064)
			(stroke
				(width 0.1524)
				(type default)
			)
			(layer "F.SilkS")
		)
		(fp_line
			(start -0.7874 0.4064)
			(end -0.7874 -0.4064)
			(stroke
				(width 0.1524)
				(type default)
			)
			(layer "F.SilkS")
		)
		(fp_line
			(start 0.7874 -0.4064)
			(end 0.7874 0.4064)
			(stroke
				(width 0.1524)
				(type default)
			)
			(layer "F.SilkS")
		)
		(fp_line
			(start 0.7874 0.4064)
			(end -0.7874 0.4064)
			(stroke
				(width 0.1524)
				(type default)
			)
			(layer "F.SilkS")
		)
		(fp_line
			(start -0.67945 -0.305054)
			(end -0.12065 -0.305054)
			(stroke
				(width 0.1)
				(type default)
			)
			(layer "F.Fab")
		)
		(fp_line
			(start -0.67945 0.3048)
			(end -0.67945 -0.305054)
			(stroke
				(width 0.1)
				(type default)
			)
			(layer "F.Fab")
		)
		(fp_line
			(start -0.12065 -0.305054)
			(end -0.12065 -0.2794)
			(stroke
				(width 0.1)
				(type default)
			)
			(layer "F.Fab")
		)
		(fp_line
			(start -0.12065 -0.2794)
			(end 0.12065 -0.2794)
			(stroke
				(width 0.1)
				(type default)
			)
			(layer "F.Fab")
		)
		(fp_line
			(start -0.12065 0.2794)
			(end -0.12065 0.3048)
			(stroke
				(width 0.1)
				(type default)
			)
			(layer "F.Fab")
		)
		(fp_line
			(start -0.12065 0.3048)
			(end -0.67945 0.3048)
			(stroke
				(width 0.1)
				(type default)
			)
			(layer "F.Fab")
		)
		(fp_line
			(start 0.120396 0.2794)
			(end -0.12065 0.2794)
			(stroke
				(width 0.1)
				(type default)
			)
			(layer "F.Fab")
		)
		(fp_line
			(start 0.120396 0.3048)
			(end 0.120396 0.2794)
			(stroke
				(width 0.1)
				(type default)
			)
			(layer "F.Fab")
		)
		(fp_line
			(start 0.12065 -0.3048)
			(end 0.67945 -0.3048)
			(stroke
				(width 0.1)
				(type default)
			)
			(layer "F.Fab")
		)
		(fp_line
			(start 0.12065 -0.2794)
			(end 0.12065 -0.3048)
			(stroke
				(width 0.1)
				(type default)
			)
			(layer "F.Fab")
		)
		(fp_line
			(start 0.67945 -0.3048)
			(end 0.67945 0.3048)
			(stroke
				(width 0.1)
				(type default)
			)
			(layer "F.Fab")
		)
		(fp_line
			(start 0.67945 0.3048)
			(end 0.120396 0.3048)
			(stroke
				(width 0.1)
				(type default)
			)
			(layer "F.Fab")
		)
		(pad "1" smd circle
			(at -0.40005 0)
			(size 0 0)
			(layers "F.Cu" "F.Mask" "F.Paste")
			(net "SMB_FRU_3V3AUX_SDA_R")
		)
		(pad "2" smd circle
			(at 0.40005 0)
			(size 0 0)
			(layers "F.Cu" "F.Mask" "F.Paste")
			(net "SMB_FRU_3V3AUX_SDA")
		)
	)
	(footprint ""
		(layer "F.Cu")
		(at 44.467018 -439.824368 -90)
		(property "Reference" "R2986"
			(at 0 0 270)
			(layer "F.SilkS")
			(hide yes)
			(effects
				(font
					(size 1.27 1.27)
				)
			)
		)
		(property "Value" ""
			(at 0 0 270)
			(layer "F.Fab")
			(effects
				(font
					(size 1.27 1.27)
				)
			)
		)
		(duplicate_pad_numbers_are_jumpers no)
		(fp_line
			(start -0.7874 0.4064)
			(end -0.7874 -0.4064)
			(stroke
				(width 0.1524)
				(type default)
			)
			(layer "F.SilkS")
		)
		(fp_line
			(start 0.7874 0.4064)
			(end -0.7874 0.4064)
			(stroke
				(width 0.1524)
				(type default)
			)
			(layer "F.SilkS")
		)
		(fp_line
			(start -0.7874 -0.4064)
			(end 0.7874 -0.4064)
			(stroke
				(width 0.1524)
				(type default)
			)
			(layer "F.SilkS")
		)
		(fp_line
			(start 0.7874 -0.4064)
			(end 0.7874 0.4064)
			(stroke
				(width 0.1524)
				(type default)
			)
			(layer "F.SilkS")
		)
		(fp_line
			(start -0.67945 0.3048)
			(end -0.67945 -0.305054)
			(stroke
				(width 0.1)
				(type default)
			)
			(layer "F.Fab")
		)
		(fp_line
			(start -0.12065 0.3048)
			(end -0.67945 0.3048)
			(stroke
				(width 0.1)
				(type default)
			)
			(layer "F.Fab")
		)
		(fp_line
			(start 0.120396 0.3048)
			(end 0.120396 0.2794)
			(stroke
				(width 0.1)
				(type default)
			)
			(layer "F.Fab")
		)
		(fp_line
			(start 0.67945 0.3048)
			(end 0.120396 0.3048)
			(stroke
				(width 0.1)
				(type default)
			)
			(layer "F.Fab")
		)
		(fp_line
			(start -0.12065 0.2794)
			(end -0.12065 0.3048)
			(stroke
				(width 0.1)
				(type default)
			)
			(layer "F.Fab")
		)
		(fp_line
			(start 0.120396 0.2794)
			(end -0.12065 0.2794)
			(stroke
				(width 0.1)
				(type default)
			)
			(layer "F.Fab")
		)
		(fp_line
			(start -0.12065 -0.2794)
			(end 0.12065 -0.2794)
			(stroke
				(width 0.1)
				(type default)
			)
			(layer "F.Fab")
		)
		(fp_line
			(start 0.12065 -0.2794)
			(end 0.12065 -0.3048)
			(stroke
				(width 0.1)
				(type default)
			)
			(layer "F.Fab")
		)
		(fp_line
			(start 0.12065 -0.3048)
			(end 0.67945 -0.3048)
			(stroke
				(width 0.1)
				(type default)
			)
			(layer "F.Fab")
		)
		(fp_line
			(start 0.67945 -0.3048)
			(end 0.67945 0.3048)
			(stroke
				(width 0.1)
				(type default)
			)
			(layer "F.Fab")
		)
		(fp_line
			(start -0.67945 -0.305054)
			(end -0.12065 -0.305054)
			(stroke
				(width 0.1)
				(type default)
			)
			(layer "F.Fab")
		)
		(fp_line
			(start -0.12065 -0.305054)
			(end -0.12065 -0.2794)
			(stroke
				(width 0.1)
				(type default)
			)
			(layer "F.Fab")
		)
		(pad "1" smd circle
			(at -0.40005 0 270)
			(size 0 0)
			(layers "F.Cu" "F.Mask" "F.Paste")
			(net "SMB_2_BMC_GPU_R_SCL")
		)
		(pad "2" smd circle
			(at 0.40005 0 270)
			(size 0 0)
			(layers "F.Cu" "F.Mask" "F.Paste")
			(net "SMB_2_BMC_GPU_BUF_R_SCL")
		)
	)
	(footprint ""
		(layer "F.Cu")
		(at 416.097974 -158.61665 180)
		(property "Reference" "PC634"
			(at 0 0 180)
			(layer "F.SilkS")
			(hide yes)
			(effects
				(font
					(size 1.27 1.27)
				)
			)
		)
		(property "Value" ""
			(at 0 0 180)
			(layer "F.Fab")
			(effects
				(font
					(size 1.27 1.27)
				)
			)
		)
		(duplicate_pad_numbers_are_jumpers no)
		(fp_line
			(start 0.7874 0.4064)
			(end -0.7874 0.4064)
			(stroke
				(width 0.1524)
				(type default)
			)
			(layer "F.SilkS")
		)
		(fp_line
			(start 0.7874 -0.4064)
			(end 0.7874 0.4064)
			(stroke
				(width 0.1524)
				(type default)
			)
			(layer "F.SilkS")
		)
		(fp_line
			(start -0.7874 0.4064)
			(end -0.7874 -0.4064)
			(stroke
				(width 0.1524)
				(type default)
			)
			(layer "F.SilkS")
		)
		(fp_line
			(start -0.7874 -0.4064)
			(end 0.7874 -0.4064)
			(stroke
				(width 0.1524)
				(type default)
			)
			(layer "F.SilkS")
		)
		(fp_line
			(start 0.67945 0.3048)
			(end 0.120396 0.3048)
			(stroke
				(width 0.1)
				(type default)
			)
			(layer "F.Fab")
		)
		(fp_line
			(start 0.67945 -0.3048)
			(end 0.67945 0.3048)
			(stroke
				(width 0.1)
				(type default)
			)
			(layer "F.Fab")
		)
		(fp_line
			(start 0.12065 -0.2794)
			(end 0.12065 -0.3048)
			(stroke
				(width 0.1)
				(type default)
			)
			(layer "F.Fab")
		)
		(fp_line
			(start 0.12065 -0.3048)
			(end 0.67945 -0.3048)
			(stroke
				(width 0.1)
				(type default)
			)
			(layer "F.Fab")
		)
		(fp_line
			(start 0.120396 0.3048)
			(end 0.120396 0.2794)
			(stroke
				(width 0.1)
				(type default)
			)
			(layer "F.Fab")
		)
		(fp_line
			(start 0.120396 0.2794)
			(end -0.12065 0.2794)
			(stroke
				(width 0.1)
				(type default)
			)
			(layer "F.Fab")
		)
		(fp_line
			(start -0.12065 0.3048)
			(end -0.67945 0.3048)
			(stroke
				(width 0.1)
				(type default)
			)
			(layer "F.Fab")
		)
		(fp_line
			(start -0.12065 0.2794)
			(end -0.12065 0.3048)
			(stroke
				(width 0.1)
				(type default)
			)
			(layer "F.Fab")
		)
		(fp_line
			(start -0.12065 -0.2794)
			(end 0.12065 -0.2794)
			(stroke
				(width 0.1)
				(type default)
			)
			(layer "F.Fab")
		)
		(fp_line
			(start -0.12065 -0.305054)
			(end -0.12065 -0.2794)
			(stroke
				(width 0.1)
				(type default)
			)
			(layer "F.Fab")
		)
		(fp_line
			(start -0.67945 0.3048)
			(end -0.67945 -0.305054)
			(stroke
				(width 0.1)
				(type default)
			)
			(layer "F.Fab")
		)
		(fp_line
			(start -0.67945 -0.305054)
			(end -0.12065 -0.305054)
			(stroke
				(width 0.1)
				(type default)
			)
			(layer "F.Fab")
		)
		(pad "1" smd circle
			(at -0.40005 0 180)
			(size 0 0)
			(layers "F.Cu" "F.Mask" "F.Paste")
			(net "SW_P12V_PVCCINFAON_CPU0_FLT")
		)
		(pad "2" smd circle
			(at 0.40005 0 180)
			(size 0 0)
			(layers "F.Cu" "F.Mask" "F.Paste")
			(net "GND")
		)
	)
	(footprint ""
		(layer "F.Cu")
		(at 280.278078 -417.2839 90)
		(property "Reference" "R4667"
			(at 0 0 90)
			(layer "F.SilkS")
			(hide yes)
			(effects
				(font
					(size 1.27 1.27)
				)
			)
		)
		(property "Value" ""
			(at 0 0 90)
			(layer "F.Fab")
			(effects
				(font
					(size 1.27 1.27)
				)
			)
		)
		(duplicate_pad_numbers_are_jumpers no)
		(fp_line
			(start 0.7874 -0.4064)
			(end 0.7874 0.4064)
			(stroke
				(width 0.1524)
				(type default)
			)
			(layer "F.SilkS")
		)
		(fp_line
			(start -0.7874 -0.4064)
			(end 0.7874 -0.4064)
			(stroke
				(width 0.1524)
				(type default)
			)
			(layer "F.SilkS")
		)
		(fp_line
			(start 0.7874 0.4064)
			(end -0.7874 0.4064)
			(stroke
				(width 0.1524)
				(type default)
			)
			(layer "F.SilkS")
		)
		(fp_line
			(start -0.7874 0.4064)
			(end -0.7874 -0.4064)
			(stroke
				(width 0.1524)
				(type default)
			)
			(layer "F.SilkS")
		)
		(fp_line
			(start -0.12065 -0.305054)
			(end -0.12065 -0.2794)
			(stroke
				(width 0.1)
				(type default)
			)
			(layer "F.Fab")
		)
		(fp_line
			(start -0.67945 -0.305054)
			(end -0.12065 -0.305054)
			(stroke
				(width 0.1)
				(type default)
			)
			(layer "F.Fab")
		)
		(fp_line
			(start 0.67945 -0.3048)
			(end 0.67945 0.3048)
			(stroke
				(width 0.1)
				(type default)
			)
			(layer "F.Fab")
		)
		(fp_line
			(start 0.12065 -0.3048)
			(end 0.67945 -0.3048)
			(stroke
				(width 0.1)
				(type default)
			)
			(layer "F.Fab")
		)
		(fp_line
			(start 0.12065 -0.2794)
			(end 0.12065 -0.3048)
			(stroke
				(width 0.1)
				(type default)
			)
			(layer "F.Fab")
		)
		(fp_line
			(start -0.12065 -0.2794)
			(end 0.12065 -0.2794)
			(stroke
				(width 0.1)
				(type default)
			)
			(layer "F.Fab")
		)
		(fp_line
			(start 0.120396 0.2794)
			(end -0.12065 0.2794)
			(stroke
				(width 0.1)
				(type default)
			)
			(layer "F.Fab")
		)
		(fp_line
			(start -0.12065 0.2794)
			(end -0.12065 0.3048)
			(stroke
				(width 0.1)
				(type default)
			)
			(layer "F.Fab")
		)
		(fp_line
			(start 0.67945 0.3048)
			(end 0.120396 0.3048)
			(stroke
				(width 0.1)
				(type default)
			)
			(layer "F.Fab")
		)
		(fp_line
			(start 0.120396 0.3048)
			(end 0.120396 0.2794)
			(stroke
				(width 0.1)
				(type default)
			)
			(layer "F.Fab")
		)
		(fp_line
			(start -0.12065 0.3048)
			(end -0.67945 0.3048)
			(stroke
				(width 0.1)
				(type default)
			)
			(layer "F.Fab")
		)
		(fp_line
			(start -0.67945 0.3048)
			(end -0.67945 -0.305054)
			(stroke
				(width 0.1)
				(type default)
			)
			(layer "F.Fab")
		)
		(pad "1" smd circle
			(at -0.40005 0 90)
			(size 0 0)
			(layers "F.Cu" "F.Mask" "F.Paste")
			(net "HSC_CSOUT")
		)
		(pad "2" smd circle
			(at 0.40005 0 90)
			(size 0 0)
			(layers "F.Cu" "F.Mask" "F.Paste")
			(net "A_HSC_LOW")
		)
	)
	(footprint ""
		(layer "F.Cu")
		(at 418.11194 -105.207308 180)
		(property "Reference" "PC2159"
			(at 0 0 180)
			(layer "F.SilkS")
			(hide yes)
			(effects
				(font
					(size 1.27 1.27)
				)
			)
		)
		(property "Value" ""
			(at 0 0 180)
			(layer "F.Fab")
			(effects
				(font
					(size 1.27 1.27)
				)
			)
		)
		(duplicate_pad_numbers_are_jumpers no)
		(fp_line
			(start 0.7874 0.4064)
			(end -0.7874 0.4064)
			(stroke
				(width 0.1524)
				(type default)
			)
			(layer "F.SilkS")
		)
		(fp_line
			(start 0.7874 -0.4064)
			(end 0.7874 0.4064)
			(stroke
				(width 0.1524)
				(type default)
			)
			(layer "F.SilkS")
		)
		(fp_line
			(start -0.7874 0.4064)
			(end -0.7874 -0.4064)
			(stroke
				(width 0.1524)
				(type default)
			)
			(layer "F.SilkS")
		)
		(fp_line
			(start -0.7874 -0.4064)
			(end 0.7874 -0.4064)
			(stroke
				(width 0.1524)
				(type default)
			)
			(layer "F.SilkS")
		)
		(fp_line
			(start 0.67945 0.3048)
			(end 0.120396 0.3048)
			(stroke
				(width 0.1)
				(type default)
			)
			(layer "F.Fab")
		)
		(fp_line
			(start 0.67945 -0.3048)
			(end 0.67945 0.3048)
			(stroke
				(width 0.1)
				(type default)
			)
			(layer "F.Fab")
		)
		(fp_line
			(start 0.12065 -0.2794)
			(end 0.12065 -0.3048)
			(stroke
				(width 0.1)
				(type default)
			)
			(layer "F.Fab")
		)
		(fp_line
			(start 0.12065 -0.3048)
			(end 0.67945 -0.3048)
			(stroke
				(width 0.1)
				(type default)
			)
			(layer "F.Fab")
		)
		(fp_line
			(start 0.120396 0.3048)
			(end 0.120396 0.2794)
			(stroke
				(width 0.1)
				(type default)
			)
			(layer "F.Fab")
		)
		(fp_line
			(start 0.120396 0.2794)
			(end -0.12065 0.2794)
			(stroke
				(width 0.1)
				(type default)
			)
			(layer "F.Fab")
		)
		(fp_line
			(start -0.12065 0.3048)
			(end -0.67945 0.3048)
			(stroke
				(width 0.1)
				(type default)
			)
			(layer "F.Fab")
		)
		(fp_line
			(start -0.12065 0.2794)
			(end -0.12065 0.3048)
			(stroke
				(width 0.1)
				(type default)
			)
			(layer "F.Fab")
		)
		(fp_line
			(start -0.12065 -0.2794)
			(end 0.12065 -0.2794)
			(stroke
				(width 0.1)
				(type default)
			)
			(layer "F.Fab")
		)
		(fp_line
			(start -0.12065 -0.305054)
			(end -0.12065 -0.2794)
			(stroke
				(width 0.1)
				(type default)
			)
			(layer "F.Fab")
		)
		(fp_line
			(start -0.67945 0.3048)
			(end -0.67945 -0.305054)
			(stroke
				(width 0.1)
				(type default)
			)
			(layer "F.Fab")
		)
		(fp_line
			(start -0.67945 -0.305054)
			(end -0.12065 -0.305054)
			(stroke
				(width 0.1)
				(type default)
			)
			(layer "F.Fab")
		)
		(pad "1" smd circle
			(at -0.40005 0 180)
			(size 0 0)
			(layers "F.Cu" "F.Mask" "F.Paste")
			(net "P3V3_AUX")
		)
		(pad "2" smd circle
			(at 0.40005 0 180)
			(size 0 0)
			(layers "F.Cu" "F.Mask" "F.Paste")
			(net "GND")
		)
	)
	(footprint ""
		(layer "F.Cu")
		(at 136.6266 -28.578048 180)
		(property "Reference" "R4281"
			(at 0 0 180)
			(layer "F.SilkS")
			(hide yes)
			(effects
				(font
					(size 1.27 1.27)
				)
			)
		)
		(property "Value" ""
			(at 0 0 180)
			(layer "F.Fab")
			(effects
				(font
					(size 1.27 1.27)
				)
			)
		)
		(duplicate_pad_numbers_are_jumpers no)
		(fp_line
			(start 0.7874 0.4064)
			(end -0.7874 0.4064)
			(stroke
				(width 0.1524)
				(type default)
			)
			(layer "F.SilkS")
		)
		(fp_line
			(start 0.7874 -0.4064)
			(end 0.7874 0.4064)
			(stroke
				(width 0.1524)
				(type default)
			)
			(layer "F.SilkS")
		)
		(fp_line
			(start -0.7874 0.4064)
			(end -0.7874 -0.4064)
			(stroke
				(width 0.1524)
				(type default)
			)
			(layer "F.SilkS")
		)
		(fp_line
			(start -0.7874 -0.4064)
			(end 0.7874 -0.4064)
			(stroke
				(width 0.1524)
				(type default)
			)
			(layer "F.SilkS")
		)
		(fp_line
			(start 0.67945 0.3048)
			(end 0.120396 0.3048)
			(stroke
				(width 0.1)
				(type default)
			)
			(layer "F.Fab")
		)
		(fp_line
			(start 0.67945 -0.3048)
			(end 0.67945 0.3048)
			(stroke
				(width 0.1)
				(type default)
			)
			(layer "F.Fab")
		)
		(fp_line
			(start 0.12065 -0.2794)
			(end 0.12065 -0.3048)
			(stroke
				(width 0.1)
				(type default)
			)
			(layer "F.Fab")
		)
		(fp_line
			(start 0.12065 -0.3048)
			(end 0.67945 -0.3048)
			(stroke
				(width 0.1)
				(type default)
			)
			(layer "F.Fab")
		)
		(fp_line
			(start 0.120396 0.3048)
			(end 0.120396 0.2794)
			(stroke
				(width 0.1)
				(type default)
			)
			(layer "F.Fab")
		)
		(fp_line
			(start 0.120396 0.2794)
			(end -0.12065 0.2794)
			(stroke
				(width 0.1)
				(type default)
			)
			(layer "F.Fab")
		)
		(fp_line
			(start -0.12065 0.3048)
			(end -0.67945 0.3048)
			(stroke
				(width 0.1)
				(type default)
			)
			(layer "F.Fab")
		)
		(fp_line
			(start -0.12065 0.2794)
			(end -0.12065 0.3048)
			(stroke
				(width 0.1)
				(type default)
			)
			(layer "F.Fab")
		)
		(fp_line
			(start -0.12065 -0.2794)
			(end 0.12065 -0.2794)
			(stroke
				(width 0.1)
				(type default)
			)
			(layer "F.Fab")
		)
		(fp_line
			(start -0.12065 -0.305054)
			(end -0.12065 -0.2794)
			(stroke
				(width 0.1)
				(type default)
			)
			(layer "F.Fab")
		)
		(fp_line
			(start -0.67945 0.3048)
			(end -0.67945 -0.305054)
			(stroke
				(width 0.1)
				(type default)
			)
			(layer "F.Fab")
		)
		(fp_line
			(start -0.67945 -0.305054)
			(end -0.12065 -0.305054)
			(stroke
				(width 0.1)
				(type default)
			)
			(layer "F.Fab")
		)
		(pad "1" smd circle
			(at -0.40005 0 180)
			(size 0 0)
			(layers "F.Cu" "F.Mask" "F.Paste")
			(net "P3V3_AUX")
		)
		(pad "2" smd circle
			(at 0.40005 0 180)
			(size 0 0)
			(layers "F.Cu" "F.Mask" "F.Paste")
			(net "FM_USB3_1_EQB")
		)
	)
	(footprint ""
		(layer "F.Cu")
		(at 162.34283 -76.770738)
		(property "Reference" "R2209"
			(at 0 0 0)
			(layer "F.SilkS")
			(hide yes)
			(effects
				(font
					(size 1.27 1.27)
				)
			)
		)
		(property "Value" ""
			(at 0 0 0)
			(layer "F.Fab")
			(effects
				(font
					(size 1.27 1.27)
				)
			)
		)
		(duplicate_pad_numbers_are_jumpers no)
		(fp_line
			(start -0.7874 -0.4064)
			(end 0.7874 -0.4064)
			(stroke
				(width 0.1524)
				(type default)
			)
			(layer "F.SilkS")
		)
		(fp_line
			(start -0.7874 0.4064)
			(end -0.7874 -0.4064)
			(stroke
				(width 0.1524)
				(type default)
			)
			(layer "F.SilkS")
		)
		(fp_line
			(start 0.7874 -0.4064)
			(end 0.7874 0.4064)
			(stroke
				(width 0.1524)
				(type default)
			)
			(layer "F.SilkS")
		)
		(fp_line
			(start 0.7874 0.4064)
			(end -0.7874 0.4064)
			(stroke
				(width 0.1524)
				(type default)
			)
			(layer "F.SilkS")
		)
		(fp_line
			(start -0.67945 -0.305054)
			(end -0.12065 -0.305054)
			(stroke
				(width 0.1)
				(type default)
			)
			(layer "F.Fab")
		)
		(fp_line
			(start -0.67945 0.3048)
			(end -0.67945 -0.305054)
			(stroke
				(width 0.1)
				(type default)
			)
			(layer "F.Fab")
		)
		(fp_line
			(start -0.12065 -0.305054)
			(end -0.12065 -0.2794)
			(stroke
				(width 0.1)
				(type default)
			)
			(layer "F.Fab")
		)
		(fp_line
			(start -0.12065 -0.2794)
			(end 0.12065 -0.2794)
			(stroke
				(width 0.1)
				(type default)
			)
			(layer "F.Fab")
		)
		(fp_line
			(start -0.12065 0.2794)
			(end -0.12065 0.3048)
			(stroke
				(width 0.1)
				(type default)
			)
			(layer "F.Fab")
		)
		(fp_line
			(start -0.12065 0.3048)
			(end -0.67945 0.3048)
			(stroke
				(width 0.1)
				(type default)
			)
			(layer "F.Fab")
		)
		(fp_line
			(start 0.120396 0.2794)
			(end -0.12065 0.2794)
			(stroke
				(width 0.1)
				(type default)
			)
			(layer "F.Fab")
		)
		(fp_line
			(start 0.120396 0.3048)
			(end 0.120396 0.2794)
			(stroke
				(width 0.1)
				(type default)
			)
			(layer "F.Fab")
		)
		(fp_line
			(start 0.12065 -0.3048)
			(end 0.67945 -0.3048)
			(stroke
				(width 0.1)
				(type default)
			)
			(layer "F.Fab")
		)
		(fp_line
			(start 0.12065 -0.2794)
			(end 0.12065 -0.3048)
			(stroke
				(width 0.1)
				(type default)
			)
			(layer "F.Fab")
		)
		(fp_line
			(start 0.67945 -0.3048)
			(end 0.67945 0.3048)
			(stroke
				(width 0.1)
				(type default)
			)
			(layer "F.Fab")
		)
		(fp_line
			(start 0.67945 0.3048)
			(end 0.120396 0.3048)
			(stroke
				(width 0.1)
				(type default)
			)
			(layer "F.Fab")
		)
		(pad "1" smd circle
			(at -0.40005 0)
			(size 0 0)
			(layers "F.Cu" "F.Mask" "F.Paste")
			(net "SMB_S3M_CPU0_3V3AUX_SCL_R")
		)
		(pad "2" smd circle
			(at 0.40005 0)
			(size 0 0)
			(layers "F.Cu" "F.Mask" "F.Paste")
			(net "SMB_S3M_CPU0_3V3AUX_SCL")
		)
	)
	(footprint ""
		(layer "F.Cu")
		(at 214.43188 -47.335948 90)
		(property "Reference" "R3588"
			(at 0 0 90)
			(layer "F.SilkS")
			(hide yes)
			(effects
				(font
					(size 1.27 1.27)
				)
			)
		)
		(property "Value" ""
			(at 0 0 90)
			(layer "F.Fab")
			(effects
				(font
					(size 1.27 1.27)
				)
			)
		)
		(duplicate_pad_numbers_are_jumpers no)
		(fp_line
			(start 0.7874 -0.4064)
			(end 0.7874 0.4064)
			(stroke
				(width 0.1524)
				(type default)
			)
			(layer "F.SilkS")
		)
		(fp_line
			(start -0.7874 -0.4064)
			(end 0.7874 -0.4064)
			(stroke
				(width 0.1524)
				(type default)
			)
			(layer "F.SilkS")
		)
		(fp_line
			(start 0.7874 0.4064)
			(end -0.7874 0.4064)
			(stroke
				(width 0.1524)
				(type default)
			)
			(layer "F.SilkS")
		)
		(fp_line
			(start -0.7874 0.4064)
			(end -0.7874 -0.4064)
			(stroke
				(width 0.1524)
				(type default)
			)
			(layer "F.SilkS")
		)
		(fp_line
			(start -0.12065 -0.305054)
			(end -0.12065 -0.2794)
			(stroke
				(width 0.1)
				(type default)
			)
			(layer "F.Fab")
		)
		(fp_line
			(start -0.67945 -0.305054)
			(end -0.12065 -0.305054)
			(stroke
				(width 0.1)
				(type default)
			)
			(layer "F.Fab")
		)
		(fp_line
			(start 0.67945 -0.3048)
			(end 0.67945 0.3048)
			(stroke
				(width 0.1)
				(type default)
			)
			(layer "F.Fab")
		)
		(fp_line
			(start 0.12065 -0.3048)
			(end 0.67945 -0.3048)
			(stroke
				(width 0.1)
				(type default)
			)
			(layer "F.Fab")
		)
		(fp_line
			(start 0.12065 -0.2794)
			(end 0.12065 -0.3048)
			(stroke
				(width 0.1)
				(type default)
			)
			(layer "F.Fab")
		)
		(fp_line
			(start -0.12065 -0.2794)
			(end 0.12065 -0.2794)
			(stroke
				(width 0.1)
				(type default)
			)
			(layer "F.Fab")
		)
		(fp_line
			(start 0.120396 0.2794)
			(end -0.12065 0.2794)
			(stroke
				(width 0.1)
				(type default)
			)
			(layer "F.Fab")
		)
		(fp_line
			(start -0.12065 0.2794)
			(end -0.12065 0.3048)
			(stroke
				(width 0.1)
				(type default)
			)
			(layer "F.Fab")
		)
		(fp_line
			(start 0.67945 0.3048)
			(end 0.120396 0.3048)
			(stroke
				(width 0.1)
				(type default)
			)
			(layer "F.Fab")
		)
		(fp_line
			(start 0.120396 0.3048)
			(end 0.120396 0.2794)
			(stroke
				(width 0.1)
				(type default)
			)
			(layer "F.Fab")
		)
		(fp_line
			(start -0.12065 0.3048)
			(end -0.67945 0.3048)
			(stroke
				(width 0.1)
				(type default)
			)
			(layer "F.Fab")
		)
		(fp_line
			(start -0.67945 0.3048)
			(end -0.67945 -0.305054)
			(stroke
				(width 0.1)
				(type default)
			)
			(layer "F.Fab")
		)
		(pad "1" smd circle
			(at -0.40005 0 90)
			(size 0 0)
			(layers "F.Cu" "F.Mask" "F.Paste")
			(net "SMB_INA230_3V3AUX_SCL")
		)
		(pad "2" smd circle
			(at 0.40005 0 90)
			(size 0 0)
			(layers "F.Cu" "F.Mask" "F.Paste")
			(net "SMB_INA230_2_3V3AUX_SCL_R")
		)
	)
	(footprint ""
		(layer "F.Cu")
		(at 309.519066 -43.92803 180)
		(property "Reference" "R1955"
			(at 0 0 180)
			(layer "F.SilkS")
			(hide yes)
			(effects
				(font
					(size 1.27 1.27)
				)
			)
		)
		(property "Value" ""
			(at 0 0 180)
			(layer "F.Fab")
			(effects
				(font
					(size 1.27 1.27)
				)
			)
		)
		(duplicate_pad_numbers_are_jumpers no)
		(fp_line
			(start 0.7874 0.4064)
			(end -0.7874 0.4064)
			(stroke
				(width 0.1524)
				(type default)
			)
			(layer "F.SilkS")
		)
		(fp_line
			(start 0.7874 -0.4064)
			(end 0.7874 0.4064)
			(stroke
				(width 0.1524)
				(type default)
			)
			(layer "F.SilkS")
		)
		(fp_line
			(start -0.7874 0.4064)
			(end -0.7874 -0.4064)
			(stroke
				(width 0.1524)
				(type default)
			)
			(layer "F.SilkS")
		)
		(fp_line
			(start -0.7874 -0.4064)
			(end 0.7874 -0.4064)
			(stroke
				(width 0.1524)
				(type default)
			)
			(layer "F.SilkS")
		)
		(fp_line
			(start 0.67945 0.3048)
			(end 0.120396 0.3048)
			(stroke
				(width 0.1)
				(type default)
			)
			(layer "F.Fab")
		)
		(fp_line
			(start 0.67945 -0.3048)
			(end 0.67945 0.3048)
			(stroke
				(width 0.1)
				(type default)
			)
			(layer "F.Fab")
		)
		(fp_line
			(start 0.12065 -0.2794)
			(end 0.12065 -0.3048)
			(stroke
				(width 0.1)
				(type default)
			)
			(layer "F.Fab")
		)
		(fp_line
			(start 0.12065 -0.3048)
			(end 0.67945 -0.3048)
			(stroke
				(width 0.1)
				(type default)
			)
			(layer "F.Fab")
		)
		(fp_line
			(start 0.120396 0.3048)
			(end 0.120396 0.2794)
			(stroke
				(width 0.1)
				(type default)
			)
			(layer "F.Fab")
		)
		(fp_line
			(start 0.120396 0.2794)
			(end -0.12065 0.2794)
			(stroke
				(width 0.1)
				(type default)
			)
			(layer "F.Fab")
		)
		(fp_line
			(start -0.12065 0.3048)
			(end -0.67945 0.3048)
			(stroke
				(width 0.1)
				(type default)
			)
			(layer "F.Fab")
		)
		(fp_line
			(start -0.12065 0.2794)
			(end -0.12065 0.3048)
			(stroke
				(width 0.1)
				(type default)
			)
			(layer "F.Fab")
		)
		(fp_line
			(start -0.12065 -0.2794)
			(end 0.12065 -0.2794)
			(stroke
				(width 0.1)
				(type default)
			)
			(layer "F.Fab")
		)
		(fp_line
			(start -0.12065 -0.305054)
			(end -0.12065 -0.2794)
			(stroke
				(width 0.1)
				(type default)
			)
			(layer "F.Fab")
		)
		(fp_line
			(start -0.67945 0.3048)
			(end -0.67945 -0.305054)
			(stroke
				(width 0.1)
				(type default)
			)
			(layer "F.Fab")
		)
		(fp_line
			(start -0.67945 -0.305054)
			(end -0.12065 -0.305054)
			(stroke
				(width 0.1)
				(type default)
			)
			(layer "F.Fab")
		)
		(pad "1" smd circle
			(at -0.40005 0 180)
			(size 0 0)
			(layers "F.Cu" "F.Mask" "F.Paste")
			(net "P3V3_AUX")
		)
		(pad "2" smd circle
			(at 0.40005 0 180)
			(size 0 0)
			(layers "F.Cu" "F.Mask" "F.Paste")
			(net "FM_PCHHOT_N")
		)
	)
	(footprint ""
		(layer "F.Cu")
		(at 179.352448 -403.271482 180)
		(property "Reference" "PC2187"
			(at 0 0 180)
			(layer "F.SilkS")
			(hide yes)
			(effects
				(font
					(size 1.27 1.27)
				)
			)
		)
		(property "Value" ""
			(at 0 0 180)
			(layer "F.Fab")
			(effects
				(font
					(size 1.27 1.27)
				)
			)
		)
		(duplicate_pad_numbers_are_jumpers no)
		(fp_line
			(start 0.7874 0.4064)
			(end -0.7874 0.4064)
			(stroke
				(width 0.1524)
				(type default)
			)
			(layer "F.SilkS")
		)
		(fp_line
			(start 0.7874 -0.4064)
			(end 0.7874 0.4064)
			(stroke
				(width 0.1524)
				(type default)
			)
			(layer "F.SilkS")
		)
		(fp_line
			(start -0.7874 0.4064)
			(end -0.7874 -0.4064)
			(stroke
				(width 0.1524)
				(type default)
			)
			(layer "F.SilkS")
		)
		(fp_line
			(start -0.7874 -0.4064)
			(end 0.7874 -0.4064)
			(stroke
				(width 0.1524)
				(type default)
			)
			(layer "F.SilkS")
		)
		(fp_line
			(start 0.67945 0.3048)
			(end 0.120396 0.3048)
			(stroke
				(width 0.1)
				(type default)
			)
			(layer "F.Fab")
		)
		(fp_line
			(start 0.67945 -0.3048)
			(end 0.67945 0.3048)
			(stroke
				(width 0.1)
				(type default)
			)
			(layer "F.Fab")
		)
		(fp_line
			(start 0.12065 -0.2794)
			(end 0.12065 -0.3048)
			(stroke
				(width 0.1)
				(type default)
			)
			(layer "F.Fab")
		)
		(fp_line
			(start 0.12065 -0.3048)
			(end 0.67945 -0.3048)
			(stroke
				(width 0.1)
				(type default)
			)
			(layer "F.Fab")
		)
		(fp_line
			(start 0.120396 0.3048)
			(end 0.120396 0.2794)
			(stroke
				(width 0.1)
				(type default)
			)
			(layer "F.Fab")
		)
		(fp_line
			(start 0.120396 0.2794)
			(end -0.12065 0.2794)
			(stroke
				(width 0.1)
				(type default)
			)
			(layer "F.Fab")
		)
		(fp_line
			(start -0.12065 0.3048)
			(end -0.67945 0.3048)
			(stroke
				(width 0.1)
				(type default)
			)
			(layer "F.Fab")
		)
		(fp_line
			(start -0.12065 0.2794)
			(end -0.12065 0.3048)
			(stroke
				(width 0.1)
				(type default)
			)
			(layer "F.Fab")
		)
		(fp_line
			(start -0.12065 -0.2794)
			(end 0.12065 -0.2794)
			(stroke
				(width 0.1)
				(type default)
			)
			(layer "F.Fab")
		)
		(fp_line
			(start -0.12065 -0.305054)
			(end -0.12065 -0.2794)
			(stroke
				(width 0.1)
				(type default)
			)
			(layer "F.Fab")
		)
		(fp_line
			(start -0.67945 0.3048)
			(end -0.67945 -0.305054)
			(stroke
				(width 0.1)
				(type default)
			)
			(layer "F.Fab")
		)
		(fp_line
			(start -0.67945 -0.305054)
			(end -0.12065 -0.305054)
			(stroke
				(width 0.1)
				(type default)
			)
			(layer "F.Fab")
		)
		(pad "1" smd circle
			(at -0.40005 0 180)
			(size 0 0)
			(layers "F.Cu" "F.Mask" "F.Paste")
			(net "HSC_VDD_R")
		)
		(pad "2" smd circle
			(at 0.40005 0 180)
			(size 0 0)
			(layers "F.Cu" "F.Mask" "F.Paste")
			(net "AGND_HSC")
		)
	)
	(footprint ""
		(layer "F.Cu")
		(at 203.326492 -101.606604 -90)
		(property "Reference" "R1839"
			(at 0 0 270)
			(layer "F.SilkS")
			(hide yes)
			(effects
				(font
					(size 1.27 1.27)
				)
			)
		)
		(property "Value" ""
			(at 0 0 270)
			(layer "F.Fab")
			(effects
				(font
					(size 1.27 1.27)
				)
			)
		)
		(duplicate_pad_numbers_are_jumpers no)
		(fp_line
			(start -0.7874 0.4064)
			(end -0.7874 -0.4064)
			(stroke
				(width 0.1524)
				(type default)
			)
			(layer "F.SilkS")
		)
		(fp_line
			(start 0.7874 0.4064)
			(end -0.7874 0.4064)
			(stroke
				(width 0.1524)
				(type default)
			)
			(layer "F.SilkS")
		)
		(fp_line
			(start -0.7874 -0.4064)
			(end 0.7874 -0.4064)
			(stroke
				(width 0.1524)
				(type default)
			)
			(layer "F.SilkS")
		)
		(fp_line
			(start 0.7874 -0.4064)
			(end 0.7874 0.4064)
			(stroke
				(width 0.1524)
				(type default)
			)
			(layer "F.SilkS")
		)
		(fp_line
			(start -0.67945 0.3048)
			(end -0.67945 -0.305054)
			(stroke
				(width 0.1)
				(type default)
			)
			(layer "F.Fab")
		)
		(fp_line
			(start -0.12065 0.3048)
			(end -0.67945 0.3048)
			(stroke
				(width 0.1)
				(type default)
			)
			(layer "F.Fab")
		)
		(fp_line
			(start 0.120396 0.3048)
			(end 0.120396 0.2794)
			(stroke
				(width 0.1)
				(type default)
			)
			(layer "F.Fab")
		)
		(fp_line
			(start 0.67945 0.3048)
			(end 0.120396 0.3048)
			(stroke
				(width 0.1)
				(type default)
			)
			(layer "F.Fab")
		)
		(fp_line
			(start -0.12065 0.2794)
			(end -0.12065 0.3048)
			(stroke
				(width 0.1)
				(type default)
			)
			(layer "F.Fab")
		)
		(fp_line
			(start 0.120396 0.2794)
			(end -0.12065 0.2794)
			(stroke
				(width 0.1)
				(type default)
			)
			(layer "F.Fab")
		)
		(fp_line
			(start -0.12065 -0.2794)
			(end 0.12065 -0.2794)
			(stroke
				(width 0.1)
				(type default)
			)
			(layer "F.Fab")
		)
		(fp_line
			(start 0.12065 -0.2794)
			(end 0.12065 -0.3048)
			(stroke
				(width 0.1)
				(type default)
			)
			(layer "F.Fab")
		)
		(fp_line
			(start 0.12065 -0.3048)
			(end 0.67945 -0.3048)
			(stroke
				(width 0.1)
				(type default)
			)
			(layer "F.Fab")
		)
		(fp_line
			(start 0.67945 -0.3048)
			(end 0.67945 0.3048)
			(stroke
				(width 0.1)
				(type default)
			)
			(layer "F.Fab")
		)
		(fp_line
			(start -0.67945 -0.305054)
			(end -0.12065 -0.305054)
			(stroke
				(width 0.1)
				(type default)
			)
			(layer "F.Fab")
		)
		(fp_line
			(start -0.12065 -0.305054)
			(end -0.12065 -0.2794)
			(stroke
				(width 0.1)
				(type default)
			)
			(layer "F.Fab")
		)
		(pad "1" smd circle
			(at -0.40005 0 270)
			(size 0 0)
			(layers "F.Cu" "F.Mask" "F.Paste")
			(net "RST_PFR_OVR_RTC")
		)
		(pad "2" smd circle
			(at 0.40005 0 270)
			(size 0 0)
			(layers "F.Cu" "F.Mask" "F.Paste")
			(net "RST_RTCRST_N")
		)
	)
	(footprint ""
		(layer "F.Cu")
		(at 22.13356 -165.751256)
		(property "Reference" "R2578"
			(at 0 0 0)
			(layer "F.SilkS")
			(hide yes)
			(effects
				(font
					(size 1.27 1.27)
				)
			)
		)
		(property "Value" ""
			(at 0 0 0)
			(layer "F.Fab")
			(effects
				(font
					(size 1.27 1.27)
				)
			)
		)
		(duplicate_pad_numbers_are_jumpers no)
		(fp_line
			(start -0.7874 -0.4064)
			(end 0.7874 -0.4064)
			(stroke
				(width 0.1524)
				(type default)
			)
			(layer "F.SilkS")
		)
		(fp_line
			(start -0.7874 0.4064)
			(end -0.7874 -0.4064)
			(stroke
				(width 0.1524)
				(type default)
			)
			(layer "F.SilkS")
		)
		(fp_line
			(start 0.7874 -0.4064)
			(end 0.7874 0.4064)
			(stroke
				(width 0.1524)
				(type default)
			)
			(layer "F.SilkS")
		)
		(fp_line
			(start 0.7874 0.4064)
			(end -0.7874 0.4064)
			(stroke
				(width 0.1524)
				(type default)
			)
			(layer "F.SilkS")
		)
		(fp_line
			(start -0.67945 -0.305054)
			(end -0.12065 -0.305054)
			(stroke
				(width 0.1)
				(type default)
			)
			(layer "F.Fab")
		)
		(fp_line
			(start -0.67945 0.3048)
			(end -0.67945 -0.305054)
			(stroke
				(width 0.1)
				(type default)
			)
			(layer "F.Fab")
		)
		(fp_line
			(start -0.12065 -0.305054)
			(end -0.12065 -0.2794)
			(stroke
				(width 0.1)
				(type default)
			)
			(layer "F.Fab")
		)
		(fp_line
			(start -0.12065 -0.2794)
			(end 0.12065 -0.2794)
			(stroke
				(width 0.1)
				(type default)
			)
			(layer "F.Fab")
		)
		(fp_line
			(start -0.12065 0.2794)
			(end -0.12065 0.3048)
			(stroke
				(width 0.1)
				(type default)
			)
			(layer "F.Fab")
		)
		(fp_line
			(start -0.12065 0.3048)
			(end -0.67945 0.3048)
			(stroke
				(width 0.1)
				(type default)
			)
			(layer "F.Fab")
		)
		(fp_line
			(start 0.120396 0.2794)
			(end -0.12065 0.2794)
			(stroke
				(width 0.1)
				(type default)
			)
			(layer "F.Fab")
		)
		(fp_line
			(start 0.120396 0.3048)
			(end 0.120396 0.2794)
			(stroke
				(width 0.1)
				(type default)
			)
			(layer "F.Fab")
		)
		(fp_line
			(start 0.12065 -0.3048)
			(end 0.67945 -0.3048)
			(stroke
				(width 0.1)
				(type default)
			)
			(layer "F.Fab")
		)
		(fp_line
			(start 0.12065 -0.2794)
			(end 0.12065 -0.3048)
			(stroke
				(width 0.1)
				(type default)
			)
			(layer "F.Fab")
		)
		(fp_line
			(start 0.67945 -0.3048)
			(end 0.67945 0.3048)
			(stroke
				(width 0.1)
				(type default)
			)
			(layer "F.Fab")
		)
		(fp_line
			(start 0.67945 0.3048)
			(end 0.120396 0.3048)
			(stroke
				(width 0.1)
				(type default)
			)
			(layer "F.Fab")
		)
		(pad "1" smd circle
			(at -0.40005 0)
			(size 0 0)
			(layers "F.Cu" "F.Mask" "F.Paste")
			(net "SVID_CLK1_CPU1_R")
		)
		(pad "2" smd circle
			(at 0.40005 0)
			(size 0 0)
			(layers "F.Cu" "F.Mask" "F.Paste")
			(net "SVID_CLK_PVCCD_HV_CPU1_R")
		)
	)
	(footprint ""
		(layer "F.Cu")
		(at 220.190822 -57.851802 180)
		(property "Reference" "R3758"
			(at 0 0 180)
			(layer "F.SilkS")
			(hide yes)
			(effects
				(font
					(size 1.27 1.27)
				)
			)
		)
		(property "Value" ""
			(at 0 0 180)
			(layer "F.Fab")
			(effects
				(font
					(size 1.27 1.27)
				)
			)
		)
		(duplicate_pad_numbers_are_jumpers no)
		(fp_line
			(start 0.7874 0.4064)
			(end -0.7874 0.4064)
			(stroke
				(width 0.1524)
				(type default)
			)
			(layer "F.SilkS")
		)
		(fp_line
			(start 0.7874 -0.4064)
			(end 0.7874 0.4064)
			(stroke
				(width 0.1524)
				(type default)
			)
			(layer "F.SilkS")
		)
		(fp_line
			(start -0.7874 0.4064)
			(end -0.7874 -0.4064)
			(stroke
				(width 0.1524)
				(type default)
			)
			(layer "F.SilkS")
		)
		(fp_line
			(start -0.7874 -0.4064)
			(end 0.7874 -0.4064)
			(stroke
				(width 0.1524)
				(type default)
			)
			(layer "F.SilkS")
		)
		(fp_line
			(start 0.67945 0.3048)
			(end 0.120396 0.3048)
			(stroke
				(width 0.1)
				(type default)
			)
			(layer "F.Fab")
		)
		(fp_line
			(start 0.67945 -0.3048)
			(end 0.67945 0.3048)
			(stroke
				(width 0.1)
				(type default)
			)
			(layer "F.Fab")
		)
		(fp_line
			(start 0.12065 -0.2794)
			(end 0.12065 -0.3048)
			(stroke
				(width 0.1)
				(type default)
			)
			(layer "F.Fab")
		)
		(fp_line
			(start 0.12065 -0.3048)
			(end 0.67945 -0.3048)
			(stroke
				(width 0.1)
				(type default)
			)
			(layer "F.Fab")
		)
		(fp_line
			(start 0.120396 0.3048)
			(end 0.120396 0.2794)
			(stroke
				(width 0.1)
				(type default)
			)
			(layer "F.Fab")
		)
		(fp_line
			(start 0.120396 0.2794)
			(end -0.12065 0.2794)
			(stroke
				(width 0.1)
				(type default)
			)
			(layer "F.Fab")
		)
		(fp_line
			(start -0.12065 0.3048)
			(end -0.67945 0.3048)
			(stroke
				(width 0.1)
				(type default)
			)
			(layer "F.Fab")
		)
		(fp_line
			(start -0.12065 0.2794)
			(end -0.12065 0.3048)
			(stroke
				(width 0.1)
				(type default)
			)
			(layer "F.Fab")
		)
		(fp_line
			(start -0.12065 -0.2794)
			(end 0.12065 -0.2794)
			(stroke
				(width 0.1)
				(type default)
			)
			(layer "F.Fab")
		)
		(fp_line
			(start -0.12065 -0.305054)
			(end -0.12065 -0.2794)
			(stroke
				(width 0.1)
				(type default)
			)
			(layer "F.Fab")
		)
		(fp_line
			(start -0.67945 0.3048)
			(end -0.67945 -0.305054)
			(stroke
				(width 0.1)
				(type default)
			)
			(layer "F.Fab")
		)
		(fp_line
			(start -0.67945 -0.305054)
			(end -0.12065 -0.305054)
			(stroke
				(width 0.1)
				(type default)
			)
			(layer "F.Fab")
		)
		(pad "1" smd circle
			(at -0.40005 0 180)
			(size 0 0)
			(layers "F.Cu" "F.Mask" "F.Paste")
			(net "P3V3_E1S_0_R")
		)
		(pad "2" smd circle
			(at 0.40005 0 180)
			(size 0 0)
			(layers "F.Cu" "F.Mask" "F.Paste")
			(net "VSENSE_P3V3_INA230_2_INP")
		)
	)
	(footprint ""
		(layer "F.Cu")
		(at 157.988 -22.824948 90)
		(property "Reference" "R1752"
			(at 0 0 90)
			(layer "F.SilkS")
			(hide yes)
			(effects
				(font
					(size 1.27 1.27)
				)
			)
		)
		(property "Value" ""
			(at 0 0 90)
			(layer "F.Fab")
			(effects
				(font
					(size 1.27 1.27)
				)
			)
		)
		(duplicate_pad_numbers_are_jumpers no)
		(fp_line
			(start 0.7874 -0.4064)
			(end 0.7874 0.4064)
			(stroke
				(width 0.1524)
				(type default)
			)
			(layer "F.SilkS")
		)
		(fp_line
			(start -0.7874 -0.4064)
			(end 0.7874 -0.4064)
			(stroke
				(width 0.1524)
				(type default)
			)
			(layer "F.SilkS")
		)
		(fp_line
			(start 0.7874 0.4064)
			(end -0.7874 0.4064)
			(stroke
				(width 0.1524)
				(type default)
			)
			(layer "F.SilkS")
		)
		(fp_line
			(start -0.7874 0.4064)
			(end -0.7874 -0.4064)
			(stroke
				(width 0.1524)
				(type default)
			)
			(layer "F.SilkS")
		)
		(fp_line
			(start -0.12065 -0.305054)
			(end -0.12065 -0.2794)
			(stroke
				(width 0.1)
				(type default)
			)
			(layer "F.Fab")
		)
		(fp_line
			(start -0.67945 -0.305054)
			(end -0.12065 -0.305054)
			(stroke
				(width 0.1)
				(type default)
			)
			(layer "F.Fab")
		)
		(fp_line
			(start 0.67945 -0.3048)
			(end 0.67945 0.3048)
			(stroke
				(width 0.1)
				(type default)
			)
			(layer "F.Fab")
		)
		(fp_line
			(start 0.12065 -0.3048)
			(end 0.67945 -0.3048)
			(stroke
				(width 0.1)
				(type default)
			)
			(layer "F.Fab")
		)
		(fp_line
			(start 0.12065 -0.2794)
			(end 0.12065 -0.3048)
			(stroke
				(width 0.1)
				(type default)
			)
			(layer "F.Fab")
		)
		(fp_line
			(start -0.12065 -0.2794)
			(end 0.12065 -0.2794)
			(stroke
				(width 0.1)
				(type default)
			)
			(layer "F.Fab")
		)
		(fp_line
			(start 0.120396 0.2794)
			(end -0.12065 0.2794)
			(stroke
				(width 0.1)
				(type default)
			)
			(layer "F.Fab")
		)
		(fp_line
			(start -0.12065 0.2794)
			(end -0.12065 0.3048)
			(stroke
				(width 0.1)
				(type default)
			)
			(layer "F.Fab")
		)
		(fp_line
			(start 0.67945 0.3048)
			(end 0.120396 0.3048)
			(stroke
				(width 0.1)
				(type default)
			)
			(layer "F.Fab")
		)
		(fp_line
			(start 0.120396 0.3048)
			(end 0.120396 0.2794)
			(stroke
				(width 0.1)
				(type default)
			)
			(layer "F.Fab")
		)
		(fp_line
			(start -0.12065 0.3048)
			(end -0.67945 0.3048)
			(stroke
				(width 0.1)
				(type default)
			)
			(layer "F.Fab")
		)
		(fp_line
			(start -0.67945 0.3048)
			(end -0.67945 -0.305054)
			(stroke
				(width 0.1)
				(type default)
			)
			(layer "F.Fab")
		)
		(pad "1" smd circle
			(at -0.40005 0 90)
			(size 0 0)
			(layers "F.Cu" "F.Mask" "F.Paste")
			(net "SGPIO_CLK_0")
		)
		(pad "2" smd circle
			(at 0.40005 0 90)
			(size 0 0)
			(layers "F.Cu" "F.Mask" "F.Paste")
			(net "SGPIO_DEBUG_PLD_CLK")
		)
	)
	(footprint ""
		(layer "F.Cu")
		(at 355.247448 -249.320304 -90)
		(property "Reference" "C967"
			(at 0 0 270)
			(layer "F.SilkS")
			(hide yes)
			(effects
				(font
					(size 1.27 1.27)
				)
			)
		)
		(property "Value" ""
			(at 0 0 270)
			(layer "F.Fab")
			(effects
				(font
					(size 1.27 1.27)
				)
			)
		)
		(duplicate_pad_numbers_are_jumpers no)
		(fp_line
			(start -0.7874 0.4064)
			(end -0.7874 -0.4064)
			(stroke
				(width 0.1524)
				(type default)
			)
			(layer "F.SilkS")
		)
		(fp_line
			(start 0.7874 0.4064)
			(end -0.7874 0.4064)
			(stroke
				(width 0.1524)
				(type default)
			)
			(layer "F.SilkS")
		)
		(fp_line
			(start -0.7874 -0.4064)
			(end 0.7874 -0.4064)
			(stroke
				(width 0.1524)
				(type default)
			)
			(layer "F.SilkS")
		)
		(fp_line
			(start 0.7874 -0.4064)
			(end 0.7874 0.4064)
			(stroke
				(width 0.1524)
				(type default)
			)
			(layer "F.SilkS")
		)
		(fp_line
			(start -0.67945 0.3048)
			(end -0.67945 -0.305054)
			(stroke
				(width 0.1)
				(type default)
			)
			(layer "F.Fab")
		)
		(fp_line
			(start -0.12065 0.3048)
			(end -0.67945 0.3048)
			(stroke
				(width 0.1)
				(type default)
			)
			(layer "F.Fab")
		)
		(fp_line
			(start 0.120396 0.3048)
			(end 0.120396 0.2794)
			(stroke
				(width 0.1)
				(type default)
			)
			(layer "F.Fab")
		)
		(fp_line
			(start 0.67945 0.3048)
			(end 0.120396 0.3048)
			(stroke
				(width 0.1)
				(type default)
			)
			(layer "F.Fab")
		)
		(fp_line
			(start -0.12065 0.2794)
			(end -0.12065 0.3048)
			(stroke
				(width 0.1)
				(type default)
			)
			(layer "F.Fab")
		)
		(fp_line
			(start 0.120396 0.2794)
			(end -0.12065 0.2794)
			(stroke
				(width 0.1)
				(type default)
			)
			(layer "F.Fab")
		)
		(fp_line
			(start -0.12065 -0.2794)
			(end 0.12065 -0.2794)
			(stroke
				(width 0.1)
				(type default)
			)
			(layer "F.Fab")
		)
		(fp_line
			(start 0.12065 -0.2794)
			(end 0.12065 -0.3048)
			(stroke
				(width 0.1)
				(type default)
			)
			(layer "F.Fab")
		)
		(fp_line
			(start 0.12065 -0.3048)
			(end 0.67945 -0.3048)
			(stroke
				(width 0.1)
				(type default)
			)
			(layer "F.Fab")
		)
		(fp_line
			(start 0.67945 -0.3048)
			(end 0.67945 0.3048)
			(stroke
				(width 0.1)
				(type default)
			)
			(layer "F.Fab")
		)
		(fp_line
			(start -0.67945 -0.305054)
			(end -0.12065 -0.305054)
			(stroke
				(width 0.1)
				(type default)
			)
			(layer "F.Fab")
		)
		(fp_line
			(start -0.12065 -0.305054)
			(end -0.12065 -0.2794)
			(stroke
				(width 0.1)
				(type default)
			)
			(layer "F.Fab")
		)
		(pad "1" smd circle
			(at -0.40005 0 270)
			(size 0 0)
			(layers "F.Cu" "F.Mask" "F.Paste")
			(net "PVCCIN_CPU0")
		)
		(pad "2" smd circle
			(at 0.40005 0 270)
			(size 0 0)
			(layers "F.Cu" "F.Mask" "F.Paste")
			(net "GND")
		)
	)
	(footprint ""
		(layer "F.Cu")
		(at 250.733306 -108.192824 90)
		(property "Reference" "R1010"
			(at 0 0 90)
			(layer "F.SilkS")
			(hide yes)
			(effects
				(font
					(size 1.27 1.27)
				)
			)
		)
		(property "Value" ""
			(at 0 0 90)
			(layer "F.Fab")
			(effects
				(font
					(size 1.27 1.27)
				)
			)
		)
		(duplicate_pad_numbers_are_jumpers no)
		(fp_line
			(start 0.7874 -0.4064)
			(end 0.7874 0.4064)
			(stroke
				(width 0.1524)
				(type default)
			)
			(layer "F.SilkS")
		)
		(fp_line
			(start -0.7874 -0.4064)
			(end 0.7874 -0.4064)
			(stroke
				(width 0.1524)
				(type default)
			)
			(layer "F.SilkS")
		)
		(fp_line
			(start 0.7874 0.4064)
			(end -0.7874 0.4064)
			(stroke
				(width 0.1524)
				(type default)
			)
			(layer "F.SilkS")
		)
		(fp_line
			(start -0.7874 0.4064)
			(end -0.7874 -0.4064)
			(stroke
				(width 0.1524)
				(type default)
			)
			(layer "F.SilkS")
		)
		(fp_line
			(start -0.12065 -0.305054)
			(end -0.12065 -0.2794)
			(stroke
				(width 0.1)
				(type default)
			)
			(layer "F.Fab")
		)
		(fp_line
			(start -0.67945 -0.305054)
			(end -0.12065 -0.305054)
			(stroke
				(width 0.1)
				(type default)
			)
			(layer "F.Fab")
		)
		(fp_line
			(start 0.67945 -0.3048)
			(end 0.67945 0.3048)
			(stroke
				(width 0.1)
				(type default)
			)
			(layer "F.Fab")
		)
		(fp_line
			(start 0.12065 -0.3048)
			(end 0.67945 -0.3048)
			(stroke
				(width 0.1)
				(type default)
			)
			(layer "F.Fab")
		)
		(fp_line
			(start 0.12065 -0.2794)
			(end 0.12065 -0.3048)
			(stroke
				(width 0.1)
				(type default)
			)
			(layer "F.Fab")
		)
		(fp_line
			(start -0.12065 -0.2794)
			(end 0.12065 -0.2794)
			(stroke
				(width 0.1)
				(type default)
			)
			(layer "F.Fab")
		)
		(fp_line
			(start 0.120396 0.2794)
			(end -0.12065 0.2794)
			(stroke
				(width 0.1)
				(type default)
			)
			(layer "F.Fab")
		)
		(fp_line
			(start -0.12065 0.2794)
			(end -0.12065 0.3048)
			(stroke
				(width 0.1)
				(type default)
			)
			(layer "F.Fab")
		)
		(fp_line
			(start 0.67945 0.3048)
			(end 0.120396 0.3048)
			(stroke
				(width 0.1)
				(type default)
			)
			(layer "F.Fab")
		)
		(fp_line
			(start 0.120396 0.3048)
			(end 0.120396 0.2794)
			(stroke
				(width 0.1)
				(type default)
			)
			(layer "F.Fab")
		)
		(fp_line
			(start -0.12065 0.3048)
			(end -0.67945 0.3048)
			(stroke
				(width 0.1)
				(type default)
			)
			(layer "F.Fab")
		)
		(fp_line
			(start -0.67945 0.3048)
			(end -0.67945 -0.305054)
			(stroke
				(width 0.1)
				(type default)
			)
			(layer "F.Fab")
		)
		(pad "1" smd circle
			(at -0.40005 0 90)
			(size 0 0)
			(layers "F.Cu" "F.Mask" "F.Paste")
			(net "CLK_25M_CK440_ISCLK_REF_DP")
		)
		(pad "2" smd circle
			(at 0.40005 0 90)
			(size 0 0)
			(layers "F.Cu" "F.Mask" "F.Paste")
			(net "CLK_25M_PCH_REF_NS_DP")
		)
	)
	(footprint ""
		(layer "F.Cu")
		(at 242.92179 -249.281442 180)
		(property "Reference" "Y3"
			(at -0.22225 -3.369564 0)
			(unlocked yes)
			(layer "F.SilkS")
			(effects
				(font
					(size 0.7874 0.5842)
					(thickness 0.1524)
				)
				(justify left)
			)
		)
		(property "Value" ""
			(at 0 0 180)
			(layer "F.Fab")
			(effects
				(font
					(size 1.27 1.27)
				)
			)
		)
		(duplicate_pad_numbers_are_jumpers no)
		(fp_line
			(start 1.538732 1.937004)
			(end -1.538732 1.937004)
			(stroke
				(width 0.1524)
				(type default)
			)
			(layer "F.SilkS")
		)
		(fp_line
			(start 1.538732 -1.937004)
			(end 1.538732 1.937004)
			(stroke
				(width 0.1524)
				(type default)
			)
			(layer "F.SilkS")
		)
		(fp_line
			(start -1.538732 1.937004)
			(end -1.538732 -1.937004)
			(stroke
				(width 0.1524)
				(type default)
			)
			(layer "F.SilkS")
		)
		(fp_line
			(start -1.538732 -1.937004)
			(end 1.538732 -1.937004)
			(stroke
				(width 0.1524)
				(type default)
			)
			(layer "F.SilkS")
		)
		(fp_poly
			(pts
				(xy -1.724406 -1.059942) (xy -2.5908 -0.626872) (xy -2.5908 -1.493266)
			)
			(stroke
				(width 0)
				(type default)
			)
			(fill yes)
			(layer "F.SilkS")
		)
		(fp_line
			(start 1.299972 1.649984)
			(end -1.299972 1.649984)
			(stroke
				(width 0.1)
				(type default)
			)
			(layer "F.Fab")
		)
		(fp_line
			(start 1.299972 -1.649984)
			(end 1.299972 1.649984)
			(stroke
				(width 0.1)
				(type default)
			)
			(layer "F.Fab")
		)
		(fp_line
			(start -1.299972 1.649984)
			(end -1.299972 -1.649984)
			(stroke
				(width 0.1)
				(type default)
			)
			(layer "F.Fab")
		)
		(fp_line
			(start -1.299972 -1.649984)
			(end 1.299972 -1.649984)
			(stroke
				(width 0.1)
				(type default)
			)
			(layer "F.Fab")
		)
		(fp_poly
			(pts
				(xy -2.5908 -0.626872) (xy -2.5908 -1.493266) (xy -1.724406 -1.059942)
			)
			(stroke
				(width 0)
				(type default)
			)
			(fill yes)
			(layer "F.Fab")
		)
		(pad "1" smd rect
			(at -0.8001 -1.059942 180)
			(size 1.2192 1.4986)
			(layers "F.Cu" "F.Mask" "F.Paste")
			(net "CLK_GEN2_XTAL_IN_R")
		)
		(pad "2" smd rect
			(at -0.8001 1.059942 180)
			(size 1.2192 1.4986)
			(layers "F.Cu" "F.Mask" "F.Paste")
			(net "GND")
		)
		(pad "3" smd rect
			(at 0.8001 1.059942 180)
			(size 1.2192 1.4986)
			(layers "F.Cu" "F.Mask" "F.Paste")
			(net "CLK_GEN2_XTAL_OUT")
		)
		(pad "4" smd rect
			(at 0.8001 -1.059942 180)
			(size 1.2192 1.4986)
			(layers "F.Cu" "F.Mask" "F.Paste")
			(net "GND")
		)
	)
	(footprint ""
		(layer "F.Cu")
		(at 312.443622 -42.713148)
		(property "Reference" "R380"
			(at 0 0 0)
			(layer "F.SilkS")
			(hide yes)
			(effects
				(font
					(size 1.27 1.27)
				)
			)
		)
		(property "Value" ""
			(at 0 0 0)
			(layer "F.Fab")
			(effects
				(font
					(size 1.27 1.27)
				)
			)
		)
		(duplicate_pad_numbers_are_jumpers no)
		(fp_line
			(start -0.7874 -0.4064)
			(end 0.7874 -0.4064)
			(stroke
				(width 0.1524)
				(type default)
			)
			(layer "F.SilkS")
		)
		(fp_line
			(start -0.7874 0.4064)
			(end -0.7874 -0.4064)
			(stroke
				(width 0.1524)
				(type default)
			)
			(layer "F.SilkS")
		)
		(fp_line
			(start 0.7874 -0.4064)
			(end 0.7874 0.4064)
			(stroke
				(width 0.1524)
				(type default)
			)
			(layer "F.SilkS")
		)
		(fp_line
			(start 0.7874 0.4064)
			(end -0.7874 0.4064)
			(stroke
				(width 0.1524)
				(type default)
			)
			(layer "F.SilkS")
		)
		(fp_line
			(start -0.67945 -0.305054)
			(end -0.12065 -0.305054)
			(stroke
				(width 0.1)
				(type default)
			)
			(layer "F.Fab")
		)
		(fp_line
			(start -0.67945 0.3048)
			(end -0.67945 -0.305054)
			(stroke
				(width 0.1)
				(type default)
			)
			(layer "F.Fab")
		)
		(fp_line
			(start -0.12065 -0.305054)
			(end -0.12065 -0.2794)
			(stroke
				(width 0.1)
				(type default)
			)
			(layer "F.Fab")
		)
		(fp_line
			(start -0.12065 -0.2794)
			(end 0.12065 -0.2794)
			(stroke
				(width 0.1)
				(type default)
			)
			(layer "F.Fab")
		)
		(fp_line
			(start -0.12065 0.2794)
			(end -0.12065 0.3048)
			(stroke
				(width 0.1)
				(type default)
			)
			(layer "F.Fab")
		)
		(fp_line
			(start -0.12065 0.3048)
			(end -0.67945 0.3048)
			(stroke
				(width 0.1)
				(type default)
			)
			(layer "F.Fab")
		)
		(fp_line
			(start 0.120396 0.2794)
			(end -0.12065 0.2794)
			(stroke
				(width 0.1)
				(type default)
			)
			(layer "F.Fab")
		)
		(fp_line
			(start 0.120396 0.3048)
			(end 0.120396 0.2794)
			(stroke
				(width 0.1)
				(type default)
			)
			(layer "F.Fab")
		)
		(fp_line
			(start 0.12065 -0.3048)
			(end 0.67945 -0.3048)
			(stroke
				(width 0.1)
				(type default)
			)
			(layer "F.Fab")
		)
		(fp_line
			(start 0.12065 -0.2794)
			(end 0.12065 -0.3048)
			(stroke
				(width 0.1)
				(type default)
			)
			(layer "F.Fab")
		)
		(fp_line
			(start 0.67945 -0.3048)
			(end 0.67945 0.3048)
			(stroke
				(width 0.1)
				(type default)
			)
			(layer "F.Fab")
		)
		(fp_line
			(start 0.67945 0.3048)
			(end 0.120396 0.3048)
			(stroke
				(width 0.1)
				(type default)
			)
			(layer "F.Fab")
		)
		(pad "1" smd circle
			(at -0.40005 0)
			(size 0 0)
			(layers "F.Cu" "F.Mask" "F.Paste")
			(net "P3V3_AUX")
		)
		(pad "2" smd circle
			(at 0.40005 0)
			(size 0 0)
			(layers "F.Cu" "F.Mask" "F.Paste")
			(net "FM_FLASH_SECURITY_STRAP")
		)
	)
	(footprint ""
		(layer "F.Cu")
		(at 108.56722 -296.05478)
		(property "Reference" "C260"
			(at 0 0 0)
			(layer "F.SilkS")
			(hide yes)
			(effects
				(font
					(size 1.27 1.27)
				)
			)
		)
		(property "Value" ""
			(at 0 0 0)
			(layer "F.Fab")
			(effects
				(font
					(size 1.27 1.27)
				)
			)
		)
		(duplicate_pad_numbers_are_jumpers no)
		(fp_line
			(start -1.524 -0.762)
			(end 1.524 -0.762)
			(stroke
				(width 0.1524)
				(type default)
			)
			(layer "F.SilkS")
		)
		(fp_line
			(start -1.524 0.762)
			(end -1.524 -0.762)
			(stroke
				(width 0.1524)
				(type default)
			)
			(layer "F.SilkS")
		)
		(fp_line
			(start 1.524 -0.762)
			(end 1.524 0.762)
			(stroke
				(width 0.1524)
				(type default)
			)
			(layer "F.SilkS")
		)
		(fp_line
			(start 1.524 0.762)
			(end -1.524 0.762)
			(stroke
				(width 0.1524)
				(type default)
			)
			(layer "F.SilkS")
		)
		(fp_line
			(start -1.1049 -0.724916)
			(end -1.1049 0.724916)
			(stroke
				(width 0.1)
				(type default)
			)
			(layer "F.Fab")
		)
		(fp_line
			(start -1.1049 0.724916)
			(end 1.1049 0.724916)
			(stroke
				(width 0.1)
				(type default)
			)
			(layer "F.Fab")
		)
		(fp_line
			(start 1.1049 -0.724916)
			(end -1.1049 -0.724916)
			(stroke
				(width 0.1)
				(type default)
			)
			(layer "F.Fab")
		)
		(fp_line
			(start 1.1049 0.724916)
			(end 1.1049 -0.724916)
			(stroke
				(width 0.1)
				(type default)
			)
			(layer "F.Fab")
		)
		(pad "1" smd rect
			(at -0.889 0 180)
			(size 1.016 1.27)
			(layers "F.Cu" "F.Mask" "F.Paste")
			(net "PVCCIN_CPU1")
		)
		(pad "2" smd rect
			(at 0.889 0 180)
			(size 1.016 1.27)
			(layers "F.Cu" "F.Mask" "F.Paste")
			(net "GND")
		)
	)
	(footprint ""
		(layer "F.Cu")
		(at 446.18783 -376.471434)
		(property "Reference" "C1171"
			(at 0 0 0)
			(layer "F.SilkS")
			(hide yes)
			(effects
				(font
					(size 1.27 1.27)
				)
			)
		)
		(property "Value" ""
			(at 0 0 0)
			(layer "F.Fab")
			(effects
				(font
					(size 1.27 1.27)
				)
			)
		)
		(duplicate_pad_numbers_are_jumpers no)
		(fp_line
			(start -1.524 -0.762)
			(end 1.524 -0.762)
			(stroke
				(width 0.1524)
				(type default)
			)
			(layer "F.SilkS")
		)
		(fp_line
			(start -1.524 0.762)
			(end -1.524 -0.762)
			(stroke
				(width 0.1524)
				(type default)
			)
			(layer "F.SilkS")
		)
		(fp_line
			(start 1.524 -0.762)
			(end 1.524 0.762)
			(stroke
				(width 0.1524)
				(type default)
			)
			(layer "F.SilkS")
		)
		(fp_line
			(start 1.524 0.762)
			(end -1.524 0.762)
			(stroke
				(width 0.1524)
				(type default)
			)
			(layer "F.SilkS")
		)
		(fp_line
			(start -1.1049 -0.724916)
			(end -1.1049 0.724916)
			(stroke
				(width 0.1)
				(type default)
			)
			(layer "F.Fab")
		)
		(fp_line
			(start -1.1049 0.724916)
			(end 1.1049 0.724916)
			(stroke
				(width 0.1)
				(type default)
			)
			(layer "F.Fab")
		)
		(fp_line
			(start 1.1049 -0.724916)
			(end -1.1049 -0.724916)
			(stroke
				(width 0.1)
				(type default)
			)
			(layer "F.Fab")
		)
		(fp_line
			(start 1.1049 0.724916)
			(end 1.1049 -0.724916)
			(stroke
				(width 0.1)
				(type default)
			)
			(layer "F.Fab")
		)
		(pad "1" smd rect
			(at -0.889 0 180)
			(size 1.016 1.27)
			(layers "F.Cu" "F.Mask" "F.Paste")
			(net "P5V_AUX")
		)
		(pad "2" smd rect
			(at 0.889 0 180)
			(size 1.016 1.27)
			(layers "F.Cu" "F.Mask" "F.Paste")
			(net "GND")
		)
	)
	(footprint ""
		(layer "F.Cu")
		(at 396.518384 -16.088614 90)
		(property "Reference" "C842"
			(at 0 0 90)
			(layer "F.SilkS")
			(hide yes)
			(effects
				(font
					(size 1.27 1.27)
				)
			)
		)
		(property "Value" ""
			(at 0 0 90)
			(layer "F.Fab")
			(effects
				(font
					(size 1.27 1.27)
				)
			)
		)
		(duplicate_pad_numbers_are_jumpers no)
		(fp_line
			(start 0.299974 -0.150114)
			(end 0.299974 0.150114)
			(stroke
				(width 0.1)
				(type default)
			)
			(layer "F.Fab")
		)
		(fp_line
			(start -0.299974 -0.150114)
			(end 0.299974 -0.150114)
			(stroke
				(width 0.1)
				(type default)
			)
			(layer "F.Fab")
		)
		(fp_line
			(start 0.299974 0.150114)
			(end -0.299974 0.150114)
			(stroke
				(width 0.1)
				(type default)
			)
			(layer "F.Fab")
		)
		(fp_line
			(start -0.299974 0.150114)
			(end -0.299974 -0.150114)
			(stroke
				(width 0.1)
				(type default)
			)
			(layer "F.Fab")
		)
		(pad "1" smd rect
			(at -0.2667 0 90)
			(size 0.3048 0.381)
			(layers "F.Cu" "F.Mask" "F.Paste")
			(net "P5E_CPU0_PE1_TX_C_DN<13>")
		)
		(pad "2" smd rect
			(at 0.2667 0 90)
			(size 0.3048 0.381)
			(layers "F.Cu" "F.Mask" "F.Paste")
			(net "P5E_CPU0_PE1_TX_DN<13>")
		)
	)
	(footprint ""
		(layer "F.Cu")
		(at 107.019598 -17.13611)
		(property "Reference" "R3554"
			(at 0 0 0)
			(layer "F.SilkS")
			(hide yes)
			(effects
				(font
					(size 1.27 1.27)
				)
			)
		)
		(property "Value" ""
			(at 0 0 0)
			(layer "F.Fab")
			(effects
				(font
					(size 1.27 1.27)
				)
			)
		)
		(duplicate_pad_numbers_are_jumpers no)
		(fp_line
			(start -0.7874 -0.4064)
			(end 0.7874 -0.4064)
			(stroke
				(width 0.1524)
				(type default)
			)
			(layer "F.SilkS")
		)
		(fp_line
			(start -0.7874 0.4064)
			(end -0.7874 -0.4064)
			(stroke
				(width 0.1524)
				(type default)
			)
			(layer "F.SilkS")
		)
		(fp_line
			(start 0.7874 -0.4064)
			(end 0.7874 0.4064)
			(stroke
				(width 0.1524)
				(type default)
			)
			(layer "F.SilkS")
		)
		(fp_line
			(start 0.7874 0.4064)
			(end -0.7874 0.4064)
			(stroke
				(width 0.1524)
				(type default)
			)
			(layer "F.SilkS")
		)
		(fp_line
			(start -0.67945 -0.305054)
			(end -0.12065 -0.305054)
			(stroke
				(width 0.1)
				(type default)
			)
			(layer "F.Fab")
		)
		(fp_line
			(start -0.67945 0.3048)
			(end -0.67945 -0.305054)
			(stroke
				(width 0.1)
				(type default)
			)
			(layer "F.Fab")
		)
		(fp_line
			(start -0.12065 -0.305054)
			(end -0.12065 -0.2794)
			(stroke
				(width 0.1)
				(type default)
			)
			(layer "F.Fab")
		)
		(fp_line
			(start -0.12065 -0.2794)
			(end 0.12065 -0.2794)
			(stroke
				(width 0.1)
				(type default)
			)
			(layer "F.Fab")
		)
		(fp_line
			(start -0.12065 0.2794)
			(end -0.12065 0.3048)
			(stroke
				(width 0.1)
				(type default)
			)
			(layer "F.Fab")
		)
		(fp_line
			(start -0.12065 0.3048)
			(end -0.67945 0.3048)
			(stroke
				(width 0.1)
				(type default)
			)
			(layer "F.Fab")
		)
		(fp_line
			(start 0.120396 0.2794)
			(end -0.12065 0.2794)
			(stroke
				(width 0.1)
				(type default)
			)
			(layer "F.Fab")
		)
		(fp_line
			(start 0.120396 0.3048)
			(end 0.120396 0.2794)
			(stroke
				(width 0.1)
				(type default)
			)
			(layer "F.Fab")
		)
		(fp_line
			(start 0.12065 -0.3048)
			(end 0.67945 -0.3048)
			(stroke
				(width 0.1)
				(type default)
			)
			(layer "F.Fab")
		)
		(fp_line
			(start 0.12065 -0.2794)
			(end 0.12065 -0.3048)
			(stroke
				(width 0.1)
				(type default)
			)
			(layer "F.Fab")
		)
		(fp_line
			(start 0.67945 -0.3048)
			(end 0.67945 0.3048)
			(stroke
				(width 0.1)
				(type default)
			)
			(layer "F.Fab")
		)
		(fp_line
			(start 0.67945 0.3048)
			(end 0.120396 0.3048)
			(stroke
				(width 0.1)
				(type default)
			)
			(layer "F.Fab")
		)
		(pad "1" smd circle
			(at -0.40005 0)
			(size 0 0)
			(layers "F.Cu" "F.Mask" "F.Paste")
			(net "SMB_LM75_3_3V3AUX_SDA")
		)
		(pad "2" smd circle
			(at 0.40005 0)
			(size 0 0)
			(layers "F.Cu" "F.Mask" "F.Paste")
			(net "SMB_LM75_3_3V3AUX_SDA_R1")
		)
	)
	(footprint ""
		(layer "F.Cu")
		(at 27.0383 -127.348996 180)
		(property "Reference" "PC478"
			(at 0 0 180)
			(layer "F.SilkS")
			(hide yes)
			(effects
				(font
					(size 1.27 1.27)
				)
			)
		)
		(property "Value" ""
			(at 0 0 180)
			(layer "F.Fab")
			(effects
				(font
					(size 1.27 1.27)
				)
			)
		)
		(duplicate_pad_numbers_are_jumpers no)
		(fp_line
			(start 0.7874 0.4064)
			(end -0.7874 0.4064)
			(stroke
				(width 0.1524)
				(type default)
			)
			(layer "F.SilkS")
		)
		(fp_line
			(start 0.7874 -0.4064)
			(end 0.7874 0.4064)
			(stroke
				(width 0.1524)
				(type default)
			)
			(layer "F.SilkS")
		)
		(fp_line
			(start -0.7874 0.4064)
			(end -0.7874 -0.4064)
			(stroke
				(width 0.1524)
				(type default)
			)
			(layer "F.SilkS")
		)
		(fp_line
			(start -0.7874 -0.4064)
			(end 0.7874 -0.4064)
			(stroke
				(width 0.1524)
				(type default)
			)
			(layer "F.SilkS")
		)
		(fp_line
			(start 0.67945 0.3048)
			(end 0.120396 0.3048)
			(stroke
				(width 0.1)
				(type default)
			)
			(layer "F.Fab")
		)
		(fp_line
			(start 0.67945 -0.3048)
			(end 0.67945 0.3048)
			(stroke
				(width 0.1)
				(type default)
			)
			(layer "F.Fab")
		)
		(fp_line
			(start 0.12065 -0.2794)
			(end 0.12065 -0.3048)
			(stroke
				(width 0.1)
				(type default)
			)
			(layer "F.Fab")
		)
		(fp_line
			(start 0.12065 -0.3048)
			(end 0.67945 -0.3048)
			(stroke
				(width 0.1)
				(type default)
			)
			(layer "F.Fab")
		)
		(fp_line
			(start 0.120396 0.3048)
			(end 0.120396 0.2794)
			(stroke
				(width 0.1)
				(type default)
			)
			(layer "F.Fab")
		)
		(fp_line
			(start 0.120396 0.2794)
			(end -0.12065 0.2794)
			(stroke
				(width 0.1)
				(type default)
			)
			(layer "F.Fab")
		)
		(fp_line
			(start -0.12065 0.3048)
			(end -0.67945 0.3048)
			(stroke
				(width 0.1)
				(type default)
			)
			(layer "F.Fab")
		)
		(fp_line
			(start -0.12065 0.2794)
			(end -0.12065 0.3048)
			(stroke
				(width 0.1)
				(type default)
			)
			(layer "F.Fab")
		)
		(fp_line
			(start -0.12065 -0.2794)
			(end 0.12065 -0.2794)
			(stroke
				(width 0.1)
				(type default)
			)
			(layer "F.Fab")
		)
		(fp_line
			(start -0.12065 -0.305054)
			(end -0.12065 -0.2794)
			(stroke
				(width 0.1)
				(type default)
			)
			(layer "F.Fab")
		)
		(fp_line
			(start -0.67945 0.3048)
			(end -0.67945 -0.305054)
			(stroke
				(width 0.1)
				(type default)
			)
			(layer "F.Fab")
		)
		(fp_line
			(start -0.67945 -0.305054)
			(end -0.12065 -0.305054)
			(stroke
				(width 0.1)
				(type default)
			)
			(layer "F.Fab")
		)
		(pad "1" smd circle
			(at -0.40005 0 180)
			(size 0 0)
			(layers "F.Cu" "F.Mask" "F.Paste")
			(net "PVCCINFAON_CPU1_VCC")
		)
		(pad "2" smd circle
			(at 0.40005 0 180)
			(size 0 0)
			(layers "F.Cu" "F.Mask" "F.Paste")
			(net "GND")
		)
	)
	(footprint ""
		(layer "F.Cu")
		(at 118.09222 -419.920928 90)
		(property "Reference" "C1770"
			(at 0 0 90)
			(layer "F.SilkS")
			(hide yes)
			(effects
				(font
					(size 1.27 1.27)
				)
			)
		)
		(property "Value" ""
			(at 0 0 90)
			(layer "F.Fab")
			(effects
				(font
					(size 1.27 1.27)
				)
			)
		)
		(duplicate_pad_numbers_are_jumpers no)
		(fp_line
			(start 0.7874 -0.4064)
			(end 0.7874 0.4064)
			(stroke
				(width 0.1524)
				(type default)
			)
			(layer "F.SilkS")
		)
		(fp_line
			(start -0.7874 -0.4064)
			(end 0.7874 -0.4064)
			(stroke
				(width 0.1524)
				(type default)
			)
			(layer "F.SilkS")
		)
		(fp_line
			(start 0.7874 0.4064)
			(end -0.7874 0.4064)
			(stroke
				(width 0.1524)
				(type default)
			)
			(layer "F.SilkS")
		)
		(fp_line
			(start -0.7874 0.4064)
			(end -0.7874 -0.4064)
			(stroke
				(width 0.1524)
				(type default)
			)
			(layer "F.SilkS")
		)
		(fp_line
			(start -0.12065 -0.305054)
			(end -0.12065 -0.2794)
			(stroke
				(width 0.1)
				(type default)
			)
			(layer "F.Fab")
		)
		(fp_line
			(start -0.67945 -0.305054)
			(end -0.12065 -0.305054)
			(stroke
				(width 0.1)
				(type default)
			)
			(layer "F.Fab")
		)
		(fp_line
			(start 0.67945 -0.3048)
			(end 0.67945 0.3048)
			(stroke
				(width 0.1)
				(type default)
			)
			(layer "F.Fab")
		)
		(fp_line
			(start 0.12065 -0.3048)
			(end 0.67945 -0.3048)
			(stroke
				(width 0.1)
				(type default)
			)
			(layer "F.Fab")
		)
		(fp_line
			(start 0.12065 -0.2794)
			(end 0.12065 -0.3048)
			(stroke
				(width 0.1)
				(type default)
			)
			(layer "F.Fab")
		)
		(fp_line
			(start -0.12065 -0.2794)
			(end 0.12065 -0.2794)
			(stroke
				(width 0.1)
				(type default)
			)
			(layer "F.Fab")
		)
		(fp_line
			(start 0.120396 0.2794)
			(end -0.12065 0.2794)
			(stroke
				(width 0.1)
				(type default)
			)
			(layer "F.Fab")
		)
		(fp_line
			(start -0.12065 0.2794)
			(end -0.12065 0.3048)
			(stroke
				(width 0.1)
				(type default)
			)
			(layer "F.Fab")
		)
		(fp_line
			(start 0.67945 0.3048)
			(end 0.120396 0.3048)
			(stroke
				(width 0.1)
				(type default)
			)
			(layer "F.Fab")
		)
		(fp_line
			(start 0.120396 0.3048)
			(end 0.120396 0.2794)
			(stroke
				(width 0.1)
				(type default)
			)
			(layer "F.Fab")
		)
		(fp_line
			(start -0.12065 0.3048)
			(end -0.67945 0.3048)
			(stroke
				(width 0.1)
				(type default)
			)
			(layer "F.Fab")
		)
		(fp_line
			(start -0.67945 0.3048)
			(end -0.67945 -0.305054)
			(stroke
				(width 0.1)
				(type default)
			)
			(layer "F.Fab")
		)
		(pad "1" smd circle
			(at -0.40005 0 90)
			(size 0 0)
			(layers "F.Cu" "F.Mask" "F.Paste")
			(net "P3V3_AUX")
		)
		(pad "2" smd circle
			(at 0.40005 0 90)
			(size 0 0)
			(layers "F.Cu" "F.Mask" "F.Paste")
			(net "GND")
		)
	)
	(footprint ""
		(layer "F.Cu")
		(at 24.93137 -42.992802 180)
		(property "Reference" "R3065"
			(at 0 0 180)
			(layer "F.SilkS")
			(hide yes)
			(effects
				(font
					(size 1.27 1.27)
				)
			)
		)
		(property "Value" ""
			(at 0 0 180)
			(layer "F.Fab")
			(effects
				(font
					(size 1.27 1.27)
				)
			)
		)
		(duplicate_pad_numbers_are_jumpers no)
		(fp_line
			(start 0.7874 0.4064)
			(end -0.7874 0.4064)
			(stroke
				(width 0.1524)
				(type default)
			)
			(layer "F.SilkS")
		)
		(fp_line
			(start 0.7874 -0.4064)
			(end 0.7874 0.4064)
			(stroke
				(width 0.1524)
				(type default)
			)
			(layer "F.SilkS")
		)
		(fp_line
			(start -0.7874 0.4064)
			(end -0.7874 -0.4064)
			(stroke
				(width 0.1524)
				(type default)
			)
			(layer "F.SilkS")
		)
		(fp_line
			(start -0.7874 -0.4064)
			(end 0.7874 -0.4064)
			(stroke
				(width 0.1524)
				(type default)
			)
			(layer "F.SilkS")
		)
		(fp_line
			(start 0.67945 0.3048)
			(end 0.120396 0.3048)
			(stroke
				(width 0.1)
				(type default)
			)
			(layer "F.Fab")
		)
		(fp_line
			(start 0.67945 -0.3048)
			(end 0.67945 0.3048)
			(stroke
				(width 0.1)
				(type default)
			)
			(layer "F.Fab")
		)
		(fp_line
			(start 0.12065 -0.2794)
			(end 0.12065 -0.3048)
			(stroke
				(width 0.1)
				(type default)
			)
			(layer "F.Fab")
		)
		(fp_line
			(start 0.12065 -0.3048)
			(end 0.67945 -0.3048)
			(stroke
				(width 0.1)
				(type default)
			)
			(layer "F.Fab")
		)
		(fp_line
			(start 0.120396 0.3048)
			(end 0.120396 0.2794)
			(stroke
				(width 0.1)
				(type default)
			)
			(layer "F.Fab")
		)
		(fp_line
			(start 0.120396 0.2794)
			(end -0.12065 0.2794)
			(stroke
				(width 0.1)
				(type default)
			)
			(layer "F.Fab")
		)
		(fp_line
			(start -0.12065 0.3048)
			(end -0.67945 0.3048)
			(stroke
				(width 0.1)
				(type default)
			)
			(layer "F.Fab")
		)
		(fp_line
			(start -0.12065 0.2794)
			(end -0.12065 0.3048)
			(stroke
				(width 0.1)
				(type default)
			)
			(layer "F.Fab")
		)
		(fp_line
			(start -0.12065 -0.2794)
			(end 0.12065 -0.2794)
			(stroke
				(width 0.1)
				(type default)
			)
			(layer "F.Fab")
		)
		(fp_line
			(start -0.12065 -0.305054)
			(end -0.12065 -0.2794)
			(stroke
				(width 0.1)
				(type default)
			)
			(layer "F.Fab")
		)
		(fp_line
			(start -0.67945 0.3048)
			(end -0.67945 -0.305054)
			(stroke
				(width 0.1)
				(type default)
			)
			(layer "F.Fab")
		)
		(fp_line
			(start -0.67945 -0.305054)
			(end -0.12065 -0.305054)
			(stroke
				(width 0.1)
				(type default)
			)
			(layer "F.Fab")
		)
		(pad "1" smd circle
			(at -0.40005 0 180)
			(size 0 0)
			(layers "F.Cu" "F.Mask" "F.Paste")
			(net "FM_BIOS_POST_CMPLT_N")
		)
		(pad "2" smd circle
			(at 0.40005 0 180)
			(size 0 0)
			(layers "F.Cu" "F.Mask" "F.Paste")
			(net "FM_BIOS_POST_CMPLT_HDR_N")
		)
	)
	(footprint ""
		(layer "F.Cu")
		(at 242.291616 -398.78 90)
		(property "Reference" "PPQ1"
			(at -8.230108 -1.771396 0)
			(unlocked yes)
			(layer "F.SilkS")
			(effects
				(font
					(size 0.7874 0.5842)
					(thickness 0.1524)
				)
				(justify left)
			)
		)
		(property "Value" ""
			(at 0 0 90)
			(layer "F.Fab")
			(effects
				(font
					(size 1.27 1.27)
				)
			)
		)
		(duplicate_pad_numbers_are_jumpers no)
		(fp_line
			(start 2.350008 -2.649982)
			(end 2.350008 -2.4892)
			(stroke
				(width 0.1524)
				(type default)
			)
			(layer "F.SilkS")
		)
		(fp_line
			(start -2.350008 -2.649982)
			(end 2.350008 -2.649982)
			(stroke
				(width 0.1524)
				(type default)
			)
			(layer "F.SilkS")
		)
		(fp_line
			(start -2.350008 -2.4384)
			(end -2.350008 -2.649982)
			(stroke
				(width 0.1524)
				(type default)
			)
			(layer "F.SilkS")
		)
		(fp_line
			(start 2.350008 2.4892)
			(end 2.350008 2.649982)
			(stroke
				(width 0.1524)
				(type default)
			)
			(layer "F.SilkS")
		)
		(fp_line
			(start 2.350008 2.649982)
			(end -2.350008 2.649982)
			(stroke
				(width 0.1524)
				(type default)
			)
			(layer "F.SilkS")
		)
		(fp_line
			(start -2.350008 2.649982)
			(end -2.350008 2.413)
			(stroke
				(width 0.1524)
				(type default)
			)
			(layer "F.SilkS")
		)
		(fp_poly
			(pts
				(xy -3.717544 -1.905) (xy -4.758944 -2.3241) (xy -4.758944 -1.524)
			)
			(stroke
				(width 0)
				(type default)
			)
			(fill yes)
			(layer "F.SilkS")
		)
		(fp_line
			(start 2.350008 -2.649982)
			(end 2.350008 2.649982)
			(stroke
				(width 0.1)
				(type default)
			)
			(layer "F.Fab")
		)
		(fp_line
			(start -2.350008 -2.649982)
			(end 2.350008 -2.649982)
			(stroke
				(width 0.1)
				(type default)
			)
			(layer "F.Fab")
		)
		(fp_line
			(start 2.350008 2.649982)
			(end -2.350008 2.649982)
			(stroke
				(width 0.1)
				(type default)
			)
			(layer "F.Fab")
		)
		(fp_line
			(start -2.350008 2.649982)
			(end -2.350008 -2.649982)
			(stroke
				(width 0.1)
				(type default)
			)
			(layer "F.Fab")
		)
		(fp_poly
			(pts
				(xy -3.717544 -1.905) (xy -4.758944 -2.3241) (xy -4.758944 -1.524)
			)
			(stroke
				(width 0)
				(type default)
			)
			(fill yes)
			(layer "F.Fab")
		)
		(pad "1" smd rect
			(at -2.999994 -1.905)
			(size 0.7112 1.1684)
			(layers "F.Cu" "F.Mask" "F.Paste")
			(net "P12V_AUX")
		)
		(pad "2" smd rect
			(at -2.999994 -0.635)
			(size 0.7112 1.1684)
			(layers "F.Cu" "F.Mask" "F.Paste")
			(net "P12V_AUX")
		)
		(pad "3" smd rect
			(at -2.999994 0.635)
			(size 0.7112 1.1684)
			(layers "F.Cu" "F.Mask" "F.Paste")
			(net "P12V_AUX")
		)
		(pad "4" smd rect
			(at -2.999994 1.905)
			(size 0.7112 1.1684)
			(layers "F.Cu" "F.Mask" "F.Paste")
			(net "P12V_HSC_GATE_G5")
		)
		(pad "5" smd circle
			(at 0.925068 0)
			(size 0 0)
			(layers "F.Cu" "F.Mask" "F.Paste")
			(net "P12V_MAIN_R")
		)
		(zone
			(layer "F.Cu")
			(hatch none 0.5)
			(connect_pads
				(clearance 0)
			)
			(min_thickness 0.25)
			(keepout
				(tracks not_allowed)
				(vias allowed)
				(pads allowed)
				(copperpour not_allowed)
				(footprints allowed)
			)
			(placement
				(enabled no)
				(sheetname "")
			)
			(fill
				(thermal_gap 0.5)
				(thermal_bridge_width 0.5)
				(island_removal_mode 0)
			)
			(polygon
				(pts
					(xy 240.132616 -397.3322) (xy 244.450616 -397.3322) (xy 244.933216 -397.3322) (xy 244.933216 -396.4305)
					(xy 239.650016 -396.4305) (xy 239.650016 -397.3322)
				)
			)
		)
	)
	(footprint ""
		(layer "F.Cu")
		(at 421.780208 -141.756638 180)
		(property "Reference" "PJ46"
			(at 2.878328 1.442212 0)
			(unlocked yes)
			(layer "F.SilkS")
			(effects
				(font
					(size 0.7874 0.5842)
					(thickness 0.1524)
				)
				(justify left)
			)
		)
		(property "Value" ""
			(at 0 0 180)
			(layer "F.Fab")
			(effects
				(font
					(size 1.27 1.27)
				)
			)
		)
		(duplicate_pad_numbers_are_jumpers no)
		(pad "1" smd circle
			(at -0.7493 0 270)
			(size 0 0)
			(layers "F.Cu" "F.Mask" "F.Paste")
			(net "VSENSE_PVCCFA_EHV_CPU0_DP")
		)
		(pad "2" smd rect
			(at 0.7493 0 90)
			(size 0.7112 0.8128)
			(layers "F.Cu" "F.Mask" "F.Paste")
			(net "SH_PVCCFA_EHV_CPU0")
		)
		(zone
			(layer "F.Cu")
			(hatch none 0.5)
			(connect_pads
				(clearance 0)
			)
			(min_thickness 0.25)
			(keepout
				(tracks allowed)
				(vias not_allowed)
				(pads allowed)
				(copperpour not_allowed)
				(footprints allowed)
			)
			(placement
				(enabled no)
				(sheetname "")
			)
			(fill
				(thermal_gap 0.5)
				(thermal_bridge_width 0.5)
				(island_removal_mode 0)
			)
			(polygon
				(pts
					(xy 420.573708 -141.350238) (xy 422.961308 -141.350238) (xy 422.961308 -142.167864) (xy 420.573708 -142.167864)
				)
			)
		)
	)
	(footprint ""
		(layer "F.Cu")
		(at 359.7656 -404.7998 180)
		(property "Reference" "R4732"
			(at 0 0 180)
			(layer "F.SilkS")
			(hide yes)
			(effects
				(font
					(size 1.27 1.27)
				)
			)
		)
		(property "Value" ""
			(at 0 0 180)
			(layer "F.Fab")
			(effects
				(font
					(size 1.27 1.27)
				)
			)
		)
		(duplicate_pad_numbers_are_jumpers no)
		(fp_line
			(start 0.7874 0.4064)
			(end -0.7874 0.4064)
			(stroke
				(width 0.1524)
				(type default)
			)
			(layer "F.SilkS")
		)
		(fp_line
			(start 0.7874 -0.4064)
			(end 0.7874 0.4064)
			(stroke
				(width 0.1524)
				(type default)
			)
			(layer "F.SilkS")
		)
		(fp_line
			(start -0.7874 0.4064)
			(end -0.7874 -0.4064)
			(stroke
				(width 0.1524)
				(type default)
			)
			(layer "F.SilkS")
		)
		(fp_line
			(start -0.7874 -0.4064)
			(end 0.7874 -0.4064)
			(stroke
				(width 0.1524)
				(type default)
			)
			(layer "F.SilkS")
		)
		(fp_line
			(start 0.67945 0.3048)
			(end 0.120396 0.3048)
			(stroke
				(width 0.1)
				(type default)
			)
			(layer "F.Fab")
		)
		(fp_line
			(start 0.67945 -0.3048)
			(end 0.67945 0.3048)
			(stroke
				(width 0.1)
				(type default)
			)
			(layer "F.Fab")
		)
		(fp_line
			(start 0.12065 -0.2794)
			(end 0.12065 -0.3048)
			(stroke
				(width 0.1)
				(type default)
			)
			(layer "F.Fab")
		)
		(fp_line
			(start 0.12065 -0.3048)
			(end 0.67945 -0.3048)
			(stroke
				(width 0.1)
				(type default)
			)
			(layer "F.Fab")
		)
		(fp_line
			(start 0.120396 0.3048)
			(end 0.120396 0.2794)
			(stroke
				(width 0.1)
				(type default)
			)
			(layer "F.Fab")
		)
		(fp_line
			(start 0.120396 0.2794)
			(end -0.12065 0.2794)
			(stroke
				(width 0.1)
				(type default)
			)
			(layer "F.Fab")
		)
		(fp_line
			(start -0.12065 0.3048)
			(end -0.67945 0.3048)
			(stroke
				(width 0.1)
				(type default)
			)
			(layer "F.Fab")
		)
		(fp_line
			(start -0.12065 0.2794)
			(end -0.12065 0.3048)
			(stroke
				(width 0.1)
				(type default)
			)
			(layer "F.Fab")
		)
		(fp_line
			(start -0.12065 -0.2794)
			(end 0.12065 -0.2794)
			(stroke
				(width 0.1)
				(type default)
			)
			(layer "F.Fab")
		)
		(fp_line
			(start -0.12065 -0.305054)
			(end -0.12065 -0.2794)
			(stroke
				(width 0.1)
				(type default)
			)
			(layer "F.Fab")
		)
		(fp_line
			(start -0.67945 0.3048)
			(end -0.67945 -0.305054)
			(stroke
				(width 0.1)
				(type default)
			)
			(layer "F.Fab")
		)
		(fp_line
			(start -0.67945 -0.305054)
			(end -0.12065 -0.305054)
			(stroke
				(width 0.1)
				(type default)
			)
			(layer "F.Fab")
		)
		(pad "1" smd circle
			(at -0.40005 0 180)
			(size 0 0)
			(layers "F.Cu" "F.Mask" "F.Paste")
			(net "P3V3_AUX")
		)
		(pad "2" smd circle
			(at 0.40005 0 180)
			(size 0 0)
			(layers "F.Cu" "F.Mask" "F.Paste")
			(net "PRSNT_CABLE_SWB_B2")
		)
	)
	(footprint ""
		(layer "F.Cu")
		(at 160.83788 -112.232948)
		(property "Reference" "R3476"
			(at 0 0 0)
			(layer "F.SilkS")
			(hide yes)
			(effects
				(font
					(size 1.27 1.27)
				)
			)
		)
		(property "Value" ""
			(at 0 0 0)
			(layer "F.Fab")
			(effects
				(font
					(size 1.27 1.27)
				)
			)
		)
		(duplicate_pad_numbers_are_jumpers no)
		(fp_line
			(start -0.7874 -0.4064)
			(end 0.7874 -0.4064)
			(stroke
				(width 0.1524)
				(type default)
			)
			(layer "F.SilkS")
		)
		(fp_line
			(start -0.7874 0.4064)
			(end -0.7874 -0.4064)
			(stroke
				(width 0.1524)
				(type default)
			)
			(layer "F.SilkS")
		)
		(fp_line
			(start 0.7874 -0.4064)
			(end 0.7874 0.4064)
			(stroke
				(width 0.1524)
				(type default)
			)
			(layer "F.SilkS")
		)
		(fp_line
			(start 0.7874 0.4064)
			(end -0.7874 0.4064)
			(stroke
				(width 0.1524)
				(type default)
			)
			(layer "F.SilkS")
		)
		(fp_line
			(start -0.67945 -0.305054)
			(end -0.12065 -0.305054)
			(stroke
				(width 0.1)
				(type default)
			)
			(layer "F.Fab")
		)
		(fp_line
			(start -0.67945 0.3048)
			(end -0.67945 -0.305054)
			(stroke
				(width 0.1)
				(type default)
			)
			(layer "F.Fab")
		)
		(fp_line
			(start -0.12065 -0.305054)
			(end -0.12065 -0.2794)
			(stroke
				(width 0.1)
				(type default)
			)
			(layer "F.Fab")
		)
		(fp_line
			(start -0.12065 -0.2794)
			(end 0.12065 -0.2794)
			(stroke
				(width 0.1)
				(type default)
			)
			(layer "F.Fab")
		)
		(fp_line
			(start -0.12065 0.2794)
			(end -0.12065 0.3048)
			(stroke
				(width 0.1)
				(type default)
			)
			(layer "F.Fab")
		)
		(fp_line
			(start -0.12065 0.3048)
			(end -0.67945 0.3048)
			(stroke
				(width 0.1)
				(type default)
			)
			(layer "F.Fab")
		)
		(fp_line
			(start 0.120396 0.2794)
			(end -0.12065 0.2794)
			(stroke
				(width 0.1)
				(type default)
			)
			(layer "F.Fab")
		)
		(fp_line
			(start 0.120396 0.3048)
			(end 0.120396 0.2794)
			(stroke
				(width 0.1)
				(type default)
			)
			(layer "F.Fab")
		)
		(fp_line
			(start 0.12065 -0.3048)
			(end 0.67945 -0.3048)
			(stroke
				(width 0.1)
				(type default)
			)
			(layer "F.Fab")
		)
		(fp_line
			(start 0.12065 -0.2794)
			(end 0.12065 -0.3048)
			(stroke
				(width 0.1)
				(type default)
			)
			(layer "F.Fab")
		)
		(fp_line
			(start 0.67945 -0.3048)
			(end 0.67945 0.3048)
			(stroke
				(width 0.1)
				(type default)
			)
			(layer "F.Fab")
		)
		(fp_line
			(start 0.67945 0.3048)
			(end 0.120396 0.3048)
			(stroke
				(width 0.1)
				(type default)
			)
			(layer "F.Fab")
		)
		(pad "1" smd circle
			(at -0.40005 0)
			(size 0 0)
			(layers "F.Cu" "F.Mask" "F.Paste")
			(net "GPU_FPGA_THERM_OVERT_ISO_N")
		)
		(pad "2" smd circle
			(at 0.40005 0)
			(size 0 0)
			(layers "F.Cu" "F.Mask" "F.Paste")
			(net "GPU_FPGA_THERM_OVERT_ISO_R_N")
		)
	)
	(footprint ""
		(layer "F.Cu")
		(at 339.910928 -408.517344 -90)
		(property "Reference" "C925"
			(at 0 0 270)
			(layer "F.SilkS")
			(hide yes)
			(effects
				(font
					(size 1.27 1.27)
				)
			)
		)
		(property "Value" ""
			(at 0 0 270)
			(layer "F.Fab")
			(effects
				(font
					(size 1.27 1.27)
				)
			)
		)
		(duplicate_pad_numbers_are_jumpers no)
		(fp_line
			(start -0.299974 0.150114)
			(end -0.299974 -0.150114)
			(stroke
				(width 0.1)
				(type default)
			)
			(layer "F.Fab")
		)
		(fp_line
			(start 0.299974 0.150114)
			(end -0.299974 0.150114)
			(stroke
				(width 0.1)
				(type default)
			)
			(layer "F.Fab")
		)
		(fp_line
			(start -0.299974 -0.150114)
			(end 0.299974 -0.150114)
			(stroke
				(width 0.1)
				(type default)
			)
			(layer "F.Fab")
		)
		(fp_line
			(start 0.299974 -0.150114)
			(end 0.299974 0.150114)
			(stroke
				(width 0.1)
				(type default)
			)
			(layer "F.Fab")
		)
		(pad "1" smd rect
			(at -0.2667 0 270)
			(size 0.3048 0.381)
			(layers "F.Cu" "F.Mask" "F.Paste")
			(net "P5E_CPU0_PE0_TX_C_DP<4>")
		)
		(pad "2" smd rect
			(at 0.2667 0 270)
			(size 0.3048 0.381)
			(layers "F.Cu" "F.Mask" "F.Paste")
			(net "P5E_CPU0_PE0_TX_DP<4>")
		)
	)
	(footprint ""
		(layer "F.Cu")
		(at 130.48488 -100.167948 90)
		(property "Reference" "R4411"
			(at 0 0 90)
			(layer "F.SilkS")
			(hide yes)
			(effects
				(font
					(size 1.27 1.27)
				)
			)
		)
		(property "Value" ""
			(at 0 0 90)
			(layer "F.Fab")
			(effects
				(font
					(size 1.27 1.27)
				)
			)
		)
		(duplicate_pad_numbers_are_jumpers no)
		(fp_line
			(start 0.7874 -0.4064)
			(end 0.7874 0.4064)
			(stroke
				(width 0.1524)
				(type default)
			)
			(layer "F.SilkS")
		)
		(fp_line
			(start -0.7874 -0.4064)
			(end 0.7874 -0.4064)
			(stroke
				(width 0.1524)
				(type default)
			)
			(layer "F.SilkS")
		)
		(fp_line
			(start 0.7874 0.4064)
			(end -0.7874 0.4064)
			(stroke
				(width 0.1524)
				(type default)
			)
			(layer "F.SilkS")
		)
		(fp_line
			(start -0.7874 0.4064)
			(end -0.7874 -0.4064)
			(stroke
				(width 0.1524)
				(type default)
			)
			(layer "F.SilkS")
		)
		(fp_line
			(start -0.12065 -0.305054)
			(end -0.12065 -0.2794)
			(stroke
				(width 0.1)
				(type default)
			)
			(layer "F.Fab")
		)
		(fp_line
			(start -0.67945 -0.305054)
			(end -0.12065 -0.305054)
			(stroke
				(width 0.1)
				(type default)
			)
			(layer "F.Fab")
		)
		(fp_line
			(start 0.67945 -0.3048)
			(end 0.67945 0.3048)
			(stroke
				(width 0.1)
				(type default)
			)
			(layer "F.Fab")
		)
		(fp_line
			(start 0.12065 -0.3048)
			(end 0.67945 -0.3048)
			(stroke
				(width 0.1)
				(type default)
			)
			(layer "F.Fab")
		)
		(fp_line
			(start 0.12065 -0.2794)
			(end 0.12065 -0.3048)
			(stroke
				(width 0.1)
				(type default)
			)
			(layer "F.Fab")
		)
		(fp_line
			(start -0.12065 -0.2794)
			(end 0.12065 -0.2794)
			(stroke
				(width 0.1)
				(type default)
			)
			(layer "F.Fab")
		)
		(fp_line
			(start 0.120396 0.2794)
			(end -0.12065 0.2794)
			(stroke
				(width 0.1)
				(type default)
			)
			(layer "F.Fab")
		)
		(fp_line
			(start -0.12065 0.2794)
			(end -0.12065 0.3048)
			(stroke
				(width 0.1)
				(type default)
			)
			(layer "F.Fab")
		)
		(fp_line
			(start 0.67945 0.3048)
			(end 0.120396 0.3048)
			(stroke
				(width 0.1)
				(type default)
			)
			(layer "F.Fab")
		)
		(fp_line
			(start 0.120396 0.3048)
			(end 0.120396 0.2794)
			(stroke
				(width 0.1)
				(type default)
			)
			(layer "F.Fab")
		)
		(fp_line
			(start -0.12065 0.3048)
			(end -0.67945 0.3048)
			(stroke
				(width 0.1)
				(type default)
			)
			(layer "F.Fab")
		)
		(fp_line
			(start -0.67945 0.3048)
			(end -0.67945 -0.305054)
			(stroke
				(width 0.1)
				(type default)
			)
			(layer "F.Fab")
		)
		(pad "1" smd circle
			(at -0.40005 0 90)
			(size 0 0)
			(layers "F.Cu" "F.Mask" "F.Paste")
			(net "P3V3")
		)
		(pad "2" smd circle
			(at 0.40005 0 90)
			(size 0 0)
			(layers "F.Cu" "F.Mask" "F.Paste")
			(net "H_CPU0_MEMTRIP_VT_N")
		)
	)
	(footprint ""
		(layer "F.Cu")
		(at 176.6824 -93.538548 90)
		(property "Reference" "R4586"
			(at 0 0 90)
			(layer "F.SilkS")
			(hide yes)
			(effects
				(font
					(size 1.27 1.27)
				)
			)
		)
		(property "Value" ""
			(at 0 0 90)
			(layer "F.Fab")
			(effects
				(font
					(size 1.27 1.27)
				)
			)
		)
		(duplicate_pad_numbers_are_jumpers no)
		(fp_line
			(start 0.7874 -0.4064)
			(end 0.7874 0.4064)
			(stroke
				(width 0.1524)
				(type default)
			)
			(layer "F.SilkS")
		)
		(fp_line
			(start -0.7874 -0.4064)
			(end 0.7874 -0.4064)
			(stroke
				(width 0.1524)
				(type default)
			)
			(layer "F.SilkS")
		)
		(fp_line
			(start 0.7874 0.4064)
			(end -0.7874 0.4064)
			(stroke
				(width 0.1524)
				(type default)
			)
			(layer "F.SilkS")
		)
		(fp_line
			(start -0.7874 0.4064)
			(end -0.7874 -0.4064)
			(stroke
				(width 0.1524)
				(type default)
			)
			(layer "F.SilkS")
		)
		(fp_line
			(start -0.12065 -0.305054)
			(end -0.12065 -0.2794)
			(stroke
				(width 0.1)
				(type default)
			)
			(layer "F.Fab")
		)
		(fp_line
			(start -0.67945 -0.305054)
			(end -0.12065 -0.305054)
			(stroke
				(width 0.1)
				(type default)
			)
			(layer "F.Fab")
		)
		(fp_line
			(start 0.67945 -0.3048)
			(end 0.67945 0.3048)
			(stroke
				(width 0.1)
				(type default)
			)
			(layer "F.Fab")
		)
		(fp_line
			(start 0.12065 -0.3048)
			(end 0.67945 -0.3048)
			(stroke
				(width 0.1)
				(type default)
			)
			(layer "F.Fab")
		)
		(fp_line
			(start 0.12065 -0.2794)
			(end 0.12065 -0.3048)
			(stroke
				(width 0.1)
				(type default)
			)
			(layer "F.Fab")
		)
		(fp_line
			(start -0.12065 -0.2794)
			(end 0.12065 -0.2794)
			(stroke
				(width 0.1)
				(type default)
			)
			(layer "F.Fab")
		)
		(fp_line
			(start 0.120396 0.2794)
			(end -0.12065 0.2794)
			(stroke
				(width 0.1)
				(type default)
			)
			(layer "F.Fab")
		)
		(fp_line
			(start -0.12065 0.2794)
			(end -0.12065 0.3048)
			(stroke
				(width 0.1)
				(type default)
			)
			(layer "F.Fab")
		)
		(fp_line
			(start 0.67945 0.3048)
			(end 0.120396 0.3048)
			(stroke
				(width 0.1)
				(type default)
			)
			(layer "F.Fab")
		)
		(fp_line
			(start 0.120396 0.3048)
			(end 0.120396 0.2794)
			(stroke
				(width 0.1)
				(type default)
			)
			(layer "F.Fab")
		)
		(fp_line
			(start -0.12065 0.3048)
			(end -0.67945 0.3048)
			(stroke
				(width 0.1)
				(type default)
			)
			(layer "F.Fab")
		)
		(fp_line
			(start -0.67945 0.3048)
			(end -0.67945 -0.305054)
			(stroke
				(width 0.1)
				(type default)
			)
			(layer "F.Fab")
		)
		(pad "1" smd rect
			(at -0.40005 0 270)
			(size 0.4572 0.508)
			(layers "F.Cu" "F.Mask" "F.Paste")
			(net "P3V3_AUX")
		)
		(pad "2" smd rect
			(at 0.40005 0 270)
			(size 0.4572 0.508)
			(layers "F.Cu" "F.Mask" "F.Paste")
			(net "FAB_BMC_REV_ID2")
		)
	)
	(footprint ""
		(layer "F.Cu")
		(at 95.706438 -338.86013)
		(property "Reference" "PR326"
			(at 0 0 0)
			(layer "F.SilkS")
			(hide yes)
			(effects
				(font
					(size 1.27 1.27)
				)
			)
		)
		(property "Value" ""
			(at 0 0 0)
			(layer "F.Fab")
			(effects
				(font
					(size 1.27 1.27)
				)
			)
		)
		(duplicate_pad_numbers_are_jumpers no)
		(fp_line
			(start -0.7874 -0.4064)
			(end 0.7874 -0.4064)
			(stroke
				(width 0.1524)
				(type default)
			)
			(layer "F.SilkS")
		)
		(fp_line
			(start -0.7874 0.4064)
			(end -0.7874 -0.4064)
			(stroke
				(width 0.1524)
				(type default)
			)
			(layer "F.SilkS")
		)
		(fp_line
			(start 0.7874 -0.4064)
			(end 0.7874 0.4064)
			(stroke
				(width 0.1524)
				(type default)
			)
			(layer "F.SilkS")
		)
		(fp_line
			(start 0.7874 0.4064)
			(end -0.7874 0.4064)
			(stroke
				(width 0.1524)
				(type default)
			)
			(layer "F.SilkS")
		)
		(fp_line
			(start -0.67945 -0.305054)
			(end -0.12065 -0.305054)
			(stroke
				(width 0.1)
				(type default)
			)
			(layer "F.Fab")
		)
		(fp_line
			(start -0.67945 0.3048)
			(end -0.67945 -0.305054)
			(stroke
				(width 0.1)
				(type default)
			)
			(layer "F.Fab")
		)
		(fp_line
			(start -0.12065 -0.305054)
			(end -0.12065 -0.2794)
			(stroke
				(width 0.1)
				(type default)
			)
			(layer "F.Fab")
		)
		(fp_line
			(start -0.12065 -0.2794)
			(end 0.12065 -0.2794)
			(stroke
				(width 0.1)
				(type default)
			)
			(layer "F.Fab")
		)
		(fp_line
			(start -0.12065 0.2794)
			(end -0.12065 0.3048)
			(stroke
				(width 0.1)
				(type default)
			)
			(layer "F.Fab")
		)
		(fp_line
			(start -0.12065 0.3048)
			(end -0.67945 0.3048)
			(stroke
				(width 0.1)
				(type default)
			)
			(layer "F.Fab")
		)
		(fp_line
			(start 0.120396 0.2794)
			(end -0.12065 0.2794)
			(stroke
				(width 0.1)
				(type default)
			)
			(layer "F.Fab")
		)
		(fp_line
			(start 0.120396 0.3048)
			(end 0.120396 0.2794)
			(stroke
				(width 0.1)
				(type default)
			)
			(layer "F.Fab")
		)
		(fp_line
			(start 0.12065 -0.3048)
			(end 0.67945 -0.3048)
			(stroke
				(width 0.1)
				(type default)
			)
			(layer "F.Fab")
		)
		(fp_line
			(start 0.12065 -0.2794)
			(end 0.12065 -0.3048)
			(stroke
				(width 0.1)
				(type default)
			)
			(layer "F.Fab")
		)
		(fp_line
			(start 0.67945 -0.3048)
			(end 0.67945 0.3048)
			(stroke
				(width 0.1)
				(type default)
			)
			(layer "F.Fab")
		)
		(fp_line
			(start 0.67945 0.3048)
			(end 0.120396 0.3048)
			(stroke
				(width 0.1)
				(type default)
			)
			(layer "F.Fab")
		)
		(pad "1" smd circle
			(at -0.40005 0)
			(size 0 0)
			(layers "F.Cu" "F.Mask" "F.Paste")
			(net "PVCCIN_CPU1_LSET1")
		)
		(pad "2" smd circle
			(at 0.40005 0)
			(size 0 0)
			(layers "F.Cu" "F.Mask" "F.Paste")
			(net "GND")
		)
	)
	(footprint ""
		(layer "F.Cu")
		(at 155.742386 -64.761364)
		(property "Reference" "U134"
			(at -1.4732 2.041652 0)
			(unlocked yes)
			(layer "F.SilkS")
			(effects
				(font
					(size 0.7874 0.5842)
					(thickness 0.1524)
				)
				(justify left)
			)
		)
		(property "Value" ""
			(at 0 0 0)
			(layer "F.Fab")
			(effects
				(font
					(size 1.27 1.27)
				)
			)
		)
		(duplicate_pad_numbers_are_jumpers no)
		(fp_line
			(start -1.38176 -1.100074)
			(end -1.38176 1.100074)
			(stroke
				(width 0.1524)
				(type default)
			)
			(layer "F.SilkS")
		)
		(fp_line
			(start -1.38176 1.100074)
			(end 1.38176 1.100074)
			(stroke
				(width 0.1524)
				(type default)
			)
			(layer "F.SilkS")
		)
		(fp_line
			(start -0.592074 -1.100074)
			(end -1.38176 -1.100074)
			(stroke
				(width 0.1524)
				(type default)
			)
			(layer "F.SilkS")
		)
		(fp_line
			(start 0 -0.508)
			(end -0.592074 -1.100074)
			(stroke
				(width 0.1524)
				(type default)
			)
			(layer "F.SilkS")
		)
		(fp_line
			(start 0.592074 -1.100074)
			(end 0 -0.508)
			(stroke
				(width 0.1524)
				(type default)
			)
			(layer "F.SilkS")
		)
		(fp_line
			(start 1.38176 -1.100074)
			(end 0.592074 -1.100074)
			(stroke
				(width 0.1524)
				(type default)
			)
			(layer "F.SilkS")
		)
		(fp_line
			(start 1.38176 1.100074)
			(end 1.38176 -1.100074)
			(stroke
				(width 0.1524)
				(type default)
			)
			(layer "F.SilkS")
		)
		(fp_poly
			(pts
				(xy -0.989584 -1.349248) (xy -1.209802 -1.789938) (xy -0.769366 -1.789938)
			)
			(stroke
				(width 0)
				(type default)
			)
			(fill yes)
			(layer "F.SilkS")
		)
		(fp_line
			(start -0.674878 -1.100074)
			(end -0.674878 1.100074)
			(stroke
				(width 0.1)
				(type default)
			)
			(layer "F.Fab")
		)
		(fp_line
			(start -0.674878 1.100074)
			(end 0.674878 1.100074)
			(stroke
				(width 0.1)
				(type default)
			)
			(layer "F.Fab")
		)
		(fp_line
			(start 0.674878 -1.100074)
			(end -0.674878 -1.100074)
			(stroke
				(width 0.1)
				(type default)
			)
			(layer "F.Fab")
		)
		(fp_line
			(start 0.674878 1.100074)
			(end 0.674878 -1.100074)
			(stroke
				(width 0.1)
				(type default)
			)
			(layer "F.Fab")
		)
		(fp_poly
			(pts
				(xy -1.9431 -0.870204) (xy -1.50241 -0.649986) (xy -1.9431 -0.429768)
			)
			(stroke
				(width 0)
				(type default)
			)
			(fill yes)
			(layer "F.Fab")
		)
		(pad "1" smd rect
			(at -0.94996 -0.649986 270)
			(size 0.4318 0.6096)
			(layers "F.Cu" "F.Mask" "F.Paste")
			(net "RST_SMB_E1S_N")
		)
		(pad "2" smd rect
			(at -0.94996 0 270)
			(size 0.4318 0.6096)
			(layers "F.Cu" "F.Mask" "F.Paste")
			(net "GND")
		)
		(pad "3" smd rect
			(at -0.94996 0.649986 270)
			(size 0.4318 0.6096)
			(layers "F.Cu" "F.Mask" "F.Paste")
			(net "RST_SMB_E1S_N")
		)
		(pad "4" smd rect
			(at 0.94996 0.649986 270)
			(size 0.4318 0.6096)
			(layers "F.Cu" "F.Mask" "F.Paste")
			(net "SMB_PCIE_E1S_ISO_EN_R2")
		)
		(pad "5" smd rect
			(at 0.94996 0 270)
			(size 0.4318 0.6096)
			(layers "F.Cu" "F.Mask" "F.Paste")
			(net "P3V3_AUX")
		)
		(pad "6" smd rect
			(at 0.94996 -0.649986 270)
			(size 0.4318 0.6096)
			(layers "F.Cu" "F.Mask" "F.Paste")
			(net "RST_SMB_BUF_E1S_0_N")
		)
	)
	(footprint ""
		(layer "F.Cu")
		(at 421.901874 -5.569966 -90)
		(property "Reference" "J37"
			(at -16.985996 31.63951 0)
			(unlocked yes)
			(layer "F.SilkS")
			(effects
				(font
					(size 0.7874 0.5842)
					(thickness 0.1524)
				)
				(justify left)
			)
		)
		(property "Value" ""
			(at 0 0 270)
			(layer "F.Fab")
			(effects
				(font
					(size 1.27 1.27)
				)
			)
		)
		(duplicate_pad_numbers_are_jumpers no)
		(fp_line
			(start -6.751574 34.360104)
			(end 6.210046 34.360104)
			(stroke
				(width 0.1524)
				(type default)
			)
			(layer "F.SilkS")
		)
		(fp_line
			(start 6.210046 34.360104)
			(end 6.210046 -34.360104)
			(stroke
				(width 0.1524)
				(type default)
			)
			(layer "F.SilkS")
		)
		(fp_line
			(start -5.5499 33.8201)
			(end 5.5499 33.8201)
			(stroke
				(width 0.1524)
				(type default)
			)
			(layer "F.SilkS")
		)
		(fp_line
			(start 5.5499 33.8201)
			(end 5.5499 -33.8201)
			(stroke
				(width 0.1524)
				(type default)
			)
			(layer "F.SilkS")
		)
		(fp_line
			(start -5.5499 30.97784)
			(end -5.5499 33.8201)
			(stroke
				(width 0.1524)
				(type default)
			)
			(layer "F.SilkS")
		)
		(fp_line
			(start -5.5499 9.8806)
			(end -5.5499 14.13256)
			(stroke
				(width 0.1524)
				(type default)
			)
			(layer "F.SilkS")
		)
		(fp_line
			(start -5.5499 -1.9304)
			(end -5.5499 1.4224)
			(stroke
				(width 0.1524)
				(type default)
			)
			(layer "F.SilkS")
		)
		(fp_line
			(start -5.5499 -22.5425)
			(end -5.5499 -18.7833)
			(stroke
				(width 0.1524)
				(type default)
			)
			(layer "F.SilkS")
		)
		(fp_line
			(start -5.5499 -33.8201)
			(end -5.5499 -30.988)
			(stroke
				(width 0.1524)
				(type default)
			)
			(layer "F.SilkS")
		)
		(fp_line
			(start 5.5499 -33.8201)
			(end -5.5499 -33.8201)
			(stroke
				(width 0.1524)
				(type default)
			)
			(layer "F.SilkS")
		)
		(fp_line
			(start -7.420102 -34.360104)
			(end -7.420102 -34.231326)
			(stroke
				(width 0.1524)
				(type default)
			)
			(layer "F.SilkS")
		)
		(fp_line
			(start 6.210046 -34.360104)
			(end -7.420102 -34.360104)
			(stroke
				(width 0.1524)
				(type default)
			)
			(layer "F.SilkS")
		)
		(fp_poly
			(pts
				(xy 5.35178 -17.995138) (xy 5.35178 -19.011138) (xy 4.33578 -18.503138)
			)
			(stroke
				(width 0)
				(type default)
			)
			(fill yes)
			(layer "F.SilkS")
		)
		(fp_line
			(start -5.5499 33.8201)
			(end 5.5499 33.8201)
			(stroke
				(width 0.1)
				(type default)
			)
			(layer "F.Fab")
		)
		(fp_line
			(start 5.5499 33.8201)
			(end 5.5499 -33.8201)
			(stroke
				(width 0.1)
				(type default)
			)
			(layer "F.Fab")
		)
		(fp_line
			(start -5.5499 -33.8201)
			(end -5.5499 33.8201)
			(stroke
				(width 0.1)
				(type default)
			)
			(layer "F.Fab")
		)
		(fp_line
			(start 5.5499 -33.8201)
			(end -5.5499 -33.8201)
			(stroke
				(width 0.1)
				(type default)
			)
			(layer "F.Fab")
		)
		(fp_poly
			(pts
				(xy 7.4168 -17.957038) (xy 7.4168 -18.973038) (xy 6.4008 -18.465038)
			)
			(stroke
				(width 0)
				(type default)
			)
			(fill yes)
			(layer "F.Fab")
		)
		(pad "" np_thru_hole circle
			(at -0.599948 -32.079946 180)
			(size 1.1176 1.1176)
			(drill 1.1176)
			(layers "*.Cu" "*.Mask")
			(clearance 0.381)
			(thermal_gap 0.381)
		)
		(pad "" np_thru_hole circle
			(at 0.40005 32.085026 180)
			(size 1.1176 1.1176)
			(drill 1.1176)
			(layers "*.Cu" "*.Mask")
			(clearance 0.381)
			(thermal_gap 0.381)
		)
		(pad "A1" smd rect
			(at -2.750058 -18.465038 180)
			(size 0.381 1.4478)
			(layers "F.Cu" "F.Mask" "F.Paste")
			(net "GND")
		)
		(pad "A2" smd rect
			(at -2.750058 -17.86509 180)
			(size 0.381 1.4478)
			(layers "F.Cu" "F.Mask" "F.Paste")
			(net "GND")
		)
		(pad "A3" smd rect
			(at -2.750058 -17.264888 180)
			(size 0.381 1.4478)
			(layers "F.Cu" "F.Mask" "F.Paste")
			(net "GND")
		)
		(pad "A4" smd rect
			(at -2.750058 -16.66494 180)
			(size 0.381 1.4478)
			(layers "F.Cu" "F.Mask" "F.Paste")
			(net "GND")
		)
		(pad "A5" smd rect
			(at -2.750058 -16.064992 180)
			(size 0.381 1.4478)
			(layers "F.Cu" "F.Mask" "F.Paste")
			(net "GND")
		)
		(pad "A6" smd rect
			(at -2.750058 -15.465044 180)
			(size 0.381 1.4478)
			(layers "F.Cu" "F.Mask" "F.Paste")
			(net "GND")
		)
		(pad "A7" smd rect
			(at -2.750058 -14.865096 180)
			(size 0.381 1.4478)
			(layers "F.Cu" "F.Mask" "F.Paste")
			(net "SMB_OCP_SFF_3V3AUX_BUF_R_SCL")
		)
		(pad "A8" smd rect
			(at -2.750058 -14.264894 180)
			(size 0.381 1.4478)
			(layers "F.Cu" "F.Mask" "F.Paste")
			(net "SMB_OCP_SFF_3V3AUX_BUF_R_SDA")
		)
		(pad "A9" smd rect
			(at -2.750058 -13.664946 180)
			(size 0.381 1.4478)
			(layers "F.Cu" "F.Mask" "F.Paste")
			(net "RST_SMB_OCP_SFF_N")
		)
		(pad "A10" smd rect
			(at -2.750058 -13.064998 180)
			(size 0.381 1.4478)
			(layers "F.Cu" "F.Mask" "F.Paste")
			(net "OCP_SFF_PRSNTA_R_N")
		)
		(pad "A11" smd rect
			(at -2.750058 -12.46505 180)
			(size 0.381 1.4478)
			(layers "F.Cu" "F.Mask" "F.Paste")
			(net "RST_PERST1_OCP_SFF_N")
		)
		(pad "A12" smd rect
			(at -2.750058 -11.865102 180)
			(size 0.381 1.4478)
			(layers "F.Cu" "F.Mask" "F.Paste")
			(net "OCP_SFF_PRSNT2_R_N")
		)
		(pad "A13" smd rect
			(at -2.750058 -11.2649 180)
			(size 0.381 1.4478)
			(layers "F.Cu" "F.Mask" "F.Paste")
			(net "GND")
		)
		(pad "A14" smd rect
			(at -2.750058 -10.664952 180)
			(size 0.381 1.4478)
			(layers "F.Cu" "F.Mask" "F.Paste")
			(net "CLK_100M_OCP_SFF_1_DN")
		)
		(pad "A15" smd rect
			(at -2.750058 -10.065004 180)
			(size 0.381 1.4478)
			(layers "F.Cu" "F.Mask" "F.Paste")
			(net "CLK_100M_OCP_SFF_1_DP")
		)
		(pad "A16" smd rect
			(at -2.750058 -9.465056 180)
			(size 0.381 1.4478)
			(layers "F.Cu" "F.Mask" "F.Paste")
			(net "GND")
		)
		(pad "A17" smd rect
			(at -2.750058 -8.865108 180)
			(size 0.381 1.4478)
			(layers "F.Cu" "F.Mask" "F.Paste")
			(net "P5E_CPU0_PE1_RX_DN<0>")
		)
		(pad "A18" smd rect
			(at -2.750058 -8.264906 180)
			(size 0.381 1.4478)
			(layers "F.Cu" "F.Mask" "F.Paste")
			(net "P5E_CPU0_PE1_RX_DP<0>")
		)
		(pad "A19" smd rect
			(at -2.750058 -7.664958 180)
			(size 0.381 1.4478)
			(layers "F.Cu" "F.Mask" "F.Paste")
			(net "GND")
		)
		(pad "A20" smd rect
			(at -2.750058 -7.06501 180)
			(size 0.381 1.4478)
			(layers "F.Cu" "F.Mask" "F.Paste")
			(net "P5E_CPU0_PE1_RX_DP<1>")
		)
		(pad "A21" smd rect
			(at -2.750058 -6.465062 180)
			(size 0.381 1.4478)
			(layers "F.Cu" "F.Mask" "F.Paste")
			(net "P5E_CPU0_PE1_RX_DN<1>")
		)
		(pad "A22" smd rect
			(at -2.750058 -5.865114 180)
			(size 0.381 1.4478)
			(layers "F.Cu" "F.Mask" "F.Paste")
			(net "GND")
		)
		(pad "A23" smd rect
			(at -2.750058 -5.264912 180)
			(size 0.381 1.4478)
			(layers "F.Cu" "F.Mask" "F.Paste")
			(net "P5E_CPU0_PE1_RX_DP<2>")
		)
		(pad "A24" smd rect
			(at -2.750058 -4.664964 180)
			(size 0.381 1.4478)
			(layers "F.Cu" "F.Mask" "F.Paste")
			(net "P5E_CPU0_PE1_RX_DN<2>")
		)
		(pad "A25" smd rect
			(at -2.750058 -4.065016 180)
			(size 0.381 1.4478)
			(layers "F.Cu" "F.Mask" "F.Paste")
			(net "GND")
		)
		(pad "A26" smd rect
			(at -2.750058 -3.465068 180)
			(size 0.381 1.4478)
			(layers "F.Cu" "F.Mask" "F.Paste")
			(net "P5E_CPU0_PE1_RX_DP<3>")
		)
		(pad "A27" smd rect
			(at -2.750058 -2.86512 180)
			(size 0.381 1.4478)
			(layers "F.Cu" "F.Mask" "F.Paste")
			(net "P5E_CPU0_PE1_RX_DN<3>")
		)
		(pad "A28" smd rect
			(at -2.750058 -2.264918 180)
			(size 0.381 1.4478)
			(layers "F.Cu" "F.Mask" "F.Paste")
			(net "GND")
		)
		(pad "A29" smd rect
			(at -2.750058 1.74498 180)
			(size 0.381 1.4478)
			(layers "F.Cu" "F.Mask" "F.Paste")
			(net "GND")
		)
		(pad "A30" smd rect
			(at -2.750058 2.344928 180)
			(size 0.381 1.4478)
			(layers "F.Cu" "F.Mask" "F.Paste")
			(net "P5E_CPU0_PE1_RX_DP<4>")
		)
		(pad "A31" smd rect
			(at -2.750058 2.944876 180)
			(size 0.381 1.4478)
			(layers "F.Cu" "F.Mask" "F.Paste")
			(net "P5E_CPU0_PE1_RX_DN<4>")
		)
		(pad "A32" smd rect
			(at -2.750058 3.545078 180)
			(size 0.381 1.4478)
			(layers "F.Cu" "F.Mask" "F.Paste")
			(net "GND")
		)
		(pad "A33" smd rect
			(at -2.750058 4.145026 180)
			(size 0.381 1.4478)
			(layers "F.Cu" "F.Mask" "F.Paste")
			(net "P5E_CPU0_PE1_RX_DP<5>")
		)
		(pad "A34" smd rect
			(at -2.750058 4.744974 180)
			(size 0.381 1.4478)
			(layers "F.Cu" "F.Mask" "F.Paste")
			(net "P5E_CPU0_PE1_RX_DN<5>")
		)
		(pad "A35" smd rect
			(at -2.750058 5.344922 180)
			(size 0.381 1.4478)
			(layers "F.Cu" "F.Mask" "F.Paste")
			(net "GND")
		)
		(pad "A36" smd rect
			(at -2.750058 5.945124 180)
			(size 0.381 1.4478)
			(layers "F.Cu" "F.Mask" "F.Paste")
			(net "P5E_CPU0_PE1_RX_DP<6>")
		)
		(pad "A37" smd rect
			(at -2.750058 6.545072 180)
			(size 0.381 1.4478)
			(layers "F.Cu" "F.Mask" "F.Paste")
			(net "P5E_CPU0_PE1_RX_DN<6>")
		)
		(pad "A38" smd rect
			(at -2.750058 7.14502 180)
			(size 0.381 1.4478)
			(layers "F.Cu" "F.Mask" "F.Paste")
			(net "GND")
		)
		(pad "A39" smd rect
			(at -2.750058 7.744968 180)
			(size 0.381 1.4478)
			(layers "F.Cu" "F.Mask" "F.Paste")
			(net "P5E_CPU0_PE1_RX_DP<7>")
		)
		(pad "A40" smd rect
			(at -2.750058 8.344916 180)
			(size 0.381 1.4478)
			(layers "F.Cu" "F.Mask" "F.Paste")
			(net "P5E_CPU0_PE1_RX_DN<7>")
		)
		(pad "A41" smd rect
			(at -2.750058 8.945118 180)
			(size 0.381 1.4478)
			(layers "F.Cu" "F.Mask" "F.Paste")
			(net "GND")
		)
		(pad "A42" smd rect
			(at -2.750058 9.545066 180)
			(size 0.381 1.4478)
			(layers "F.Cu" "F.Mask" "F.Paste")
			(net "OCP_SFF_PRSNT1_R_N")
		)
		(pad "A43" smd rect
			(at -2.750058 14.454886 180)
			(size 0.381 1.4478)
			(layers "F.Cu" "F.Mask" "F.Paste")
			(net "GND")
		)
		(pad "A44" smd rect
			(at -2.750058 15.055088 180)
			(size 0.381 1.4478)
			(layers "F.Cu" "F.Mask" "F.Paste")
			(net "P5E_CPU0_PE1_RX_DP<8>")
		)
		(pad "A45" smd rect
			(at -2.750058 15.655036 180)
			(size 0.381 1.4478)
			(layers "F.Cu" "F.Mask" "F.Paste")
			(net "P5E_CPU0_PE1_RX_DN<8>")
		)
		(pad "A46" smd rect
			(at -2.750058 16.254984 180)
			(size 0.381 1.4478)
			(layers "F.Cu" "F.Mask" "F.Paste")
			(net "GND")
		)
		(pad "A47" smd rect
			(at -2.750058 16.854932 180)
			(size 0.381 1.4478)
			(layers "F.Cu" "F.Mask" "F.Paste")
			(net "P5E_CPU0_PE1_RX_DP<9>")
		)
		(pad "A48" smd rect
			(at -2.750058 17.45488 180)
			(size 0.381 1.4478)
			(layers "F.Cu" "F.Mask" "F.Paste")
			(net "P5E_CPU0_PE1_RX_DN<9>")
		)
		(pad "A49" smd rect
			(at -2.750058 18.055082 180)
			(size 0.381 1.4478)
			(layers "F.Cu" "F.Mask" "F.Paste")
			(net "GND")
		)
		(pad "A50" smd rect
			(at -2.750058 18.65503 180)
			(size 0.381 1.4478)
			(layers "F.Cu" "F.Mask" "F.Paste")
			(net "P5E_CPU0_PE1_RX_DP<10>")
		)
		(pad "A51" smd rect
			(at -2.750058 19.254978 180)
			(size 0.381 1.4478)
			(layers "F.Cu" "F.Mask" "F.Paste")
			(net "P5E_CPU0_PE1_RX_DN<10>")
		)
		(pad "A52" smd rect
			(at -2.750058 19.854926 180)
			(size 0.381 1.4478)
			(layers "F.Cu" "F.Mask" "F.Paste")
			(net "GND")
		)
		(pad "A53" smd rect
			(at -2.750058 20.455128 180)
			(size 0.381 1.4478)
			(layers "F.Cu" "F.Mask" "F.Paste")
			(net "P5E_CPU0_PE1_RX_DP<11>")
		)
		(pad "A54" smd rect
			(at -2.750058 21.055076 180)
			(size 0.381 1.4478)
			(layers "F.Cu" "F.Mask" "F.Paste")
			(net "P5E_CPU0_PE1_RX_DN<11>")
		)
		(pad "A55" smd rect
			(at -2.750058 21.655024 180)
			(size 0.381 1.4478)
			(layers "F.Cu" "F.Mask" "F.Paste")
			(net "GND")
		)
		(pad "A56" smd rect
			(at -2.750058 22.254972 180)
			(size 0.381 1.4478)
			(layers "F.Cu" "F.Mask" "F.Paste")
			(net "P5E_CPU0_PE1_RX_DP<12>")
		)
		(pad "A57" smd rect
			(at -2.750058 22.85492 180)
			(size 0.381 1.4478)
			(layers "F.Cu" "F.Mask" "F.Paste")
			(net "P5E_CPU0_PE1_RX_DN<12>")
		)
		(pad "A58" smd rect
			(at -2.750058 23.455122 180)
			(size 0.381 1.4478)
			(layers "F.Cu" "F.Mask" "F.Paste")
			(net "GND")
		)
		(pad "A59" smd rect
			(at -2.750058 24.05507 180)
			(size 0.381 1.4478)
			(layers "F.Cu" "F.Mask" "F.Paste")
			(net "P5E_CPU0_PE1_RX_DP<13>")
		)
		(pad "A60" smd rect
			(at -2.750058 24.655018 180)
			(size 0.381 1.4478)
			(layers "F.Cu" "F.Mask" "F.Paste")
			(net "P5E_CPU0_PE1_RX_DN<13>")
		)
		(pad "A61" smd rect
			(at -2.750058 25.254966 180)
			(size 0.381 1.4478)
			(layers "F.Cu" "F.Mask" "F.Paste")
			(net "GND")
		)
		(pad "A62" smd rect
			(at -2.750058 25.854914 180)
			(size 0.381 1.4478)
			(layers "F.Cu" "F.Mask" "F.Paste")
			(net "P5E_CPU0_PE1_RX_DP<14>")
		)
		(pad "A63" smd rect
			(at -2.750058 26.455116 180)
			(size 0.381 1.4478)
			(layers "F.Cu" "F.Mask" "F.Paste")
			(net "P5E_CPU0_PE1_RX_DN<14>")
		)
		(pad "A64" smd rect
			(at -2.750058 27.055064 180)
			(size 0.381 1.4478)
			(layers "F.Cu" "F.Mask" "F.Paste")
			(net "GND")
		)
		(pad "A65" smd rect
			(at -2.750058 27.655012 180)
			(size 0.381 1.4478)
			(layers "F.Cu" "F.Mask" "F.Paste")
			(net "P5E_CPU0_PE1_RX_DP<15>")
		)
		(pad "A66" smd rect
			(at -2.750058 28.25496 180)
			(size 0.381 1.4478)
			(layers "F.Cu" "F.Mask" "F.Paste")
			(net "P5E_CPU0_PE1_RX_DN<15>")
		)
		(pad "A67" smd rect
			(at -2.750058 28.854908 180)
			(size 0.381 1.4478)
			(layers "F.Cu" "F.Mask" "F.Paste")
			(net "GND")
		)
		(pad "A68" smd rect
			(at -2.750058 29.45511 180)
			(size 0.381 1.4478)
			(layers "F.Cu" "F.Mask" "F.Paste")
			(net "OCP_SFF_USB2_3_DN")
		)
		(pad "A69" smd rect
			(at -2.750058 30.055058 180)
			(size 0.381 1.4478)
			(layers "F.Cu" "F.Mask" "F.Paste")
			(net "OCP_SFF_USB2_3_DP")
		)
		(pad "A70" smd rect
			(at -2.750058 30.655006 180)
			(size 0.381 1.4478)
			(layers "F.Cu" "F.Mask" "F.Paste")
			(net "OCP_SFF_PWRBRK_N")
		)
		(pad "B1" smd rect
			(at -5.700014 -18.465038 180)
			(size 0.381 1.4478)
			(layers "F.Cu" "F.Mask" "F.Paste")
			(net "P12V_OCP_SFF")
		)
		(pad "B2" smd rect
			(at -5.700014 -17.86509 180)
			(size 0.381 1.4478)
			(layers "F.Cu" "F.Mask" "F.Paste")
			(net "P12V_OCP_SFF")
		)
		(pad "B3" smd rect
			(at -5.700014 -17.264888 180)
			(size 0.381 1.4478)
			(layers "F.Cu" "F.Mask" "F.Paste")
			(net "P12V_OCP_SFF")
		)
		(pad "B4" smd rect
			(at -5.700014 -16.66494 180)
			(size 0.381 1.4478)
			(layers "F.Cu" "F.Mask" "F.Paste")
			(net "P12V_OCP_SFF")
		)
		(pad "B5" smd rect
			(at -5.700014 -16.064992 180)
			(size 0.381 1.4478)
			(layers "F.Cu" "F.Mask" "F.Paste")
			(net "P12V_OCP_SFF")
		)
		(pad "B6" smd rect
			(at -5.700014 -15.465044 180)
			(size 0.381 1.4478)
			(layers "F.Cu" "F.Mask" "F.Paste")
			(net "P12V_OCP_SFF")
		)
		(pad "B7" smd rect
			(at -5.700014 -14.865096 180)
			(size 0.381 1.4478)
			(layers "F.Cu" "F.Mask" "F.Paste")
			(net "OCP_SFF_BIF0_R_N")
		)
		(pad "B8" smd rect
			(at -5.700014 -14.264894 180)
			(size 0.381 1.4478)
			(layers "F.Cu" "F.Mask" "F.Paste")
			(net "OCP_SFF_BIF1_R_N")
		)
		(pad "B9" smd rect
			(at -5.700014 -13.664946 180)
			(size 0.381 1.4478)
			(layers "F.Cu" "F.Mask" "F.Paste")
			(net "OCP_SFF_BIF2_R_N")
		)
		(pad "B10" smd rect
			(at -5.700014 -13.064998 180)
			(size 0.381 1.4478)
			(layers "F.Cu" "F.Mask" "F.Paste")
			(net "RST_PERST0_OCP_SFF_N")
		)
		(pad "B11" smd rect
			(at -5.700014 -12.46505 180)
			(size 0.381 1.4478)
			(layers "F.Cu" "F.Mask" "F.Paste")
			(net "P3V3_OCP_SFF")
		)
		(pad "B12" smd rect
			(at -5.700014 -11.865102 180)
			(size 0.381 1.4478)
			(layers "F.Cu" "F.Mask" "F.Paste")
			(net "OCP_SFF_AUX_PWR_EN_R")
		)
		(pad "B13" smd rect
			(at -5.700014 -11.2649 180)
			(size 0.381 1.4478)
			(layers "F.Cu" "F.Mask" "F.Paste")
			(net "GND")
		)
		(pad "B14" smd rect
			(at -5.700014 -10.664952 180)
			(size 0.381 1.4478)
			(layers "F.Cu" "F.Mask" "F.Paste")
			(net "CLK_100M_OCP_SFF_0_DN")
		)
		(pad "B15" smd rect
			(at -5.700014 -10.065004 180)
			(size 0.381 1.4478)
			(layers "F.Cu" "F.Mask" "F.Paste")
			(net "CLK_100M_OCP_SFF_0_DP")
		)
		(pad "B16" smd rect
			(at -5.700014 -9.465056 180)
			(size 0.381 1.4478)
			(layers "F.Cu" "F.Mask" "F.Paste")
			(net "GND")
		)
		(pad "B17" smd rect
			(at -5.700014 -8.865108 180)
			(size 0.381 1.4478)
			(layers "F.Cu" "F.Mask" "F.Paste")
			(net "P5E_CPU0_PE1_TX_C_DN<0>")
		)
		(pad "B18" smd rect
			(at -5.700014 -8.264906 180)
			(size 0.381 1.4478)
			(layers "F.Cu" "F.Mask" "F.Paste")
			(net "P5E_CPU0_PE1_TX_C_DP<0>")
		)
		(pad "B19" smd rect
			(at -5.700014 -7.664958 180)
			(size 0.381 1.4478)
			(layers "F.Cu" "F.Mask" "F.Paste")
			(net "GND")
		)
		(pad "B20" smd rect
			(at -5.700014 -7.06501 180)
			(size 0.381 1.4478)
			(layers "F.Cu" "F.Mask" "F.Paste")
			(net "P5E_CPU0_PE1_TX_C_DN<1>")
		)
		(pad "B21" smd rect
			(at -5.700014 -6.465062 180)
			(size 0.381 1.4478)
			(layers "F.Cu" "F.Mask" "F.Paste")
			(net "P5E_CPU0_PE1_TX_C_DP<1>")
		)
		(pad "B22" smd rect
			(at -5.700014 -5.865114 180)
			(size 0.381 1.4478)
			(layers "F.Cu" "F.Mask" "F.Paste")
			(net "GND")
		)
		(pad "B23" smd rect
			(at -5.700014 -5.264912 180)
			(size 0.381 1.4478)
			(layers "F.Cu" "F.Mask" "F.Paste")
			(net "P5E_CPU0_PE1_TX_C_DP<2>")
		)
		(pad "B24" smd rect
			(at -5.700014 -4.664964 180)
			(size 0.381 1.4478)
			(layers "F.Cu" "F.Mask" "F.Paste")
			(net "P5E_CPU0_PE1_TX_C_DN<2>")
		)
		(pad "B25" smd rect
			(at -5.700014 -4.065016 180)
			(size 0.381 1.4478)
			(layers "F.Cu" "F.Mask" "F.Paste")
			(net "GND")
		)
		(pad "B26" smd rect
			(at -5.700014 -3.465068 180)
			(size 0.381 1.4478)
			(layers "F.Cu" "F.Mask" "F.Paste")
			(net "P5E_CPU0_PE1_TX_C_DN<3>")
		)
		(pad "B27" smd rect
			(at -5.700014 -2.86512 180)
			(size 0.381 1.4478)
			(layers "F.Cu" "F.Mask" "F.Paste")
			(net "P5E_CPU0_PE1_TX_C_DP<3>")
		)
		(pad "B28" smd rect
			(at -5.700014 -2.264918 180)
			(size 0.381 1.4478)
			(layers "F.Cu" "F.Mask" "F.Paste")
			(net "GND")
		)
		(pad "B29" smd rect
			(at -5.700014 1.74498 180)
			(size 0.381 1.4478)
			(layers "F.Cu" "F.Mask" "F.Paste")
			(net "GND")
		)
		(pad "B30" smd rect
			(at -5.700014 2.344928 180)
			(size 0.381 1.4478)
			(layers "F.Cu" "F.Mask" "F.Paste")
			(net "P5E_CPU0_PE1_TX_C_DP<4>")
		)
		(pad "B31" smd rect
			(at -5.700014 2.944876 180)
			(size 0.381 1.4478)
			(layers "F.Cu" "F.Mask" "F.Paste")
			(net "P5E_CPU0_PE1_TX_C_DN<4>")
		)
		(pad "B32" smd rect
			(at -5.700014 3.545078 180)
			(size 0.381 1.4478)
			(layers "F.Cu" "F.Mask" "F.Paste")
			(net "GND")
		)
		(pad "B33" smd rect
			(at -5.700014 4.145026 180)
			(size 0.381 1.4478)
			(layers "F.Cu" "F.Mask" "F.Paste")
			(net "P5E_CPU0_PE1_TX_C_DN<5>")
		)
		(pad "B34" smd rect
			(at -5.700014 4.744974 180)
			(size 0.381 1.4478)
			(layers "F.Cu" "F.Mask" "F.Paste")
			(net "P5E_CPU0_PE1_TX_C_DP<5>")
		)
		(pad "B35" smd rect
			(at -5.700014 5.344922 180)
			(size 0.381 1.4478)
			(layers "F.Cu" "F.Mask" "F.Paste")
			(net "GND")
		)
		(pad "B36" smd rect
			(at -5.700014 5.945124 180)
			(size 0.381 1.4478)
			(layers "F.Cu" "F.Mask" "F.Paste")
			(net "P5E_CPU0_PE1_TX_C_DP<6>")
		)
		(pad "B37" smd rect
			(at -5.700014 6.545072 180)
			(size 0.381 1.4478)
			(layers "F.Cu" "F.Mask" "F.Paste")
			(net "P5E_CPU0_PE1_TX_C_DN<6>")
		)
		(pad "B38" smd rect
			(at -5.700014 7.14502 180)
			(size 0.381 1.4478)
			(layers "F.Cu" "F.Mask" "F.Paste")
			(net "GND")
		)
		(pad "B39" smd rect
			(at -5.700014 7.744968 180)
			(size 0.381 1.4478)
			(layers "F.Cu" "F.Mask" "F.Paste")
			(net "P5E_CPU0_PE1_TX_C_DN<7>")
		)
		(pad "B40" smd rect
			(at -5.700014 8.344916 180)
			(size 0.381 1.4478)
			(layers "F.Cu" "F.Mask" "F.Paste")
			(net "P5E_CPU0_PE1_TX_C_DP<7>")
		)
		(pad "B41" smd rect
			(at -5.700014 8.945118 180)
			(size 0.381 1.4478)
			(layers "F.Cu" "F.Mask" "F.Paste")
			(net "GND")
		)
		(pad "B42" smd rect
			(at -5.700014 9.545066 180)
			(size 0.381 1.4478)
			(layers "F.Cu" "F.Mask" "F.Paste")
			(net "OCP_SFF_PRSNT0_R_N")
		)
		(pad "B43" smd rect
			(at -5.700014 14.454886 180)
			(size 0.381 1.4478)
			(layers "F.Cu" "F.Mask" "F.Paste")
			(net "GND")
		)
		(pad "B44" smd rect
			(at -5.700014 15.055088 180)
			(size 0.381 1.4478)
			(layers "F.Cu" "F.Mask" "F.Paste")
			(net "P5E_CPU0_PE1_TX_C_DP<8>")
		)
		(pad "B45" smd rect
			(at -5.700014 15.655036 180)
			(size 0.381 1.4478)
			(layers "F.Cu" "F.Mask" "F.Paste")
			(net "P5E_CPU0_PE1_TX_C_DN<8>")
		)
		(pad "B46" smd rect
			(at -5.700014 16.254984 180)
			(size 0.381 1.4478)
			(layers "F.Cu" "F.Mask" "F.Paste")
			(net "GND")
		)
		(pad "B47" smd rect
			(at -5.700014 16.854932 180)
			(size 0.381 1.4478)
			(layers "F.Cu" "F.Mask" "F.Paste")
			(net "P5E_CPU0_PE1_TX_C_DN<9>")
		)
		(pad "B48" smd rect
			(at -5.700014 17.45488 180)
			(size 0.381 1.4478)
			(layers "F.Cu" "F.Mask" "F.Paste")
			(net "P5E_CPU0_PE1_TX_C_DP<9>")
		)
		(pad "B49" smd rect
			(at -5.700014 18.055082 180)
			(size 0.381 1.4478)
			(layers "F.Cu" "F.Mask" "F.Paste")
			(net "GND")
		)
		(pad "B50" smd rect
			(at -5.700014 18.65503 180)
			(size 0.381 1.4478)
			(layers "F.Cu" "F.Mask" "F.Paste")
			(net "P5E_CPU0_PE1_TX_C_DP<10>")
		)
		(pad "B51" smd rect
			(at -5.700014 19.254978 180)
			(size 0.381 1.4478)
			(layers "F.Cu" "F.Mask" "F.Paste")
			(net "P5E_CPU0_PE1_TX_C_DN<10>")
		)
		(pad "B52" smd rect
			(at -5.700014 19.854926 180)
			(size 0.381 1.4478)
			(layers "F.Cu" "F.Mask" "F.Paste")
			(net "GND")
		)
		(pad "B53" smd rect
			(at -5.700014 20.455128 180)
			(size 0.381 1.4478)
			(layers "F.Cu" "F.Mask" "F.Paste")
			(net "P5E_CPU0_PE1_TX_C_DN<11>")
		)
		(pad "B54" smd rect
			(at -5.700014 21.055076 180)
			(size 0.381 1.4478)
			(layers "F.Cu" "F.Mask" "F.Paste")
			(net "P5E_CPU0_PE1_TX_C_DP<11>")
		)
		(pad "B55" smd rect
			(at -5.700014 21.655024 180)
			(size 0.381 1.4478)
			(layers "F.Cu" "F.Mask" "F.Paste")
			(net "GND")
		)
		(pad "B56" smd rect
			(at -5.700014 22.254972 180)
			(size 0.381 1.4478)
			(layers "F.Cu" "F.Mask" "F.Paste")
			(net "P5E_CPU0_PE1_TX_C_DP<12>")
		)
		(pad "B57" smd rect
			(at -5.700014 22.85492 180)
			(size 0.381 1.4478)
			(layers "F.Cu" "F.Mask" "F.Paste")
			(net "P5E_CPU0_PE1_TX_C_DN<12>")
		)
		(pad "B58" smd rect
			(at -5.700014 23.455122 180)
			(size 0.381 1.4478)
			(layers "F.Cu" "F.Mask" "F.Paste")
			(net "GND")
		)
		(pad "B59" smd rect
			(at -5.700014 24.05507 180)
			(size 0.381 1.4478)
			(layers "F.Cu" "F.Mask" "F.Paste")
			(net "P5E_CPU0_PE1_TX_C_DN<13>")
		)
		(pad "B60" smd rect
			(at -5.700014 24.655018 180)
			(size 0.381 1.4478)
			(layers "F.Cu" "F.Mask" "F.Paste")
			(net "P5E_CPU0_PE1_TX_C_DP<13>")
		)
		(pad "B61" smd rect
			(at -5.700014 25.254966 180)
			(size 0.381 1.4478)
			(layers "F.Cu" "F.Mask" "F.Paste")
			(net "GND")
		)
		(pad "B62" smd rect
			(at -5.700014 25.854914 180)
			(size 0.381 1.4478)
			(layers "F.Cu" "F.Mask" "F.Paste")
			(net "P5E_CPU0_PE1_TX_C_DP<14>")
		)
		(pad "B63" smd rect
			(at -5.700014 26.455116 180)
			(size 0.381 1.4478)
			(layers "F.Cu" "F.Mask" "F.Paste")
			(net "P5E_CPU0_PE1_TX_C_DN<14>")
		)
		(pad "B64" smd rect
			(at -5.700014 27.055064 180)
			(size 0.381 1.4478)
			(layers "F.Cu" "F.Mask" "F.Paste")
			(net "GND")
		)
		(pad "B65" smd rect
			(at -5.700014 27.655012 180)
			(size 0.381 1.4478)
			(layers "F.Cu" "F.Mask" "F.Paste")
			(net "P5E_CPU0_PE1_TX_C_DN<15>")
		)
		(pad "B66" smd rect
			(at -5.700014 28.25496 180)
			(size 0.381 1.4478)
			(layers "F.Cu" "F.Mask" "F.Paste")
			(net "P5E_CPU0_PE1_TX_C_DP<15>")
		)
		(pad "B67" smd rect
			(at -5.700014 28.854908 180)
			(size 0.381 1.4478)
			(layers "F.Cu" "F.Mask" "F.Paste")
			(net "GND")
		)
		(pad "B68" smd rect
			(at -5.700014 29.45511 180)
			(size 0.381 1.4478)
			(layers "F.Cu" "F.Mask" "F.Paste")
			(net "TP_OCP_SFF_B68")
		)
		(pad "B69" smd rect
			(at -5.700014 30.055058 180)
			(size 0.381 1.4478)
			(layers "F.Cu" "F.Mask" "F.Paste")
			(net "TP_OCP_SFF_B69")
		)
		(pad "B70" smd rect
			(at -5.700014 30.655006 180)
			(size 0.381 1.4478)
			(layers "F.Cu" "F.Mask" "F.Paste")
			(net "OCP_SFF_PRSNT3_R_N")
		)
		(pad "G1" thru_hole circle
			(at 2.400046 -32.759904 180)
			(size 1.6256 1.6256)
			(drill 1.1176)
			(layers "*.Cu" "*.Mask")
			(remove_unused_layers no)
			(net "GND")
			(clearance 0)
		)
		(pad "G2" thru_hole circle
			(at 2.400046 -20.379944 180)
			(size 1.6256 1.6256)
			(drill 1.1176)
			(layers "*.Cu" "*.Mask")
			(remove_unused_layers no)
			(net "GND")
			(clearance 0)
		)
		(pad "G3" thru_hole circle
			(at 2.400046 0 180)
			(size 1.6256 1.6256)
			(drill 1.1176)
			(layers "*.Cu" "*.Mask")
			(remove_unused_layers no)
			(net "GND")
			(clearance 0)
		)
		(pad "G4" thru_hole circle
			(at 2.400046 12.5349 180)
			(size 1.6256 1.6256)
			(drill 1.1176)
			(layers "*.Cu" "*.Mask")
			(remove_unused_layers no)
			(net "GND")
			(clearance 0)
		)
		(pad "G5" thru_hole circle
			(at 2.400046 32.759904 180)
			(size 1.6256 1.6256)
			(drill 1.1176)
			(layers "*.Cu" "*.Mask")
			(remove_unused_layers no)
			(net "GND")
			(clearance 0)
		)
		(pad "OA1" smd rect
			(at -2.750058 -30.660086 180)
			(size 0.381 1.4478)
			(layers "F.Cu" "F.Mask" "F.Paste")
			(net "RST_PERST2_OCP_SFF_N")
		)
		(pad "OA2" smd rect
			(at -2.750058 -30.059884 180)
			(size 0.381 1.4478)
			(layers "F.Cu" "F.Mask" "F.Paste")
			(net "RST_PERST3_OCP_SFF_N")
		)
		(pad "OA3" smd rect
			(at -2.750058 -29.459936 180)
			(size 0.381 1.4478)
			(layers "F.Cu" "F.Mask" "F.Paste")
			(net "IRQ_LVC3_OCP_SFF_WAKE_N")
		)
		(pad "OA4" smd rect
			(at -2.750058 -28.859988 180)
			(size 0.381 1.4478)
			(layers "F.Cu" "F.Mask" "F.Paste")
			(net "OCP_SFF_ISO1_RBT_ARB_IN")
		)
		(pad "OA5" smd rect
			(at -2.750058 -28.26004 180)
			(size 0.381 1.4478)
			(layers "F.Cu" "F.Mask" "F.Paste")
			(net "OCP_SFF_ISO2_RBT_ARB_OUT")
		)
		(pad "OA6" smd rect
			(at -2.750058 -27.660092 180)
			(size 0.381 1.4478)
			(layers "F.Cu" "F.Mask" "F.Paste")
			(net "OCP_SFF_ID1")
		)
		(pad "OA7" smd rect
			(at -2.750058 -27.05989 180)
			(size 0.381 1.4478)
			(layers "F.Cu" "F.Mask" "F.Paste")
			(net "NCSI_OCP_SFF_TX_EN")
		)
		(pad "OA8" smd rect
			(at -2.750058 -26.459942 180)
			(size 0.381 1.4478)
			(layers "F.Cu" "F.Mask" "F.Paste")
			(net "NCSI_OCP_SFF_TXD1")
		)
		(pad "OA9" smd rect
			(at -2.750058 -25.859994 180)
			(size 0.381 1.4478)
			(layers "F.Cu" "F.Mask" "F.Paste")
			(net "NCSI_OCP_SFF_TXD0")
		)
		(pad "OA10" smd rect
			(at -2.750058 -25.260046 180)
			(size 0.381 1.4478)
			(layers "F.Cu" "F.Mask" "F.Paste")
			(net "GND")
		)
		(pad "OA11" smd rect
			(at -2.750058 -24.660098 180)
			(size 0.381 1.4478)
			(layers "F.Cu" "F.Mask" "F.Paste")
			(net "CLK_100M_OCP_SFF_3_DN")
		)
		(pad "OA12" smd rect
			(at -2.750058 -24.059896 180)
			(size 0.381 1.4478)
			(layers "F.Cu" "F.Mask" "F.Paste")
			(net "CLK_100M_OCP_SFF_3_DP")
		)
		(pad "OA13" smd rect
			(at -2.750058 -23.459948 180)
			(size 0.381 1.4478)
			(layers "F.Cu" "F.Mask" "F.Paste")
			(net "GND")
		)
		(pad "OA14" smd rect
			(at -2.750058 -22.86 180)
			(size 0.381 1.4478)
			(layers "F.Cu" "F.Mask" "F.Paste")
			(net "CLK_50M_NCSI_OCP_SFF_ISO")
		)
		(pad "OB1" smd rect
			(at -5.700014 -30.660086 180)
			(size 0.381 1.4478)
			(layers "F.Cu" "F.Mask" "F.Paste")
			(net "FM_OCP_SFF_PWR_GOOD")
		)
		(pad "OB2" smd rect
			(at -5.700014 -30.059884 180)
			(size 0.381 1.4478)
			(layers "F.Cu" "F.Mask" "F.Paste")
			(net "OCP_SFF_MAIN_PWR_EN_R")
		)
		(pad "OB3" smd rect
			(at -5.700014 -29.459936 180)
			(size 0.381 1.4478)
			(layers "F.Cu" "F.Mask" "F.Paste")
			(net "SGPIO_OCP_SFF_LD_N")
		)
		(pad "OB4" smd rect
			(at -5.700014 -28.859988 180)
			(size 0.381 1.4478)
			(layers "F.Cu" "F.Mask" "F.Paste")
			(net "SGPIO_OCP_SFF_DATAIN")
		)
		(pad "OB5" smd rect
			(at -5.700014 -28.26004 180)
			(size 0.381 1.4478)
			(layers "F.Cu" "F.Mask" "F.Paste")
			(net "SGPIO_OCP_SFF_DATAOUT")
		)
		(pad "OB6" smd rect
			(at -5.700014 -27.660092 180)
			(size 0.381 1.4478)
			(layers "F.Cu" "F.Mask" "F.Paste")
			(net "SGPIO_OCP_SFF_CLK")
		)
		(pad "OB7" smd rect
			(at -5.700014 -27.05989 180)
			(size 0.381 1.4478)
			(layers "F.Cu" "F.Mask" "F.Paste")
			(net "OCP_SFF_ID0")
		)
		(pad "OB8" smd rect
			(at -5.700014 -26.459942 180)
			(size 0.381 1.4478)
			(layers "F.Cu" "F.Mask" "F.Paste")
			(net "NCSI_OCP_SFF_RXD1")
		)
		(pad "OB9" smd rect
			(at -5.700014 -25.859994 180)
			(size 0.381 1.4478)
			(layers "F.Cu" "F.Mask" "F.Paste")
			(net "NCSI_OCP_SFF_RXD0")
		)
		(pad "OB10" smd rect
			(at -5.700014 -25.260046 180)
			(size 0.381 1.4478)
			(layers "F.Cu" "F.Mask" "F.Paste")
			(net "GND")
		)
		(pad "OB11" smd rect
			(at -5.700014 -24.660098 180)
			(size 0.381 1.4478)
			(layers "F.Cu" "F.Mask" "F.Paste")
			(net "CLK_100M_OCP_SFF_2_DN")
		)
		(pad "OB12" smd rect
			(at -5.700014 -24.059896 180)
			(size 0.381 1.4478)
			(layers "F.Cu" "F.Mask" "F.Paste")
			(net "CLK_100M_OCP_SFF_2_DP")
		)
		(pad "OB13" smd rect
			(at -5.700014 -23.459948 180)
			(size 0.381 1.4478)
			(layers "F.Cu" "F.Mask" "F.Paste")
			(net "GND")
		)
		(pad "OB14" smd rect
			(at -5.700014 -22.86 180)
			(size 0.381 1.4478)
			(layers "F.Cu" "F.Mask" "F.Paste")
			(net "NCSI_OCP_SFF_CRS_DV")
		)
		(zone
			(layers "F.Cu" "B.Cu" "In1.Cu" "In2.Cu" "In3.Cu" "In4.Cu" "In5.Cu" "In6.Cu"
				"In7.Cu" "In8.Cu" "In9.Cu" "In10.Cu" "In11.Cu" "In12.Cu" "In13.Cu" "In14.Cu"
				"In15.Cu" "In16.Cu"
			)
			(hatch none 0.5)
			(connect_pads
				(clearance 0)
			)
			(min_thickness 0.25)
			(keepout
				(tracks not_allowed)
				(vias allowed)
				(pads allowed)
				(copperpour not_allowed)
				(footprints allowed)
			)
			(placement
				(enabled no)
				(sheetname "")
			)
			(fill
				(thermal_gap 0.5)
				(thermal_bridge_width 0.5)
				(island_removal_mode 0)
			)
			(polygon
				(pts
					(arc
						(start 390.782048 -5.169916)
						(mid 388.851648 -5.169916)
						(end 390.782048 -5.169916)
					)
				)
			)
		)
		(zone
			(layers "F.Cu" "B.Cu" "In1.Cu" "In2.Cu" "In3.Cu" "In4.Cu" "In5.Cu" "In6.Cu"
				"In7.Cu" "In8.Cu" "In9.Cu" "In10.Cu" "In11.Cu" "In12.Cu" "In13.Cu" "In14.Cu"
				"In15.Cu" "In16.Cu"
			)
			(hatch none 0.5)
			(connect_pads
				(clearance 0)
			)
			(min_thickness 0.25)
			(keepout
				(tracks not_allowed)
				(vias allowed)
				(pads allowed)
				(copperpour not_allowed)
				(footprints allowed)
			)
			(placement
				(enabled no)
				(sheetname "")
			)
			(fill
				(thermal_gap 0.5)
				(thermal_bridge_width 0.5)
				(island_removal_mode 0)
			)
			(polygon
				(pts
					(arc
						(start 454.94702 -6.169914)
						(mid 453.01662 -6.169914)
						(end 454.94702 -6.169914)
					)
				)
			)
		)
	)
	(footprint ""
		(layer "F.Cu")
		(at 254.147828 -70.440296 -90)
		(property "Reference" "PC1216"
			(at 0 0 270)
			(layer "F.SilkS")
			(hide yes)
			(effects
				(font
					(size 1.27 1.27)
				)
			)
		)
		(property "Value" ""
			(at 0 0 270)
			(layer "F.Fab")
			(effects
				(font
					(size 1.27 1.27)
				)
			)
		)
		(duplicate_pad_numbers_are_jumpers no)
		(fp_line
			(start -1.524 0.762)
			(end -1.524 -0.762)
			(stroke
				(width 0.1524)
				(type default)
			)
			(layer "F.SilkS")
		)
		(fp_line
			(start 1.524 0.762)
			(end -1.524 0.762)
			(stroke
				(width 0.1524)
				(type default)
			)
			(layer "F.SilkS")
		)
		(fp_line
			(start -1.524 -0.762)
			(end 1.524 -0.762)
			(stroke
				(width 0.1524)
				(type default)
			)
			(layer "F.SilkS")
		)
		(fp_line
			(start 1.524 -0.762)
			(end 1.524 0.762)
			(stroke
				(width 0.1524)
				(type default)
			)
			(layer "F.SilkS")
		)
		(fp_line
			(start -1.1049 0.724916)
			(end 1.1049 0.724916)
			(stroke
				(width 0.1)
				(type default)
			)
			(layer "F.Fab")
		)
		(fp_line
			(start 1.1049 0.724916)
			(end 1.1049 -0.724916)
			(stroke
				(width 0.1)
				(type default)
			)
			(layer "F.Fab")
		)
		(fp_line
			(start -1.1049 -0.724916)
			(end -1.1049 0.724916)
			(stroke
				(width 0.1)
				(type default)
			)
			(layer "F.Fab")
		)
		(fp_line
			(start 1.1049 -0.724916)
			(end -1.1049 -0.724916)
			(stroke
				(width 0.1)
				(type default)
			)
			(layer "F.Fab")
		)
		(pad "1" smd rect
			(at -0.889 0 90)
			(size 1.016 1.27)
			(layers "F.Cu" "F.Mask" "F.Paste")
			(net "SW_P12V_AUX_P1V05_PCH_AUX_FLT")
		)
		(pad "2" smd rect
			(at 0.889 0 90)
			(size 1.016 1.27)
			(layers "F.Cu" "F.Mask" "F.Paste")
			(net "GND")
		)
	)
	(footprint ""
		(layer "F.Cu")
		(at 423.68216 -143.675608 90)
		(property "Reference" "PR4224"
			(at 0 0 90)
			(layer "F.SilkS")
			(hide yes)
			(effects
				(font
					(size 1.27 1.27)
				)
			)
		)
		(property "Value" ""
			(at 0 0 90)
			(layer "F.Fab")
			(effects
				(font
					(size 1.27 1.27)
				)
			)
		)
		(duplicate_pad_numbers_are_jumpers no)
		(fp_line
			(start 0.7874 -0.4064)
			(end 0.7874 0.4064)
			(stroke
				(width 0.1524)
				(type default)
			)
			(layer "F.SilkS")
		)
		(fp_line
			(start -0.7874 -0.4064)
			(end 0.7874 -0.4064)
			(stroke
				(width 0.1524)
				(type default)
			)
			(layer "F.SilkS")
		)
		(fp_line
			(start 0.7874 0.4064)
			(end -0.7874 0.4064)
			(stroke
				(width 0.1524)
				(type default)
			)
			(layer "F.SilkS")
		)
		(fp_line
			(start -0.7874 0.4064)
			(end -0.7874 -0.4064)
			(stroke
				(width 0.1524)
				(type default)
			)
			(layer "F.SilkS")
		)
		(fp_line
			(start -0.12065 -0.305054)
			(end -0.12065 -0.2794)
			(stroke
				(width 0.1)
				(type default)
			)
			(layer "F.Fab")
		)
		(fp_line
			(start -0.67945 -0.305054)
			(end -0.12065 -0.305054)
			(stroke
				(width 0.1)
				(type default)
			)
			(layer "F.Fab")
		)
		(fp_line
			(start 0.67945 -0.3048)
			(end 0.67945 0.3048)
			(stroke
				(width 0.1)
				(type default)
			)
			(layer "F.Fab")
		)
		(fp_line
			(start 0.12065 -0.3048)
			(end 0.67945 -0.3048)
			(stroke
				(width 0.1)
				(type default)
			)
			(layer "F.Fab")
		)
		(fp_line
			(start 0.12065 -0.2794)
			(end 0.12065 -0.3048)
			(stroke
				(width 0.1)
				(type default)
			)
			(layer "F.Fab")
		)
		(fp_line
			(start -0.12065 -0.2794)
			(end 0.12065 -0.2794)
			(stroke
				(width 0.1)
				(type default)
			)
			(layer "F.Fab")
		)
		(fp_line
			(start 0.120396 0.2794)
			(end -0.12065 0.2794)
			(stroke
				(width 0.1)
				(type default)
			)
			(layer "F.Fab")
		)
		(fp_line
			(start -0.12065 0.2794)
			(end -0.12065 0.3048)
			(stroke
				(width 0.1)
				(type default)
			)
			(layer "F.Fab")
		)
		(fp_line
			(start 0.67945 0.3048)
			(end 0.120396 0.3048)
			(stroke
				(width 0.1)
				(type default)
			)
			(layer "F.Fab")
		)
		(fp_line
			(start 0.120396 0.3048)
			(end 0.120396 0.2794)
			(stroke
				(width 0.1)
				(type default)
			)
			(layer "F.Fab")
		)
		(fp_line
			(start -0.12065 0.3048)
			(end -0.67945 0.3048)
			(stroke
				(width 0.1)
				(type default)
			)
			(layer "F.Fab")
		)
		(fp_line
			(start -0.67945 0.3048)
			(end -0.67945 -0.305054)
			(stroke
				(width 0.1)
				(type default)
			)
			(layer "F.Fab")
		)
		(pad "1" smd circle
			(at -0.40005 0 90)
			(size 0 0)
			(layers "F.Cu" "F.Mask" "F.Paste")
			(net "NC_PVCCINFAON_CPU0_ACSP6")
		)
		(pad "2" smd circle
			(at 0.40005 0 90)
			(size 0 0)
			(layers "F.Cu" "F.Mask" "F.Paste")
			(net "GND")
		)
	)
	(footprint ""
		(layer "F.Cu")
		(at 163.50488 -435.447948 180)
		(property "Reference" "R3452"
			(at 0 0 180)
			(layer "F.SilkS")
			(hide yes)
			(effects
				(font
					(size 1.27 1.27)
				)
			)
		)
		(property "Value" ""
			(at 0 0 180)
			(layer "F.Fab")
			(effects
				(font
					(size 1.27 1.27)
				)
			)
		)
		(duplicate_pad_numbers_are_jumpers no)
		(fp_line
			(start 0.7874 0.4064)
			(end -0.7874 0.4064)
			(stroke
				(width 0.1524)
				(type default)
			)
			(layer "F.SilkS")
		)
		(fp_line
			(start 0.7874 -0.4064)
			(end 0.7874 0.4064)
			(stroke
				(width 0.1524)
				(type default)
			)
			(layer "F.SilkS")
		)
		(fp_line
			(start -0.7874 0.4064)
			(end -0.7874 -0.4064)
			(stroke
				(width 0.1524)
				(type default)
			)
			(layer "F.SilkS")
		)
		(fp_line
			(start -0.7874 -0.4064)
			(end 0.7874 -0.4064)
			(stroke
				(width 0.1524)
				(type default)
			)
			(layer "F.SilkS")
		)
		(fp_line
			(start 0.67945 0.3048)
			(end 0.120396 0.3048)
			(stroke
				(width 0.1)
				(type default)
			)
			(layer "F.Fab")
		)
		(fp_line
			(start 0.67945 -0.3048)
			(end 0.67945 0.3048)
			(stroke
				(width 0.1)
				(type default)
			)
			(layer "F.Fab")
		)
		(fp_line
			(start 0.12065 -0.2794)
			(end 0.12065 -0.3048)
			(stroke
				(width 0.1)
				(type default)
			)
			(layer "F.Fab")
		)
		(fp_line
			(start 0.12065 -0.3048)
			(end 0.67945 -0.3048)
			(stroke
				(width 0.1)
				(type default)
			)
			(layer "F.Fab")
		)
		(fp_line
			(start 0.120396 0.3048)
			(end 0.120396 0.2794)
			(stroke
				(width 0.1)
				(type default)
			)
			(layer "F.Fab")
		)
		(fp_line
			(start 0.120396 0.2794)
			(end -0.12065 0.2794)
			(stroke
				(width 0.1)
				(type default)
			)
			(layer "F.Fab")
		)
		(fp_line
			(start -0.12065 0.3048)
			(end -0.67945 0.3048)
			(stroke
				(width 0.1)
				(type default)
			)
			(layer "F.Fab")
		)
		(fp_line
			(start -0.12065 0.2794)
			(end -0.12065 0.3048)
			(stroke
				(width 0.1)
				(type default)
			)
			(layer "F.Fab")
		)
		(fp_line
			(start -0.12065 -0.2794)
			(end 0.12065 -0.2794)
			(stroke
				(width 0.1)
				(type default)
			)
			(layer "F.Fab")
		)
		(fp_line
			(start -0.12065 -0.305054)
			(end -0.12065 -0.2794)
			(stroke
				(width 0.1)
				(type default)
			)
			(layer "F.Fab")
		)
		(fp_line
			(start -0.67945 0.3048)
			(end -0.67945 -0.305054)
			(stroke
				(width 0.1)
				(type default)
			)
			(layer "F.Fab")
		)
		(fp_line
			(start -0.67945 -0.305054)
			(end -0.12065 -0.305054)
			(stroke
				(width 0.1)
				(type default)
			)
			(layer "F.Fab")
		)
		(pad "1" smd circle
			(at -0.40005 0 180)
			(size 0 0)
			(layers "F.Cu" "F.Mask" "F.Paste")
			(net "GPU_BASE_STBY_EN")
		)
		(pad "2" smd circle
			(at 0.40005 0 180)
			(size 0 0)
			(layers "F.Cu" "F.Mask" "F.Paste")
			(net "GND")
		)
	)
	(footprint ""
		(layer "F.Cu")
		(at 68.961 -34.788348)
		(property "Reference" "R3591"
			(at 0 0 0)
			(layer "F.SilkS")
			(hide yes)
			(effects
				(font
					(size 1.27 1.27)
				)
			)
		)
		(property "Value" ""
			(at 0 0 0)
			(layer "F.Fab")
			(effects
				(font
					(size 1.27 1.27)
				)
			)
		)
		(duplicate_pad_numbers_are_jumpers no)
		(fp_line
			(start -0.7874 -0.4064)
			(end 0.7874 -0.4064)
			(stroke
				(width 0.1524)
				(type default)
			)
			(layer "F.SilkS")
		)
		(fp_line
			(start -0.7874 0.4064)
			(end -0.7874 -0.4064)
			(stroke
				(width 0.1524)
				(type default)
			)
			(layer "F.SilkS")
		)
		(fp_line
			(start 0.7874 -0.4064)
			(end 0.7874 0.4064)
			(stroke
				(width 0.1524)
				(type default)
			)
			(layer "F.SilkS")
		)
		(fp_line
			(start 0.7874 0.4064)
			(end -0.7874 0.4064)
			(stroke
				(width 0.1524)
				(type default)
			)
			(layer "F.SilkS")
		)
		(fp_line
			(start -0.67945 -0.305054)
			(end -0.12065 -0.305054)
			(stroke
				(width 0.1)
				(type default)
			)
			(layer "F.Fab")
		)
		(fp_line
			(start -0.67945 0.3048)
			(end -0.67945 -0.305054)
			(stroke
				(width 0.1)
				(type default)
			)
			(layer "F.Fab")
		)
		(fp_line
			(start -0.12065 -0.305054)
			(end -0.12065 -0.2794)
			(stroke
				(width 0.1)
				(type default)
			)
			(layer "F.Fab")
		)
		(fp_line
			(start -0.12065 -0.2794)
			(end 0.12065 -0.2794)
			(stroke
				(width 0.1)
				(type default)
			)
			(layer "F.Fab")
		)
		(fp_line
			(start -0.12065 0.2794)
			(end -0.12065 0.3048)
			(stroke
				(width 0.1)
				(type default)
			)
			(layer "F.Fab")
		)
		(fp_line
			(start -0.12065 0.3048)
			(end -0.67945 0.3048)
			(stroke
				(width 0.1)
				(type default)
			)
			(layer "F.Fab")
		)
		(fp_line
			(start 0.120396 0.2794)
			(end -0.12065 0.2794)
			(stroke
				(width 0.1)
				(type default)
			)
			(layer "F.Fab")
		)
		(fp_line
			(start 0.120396 0.3048)
			(end 0.120396 0.2794)
			(stroke
				(width 0.1)
				(type default)
			)
			(layer "F.Fab")
		)
		(fp_line
			(start 0.12065 -0.3048)
			(end 0.67945 -0.3048)
			(stroke
				(width 0.1)
				(type default)
			)
			(layer "F.Fab")
		)
		(fp_line
			(start 0.12065 -0.2794)
			(end 0.12065 -0.3048)
			(stroke
				(width 0.1)
				(type default)
			)
			(layer "F.Fab")
		)
		(fp_line
			(start 0.67945 -0.3048)
			(end 0.67945 0.3048)
			(stroke
				(width 0.1)
				(type default)
			)
			(layer "F.Fab")
		)
		(fp_line
			(start 0.67945 0.3048)
			(end 0.120396 0.3048)
			(stroke
				(width 0.1)
				(type default)
			)
			(layer "F.Fab")
		)
		(pad "1" smd circle
			(at -0.40005 0)
			(size 0 0)
			(layers "F.Cu" "F.Mask" "F.Paste")
			(net "SMB_INA230_3V3AUX_SDA")
		)
		(pad "2" smd circle
			(at 0.40005 0)
			(size 0 0)
			(layers "F.Cu" "F.Mask" "F.Paste")
			(net "SMB_INA230_3_3V3AUX_SDA_R")
		)
	)
	(footprint ""
		(layer "F.Cu")
		(at 52.363878 -408.517344 -90)
		(property "Reference" "C707"
			(at 0 0 270)
			(layer "F.SilkS")
			(hide yes)
			(effects
				(font
					(size 1.27 1.27)
				)
			)
		)
		(property "Value" ""
			(at 0 0 270)
			(layer "F.Fab")
			(effects
				(font
					(size 1.27 1.27)
				)
			)
		)
		(duplicate_pad_numbers_are_jumpers no)
		(fp_line
			(start -0.299974 0.150114)
			(end -0.299974 -0.150114)
			(stroke
				(width 0.1)
				(type default)
			)
			(layer "F.Fab")
		)
		(fp_line
			(start 0.299974 0.150114)
			(end -0.299974 0.150114)
			(stroke
				(width 0.1)
				(type default)
			)
			(layer "F.Fab")
		)
		(fp_line
			(start -0.299974 -0.150114)
			(end 0.299974 -0.150114)
			(stroke
				(width 0.1)
				(type default)
			)
			(layer "F.Fab")
		)
		(fp_line
			(start 0.299974 -0.150114)
			(end 0.299974 0.150114)
			(stroke
				(width 0.1)
				(type default)
			)
			(layer "F.Fab")
		)
		(pad "1" smd rect
			(at -0.2667 0 270)
			(size 0.3048 0.381)
			(layers "F.Cu" "F.Mask" "F.Paste")
			(net "P5E_CPU1_PE4_TX_C_DP<1>")
		)
		(pad "2" smd rect
			(at 0.2667 0 270)
			(size 0.3048 0.381)
			(layers "F.Cu" "F.Mask" "F.Paste")
			(net "P5E_CPU1_PE4_TX_DP<1>")
		)
	)
	(footprint ""
		(layer "F.Cu")
		(at 134.42188 -96.357948 -90)
		(property "Reference" "Q142"
			(at -0.035052 -2.38379 90)
			(unlocked yes)
			(layer "F.SilkS")
			(effects
				(font
					(size 0.7874 0.5842)
					(thickness 0.1524)
				)
			)
		)
		(property "Value" ""
			(at 0 0 270)
			(layer "F.Fab")
			(effects
				(font
					(size 1.27 1.27)
				)
			)
		)
		(duplicate_pad_numbers_are_jumpers no)
		(fp_line
			(start -1.376172 1.199896)
			(end -1.376172 -1.199896)
			(stroke
				(width 0.1524)
				(type default)
			)
			(layer "F.SilkS")
		)
		(fp_line
			(start 1.376172 1.199896)
			(end -1.376172 1.199896)
			(stroke
				(width 0.1524)
				(type default)
			)
			(layer "F.SilkS")
		)
		(fp_line
			(start 0 -0.762)
			(end 0.508 -1.199896)
			(stroke
				(width 0.1524)
				(type default)
			)
			(layer "F.SilkS")
		)
		(fp_line
			(start -1.376172 -1.199896)
			(end -0.508 -1.199896)
			(stroke
				(width 0.1524)
				(type default)
			)
			(layer "F.SilkS")
		)
		(fp_line
			(start -0.508 -1.199896)
			(end 0 -0.762)
			(stroke
				(width 0.1524)
				(type default)
			)
			(layer "F.SilkS")
		)
		(fp_line
			(start 0.508 -1.199896)
			(end 1.376172 -1.199896)
			(stroke
				(width 0.1524)
				(type default)
			)
			(layer "F.SilkS")
		)
		(fp_line
			(start 1.376172 -1.199896)
			(end 1.376172 1.199896)
			(stroke
				(width 0.1524)
				(type default)
			)
			(layer "F.SilkS")
		)
		(fp_poly
			(pts
				(xy -1.4605 -0.7493) (xy -2.2225 -1.1303) (xy -2.2225 -0.3683)
			)
			(stroke
				(width 0)
				(type default)
			)
			(fill yes)
			(layer "F.SilkS")
		)
		(fp_line
			(start -0.674878 1.100074)
			(end -0.674878 -1.100074)
			(stroke
				(width 0.1)
				(type default)
			)
			(layer "F.Fab")
		)
		(fp_line
			(start 0.674878 1.100074)
			(end -0.674878 1.100074)
			(stroke
				(width 0.1)
				(type default)
			)
			(layer "F.Fab")
		)
		(fp_line
			(start -0.674878 -1.100074)
			(end 0.674878 -1.100074)
			(stroke
				(width 0.1)
				(type default)
			)
			(layer "F.Fab")
		)
		(fp_line
			(start 0.674878 -1.100074)
			(end 0.674878 1.100074)
			(stroke
				(width 0.1)
				(type default)
			)
			(layer "F.Fab")
		)
		(fp_poly
			(pts
				(xy -1.4605 -0.7493) (xy -2.2225 -1.1303) (xy -2.2225 -0.3683)
			)
			(stroke
				(width 0)
				(type default)
			)
			(fill yes)
			(layer "F.Fab")
		)
		(pad "1" smd rect
			(at -0.899922 -0.750062 180)
			(size 0.6096 0.6096)
			(layers "F.Cu" "F.Mask" "F.Paste")
			(net "GND")
		)
		(pad "2" smd rect
			(at -0.899922 0 180)
			(size 0.4064 0.6096)
			(layers "F.Cu" "F.Mask" "F.Paste")
			(net "H_CPU1_MEMHOT_OUT_R")
		)
		(pad "3" smd rect
			(at -0.899922 0.750062 180)
			(size 0.6096 0.6096)
			(layers "F.Cu" "F.Mask" "F.Paste")
			(net "H_CPU1_MEMHOT_OUT")
		)
		(pad "4" smd rect
			(at 0.899922 0.750062 180)
			(size 0.6096 0.6096)
			(layers "F.Cu" "F.Mask" "F.Paste")
			(net "PVNN_TERM_CPU1")
		)
		(pad "5" smd rect
			(at 0.899922 0 180)
			(size 0.4064 0.6096)
			(layers "F.Cu" "F.Mask" "F.Paste")
			(net "H_CPU1_MEMHOT_OUT_VT_R_N")
		)
		(pad "6" smd rect
			(at 0.899922 -0.750062 180)
			(size 0.6096 0.6096)
			(layers "F.Cu" "F.Mask" "F.Paste")
			(net "H_CPU1_MEMHOT_OUT_VT_N")
		)
	)
	(footprint ""
		(layer "F.Cu")
		(at 176.6824 -94.338648 90)
		(property "Reference" "R4588"
			(at 0 0 90)
			(layer "F.SilkS")
			(hide yes)
			(effects
				(font
					(size 1.27 1.27)
				)
			)
		)
		(property "Value" ""
			(at 0 0 90)
			(layer "F.Fab")
			(effects
				(font
					(size 1.27 1.27)
				)
			)
		)
		(duplicate_pad_numbers_are_jumpers no)
		(fp_line
			(start 0.7874 -0.4064)
			(end 0.7874 0.4064)
			(stroke
				(width 0.1524)
				(type default)
			)
			(layer "F.SilkS")
		)
		(fp_line
			(start -0.7874 -0.4064)
			(end 0.7874 -0.4064)
			(stroke
				(width 0.1524)
				(type default)
			)
			(layer "F.SilkS")
		)
		(fp_line
			(start 0.7874 0.4064)
			(end -0.7874 0.4064)
			(stroke
				(width 0.1524)
				(type default)
			)
			(layer "F.SilkS")
		)
		(fp_line
			(start -0.7874 0.4064)
			(end -0.7874 -0.4064)
			(stroke
				(width 0.1524)
				(type default)
			)
			(layer "F.SilkS")
		)
		(fp_line
			(start -0.12065 -0.305054)
			(end -0.12065 -0.2794)
			(stroke
				(width 0.1)
				(type default)
			)
			(layer "F.Fab")
		)
		(fp_line
			(start -0.67945 -0.305054)
			(end -0.12065 -0.305054)
			(stroke
				(width 0.1)
				(type default)
			)
			(layer "F.Fab")
		)
		(fp_line
			(start 0.67945 -0.3048)
			(end 0.67945 0.3048)
			(stroke
				(width 0.1)
				(type default)
			)
			(layer "F.Fab")
		)
		(fp_line
			(start 0.12065 -0.3048)
			(end 0.67945 -0.3048)
			(stroke
				(width 0.1)
				(type default)
			)
			(layer "F.Fab")
		)
		(fp_line
			(start 0.12065 -0.2794)
			(end 0.12065 -0.3048)
			(stroke
				(width 0.1)
				(type default)
			)
			(layer "F.Fab")
		)
		(fp_line
			(start -0.12065 -0.2794)
			(end 0.12065 -0.2794)
			(stroke
				(width 0.1)
				(type default)
			)
			(layer "F.Fab")
		)
		(fp_line
			(start 0.120396 0.2794)
			(end -0.12065 0.2794)
			(stroke
				(width 0.1)
				(type default)
			)
			(layer "F.Fab")
		)
		(fp_line
			(start -0.12065 0.2794)
			(end -0.12065 0.3048)
			(stroke
				(width 0.1)
				(type default)
			)
			(layer "F.Fab")
		)
		(fp_line
			(start 0.67945 0.3048)
			(end 0.120396 0.3048)
			(stroke
				(width 0.1)
				(type default)
			)
			(layer "F.Fab")
		)
		(fp_line
			(start 0.120396 0.3048)
			(end 0.120396 0.2794)
			(stroke
				(width 0.1)
				(type default)
			)
			(layer "F.Fab")
		)
		(fp_line
			(start -0.12065 0.3048)
			(end -0.67945 0.3048)
			(stroke
				(width 0.1)
				(type default)
			)
			(layer "F.Fab")
		)
		(fp_line
			(start -0.67945 0.3048)
			(end -0.67945 -0.305054)
			(stroke
				(width 0.1)
				(type default)
			)
			(layer "F.Fab")
		)
		(pad "1" smd rect
			(at -0.40005 0 270)
			(size 0.4572 0.508)
			(layers "F.Cu" "F.Mask" "F.Paste")
			(net "FAB_BMC_REV_ID2")
		)
		(pad "2" smd rect
			(at 0.40005 0 270)
			(size 0.4572 0.508)
			(layers "F.Cu" "F.Mask" "F.Paste")
			(net "GND")
		)
	)
	(footprint ""
		(layer "F.Cu")
		(at 290.874704 -372.471188)
		(property "Reference" "PL44"
			(at -1.46812 -4.415028 0)
			(unlocked yes)
			(layer "F.SilkS")
			(effects
				(font
					(size 0.7874 0.5842)
					(thickness 0.1524)
				)
				(justify left)
			)
		)
		(property "Value" ""
			(at 0 0 0)
			(layer "F.Fab")
			(effects
				(font
					(size 1.27 1.27)
				)
			)
		)
		(duplicate_pad_numbers_are_jumpers no)
		(fp_line
			(start -2.249932 -2.249932)
			(end 2.249932 -2.249932)
			(stroke
				(width 0.1524)
				(type default)
			)
			(layer "F.SilkS")
		)
		(fp_line
			(start -2.249932 -1.3843)
			(end -2.249932 -2.249932)
			(stroke
				(width 0.1524)
				(type default)
			)
			(layer "F.SilkS")
		)
		(fp_line
			(start -2.249932 2.249932)
			(end -2.249932 1.3843)
			(stroke
				(width 0.1524)
				(type default)
			)
			(layer "F.SilkS")
		)
		(fp_line
			(start 2.249932 -2.249932)
			(end 2.249932 -1.3843)
			(stroke
				(width 0.1524)
				(type default)
			)
			(layer "F.SilkS")
		)
		(fp_line
			(start 2.249932 1.3843)
			(end 2.249932 2.249932)
			(stroke
				(width 0.1524)
				(type default)
			)
			(layer "F.SilkS")
		)
		(fp_line
			(start 2.249932 2.249932)
			(end -2.249932 2.249932)
			(stroke
				(width 0.1524)
				(type default)
			)
			(layer "F.SilkS")
		)
		(fp_line
			(start -2.249932 -2.249932)
			(end 2.249932 -2.249932)
			(stroke
				(width 0.1)
				(type default)
			)
			(layer "F.Fab")
		)
		(fp_line
			(start -2.249932 2.249932)
			(end -2.249932 -2.249932)
			(stroke
				(width 0.1)
				(type default)
			)
			(layer "F.Fab")
		)
		(fp_line
			(start 2.249932 -2.249932)
			(end 2.249932 2.249932)
			(stroke
				(width 0.1)
				(type default)
			)
			(layer "F.Fab")
		)
		(fp_line
			(start 2.249932 2.249932)
			(end -2.249932 2.249932)
			(stroke
				(width 0.1)
				(type default)
			)
			(layer "F.Fab")
		)
		(pad "1" smd rect
			(at -1.82499 0)
			(size 1.0668 2.5146)
			(layers "F.Cu" "F.Mask" "F.Paste")
			(net "P12V_AUX")
		)
		(pad "2" smd rect
			(at 1.82499 0)
			(size 1.0668 2.5146)
			(layers "F.Cu" "F.Mask" "F.Paste")
			(net "SW_P12V_PVCCFA_EHV_FIVRA_CPU0_L")
		)
	)
	(footprint ""
		(layer "F.Cu")
		(at 372.561358 -92.962984 90)
		(property "Reference" "R481"
			(at 0 0 90)
			(layer "F.SilkS")
			(hide yes)
			(effects
				(font
					(size 1.27 1.27)
				)
			)
		)
		(property "Value" ""
			(at 0 0 90)
			(layer "F.Fab")
			(effects
				(font
					(size 1.27 1.27)
				)
			)
		)
		(duplicate_pad_numbers_are_jumpers no)
		(fp_line
			(start 0.7874 -0.4064)
			(end 0.7874 0.4064)
			(stroke
				(width 0.1524)
				(type default)
			)
			(layer "F.SilkS")
		)
		(fp_line
			(start -0.7874 -0.4064)
			(end 0.7874 -0.4064)
			(stroke
				(width 0.1524)
				(type default)
			)
			(layer "F.SilkS")
		)
		(fp_line
			(start 0.7874 0.4064)
			(end -0.7874 0.4064)
			(stroke
				(width 0.1524)
				(type default)
			)
			(layer "F.SilkS")
		)
		(fp_line
			(start -0.7874 0.4064)
			(end -0.7874 -0.4064)
			(stroke
				(width 0.1524)
				(type default)
			)
			(layer "F.SilkS")
		)
		(fp_line
			(start -0.12065 -0.305054)
			(end -0.12065 -0.2794)
			(stroke
				(width 0.1)
				(type default)
			)
			(layer "F.Fab")
		)
		(fp_line
			(start -0.67945 -0.305054)
			(end -0.12065 -0.305054)
			(stroke
				(width 0.1)
				(type default)
			)
			(layer "F.Fab")
		)
		(fp_line
			(start 0.67945 -0.3048)
			(end 0.67945 0.3048)
			(stroke
				(width 0.1)
				(type default)
			)
			(layer "F.Fab")
		)
		(fp_line
			(start 0.12065 -0.3048)
			(end 0.67945 -0.3048)
			(stroke
				(width 0.1)
				(type default)
			)
			(layer "F.Fab")
		)
		(fp_line
			(start 0.12065 -0.2794)
			(end 0.12065 -0.3048)
			(stroke
				(width 0.1)
				(type default)
			)
			(layer "F.Fab")
		)
		(fp_line
			(start -0.12065 -0.2794)
			(end 0.12065 -0.2794)
			(stroke
				(width 0.1)
				(type default)
			)
			(layer "F.Fab")
		)
		(fp_line
			(start 0.120396 0.2794)
			(end -0.12065 0.2794)
			(stroke
				(width 0.1)
				(type default)
			)
			(layer "F.Fab")
		)
		(fp_line
			(start -0.12065 0.2794)
			(end -0.12065 0.3048)
			(stroke
				(width 0.1)
				(type default)
			)
			(layer "F.Fab")
		)
		(fp_line
			(start 0.67945 0.3048)
			(end 0.120396 0.3048)
			(stroke
				(width 0.1)
				(type default)
			)
			(layer "F.Fab")
		)
		(fp_line
			(start 0.120396 0.3048)
			(end 0.120396 0.2794)
			(stroke
				(width 0.1)
				(type default)
			)
			(layer "F.Fab")
		)
		(fp_line
			(start -0.12065 0.3048)
			(end -0.67945 0.3048)
			(stroke
				(width 0.1)
				(type default)
			)
			(layer "F.Fab")
		)
		(fp_line
			(start -0.67945 0.3048)
			(end -0.67945 -0.305054)
			(stroke
				(width 0.1)
				(type default)
			)
			(layer "F.Fab")
		)
		(pad "1" smd circle
			(at -0.40005 0 90)
			(size 0 0)
			(layers "F.Cu" "F.Mask" "F.Paste")
			(net "JTAG_DBP_TDI")
		)
		(pad "2" smd circle
			(at 0.40005 0 90)
			(size 0 0)
			(layers "F.Cu" "F.Mask" "F.Paste")
			(net "JTAG_DBP_FB_TDI")
		)
	)
	(footprint ""
		(layer "F.Cu")
		(at 223.384364 -75.86091 180)
		(property "Reference" "PR4527"
			(at 0 0 180)
			(layer "F.SilkS")
			(hide yes)
			(effects
				(font
					(size 1.27 1.27)
				)
			)
		)
		(property "Value" ""
			(at 0 0 180)
			(layer "F.Fab")
			(effects
				(font
					(size 1.27 1.27)
				)
			)
		)
		(duplicate_pad_numbers_are_jumpers no)
		(fp_line
			(start 0.7874 0.4064)
			(end -0.7874 0.4064)
			(stroke
				(width 0.1524)
				(type default)
			)
			(layer "F.SilkS")
		)
		(fp_line
			(start 0.7874 -0.4064)
			(end 0.7874 0.4064)
			(stroke
				(width 0.1524)
				(type default)
			)
			(layer "F.SilkS")
		)
		(fp_line
			(start -0.7874 0.4064)
			(end -0.7874 -0.4064)
			(stroke
				(width 0.1524)
				(type default)
			)
			(layer "F.SilkS")
		)
		(fp_line
			(start -0.7874 -0.4064)
			(end 0.7874 -0.4064)
			(stroke
				(width 0.1524)
				(type default)
			)
			(layer "F.SilkS")
		)
		(fp_line
			(start 0.67945 0.3048)
			(end 0.120396 0.3048)
			(stroke
				(width 0.1)
				(type default)
			)
			(layer "F.Fab")
		)
		(fp_line
			(start 0.67945 -0.3048)
			(end 0.67945 0.3048)
			(stroke
				(width 0.1)
				(type default)
			)
			(layer "F.Fab")
		)
		(fp_line
			(start 0.12065 -0.2794)
			(end 0.12065 -0.3048)
			(stroke
				(width 0.1)
				(type default)
			)
			(layer "F.Fab")
		)
		(fp_line
			(start 0.12065 -0.3048)
			(end 0.67945 -0.3048)
			(stroke
				(width 0.1)
				(type default)
			)
			(layer "F.Fab")
		)
		(fp_line
			(start 0.120396 0.3048)
			(end 0.120396 0.2794)
			(stroke
				(width 0.1)
				(type default)
			)
			(layer "F.Fab")
		)
		(fp_line
			(start 0.120396 0.2794)
			(end -0.12065 0.2794)
			(stroke
				(width 0.1)
				(type default)
			)
			(layer "F.Fab")
		)
		(fp_line
			(start -0.12065 0.3048)
			(end -0.67945 0.3048)
			(stroke
				(width 0.1)
				(type default)
			)
			(layer "F.Fab")
		)
		(fp_line
			(start -0.12065 0.2794)
			(end -0.12065 0.3048)
			(stroke
				(width 0.1)
				(type default)
			)
			(layer "F.Fab")
		)
		(fp_line
			(start -0.12065 -0.2794)
			(end 0.12065 -0.2794)
			(stroke
				(width 0.1)
				(type default)
			)
			(layer "F.Fab")
		)
		(fp_line
			(start -0.12065 -0.305054)
			(end -0.12065 -0.2794)
			(stroke
				(width 0.1)
				(type default)
			)
			(layer "F.Fab")
		)
		(fp_line
			(start -0.67945 0.3048)
			(end -0.67945 -0.305054)
			(stroke
				(width 0.1)
				(type default)
			)
			(layer "F.Fab")
		)
		(fp_line
			(start -0.67945 -0.305054)
			(end -0.12065 -0.305054)
			(stroke
				(width 0.1)
				(type default)
			)
			(layer "F.Fab")
		)
		(pad "1" smd circle
			(at -0.40005 0 180)
			(size 0 0)
			(layers "F.Cu" "F.Mask" "F.Paste")
			(net "P3V3_E1S_0_R")
		)
		(pad "2" smd circle
			(at 0.40005 0 180)
			(size 0 0)
			(layers "F.Cu" "F.Mask" "F.Paste")
			(net "P3V3_E1S_GATE_0")
		)
	)
	(footprint ""
		(layer "F.Cu")
		(at 318.468248 -408.517344 -90)
		(property "Reference" "C911"
			(at 0 0 270)
			(layer "F.SilkS")
			(hide yes)
			(effects
				(font
					(size 1.27 1.27)
				)
			)
		)
		(property "Value" ""
			(at 0 0 270)
			(layer "F.Fab")
			(effects
				(font
					(size 1.27 1.27)
				)
			)
		)
		(duplicate_pad_numbers_are_jumpers no)
		(fp_line
			(start -0.299974 0.150114)
			(end -0.299974 -0.150114)
			(stroke
				(width 0.1)
				(type default)
			)
			(layer "F.Fab")
		)
		(fp_line
			(start 0.299974 0.150114)
			(end -0.299974 0.150114)
			(stroke
				(width 0.1)
				(type default)
			)
			(layer "F.Fab")
		)
		(fp_line
			(start -0.299974 -0.150114)
			(end 0.299974 -0.150114)
			(stroke
				(width 0.1)
				(type default)
			)
			(layer "F.Fab")
		)
		(fp_line
			(start 0.299974 -0.150114)
			(end 0.299974 0.150114)
			(stroke
				(width 0.1)
				(type default)
			)
			(layer "F.Fab")
		)
		(pad "1" smd rect
			(at -0.2667 0 270)
			(size 0.3048 0.381)
			(layers "F.Cu" "F.Mask" "F.Paste")
			(net "P5E_CPU0_PE0_TX_C_DP<11>")
		)
		(pad "2" smd rect
			(at 0.2667 0 270)
			(size 0.3048 0.381)
			(layers "F.Cu" "F.Mask" "F.Paste")
			(net "P5E_CPU0_PE0_TX_DP<11>")
		)
	)
	(footprint ""
		(layer "F.Cu")
		(at 48.28794 -145.026888 -90)
		(property "Reference" "PC1659"
			(at 0 0 270)
			(layer "F.SilkS")
			(hide yes)
			(effects
				(font
					(size 1.27 1.27)
				)
			)
		)
		(property "Value" ""
			(at 0 0 270)
			(layer "F.Fab")
			(effects
				(font
					(size 1.27 1.27)
				)
			)
		)
		(duplicate_pad_numbers_are_jumpers no)
		(fp_line
			(start -0.7874 0.4064)
			(end -0.7874 -0.4064)
			(stroke
				(width 0.1524)
				(type default)
			)
			(layer "F.SilkS")
		)
		(fp_line
			(start 0.7874 0.4064)
			(end -0.7874 0.4064)
			(stroke
				(width 0.1524)
				(type default)
			)
			(layer "F.SilkS")
		)
		(fp_line
			(start -0.7874 -0.4064)
			(end 0.7874 -0.4064)
			(stroke
				(width 0.1524)
				(type default)
			)
			(layer "F.SilkS")
		)
		(fp_line
			(start 0.7874 -0.4064)
			(end 0.7874 0.4064)
			(stroke
				(width 0.1524)
				(type default)
			)
			(layer "F.SilkS")
		)
		(fp_line
			(start -0.67945 0.3048)
			(end -0.67945 -0.305054)
			(stroke
				(width 0.1)
				(type default)
			)
			(layer "F.Fab")
		)
		(fp_line
			(start -0.12065 0.3048)
			(end -0.67945 0.3048)
			(stroke
				(width 0.1)
				(type default)
			)
			(layer "F.Fab")
		)
		(fp_line
			(start 0.120396 0.3048)
			(end 0.120396 0.2794)
			(stroke
				(width 0.1)
				(type default)
			)
			(layer "F.Fab")
		)
		(fp_line
			(start 0.67945 0.3048)
			(end 0.120396 0.3048)
			(stroke
				(width 0.1)
				(type default)
			)
			(layer "F.Fab")
		)
		(fp_line
			(start -0.12065 0.2794)
			(end -0.12065 0.3048)
			(stroke
				(width 0.1)
				(type default)
			)
			(layer "F.Fab")
		)
		(fp_line
			(start 0.120396 0.2794)
			(end -0.12065 0.2794)
			(stroke
				(width 0.1)
				(type default)
			)
			(layer "F.Fab")
		)
		(fp_line
			(start -0.12065 -0.2794)
			(end 0.12065 -0.2794)
			(stroke
				(width 0.1)
				(type default)
			)
			(layer "F.Fab")
		)
		(fp_line
			(start 0.12065 -0.2794)
			(end 0.12065 -0.3048)
			(stroke
				(width 0.1)
				(type default)
			)
			(layer "F.Fab")
		)
		(fp_line
			(start 0.12065 -0.3048)
			(end 0.67945 -0.3048)
			(stroke
				(width 0.1)
				(type default)
			)
			(layer "F.Fab")
		)
		(fp_line
			(start 0.67945 -0.3048)
			(end 0.67945 0.3048)
			(stroke
				(width 0.1)
				(type default)
			)
			(layer "F.Fab")
		)
		(fp_line
			(start -0.67945 -0.305054)
			(end -0.12065 -0.305054)
			(stroke
				(width 0.1)
				(type default)
			)
			(layer "F.Fab")
		)
		(fp_line
			(start -0.12065 -0.305054)
			(end -0.12065 -0.2794)
			(stroke
				(width 0.1)
				(type default)
			)
			(layer "F.Fab")
		)
		(pad "1" smd circle
			(at -0.40005 0 270)
			(size 0 0)
			(layers "F.Cu" "F.Mask" "F.Paste")
			(net "P12V_AUX")
		)
		(pad "2" smd circle
			(at 0.40005 0 270)
			(size 0 0)
			(layers "F.Cu" "F.Mask" "F.Paste")
			(net "GND")
		)
	)
	(footprint ""
		(layer "F.Cu")
		(at 191.806322 -20.126452 180)
		(property "Reference" "PD116"
			(at 10.696702 -0.955294 0)
			(unlocked yes)
			(layer "F.SilkS")
			(effects
				(font
					(size 0.7874 0.5842)
					(thickness 0.1524)
				)
				(justify left)
			)
		)
		(property "Value" ""
			(at 0 0 180)
			(layer "F.Fab")
			(effects
				(font
					(size 1.27 1.27)
				)
			)
		)
		(duplicate_pad_numbers_are_jumpers no)
		(fp_line
			(start 4.107942 1.459992)
			(end -3.400044 1.459992)
			(stroke
				(width 0.1524)
				(type default)
			)
			(layer "F.SilkS")
		)
		(fp_line
			(start 4.107942 -1.459992)
			(end 4.107942 1.459992)
			(stroke
				(width 0.1524)
				(type default)
			)
			(layer "F.SilkS")
		)
		(fp_line
			(start -3.400044 1.459992)
			(end -3.400044 -1.459992)
			(stroke
				(width 0.1524)
				(type default)
			)
			(layer "F.SilkS")
		)
		(fp_line
			(start -3.400044 -1.459992)
			(end 4.107942 -1.459992)
			(stroke
				(width 0.1524)
				(type default)
			)
			(layer "F.SilkS")
		)
		(fp_rect
			(start 4.107942 -1.459992)
			(end 3.308096 1.459992)
			(stroke
				(width 0)
				(type default)
			)
			(fill yes)
			(layer "F.SilkS")
		)
		(fp_line
			(start 2.29997 1.459992)
			(end -2.29997 1.459992)
			(stroke
				(width 0.1)
				(type default)
			)
			(layer "F.Fab")
		)
		(fp_line
			(start 2.29997 -1.459992)
			(end 2.29997 1.459992)
			(stroke
				(width 0.1)
				(type default)
			)
			(layer "F.Fab")
		)
		(fp_line
			(start -2.29997 1.459992)
			(end -2.29997 -1.459992)
			(stroke
				(width 0.1)
				(type default)
			)
			(layer "F.Fab")
		)
		(fp_line
			(start -2.29997 -1.459992)
			(end 2.29997 -1.459992)
			(stroke
				(width 0.1)
				(type default)
			)
			(layer "F.Fab")
		)
		(fp_text user "-"
			(at 5.4102 0.29845 0)
			(unlocked yes)
			(layer "F.SilkS")
			(effects
				(font
					(size 1.905 1.4224)
					(thickness 0.1524)
				)
				(justify left)
			)
		)
		(fp_text user "+"
			(at -4.7752 -0.12065 180)
			(unlocked yes)
			(layer "F.SilkS")
			(effects
				(font
					(size 1.905 1.4224)
					(thickness 0.1524)
				)
				(justify left)
			)
		)
		(fp_text user "-"
			(at 5.4102 0.29845 0)
			(unlocked yes)
			(layer "F.Fab")
			(effects
				(font
					(size 1.905 1.4224)
					(thickness 0.1524)
				)
				(justify left)
			)
		)
		(fp_text user "+"
			(at -4.7752 -0.12065 180)
			(unlocked yes)
			(layer "F.Fab")
			(effects
				(font
					(size 1.905 1.4224)
					(thickness 0.1524)
				)
				(justify left)
			)
		)
		(pad "A" smd rect
			(at -1.999996 0 270)
			(size 1.7018 2.5146)
			(layers "F.Cu" "F.Mask" "F.Paste")
			(net "GND")
		)
		(pad "C" smd rect
			(at 1.999996 0 270)
			(size 1.7018 2.5146)
			(layers "F.Cu" "F.Mask" "F.Paste")
			(net "P12V_SCM_R")
		)
	)
	(footprint ""
		(layer "F.Cu")
		(at 401.62988 -186.781948)
		(property "Reference" "R323"
			(at 0 0 0)
			(layer "F.SilkS")
			(hide yes)
			(effects
				(font
					(size 1.27 1.27)
				)
			)
		)
		(property "Value" ""
			(at 0 0 0)
			(layer "F.Fab")
			(effects
				(font
					(size 1.27 1.27)
				)
			)
		)
		(duplicate_pad_numbers_are_jumpers no)
		(fp_line
			(start -2.044192 -0.94361)
			(end -2.044192 0.898398)
			(stroke
				(width 0.1524)
				(type default)
			)
			(layer "F.SilkS")
		)
		(fp_line
			(start -2.044192 0.94361)
			(end 2.044192 0.94361)
			(stroke
				(width 0.1524)
				(type default)
			)
			(layer "F.SilkS")
		)
		(fp_line
			(start 2.044192 -0.94361)
			(end -2.044192 -0.94361)
			(stroke
				(width 0.1524)
				(type default)
			)
			(layer "F.SilkS")
		)
		(fp_line
			(start 2.044192 0.94361)
			(end 2.044192 -0.94361)
			(stroke
				(width 0.1524)
				(type default)
			)
			(layer "F.SilkS")
		)
		(fp_line
			(start -1.625092 -0.87503)
			(end -1.625092 0.87503)
			(stroke
				(width 0.1)
				(type default)
			)
			(layer "F.Fab")
		)
		(fp_line
			(start -1.625092 0.87503)
			(end 1.625092 0.87503)
			(stroke
				(width 0.1)
				(type default)
			)
			(layer "F.Fab")
		)
		(fp_line
			(start 1.625092 -0.87503)
			(end -1.625092 -0.87503)
			(stroke
				(width 0.1)
				(type default)
			)
			(layer "F.Fab")
		)
		(fp_line
			(start 1.625092 0.87503)
			(end 1.625092 -0.87503)
			(stroke
				(width 0.1)
				(type default)
			)
			(layer "F.Fab")
		)
		(pad "1" smd rect
			(at -1.450086 0)
			(size 0.9144 1.6002)
			(layers "F.Cu" "F.Mask" "F.Paste")
			(net "PVCCINFAON_CPU0")
		)
		(pad "2" smd rect
			(at 1.450086 0)
			(size 0.9144 1.6002)
			(layers "F.Cu" "F.Mask" "F.Paste")
			(net "PVNN_TERM_CPU0")
		)
	)
	(footprint ""
		(layer "F.Cu")
		(at 403.946106 -62.994032)
		(property "Reference" "R769"
			(at 0 0 0)
			(layer "F.SilkS")
			(hide yes)
			(effects
				(font
					(size 1.27 1.27)
				)
			)
		)
		(property "Value" ""
			(at 0 0 0)
			(layer "F.Fab")
			(effects
				(font
					(size 1.27 1.27)
				)
			)
		)
		(duplicate_pad_numbers_are_jumpers no)
		(fp_line
			(start -0.7874 -0.4064)
			(end 0.7874 -0.4064)
			(stroke
				(width 0.1524)
				(type default)
			)
			(layer "F.SilkS")
		)
		(fp_line
			(start -0.7874 0.4064)
			(end -0.7874 -0.4064)
			(stroke
				(width 0.1524)
				(type default)
			)
			(layer "F.SilkS")
		)
		(fp_line
			(start 0.7874 -0.4064)
			(end 0.7874 0.4064)
			(stroke
				(width 0.1524)
				(type default)
			)
			(layer "F.SilkS")
		)
		(fp_line
			(start 0.7874 0.4064)
			(end -0.7874 0.4064)
			(stroke
				(width 0.1524)
				(type default)
			)
			(layer "F.SilkS")
		)
		(fp_line
			(start -0.67945 -0.305054)
			(end -0.12065 -0.305054)
			(stroke
				(width 0.1)
				(type default)
			)
			(layer "F.Fab")
		)
		(fp_line
			(start -0.67945 0.3048)
			(end -0.67945 -0.305054)
			(stroke
				(width 0.1)
				(type default)
			)
			(layer "F.Fab")
		)
		(fp_line
			(start -0.12065 -0.305054)
			(end -0.12065 -0.2794)
			(stroke
				(width 0.1)
				(type default)
			)
			(layer "F.Fab")
		)
		(fp_line
			(start -0.12065 -0.2794)
			(end 0.12065 -0.2794)
			(stroke
				(width 0.1)
				(type default)
			)
			(layer "F.Fab")
		)
		(fp_line
			(start -0.12065 0.2794)
			(end -0.12065 0.3048)
			(stroke
				(width 0.1)
				(type default)
			)
			(layer "F.Fab")
		)
		(fp_line
			(start -0.12065 0.3048)
			(end -0.67945 0.3048)
			(stroke
				(width 0.1)
				(type default)
			)
			(layer "F.Fab")
		)
		(fp_line
			(start 0.120396 0.2794)
			(end -0.12065 0.2794)
			(stroke
				(width 0.1)
				(type default)
			)
			(layer "F.Fab")
		)
		(fp_line
			(start 0.120396 0.3048)
			(end 0.120396 0.2794)
			(stroke
				(width 0.1)
				(type default)
			)
			(layer "F.Fab")
		)
		(fp_line
			(start 0.12065 -0.3048)
			(end 0.67945 -0.3048)
			(stroke
				(width 0.1)
				(type default)
			)
			(layer "F.Fab")
		)
		(fp_line
			(start 0.12065 -0.2794)
			(end 0.12065 -0.3048)
			(stroke
				(width 0.1)
				(type default)
			)
			(layer "F.Fab")
		)
		(fp_line
			(start 0.67945 -0.3048)
			(end 0.67945 0.3048)
			(stroke
				(width 0.1)
				(type default)
			)
			(layer "F.Fab")
		)
		(fp_line
			(start 0.67945 0.3048)
			(end 0.120396 0.3048)
			(stroke
				(width 0.1)
				(type default)
			)
			(layer "F.Fab")
		)
		(pad "1" smd circle
			(at -0.40005 0)
			(size 0 0)
			(layers "F.Cu" "F.Mask" "F.Paste")
			(net "PD_TRST_P3")
		)
		(pad "2" smd circle
			(at 0.40005 0)
			(size 0 0)
			(layers "F.Cu" "F.Mask" "F.Paste")
			(net "GND")
		)
	)
	(footprint ""
		(layer "F.Cu")
		(at 410.41701 -408.517344 -90)
		(property "Reference" "C895"
			(at 0 0 270)
			(layer "F.SilkS")
			(hide yes)
			(effects
				(font
					(size 1.27 1.27)
				)
			)
		)
		(property "Value" ""
			(at 0 0 270)
			(layer "F.Fab")
			(effects
				(font
					(size 1.27 1.27)
				)
			)
		)
		(duplicate_pad_numbers_are_jumpers no)
		(fp_line
			(start -0.299974 0.150114)
			(end -0.299974 -0.150114)
			(stroke
				(width 0.1)
				(type default)
			)
			(layer "F.Fab")
		)
		(fp_line
			(start 0.299974 0.150114)
			(end -0.299974 0.150114)
			(stroke
				(width 0.1)
				(type default)
			)
			(layer "F.Fab")
		)
		(fp_line
			(start -0.299974 -0.150114)
			(end 0.299974 -0.150114)
			(stroke
				(width 0.1)
				(type default)
			)
			(layer "F.Fab")
		)
		(fp_line
			(start 0.299974 -0.150114)
			(end 0.299974 0.150114)
			(stroke
				(width 0.1)
				(type default)
			)
			(layer "F.Fab")
		)
		(pad "1" smd rect
			(at -0.2667 0 270)
			(size 0.3048 0.381)
			(layers "F.Cu" "F.Mask" "F.Paste")
			(net "P5E_CPU0_PE3_TX_C_DP<3>")
		)
		(pad "2" smd rect
			(at 0.2667 0 270)
			(size 0.3048 0.381)
			(layers "F.Cu" "F.Mask" "F.Paste")
			(net "P5E_CPU0_PE3_TX_DP<3>")
		)
	)
	(footprint ""
		(layer "F.Cu")
		(at 42.446194 -366.62106)
		(property "Reference" "PC1657"
			(at 0 0 0)
			(layer "F.SilkS")
			(hide yes)
			(effects
				(font
					(size 1.27 1.27)
				)
			)
		)
		(property "Value" ""
			(at 0 0 0)
			(layer "F.Fab")
			(effects
				(font
					(size 1.27 1.27)
				)
			)
		)
		(duplicate_pad_numbers_are_jumpers no)
		(fp_line
			(start -0.7874 -0.4064)
			(end 0.7874 -0.4064)
			(stroke
				(width 0.1524)
				(type default)
			)
			(layer "F.SilkS")
		)
		(fp_line
			(start -0.7874 0.4064)
			(end -0.7874 -0.4064)
			(stroke
				(width 0.1524)
				(type default)
			)
			(layer "F.SilkS")
		)
		(fp_line
			(start 0.7874 -0.4064)
			(end 0.7874 0.4064)
			(stroke
				(width 0.1524)
				(type default)
			)
			(layer "F.SilkS")
		)
		(fp_line
			(start 0.7874 0.4064)
			(end -0.7874 0.4064)
			(stroke
				(width 0.1524)
				(type default)
			)
			(layer "F.SilkS")
		)
		(fp_line
			(start -0.67945 -0.305054)
			(end -0.12065 -0.305054)
			(stroke
				(width 0.1)
				(type default)
			)
			(layer "F.Fab")
		)
		(fp_line
			(start -0.67945 0.3048)
			(end -0.67945 -0.305054)
			(stroke
				(width 0.1)
				(type default)
			)
			(layer "F.Fab")
		)
		(fp_line
			(start -0.12065 -0.305054)
			(end -0.12065 -0.2794)
			(stroke
				(width 0.1)
				(type default)
			)
			(layer "F.Fab")
		)
		(fp_line
			(start -0.12065 -0.2794)
			(end 0.12065 -0.2794)
			(stroke
				(width 0.1)
				(type default)
			)
			(layer "F.Fab")
		)
		(fp_line
			(start -0.12065 0.2794)
			(end -0.12065 0.3048)
			(stroke
				(width 0.1)
				(type default)
			)
			(layer "F.Fab")
		)
		(fp_line
			(start -0.12065 0.3048)
			(end -0.67945 0.3048)
			(stroke
				(width 0.1)
				(type default)
			)
			(layer "F.Fab")
		)
		(fp_line
			(start 0.120396 0.2794)
			(end -0.12065 0.2794)
			(stroke
				(width 0.1)
				(type default)
			)
			(layer "F.Fab")
		)
		(fp_line
			(start 0.120396 0.3048)
			(end 0.120396 0.2794)
			(stroke
				(width 0.1)
				(type default)
			)
			(layer "F.Fab")
		)
		(fp_line
			(start 0.12065 -0.3048)
			(end 0.67945 -0.3048)
			(stroke
				(width 0.1)
				(type default)
			)
			(layer "F.Fab")
		)
		(fp_line
			(start 0.12065 -0.2794)
			(end 0.12065 -0.3048)
			(stroke
				(width 0.1)
				(type default)
			)
			(layer "F.Fab")
		)
		(fp_line
			(start 0.67945 -0.3048)
			(end 0.67945 0.3048)
			(stroke
				(width 0.1)
				(type default)
			)
			(layer "F.Fab")
		)
		(fp_line
			(start 0.67945 0.3048)
			(end 0.120396 0.3048)
			(stroke
				(width 0.1)
				(type default)
			)
			(layer "F.Fab")
		)
		(pad "1" smd circle
			(at -0.40005 0)
			(size 0 0)
			(layers "F.Cu" "F.Mask" "F.Paste")
			(net "P12V_AUX")
		)
		(pad "2" smd circle
			(at 0.40005 0)
			(size 0 0)
			(layers "F.Cu" "F.Mask" "F.Paste")
			(net "GND")
		)
	)
	(footprint ""
		(layer "F.Cu")
		(at 172.77588 -133.695948 -90)
		(property "Reference" "R3047"
			(at 0 0 270)
			(layer "F.SilkS")
			(hide yes)
			(effects
				(font
					(size 1.27 1.27)
				)
			)
		)
		(property "Value" ""
			(at 0 0 270)
			(layer "F.Fab")
			(effects
				(font
					(size 1.27 1.27)
				)
			)
		)
		(duplicate_pad_numbers_are_jumpers no)
		(fp_line
			(start -0.7874 0.4064)
			(end -0.7874 -0.4064)
			(stroke
				(width 0.1524)
				(type default)
			)
			(layer "F.SilkS")
		)
		(fp_line
			(start 0.7874 0.4064)
			(end -0.7874 0.4064)
			(stroke
				(width 0.1524)
				(type default)
			)
			(layer "F.SilkS")
		)
		(fp_line
			(start -0.7874 -0.4064)
			(end 0.7874 -0.4064)
			(stroke
				(width 0.1524)
				(type default)
			)
			(layer "F.SilkS")
		)
		(fp_line
			(start 0.7874 -0.4064)
			(end 0.7874 0.4064)
			(stroke
				(width 0.1524)
				(type default)
			)
			(layer "F.SilkS")
		)
		(fp_line
			(start -0.67945 0.3048)
			(end -0.67945 -0.305054)
			(stroke
				(width 0.1)
				(type default)
			)
			(layer "F.Fab")
		)
		(fp_line
			(start -0.12065 0.3048)
			(end -0.67945 0.3048)
			(stroke
				(width 0.1)
				(type default)
			)
			(layer "F.Fab")
		)
		(fp_line
			(start 0.120396 0.3048)
			(end 0.120396 0.2794)
			(stroke
				(width 0.1)
				(type default)
			)
			(layer "F.Fab")
		)
		(fp_line
			(start 0.67945 0.3048)
			(end 0.120396 0.3048)
			(stroke
				(width 0.1)
				(type default)
			)
			(layer "F.Fab")
		)
		(fp_line
			(start -0.12065 0.2794)
			(end -0.12065 0.3048)
			(stroke
				(width 0.1)
				(type default)
			)
			(layer "F.Fab")
		)
		(fp_line
			(start 0.120396 0.2794)
			(end -0.12065 0.2794)
			(stroke
				(width 0.1)
				(type default)
			)
			(layer "F.Fab")
		)
		(fp_line
			(start -0.12065 -0.2794)
			(end 0.12065 -0.2794)
			(stroke
				(width 0.1)
				(type default)
			)
			(layer "F.Fab")
		)
		(fp_line
			(start 0.12065 -0.2794)
			(end 0.12065 -0.3048)
			(stroke
				(width 0.1)
				(type default)
			)
			(layer "F.Fab")
		)
		(fp_line
			(start 0.12065 -0.3048)
			(end 0.67945 -0.3048)
			(stroke
				(width 0.1)
				(type default)
			)
			(layer "F.Fab")
		)
		(fp_line
			(start 0.67945 -0.3048)
			(end 0.67945 0.3048)
			(stroke
				(width 0.1)
				(type default)
			)
			(layer "F.Fab")
		)
		(fp_line
			(start -0.67945 -0.305054)
			(end -0.12065 -0.305054)
			(stroke
				(width 0.1)
				(type default)
			)
			(layer "F.Fab")
		)
		(fp_line
			(start -0.12065 -0.305054)
			(end -0.12065 -0.2794)
			(stroke
				(width 0.1)
				(type default)
			)
			(layer "F.Fab")
		)
		(pad "1" smd circle
			(at -0.40005 0 270)
			(size 0 0)
			(layers "F.Cu" "F.Mask" "F.Paste")
			(net "MB0_P12V_STBY_PWRGD")
		)
		(pad "2" smd circle
			(at 0.40005 0 270)
			(size 0 0)
			(layers "F.Cu" "F.Mask" "F.Paste")
			(net "PWRGD_PS_PWROK_PLD")
		)
	)
	(footprint ""
		(layer "F.Cu")
		(at 69.917818 -25.192482)
		(property "Reference" "PC2174"
			(at 0 0 0)
			(layer "F.SilkS")
			(hide yes)
			(effects
				(font
					(size 1.27 1.27)
				)
			)
		)
		(property "Value" ""
			(at 0 0 0)
			(layer "F.Fab")
			(effects
				(font
					(size 1.27 1.27)
				)
			)
		)
		(duplicate_pad_numbers_are_jumpers no)
		(fp_line
			(start -0.7874 -0.4064)
			(end 0.7874 -0.4064)
			(stroke
				(width 0.1524)
				(type default)
			)
			(layer "F.SilkS")
		)
		(fp_line
			(start -0.7874 0.4064)
			(end -0.7874 -0.4064)
			(stroke
				(width 0.1524)
				(type default)
			)
			(layer "F.SilkS")
		)
		(fp_line
			(start 0.7874 -0.4064)
			(end 0.7874 0.4064)
			(stroke
				(width 0.1524)
				(type default)
			)
			(layer "F.SilkS")
		)
		(fp_line
			(start 0.7874 0.4064)
			(end -0.7874 0.4064)
			(stroke
				(width 0.1524)
				(type default)
			)
			(layer "F.SilkS")
		)
		(fp_line
			(start -0.67945 -0.305054)
			(end -0.12065 -0.305054)
			(stroke
				(width 0.1)
				(type default)
			)
			(layer "F.Fab")
		)
		(fp_line
			(start -0.67945 0.3048)
			(end -0.67945 -0.305054)
			(stroke
				(width 0.1)
				(type default)
			)
			(layer "F.Fab")
		)
		(fp_line
			(start -0.12065 -0.305054)
			(end -0.12065 -0.2794)
			(stroke
				(width 0.1)
				(type default)
			)
			(layer "F.Fab")
		)
		(fp_line
			(start -0.12065 -0.2794)
			(end 0.12065 -0.2794)
			(stroke
				(width 0.1)
				(type default)
			)
			(layer "F.Fab")
		)
		(fp_line
			(start -0.12065 0.2794)
			(end -0.12065 0.3048)
			(stroke
				(width 0.1)
				(type default)
			)
			(layer "F.Fab")
		)
		(fp_line
			(start -0.12065 0.3048)
			(end -0.67945 0.3048)
			(stroke
				(width 0.1)
				(type default)
			)
			(layer "F.Fab")
		)
		(fp_line
			(start 0.120396 0.2794)
			(end -0.12065 0.2794)
			(stroke
				(width 0.1)
				(type default)
			)
			(layer "F.Fab")
		)
		(fp_line
			(start 0.120396 0.3048)
			(end 0.120396 0.2794)
			(stroke
				(width 0.1)
				(type default)
			)
			(layer "F.Fab")
		)
		(fp_line
			(start 0.12065 -0.3048)
			(end 0.67945 -0.3048)
			(stroke
				(width 0.1)
				(type default)
			)
			(layer "F.Fab")
		)
		(fp_line
			(start 0.12065 -0.2794)
			(end 0.12065 -0.3048)
			(stroke
				(width 0.1)
				(type default)
			)
			(layer "F.Fab")
		)
		(fp_line
			(start 0.67945 -0.3048)
			(end 0.67945 0.3048)
			(stroke
				(width 0.1)
				(type default)
			)
			(layer "F.Fab")
		)
		(fp_line
			(start 0.67945 0.3048)
			(end 0.120396 0.3048)
			(stroke
				(width 0.1)
				(type default)
			)
			(layer "F.Fab")
		)
		(pad "1" smd circle
			(at -0.40005 0)
			(size 0 0)
			(layers "F.Cu" "F.Mask" "F.Paste")
			(net "P12V_OCP_V3_2")
		)
		(pad "2" smd circle
			(at 0.40005 0)
			(size 0 0)
			(layers "F.Cu" "F.Mask" "F.Paste")
			(net "GND")
		)
	)
	(footprint ""
		(layer "F.Cu")
		(at 101.046026 -357.126032 -90)
		(property "Reference" "C2448"
			(at 0 0 270)
			(layer "F.SilkS")
			(hide yes)
			(effects
				(font
					(size 1.27 1.27)
				)
			)
		)
		(property "Value" ""
			(at 0 0 270)
			(layer "F.Fab")
			(effects
				(font
					(size 1.27 1.27)
				)
			)
		)
		(duplicate_pad_numbers_are_jumpers no)
		(fp_line
			(start -1.2954 0.5842)
			(end -1.2954 -0.5842)
			(stroke
				(width 0.1524)
				(type default)
			)
			(layer "F.SilkS")
		)
		(fp_line
			(start 1.2954 0.5842)
			(end -1.2954 0.5842)
			(stroke
				(width 0.1524)
				(type default)
			)
			(layer "F.SilkS")
		)
		(fp_line
			(start -1.2954 -0.5842)
			(end 1.2954 -0.5842)
			(stroke
				(width 0.1524)
				(type default)
			)
			(layer "F.SilkS")
		)
		(fp_line
			(start 0 -0.5842)
			(end 0 0.5842)
			(stroke
				(width 0.1524)
				(type default)
			)
			(layer "F.SilkS")
		)
		(fp_line
			(start 1.2954 -0.5842)
			(end 1.2954 0.5842)
			(stroke
				(width 0.1524)
				(type default)
			)
			(layer "F.SilkS")
		)
		(fp_line
			(start -0.8636 0.4572)
			(end -0.8636 0.4064)
			(stroke
				(width 0.1)
				(type default)
			)
			(layer "F.Fab")
		)
		(fp_line
			(start 0.8636 0.4572)
			(end -0.8636 0.4572)
			(stroke
				(width 0.1)
				(type default)
			)
			(layer "F.Fab")
		)
		(fp_line
			(start -1.1938 0.4064)
			(end -1.1938 -0.4064)
			(stroke
				(width 0.1)
				(type default)
			)
			(layer "F.Fab")
		)
		(fp_line
			(start -0.8636 0.4064)
			(end -1.1938 0.4064)
			(stroke
				(width 0.1)
				(type default)
			)
			(layer "F.Fab")
		)
		(fp_line
			(start 0.8636 0.4064)
			(end 0.8636 0.4572)
			(stroke
				(width 0.1)
				(type default)
			)
			(layer "F.Fab")
		)
		(fp_line
			(start 1.1938 0.4064)
			(end 0.8636 0.4064)
			(stroke
				(width 0.1)
				(type default)
			)
			(layer "F.Fab")
		)
		(fp_line
			(start -1.1938 -0.4064)
			(end -0.8636 -0.4064)
			(stroke
				(width 0.1)
				(type default)
			)
			(layer "F.Fab")
		)
		(fp_line
			(start -0.8636 -0.4064)
			(end -0.8636 -0.4572)
			(stroke
				(width 0.1)
				(type default)
			)
			(layer "F.Fab")
		)
		(fp_line
			(start 0.8636 -0.4064)
			(end 1.1938 -0.4064)
			(stroke
				(width 0.1)
				(type default)
			)
			(layer "F.Fab")
		)
		(fp_line
			(start 1.1938 -0.4064)
			(end 1.1938 0.4064)
			(stroke
				(width 0.1)
				(type default)
			)
			(layer "F.Fab")
		)
		(fp_line
			(start -0.8636 -0.4572)
			(end 0.8636 -0.4572)
			(stroke
				(width 0.1)
				(type default)
			)
			(layer "F.Fab")
		)
		(fp_line
			(start 0.8636 -0.4572)
			(end 0.8636 -0.4064)
			(stroke
				(width 0.1)
				(type default)
			)
			(layer "F.Fab")
		)
		(pad "1" smd rect
			(at -0.7366 0 180)
			(size 0.7112 0.8128)
			(layers "F.Cu" "F.Mask" "F.Paste")
			(net "PVNN_TERM_CPU1")
		)
		(pad "2" smd rect
			(at 0.7366 0 180)
			(size 0.7112 0.8128)
			(layers "F.Cu" "F.Mask" "F.Paste")
			(net "GND")
		)
	)
	(footprint ""
		(layer "F.Cu")
		(at 221.508066 -402.722842 180)
		(property "Reference" "PU296"
			(at -0.222504 7.882128 0)
			(unlocked yes)
			(layer "F.SilkS")
			(effects
				(font
					(size 0.7874 0.5842)
					(thickness 0.1524)
				)
			)
		)
		(property "Value" ""
			(at 0 0 180)
			(layer "F.Fab")
			(effects
				(font
					(size 1.27 1.27)
				)
			)
		)
		(duplicate_pad_numbers_are_jumpers no)
		(fp_line
			(start 2.567686 2.567686)
			(end 2.567686 -2.567686)
			(stroke
				(width 0.1524)
				(type default)
			)
			(layer "F.SilkS")
		)
		(fp_line
			(start 2.567686 -2.567686)
			(end -2.567686 -2.567686)
			(stroke
				(width 0.1524)
				(type default)
			)
			(layer "F.SilkS")
		)
		(fp_line
			(start -2.567686 2.567686)
			(end 2.567686 2.567686)
			(stroke
				(width 0.1524)
				(type default)
			)
			(layer "F.SilkS")
		)
		(fp_line
			(start -2.567686 -2.567686)
			(end -2.567686 2.567686)
			(stroke
				(width 0.1524)
				(type default)
			)
			(layer "F.SilkS")
		)
		(fp_poly
			(pts
				(xy -3.1242 -3.37058) (xy -2.765044 -2.292858) (xy -3.842766 -2.652014)
			)
			(stroke
				(width 0)
				(type default)
			)
			(fill yes)
			(layer "F.SilkS")
		)
		(fp_line
			(start 2.549906 2.549906)
			(end 2.549906 -2.549906)
			(stroke
				(width 0.1)
				(type default)
			)
			(layer "F.Fab")
		)
		(fp_line
			(start 2.549906 -2.549906)
			(end -2.549906 -2.549906)
			(stroke
				(width 0.1)
				(type default)
			)
			(layer "F.Fab")
		)
		(fp_line
			(start -2.549906 2.549906)
			(end 2.549906 2.549906)
			(stroke
				(width 0.1)
				(type default)
			)
			(layer "F.Fab")
		)
		(fp_line
			(start -2.549906 -2.549906)
			(end -2.549906 2.549906)
			(stroke
				(width 0.1)
				(type default)
			)
			(layer "F.Fab")
		)
		(fp_poly
			(pts
				(xy -3.806698 -2.25806) (xy -3.806698 -1.24206) (xy -2.790698 -1.75006)
			)
			(stroke
				(width 0)
				(type default)
			)
			(fill yes)
			(layer "F.Fab")
		)
		(pad "1" smd rect
			(at -2.250186 -1.75006 270)
			(size 0.254 0.3556)
			(layers "F.Cu" "F.Mask" "F.Paste")
			(net "P12V_AUX")
		)
		(pad "2" smd rect
			(at -2.237486 -1.249934 270)
			(size 0.254 0.381)
			(layers "F.Cu" "F.Mask" "F.Paste")
			(net "P12V_AUX")
		)
		(pad "3" smd rect
			(at -2.237486 -0.750062 270)
			(size 0.254 0.381)
			(layers "F.Cu" "F.Mask" "F.Paste")
			(net "HSC_D_OC_3")
		)
		(pad "4" smd rect
			(at -2.237486 -0.249936 270)
			(size 0.254 0.381)
			(layers "F.Cu" "F.Mask" "F.Paste")
			(net "HSC_ON")
		)
		(pad "5" smd rect
			(at -2.237486 0.249936 270)
			(size 0.254 0.381)
			(layers "F.Cu" "F.Mask" "F.Paste")
			(net "HSC_FAULT")
		)
		(pad "6" smd rect
			(at -2.237486 0.750062 270)
			(size 0.254 0.381)
			(layers "F.Cu" "F.Mask" "F.Paste")
			(net "HSC_FLT_TYPE_3")
		)
		(pad "7" smd rect
			(at -2.237486 1.249934 270)
			(size 0.254 0.381)
			(layers "F.Cu" "F.Mask" "F.Paste")
			(net "HSC_NC1_3")
		)
		(pad "8" smd rect
			(at -2.250186 1.75006 270)
			(size 0.254 0.3556)
			(layers "F.Cu" "F.Mask" "F.Paste")
			(net "HSC_MODE_3")
		)
		(pad "9" smd rect
			(at -1.75006 2.250186 180)
			(size 0.254 0.3556)
			(layers "F.Cu" "F.Mask" "F.Paste")
			(net "P12V_PSU")
		)
		(pad "10" smd rect
			(at -1.249934 2.237486 180)
			(size 0.254 0.381)
			(layers "F.Cu" "F.Mask" "F.Paste")
			(net "P12V_PSU")
		)
		(pad "11" smd rect
			(at -0.750062 2.237486 180)
			(size 0.254 0.381)
			(layers "F.Cu" "F.Mask" "F.Paste")
			(net "P12V_PSU")
		)
		(pad "12" smd rect
			(at -0.249936 2.237486 180)
			(size 0.254 0.381)
			(layers "F.Cu" "F.Mask" "F.Paste")
			(net "P12V_PSU")
		)
		(pad "13" smd rect
			(at 0.249936 2.237486 180)
			(size 0.254 0.381)
			(layers "F.Cu" "F.Mask" "F.Paste")
			(net "P12V_PSU")
		)
		(pad "14" smd rect
			(at 0.750062 2.237486 180)
			(size 0.254 0.381)
			(layers "F.Cu" "F.Mask" "F.Paste")
			(net "P12V_PSU")
		)
		(pad "15" smd rect
			(at 1.249934 2.237486 180)
			(size 0.254 0.381)
			(layers "F.Cu" "F.Mask" "F.Paste")
			(net "P12V_PSU")
		)
		(pad "16" smd rect
			(at 1.75006 2.250186 180)
			(size 0.254 0.3556)
			(layers "F.Cu" "F.Mask" "F.Paste")
			(net "P12V_PSU")
		)
		(pad "17" smd rect
			(at 2.250186 1.75006 270)
			(size 0.254 0.3556)
			(layers "F.Cu" "F.Mask" "F.Paste")
			(net "HSC_SCREF_3")
		)
		(pad "18" smd rect
			(at 2.237486 1.249934 270)
			(size 0.254 0.381)
			(layers "F.Cu" "F.Mask" "F.Paste")
			(net "HSC_VTEMP")
		)
		(pad "19" smd rect
			(at 2.237486 0.750062 270)
			(size 0.254 0.381)
			(layers "F.Cu" "F.Mask" "F.Paste")
			(net "HSC_SS")
		)
		(pad "20" smd rect
			(at 2.237486 0.249936 270)
			(size 0.254 0.381)
			(layers "F.Cu" "F.Mask" "F.Paste")
			(net "AGND_HSC")
		)
		(pad "21" smd rect
			(at 2.237486 -0.249936 270)
			(size 0.254 0.381)
			(layers "F.Cu" "F.Mask" "F.Paste")
			(net "HSC_VDD_R_3")
		)
		(pad "22" smd rect
			(at 2.237486 -0.750062 270)
			(size 0.254 0.381)
			(layers "F.Cu" "F.Mask" "F.Paste")
			(net "HSC_IMON")
		)
		(pad "23" smd rect
			(at 2.237486 -1.249934 270)
			(size 0.254 0.381)
			(layers "F.Cu" "F.Mask" "F.Paste")
			(net "HSC_CS_3")
		)
		(pad "24" smd rect
			(at 2.250186 -1.75006 270)
			(size 0.254 0.3556)
			(layers "F.Cu" "F.Mask" "F.Paste")
			(net "HSC_OCREF")
		)
		(pad "25" smd rect
			(at 1.75006 -2.250186 180)
			(size 0.254 0.3556)
			(layers "F.Cu" "F.Mask" "F.Paste")
			(net "P12V_AUX")
		)
		(pad "26" smd rect
			(at 1.249934 -2.237486 180)
			(size 0.254 0.381)
			(layers "F.Cu" "F.Mask" "F.Paste")
			(net "P12V_AUX")
		)
		(pad "27" smd rect
			(at 0.750062 -2.237486 180)
			(size 0.254 0.381)
			(layers "F.Cu" "F.Mask" "F.Paste")
			(net "P12V_AUX")
		)
		(pad "28" smd rect
			(at 0.249936 -2.237486 180)
			(size 0.254 0.381)
			(layers "F.Cu" "F.Mask" "F.Paste")
			(net "P12V_AUX")
		)
		(pad "29" smd rect
			(at -0.249936 -2.237486 180)
			(size 0.254 0.381)
			(layers "F.Cu" "F.Mask" "F.Paste")
			(net "P12V_AUX")
		)
		(pad "30" smd rect
			(at -0.750062 -2.237486 180)
			(size 0.254 0.381)
			(layers "F.Cu" "F.Mask" "F.Paste")
			(net "P12V_AUX")
		)
		(pad "31" smd rect
			(at -1.249934 -2.237486 180)
			(size 0.254 0.381)
			(layers "F.Cu" "F.Mask" "F.Paste")
			(net "P12V_AUX")
		)
		(pad "32" smd rect
			(at -1.75006 -2.250186 180)
			(size 0.254 0.3556)
			(layers "F.Cu" "F.Mask" "F.Paste")
			(net "P12V_AUX")
		)
		(pad "33" smd rect
			(at 0 0 180)
			(size 3.4036 3.4036)
			(layers "F.Cu" "F.Mask" "F.Paste")
			(net "P12V_PSU")
		)
		(zone
			(layer "F.Cu")
			(hatch none 0.5)
			(connect_pads
				(clearance 0)
			)
			(min_thickness 0.25)
			(keepout
				(tracks not_allowed)
				(vias allowed)
				(pads allowed)
				(copperpour not_allowed)
				(footprints allowed)
			)
			(placement
				(enabled no)
				(sheetname "")
			)
			(fill
				(thermal_gap 0.5)
				(thermal_bridge_width 0.5)
				(island_removal_mode 0)
			)
			(polygon
				(pts
					(xy 223.529652 -401.275042) (xy 223.529652 -400.769328) (xy 223.46158 -400.701256) (xy 222.955866 -400.701256)
					(xy 222.955866 -400.726656) (xy 220.060266 -400.726656) (xy 220.060266 -400.701256) (xy 219.48648 -400.701256)
					(xy 219.48648 -401.275042) (xy 219.51188 -401.275042) (xy 219.51188 -404.170642) (xy 219.48648 -404.170642)
					(xy 219.48648 -404.475442) (xy 219.755466 -404.475442) (xy 219.755466 -400.970242) (xy 223.260666 -400.970242)
					(xy 223.260666 -403.230842) (xy 223.504252 -403.230842) (xy 223.504252 -401.275042)
				)
			)
		)
	)
	(footprint ""
		(layer "F.Cu")
		(at 347.057726 -22.36978 90)
		(property "Reference" "R1828"
			(at 0 0 90)
			(layer "F.SilkS")
			(hide yes)
			(effects
				(font
					(size 1.27 1.27)
				)
			)
		)
		(property "Value" ""
			(at 0 0 90)
			(layer "F.Fab")
			(effects
				(font
					(size 1.27 1.27)
				)
			)
		)
		(duplicate_pad_numbers_are_jumpers no)
		(fp_line
			(start 0.7874 -0.4064)
			(end 0.7874 0.4064)
			(stroke
				(width 0.1524)
				(type default)
			)
			(layer "F.SilkS")
		)
		(fp_line
			(start -0.7874 -0.4064)
			(end 0.7874 -0.4064)
			(stroke
				(width 0.1524)
				(type default)
			)
			(layer "F.SilkS")
		)
		(fp_line
			(start 0.7874 0.4064)
			(end -0.7874 0.4064)
			(stroke
				(width 0.1524)
				(type default)
			)
			(layer "F.SilkS")
		)
		(fp_line
			(start -0.7874 0.4064)
			(end -0.7874 -0.4064)
			(stroke
				(width 0.1524)
				(type default)
			)
			(layer "F.SilkS")
		)
		(fp_line
			(start -0.12065 -0.305054)
			(end -0.12065 -0.2794)
			(stroke
				(width 0.1)
				(type default)
			)
			(layer "F.Fab")
		)
		(fp_line
			(start -0.67945 -0.305054)
			(end -0.12065 -0.305054)
			(stroke
				(width 0.1)
				(type default)
			)
			(layer "F.Fab")
		)
		(fp_line
			(start 0.67945 -0.3048)
			(end 0.67945 0.3048)
			(stroke
				(width 0.1)
				(type default)
			)
			(layer "F.Fab")
		)
		(fp_line
			(start 0.12065 -0.3048)
			(end 0.67945 -0.3048)
			(stroke
				(width 0.1)
				(type default)
			)
			(layer "F.Fab")
		)
		(fp_line
			(start 0.12065 -0.2794)
			(end 0.12065 -0.3048)
			(stroke
				(width 0.1)
				(type default)
			)
			(layer "F.Fab")
		)
		(fp_line
			(start -0.12065 -0.2794)
			(end 0.12065 -0.2794)
			(stroke
				(width 0.1)
				(type default)
			)
			(layer "F.Fab")
		)
		(fp_line
			(start 0.120396 0.2794)
			(end -0.12065 0.2794)
			(stroke
				(width 0.1)
				(type default)
			)
			(layer "F.Fab")
		)
		(fp_line
			(start -0.12065 0.2794)
			(end -0.12065 0.3048)
			(stroke
				(width 0.1)
				(type default)
			)
			(layer "F.Fab")
		)
		(fp_line
			(start 0.67945 0.3048)
			(end 0.120396 0.3048)
			(stroke
				(width 0.1)
				(type default)
			)
			(layer "F.Fab")
		)
		(fp_line
			(start 0.120396 0.3048)
			(end 0.120396 0.2794)
			(stroke
				(width 0.1)
				(type default)
			)
			(layer "F.Fab")
		)
		(fp_line
			(start -0.12065 0.3048)
			(end -0.67945 0.3048)
			(stroke
				(width 0.1)
				(type default)
			)
			(layer "F.Fab")
		)
		(fp_line
			(start -0.67945 0.3048)
			(end -0.67945 -0.305054)
			(stroke
				(width 0.1)
				(type default)
			)
			(layer "F.Fab")
		)
		(pad "1" smd circle
			(at -0.40005 0 90)
			(size 0 0)
			(layers "F.Cu" "F.Mask" "F.Paste")
			(net "USB_OC1_REAR_R_N")
		)
		(pad "2" smd circle
			(at 0.40005 0 90)
			(size 0 0)
			(layers "F.Cu" "F.Mask" "F.Paste")
			(net "P3V3_AUX")
		)
	)
	(footprint ""
		(layer "F.Cu")
		(at 46.676818 -105.874058)
		(property "Reference" "L15"
			(at 0 0 0)
			(layer "F.SilkS")
			(hide yes)
			(effects
				(font
					(size 1.27 1.27)
				)
			)
		)
		(property "Value" ""
			(at 0 0 0)
			(layer "F.Fab")
			(effects
				(font
					(size 1.27 1.27)
				)
			)
		)
		(duplicate_pad_numbers_are_jumpers no)
		(fp_line
			(start -1.27 -0.5842)
			(end 1.27 -0.5842)
			(stroke
				(width 0.1524)
				(type default)
			)
			(layer "F.SilkS")
		)
		(fp_line
			(start -1.27 -0.5588)
			(end -1.27 -0.5842)
			(stroke
				(width 0.1524)
				(type default)
			)
			(layer "F.SilkS")
		)
		(fp_line
			(start -1.27 0.5842)
			(end -1.27 -0.5842)
			(stroke
				(width 0.1524)
				(type default)
			)
			(layer "F.SilkS")
		)
		(fp_line
			(start -0.127 0.5842)
			(end -0.127 -0.5842)
			(stroke
				(width 0.1524)
				(type default)
			)
			(layer "F.SilkS")
		)
		(fp_line
			(start 0.127 0.5842)
			(end 0.127 -0.5842)
			(stroke
				(width 0.1524)
				(type default)
			)
			(layer "F.SilkS")
		)
		(fp_line
			(start 1.27 0.5842)
			(end -1.27 0.5842)
			(stroke
				(width 0.1524)
				(type default)
			)
			(layer "F.SilkS")
		)
		(fp_line
			(start 1.27 0.5842)
			(end 1.27 -0.5842)
			(stroke
				(width 0.1524)
				(type default)
			)
			(layer "F.SilkS")
		)
		(fp_line
			(start -1.194308 -0.406654)
			(end -0.9144 -0.406654)
			(stroke
				(width 0.1)
				(type default)
			)
			(layer "F.Fab")
		)
		(fp_line
			(start -1.194308 0.406654)
			(end -1.194308 -0.406654)
			(stroke
				(width 0.1)
				(type default)
			)
			(layer "F.Fab")
		)
		(fp_line
			(start -0.9144 -0.508)
			(end 0.9144 -0.508)
			(stroke
				(width 0.1)
				(type default)
			)
			(layer "F.Fab")
		)
		(fp_line
			(start -0.9144 -0.406654)
			(end -0.9144 -0.508)
			(stroke
				(width 0.1)
				(type default)
			)
			(layer "F.Fab")
		)
		(fp_line
			(start -0.9144 0.406654)
			(end -1.194308 0.406654)
			(stroke
				(width 0.1)
				(type default)
			)
			(layer "F.Fab")
		)
		(fp_line
			(start -0.9144 0.508)
			(end -0.9144 0.406654)
			(stroke
				(width 0.1)
				(type default)
			)
			(layer "F.Fab")
		)
		(fp_line
			(start 0.9144 -0.508)
			(end 0.9144 -0.406654)
			(stroke
				(width 0.1)
				(type default)
			)
			(layer "F.Fab")
		)
		(fp_line
			(start 0.9144 -0.406654)
			(end 1.1938 -0.406654)
			(stroke
				(width 0.1)
				(type default)
			)
			(layer "F.Fab")
		)
		(fp_line
			(start 0.9144 0.4064)
			(end 0.9144 0.508)
			(stroke
				(width 0.1)
				(type default)
			)
			(layer "F.Fab")
		)
		(fp_line
			(start 0.9144 0.508)
			(end -0.9144 0.508)
			(stroke
				(width 0.1)
				(type default)
			)
			(layer "F.Fab")
		)
		(fp_line
			(start 1.1938 -0.406654)
			(end 1.1938 0.4064)
			(stroke
				(width 0.1)
				(type default)
			)
			(layer "F.Fab")
		)
		(fp_line
			(start 1.1938 0.4064)
			(end 0.9144 0.4064)
			(stroke
				(width 0.1)
				(type default)
			)
			(layer "F.Fab")
		)
		(pad "1" smd rect
			(at -0.7366 0 270)
			(size 0.7112 0.8128)
			(layers "F.Cu" "F.Mask" "F.Paste")
			(net "P3V3_MAX11617_VDD")
		)
		(pad "2" smd rect
			(at 0.7366 0 270)
			(size 0.7112 0.8128)
			(layers "F.Cu" "F.Mask" "F.Paste")
			(net "P3V3_AUX")
		)
	)
	(footprint ""
		(layer "F.Cu")
		(at 107.96905 -29.842714)
		(property "Reference" "C1859"
			(at 0 0 0)
			(layer "F.SilkS")
			(hide yes)
			(effects
				(font
					(size 1.27 1.27)
				)
			)
		)
		(property "Value" ""
			(at 0 0 0)
			(layer "F.Fab")
			(effects
				(font
					(size 1.27 1.27)
				)
			)
		)
		(duplicate_pad_numbers_are_jumpers no)
		(fp_line
			(start -0.7874 -0.4064)
			(end 0.7874 -0.4064)
			(stroke
				(width 0.1524)
				(type default)
			)
			(layer "F.SilkS")
		)
		(fp_line
			(start -0.7874 0.4064)
			(end -0.7874 -0.4064)
			(stroke
				(width 0.1524)
				(type default)
			)
			(layer "F.SilkS")
		)
		(fp_line
			(start 0.7874 -0.4064)
			(end 0.7874 0.4064)
			(stroke
				(width 0.1524)
				(type default)
			)
			(layer "F.SilkS")
		)
		(fp_line
			(start 0.7874 0.4064)
			(end -0.7874 0.4064)
			(stroke
				(width 0.1524)
				(type default)
			)
			(layer "F.SilkS")
		)
		(fp_line
			(start -0.67945 -0.305054)
			(end -0.12065 -0.305054)
			(stroke
				(width 0.1)
				(type default)
			)
			(layer "F.Fab")
		)
		(fp_line
			(start -0.67945 0.3048)
			(end -0.67945 -0.305054)
			(stroke
				(width 0.1)
				(type default)
			)
			(layer "F.Fab")
		)
		(fp_line
			(start -0.12065 -0.305054)
			(end -0.12065 -0.2794)
			(stroke
				(width 0.1)
				(type default)
			)
			(layer "F.Fab")
		)
		(fp_line
			(start -0.12065 -0.2794)
			(end 0.12065 -0.2794)
			(stroke
				(width 0.1)
				(type default)
			)
			(layer "F.Fab")
		)
		(fp_line
			(start -0.12065 0.2794)
			(end -0.12065 0.3048)
			(stroke
				(width 0.1)
				(type default)
			)
			(layer "F.Fab")
		)
		(fp_line
			(start -0.12065 0.3048)
			(end -0.67945 0.3048)
			(stroke
				(width 0.1)
				(type default)
			)
			(layer "F.Fab")
		)
		(fp_line
			(start 0.120396 0.2794)
			(end -0.12065 0.2794)
			(stroke
				(width 0.1)
				(type default)
			)
			(layer "F.Fab")
		)
		(fp_line
			(start 0.120396 0.3048)
			(end 0.120396 0.2794)
			(stroke
				(width 0.1)
				(type default)
			)
			(layer "F.Fab")
		)
		(fp_line
			(start 0.12065 -0.3048)
			(end 0.67945 -0.3048)
			(stroke
				(width 0.1)
				(type default)
			)
			(layer "F.Fab")
		)
		(fp_line
			(start 0.12065 -0.2794)
			(end 0.12065 -0.3048)
			(stroke
				(width 0.1)
				(type default)
			)
			(layer "F.Fab")
		)
		(fp_line
			(start 0.67945 -0.3048)
			(end 0.67945 0.3048)
			(stroke
				(width 0.1)
				(type default)
			)
			(layer "F.Fab")
		)
		(fp_line
			(start 0.67945 0.3048)
			(end 0.120396 0.3048)
			(stroke
				(width 0.1)
				(type default)
			)
			(layer "F.Fab")
		)
		(pad "1" smd circle
			(at -0.40005 0)
			(size 0 0)
			(layers "F.Cu" "F.Mask" "F.Paste")
			(net "P3V3_AUX")
		)
		(pad "2" smd circle
			(at 0.40005 0)
			(size 0 0)
			(layers "F.Cu" "F.Mask" "F.Paste")
			(net "GND")
		)
	)
	(footprint ""
		(layer "F.Cu")
		(at 424.7642 -16.088614 90)
		(property "Reference" "C862"
			(at 0 0 90)
			(layer "F.SilkS")
			(hide yes)
			(effects
				(font
					(size 1.27 1.27)
				)
			)
		)
		(property "Value" ""
			(at 0 0 90)
			(layer "F.Fab")
			(effects
				(font
					(size 1.27 1.27)
				)
			)
		)
		(duplicate_pad_numbers_are_jumpers no)
		(fp_line
			(start 0.299974 -0.150114)
			(end 0.299974 0.150114)
			(stroke
				(width 0.1)
				(type default)
			)
			(layer "F.Fab")
		)
		(fp_line
			(start -0.299974 -0.150114)
			(end 0.299974 -0.150114)
			(stroke
				(width 0.1)
				(type default)
			)
			(layer "F.Fab")
		)
		(fp_line
			(start 0.299974 0.150114)
			(end -0.299974 0.150114)
			(stroke
				(width 0.1)
				(type default)
			)
			(layer "F.Fab")
		)
		(fp_line
			(start -0.299974 0.150114)
			(end -0.299974 -0.150114)
			(stroke
				(width 0.1)
				(type default)
			)
			(layer "F.Fab")
		)
		(pad "1" smd rect
			(at -0.2667 0 90)
			(size 0.3048 0.381)
			(layers "F.Cu" "F.Mask" "F.Paste")
			(net "P5E_CPU0_PE1_TX_C_DN<3>")
		)
		(pad "2" smd rect
			(at 0.2667 0 90)
			(size 0.3048 0.381)
			(layers "F.Cu" "F.Mask" "F.Paste")
			(net "P5E_CPU0_PE1_TX_DN<3>")
		)
	)
	(footprint ""
		(layer "F.Cu")
		(at 77.982826 -347.481398 -90)
		(property "Reference" "PC1363"
			(at 0 0 270)
			(layer "F.SilkS")
			(hide yes)
			(effects
				(font
					(size 1.27 1.27)
				)
			)
		)
		(property "Value" ""
			(at 0 0 270)
			(layer "F.Fab")
			(effects
				(font
					(size 1.27 1.27)
				)
			)
		)
		(duplicate_pad_numbers_are_jumpers no)
		(fp_line
			(start -0.7874 0.4064)
			(end -0.7874 -0.4064)
			(stroke
				(width 0.1524)
				(type default)
			)
			(layer "F.SilkS")
		)
		(fp_line
			(start 0.7874 0.4064)
			(end -0.7874 0.4064)
			(stroke
				(width 0.1524)
				(type default)
			)
			(layer "F.SilkS")
		)
		(fp_line
			(start -0.7874 -0.4064)
			(end 0.7874 -0.4064)
			(stroke
				(width 0.1524)
				(type default)
			)
			(layer "F.SilkS")
		)
		(fp_line
			(start 0.7874 -0.4064)
			(end 0.7874 0.4064)
			(stroke
				(width 0.1524)
				(type default)
			)
			(layer "F.SilkS")
		)
		(fp_line
			(start -0.67945 0.3048)
			(end -0.67945 -0.305054)
			(stroke
				(width 0.1)
				(type default)
			)
			(layer "F.Fab")
		)
		(fp_line
			(start -0.12065 0.3048)
			(end -0.67945 0.3048)
			(stroke
				(width 0.1)
				(type default)
			)
			(layer "F.Fab")
		)
		(fp_line
			(start 0.120396 0.3048)
			(end 0.120396 0.2794)
			(stroke
				(width 0.1)
				(type default)
			)
			(layer "F.Fab")
		)
		(fp_line
			(start 0.67945 0.3048)
			(end 0.120396 0.3048)
			(stroke
				(width 0.1)
				(type default)
			)
			(layer "F.Fab")
		)
		(fp_line
			(start -0.12065 0.2794)
			(end -0.12065 0.3048)
			(stroke
				(width 0.1)
				(type default)
			)
			(layer "F.Fab")
		)
		(fp_line
			(start 0.120396 0.2794)
			(end -0.12065 0.2794)
			(stroke
				(width 0.1)
				(type default)
			)
			(layer "F.Fab")
		)
		(fp_line
			(start -0.12065 -0.2794)
			(end 0.12065 -0.2794)
			(stroke
				(width 0.1)
				(type default)
			)
			(layer "F.Fab")
		)
		(fp_line
			(start 0.12065 -0.2794)
			(end 0.12065 -0.3048)
			(stroke
				(width 0.1)
				(type default)
			)
			(layer "F.Fab")
		)
		(fp_line
			(start 0.12065 -0.3048)
			(end 0.67945 -0.3048)
			(stroke
				(width 0.1)
				(type default)
			)
			(layer "F.Fab")
		)
		(fp_line
			(start 0.67945 -0.3048)
			(end 0.67945 0.3048)
			(stroke
				(width 0.1)
				(type default)
			)
			(layer "F.Fab")
		)
		(fp_line
			(start -0.67945 -0.305054)
			(end -0.12065 -0.305054)
			(stroke
				(width 0.1)
				(type default)
			)
			(layer "F.Fab")
		)
		(fp_line
			(start -0.12065 -0.305054)
			(end -0.12065 -0.2794)
			(stroke
				(width 0.1)
				(type default)
			)
			(layer "F.Fab")
		)
		(pad "1" smd circle
			(at -0.40005 0 270)
			(size 0 0)
			(layers "F.Cu" "F.Mask" "F.Paste")
			(net "GND")
		)
		(pad "2" smd circle
			(at 0.40005 0 270)
			(size 0 0)
			(layers "F.Cu" "F.Mask" "F.Paste")
			(net "PVCCIN_CPU1_VREF")
		)
	)
	(footprint ""
		(layer "F.Cu")
		(at 105.2957 -256.6543 -90)
		(property "Reference" "C445"
			(at 0 0 270)
			(layer "F.SilkS")
			(hide yes)
			(effects
				(font
					(size 1.27 1.27)
				)
			)
		)
		(property "Value" ""
			(at 0 0 270)
			(layer "F.Fab")
			(effects
				(font
					(size 1.27 1.27)
				)
			)
		)
		(duplicate_pad_numbers_are_jumpers no)
		(fp_line
			(start -0.7874 0.4064)
			(end -0.7874 -0.4064)
			(stroke
				(width 0.1524)
				(type default)
			)
			(layer "F.SilkS")
		)
		(fp_line
			(start 0.7874 0.4064)
			(end -0.7874 0.4064)
			(stroke
				(width 0.1524)
				(type default)
			)
			(layer "F.SilkS")
		)
		(fp_line
			(start -0.7874 -0.4064)
			(end 0.7874 -0.4064)
			(stroke
				(width 0.1524)
				(type default)
			)
			(layer "F.SilkS")
		)
		(fp_line
			(start 0.7874 -0.4064)
			(end 0.7874 0.4064)
			(stroke
				(width 0.1524)
				(type default)
			)
			(layer "F.SilkS")
		)
		(fp_line
			(start -0.67945 0.3048)
			(end -0.67945 -0.305054)
			(stroke
				(width 0.1)
				(type default)
			)
			(layer "F.Fab")
		)
		(fp_line
			(start -0.12065 0.3048)
			(end -0.67945 0.3048)
			(stroke
				(width 0.1)
				(type default)
			)
			(layer "F.Fab")
		)
		(fp_line
			(start 0.120396 0.3048)
			(end 0.120396 0.2794)
			(stroke
				(width 0.1)
				(type default)
			)
			(layer "F.Fab")
		)
		(fp_line
			(start 0.67945 0.3048)
			(end 0.120396 0.3048)
			(stroke
				(width 0.1)
				(type default)
			)
			(layer "F.Fab")
		)
		(fp_line
			(start -0.12065 0.2794)
			(end -0.12065 0.3048)
			(stroke
				(width 0.1)
				(type default)
			)
			(layer "F.Fab")
		)
		(fp_line
			(start 0.120396 0.2794)
			(end -0.12065 0.2794)
			(stroke
				(width 0.1)
				(type default)
			)
			(layer "F.Fab")
		)
		(fp_line
			(start -0.12065 -0.2794)
			(end 0.12065 -0.2794)
			(stroke
				(width 0.1)
				(type default)
			)
			(layer "F.Fab")
		)
		(fp_line
			(start 0.12065 -0.2794)
			(end 0.12065 -0.3048)
			(stroke
				(width 0.1)
				(type default)
			)
			(layer "F.Fab")
		)
		(fp_line
			(start 0.12065 -0.3048)
			(end 0.67945 -0.3048)
			(stroke
				(width 0.1)
				(type default)
			)
			(layer "F.Fab")
		)
		(fp_line
			(start 0.67945 -0.3048)
			(end 0.67945 0.3048)
			(stroke
				(width 0.1)
				(type default)
			)
			(layer "F.Fab")
		)
		(fp_line
			(start -0.67945 -0.305054)
			(end -0.12065 -0.305054)
			(stroke
				(width 0.1)
				(type default)
			)
			(layer "F.Fab")
		)
		(fp_line
			(start -0.12065 -0.305054)
			(end -0.12065 -0.2794)
			(stroke
				(width 0.1)
				(type default)
			)
			(layer "F.Fab")
		)
		(pad "1" smd circle
			(at -0.40005 0 270)
			(size 0 0)
			(layers "F.Cu" "F.Mask" "F.Paste")
			(net "PVCCFA_EHV_CPU1")
		)
		(pad "2" smd circle
			(at 0.40005 0 270)
			(size 0 0)
			(layers "F.Cu" "F.Mask" "F.Paste")
			(net "GND")
		)
	)
	(footprint ""
		(layer "F.Cu")
		(at 120.333262 -16.91005)
		(property "Reference" "R4201"
			(at 0 0 0)
			(layer "F.SilkS")
			(hide yes)
			(effects
				(font
					(size 1.27 1.27)
				)
			)
		)
		(property "Value" ""
			(at 0 0 0)
			(layer "F.Fab")
			(effects
				(font
					(size 1.27 1.27)
				)
			)
		)
		(duplicate_pad_numbers_are_jumpers no)
		(fp_line
			(start -0.7874 -0.4064)
			(end 0.7874 -0.4064)
			(stroke
				(width 0.1524)
				(type default)
			)
			(layer "F.SilkS")
		)
		(fp_line
			(start -0.7874 0.4064)
			(end -0.7874 -0.4064)
			(stroke
				(width 0.1524)
				(type default)
			)
			(layer "F.SilkS")
		)
		(fp_line
			(start 0.7874 -0.4064)
			(end 0.7874 0.4064)
			(stroke
				(width 0.1524)
				(type default)
			)
			(layer "F.SilkS")
		)
		(fp_line
			(start 0.7874 0.4064)
			(end -0.7874 0.4064)
			(stroke
				(width 0.1524)
				(type default)
			)
			(layer "F.SilkS")
		)
		(fp_line
			(start -0.67945 -0.305054)
			(end -0.12065 -0.305054)
			(stroke
				(width 0.1)
				(type default)
			)
			(layer "F.Fab")
		)
		(fp_line
			(start -0.67945 0.3048)
			(end -0.67945 -0.305054)
			(stroke
				(width 0.1)
				(type default)
			)
			(layer "F.Fab")
		)
		(fp_line
			(start -0.12065 -0.305054)
			(end -0.12065 -0.2794)
			(stroke
				(width 0.1)
				(type default)
			)
			(layer "F.Fab")
		)
		(fp_line
			(start -0.12065 -0.2794)
			(end 0.12065 -0.2794)
			(stroke
				(width 0.1)
				(type default)
			)
			(layer "F.Fab")
		)
		(fp_line
			(start -0.12065 0.2794)
			(end -0.12065 0.3048)
			(stroke
				(width 0.1)
				(type default)
			)
			(layer "F.Fab")
		)
		(fp_line
			(start -0.12065 0.3048)
			(end -0.67945 0.3048)
			(stroke
				(width 0.1)
				(type default)
			)
			(layer "F.Fab")
		)
		(fp_line
			(start 0.120396 0.2794)
			(end -0.12065 0.2794)
			(stroke
				(width 0.1)
				(type default)
			)
			(layer "F.Fab")
		)
		(fp_line
			(start 0.120396 0.3048)
			(end 0.120396 0.2794)
			(stroke
				(width 0.1)
				(type default)
			)
			(layer "F.Fab")
		)
		(fp_line
			(start 0.12065 -0.3048)
			(end 0.67945 -0.3048)
			(stroke
				(width 0.1)
				(type default)
			)
			(layer "F.Fab")
		)
		(fp_line
			(start 0.12065 -0.2794)
			(end 0.12065 -0.3048)
			(stroke
				(width 0.1)
				(type default)
			)
			(layer "F.Fab")
		)
		(fp_line
			(start 0.67945 -0.3048)
			(end 0.67945 0.3048)
			(stroke
				(width 0.1)
				(type default)
			)
			(layer "F.Fab")
		)
		(fp_line
			(start 0.67945 0.3048)
			(end 0.120396 0.3048)
			(stroke
				(width 0.1)
				(type default)
			)
			(layer "F.Fab")
		)
		(pad "1" smd circle
			(at -0.40005 0)
			(size 0 0)
			(layers "F.Cu" "F.Mask" "F.Paste")
			(net "U273_3_ADD0")
		)
		(pad "2" smd circle
			(at 0.40005 0)
			(size 0 0)
			(layers "F.Cu" "F.Mask" "F.Paste")
			(net "GND")
		)
	)
	(footprint ""
		(layer "F.Cu")
		(at 118.954042 -66.693034 90)
		(property "Reference" "R929"
			(at 0 0 90)
			(layer "F.SilkS")
			(hide yes)
			(effects
				(font
					(size 1.27 1.27)
				)
			)
		)
		(property "Value" ""
			(at 0 0 90)
			(layer "F.Fab")
			(effects
				(font
					(size 1.27 1.27)
				)
			)
		)
		(duplicate_pad_numbers_are_jumpers no)
		(fp_line
			(start 0.7874 -0.4064)
			(end 0.7874 0.4064)
			(stroke
				(width 0.1524)
				(type default)
			)
			(layer "F.SilkS")
		)
		(fp_line
			(start -0.7874 -0.4064)
			(end 0.7874 -0.4064)
			(stroke
				(width 0.1524)
				(type default)
			)
			(layer "F.SilkS")
		)
		(fp_line
			(start 0.7874 0.4064)
			(end -0.7874 0.4064)
			(stroke
				(width 0.1524)
				(type default)
			)
			(layer "F.SilkS")
		)
		(fp_line
			(start -0.7874 0.4064)
			(end -0.7874 -0.4064)
			(stroke
				(width 0.1524)
				(type default)
			)
			(layer "F.SilkS")
		)
		(fp_line
			(start -0.12065 -0.305054)
			(end -0.12065 -0.2794)
			(stroke
				(width 0.1)
				(type default)
			)
			(layer "F.Fab")
		)
		(fp_line
			(start -0.67945 -0.305054)
			(end -0.12065 -0.305054)
			(stroke
				(width 0.1)
				(type default)
			)
			(layer "F.Fab")
		)
		(fp_line
			(start 0.67945 -0.3048)
			(end 0.67945 0.3048)
			(stroke
				(width 0.1)
				(type default)
			)
			(layer "F.Fab")
		)
		(fp_line
			(start 0.12065 -0.3048)
			(end 0.67945 -0.3048)
			(stroke
				(width 0.1)
				(type default)
			)
			(layer "F.Fab")
		)
		(fp_line
			(start 0.12065 -0.2794)
			(end 0.12065 -0.3048)
			(stroke
				(width 0.1)
				(type default)
			)
			(layer "F.Fab")
		)
		(fp_line
			(start -0.12065 -0.2794)
			(end 0.12065 -0.2794)
			(stroke
				(width 0.1)
				(type default)
			)
			(layer "F.Fab")
		)
		(fp_line
			(start 0.120396 0.2794)
			(end -0.12065 0.2794)
			(stroke
				(width 0.1)
				(type default)
			)
			(layer "F.Fab")
		)
		(fp_line
			(start -0.12065 0.2794)
			(end -0.12065 0.3048)
			(stroke
				(width 0.1)
				(type default)
			)
			(layer "F.Fab")
		)
		(fp_line
			(start 0.67945 0.3048)
			(end 0.120396 0.3048)
			(stroke
				(width 0.1)
				(type default)
			)
			(layer "F.Fab")
		)
		(fp_line
			(start 0.120396 0.3048)
			(end 0.120396 0.2794)
			(stroke
				(width 0.1)
				(type default)
			)
			(layer "F.Fab")
		)
		(fp_line
			(start -0.12065 0.3048)
			(end -0.67945 0.3048)
			(stroke
				(width 0.1)
				(type default)
			)
			(layer "F.Fab")
		)
		(fp_line
			(start -0.67945 0.3048)
			(end -0.67945 -0.305054)
			(stroke
				(width 0.1)
				(type default)
			)
			(layer "F.Fab")
		)
		(pad "1" smd circle
			(at -0.40005 0 90)
			(size 0 0)
			(layers "F.Cu" "F.Mask" "F.Paste")
			(net "P3V3_AUX")
		)
		(pad "2" smd circle
			(at 0.40005 0 90)
			(size 0 0)
			(layers "F.Cu" "F.Mask" "F.Paste")
			(net "JTAG_BMC_PLD_TMS")
		)
	)
	(footprint ""
		(layer "F.Cu")
		(at 153.944066 -31.341568 -90)
		(property "Reference" "C2317"
			(at 0 0 270)
			(layer "F.SilkS")
			(hide yes)
			(effects
				(font
					(size 1.27 1.27)
				)
			)
		)
		(property "Value" ""
			(at 0 0 270)
			(layer "F.Fab")
			(effects
				(font
					(size 1.27 1.27)
				)
			)
		)
		(duplicate_pad_numbers_are_jumpers no)
		(fp_line
			(start -0.7874 0.4064)
			(end -0.7874 -0.4064)
			(stroke
				(width 0.1524)
				(type default)
			)
			(layer "F.SilkS")
		)
		(fp_line
			(start 0.7874 0.4064)
			(end -0.7874 0.4064)
			(stroke
				(width 0.1524)
				(type default)
			)
			(layer "F.SilkS")
		)
		(fp_line
			(start -0.7874 -0.4064)
			(end 0.7874 -0.4064)
			(stroke
				(width 0.1524)
				(type default)
			)
			(layer "F.SilkS")
		)
		(fp_line
			(start 0.7874 -0.4064)
			(end 0.7874 0.4064)
			(stroke
				(width 0.1524)
				(type default)
			)
			(layer "F.SilkS")
		)
		(fp_line
			(start -0.67945 0.3048)
			(end -0.67945 -0.305054)
			(stroke
				(width 0.1)
				(type default)
			)
			(layer "F.Fab")
		)
		(fp_line
			(start -0.12065 0.3048)
			(end -0.67945 0.3048)
			(stroke
				(width 0.1)
				(type default)
			)
			(layer "F.Fab")
		)
		(fp_line
			(start 0.120396 0.3048)
			(end 0.120396 0.2794)
			(stroke
				(width 0.1)
				(type default)
			)
			(layer "F.Fab")
		)
		(fp_line
			(start 0.67945 0.3048)
			(end 0.120396 0.3048)
			(stroke
				(width 0.1)
				(type default)
			)
			(layer "F.Fab")
		)
		(fp_line
			(start -0.12065 0.2794)
			(end -0.12065 0.3048)
			(stroke
				(width 0.1)
				(type default)
			)
			(layer "F.Fab")
		)
		(fp_line
			(start 0.120396 0.2794)
			(end -0.12065 0.2794)
			(stroke
				(width 0.1)
				(type default)
			)
			(layer "F.Fab")
		)
		(fp_line
			(start -0.12065 -0.2794)
			(end 0.12065 -0.2794)
			(stroke
				(width 0.1)
				(type default)
			)
			(layer "F.Fab")
		)
		(fp_line
			(start 0.12065 -0.2794)
			(end 0.12065 -0.3048)
			(stroke
				(width 0.1)
				(type default)
			)
			(layer "F.Fab")
		)
		(fp_line
			(start 0.12065 -0.3048)
			(end 0.67945 -0.3048)
			(stroke
				(width 0.1)
				(type default)
			)
			(layer "F.Fab")
		)
		(fp_line
			(start 0.67945 -0.3048)
			(end 0.67945 0.3048)
			(stroke
				(width 0.1)
				(type default)
			)
			(layer "F.Fab")
		)
		(fp_line
			(start -0.67945 -0.305054)
			(end -0.12065 -0.305054)
			(stroke
				(width 0.1)
				(type default)
			)
			(layer "F.Fab")
		)
		(fp_line
			(start -0.12065 -0.305054)
			(end -0.12065 -0.2794)
			(stroke
				(width 0.1)
				(type default)
			)
			(layer "F.Fab")
		)
		(pad "1" smd circle
			(at -0.40005 0 270)
			(size 0 0)
			(layers "F.Cu" "F.Mask" "F.Paste")
			(net "RST_USB_HUB_2_R_N")
		)
		(pad "2" smd circle
			(at 0.40005 0 270)
			(size 0 0)
			(layers "F.Cu" "F.Mask" "F.Paste")
			(net "GND")
		)
	)
	(footprint ""
		(layer "F.Cu")
		(at 174.04588 -130.266948 90)
		(property "Reference" "R1399"
			(at 0 0 90)
			(layer "F.SilkS")
			(hide yes)
			(effects
				(font
					(size 1.27 1.27)
				)
			)
		)
		(property "Value" ""
			(at 0 0 90)
			(layer "F.Fab")
			(effects
				(font
					(size 1.27 1.27)
				)
			)
		)
		(duplicate_pad_numbers_are_jumpers no)
		(fp_line
			(start 0.7874 -0.4064)
			(end 0.7874 0.4064)
			(stroke
				(width 0.1524)
				(type default)
			)
			(layer "F.SilkS")
		)
		(fp_line
			(start -0.7874 -0.4064)
			(end 0.7874 -0.4064)
			(stroke
				(width 0.1524)
				(type default)
			)
			(layer "F.SilkS")
		)
		(fp_line
			(start 0.7874 0.4064)
			(end -0.7874 0.4064)
			(stroke
				(width 0.1524)
				(type default)
			)
			(layer "F.SilkS")
		)
		(fp_line
			(start -0.7874 0.4064)
			(end -0.7874 -0.4064)
			(stroke
				(width 0.1524)
				(type default)
			)
			(layer "F.SilkS")
		)
		(fp_line
			(start -0.12065 -0.305054)
			(end -0.12065 -0.2794)
			(stroke
				(width 0.1)
				(type default)
			)
			(layer "F.Fab")
		)
		(fp_line
			(start -0.67945 -0.305054)
			(end -0.12065 -0.305054)
			(stroke
				(width 0.1)
				(type default)
			)
			(layer "F.Fab")
		)
		(fp_line
			(start 0.67945 -0.3048)
			(end 0.67945 0.3048)
			(stroke
				(width 0.1)
				(type default)
			)
			(layer "F.Fab")
		)
		(fp_line
			(start 0.12065 -0.3048)
			(end 0.67945 -0.3048)
			(stroke
				(width 0.1)
				(type default)
			)
			(layer "F.Fab")
		)
		(fp_line
			(start 0.12065 -0.2794)
			(end 0.12065 -0.3048)
			(stroke
				(width 0.1)
				(type default)
			)
			(layer "F.Fab")
		)
		(fp_line
			(start -0.12065 -0.2794)
			(end 0.12065 -0.2794)
			(stroke
				(width 0.1)
				(type default)
			)
			(layer "F.Fab")
		)
		(fp_line
			(start 0.120396 0.2794)
			(end -0.12065 0.2794)
			(stroke
				(width 0.1)
				(type default)
			)
			(layer "F.Fab")
		)
		(fp_line
			(start -0.12065 0.2794)
			(end -0.12065 0.3048)
			(stroke
				(width 0.1)
				(type default)
			)
			(layer "F.Fab")
		)
		(fp_line
			(start 0.67945 0.3048)
			(end 0.120396 0.3048)
			(stroke
				(width 0.1)
				(type default)
			)
			(layer "F.Fab")
		)
		(fp_line
			(start 0.120396 0.3048)
			(end 0.120396 0.2794)
			(stroke
				(width 0.1)
				(type default)
			)
			(layer "F.Fab")
		)
		(fp_line
			(start -0.12065 0.3048)
			(end -0.67945 0.3048)
			(stroke
				(width 0.1)
				(type default)
			)
			(layer "F.Fab")
		)
		(fp_line
			(start -0.67945 0.3048)
			(end -0.67945 -0.305054)
			(stroke
				(width 0.1)
				(type default)
			)
			(layer "F.Fab")
		)
		(pad "1" smd circle
			(at -0.40005 0 90)
			(size 0 0)
			(layers "F.Cu" "F.Mask" "F.Paste")
			(net "FM_PFR_DSW_PWROK_N")
		)
		(pad "2" smd circle
			(at 0.40005 0 90)
			(size 0 0)
			(layers "F.Cu" "F.Mask" "F.Paste")
			(net "P3V3_AUX")
		)
	)
	(footprint ""
		(layer "F.Cu")
		(at 364.50143 -238.162338 90)
		(property "Reference" "C410"
			(at 0 0 90)
			(layer "F.SilkS")
			(hide yes)
			(effects
				(font
					(size 1.27 1.27)
				)
			)
		)
		(property "Value" ""
			(at 0 0 90)
			(layer "F.Fab")
			(effects
				(font
					(size 1.27 1.27)
				)
			)
		)
		(duplicate_pad_numbers_are_jumpers no)
		(fp_line
			(start 0.7874 -0.4064)
			(end 0.7874 0.4064)
			(stroke
				(width 0.1524)
				(type default)
			)
			(layer "F.SilkS")
		)
		(fp_line
			(start -0.7874 -0.4064)
			(end 0.7874 -0.4064)
			(stroke
				(width 0.1524)
				(type default)
			)
			(layer "F.SilkS")
		)
		(fp_line
			(start 0.7874 0.4064)
			(end -0.7874 0.4064)
			(stroke
				(width 0.1524)
				(type default)
			)
			(layer "F.SilkS")
		)
		(fp_line
			(start -0.7874 0.4064)
			(end -0.7874 -0.4064)
			(stroke
				(width 0.1524)
				(type default)
			)
			(layer "F.SilkS")
		)
		(fp_line
			(start -0.12065 -0.305054)
			(end -0.12065 -0.2794)
			(stroke
				(width 0.1)
				(type default)
			)
			(layer "F.Fab")
		)
		(fp_line
			(start -0.67945 -0.305054)
			(end -0.12065 -0.305054)
			(stroke
				(width 0.1)
				(type default)
			)
			(layer "F.Fab")
		)
		(fp_line
			(start 0.67945 -0.3048)
			(end 0.67945 0.3048)
			(stroke
				(width 0.1)
				(type default)
			)
			(layer "F.Fab")
		)
		(fp_line
			(start 0.12065 -0.3048)
			(end 0.67945 -0.3048)
			(stroke
				(width 0.1)
				(type default)
			)
			(layer "F.Fab")
		)
		(fp_line
			(start 0.12065 -0.2794)
			(end 0.12065 -0.3048)
			(stroke
				(width 0.1)
				(type default)
			)
			(layer "F.Fab")
		)
		(fp_line
			(start -0.12065 -0.2794)
			(end 0.12065 -0.2794)
			(stroke
				(width 0.1)
				(type default)
			)
			(layer "F.Fab")
		)
		(fp_line
			(start 0.120396 0.2794)
			(end -0.12065 0.2794)
			(stroke
				(width 0.1)
				(type default)
			)
			(layer "F.Fab")
		)
		(fp_line
			(start -0.12065 0.2794)
			(end -0.12065 0.3048)
			(stroke
				(width 0.1)
				(type default)
			)
			(layer "F.Fab")
		)
		(fp_line
			(start 0.67945 0.3048)
			(end 0.120396 0.3048)
			(stroke
				(width 0.1)
				(type default)
			)
			(layer "F.Fab")
		)
		(fp_line
			(start 0.120396 0.3048)
			(end 0.120396 0.2794)
			(stroke
				(width 0.1)
				(type default)
			)
			(layer "F.Fab")
		)
		(fp_line
			(start -0.12065 0.3048)
			(end -0.67945 0.3048)
			(stroke
				(width 0.1)
				(type default)
			)
			(layer "F.Fab")
		)
		(fp_line
			(start -0.67945 0.3048)
			(end -0.67945 -0.305054)
			(stroke
				(width 0.1)
				(type default)
			)
			(layer "F.Fab")
		)
		(pad "1" smd circle
			(at -0.40005 0 90)
			(size 0 0)
			(layers "F.Cu" "F.Mask" "F.Paste")
			(net "PVCCINFAON_CPU0")
		)
		(pad "2" smd circle
			(at 0.40005 0 90)
			(size 0 0)
			(layers "F.Cu" "F.Mask" "F.Paste")
			(net "GND")
		)
	)
	(footprint ""
		(layer "F.Cu")
		(at 435.350158 -118.568216 90)
		(property "Reference" "R2402"
			(at 0 0 90)
			(layer "F.SilkS")
			(hide yes)
			(effects
				(font
					(size 1.27 1.27)
				)
			)
		)
		(property "Value" ""
			(at 0 0 90)
			(layer "F.Fab")
			(effects
				(font
					(size 1.27 1.27)
				)
			)
		)
		(duplicate_pad_numbers_are_jumpers no)
		(fp_line
			(start 0.7874 -0.4064)
			(end 0.7874 0.4064)
			(stroke
				(width 0.1524)
				(type default)
			)
			(layer "F.SilkS")
		)
		(fp_line
			(start -0.7874 -0.4064)
			(end 0.7874 -0.4064)
			(stroke
				(width 0.1524)
				(type default)
			)
			(layer "F.SilkS")
		)
		(fp_line
			(start 0.7874 0.4064)
			(end -0.7874 0.4064)
			(stroke
				(width 0.1524)
				(type default)
			)
			(layer "F.SilkS")
		)
		(fp_line
			(start -0.7874 0.4064)
			(end -0.7874 -0.4064)
			(stroke
				(width 0.1524)
				(type default)
			)
			(layer "F.SilkS")
		)
		(fp_line
			(start -0.12065 -0.305054)
			(end -0.12065 -0.2794)
			(stroke
				(width 0.1)
				(type default)
			)
			(layer "F.Fab")
		)
		(fp_line
			(start -0.67945 -0.305054)
			(end -0.12065 -0.305054)
			(stroke
				(width 0.1)
				(type default)
			)
			(layer "F.Fab")
		)
		(fp_line
			(start 0.67945 -0.3048)
			(end 0.67945 0.3048)
			(stroke
				(width 0.1)
				(type default)
			)
			(layer "F.Fab")
		)
		(fp_line
			(start 0.12065 -0.3048)
			(end 0.67945 -0.3048)
			(stroke
				(width 0.1)
				(type default)
			)
			(layer "F.Fab")
		)
		(fp_line
			(start 0.12065 -0.2794)
			(end 0.12065 -0.3048)
			(stroke
				(width 0.1)
				(type default)
			)
			(layer "F.Fab")
		)
		(fp_line
			(start -0.12065 -0.2794)
			(end 0.12065 -0.2794)
			(stroke
				(width 0.1)
				(type default)
			)
			(layer "F.Fab")
		)
		(fp_line
			(start 0.120396 0.2794)
			(end -0.12065 0.2794)
			(stroke
				(width 0.1)
				(type default)
			)
			(layer "F.Fab")
		)
		(fp_line
			(start -0.12065 0.2794)
			(end -0.12065 0.3048)
			(stroke
				(width 0.1)
				(type default)
			)
			(layer "F.Fab")
		)
		(fp_line
			(start 0.67945 0.3048)
			(end 0.120396 0.3048)
			(stroke
				(width 0.1)
				(type default)
			)
			(layer "F.Fab")
		)
		(fp_line
			(start 0.120396 0.3048)
			(end 0.120396 0.2794)
			(stroke
				(width 0.1)
				(type default)
			)
			(layer "F.Fab")
		)
		(fp_line
			(start -0.12065 0.3048)
			(end -0.67945 0.3048)
			(stroke
				(width 0.1)
				(type default)
			)
			(layer "F.Fab")
		)
		(fp_line
			(start -0.67945 0.3048)
			(end -0.67945 -0.305054)
			(stroke
				(width 0.1)
				(type default)
			)
			(layer "F.Fab")
		)
		(pad "1" smd circle
			(at -0.40005 0 90)
			(size 0 0)
			(layers "F.Cu" "F.Mask" "F.Paste")
			(net "SMB_VR_3V3AUX_SCL_R2")
		)
		(pad "2" smd circle
			(at 0.40005 0 90)
			(size 0 0)
			(layers "F.Cu" "F.Mask" "F.Paste")
			(net "SMB_CLK_PVCCD_HV_CPU0")
		)
	)
	(footprint ""
		(layer "F.Cu")
		(at 197.21068 -41.466516 180)
		(property "Reference" "R4062"
			(at 0 0 180)
			(layer "F.SilkS")
			(hide yes)
			(effects
				(font
					(size 1.27 1.27)
				)
			)
		)
		(property "Value" ""
			(at 0 0 180)
			(layer "F.Fab")
			(effects
				(font
					(size 1.27 1.27)
				)
			)
		)
		(duplicate_pad_numbers_are_jumpers no)
		(fp_line
			(start 0.7874 0.4064)
			(end -0.7874 0.4064)
			(stroke
				(width 0.1524)
				(type default)
			)
			(layer "F.SilkS")
		)
		(fp_line
			(start 0.7874 -0.4064)
			(end 0.7874 0.4064)
			(stroke
				(width 0.1524)
				(type default)
			)
			(layer "F.SilkS")
		)
		(fp_line
			(start -0.7874 0.4064)
			(end -0.7874 -0.4064)
			(stroke
				(width 0.1524)
				(type default)
			)
			(layer "F.SilkS")
		)
		(fp_line
			(start -0.7874 -0.4064)
			(end 0.7874 -0.4064)
			(stroke
				(width 0.1524)
				(type default)
			)
			(layer "F.SilkS")
		)
		(fp_line
			(start 0.67945 0.3048)
			(end 0.120396 0.3048)
			(stroke
				(width 0.1)
				(type default)
			)
			(layer "F.Fab")
		)
		(fp_line
			(start 0.67945 -0.3048)
			(end 0.67945 0.3048)
			(stroke
				(width 0.1)
				(type default)
			)
			(layer "F.Fab")
		)
		(fp_line
			(start 0.12065 -0.2794)
			(end 0.12065 -0.3048)
			(stroke
				(width 0.1)
				(type default)
			)
			(layer "F.Fab")
		)
		(fp_line
			(start 0.12065 -0.3048)
			(end 0.67945 -0.3048)
			(stroke
				(width 0.1)
				(type default)
			)
			(layer "F.Fab")
		)
		(fp_line
			(start 0.120396 0.3048)
			(end 0.120396 0.2794)
			(stroke
				(width 0.1)
				(type default)
			)
			(layer "F.Fab")
		)
		(fp_line
			(start 0.120396 0.2794)
			(end -0.12065 0.2794)
			(stroke
				(width 0.1)
				(type default)
			)
			(layer "F.Fab")
		)
		(fp_line
			(start -0.12065 0.3048)
			(end -0.67945 0.3048)
			(stroke
				(width 0.1)
				(type default)
			)
			(layer "F.Fab")
		)
		(fp_line
			(start -0.12065 0.2794)
			(end -0.12065 0.3048)
			(stroke
				(width 0.1)
				(type default)
			)
			(layer "F.Fab")
		)
		(fp_line
			(start -0.12065 -0.2794)
			(end 0.12065 -0.2794)
			(stroke
				(width 0.1)
				(type default)
			)
			(layer "F.Fab")
		)
		(fp_line
			(start -0.12065 -0.305054)
			(end -0.12065 -0.2794)
			(stroke
				(width 0.1)
				(type default)
			)
			(layer "F.Fab")
		)
		(fp_line
			(start -0.67945 0.3048)
			(end -0.67945 -0.305054)
			(stroke
				(width 0.1)
				(type default)
			)
			(layer "F.Fab")
		)
		(fp_line
			(start -0.67945 -0.305054)
			(end -0.12065 -0.305054)
			(stroke
				(width 0.1)
				(type default)
			)
			(layer "F.Fab")
		)
		(pad "1" smd circle
			(at -0.40005 0 180)
			(size 0 0)
			(layers "F.Cu" "F.Mask" "F.Paste")
			(net "P12V_SCM_EN")
		)
		(pad "2" smd circle
			(at 0.40005 0 180)
			(size 0 0)
			(layers "F.Cu" "F.Mask" "F.Paste")
			(net "P12V_SCM_EN_R")
		)
	)
	(footprint ""
		(layer "F.Cu")
		(at 197.19036 -115.534948 180)
		(property "Reference" "R1465"
			(at 0 0 180)
			(layer "F.SilkS")
			(hide yes)
			(effects
				(font
					(size 1.27 1.27)
				)
			)
		)
		(property "Value" ""
			(at 0 0 180)
			(layer "F.Fab")
			(effects
				(font
					(size 1.27 1.27)
				)
			)
		)
		(duplicate_pad_numbers_are_jumpers no)
		(fp_line
			(start 0.7874 0.4064)
			(end -0.7874 0.4064)
			(stroke
				(width 0.1524)
				(type default)
			)
			(layer "F.SilkS")
		)
		(fp_line
			(start 0.7874 -0.4064)
			(end 0.7874 0.4064)
			(stroke
				(width 0.1524)
				(type default)
			)
			(layer "F.SilkS")
		)
		(fp_line
			(start -0.7874 0.4064)
			(end -0.7874 -0.4064)
			(stroke
				(width 0.1524)
				(type default)
			)
			(layer "F.SilkS")
		)
		(fp_line
			(start -0.7874 -0.4064)
			(end 0.7874 -0.4064)
			(stroke
				(width 0.1524)
				(type default)
			)
			(layer "F.SilkS")
		)
		(fp_line
			(start 0.67945 0.3048)
			(end 0.120396 0.3048)
			(stroke
				(width 0.1)
				(type default)
			)
			(layer "F.Fab")
		)
		(fp_line
			(start 0.67945 -0.3048)
			(end 0.67945 0.3048)
			(stroke
				(width 0.1)
				(type default)
			)
			(layer "F.Fab")
		)
		(fp_line
			(start 0.12065 -0.2794)
			(end 0.12065 -0.3048)
			(stroke
				(width 0.1)
				(type default)
			)
			(layer "F.Fab")
		)
		(fp_line
			(start 0.12065 -0.3048)
			(end 0.67945 -0.3048)
			(stroke
				(width 0.1)
				(type default)
			)
			(layer "F.Fab")
		)
		(fp_line
			(start 0.120396 0.3048)
			(end 0.120396 0.2794)
			(stroke
				(width 0.1)
				(type default)
			)
			(layer "F.Fab")
		)
		(fp_line
			(start 0.120396 0.2794)
			(end -0.12065 0.2794)
			(stroke
				(width 0.1)
				(type default)
			)
			(layer "F.Fab")
		)
		(fp_line
			(start -0.12065 0.3048)
			(end -0.67945 0.3048)
			(stroke
				(width 0.1)
				(type default)
			)
			(layer "F.Fab")
		)
		(fp_line
			(start -0.12065 0.2794)
			(end -0.12065 0.3048)
			(stroke
				(width 0.1)
				(type default)
			)
			(layer "F.Fab")
		)
		(fp_line
			(start -0.12065 -0.2794)
			(end 0.12065 -0.2794)
			(stroke
				(width 0.1)
				(type default)
			)
			(layer "F.Fab")
		)
		(fp_line
			(start -0.12065 -0.305054)
			(end -0.12065 -0.2794)
			(stroke
				(width 0.1)
				(type default)
			)
			(layer "F.Fab")
		)
		(fp_line
			(start -0.67945 0.3048)
			(end -0.67945 -0.305054)
			(stroke
				(width 0.1)
				(type default)
			)
			(layer "F.Fab")
		)
		(fp_line
			(start -0.67945 -0.305054)
			(end -0.12065 -0.305054)
			(stroke
				(width 0.1)
				(type default)
			)
			(layer "F.Fab")
		)
		(pad "1" smd circle
			(at -0.40005 0 180)
			(size 0 0)
			(layers "F.Cu" "F.Mask" "F.Paste")
			(net "P3V3_AUX")
		)
		(pad "2" smd circle
			(at 0.40005 0 180)
			(size 0 0)
			(layers "F.Cu" "F.Mask" "F.Paste")
			(net "IRQ_BMC_CPU_NMI_R1")
		)
	)
	(footprint ""
		(layer "F.Cu")
		(at 137.706354 -408.517344 -90)
		(property "Reference" "C1527"
			(at 0 0 270)
			(layer "F.SilkS")
			(hide yes)
			(effects
				(font
					(size 1.27 1.27)
				)
			)
		)
		(property "Value" ""
			(at 0 0 270)
			(layer "F.Fab")
			(effects
				(font
					(size 1.27 1.27)
				)
			)
		)
		(duplicate_pad_numbers_are_jumpers no)
		(fp_line
			(start -0.299974 0.150114)
			(end -0.299974 -0.150114)
			(stroke
				(width 0.1)
				(type default)
			)
			(layer "F.Fab")
		)
		(fp_line
			(start 0.299974 0.150114)
			(end -0.299974 0.150114)
			(stroke
				(width 0.1)
				(type default)
			)
			(layer "F.Fab")
		)
		(fp_line
			(start -0.299974 -0.150114)
			(end 0.299974 -0.150114)
			(stroke
				(width 0.1)
				(type default)
			)
			(layer "F.Fab")
		)
		(fp_line
			(start 0.299974 -0.150114)
			(end 0.299974 0.150114)
			(stroke
				(width 0.1)
				(type default)
			)
			(layer "F.Fab")
		)
		(pad "1" smd rect
			(at -0.2667 0 270)
			(size 0.3048 0.381)
			(layers "F.Cu" "F.Mask" "F.Paste")
			(net "P5E_CPU1_PE3_TX_C_DP<10>")
		)
		(pad "2" smd rect
			(at 0.2667 0 270)
			(size 0.3048 0.381)
			(layers "F.Cu" "F.Mask" "F.Paste")
			(net "P5E_CPU1_PE3_TX_DP<10>")
		)
	)
	(footprint ""
		(layer "F.Cu")
		(at 106.3244 -249.320558 -90)
		(property "Reference" "C303"
			(at 0 0 270)
			(layer "F.SilkS")
			(hide yes)
			(effects
				(font
					(size 1.27 1.27)
				)
			)
		)
		(property "Value" ""
			(at 0 0 270)
			(layer "F.Fab")
			(effects
				(font
					(size 1.27 1.27)
				)
			)
		)
		(duplicate_pad_numbers_are_jumpers no)
		(fp_line
			(start -0.7874 0.4064)
			(end -0.7874 -0.4064)
			(stroke
				(width 0.1524)
				(type default)
			)
			(layer "F.SilkS")
		)
		(fp_line
			(start 0.7874 0.4064)
			(end -0.7874 0.4064)
			(stroke
				(width 0.1524)
				(type default)
			)
			(layer "F.SilkS")
		)
		(fp_line
			(start -0.7874 -0.4064)
			(end 0.7874 -0.4064)
			(stroke
				(width 0.1524)
				(type default)
			)
			(layer "F.SilkS")
		)
		(fp_line
			(start 0.7874 -0.4064)
			(end 0.7874 0.4064)
			(stroke
				(width 0.1524)
				(type default)
			)
			(layer "F.SilkS")
		)
		(fp_line
			(start -0.67945 0.3048)
			(end -0.67945 -0.305054)
			(stroke
				(width 0.1)
				(type default)
			)
			(layer "F.Fab")
		)
		(fp_line
			(start -0.12065 0.3048)
			(end -0.67945 0.3048)
			(stroke
				(width 0.1)
				(type default)
			)
			(layer "F.Fab")
		)
		(fp_line
			(start 0.120396 0.3048)
			(end 0.120396 0.2794)
			(stroke
				(width 0.1)
				(type default)
			)
			(layer "F.Fab")
		)
		(fp_line
			(start 0.67945 0.3048)
			(end 0.120396 0.3048)
			(stroke
				(width 0.1)
				(type default)
			)
			(layer "F.Fab")
		)
		(fp_line
			(start -0.12065 0.2794)
			(end -0.12065 0.3048)
			(stroke
				(width 0.1)
				(type default)
			)
			(layer "F.Fab")
		)
		(fp_line
			(start 0.120396 0.2794)
			(end -0.12065 0.2794)
			(stroke
				(width 0.1)
				(type default)
			)
			(layer "F.Fab")
		)
		(fp_line
			(start -0.12065 -0.2794)
			(end 0.12065 -0.2794)
			(stroke
				(width 0.1)
				(type default)
			)
			(layer "F.Fab")
		)
		(fp_line
			(start 0.12065 -0.2794)
			(end 0.12065 -0.3048)
			(stroke
				(width 0.1)
				(type default)
			)
			(layer "F.Fab")
		)
		(fp_line
			(start 0.12065 -0.3048)
			(end 0.67945 -0.3048)
			(stroke
				(width 0.1)
				(type default)
			)
			(layer "F.Fab")
		)
		(fp_line
			(start 0.67945 -0.3048)
			(end 0.67945 0.3048)
			(stroke
				(width 0.1)
				(type default)
			)
			(layer "F.Fab")
		)
		(fp_line
			(start -0.67945 -0.305054)
			(end -0.12065 -0.305054)
			(stroke
				(width 0.1)
				(type default)
			)
			(layer "F.Fab")
		)
		(fp_line
			(start -0.12065 -0.305054)
			(end -0.12065 -0.2794)
			(stroke
				(width 0.1)
				(type default)
			)
			(layer "F.Fab")
		)
		(pad "1" smd circle
			(at -0.40005 0 270)
			(size 0 0)
			(layers "F.Cu" "F.Mask" "F.Paste")
			(net "PVCCIN_CPU1")
		)
		(pad "2" smd circle
			(at 0.40005 0 270)
			(size 0 0)
			(layers "F.Cu" "F.Mask" "F.Paste")
			(net "GND")
		)
	)
	(footprint ""
		(layer "F.Cu")
		(at 390.930384 -16.088614 90)
		(property "Reference" "C838"
			(at 0 0 90)
			(layer "F.SilkS")
			(hide yes)
			(effects
				(font
					(size 1.27 1.27)
				)
			)
		)
		(property "Value" ""
			(at 0 0 90)
			(layer "F.Fab")
			(effects
				(font
					(size 1.27 1.27)
				)
			)
		)
		(duplicate_pad_numbers_are_jumpers no)
		(fp_line
			(start 0.299974 -0.150114)
			(end 0.299974 0.150114)
			(stroke
				(width 0.1)
				(type default)
			)
			(layer "F.Fab")
		)
		(fp_line
			(start -0.299974 -0.150114)
			(end 0.299974 -0.150114)
			(stroke
				(width 0.1)
				(type default)
			)
			(layer "F.Fab")
		)
		(fp_line
			(start 0.299974 0.150114)
			(end -0.299974 0.150114)
			(stroke
				(width 0.1)
				(type default)
			)
			(layer "F.Fab")
		)
		(fp_line
			(start -0.299974 0.150114)
			(end -0.299974 -0.150114)
			(stroke
				(width 0.1)
				(type default)
			)
			(layer "F.Fab")
		)
		(pad "1" smd rect
			(at -0.2667 0 90)
			(size 0.3048 0.381)
			(layers "F.Cu" "F.Mask" "F.Paste")
			(net "P5E_CPU0_PE1_TX_C_DN<15>")
		)
		(pad "2" smd rect
			(at 0.2667 0 90)
			(size 0.3048 0.381)
			(layers "F.Cu" "F.Mask" "F.Paste")
			(net "P5E_CPU0_PE1_TX_DN<15>")
		)
	)
	(footprint ""
		(layer "F.Cu")
		(at 159.149034 -408.517344 -90)
		(property "Reference" "C1541"
			(at 0 0 270)
			(layer "F.SilkS")
			(hide yes)
			(effects
				(font
					(size 1.27 1.27)
				)
			)
		)
		(property "Value" ""
			(at 0 0 270)
			(layer "F.Fab")
			(effects
				(font
					(size 1.27 1.27)
				)
			)
		)
		(duplicate_pad_numbers_are_jumpers no)
		(fp_line
			(start -0.299974 0.150114)
			(end -0.299974 -0.150114)
			(stroke
				(width 0.1)
				(type default)
			)
			(layer "F.Fab")
		)
		(fp_line
			(start 0.299974 0.150114)
			(end -0.299974 0.150114)
			(stroke
				(width 0.1)
				(type default)
			)
			(layer "F.Fab")
		)
		(fp_line
			(start -0.299974 -0.150114)
			(end 0.299974 -0.150114)
			(stroke
				(width 0.1)
				(type default)
			)
			(layer "F.Fab")
		)
		(fp_line
			(start 0.299974 -0.150114)
			(end 0.299974 0.150114)
			(stroke
				(width 0.1)
				(type default)
			)
			(layer "F.Fab")
		)
		(pad "1" smd rect
			(at -0.2667 0 270)
			(size 0.3048 0.381)
			(layers "F.Cu" "F.Mask" "F.Paste")
			(net "P5E_CPU1_PE3_TX_C_DP<3>")
		)
		(pad "2" smd rect
			(at 0.2667 0 270)
			(size 0.3048 0.381)
			(layers "F.Cu" "F.Mask" "F.Paste")
			(net "P5E_CPU1_PE3_TX_DP<3>")
		)
	)
	(footprint ""
		(layer "F.Cu")
		(at 62.559438 -31.887922 90)
		(property "Reference" "R3873"
			(at 0 0 90)
			(layer "F.SilkS")
			(hide yes)
			(effects
				(font
					(size 1.27 1.27)
				)
			)
		)
		(property "Value" ""
			(at 0 0 90)
			(layer "F.Fab")
			(effects
				(font
					(size 1.27 1.27)
				)
			)
		)
		(duplicate_pad_numbers_are_jumpers no)
		(fp_line
			(start 0.7874 -0.4064)
			(end 0.7874 0.4064)
			(stroke
				(width 0.1524)
				(type default)
			)
			(layer "F.SilkS")
		)
		(fp_line
			(start -0.7874 -0.4064)
			(end 0.7874 -0.4064)
			(stroke
				(width 0.1524)
				(type default)
			)
			(layer "F.SilkS")
		)
		(fp_line
			(start 0.7874 0.4064)
			(end -0.7874 0.4064)
			(stroke
				(width 0.1524)
				(type default)
			)
			(layer "F.SilkS")
		)
		(fp_line
			(start -0.7874 0.4064)
			(end -0.7874 -0.4064)
			(stroke
				(width 0.1524)
				(type default)
			)
			(layer "F.SilkS")
		)
		(fp_line
			(start -0.12065 -0.305054)
			(end -0.12065 -0.2794)
			(stroke
				(width 0.1)
				(type default)
			)
			(layer "F.Fab")
		)
		(fp_line
			(start -0.67945 -0.305054)
			(end -0.12065 -0.305054)
			(stroke
				(width 0.1)
				(type default)
			)
			(layer "F.Fab")
		)
		(fp_line
			(start 0.67945 -0.3048)
			(end 0.67945 0.3048)
			(stroke
				(width 0.1)
				(type default)
			)
			(layer "F.Fab")
		)
		(fp_line
			(start 0.12065 -0.3048)
			(end 0.67945 -0.3048)
			(stroke
				(width 0.1)
				(type default)
			)
			(layer "F.Fab")
		)
		(fp_line
			(start 0.12065 -0.2794)
			(end 0.12065 -0.3048)
			(stroke
				(width 0.1)
				(type default)
			)
			(layer "F.Fab")
		)
		(fp_line
			(start -0.12065 -0.2794)
			(end 0.12065 -0.2794)
			(stroke
				(width 0.1)
				(type default)
			)
			(layer "F.Fab")
		)
		(fp_line
			(start 0.120396 0.2794)
			(end -0.12065 0.2794)
			(stroke
				(width 0.1)
				(type default)
			)
			(layer "F.Fab")
		)
		(fp_line
			(start -0.12065 0.2794)
			(end -0.12065 0.3048)
			(stroke
				(width 0.1)
				(type default)
			)
			(layer "F.Fab")
		)
		(fp_line
			(start 0.67945 0.3048)
			(end 0.120396 0.3048)
			(stroke
				(width 0.1)
				(type default)
			)
			(layer "F.Fab")
		)
		(fp_line
			(start 0.120396 0.3048)
			(end 0.120396 0.2794)
			(stroke
				(width 0.1)
				(type default)
			)
			(layer "F.Fab")
		)
		(fp_line
			(start -0.12065 0.3048)
			(end -0.67945 0.3048)
			(stroke
				(width 0.1)
				(type default)
			)
			(layer "F.Fab")
		)
		(fp_line
			(start -0.67945 0.3048)
			(end -0.67945 -0.305054)
			(stroke
				(width 0.1)
				(type default)
			)
			(layer "F.Fab")
		)
		(pad "1" smd circle
			(at -0.40005 0 90)
			(size 0 0)
			(layers "F.Cu" "F.Mask" "F.Paste")
			(net "P12V_OCP_IMON_2")
		)
		(pad "2" smd circle
			(at 0.40005 0 90)
			(size 0 0)
			(layers "F.Cu" "F.Mask" "F.Paste")
			(net "P12V_OCP_V3_2_ISENSE_MPS_MAM")
		)
	)
	(footprint ""
		(layer "F.Cu")
		(at 157.02788 -118.836948 180)
		(property "Reference" "R982"
			(at 0 0 180)
			(layer "F.SilkS")
			(hide yes)
			(effects
				(font
					(size 1.27 1.27)
				)
			)
		)
		(property "Value" ""
			(at 0 0 180)
			(layer "F.Fab")
			(effects
				(font
					(size 1.27 1.27)
				)
			)
		)
		(duplicate_pad_numbers_are_jumpers no)
		(fp_line
			(start 0.7874 0.4064)
			(end -0.7874 0.4064)
			(stroke
				(width 0.1524)
				(type default)
			)
			(layer "F.SilkS")
		)
		(fp_line
			(start 0.7874 -0.4064)
			(end 0.7874 0.4064)
			(stroke
				(width 0.1524)
				(type default)
			)
			(layer "F.SilkS")
		)
		(fp_line
			(start -0.7874 0.4064)
			(end -0.7874 -0.4064)
			(stroke
				(width 0.1524)
				(type default)
			)
			(layer "F.SilkS")
		)
		(fp_line
			(start -0.7874 -0.4064)
			(end 0.7874 -0.4064)
			(stroke
				(width 0.1524)
				(type default)
			)
			(layer "F.SilkS")
		)
		(fp_line
			(start 0.67945 0.3048)
			(end 0.120396 0.3048)
			(stroke
				(width 0.1)
				(type default)
			)
			(layer "F.Fab")
		)
		(fp_line
			(start 0.67945 -0.3048)
			(end 0.67945 0.3048)
			(stroke
				(width 0.1)
				(type default)
			)
			(layer "F.Fab")
		)
		(fp_line
			(start 0.12065 -0.2794)
			(end 0.12065 -0.3048)
			(stroke
				(width 0.1)
				(type default)
			)
			(layer "F.Fab")
		)
		(fp_line
			(start 0.12065 -0.3048)
			(end 0.67945 -0.3048)
			(stroke
				(width 0.1)
				(type default)
			)
			(layer "F.Fab")
		)
		(fp_line
			(start 0.120396 0.3048)
			(end 0.120396 0.2794)
			(stroke
				(width 0.1)
				(type default)
			)
			(layer "F.Fab")
		)
		(fp_line
			(start 0.120396 0.2794)
			(end -0.12065 0.2794)
			(stroke
				(width 0.1)
				(type default)
			)
			(layer "F.Fab")
		)
		(fp_line
			(start -0.12065 0.3048)
			(end -0.67945 0.3048)
			(stroke
				(width 0.1)
				(type default)
			)
			(layer "F.Fab")
		)
		(fp_line
			(start -0.12065 0.2794)
			(end -0.12065 0.3048)
			(stroke
				(width 0.1)
				(type default)
			)
			(layer "F.Fab")
		)
		(fp_line
			(start -0.12065 -0.2794)
			(end 0.12065 -0.2794)
			(stroke
				(width 0.1)
				(type default)
			)
			(layer "F.Fab")
		)
		(fp_line
			(start -0.12065 -0.305054)
			(end -0.12065 -0.2794)
			(stroke
				(width 0.1)
				(type default)
			)
			(layer "F.Fab")
		)
		(fp_line
			(start -0.67945 0.3048)
			(end -0.67945 -0.305054)
			(stroke
				(width 0.1)
				(type default)
			)
			(layer "F.Fab")
		)
		(fp_line
			(start -0.67945 -0.305054)
			(end -0.12065 -0.305054)
			(stroke
				(width 0.1)
				(type default)
			)
			(layer "F.Fab")
		)
		(pad "1" smd circle
			(at -0.40005 0 180)
			(size 0 0)
			(layers "F.Cu" "F.Mask" "F.Paste")
			(net "FM_PVCCFA_EHV_CPU0_R_EN")
		)
		(pad "2" smd circle
			(at 0.40005 0 180)
			(size 0 0)
			(layers "F.Cu" "F.Mask" "F.Paste")
			(net "FM_PVCCFA_EHV_CPU0_EN")
		)
	)
	(footprint ""
		(layer "F.Cu")
		(at 389.312658 -343.018872 -90)
		(property "Reference" "PC232_P0_8"
			(at 0 0 270)
			(layer "F.SilkS")
			(hide yes)
			(effects
				(font
					(size 1.27 1.27)
				)
			)
		)
		(property "Value" ""
			(at 0 0 270)
			(layer "F.Fab")
			(effects
				(font
					(size 1.27 1.27)
				)
			)
		)
		(duplicate_pad_numbers_are_jumpers no)
		(fp_line
			(start -0.7874 0.4064)
			(end -0.7874 -0.4064)
			(stroke
				(width 0.1524)
				(type default)
			)
			(layer "F.SilkS")
		)
		(fp_line
			(start 0.7874 0.4064)
			(end -0.7874 0.4064)
			(stroke
				(width 0.1524)
				(type default)
			)
			(layer "F.SilkS")
		)
		(fp_line
			(start -0.7874 -0.4064)
			(end 0.7874 -0.4064)
			(stroke
				(width 0.1524)
				(type default)
			)
			(layer "F.SilkS")
		)
		(fp_line
			(start 0.7874 -0.4064)
			(end 0.7874 0.4064)
			(stroke
				(width 0.1524)
				(type default)
			)
			(layer "F.SilkS")
		)
		(fp_line
			(start -0.67945 0.3048)
			(end -0.67945 -0.305054)
			(stroke
				(width 0.1)
				(type default)
			)
			(layer "F.Fab")
		)
		(fp_line
			(start -0.12065 0.3048)
			(end -0.67945 0.3048)
			(stroke
				(width 0.1)
				(type default)
			)
			(layer "F.Fab")
		)
		(fp_line
			(start 0.120396 0.3048)
			(end 0.120396 0.2794)
			(stroke
				(width 0.1)
				(type default)
			)
			(layer "F.Fab")
		)
		(fp_line
			(start 0.67945 0.3048)
			(end 0.120396 0.3048)
			(stroke
				(width 0.1)
				(type default)
			)
			(layer "F.Fab")
		)
		(fp_line
			(start -0.12065 0.2794)
			(end -0.12065 0.3048)
			(stroke
				(width 0.1)
				(type default)
			)
			(layer "F.Fab")
		)
		(fp_line
			(start 0.120396 0.2794)
			(end -0.12065 0.2794)
			(stroke
				(width 0.1)
				(type default)
			)
			(layer "F.Fab")
		)
		(fp_line
			(start -0.12065 -0.2794)
			(end 0.12065 -0.2794)
			(stroke
				(width 0.1)
				(type default)
			)
			(layer "F.Fab")
		)
		(fp_line
			(start 0.12065 -0.2794)
			(end 0.12065 -0.3048)
			(stroke
				(width 0.1)
				(type default)
			)
			(layer "F.Fab")
		)
		(fp_line
			(start 0.12065 -0.3048)
			(end 0.67945 -0.3048)
			(stroke
				(width 0.1)
				(type default)
			)
			(layer "F.Fab")
		)
		(fp_line
			(start 0.67945 -0.3048)
			(end 0.67945 0.3048)
			(stroke
				(width 0.1)
				(type default)
			)
			(layer "F.Fab")
		)
		(fp_line
			(start -0.67945 -0.305054)
			(end -0.12065 -0.305054)
			(stroke
				(width 0.1)
				(type default)
			)
			(layer "F.Fab")
		)
		(fp_line
			(start -0.12065 -0.305054)
			(end -0.12065 -0.2794)
			(stroke
				(width 0.1)
				(type default)
			)
			(layer "F.Fab")
		)
		(pad "1" smd circle
			(at -0.40005 0 270)
			(size 0 0)
			(layers "F.Cu" "F.Mask" "F.Paste")
			(net "SW_P12V_PVCCIN_CPU0_FLT")
		)
		(pad "2" smd circle
			(at 0.40005 0 270)
			(size 0 0)
			(layers "F.Cu" "F.Mask" "F.Paste")
			(net "GND")
		)
	)
	(footprint ""
		(layer "F.Cu")
		(at 80.550766 -65.082674 -90)
		(property "Reference" "R1371"
			(at 0 0 270)
			(layer "F.SilkS")
			(hide yes)
			(effects
				(font
					(size 1.27 1.27)
				)
			)
		)
		(property "Value" ""
			(at 0 0 270)
			(layer "F.Fab")
			(effects
				(font
					(size 1.27 1.27)
				)
			)
		)
		(duplicate_pad_numbers_are_jumpers no)
		(fp_line
			(start -0.7874 0.4064)
			(end -0.7874 -0.4064)
			(stroke
				(width 0.1524)
				(type default)
			)
			(layer "F.SilkS")
		)
		(fp_line
			(start 0.7874 0.4064)
			(end -0.7874 0.4064)
			(stroke
				(width 0.1524)
				(type default)
			)
			(layer "F.SilkS")
		)
		(fp_line
			(start -0.7874 -0.4064)
			(end 0.7874 -0.4064)
			(stroke
				(width 0.1524)
				(type default)
			)
			(layer "F.SilkS")
		)
		(fp_line
			(start 0.7874 -0.4064)
			(end 0.7874 0.4064)
			(stroke
				(width 0.1524)
				(type default)
			)
			(layer "F.SilkS")
		)
		(fp_line
			(start -0.67945 0.3048)
			(end -0.67945 -0.305054)
			(stroke
				(width 0.1)
				(type default)
			)
			(layer "F.Fab")
		)
		(fp_line
			(start -0.12065 0.3048)
			(end -0.67945 0.3048)
			(stroke
				(width 0.1)
				(type default)
			)
			(layer "F.Fab")
		)
		(fp_line
			(start 0.120396 0.3048)
			(end 0.120396 0.2794)
			(stroke
				(width 0.1)
				(type default)
			)
			(layer "F.Fab")
		)
		(fp_line
			(start 0.67945 0.3048)
			(end 0.120396 0.3048)
			(stroke
				(width 0.1)
				(type default)
			)
			(layer "F.Fab")
		)
		(fp_line
			(start -0.12065 0.2794)
			(end -0.12065 0.3048)
			(stroke
				(width 0.1)
				(type default)
			)
			(layer "F.Fab")
		)
		(fp_line
			(start 0.120396 0.2794)
			(end -0.12065 0.2794)
			(stroke
				(width 0.1)
				(type default)
			)
			(layer "F.Fab")
		)
		(fp_line
			(start -0.12065 -0.2794)
			(end 0.12065 -0.2794)
			(stroke
				(width 0.1)
				(type default)
			)
			(layer "F.Fab")
		)
		(fp_line
			(start 0.12065 -0.2794)
			(end 0.12065 -0.3048)
			(stroke
				(width 0.1)
				(type default)
			)
			(layer "F.Fab")
		)
		(fp_line
			(start 0.12065 -0.3048)
			(end 0.67945 -0.3048)
			(stroke
				(width 0.1)
				(type default)
			)
			(layer "F.Fab")
		)
		(fp_line
			(start 0.67945 -0.3048)
			(end 0.67945 0.3048)
			(stroke
				(width 0.1)
				(type default)
			)
			(layer "F.Fab")
		)
		(fp_line
			(start -0.67945 -0.305054)
			(end -0.12065 -0.305054)
			(stroke
				(width 0.1)
				(type default)
			)
			(layer "F.Fab")
		)
		(fp_line
			(start -0.12065 -0.305054)
			(end -0.12065 -0.2794)
			(stroke
				(width 0.1)
				(type default)
			)
			(layer "F.Fab")
		)
		(pad "1" smd circle
			(at -0.40005 0 270)
			(size 0 0)
			(layers "F.Cu" "F.Mask" "F.Paste")
			(net "LED_RST_PLD_CPU0_DRAM_AB_N")
		)
		(pad "2" smd circle
			(at 0.40005 0 270)
			(size 0 0)
			(layers "F.Cu" "F.Mask" "F.Paste")
			(net "P3V3_AUX")
		)
	)
	(footprint ""
		(layer "F.Cu")
		(at 106.331004 -245.634256 -90)
		(property "Reference" "C276"
			(at 0 0 270)
			(layer "F.SilkS")
			(hide yes)
			(effects
				(font
					(size 1.27 1.27)
				)
			)
		)
		(property "Value" ""
			(at 0 0 270)
			(layer "F.Fab")
			(effects
				(font
					(size 1.27 1.27)
				)
			)
		)
		(duplicate_pad_numbers_are_jumpers no)
		(fp_line
			(start -0.7874 0.4064)
			(end -0.7874 -0.4064)
			(stroke
				(width 0.1524)
				(type default)
			)
			(layer "F.SilkS")
		)
		(fp_line
			(start 0.7874 0.4064)
			(end -0.7874 0.4064)
			(stroke
				(width 0.1524)
				(type default)
			)
			(layer "F.SilkS")
		)
		(fp_line
			(start -0.7874 -0.4064)
			(end 0.7874 -0.4064)
			(stroke
				(width 0.1524)
				(type default)
			)
			(layer "F.SilkS")
		)
		(fp_line
			(start 0.7874 -0.4064)
			(end 0.7874 0.4064)
			(stroke
				(width 0.1524)
				(type default)
			)
			(layer "F.SilkS")
		)
		(fp_line
			(start -0.67945 0.3048)
			(end -0.67945 -0.305054)
			(stroke
				(width 0.1)
				(type default)
			)
			(layer "F.Fab")
		)
		(fp_line
			(start -0.12065 0.3048)
			(end -0.67945 0.3048)
			(stroke
				(width 0.1)
				(type default)
			)
			(layer "F.Fab")
		)
		(fp_line
			(start 0.120396 0.3048)
			(end 0.120396 0.2794)
			(stroke
				(width 0.1)
				(type default)
			)
			(layer "F.Fab")
		)
		(fp_line
			(start 0.67945 0.3048)
			(end 0.120396 0.3048)
			(stroke
				(width 0.1)
				(type default)
			)
			(layer "F.Fab")
		)
		(fp_line
			(start -0.12065 0.2794)
			(end -0.12065 0.3048)
			(stroke
				(width 0.1)
				(type default)
			)
			(layer "F.Fab")
		)
		(fp_line
			(start 0.120396 0.2794)
			(end -0.12065 0.2794)
			(stroke
				(width 0.1)
				(type default)
			)
			(layer "F.Fab")
		)
		(fp_line
			(start -0.12065 -0.2794)
			(end 0.12065 -0.2794)
			(stroke
				(width 0.1)
				(type default)
			)
			(layer "F.Fab")
		)
		(fp_line
			(start 0.12065 -0.2794)
			(end 0.12065 -0.3048)
			(stroke
				(width 0.1)
				(type default)
			)
			(layer "F.Fab")
		)
		(fp_line
			(start 0.12065 -0.3048)
			(end 0.67945 -0.3048)
			(stroke
				(width 0.1)
				(type default)
			)
			(layer "F.Fab")
		)
		(fp_line
			(start 0.67945 -0.3048)
			(end 0.67945 0.3048)
			(stroke
				(width 0.1)
				(type default)
			)
			(layer "F.Fab")
		)
		(fp_line
			(start -0.67945 -0.305054)
			(end -0.12065 -0.305054)
			(stroke
				(width 0.1)
				(type default)
			)
			(layer "F.Fab")
		)
		(fp_line
			(start -0.12065 -0.305054)
			(end -0.12065 -0.2794)
			(stroke
				(width 0.1)
				(type default)
			)
			(layer "F.Fab")
		)
		(pad "1" smd circle
			(at -0.40005 0 270)
			(size 0 0)
			(layers "F.Cu" "F.Mask" "F.Paste")
			(net "PVCCIN_CPU1")
		)
		(pad "2" smd circle
			(at 0.40005 0 270)
			(size 0 0)
			(layers "F.Cu" "F.Mask" "F.Paste")
			(net "GND")
		)
	)
	(footprint ""
		(layer "F.Cu")
		(at 312.443622 -43.932348)
		(property "Reference" "R1259"
			(at 0 0 0)
			(layer "F.SilkS")
			(hide yes)
			(effects
				(font
					(size 1.27 1.27)
				)
			)
		)
		(property "Value" ""
			(at 0 0 0)
			(layer "F.Fab")
			(effects
				(font
					(size 1.27 1.27)
				)
			)
		)
		(duplicate_pad_numbers_are_jumpers no)
		(fp_line
			(start -0.7874 -0.4064)
			(end 0.7874 -0.4064)
			(stroke
				(width 0.1524)
				(type default)
			)
			(layer "F.SilkS")
		)
		(fp_line
			(start -0.7874 0.4064)
			(end -0.7874 -0.4064)
			(stroke
				(width 0.1524)
				(type default)
			)
			(layer "F.SilkS")
		)
		(fp_line
			(start 0.7874 -0.4064)
			(end 0.7874 0.4064)
			(stroke
				(width 0.1524)
				(type default)
			)
			(layer "F.SilkS")
		)
		(fp_line
			(start 0.7874 0.4064)
			(end -0.7874 0.4064)
			(stroke
				(width 0.1524)
				(type default)
			)
			(layer "F.SilkS")
		)
		(fp_line
			(start -0.67945 -0.305054)
			(end -0.12065 -0.305054)
			(stroke
				(width 0.1)
				(type default)
			)
			(layer "F.Fab")
		)
		(fp_line
			(start -0.67945 0.3048)
			(end -0.67945 -0.305054)
			(stroke
				(width 0.1)
				(type default)
			)
			(layer "F.Fab")
		)
		(fp_line
			(start -0.12065 -0.305054)
			(end -0.12065 -0.2794)
			(stroke
				(width 0.1)
				(type default)
			)
			(layer "F.Fab")
		)
		(fp_line
			(start -0.12065 -0.2794)
			(end 0.12065 -0.2794)
			(stroke
				(width 0.1)
				(type default)
			)
			(layer "F.Fab")
		)
		(fp_line
			(start -0.12065 0.2794)
			(end -0.12065 0.3048)
			(stroke
				(width 0.1)
				(type default)
			)
			(layer "F.Fab")
		)
		(fp_line
			(start -0.12065 0.3048)
			(end -0.67945 0.3048)
			(stroke
				(width 0.1)
				(type default)
			)
			(layer "F.Fab")
		)
		(fp_line
			(start 0.120396 0.2794)
			(end -0.12065 0.2794)
			(stroke
				(width 0.1)
				(type default)
			)
			(layer "F.Fab")
		)
		(fp_line
			(start 0.120396 0.3048)
			(end 0.120396 0.2794)
			(stroke
				(width 0.1)
				(type default)
			)
			(layer "F.Fab")
		)
		(fp_line
			(start 0.12065 -0.3048)
			(end 0.67945 -0.3048)
			(stroke
				(width 0.1)
				(type default)
			)
			(layer "F.Fab")
		)
		(fp_line
			(start 0.12065 -0.2794)
			(end 0.12065 -0.3048)
			(stroke
				(width 0.1)
				(type default)
			)
			(layer "F.Fab")
		)
		(fp_line
			(start 0.67945 -0.3048)
			(end 0.67945 0.3048)
			(stroke
				(width 0.1)
				(type default)
			)
			(layer "F.Fab")
		)
		(fp_line
			(start 0.67945 0.3048)
			(end 0.120396 0.3048)
			(stroke
				(width 0.1)
				(type default)
			)
			(layer "F.Fab")
		)
		(pad "1" smd circle
			(at -0.40005 0)
			(size 0 0)
			(layers "F.Cu" "F.Mask" "F.Paste")
			(net "P3V3_AUX")
		)
		(pad "2" smd circle
			(at 0.40005 0)
			(size 0 0)
			(layers "F.Cu" "F.Mask" "F.Paste")
			(net "PU_LPC_PME_N")
		)
	)
	(footprint ""
		(layer "F.Cu")
		(at 200.533 -97.8662 180)
		(property "Reference" "C2383"
			(at 0 0 180)
			(layer "F.SilkS")
			(hide yes)
			(effects
				(font
					(size 1.27 1.27)
				)
			)
		)
		(property "Value" ""
			(at 0 0 180)
			(layer "F.Fab")
			(effects
				(font
					(size 1.27 1.27)
				)
			)
		)
		(duplicate_pad_numbers_are_jumpers no)
		(fp_line
			(start 0.7874 0.4064)
			(end -0.7874 0.4064)
			(stroke
				(width 0.1524)
				(type default)
			)
			(layer "F.SilkS")
		)
		(fp_line
			(start 0.7874 -0.4064)
			(end 0.7874 0.4064)
			(stroke
				(width 0.1524)
				(type default)
			)
			(layer "F.SilkS")
		)
		(fp_line
			(start -0.7874 0.4064)
			(end -0.7874 -0.4064)
			(stroke
				(width 0.1524)
				(type default)
			)
			(layer "F.SilkS")
		)
		(fp_line
			(start -0.7874 -0.4064)
			(end 0.7874 -0.4064)
			(stroke
				(width 0.1524)
				(type default)
			)
			(layer "F.SilkS")
		)
		(fp_line
			(start 0.67945 0.3048)
			(end 0.120396 0.3048)
			(stroke
				(width 0.1)
				(type default)
			)
			(layer "F.Fab")
		)
		(fp_line
			(start 0.67945 -0.3048)
			(end 0.67945 0.3048)
			(stroke
				(width 0.1)
				(type default)
			)
			(layer "F.Fab")
		)
		(fp_line
			(start 0.12065 -0.2794)
			(end 0.12065 -0.3048)
			(stroke
				(width 0.1)
				(type default)
			)
			(layer "F.Fab")
		)
		(fp_line
			(start 0.12065 -0.3048)
			(end 0.67945 -0.3048)
			(stroke
				(width 0.1)
				(type default)
			)
			(layer "F.Fab")
		)
		(fp_line
			(start 0.120396 0.3048)
			(end 0.120396 0.2794)
			(stroke
				(width 0.1)
				(type default)
			)
			(layer "F.Fab")
		)
		(fp_line
			(start 0.120396 0.2794)
			(end -0.12065 0.2794)
			(stroke
				(width 0.1)
				(type default)
			)
			(layer "F.Fab")
		)
		(fp_line
			(start -0.12065 0.3048)
			(end -0.67945 0.3048)
			(stroke
				(width 0.1)
				(type default)
			)
			(layer "F.Fab")
		)
		(fp_line
			(start -0.12065 0.2794)
			(end -0.12065 0.3048)
			(stroke
				(width 0.1)
				(type default)
			)
			(layer "F.Fab")
		)
		(fp_line
			(start -0.12065 -0.2794)
			(end 0.12065 -0.2794)
			(stroke
				(width 0.1)
				(type default)
			)
			(layer "F.Fab")
		)
		(fp_line
			(start -0.12065 -0.305054)
			(end -0.12065 -0.2794)
			(stroke
				(width 0.1)
				(type default)
			)
			(layer "F.Fab")
		)
		(fp_line
			(start -0.67945 0.3048)
			(end -0.67945 -0.305054)
			(stroke
				(width 0.1)
				(type default)
			)
			(layer "F.Fab")
		)
		(fp_line
			(start -0.67945 -0.305054)
			(end -0.12065 -0.305054)
			(stroke
				(width 0.1)
				(type default)
			)
			(layer "F.Fab")
		)
		(pad "1" smd circle
			(at -0.40005 0 180)
			(size 0 0)
			(layers "F.Cu" "F.Mask" "F.Paste")
			(net "P12V_AUX")
		)
		(pad "2" smd circle
			(at 0.40005 0 180)
			(size 0 0)
			(layers "F.Cu" "F.Mask" "F.Paste")
			(net "GND")
		)
	)
	(footprint ""
		(layer "F.Cu")
		(at 301.01032 -411.604206 -90)
		(property "Reference" "C2364"
			(at 0 0 270)
			(layer "F.SilkS")
			(hide yes)
			(effects
				(font
					(size 1.27 1.27)
				)
			)
		)
		(property "Value" ""
			(at 0 0 270)
			(layer "F.Fab")
			(effects
				(font
					(size 1.27 1.27)
				)
			)
		)
		(duplicate_pad_numbers_are_jumpers no)
		(fp_line
			(start -0.7874 0.4064)
			(end -0.7874 -0.4064)
			(stroke
				(width 0.1524)
				(type default)
			)
			(layer "F.SilkS")
		)
		(fp_line
			(start 0.7874 0.4064)
			(end -0.7874 0.4064)
			(stroke
				(width 0.1524)
				(type default)
			)
			(layer "F.SilkS")
		)
		(fp_line
			(start -0.7874 -0.4064)
			(end 0.7874 -0.4064)
			(stroke
				(width 0.1524)
				(type default)
			)
			(layer "F.SilkS")
		)
		(fp_line
			(start 0.7874 -0.4064)
			(end 0.7874 0.4064)
			(stroke
				(width 0.1524)
				(type default)
			)
			(layer "F.SilkS")
		)
		(fp_line
			(start -0.67945 0.3048)
			(end -0.67945 -0.305054)
			(stroke
				(width 0.1)
				(type default)
			)
			(layer "F.Fab")
		)
		(fp_line
			(start -0.12065 0.3048)
			(end -0.67945 0.3048)
			(stroke
				(width 0.1)
				(type default)
			)
			(layer "F.Fab")
		)
		(fp_line
			(start 0.120396 0.3048)
			(end 0.120396 0.2794)
			(stroke
				(width 0.1)
				(type default)
			)
			(layer "F.Fab")
		)
		(fp_line
			(start 0.67945 0.3048)
			(end 0.120396 0.3048)
			(stroke
				(width 0.1)
				(type default)
			)
			(layer "F.Fab")
		)
		(fp_line
			(start -0.12065 0.2794)
			(end -0.12065 0.3048)
			(stroke
				(width 0.1)
				(type default)
			)
			(layer "F.Fab")
		)
		(fp_line
			(start 0.120396 0.2794)
			(end -0.12065 0.2794)
			(stroke
				(width 0.1)
				(type default)
			)
			(layer "F.Fab")
		)
		(fp_line
			(start -0.12065 -0.2794)
			(end 0.12065 -0.2794)
			(stroke
				(width 0.1)
				(type default)
			)
			(layer "F.Fab")
		)
		(fp_line
			(start 0.12065 -0.2794)
			(end 0.12065 -0.3048)
			(stroke
				(width 0.1)
				(type default)
			)
			(layer "F.Fab")
		)
		(fp_line
			(start 0.12065 -0.3048)
			(end 0.67945 -0.3048)
			(stroke
				(width 0.1)
				(type default)
			)
			(layer "F.Fab")
		)
		(fp_line
			(start 0.67945 -0.3048)
			(end 0.67945 0.3048)
			(stroke
				(width 0.1)
				(type default)
			)
			(layer "F.Fab")
		)
		(fp_line
			(start -0.67945 -0.305054)
			(end -0.12065 -0.305054)
			(stroke
				(width 0.1)
				(type default)
			)
			(layer "F.Fab")
		)
		(fp_line
			(start -0.12065 -0.305054)
			(end -0.12065 -0.2794)
			(stroke
				(width 0.1)
				(type default)
			)
			(layer "F.Fab")
		)
		(pad "1" smd circle
			(at -0.40005 0 270)
			(size 0 0)
			(layers "F.Cu" "F.Mask" "F.Paste")
			(net "P3V3_AUX")
		)
		(pad "2" smd circle
			(at 0.40005 0 270)
			(size 0 0)
			(layers "F.Cu" "F.Mask" "F.Paste")
			(net "GND")
		)
	)
	(footprint ""
		(layer "F.Cu")
		(at 113.21288 -101.793548 90)
		(property "Reference" "R1443"
			(at 0 0 90)
			(layer "F.SilkS")
			(hide yes)
			(effects
				(font
					(size 1.27 1.27)
				)
			)
		)
		(property "Value" ""
			(at 0 0 90)
			(layer "F.Fab")
			(effects
				(font
					(size 1.27 1.27)
				)
			)
		)
		(duplicate_pad_numbers_are_jumpers no)
		(fp_line
			(start 0.7874 -0.4064)
			(end 0.7874 0.4064)
			(stroke
				(width 0.1524)
				(type default)
			)
			(layer "F.SilkS")
		)
		(fp_line
			(start -0.7874 -0.4064)
			(end 0.7874 -0.4064)
			(stroke
				(width 0.1524)
				(type default)
			)
			(layer "F.SilkS")
		)
		(fp_line
			(start 0.7874 0.4064)
			(end -0.7874 0.4064)
			(stroke
				(width 0.1524)
				(type default)
			)
			(layer "F.SilkS")
		)
		(fp_line
			(start -0.7874 0.4064)
			(end -0.7874 -0.4064)
			(stroke
				(width 0.1524)
				(type default)
			)
			(layer "F.SilkS")
		)
		(fp_line
			(start -0.12065 -0.305054)
			(end -0.12065 -0.2794)
			(stroke
				(width 0.1)
				(type default)
			)
			(layer "F.Fab")
		)
		(fp_line
			(start -0.67945 -0.305054)
			(end -0.12065 -0.305054)
			(stroke
				(width 0.1)
				(type default)
			)
			(layer "F.Fab")
		)
		(fp_line
			(start 0.67945 -0.3048)
			(end 0.67945 0.3048)
			(stroke
				(width 0.1)
				(type default)
			)
			(layer "F.Fab")
		)
		(fp_line
			(start 0.12065 -0.3048)
			(end 0.67945 -0.3048)
			(stroke
				(width 0.1)
				(type default)
			)
			(layer "F.Fab")
		)
		(fp_line
			(start 0.12065 -0.2794)
			(end 0.12065 -0.3048)
			(stroke
				(width 0.1)
				(type default)
			)
			(layer "F.Fab")
		)
		(fp_line
			(start -0.12065 -0.2794)
			(end 0.12065 -0.2794)
			(stroke
				(width 0.1)
				(type default)
			)
			(layer "F.Fab")
		)
		(fp_line
			(start 0.120396 0.2794)
			(end -0.12065 0.2794)
			(stroke
				(width 0.1)
				(type default)
			)
			(layer "F.Fab")
		)
		(fp_line
			(start -0.12065 0.2794)
			(end -0.12065 0.3048)
			(stroke
				(width 0.1)
				(type default)
			)
			(layer "F.Fab")
		)
		(fp_line
			(start 0.67945 0.3048)
			(end 0.120396 0.3048)
			(stroke
				(width 0.1)
				(type default)
			)
			(layer "F.Fab")
		)
		(fp_line
			(start 0.120396 0.3048)
			(end 0.120396 0.2794)
			(stroke
				(width 0.1)
				(type default)
			)
			(layer "F.Fab")
		)
		(fp_line
			(start -0.12065 0.3048)
			(end -0.67945 0.3048)
			(stroke
				(width 0.1)
				(type default)
			)
			(layer "F.Fab")
		)
		(fp_line
			(start -0.67945 0.3048)
			(end -0.67945 -0.305054)
			(stroke
				(width 0.1)
				(type default)
			)
			(layer "F.Fab")
		)
		(pad "1" smd circle
			(at -0.40005 0 90)
			(size 0 0)
			(layers "F.Cu" "F.Mask" "F.Paste")
			(net "PWRGD_CPUPWRGD_LVC1")
		)
		(pad "2" smd circle
			(at 0.40005 0 90)
			(size 0 0)
			(layers "F.Cu" "F.Mask" "F.Paste")
			(net "PWRGD_CPUPWRGD_LVC1_R")
		)
	)
	(footprint ""
		(layer "F.Cu")
		(at 428.179992 -381.218948)
		(property "Reference" "Q69"
			(at 0.610108 -2.01803 0)
			(unlocked yes)
			(layer "F.SilkS")
			(effects
				(font
					(size 0.7874 0.5842)
					(thickness 0.1524)
				)
				(justify left)
			)
		)
		(property "Value" ""
			(at 0 0 0)
			(layer "F.Fab")
			(effects
				(font
					(size 1.27 1.27)
				)
			)
		)
		(duplicate_pad_numbers_are_jumpers no)
		(fp_line
			(start -1.332738 -1.100074)
			(end -0.4826 -1.100074)
			(stroke
				(width 0.1524)
				(type default)
			)
			(layer "F.SilkS")
		)
		(fp_line
			(start -1.332738 1.100074)
			(end -1.332738 -1.100074)
			(stroke
				(width 0.1524)
				(type default)
			)
			(layer "F.SilkS")
		)
		(fp_line
			(start -0.4826 -1.100074)
			(end 0 -0.541274)
			(stroke
				(width 0.1524)
				(type default)
			)
			(layer "F.SilkS")
		)
		(fp_line
			(start 0 -0.541274)
			(end 0.4826 -1.100074)
			(stroke
				(width 0.1524)
				(type default)
			)
			(layer "F.SilkS")
		)
		(fp_line
			(start 0.4826 -1.100074)
			(end 1.332738 -1.100074)
			(stroke
				(width 0.1524)
				(type default)
			)
			(layer "F.SilkS")
		)
		(fp_line
			(start 1.332738 -1.100074)
			(end 1.332738 1.100074)
			(stroke
				(width 0.1524)
				(type default)
			)
			(layer "F.SilkS")
		)
		(fp_line
			(start 1.332738 1.100074)
			(end -1.332738 1.100074)
			(stroke
				(width 0.1524)
				(type default)
			)
			(layer "F.SilkS")
		)
		(fp_poly
			(pts
				(xy -0.552958 -2.070608) (xy -0.903986 -1.368552) (xy -1.255014 -2.070608)
			)
			(stroke
				(width 0)
				(type default)
			)
			(fill yes)
			(layer "F.SilkS")
		)
		(fp_line
			(start -0.674878 -1.100074)
			(end 0.674878 -1.100074)
			(stroke
				(width 0.1)
				(type default)
			)
			(layer "F.Fab")
		)
		(fp_line
			(start -0.674878 1.100074)
			(end -0.674878 -1.100074)
			(stroke
				(width 0.1)
				(type default)
			)
			(layer "F.Fab")
		)
		(fp_line
			(start 0.674878 -1.100074)
			(end 0.674878 1.100074)
			(stroke
				(width 0.1)
				(type default)
			)
			(layer "F.Fab")
		)
		(fp_line
			(start 0.674878 1.100074)
			(end -0.674878 1.100074)
			(stroke
				(width 0.1)
				(type default)
			)
			(layer "F.Fab")
		)
		(fp_poly
			(pts
				(xy -2.2352 -0.298958) (xy -2.2352 -1.001014) (xy -1.533144 -0.649986)
			)
			(stroke
				(width 0)
				(type default)
			)
			(fill yes)
			(layer "F.Fab")
		)
		(pad "1" smd rect
			(at -0.94996 -0.649986 90)
			(size 0.4318 0.508)
			(layers "F.Cu" "F.Mask" "F.Paste")
			(net "GND")
		)
		(pad "2" smd rect
			(at -0.94996 0 90)
			(size 0.4318 0.508)
			(layers "F.Cu" "F.Mask" "F.Paste")
			(net "RST_BMC_FROM_SWB_N")
		)
		(pad "3" smd rect
			(at -0.94996 0.649986 90)
			(size 0.4318 0.508)
			(layers "F.Cu" "F.Mask" "F.Paste")
			(net "RST_BMC_FROM_SWB_ISO_N")
		)
		(pad "4" smd rect
			(at 0.94996 0.649986 90)
			(size 0.4318 0.508)
			(layers "F.Cu" "F.Mask" "F.Paste")
			(net "GND")
		)
		(pad "5" smd rect
			(at 0.94996 0 90)
			(size 0.4318 0.508)
			(layers "F.Cu" "F.Mask" "F.Paste")
			(net "RST_BMC_FROM_SWB")
		)
		(pad "6" smd rect
			(at 0.94996 -0.649986 90)
			(size 0.4318 0.508)
			(layers "F.Cu" "F.Mask" "F.Paste")
			(net "RST_BMC_FROM_SWB")
		)
	)
	(footprint ""
		(layer "F.Cu")
		(at 129.59588 -103.723948 -90)
		(property "Reference" "Q141"
			(at -0.162052 -2.00279 90)
			(unlocked yes)
			(layer "F.SilkS")
			(effects
				(font
					(size 0.7874 0.5842)
					(thickness 0.1524)
				)
			)
		)
		(property "Value" ""
			(at 0 0 270)
			(layer "F.Fab")
			(effects
				(font
					(size 1.27 1.27)
				)
			)
		)
		(duplicate_pad_numbers_are_jumpers no)
		(fp_line
			(start -1.376172 1.199896)
			(end -1.376172 -1.199896)
			(stroke
				(width 0.1524)
				(type default)
			)
			(layer "F.SilkS")
		)
		(fp_line
			(start 1.376172 1.199896)
			(end -1.376172 1.199896)
			(stroke
				(width 0.1524)
				(type default)
			)
			(layer "F.SilkS")
		)
		(fp_line
			(start 0 -0.762)
			(end 0.508 -1.199896)
			(stroke
				(width 0.1524)
				(type default)
			)
			(layer "F.SilkS")
		)
		(fp_line
			(start -1.376172 -1.199896)
			(end -0.508 -1.199896)
			(stroke
				(width 0.1524)
				(type default)
			)
			(layer "F.SilkS")
		)
		(fp_line
			(start -0.508 -1.199896)
			(end 0 -0.762)
			(stroke
				(width 0.1524)
				(type default)
			)
			(layer "F.SilkS")
		)
		(fp_line
			(start 0.508 -1.199896)
			(end 1.376172 -1.199896)
			(stroke
				(width 0.1524)
				(type default)
			)
			(layer "F.SilkS")
		)
		(fp_line
			(start 1.376172 -1.199896)
			(end 1.376172 1.199896)
			(stroke
				(width 0.1524)
				(type default)
			)
			(layer "F.SilkS")
		)
		(fp_poly
			(pts
				(xy -1.4605 -0.7493) (xy -2.2225 -1.1303) (xy -2.2225 -0.3683)
			)
			(stroke
				(width 0)
				(type default)
			)
			(fill yes)
			(layer "F.SilkS")
		)
		(fp_line
			(start -0.674878 1.100074)
			(end -0.674878 -1.100074)
			(stroke
				(width 0.1)
				(type default)
			)
			(layer "F.Fab")
		)
		(fp_line
			(start 0.674878 1.100074)
			(end -0.674878 1.100074)
			(stroke
				(width 0.1)
				(type default)
			)
			(layer "F.Fab")
		)
		(fp_line
			(start -0.674878 -1.100074)
			(end 0.674878 -1.100074)
			(stroke
				(width 0.1)
				(type default)
			)
			(layer "F.Fab")
		)
		(fp_line
			(start 0.674878 -1.100074)
			(end 0.674878 1.100074)
			(stroke
				(width 0.1)
				(type default)
			)
			(layer "F.Fab")
		)
		(fp_poly
			(pts
				(xy -1.4605 -0.7493) (xy -2.2225 -1.1303) (xy -2.2225 -0.3683)
			)
			(stroke
				(width 0)
				(type default)
			)
			(fill yes)
			(layer "F.Fab")
		)
		(pad "1" smd rect
			(at -0.899922 -0.750062 180)
			(size 0.6096 0.6096)
			(layers "F.Cu" "F.Mask" "F.Paste")
			(net "GND")
		)
		(pad "2" smd rect
			(at -0.899922 0 180)
			(size 0.4064 0.6096)
			(layers "F.Cu" "F.Mask" "F.Paste")
			(net "H_CPU0_MEMTRIP_R")
		)
		(pad "3" smd rect
			(at -0.899922 0.750062 180)
			(size 0.6096 0.6096)
			(layers "F.Cu" "F.Mask" "F.Paste")
			(net "H_CPU0_MEMTRIP")
		)
		(pad "4" smd rect
			(at 0.899922 0.750062 180)
			(size 0.6096 0.6096)
			(layers "F.Cu" "F.Mask" "F.Paste")
			(net "PVNN_TERM_CPU0")
		)
		(pad "5" smd rect
			(at 0.899922 0 180)
			(size 0.4064 0.6096)
			(layers "F.Cu" "F.Mask" "F.Paste")
			(net "H_CPU0_MEMTRIP_OUT_VT_R_N")
		)
		(pad "6" smd rect
			(at 0.899922 -0.750062 180)
			(size 0.6096 0.6096)
			(layers "F.Cu" "F.Mask" "F.Paste")
			(net "H_CPU0_MEMTRIP_VT_N")
		)
	)
	(footprint ""
		(layer "F.Cu")
		(at 108.578396 -358.848406 -90)
		(property "Reference" "PU29"
			(at 8.473948 -1.629664 0)
			(unlocked yes)
			(layer "F.SilkS")
			(effects
				(font
					(size 0.7874 0.5842)
					(thickness 0.1524)
				)
				(justify left)
			)
		)
		(property "Value" ""
			(at 0 0 270)
			(layer "F.Fab")
			(effects
				(font
					(size 1.27 1.27)
				)
			)
		)
		(duplicate_pad_numbers_are_jumpers no)
		(fp_line
			(start -1.400048 3.86969)
			(end -1.400048 3.36169)
			(stroke
				(width 0.1524)
				(type default)
			)
			(layer "F.SilkS")
		)
		(fp_line
			(start 0.599948 3.366008)
			(end 0.599948 4.255008)
			(stroke
				(width 0.1524)
				(type default)
			)
			(layer "F.SilkS")
		)
		(fp_line
			(start -2.999994 2.999994)
			(end -2.999994 2.490978)
			(stroke
				(width 0.1524)
				(type default)
			)
			(layer "F.SilkS")
		)
		(fp_line
			(start -2.518156 2.999994)
			(end -2.999994 2.999994)
			(stroke
				(width 0.1524)
				(type default)
			)
			(layer "F.SilkS")
		)
		(fp_line
			(start 2.999994 2.999994)
			(end 2.47015 2.999994)
			(stroke
				(width 0.1524)
				(type default)
			)
			(layer "F.SilkS")
		)
		(fp_line
			(start 2.999994 2.490978)
			(end 2.999994 2.999994)
			(stroke
				(width 0.1524)
				(type default)
			)
			(layer "F.SilkS")
		)
		(fp_line
			(start 3.3782 2.199894)
			(end 3.8862 2.199894)
			(stroke
				(width 0.1524)
				(type default)
			)
			(layer "F.SilkS")
		)
		(fp_line
			(start -3.3782 1.400048)
			(end -4.2672 1.400048)
			(stroke
				(width 0.1524)
				(type default)
			)
			(layer "F.SilkS")
		)
		(fp_line
			(start 3.3528 0.199898)
			(end 4.2418 0.199898)
			(stroke
				(width 0.1524)
				(type default)
			)
			(layer "F.SilkS")
		)
		(fp_line
			(start -3.3782 -0.599948)
			(end -3.7592 -0.599948)
			(stroke
				(width 0.1524)
				(type default)
			)
			(layer "F.SilkS")
		)
		(fp_line
			(start 3.3528 -1.800098)
			(end 3.8608 -1.800098)
			(stroke
				(width 0.1524)
				(type default)
			)
			(layer "F.SilkS")
		)
		(fp_line
			(start -2.999994 -2.438654)
			(end -2.999994 -2.999994)
			(stroke
				(width 0.1524)
				(type default)
			)
			(layer "F.SilkS")
		)
		(fp_line
			(start -2.999994 -2.999994)
			(end -2.489962 -2.999994)
			(stroke
				(width 0.1524)
				(type default)
			)
			(layer "F.SilkS")
		)
		(fp_line
			(start 2.437384 -2.999994)
			(end 2.999994 -2.999994)
			(stroke
				(width 0.1524)
				(type default)
			)
			(layer "F.SilkS")
		)
		(fp_line
			(start 2.999994 -2.999994)
			(end 2.999994 -2.471166)
			(stroke
				(width 0.1524)
				(type default)
			)
			(layer "F.SilkS")
		)
		(fp_line
			(start -0.999998 -3.3782)
			(end -0.999998 -3.8862)
			(stroke
				(width 0.1524)
				(type default)
			)
			(layer "F.SilkS")
		)
		(fp_line
			(start 0.999998 -4.2545)
			(end 0.999998 -3.3655)
			(stroke
				(width 0.1524)
				(type default)
			)
			(layer "F.SilkS")
		)
		(fp_poly
			(pts
				(xy -3.299206 -2.199894) (xy -3.6449 -2.050034) (xy -3.6449 -2.352294)
			)
			(stroke
				(width 0)
				(type default)
			)
			(fill yes)
			(layer "F.SilkS")
		)
		(fp_line
			(start -1.400048 3.86969)
			(end -1.400048 3.36169)
			(stroke
				(width 0.1)
				(type default)
			)
			(layer "F.Fab")
		)
		(fp_line
			(start 0.599948 3.366008)
			(end 0.599948 4.255008)
			(stroke
				(width 0.1)
				(type default)
			)
			(layer "F.Fab")
		)
		(fp_line
			(start -2.999994 2.999994)
			(end -2.999994 -2.999994)
			(stroke
				(width 0.1)
				(type default)
			)
			(layer "F.Fab")
		)
		(fp_line
			(start 2.999994 2.999994)
			(end -2.999994 2.999994)
			(stroke
				(width 0.1)
				(type default)
			)
			(layer "F.Fab")
		)
		(fp_line
			(start 3.3782 2.199894)
			(end 3.8862 2.199894)
			(stroke
				(width 0.1)
				(type default)
			)
			(layer "F.Fab")
		)
		(fp_line
			(start -3.3782 1.400048)
			(end -4.2672 1.400048)
			(stroke
				(width 0.1)
				(type default)
			)
			(layer "F.Fab")
		)
		(fp_line
			(start 3.3528 0.199898)
			(end 4.2418 0.199898)
			(stroke
				(width 0.1)
				(type default)
			)
			(layer "F.Fab")
		)
		(fp_line
			(start -3.3782 -0.599948)
			(end -3.7592 -0.599948)
			(stroke
				(width 0.1)
				(type default)
			)
			(layer "F.Fab")
		)
		(fp_line
			(start 3.3528 -1.800098)
			(end 3.8608 -1.800098)
			(stroke
				(width 0.1)
				(type default)
			)
			(layer "F.Fab")
		)
		(fp_line
			(start -2.999994 -2.999994)
			(end 2.999994 -2.999994)
			(stroke
				(width 0.1)
				(type default)
			)
			(layer "F.Fab")
		)
		(fp_line
			(start 2.999994 -2.999994)
			(end 2.999994 2.999994)
			(stroke
				(width 0.1)
				(type default)
			)
			(layer "F.Fab")
		)
		(fp_line
			(start -0.999998 -3.3782)
			(end -0.999998 -3.8862)
			(stroke
				(width 0.1)
				(type default)
			)
			(layer "F.Fab")
		)
		(fp_line
			(start 0.999998 -4.2545)
			(end 0.999998 -3.3655)
			(stroke
				(width 0.1)
				(type default)
			)
			(layer "F.Fab")
		)
		(fp_poly
			(pts
				(xy -3.6449 -2.352294) (xy -3.6449 -2.050034) (xy -3.299206 -2.199894)
			)
			(stroke
				(width 0)
				(type default)
			)
			(fill yes)
			(layer "F.Fab")
		)
		(fp_text user "24"
			(at 2.807716 4.885436 0)
			(unlocked yes)
			(layer "F.SilkS")
			(effects
				(font
					(size 0.7874 0.5842)
					(thickness 0.1524)
				)
				(justify left)
			)
		)
		(fp_text user "13"
			(at -2.514092 4.717796 0)
			(unlocked yes)
			(layer "F.SilkS")
			(effects
				(font
					(size 0.7874 0.5842)
					(thickness 0.1524)
				)
				(justify left)
			)
		)
		(fp_text user "25"
			(at 3.765296 3.948176 0)
			(unlocked yes)
			(layer "F.SilkS")
			(effects
				(font
					(size 0.7874 0.5842)
					(thickness 0.1524)
				)
				(justify left)
			)
		)
		(fp_text user "12"
			(at -3.999992 2.645156 0)
			(unlocked yes)
			(layer "F.SilkS")
			(effects
				(font
					(size 0.7874 0.5842)
					(thickness 0.1524)
				)
				(justify left)
			)
		)
		(fp_text user "36"
			(at 4.059428 -2.137664 0)
			(unlocked yes)
			(layer "F.SilkS")
			(effects
				(font
					(size 0.7874 0.5842)
					(thickness 0.1524)
				)
				(justify left)
			)
		)
		(fp_text user "48"
			(at -4.530852 -2.157984 0)
			(unlocked yes)
			(layer "F.SilkS")
			(effects
				(font
					(size 0.7874 0.5842)
					(thickness 0.1524)
				)
				(justify left)
			)
		)
		(fp_text user "48"
			(at -1.754632 -3.547364 0)
			(unlocked yes)
			(layer "F.SilkS")
			(effects
				(font
					(size 0.7874 0.5842)
					(thickness 0.1524)
				)
				(justify left)
			)
		)
		(fp_text user "37"
			(at 2.908808 -3.547364 0)
			(unlocked yes)
			(layer "F.SilkS")
			(effects
				(font
					(size 0.7874 0.5842)
					(thickness 0.1524)
				)
				(justify left)
			)
		)
		(fp_text user "13"
			(at -3.5814 3.794252 270)
			(unlocked yes)
			(layer "F.Fab")
			(effects
				(font
					(size 0.7874 0.5842)
					(thickness 0.1524)
				)
				(justify left)
			)
		)
		(fp_text user "24"
			(at 2.1844 3.768852 270)
			(unlocked yes)
			(layer "F.Fab")
			(effects
				(font
					(size 0.7874 0.5842)
					(thickness 0.1524)
				)
				(justify left)
			)
		)
		(fp_text user "25"
			(at 3.2004 2.829052 270)
			(unlocked yes)
			(layer "F.Fab")
			(effects
				(font
					(size 0.7874 0.5842)
					(thickness 0.1524)
				)
				(justify left)
			)
		)
		(fp_text user "12"
			(at -4.6228 2.752852 270)
			(unlocked yes)
			(layer "F.Fab")
			(effects
				(font
					(size 0.7874 0.5842)
					(thickness 0.1524)
				)
				(justify left)
			)
		)
		(fp_text user "36"
			(at 3.2258 -2.733548 270)
			(unlocked yes)
			(layer "F.Fab")
			(effects
				(font
					(size 0.7874 0.5842)
					(thickness 0.1524)
				)
				(justify left)
			)
		)
		(fp_text user "37"
			(at 2.2352 -3.724148 270)
			(unlocked yes)
			(layer "F.Fab")
			(effects
				(font
					(size 0.7874 0.5842)
					(thickness 0.1524)
				)
				(justify left)
			)
		)
		(fp_text user "48"
			(at -3.509264 -3.740658 270)
			(unlocked yes)
			(layer "F.Fab")
			(effects
				(font
					(size 0.7874 0.5842)
					(thickness 0.1524)
				)
				(justify left)
			)
		)
		(pad "1" smd rect
			(at -2.875026 -2.199894)
			(size 0.1778 0.6604)
			(layers "F.Cu" "F.Mask" "F.Paste")
			(net "PVCCFA_EHV_FIVRA_CPU1_PWM1")
		)
		(pad "2" smd rect
			(at -2.875026 -1.800098)
			(size 0.1778 0.6604)
			(layers "F.Cu" "F.Mask" "F.Paste")
			(net "PVCCFA_EHV_FIVRA_CPU1_PWM2")
		)
		(pad "3" smd rect
			(at -2.875026 -1.400048)
			(size 0.1778 0.6604)
			(layers "F.Cu" "F.Mask" "F.Paste")
			(net "PVCCFA_EHV_FIVRA_CPU1_PWM3")
		)
		(pad "4" smd rect
			(at -2.875026 -0.999998)
			(size 0.1778 0.6604)
			(layers "F.Cu" "F.Mask" "F.Paste")
			(net "PVCCFA_EHV_FIVRA_CPU1_PWM4")
		)
		(pad "5" smd rect
			(at -2.875026 -0.599948)
			(size 0.1778 0.6604)
			(layers "F.Cu" "F.Mask" "F.Paste")
			(net "PVCCIN_CPU1_PWM8")
		)
		(pad "6" smd rect
			(at -2.875026 -0.199898)
			(size 0.1778 0.6604)
			(layers "F.Cu" "F.Mask" "F.Paste")
			(net "PVCCIN_CPU1_PWM7")
		)
		(pad "7" smd rect
			(at -2.875026 0.199898)
			(size 0.1778 0.6604)
			(layers "F.Cu" "F.Mask" "F.Paste")
			(net "PVCCIN_CPU1_PWM6")
		)
		(pad "8" smd rect
			(at -2.875026 0.599948)
			(size 0.1778 0.6604)
			(layers "F.Cu" "F.Mask" "F.Paste")
			(net "PVCCIN_CPU1_PWM5")
		)
		(pad "9" smd rect
			(at -2.875026 0.999998)
			(size 0.1778 0.6604)
			(layers "F.Cu" "F.Mask" "F.Paste")
			(net "PVCCIN_CPU1_PWM4")
		)
		(pad "10" smd rect
			(at -2.875026 1.400048)
			(size 0.1778 0.6604)
			(layers "F.Cu" "F.Mask" "F.Paste")
			(net "PVCCIN_CPU1_PWM3")
		)
		(pad "11" smd rect
			(at -2.875026 1.800098)
			(size 0.1778 0.6604)
			(layers "F.Cu" "F.Mask" "F.Paste")
			(net "PVCCIN_CPU1_PWM2")
		)
		(pad "12" smd rect
			(at -2.875026 2.199894)
			(size 0.1778 0.6604)
			(layers "F.Cu" "F.Mask" "F.Paste")
			(net "PVCCIN_CPU1_PWM1")
		)
		(pad "13" smd rect
			(at -2.199894 2.875026 270)
			(size 0.1778 0.6604)
			(layers "F.Cu" "F.Mask" "F.Paste")
			(net "SMB_DIO_PVCCIN_CPU1")
		)
		(pad "14" smd rect
			(at -1.800098 2.875026 270)
			(size 0.1778 0.6604)
			(layers "F.Cu" "F.Mask" "F.Paste")
			(net "SMB_CLK_PVCCIN_CPU1")
		)
		(pad "15" smd rect
			(at -1.400048 2.875026 270)
			(size 0.1778 0.6604)
			(layers "F.Cu" "F.Mask" "F.Paste")
			(net "NC_PVCCIN_CPU1_SMB_ALERT")
		)
		(pad "16" smd rect
			(at -0.999998 2.875026 270)
			(size 0.1778 0.6604)
			(layers "F.Cu" "F.Mask" "F.Paste")
			(net "PWRGD_PVCCIN_CPU1_R")
		)
		(pad "17" smd rect
			(at -0.599948 2.875026 270)
			(size 0.1778 0.6604)
			(layers "F.Cu" "F.Mask" "F.Paste")
			(net "PVCCIN_CPU1_EN_R")
		)
		(pad "18" smd rect
			(at -0.199898 2.875026 270)
			(size 0.1778 0.6604)
			(layers "F.Cu" "F.Mask" "F.Paste")
			(net "IRQ_PVCCIN_CPU1_VRHOT_N")
		)
		(pad "19" smd rect
			(at 0.199898 2.875026 270)
			(size 0.1778 0.6604)
			(layers "F.Cu" "F.Mask" "F.Paste")
			(net "PVCCIN_CPU1_PIN_ALERT")
		)
		(pad "20" smd rect
			(at 0.599948 2.875026 270)
			(size 0.1778 0.6604)
			(layers "F.Cu" "F.Mask" "F.Paste")
			(net "PWRGD_PVCCFA_EHV_FIVRA_CPU1_R")
		)
		(pad "21" smd rect
			(at 0.999998 2.875026 270)
			(size 0.1778 0.6604)
			(layers "F.Cu" "F.Mask" "F.Paste")
			(net "SVID_CLK_PVCCIN_CPU1_R")
		)
		(pad "22" smd rect
			(at 1.400048 2.875026 270)
			(size 0.1778 0.6604)
			(layers "F.Cu" "F.Mask" "F.Paste")
			(net "SVID_DIO_PVCCIN_CPU1_R")
		)
		(pad "23" smd rect
			(at 1.800098 2.875026 270)
			(size 0.1778 0.6604)
			(layers "F.Cu" "F.Mask" "F.Paste")
			(net "SVID_ALERT_PVCCIN_CPU1_R")
		)
		(pad "24" smd rect
			(at 2.199894 2.875026 270)
			(size 0.1778 0.6604)
			(layers "F.Cu" "F.Mask" "F.Paste")
			(net "PVCCFA_EHV_FIVRA_CPU1_EN_R")
		)
		(pad "25" smd rect
			(at 2.875026 2.199894)
			(size 0.1778 0.6604)
			(layers "F.Cu" "F.Mask" "F.Paste")
			(net "SH_PVCCIN_CPU1_R")
		)
		(pad "26" smd rect
			(at 2.875026 1.800098)
			(size 0.1778 0.6604)
			(layers "F.Cu" "F.Mask" "F.Paste")
			(net "VSENSE_PVCCIN_CPU1_DN")
		)
		(pad "27" smd rect
			(at 2.875026 1.400048)
			(size 0.1778 0.6604)
			(layers "F.Cu" "F.Mask" "F.Paste")
			(net "PVCCIN_CPU1_IMON1")
		)
		(pad "28" smd rect
			(at 2.875026 0.999998)
			(size 0.1778 0.6604)
			(layers "F.Cu" "F.Mask" "F.Paste")
			(net "PVCCIN_CPU1_IMON2")
		)
		(pad "29" smd rect
			(at 2.875026 0.599948)
			(size 0.1778 0.6604)
			(layers "F.Cu" "F.Mask" "F.Paste")
			(net "PVCCIN_CPU1_IMON3")
		)
		(pad "30" smd rect
			(at 2.875026 0.199898)
			(size 0.1778 0.6604)
			(layers "F.Cu" "F.Mask" "F.Paste")
			(net "PVCCIN_CPU1_IMON4")
		)
		(pad "31" smd rect
			(at 2.875026 -0.199898)
			(size 0.1778 0.6604)
			(layers "F.Cu" "F.Mask" "F.Paste")
			(net "PVCCIN_CPU1_IMON5")
		)
		(pad "32" smd rect
			(at 2.875026 -0.599948)
			(size 0.1778 0.6604)
			(layers "F.Cu" "F.Mask" "F.Paste")
			(net "PVCCIN_CPU1_IMON6")
		)
		(pad "33" smd rect
			(at 2.875026 -0.999998)
			(size 0.1778 0.6604)
			(layers "F.Cu" "F.Mask" "F.Paste")
			(net "PVCCIN_CPU1_IMON7")
		)
		(pad "34" smd rect
			(at 2.875026 -1.400048)
			(size 0.1778 0.6604)
			(layers "F.Cu" "F.Mask" "F.Paste")
			(net "PVCCIN_CPU1_IMON8")
		)
		(pad "35" smd rect
			(at 2.875026 -1.800098)
			(size 0.1778 0.6604)
			(layers "F.Cu" "F.Mask" "F.Paste")
			(net "PVCCFA_EHV_FIVRA_CPU1_IMON4")
		)
		(pad "36" smd rect
			(at 2.875026 -2.199894)
			(size 0.1778 0.6604)
			(layers "F.Cu" "F.Mask" "F.Paste")
			(net "PVCCFA_EHV_FIVRA_CPU1_IMON3")
		)
		(pad "37" smd rect
			(at 2.199894 -2.875026 270)
			(size 0.1778 0.6604)
			(layers "F.Cu" "F.Mask" "F.Paste")
			(net "PVCCFA_EHV_FIVRA_CPU1_IMON2")
		)
		(pad "38" smd rect
			(at 1.800098 -2.875026 270)
			(size 0.1778 0.6604)
			(layers "F.Cu" "F.Mask" "F.Paste")
			(net "PVCCFA_EHV_FIVRA_CPU1_IMON1")
		)
		(pad "39" smd rect
			(at 1.400048 -2.875026 270)
			(size 0.1778 0.6604)
			(layers "F.Cu" "F.Mask" "F.Paste")
			(net "VSENSE_PVCCFA_EHV_FIVRA_CPU1_DN")
		)
		(pad "40" smd rect
			(at 0.999998 -2.875026 270)
			(size 0.1778 0.6604)
			(layers "F.Cu" "F.Mask" "F.Paste")
			(net "SH_PVCCFA_EHV_FIVRA_CPU1_R")
		)
		(pad "41" smd rect
			(at 0.599948 -2.875026 270)
			(size 0.1778 0.6604)
			(layers "F.Cu" "F.Mask" "F.Paste")
			(net "PVCCIN_CPU1_VR_FAULT")
		)
		(pad "42" smd rect
			(at 0.199898 -2.875026 270)
			(size 0.1778 0.6604)
			(layers "F.Cu" "F.Mask" "F.Paste")
			(net "PVCCIN_CPU1_ADDR")
		)
		(pad "43" smd rect
			(at -0.199898 -2.875026 270)
			(size 0.1778 0.6604)
			(layers "F.Cu" "F.Mask" "F.Paste")
			(net "PVCCIN_CPU1_ATSEN")
		)
		(pad "44" smd rect
			(at -0.599948 -2.875026 270)
			(size 0.1778 0.6604)
			(layers "F.Cu" "F.Mask" "F.Paste")
			(net "PVCCFA_EHV_FIVRA_CPU1_BTSEN")
		)
		(pad "45" smd rect
			(at -0.999998 -2.875026 270)
			(size 0.1778 0.6604)
			(layers "F.Cu" "F.Mask" "F.Paste")
			(net "PVCCIN_CPU1_CSPIN")
		)
		(pad "46" smd rect
			(at -1.400048 -2.875026 270)
			(size 0.1778 0.6604)
			(layers "F.Cu" "F.Mask" "F.Paste")
			(net "PVCCIN_CPU1_VIN_CSNIN")
		)
		(pad "47" smd rect
			(at -1.800098 -2.875026 270)
			(size 0.1778 0.6604)
			(layers "F.Cu" "F.Mask" "F.Paste")
			(net "PVCCIN_CPU1_VCC")
		)
		(pad "48" smd rect
			(at -2.199894 -2.875026 270)
			(size 0.1778 0.6604)
			(layers "F.Cu" "F.Mask" "F.Paste")
			(net "PVCCIN_CPU1_VREF")
		)
		(pad "TH" smd rect
			(at 0 0 270)
			(size 4.4196 4.4196)
			(layers "F.Cu" "F.Mask" "F.Paste")
			(net "GND")
		)
		(zone
			(layer "F.Cu")
			(hatch none 0.5)
			(connect_pads
				(clearance 0)
			)
			(min_thickness 0.25)
			(keepout
				(tracks not_allowed)
				(vias allowed)
				(pads allowed)
				(copperpour not_allowed)
				(footprints allowed)
			)
			(placement
				(enabled no)
				(sheetname "")
			)
			(fill
				(thermal_gap 0.5)
				(thermal_bridge_width 0.5)
				(island_removal_mode 0)
			)
			(polygon
				(pts
					(xy 106.368596 -361.337606) (xy 106.368596 -361.236006) (xy 106.368596 -361.134406) (xy 106.292396 -361.134406)
					(xy 106.292396 -356.562406) (xy 110.864396 -356.562406) (xy 110.864396 -361.134406) (xy 106.393996 -361.134406)
					(xy 106.393996 -361.236006) (xy 106.393996 -361.337606) (xy 111.042196 -361.337606) (xy 111.067596 -361.337606)
					(xy 111.067596 -356.359206) (xy 111.042196 -356.359206) (xy 106.089196 -356.359206) (xy 106.089196 -361.337606)
				)
			)
		)
	)
	(footprint ""
		(layer "F.Cu")
		(at 303.52873 -417.29914)
		(property "Reference" "R4575"
			(at 0 0 0)
			(layer "F.SilkS")
			(hide yes)
			(effects
				(font
					(size 1.27 1.27)
				)
			)
		)
		(property "Value" ""
			(at 0 0 0)
			(layer "F.Fab")
			(effects
				(font
					(size 1.27 1.27)
				)
			)
		)
		(duplicate_pad_numbers_are_jumpers no)
		(fp_line
			(start -0.7874 -0.4064)
			(end 0.7874 -0.4064)
			(stroke
				(width 0.1524)
				(type default)
			)
			(layer "F.SilkS")
		)
		(fp_line
			(start -0.7874 0.4064)
			(end -0.7874 -0.4064)
			(stroke
				(width 0.1524)
				(type default)
			)
			(layer "F.SilkS")
		)
		(fp_line
			(start 0.7874 -0.4064)
			(end 0.7874 0.4064)
			(stroke
				(width 0.1524)
				(type default)
			)
			(layer "F.SilkS")
		)
		(fp_line
			(start 0.7874 0.4064)
			(end -0.7874 0.4064)
			(stroke
				(width 0.1524)
				(type default)
			)
			(layer "F.SilkS")
		)
		(fp_line
			(start -0.67945 -0.305054)
			(end -0.12065 -0.305054)
			(stroke
				(width 0.1)
				(type default)
			)
			(layer "F.Fab")
		)
		(fp_line
			(start -0.67945 0.3048)
			(end -0.67945 -0.305054)
			(stroke
				(width 0.1)
				(type default)
			)
			(layer "F.Fab")
		)
		(fp_line
			(start -0.12065 -0.305054)
			(end -0.12065 -0.2794)
			(stroke
				(width 0.1)
				(type default)
			)
			(layer "F.Fab")
		)
		(fp_line
			(start -0.12065 -0.2794)
			(end 0.12065 -0.2794)
			(stroke
				(width 0.1)
				(type default)
			)
			(layer "F.Fab")
		)
		(fp_line
			(start -0.12065 0.2794)
			(end -0.12065 0.3048)
			(stroke
				(width 0.1)
				(type default)
			)
			(layer "F.Fab")
		)
		(fp_line
			(start -0.12065 0.3048)
			(end -0.67945 0.3048)
			(stroke
				(width 0.1)
				(type default)
			)
			(layer "F.Fab")
		)
		(fp_line
			(start 0.120396 0.2794)
			(end -0.12065 0.2794)
			(stroke
				(width 0.1)
				(type default)
			)
			(layer "F.Fab")
		)
		(fp_line
			(start 0.120396 0.3048)
			(end 0.120396 0.2794)
			(stroke
				(width 0.1)
				(type default)
			)
			(layer "F.Fab")
		)
		(fp_line
			(start 0.12065 -0.3048)
			(end 0.67945 -0.3048)
			(stroke
				(width 0.1)
				(type default)
			)
			(layer "F.Fab")
		)
		(fp_line
			(start 0.12065 -0.2794)
			(end 0.12065 -0.3048)
			(stroke
				(width 0.1)
				(type default)
			)
			(layer "F.Fab")
		)
		(fp_line
			(start 0.67945 -0.3048)
			(end 0.67945 0.3048)
			(stroke
				(width 0.1)
				(type default)
			)
			(layer "F.Fab")
		)
		(fp_line
			(start 0.67945 0.3048)
			(end 0.120396 0.3048)
			(stroke
				(width 0.1)
				(type default)
			)
			(layer "F.Fab")
		)
		(pad "1" smd circle
			(at -0.40005 0)
			(size 0 0)
			(layers "F.Cu" "F.Mask" "F.Paste")
			(net "GPU_3V3IO_RSVD0_FFU")
		)
		(pad "2" smd circle
			(at 0.40005 0)
			(size 0 0)
			(layers "F.Cu" "F.Mask" "F.Paste")
			(net "GPU_3V3IO_RSVD0_FFU_ISO")
		)
	)
	(footprint ""
		(layer "F.Cu")
		(at 350.691196 -61.506354)
		(property "Reference" "C1791"
			(at 0 0 0)
			(layer "F.SilkS")
			(hide yes)
			(effects
				(font
					(size 1.27 1.27)
				)
			)
		)
		(property "Value" ""
			(at 0 0 0)
			(layer "F.Fab")
			(effects
				(font
					(size 1.27 1.27)
				)
			)
		)
		(duplicate_pad_numbers_are_jumpers no)
		(fp_line
			(start -0.299974 -0.150114)
			(end 0.299974 -0.150114)
			(stroke
				(width 0.1)
				(type default)
			)
			(layer "F.Fab")
		)
		(fp_line
			(start -0.299974 0.150114)
			(end -0.299974 -0.150114)
			(stroke
				(width 0.1)
				(type default)
			)
			(layer "F.Fab")
		)
		(fp_line
			(start 0.299974 -0.150114)
			(end 0.299974 0.150114)
			(stroke
				(width 0.1)
				(type default)
			)
			(layer "F.Fab")
		)
		(fp_line
			(start 0.299974 0.150114)
			(end -0.299974 0.150114)
			(stroke
				(width 0.1)
				(type default)
			)
			(layer "F.Fab")
		)
		(pad "1" smd rect
			(at -0.2667 0)
			(size 0.3048 0.381)
			(layers "F.Cu" "F.Mask" "F.Paste")
			(net "DMI_CPU0_PCH_TX_C_DP<7>")
		)
		(pad "2" smd rect
			(at 0.2667 0)
			(size 0.3048 0.381)
			(layers "F.Cu" "F.Mask" "F.Paste")
			(net "DMI_CPU0_PCH_TX_DP<7>")
		)
		(zone
			(layer "In1.Cu")
			(hatch none 0.5)
			(connect_pads
				(clearance 0)
			)
			(min_thickness 0.25)
			(keepout
				(tracks not_allowed)
				(vias allowed)
				(pads allowed)
				(copperpour not_allowed)
				(footprints allowed)
			)
			(placement
				(enabled no)
				(sheetname "")
			)
			(fill
				(thermal_gap 0.5)
				(thermal_bridge_width 0.5)
				(island_removal_mode 0)
			)
			(polygon
				(pts
					(arc
						(start 350.297496 -61.265054)
						(mid 350.243614 -61.287372)
						(end 350.221296 -61.341254)
					)
					(arc
						(start 350.221296 -61.671454)
						(mid 350.243614 -61.725336)
						(end 350.297496 -61.747654)
					)
					(arc
						(start 350.551496 -61.747654)
						(mid 350.605378 -61.725336)
						(end 350.627696 -61.671454)
					)
					(arc
						(start 350.627696 -61.341254)
						(mid 350.605378 -61.287372)
						(end 350.551496 -61.265054)
					)
				)
			)
		)
		(zone
			(layer "In1.Cu")
			(hatch none 0.5)
			(connect_pads
				(clearance 0)
			)
			(min_thickness 0.25)
			(keepout
				(tracks not_allowed)
				(vias allowed)
				(pads allowed)
				(copperpour not_allowed)
				(footprints allowed)
			)
			(placement
				(enabled no)
				(sheetname "")
			)
			(fill
				(thermal_gap 0.5)
				(thermal_bridge_width 0.5)
				(island_removal_mode 0)
			)
			(polygon
				(pts
					(arc
						(start 350.830896 -61.265054)
						(mid 350.777014 -61.287372)
						(end 350.754696 -61.341254)
					)
					(arc
						(start 350.754696 -61.671454)
						(mid 350.777014 -61.725336)
						(end 350.830896 -61.747654)
					)
					(arc
						(start 351.084896 -61.747654)
						(mid 351.138778 -61.725336)
						(end 351.161096 -61.671454)
					)
					(arc
						(start 351.161096 -61.341254)
						(mid 351.138778 -61.287372)
						(end 351.084896 -61.265054)
					)
				)
			)
		)
	)
	(footprint ""
		(layer "F.Cu")
		(at 305.300888 -408.517344 -90)
		(property "Reference" "C902"
			(at 0 0 270)
			(layer "F.SilkS")
			(hide yes)
			(effects
				(font
					(size 1.27 1.27)
				)
			)
		)
		(property "Value" ""
			(at 0 0 270)
			(layer "F.Fab")
			(effects
				(font
					(size 1.27 1.27)
				)
			)
		)
		(duplicate_pad_numbers_are_jumpers no)
		(fp_line
			(start -0.299974 0.150114)
			(end -0.299974 -0.150114)
			(stroke
				(width 0.1)
				(type default)
			)
			(layer "F.Fab")
		)
		(fp_line
			(start 0.299974 0.150114)
			(end -0.299974 0.150114)
			(stroke
				(width 0.1)
				(type default)
			)
			(layer "F.Fab")
		)
		(fp_line
			(start -0.299974 -0.150114)
			(end 0.299974 -0.150114)
			(stroke
				(width 0.1)
				(type default)
			)
			(layer "F.Fab")
		)
		(fp_line
			(start 0.299974 -0.150114)
			(end 0.299974 0.150114)
			(stroke
				(width 0.1)
				(type default)
			)
			(layer "F.Fab")
		)
		(pad "1" smd rect
			(at -0.2667 0 270)
			(size 0.3048 0.381)
			(layers "F.Cu" "F.Mask" "F.Paste")
			(net "P5E_CPU0_PE0_TX_C_DN<15>")
		)
		(pad "2" smd rect
			(at 0.2667 0 270)
			(size 0.3048 0.381)
			(layers "F.Cu" "F.Mask" "F.Paste")
			(net "P5E_CPU0_PE0_TX_DN<15>")
		)
	)
	(footprint ""
		(layer "F.Cu")
		(at 424.204892 -387.314948 180)
		(property "Reference" "R2838"
			(at 0 0 180)
			(layer "F.SilkS")
			(hide yes)
			(effects
				(font
					(size 1.27 1.27)
				)
			)
		)
		(property "Value" ""
			(at 0 0 180)
			(layer "F.Fab")
			(effects
				(font
					(size 1.27 1.27)
				)
			)
		)
		(duplicate_pad_numbers_are_jumpers no)
		(fp_line
			(start 0.7874 0.4064)
			(end -0.7874 0.4064)
			(stroke
				(width 0.1524)
				(type default)
			)
			(layer "F.SilkS")
		)
		(fp_line
			(start 0.7874 -0.4064)
			(end 0.7874 0.4064)
			(stroke
				(width 0.1524)
				(type default)
			)
			(layer "F.SilkS")
		)
		(fp_line
			(start -0.7874 0.4064)
			(end -0.7874 -0.4064)
			(stroke
				(width 0.1524)
				(type default)
			)
			(layer "F.SilkS")
		)
		(fp_line
			(start -0.7874 -0.4064)
			(end 0.7874 -0.4064)
			(stroke
				(width 0.1524)
				(type default)
			)
			(layer "F.SilkS")
		)
		(fp_line
			(start 0.67945 0.3048)
			(end 0.120396 0.3048)
			(stroke
				(width 0.1)
				(type default)
			)
			(layer "F.Fab")
		)
		(fp_line
			(start 0.67945 -0.3048)
			(end 0.67945 0.3048)
			(stroke
				(width 0.1)
				(type default)
			)
			(layer "F.Fab")
		)
		(fp_line
			(start 0.12065 -0.2794)
			(end 0.12065 -0.3048)
			(stroke
				(width 0.1)
				(type default)
			)
			(layer "F.Fab")
		)
		(fp_line
			(start 0.12065 -0.3048)
			(end 0.67945 -0.3048)
			(stroke
				(width 0.1)
				(type default)
			)
			(layer "F.Fab")
		)
		(fp_line
			(start 0.120396 0.3048)
			(end 0.120396 0.2794)
			(stroke
				(width 0.1)
				(type default)
			)
			(layer "F.Fab")
		)
		(fp_line
			(start 0.120396 0.2794)
			(end -0.12065 0.2794)
			(stroke
				(width 0.1)
				(type default)
			)
			(layer "F.Fab")
		)
		(fp_line
			(start -0.12065 0.3048)
			(end -0.67945 0.3048)
			(stroke
				(width 0.1)
				(type default)
			)
			(layer "F.Fab")
		)
		(fp_line
			(start -0.12065 0.2794)
			(end -0.12065 0.3048)
			(stroke
				(width 0.1)
				(type default)
			)
			(layer "F.Fab")
		)
		(fp_line
			(start -0.12065 -0.2794)
			(end 0.12065 -0.2794)
			(stroke
				(width 0.1)
				(type default)
			)
			(layer "F.Fab")
		)
		(fp_line
			(start -0.12065 -0.305054)
			(end -0.12065 -0.2794)
			(stroke
				(width 0.1)
				(type default)
			)
			(layer "F.Fab")
		)
		(fp_line
			(start -0.67945 0.3048)
			(end -0.67945 -0.305054)
			(stroke
				(width 0.1)
				(type default)
			)
			(layer "F.Fab")
		)
		(fp_line
			(start -0.67945 -0.305054)
			(end -0.12065 -0.305054)
			(stroke
				(width 0.1)
				(type default)
			)
			(layer "F.Fab")
		)
		(pad "1" smd circle
			(at -0.40005 0 180)
			(size 0 0)
			(layers "F.Cu" "F.Mask" "F.Paste")
			(net "FM_SWB_PWRGD")
		)
		(pad "2" smd circle
			(at 0.40005 0 180)
			(size 0 0)
			(layers "F.Cu" "F.Mask" "F.Paste")
			(net "GND")
		)
	)
	(footprint ""
		(layer "F.Cu")
		(at 299.02023 -56.432196 180)
		(property "Reference" "R2980"
			(at 0 0 180)
			(layer "F.SilkS")
			(hide yes)
			(effects
				(font
					(size 1.27 1.27)
				)
			)
		)
		(property "Value" ""
			(at 0 0 180)
			(layer "F.Fab")
			(effects
				(font
					(size 1.27 1.27)
				)
			)
		)
		(duplicate_pad_numbers_are_jumpers no)
		(fp_line
			(start 0.7874 0.4064)
			(end -0.7874 0.4064)
			(stroke
				(width 0.1524)
				(type default)
			)
			(layer "F.SilkS")
		)
		(fp_line
			(start 0.7874 -0.4064)
			(end 0.7874 0.4064)
			(stroke
				(width 0.1524)
				(type default)
			)
			(layer "F.SilkS")
		)
		(fp_line
			(start -0.7874 0.4064)
			(end -0.7874 -0.4064)
			(stroke
				(width 0.1524)
				(type default)
			)
			(layer "F.SilkS")
		)
		(fp_line
			(start -0.7874 -0.4064)
			(end 0.7874 -0.4064)
			(stroke
				(width 0.1524)
				(type default)
			)
			(layer "F.SilkS")
		)
		(fp_line
			(start 0.67945 0.3048)
			(end 0.120396 0.3048)
			(stroke
				(width 0.1)
				(type default)
			)
			(layer "F.Fab")
		)
		(fp_line
			(start 0.67945 -0.3048)
			(end 0.67945 0.3048)
			(stroke
				(width 0.1)
				(type default)
			)
			(layer "F.Fab")
		)
		(fp_line
			(start 0.12065 -0.2794)
			(end 0.12065 -0.3048)
			(stroke
				(width 0.1)
				(type default)
			)
			(layer "F.Fab")
		)
		(fp_line
			(start 0.12065 -0.3048)
			(end 0.67945 -0.3048)
			(stroke
				(width 0.1)
				(type default)
			)
			(layer "F.Fab")
		)
		(fp_line
			(start 0.120396 0.3048)
			(end 0.120396 0.2794)
			(stroke
				(width 0.1)
				(type default)
			)
			(layer "F.Fab")
		)
		(fp_line
			(start 0.120396 0.2794)
			(end -0.12065 0.2794)
			(stroke
				(width 0.1)
				(type default)
			)
			(layer "F.Fab")
		)
		(fp_line
			(start -0.12065 0.3048)
			(end -0.67945 0.3048)
			(stroke
				(width 0.1)
				(type default)
			)
			(layer "F.Fab")
		)
		(fp_line
			(start -0.12065 0.2794)
			(end -0.12065 0.3048)
			(stroke
				(width 0.1)
				(type default)
			)
			(layer "F.Fab")
		)
		(fp_line
			(start -0.12065 -0.2794)
			(end 0.12065 -0.2794)
			(stroke
				(width 0.1)
				(type default)
			)
			(layer "F.Fab")
		)
		(fp_line
			(start -0.12065 -0.305054)
			(end -0.12065 -0.2794)
			(stroke
				(width 0.1)
				(type default)
			)
			(layer "F.Fab")
		)
		(fp_line
			(start -0.67945 0.3048)
			(end -0.67945 -0.305054)
			(stroke
				(width 0.1)
				(type default)
			)
			(layer "F.Fab")
		)
		(fp_line
			(start -0.67945 -0.305054)
			(end -0.12065 -0.305054)
			(stroke
				(width 0.1)
				(type default)
			)
			(layer "F.Fab")
		)
		(pad "1" smd circle
			(at -0.40005 0 180)
			(size 0 0)
			(layers "F.Cu" "F.Mask" "F.Paste")
			(net "FM_BOARD_SKU_ID2")
		)
		(pad "2" smd circle
			(at 0.40005 0 180)
			(size 0 0)
			(layers "F.Cu" "F.Mask" "F.Paste")
			(net "GND")
		)
	)
	(footprint ""
		(layer "F.Cu")
		(at 295.25595 -417.2204)
		(property "Reference" "R4574"
			(at 0 0 0)
			(layer "F.SilkS")
			(hide yes)
			(effects
				(font
					(size 1.27 1.27)
				)
			)
		)
		(property "Value" ""
			(at 0 0 0)
			(layer "F.Fab")
			(effects
				(font
					(size 1.27 1.27)
				)
			)
		)
		(duplicate_pad_numbers_are_jumpers no)
		(fp_line
			(start -0.7874 -0.4064)
			(end 0.7874 -0.4064)
			(stroke
				(width 0.1524)
				(type default)
			)
			(layer "F.SilkS")
		)
		(fp_line
			(start -0.7874 0.4064)
			(end -0.7874 -0.4064)
			(stroke
				(width 0.1524)
				(type default)
			)
			(layer "F.SilkS")
		)
		(fp_line
			(start 0.7874 -0.4064)
			(end 0.7874 0.4064)
			(stroke
				(width 0.1524)
				(type default)
			)
			(layer "F.SilkS")
		)
		(fp_line
			(start 0.7874 0.4064)
			(end -0.7874 0.4064)
			(stroke
				(width 0.1524)
				(type default)
			)
			(layer "F.SilkS")
		)
		(fp_line
			(start -0.67945 -0.305054)
			(end -0.12065 -0.305054)
			(stroke
				(width 0.1)
				(type default)
			)
			(layer "F.Fab")
		)
		(fp_line
			(start -0.67945 0.3048)
			(end -0.67945 -0.305054)
			(stroke
				(width 0.1)
				(type default)
			)
			(layer "F.Fab")
		)
		(fp_line
			(start -0.12065 -0.305054)
			(end -0.12065 -0.2794)
			(stroke
				(width 0.1)
				(type default)
			)
			(layer "F.Fab")
		)
		(fp_line
			(start -0.12065 -0.2794)
			(end 0.12065 -0.2794)
			(stroke
				(width 0.1)
				(type default)
			)
			(layer "F.Fab")
		)
		(fp_line
			(start -0.12065 0.2794)
			(end -0.12065 0.3048)
			(stroke
				(width 0.1)
				(type default)
			)
			(layer "F.Fab")
		)
		(fp_line
			(start -0.12065 0.3048)
			(end -0.67945 0.3048)
			(stroke
				(width 0.1)
				(type default)
			)
			(layer "F.Fab")
		)
		(fp_line
			(start 0.120396 0.2794)
			(end -0.12065 0.2794)
			(stroke
				(width 0.1)
				(type default)
			)
			(layer "F.Fab")
		)
		(fp_line
			(start 0.120396 0.3048)
			(end 0.120396 0.2794)
			(stroke
				(width 0.1)
				(type default)
			)
			(layer "F.Fab")
		)
		(fp_line
			(start 0.12065 -0.3048)
			(end 0.67945 -0.3048)
			(stroke
				(width 0.1)
				(type default)
			)
			(layer "F.Fab")
		)
		(fp_line
			(start 0.12065 -0.2794)
			(end 0.12065 -0.3048)
			(stroke
				(width 0.1)
				(type default)
			)
			(layer "F.Fab")
		)
		(fp_line
			(start 0.67945 -0.3048)
			(end 0.67945 0.3048)
			(stroke
				(width 0.1)
				(type default)
			)
			(layer "F.Fab")
		)
		(fp_line
			(start 0.67945 0.3048)
			(end 0.120396 0.3048)
			(stroke
				(width 0.1)
				(type default)
			)
			(layer "F.Fab")
		)
		(pad "1" smd circle
			(at -0.40005 0)
			(size 0 0)
			(layers "F.Cu" "F.Mask" "F.Paste")
			(net "PRSNT_CABLE_GPU_A1_N")
		)
		(pad "2" smd circle
			(at 0.40005 0)
			(size 0 0)
			(layers "F.Cu" "F.Mask" "F.Paste")
			(net "PRSNT_CABLE_GPU_A1_ISO_N")
		)
	)
	(footprint ""
		(layer "F.Cu")
		(at 127.804926 -119.810784 90)
		(property "Reference" "R4054"
			(at 0 0 90)
			(layer "F.SilkS")
			(hide yes)
			(effects
				(font
					(size 1.27 1.27)
				)
			)
		)
		(property "Value" ""
			(at 0 0 90)
			(layer "F.Fab")
			(effects
				(font
					(size 1.27 1.27)
				)
			)
		)
		(duplicate_pad_numbers_are_jumpers no)
		(fp_line
			(start 0.7874 -0.4064)
			(end 0.7874 0.4064)
			(stroke
				(width 0.1524)
				(type default)
			)
			(layer "F.SilkS")
		)
		(fp_line
			(start -0.7874 -0.4064)
			(end 0.7874 -0.4064)
			(stroke
				(width 0.1524)
				(type default)
			)
			(layer "F.SilkS")
		)
		(fp_line
			(start 0.7874 0.4064)
			(end -0.7874 0.4064)
			(stroke
				(width 0.1524)
				(type default)
			)
			(layer "F.SilkS")
		)
		(fp_line
			(start -0.7874 0.4064)
			(end -0.7874 -0.4064)
			(stroke
				(width 0.1524)
				(type default)
			)
			(layer "F.SilkS")
		)
		(fp_line
			(start -0.12065 -0.305054)
			(end -0.12065 -0.2794)
			(stroke
				(width 0.1)
				(type default)
			)
			(layer "F.Fab")
		)
		(fp_line
			(start -0.67945 -0.305054)
			(end -0.12065 -0.305054)
			(stroke
				(width 0.1)
				(type default)
			)
			(layer "F.Fab")
		)
		(fp_line
			(start 0.67945 -0.3048)
			(end 0.67945 0.3048)
			(stroke
				(width 0.1)
				(type default)
			)
			(layer "F.Fab")
		)
		(fp_line
			(start 0.12065 -0.3048)
			(end 0.67945 -0.3048)
			(stroke
				(width 0.1)
				(type default)
			)
			(layer "F.Fab")
		)
		(fp_line
			(start 0.12065 -0.2794)
			(end 0.12065 -0.3048)
			(stroke
				(width 0.1)
				(type default)
			)
			(layer "F.Fab")
		)
		(fp_line
			(start -0.12065 -0.2794)
			(end 0.12065 -0.2794)
			(stroke
				(width 0.1)
				(type default)
			)
			(layer "F.Fab")
		)
		(fp_line
			(start 0.120396 0.2794)
			(end -0.12065 0.2794)
			(stroke
				(width 0.1)
				(type default)
			)
			(layer "F.Fab")
		)
		(fp_line
			(start -0.12065 0.2794)
			(end -0.12065 0.3048)
			(stroke
				(width 0.1)
				(type default)
			)
			(layer "F.Fab")
		)
		(fp_line
			(start 0.67945 0.3048)
			(end 0.120396 0.3048)
			(stroke
				(width 0.1)
				(type default)
			)
			(layer "F.Fab")
		)
		(fp_line
			(start 0.120396 0.3048)
			(end 0.120396 0.2794)
			(stroke
				(width 0.1)
				(type default)
			)
			(layer "F.Fab")
		)
		(fp_line
			(start -0.12065 0.3048)
			(end -0.67945 0.3048)
			(stroke
				(width 0.1)
				(type default)
			)
			(layer "F.Fab")
		)
		(fp_line
			(start -0.67945 0.3048)
			(end -0.67945 -0.305054)
			(stroke
				(width 0.1)
				(type default)
			)
			(layer "F.Fab")
		)
		(pad "1" smd circle
			(at -0.40005 0 90)
			(size 0 0)
			(layers "F.Cu" "F.Mask" "F.Paste")
			(net "PD_GTL2014_BMC_JTAG_DIR_1")
		)
		(pad "2" smd circle
			(at 0.40005 0 90)
			(size 0 0)
			(layers "F.Cu" "F.Mask" "F.Paste")
			(net "GND")
		)
	)
	(footprint ""
		(layer "F.Cu")
		(at 54.811168 -168.683178)
		(property "Reference" "PC375"
			(at 0 0 0)
			(layer "F.SilkS")
			(hide yes)
			(effects
				(font
					(size 1.27 1.27)
				)
			)
		)
		(property "Value" ""
			(at 0 0 0)
			(layer "F.Fab")
			(effects
				(font
					(size 1.27 1.27)
				)
			)
		)
		(duplicate_pad_numbers_are_jumpers no)
		(fp_line
			(start -0.7874 -0.4064)
			(end 0.7874 -0.4064)
			(stroke
				(width 0.1524)
				(type default)
			)
			(layer "F.SilkS")
		)
		(fp_line
			(start -0.7874 0.4064)
			(end -0.7874 -0.4064)
			(stroke
				(width 0.1524)
				(type default)
			)
			(layer "F.SilkS")
		)
		(fp_line
			(start 0.7874 -0.4064)
			(end 0.7874 0.4064)
			(stroke
				(width 0.1524)
				(type default)
			)
			(layer "F.SilkS")
		)
		(fp_line
			(start 0.7874 0.4064)
			(end -0.7874 0.4064)
			(stroke
				(width 0.1524)
				(type default)
			)
			(layer "F.SilkS")
		)
		(fp_line
			(start -0.67945 -0.305054)
			(end -0.12065 -0.305054)
			(stroke
				(width 0.1)
				(type default)
			)
			(layer "F.Fab")
		)
		(fp_line
			(start -0.67945 0.3048)
			(end -0.67945 -0.305054)
			(stroke
				(width 0.1)
				(type default)
			)
			(layer "F.Fab")
		)
		(fp_line
			(start -0.12065 -0.305054)
			(end -0.12065 -0.2794)
			(stroke
				(width 0.1)
				(type default)
			)
			(layer "F.Fab")
		)
		(fp_line
			(start -0.12065 -0.2794)
			(end 0.12065 -0.2794)
			(stroke
				(width 0.1)
				(type default)
			)
			(layer "F.Fab")
		)
		(fp_line
			(start -0.12065 0.2794)
			(end -0.12065 0.3048)
			(stroke
				(width 0.1)
				(type default)
			)
			(layer "F.Fab")
		)
		(fp_line
			(start -0.12065 0.3048)
			(end -0.67945 0.3048)
			(stroke
				(width 0.1)
				(type default)
			)
			(layer "F.Fab")
		)
		(fp_line
			(start 0.120396 0.2794)
			(end -0.12065 0.2794)
			(stroke
				(width 0.1)
				(type default)
			)
			(layer "F.Fab")
		)
		(fp_line
			(start 0.120396 0.3048)
			(end 0.120396 0.2794)
			(stroke
				(width 0.1)
				(type default)
			)
			(layer "F.Fab")
		)
		(fp_line
			(start 0.12065 -0.3048)
			(end 0.67945 -0.3048)
			(stroke
				(width 0.1)
				(type default)
			)
			(layer "F.Fab")
		)
		(fp_line
			(start 0.12065 -0.2794)
			(end 0.12065 -0.3048)
			(stroke
				(width 0.1)
				(type default)
			)
			(layer "F.Fab")
		)
		(fp_line
			(start 0.67945 -0.3048)
			(end 0.67945 0.3048)
			(stroke
				(width 0.1)
				(type default)
			)
			(layer "F.Fab")
		)
		(fp_line
			(start 0.67945 0.3048)
			(end 0.120396 0.3048)
			(stroke
				(width 0.1)
				(type default)
			)
			(layer "F.Fab")
		)
		(pad "1" smd circle
			(at -0.40005 0)
			(size 0 0)
			(layers "F.Cu" "F.Mask" "F.Paste")
			(net "SW_P12V_PVCCINFAON_CPU1_FLT")
		)
		(pad "2" smd circle
			(at 0.40005 0)
			(size 0 0)
			(layers "F.Cu" "F.Mask" "F.Paste")
			(net "GND")
		)
	)
	(footprint ""
		(layer "F.Cu")
		(at 136.519158 -354.434902)
		(property "Reference" "H49"
			(at -2.63906 -5.052568 0)
			(unlocked yes)
			(layer "F.SilkS")
			(effects
				(font
					(size 0.7874 0.5842)
					(thickness 0.1524)
				)
				(justify left)
			)
		)
		(property "Value" ""
			(at 0 0 0)
			(layer "F.Fab")
			(effects
				(font
					(size 1.27 1.27)
				)
			)
		)
		(duplicate_pad_numbers_are_jumpers no)
		(pad "1" thru_hole circle
			(at 0 0)
			(size 8.001 8.001)
			(drill 3.2004)
			(layers "*.Cu" "*.Mask")
			(remove_unused_layers no)
			(net "GND")
			(clearance -2.1463)
			(padstack
				(mode front_inner_back)
				(layer "Inner"
					(shape circle)
					(size 5.0038 5.0038)
					(clearance -0.6477)
				)
				(layer "B.Cu"
					(shape circle)
					(size 8.001 8.001)
					(clearance -2.1463)
				)
			)
		)
	)
	(footprint ""
		(layer "F.Cu")
		(at 20.60956 -77.028548)
		(property "Reference" "R3133"
			(at 0 0 0)
			(layer "F.SilkS")
			(hide yes)
			(effects
				(font
					(size 1.27 1.27)
				)
			)
		)
		(property "Value" ""
			(at 0 0 0)
			(layer "F.Fab")
			(effects
				(font
					(size 1.27 1.27)
				)
			)
		)
		(duplicate_pad_numbers_are_jumpers no)
		(fp_line
			(start -0.7874 -0.4064)
			(end 0.7874 -0.4064)
			(stroke
				(width 0.1524)
				(type default)
			)
			(layer "F.SilkS")
		)
		(fp_line
			(start -0.7874 0.4064)
			(end -0.7874 -0.4064)
			(stroke
				(width 0.1524)
				(type default)
			)
			(layer "F.SilkS")
		)
		(fp_line
			(start 0.7874 -0.4064)
			(end 0.7874 0.4064)
			(stroke
				(width 0.1524)
				(type default)
			)
			(layer "F.SilkS")
		)
		(fp_line
			(start 0.7874 0.4064)
			(end -0.7874 0.4064)
			(stroke
				(width 0.1524)
				(type default)
			)
			(layer "F.SilkS")
		)
		(fp_line
			(start -0.67945 -0.305054)
			(end -0.12065 -0.305054)
			(stroke
				(width 0.1)
				(type default)
			)
			(layer "F.Fab")
		)
		(fp_line
			(start -0.67945 0.3048)
			(end -0.67945 -0.305054)
			(stroke
				(width 0.1)
				(type default)
			)
			(layer "F.Fab")
		)
		(fp_line
			(start -0.12065 -0.305054)
			(end -0.12065 -0.2794)
			(stroke
				(width 0.1)
				(type default)
			)
			(layer "F.Fab")
		)
		(fp_line
			(start -0.12065 -0.2794)
			(end 0.12065 -0.2794)
			(stroke
				(width 0.1)
				(type default)
			)
			(layer "F.Fab")
		)
		(fp_line
			(start -0.12065 0.2794)
			(end -0.12065 0.3048)
			(stroke
				(width 0.1)
				(type default)
			)
			(layer "F.Fab")
		)
		(fp_line
			(start -0.12065 0.3048)
			(end -0.67945 0.3048)
			(stroke
				(width 0.1)
				(type default)
			)
			(layer "F.Fab")
		)
		(fp_line
			(start 0.120396 0.2794)
			(end -0.12065 0.2794)
			(stroke
				(width 0.1)
				(type default)
			)
			(layer "F.Fab")
		)
		(fp_line
			(start 0.120396 0.3048)
			(end 0.120396 0.2794)
			(stroke
				(width 0.1)
				(type default)
			)
			(layer "F.Fab")
		)
		(fp_line
			(start 0.12065 -0.3048)
			(end 0.67945 -0.3048)
			(stroke
				(width 0.1)
				(type default)
			)
			(layer "F.Fab")
		)
		(fp_line
			(start 0.12065 -0.2794)
			(end 0.12065 -0.3048)
			(stroke
				(width 0.1)
				(type default)
			)
			(layer "F.Fab")
		)
		(fp_line
			(start 0.67945 -0.3048)
			(end 0.67945 0.3048)
			(stroke
				(width 0.1)
				(type default)
			)
			(layer "F.Fab")
		)
		(fp_line
			(start 0.67945 0.3048)
			(end 0.120396 0.3048)
			(stroke
				(width 0.1)
				(type default)
			)
			(layer "F.Fab")
		)
		(pad "1" smd circle
			(at -0.40005 0)
			(size 0 0)
			(layers "F.Cu" "F.Mask" "F.Paste")
			(net "P3V3_AUX")
		)
		(pad "2" smd circle
			(at 0.40005 0)
			(size 0 0)
			(layers "F.Cu" "F.Mask" "F.Paste")
			(net "OCP_V3_2_PRSNT0_R_N")
		)
	)
	(footprint ""
		(layer "F.Cu")
		(at 268.833092 -407.416 -90)
		(property "Reference" "PR2532"
			(at 0 0 270)
			(layer "F.SilkS")
			(hide yes)
			(effects
				(font
					(size 1.27 1.27)
				)
			)
		)
		(property "Value" ""
			(at 0 0 270)
			(layer "F.Fab")
			(effects
				(font
					(size 1.27 1.27)
				)
			)
		)
		(duplicate_pad_numbers_are_jumpers no)
		(fp_line
			(start -3.9878 3.5814)
			(end -3.9878 -3.5814)
			(stroke
				(width 0.1524)
				(type default)
			)
			(layer "F.SilkS")
		)
		(fp_line
			(start 3.9878 3.5814)
			(end -3.9878 3.5814)
			(stroke
				(width 0.1524)
				(type default)
			)
			(layer "F.SilkS")
		)
		(fp_line
			(start -3.9878 -3.5814)
			(end 3.9878 -3.5814)
			(stroke
				(width 0.1524)
				(type default)
			)
			(layer "F.SilkS")
		)
		(fp_line
			(start 3.9878 -3.5814)
			(end 3.9878 3.5814)
			(stroke
				(width 0.1524)
				(type default)
			)
			(layer "F.SilkS")
		)
		(fp_line
			(start -3.5306 3.353054)
			(end -3.5306 -3.353054)
			(stroke
				(width 0.1)
				(type default)
			)
			(layer "F.Fab")
		)
		(fp_line
			(start 3.5306 3.353054)
			(end -3.5306 3.353054)
			(stroke
				(width 0.1)
				(type default)
			)
			(layer "F.Fab")
		)
		(fp_line
			(start -3.5306 -3.353054)
			(end 3.5306 -3.353054)
			(stroke
				(width 0.1)
				(type default)
			)
			(layer "F.Fab")
		)
		(fp_line
			(start 3.5306 -3.353054)
			(end 3.5306 3.353054)
			(stroke
				(width 0.1)
				(type default)
			)
			(layer "F.Fab")
		)
		(pad "1A" smd rect
			(at -2.249932 0 90)
			(size 3.2004 6.858)
			(layers "F.Cu" "F.Mask" "F.Paste")
			(net "P12V_PSU")
		)
		(pad "1B" smd rect
			(at -0.776732 0 270)
			(size 0.254 0.508)
			(layers "F.Cu" "F.Mask" "F.Paste")
			(net "P12V_HSC_SENSE2_R2_P")
		)
		(pad "2A" smd rect
			(at 2.249932 0 90)
			(size 3.2004 6.858)
			(layers "F.Cu" "F.Mask" "F.Paste")
			(net "P12V_MAIN_R")
		)
		(pad "2B" smd rect
			(at 0.776732 0 270)
			(size 0.254 0.508)
			(layers "F.Cu" "F.Mask" "F.Paste")
			(net "P12V_HSC_SENSE2_R2_N")
		)
	)
	(footprint ""
		(layer "F.Cu")
		(at 13.800582 -408.516836 -90)
		(property "Reference" "R2694"
			(at 0 0 270)
			(layer "F.SilkS")
			(hide yes)
			(effects
				(font
					(size 1.27 1.27)
				)
			)
		)
		(property "Value" ""
			(at 0 0 270)
			(layer "F.Fab")
			(effects
				(font
					(size 1.27 1.27)
				)
			)
		)
		(duplicate_pad_numbers_are_jumpers no)
		(fp_line
			(start -0.7874 0.4064)
			(end -0.7874 -0.4064)
			(stroke
				(width 0.1524)
				(type default)
			)
			(layer "F.SilkS")
		)
		(fp_line
			(start 0.7874 0.4064)
			(end -0.7874 0.4064)
			(stroke
				(width 0.1524)
				(type default)
			)
			(layer "F.SilkS")
		)
		(fp_line
			(start -0.7874 -0.4064)
			(end 0.7874 -0.4064)
			(stroke
				(width 0.1524)
				(type default)
			)
			(layer "F.SilkS")
		)
		(fp_line
			(start 0.7874 -0.4064)
			(end 0.7874 0.4064)
			(stroke
				(width 0.1524)
				(type default)
			)
			(layer "F.SilkS")
		)
		(fp_line
			(start -0.67945 0.3048)
			(end -0.67945 -0.305054)
			(stroke
				(width 0.1)
				(type default)
			)
			(layer "F.Fab")
		)
		(fp_line
			(start -0.12065 0.3048)
			(end -0.67945 0.3048)
			(stroke
				(width 0.1)
				(type default)
			)
			(layer "F.Fab")
		)
		(fp_line
			(start 0.120396 0.3048)
			(end 0.120396 0.2794)
			(stroke
				(width 0.1)
				(type default)
			)
			(layer "F.Fab")
		)
		(fp_line
			(start 0.67945 0.3048)
			(end 0.120396 0.3048)
			(stroke
				(width 0.1)
				(type default)
			)
			(layer "F.Fab")
		)
		(fp_line
			(start -0.12065 0.2794)
			(end -0.12065 0.3048)
			(stroke
				(width 0.1)
				(type default)
			)
			(layer "F.Fab")
		)
		(fp_line
			(start 0.120396 0.2794)
			(end -0.12065 0.2794)
			(stroke
				(width 0.1)
				(type default)
			)
			(layer "F.Fab")
		)
		(fp_line
			(start -0.12065 -0.2794)
			(end 0.12065 -0.2794)
			(stroke
				(width 0.1)
				(type default)
			)
			(layer "F.Fab")
		)
		(fp_line
			(start 0.12065 -0.2794)
			(end 0.12065 -0.3048)
			(stroke
				(width 0.1)
				(type default)
			)
			(layer "F.Fab")
		)
		(fp_line
			(start 0.12065 -0.3048)
			(end 0.67945 -0.3048)
			(stroke
				(width 0.1)
				(type default)
			)
			(layer "F.Fab")
		)
		(fp_line
			(start 0.67945 -0.3048)
			(end 0.67945 0.3048)
			(stroke
				(width 0.1)
				(type default)
			)
			(layer "F.Fab")
		)
		(fp_line
			(start -0.67945 -0.305054)
			(end -0.12065 -0.305054)
			(stroke
				(width 0.1)
				(type default)
			)
			(layer "F.Fab")
		)
		(fp_line
			(start -0.12065 -0.305054)
			(end -0.12065 -0.2794)
			(stroke
				(width 0.1)
				(type default)
			)
			(layer "F.Fab")
		)
		(pad "1" smd circle
			(at -0.40005 0 270)
			(size 0 0)
			(layers "F.Cu" "F.Mask" "F.Paste")
			(net "TCA9539_0_ADD1")
		)
		(pad "2" smd circle
			(at 0.40005 0 270)
			(size 0 0)
			(layers "F.Cu" "F.Mask" "F.Paste")
			(net "GND")
		)
	)
	(footprint ""
		(layer "F.Cu")
		(at 85.576156 -95.992442)
		(property "Reference" "Q85"
			(at -5.17652 -0.638048 0)
			(unlocked yes)
			(layer "F.SilkS")
			(effects
				(font
					(size 0.7874 0.5842)
					(thickness 0.1524)
				)
				(justify left)
			)
		)
		(property "Value" ""
			(at 0 0 0)
			(layer "F.Fab")
			(effects
				(font
					(size 1.27 1.27)
				)
			)
		)
		(duplicate_pad_numbers_are_jumpers no)
		(fp_line
			(start -1.332738 -1.100074)
			(end -0.4826 -1.100074)
			(stroke
				(width 0.1524)
				(type default)
			)
			(layer "F.SilkS")
		)
		(fp_line
			(start -1.332738 1.100074)
			(end -1.332738 -1.100074)
			(stroke
				(width 0.1524)
				(type default)
			)
			(layer "F.SilkS")
		)
		(fp_line
			(start -0.4826 -1.100074)
			(end 0 -0.541274)
			(stroke
				(width 0.1524)
				(type default)
			)
			(layer "F.SilkS")
		)
		(fp_line
			(start 0 -0.541274)
			(end 0.4826 -1.100074)
			(stroke
				(width 0.1524)
				(type default)
			)
			(layer "F.SilkS")
		)
		(fp_line
			(start 0.4826 -1.100074)
			(end 1.332738 -1.100074)
			(stroke
				(width 0.1524)
				(type default)
			)
			(layer "F.SilkS")
		)
		(fp_line
			(start 1.332738 -1.100074)
			(end 1.332738 1.100074)
			(stroke
				(width 0.1524)
				(type default)
			)
			(layer "F.SilkS")
		)
		(fp_line
			(start 1.332738 1.100074)
			(end -1.332738 1.100074)
			(stroke
				(width 0.1524)
				(type default)
			)
			(layer "F.SilkS")
		)
		(fp_poly
			(pts
				(xy -2.2352 -1.001014) (xy -1.533144 -0.649986) (xy -2.2352 -0.298958)
			)
			(stroke
				(width 0)
				(type default)
			)
			(fill yes)
			(layer "F.SilkS")
		)
		(fp_line
			(start -0.674878 -1.100074)
			(end 0.674878 -1.100074)
			(stroke
				(width 0.1)
				(type default)
			)
			(layer "F.Fab")
		)
		(fp_line
			(start -0.674878 1.100074)
			(end -0.674878 -1.100074)
			(stroke
				(width 0.1)
				(type default)
			)
			(layer "F.Fab")
		)
		(fp_line
			(start 0.674878 -1.100074)
			(end 0.674878 1.100074)
			(stroke
				(width 0.1)
				(type default)
			)
			(layer "F.Fab")
		)
		(fp_line
			(start 0.674878 1.100074)
			(end -0.674878 1.100074)
			(stroke
				(width 0.1)
				(type default)
			)
			(layer "F.Fab")
		)
		(fp_poly
			(pts
				(xy -2.2352 -0.298958) (xy -2.2352 -1.001014) (xy -1.533144 -0.649986)
			)
			(stroke
				(width 0)
				(type default)
			)
			(fill yes)
			(layer "F.Fab")
		)
		(pad "1" smd rect
			(at -0.94996 -0.649986 90)
			(size 0.4318 0.508)
			(layers "F.Cu" "F.Mask" "F.Paste")
			(net "GND")
		)
		(pad "2" smd rect
			(at -0.94996 0 90)
			(size 0.4318 0.508)
			(layers "F.Cu" "F.Mask" "F.Paste")
			(net "PWRGD_PVCCFA_EHV_CPU1")
		)
		(pad "3" smd rect
			(at -0.94996 0.649986 90)
			(size 0.4318 0.508)
			(layers "F.Cu" "F.Mask" "F.Paste")
			(net "LED_PWRGD_PVCCFA_EHV_FIVRA_CP_2")
		)
		(pad "4" smd rect
			(at 0.94996 0.649986 90)
			(size 0.4318 0.508)
			(layers "F.Cu" "F.Mask" "F.Paste")
			(net "GND")
		)
		(pad "5" smd rect
			(at 0.94996 0 90)
			(size 0.4318 0.508)
			(layers "F.Cu" "F.Mask" "F.Paste")
			(net "PWRGD_PVCCFA_EHV_FIVRA_CPU1")
		)
		(pad "6" smd rect
			(at 0.94996 -0.649986 90)
			(size 0.4318 0.508)
			(layers "F.Cu" "F.Mask" "F.Paste")
			(net "LED_PWRGD_PVCCFA_EHV_CPU1_D")
		)
	)
	(footprint ""
		(layer "F.Cu")
		(at 294.95242 -424.00601 90)
		(property "Reference" "Q134"
			(at -7.737602 10.748772 90)
			(unlocked yes)
			(layer "F.SilkS")
			(effects
				(font
					(size 0.7874 0.5842)
					(thickness 0.1524)
				)
				(justify left)
			)
		)
		(property "Value" ""
			(at 0 0 90)
			(layer "F.Fab")
			(effects
				(font
					(size 1.27 1.27)
				)
			)
		)
		(duplicate_pad_numbers_are_jumpers no)
		(fp_line
			(start 1.332738 -1.100074)
			(end 1.332738 1.100074)
			(stroke
				(width 0.1524)
				(type default)
			)
			(layer "F.SilkS")
		)
		(fp_line
			(start 0.4826 -1.100074)
			(end 1.332738 -1.100074)
			(stroke
				(width 0.1524)
				(type default)
			)
			(layer "F.SilkS")
		)
		(fp_line
			(start -0.4826 -1.100074)
			(end 0 -0.541274)
			(stroke
				(width 0.1524)
				(type default)
			)
			(layer "F.SilkS")
		)
		(fp_line
			(start -1.332738 -1.100074)
			(end -0.4826 -1.100074)
			(stroke
				(width 0.1524)
				(type default)
			)
			(layer "F.SilkS")
		)
		(fp_line
			(start 0 -0.541274)
			(end 0.4826 -1.100074)
			(stroke
				(width 0.1524)
				(type default)
			)
			(layer "F.SilkS")
		)
		(fp_line
			(start 1.332738 1.100074)
			(end -1.332738 1.100074)
			(stroke
				(width 0.1524)
				(type default)
			)
			(layer "F.SilkS")
		)
		(fp_line
			(start -1.332738 1.100074)
			(end -1.332738 -1.100074)
			(stroke
				(width 0.1524)
				(type default)
			)
			(layer "F.SilkS")
		)
		(fp_poly
			(pts
				(xy -1.760728 -1.63322) (xy -1.51257 -0.888746) (xy -2.257044 -1.136904)
			)
			(stroke
				(width 0)
				(type default)
			)
			(fill yes)
			(layer "F.SilkS")
		)
		(fp_line
			(start 0.674878 -1.100074)
			(end 0.674878 1.100074)
			(stroke
				(width 0.1)
				(type default)
			)
			(layer "F.Fab")
		)
		(fp_line
			(start -0.674878 -1.100074)
			(end 0.674878 -1.100074)
			(stroke
				(width 0.1)
				(type default)
			)
			(layer "F.Fab")
		)
		(fp_line
			(start 0.674878 1.100074)
			(end -0.674878 1.100074)
			(stroke
				(width 0.1)
				(type default)
			)
			(layer "F.Fab")
		)
		(fp_line
			(start -0.674878 1.100074)
			(end -0.674878 -1.100074)
			(stroke
				(width 0.1)
				(type default)
			)
			(layer "F.Fab")
		)
		(fp_poly
			(pts
				(xy -2.2352 -0.298958) (xy -2.2352 -1.001014) (xy -1.533144 -0.649986)
			)
			(stroke
				(width 0)
				(type default)
			)
			(fill yes)
			(layer "F.Fab")
		)
		(pad "1" smd rect
			(at -0.94996 -0.649986 180)
			(size 0.4318 0.508)
			(layers "F.Cu" "F.Mask" "F.Paste")
			(net "GND")
		)
		(pad "2" smd rect
			(at -0.94996 0 180)
			(size 0.4318 0.508)
			(layers "F.Cu" "F.Mask" "F.Paste")
			(net "PRSNT_CABLE_GPU_A1_N")
		)
		(pad "3" smd rect
			(at -0.94996 0.649986 180)
			(size 0.4318 0.508)
			(layers "F.Cu" "F.Mask" "F.Paste")
			(net "PRSNT_CABLE_GPU_A1_ISO_N")
		)
		(pad "4" smd rect
			(at 0.94996 0.649986 180)
			(size 0.4318 0.508)
			(layers "F.Cu" "F.Mask" "F.Paste")
			(net "GND")
		)
		(pad "5" smd rect
			(at 0.94996 0 180)
			(size 0.4318 0.508)
			(layers "F.Cu" "F.Mask" "F.Paste")
			(net "PRSNT_CABLE_GPU_A1")
		)
		(pad "6" smd rect
			(at 0.94996 -0.649986 180)
			(size 0.4318 0.508)
			(layers "F.Cu" "F.Mask" "F.Paste")
			(net "PRSNT_CABLE_GPU_A1")
		)
	)
	(footprint ""
		(layer "F.Cu")
		(at 228.816662 -122.151902 180)
		(property "Reference" "R1274"
			(at 0 0 180)
			(layer "F.SilkS")
			(hide yes)
			(effects
				(font
					(size 1.27 1.27)
				)
			)
		)
		(property "Value" ""
			(at 0 0 180)
			(layer "F.Fab")
			(effects
				(font
					(size 1.27 1.27)
				)
			)
		)
		(duplicate_pad_numbers_are_jumpers no)
		(fp_line
			(start 0.7874 -0.4064)
			(end 0.7874 0.164338)
			(stroke
				(width 0.1524)
				(type default)
			)
			(layer "F.SilkS")
		)
		(fp_line
			(start 0.610362 0.4064)
			(end -0.507238 0.4064)
			(stroke
				(width 0.1524)
				(type default)
			)
			(layer "F.SilkS")
		)
		(fp_line
			(start -0.7874 0.067818)
			(end -0.7874 -0.4064)
			(stroke
				(width 0.1524)
				(type default)
			)
			(layer "F.SilkS")
		)
		(fp_line
			(start -0.7874 -0.4064)
			(end 0.7874 -0.4064)
			(stroke
				(width 0.1524)
				(type default)
			)
			(layer "F.SilkS")
		)
		(fp_line
			(start 0.67945 0.3048)
			(end 0.120396 0.3048)
			(stroke
				(width 0.1)
				(type default)
			)
			(layer "F.Fab")
		)
		(fp_line
			(start 0.67945 -0.3048)
			(end 0.67945 0.3048)
			(stroke
				(width 0.1)
				(type default)
			)
			(layer "F.Fab")
		)
		(fp_line
			(start 0.12065 -0.2794)
			(end 0.12065 -0.3048)
			(stroke
				(width 0.1)
				(type default)
			)
			(layer "F.Fab")
		)
		(fp_line
			(start 0.12065 -0.3048)
			(end 0.67945 -0.3048)
			(stroke
				(width 0.1)
				(type default)
			)
			(layer "F.Fab")
		)
		(fp_line
			(start 0.120396 0.3048)
			(end 0.120396 0.2794)
			(stroke
				(width 0.1)
				(type default)
			)
			(layer "F.Fab")
		)
		(fp_line
			(start 0.120396 0.2794)
			(end -0.12065 0.2794)
			(stroke
				(width 0.1)
				(type default)
			)
			(layer "F.Fab")
		)
		(fp_line
			(start -0.12065 0.3048)
			(end -0.67945 0.3048)
			(stroke
				(width 0.1)
				(type default)
			)
			(layer "F.Fab")
		)
		(fp_line
			(start -0.12065 0.2794)
			(end -0.12065 0.3048)
			(stroke
				(width 0.1)
				(type default)
			)
			(layer "F.Fab")
		)
		(fp_line
			(start -0.12065 -0.2794)
			(end 0.12065 -0.2794)
			(stroke
				(width 0.1)
				(type default)
			)
			(layer "F.Fab")
		)
		(fp_line
			(start -0.12065 -0.305054)
			(end -0.12065 -0.2794)
			(stroke
				(width 0.1)
				(type default)
			)
			(layer "F.Fab")
		)
		(fp_line
			(start -0.67945 0.3048)
			(end -0.67945 -0.305054)
			(stroke
				(width 0.1)
				(type default)
			)
			(layer "F.Fab")
		)
		(fp_line
			(start -0.67945 -0.305054)
			(end -0.12065 -0.305054)
			(stroke
				(width 0.1)
				(type default)
			)
			(layer "F.Fab")
		)
		(pad "1" smd circle
			(at -0.40005 0 180)
			(size 0 0)
			(layers "F.Cu" "F.Mask" "F.Paste")
			(net "CLK_100M_OCP_SFF_2_R_DN")
		)
		(pad "2" smd circle
			(at 0.40005 0 180)
			(size 0 0)
			(layers "F.Cu" "F.Mask" "F.Paste")
			(net "CLK_100M_OCP_SFF_2_DN")
		)
	)
	(footprint ""
		(layer "F.Cu")
		(at 93.597476 -79.078836)
		(property "Reference" "D96"
			(at -47.22241 38.649402 90)
			(unlocked yes)
			(layer "F.SilkS")
			(effects
				(font
					(size 0.635 0.4064)
					(thickness 0.1524)
				)
				(justify left)
			)
		)
		(property "Value" ""
			(at 0 0 0)
			(layer "F.Fab")
			(effects
				(font
					(size 1.27 1.27)
				)
			)
		)
		(duplicate_pad_numbers_are_jumpers no)
		(fp_line
			(start -0.90678 0.4826)
			(end -0.90678 -0.4699)
			(stroke
				(width 0.1524)
				(type default)
			)
			(layer "F.SilkS")
		)
		(fp_line
			(start -0.89408 -0.4826)
			(end 0.90678 -0.4826)
			(stroke
				(width 0.1524)
				(type default)
			)
			(layer "F.SilkS")
		)
		(fp_line
			(start -0.79248 -0.4826)
			(end 1.03378 -0.4826)
			(stroke
				(width 0.1524)
				(type default)
			)
			(layer "F.SilkS")
		)
		(fp_line
			(start -0.64008 -0.4826)
			(end 1.16078 -0.4826)
			(stroke
				(width 0.1524)
				(type default)
			)
			(layer "F.SilkS")
		)
		(fp_line
			(start 0.90678 -0.4826)
			(end 0.90678 0.4826)
			(stroke
				(width 0.1524)
				(type default)
			)
			(layer "F.SilkS")
		)
		(fp_line
			(start 0.90678 0.4826)
			(end -0.90678 0.4826)
			(stroke
				(width 0.1524)
				(type default)
			)
			(layer "F.SilkS")
		)
		(fp_line
			(start 1.03378 -0.4826)
			(end 1.03378 0.4826)
			(stroke
				(width 0.1524)
				(type default)
			)
			(layer "F.SilkS")
		)
		(fp_line
			(start 1.03378 0.4826)
			(end -0.79248 0.4826)
			(stroke
				(width 0.1524)
				(type default)
			)
			(layer "F.SilkS")
		)
		(fp_line
			(start 1.16078 -0.4826)
			(end 1.16078 0.4826)
			(stroke
				(width 0.1524)
				(type default)
			)
			(layer "F.SilkS")
		)
		(fp_line
			(start 1.16078 0.4826)
			(end -0.64008 0.4826)
			(stroke
				(width 0.1524)
				(type default)
			)
			(layer "F.SilkS")
		)
		(fp_line
			(start -0.499872 -0.249936)
			(end 0.499872 -0.249936)
			(stroke
				(width 0.1)
				(type default)
			)
			(layer "F.Fab")
		)
		(fp_line
			(start -0.499872 0.249936)
			(end -0.499872 -0.249936)
			(stroke
				(width 0.1)
				(type default)
			)
			(layer "F.Fab")
		)
		(fp_line
			(start 0.499872 -0.249936)
			(end 0.499872 0.249936)
			(stroke
				(width 0.1)
				(type default)
			)
			(layer "F.Fab")
		)
		(fp_line
			(start 0.499872 0.249936)
			(end -0.499872 0.249936)
			(stroke
				(width 0.1)
				(type default)
			)
			(layer "F.Fab")
		)
		(pad "A" smd rect
			(at -0.47498 0)
			(size 0.6096 0.7112)
			(layers "F.Cu" "F.Mask" "F.Paste")
			(net "LED_PWRGD_PS_PWROK_PLD")
		)
		(pad "C" smd rect
			(at 0.47498 0)
			(size 0.6096 0.7112)
			(layers "F.Cu" "F.Mask" "F.Paste")
			(net "LED_PWRGD_PS_PWROK_PLD_D")
		)
	)
	(footprint ""
		(layer "F.Cu")
		(at 74.615802 -74.901552 -90)
		(property "Reference" "R3096"
			(at 0 0 270)
			(layer "F.SilkS")
			(hide yes)
			(effects
				(font
					(size 1.27 1.27)
				)
			)
		)
		(property "Value" ""
			(at 0 0 270)
			(layer "F.Fab")
			(effects
				(font
					(size 1.27 1.27)
				)
			)
		)
		(duplicate_pad_numbers_are_jumpers no)
		(fp_line
			(start -0.7874 0.4064)
			(end -0.7874 -0.4064)
			(stroke
				(width 0.1524)
				(type default)
			)
			(layer "F.SilkS")
		)
		(fp_line
			(start 0.7874 0.4064)
			(end -0.7874 0.4064)
			(stroke
				(width 0.1524)
				(type default)
			)
			(layer "F.SilkS")
		)
		(fp_line
			(start -0.7874 -0.4064)
			(end 0.7874 -0.4064)
			(stroke
				(width 0.1524)
				(type default)
			)
			(layer "F.SilkS")
		)
		(fp_line
			(start 0.7874 -0.4064)
			(end 0.7874 0.4064)
			(stroke
				(width 0.1524)
				(type default)
			)
			(layer "F.SilkS")
		)
		(fp_line
			(start -0.67945 0.3048)
			(end -0.67945 -0.305054)
			(stroke
				(width 0.1)
				(type default)
			)
			(layer "F.Fab")
		)
		(fp_line
			(start -0.12065 0.3048)
			(end -0.67945 0.3048)
			(stroke
				(width 0.1)
				(type default)
			)
			(layer "F.Fab")
		)
		(fp_line
			(start 0.120396 0.3048)
			(end 0.120396 0.2794)
			(stroke
				(width 0.1)
				(type default)
			)
			(layer "F.Fab")
		)
		(fp_line
			(start 0.67945 0.3048)
			(end 0.120396 0.3048)
			(stroke
				(width 0.1)
				(type default)
			)
			(layer "F.Fab")
		)
		(fp_line
			(start -0.12065 0.2794)
			(end -0.12065 0.3048)
			(stroke
				(width 0.1)
				(type default)
			)
			(layer "F.Fab")
		)
		(fp_line
			(start 0.120396 0.2794)
			(end -0.12065 0.2794)
			(stroke
				(width 0.1)
				(type default)
			)
			(layer "F.Fab")
		)
		(fp_line
			(start -0.12065 -0.2794)
			(end 0.12065 -0.2794)
			(stroke
				(width 0.1)
				(type default)
			)
			(layer "F.Fab")
		)
		(fp_line
			(start 0.12065 -0.2794)
			(end 0.12065 -0.3048)
			(stroke
				(width 0.1)
				(type default)
			)
			(layer "F.Fab")
		)
		(fp_line
			(start 0.12065 -0.3048)
			(end 0.67945 -0.3048)
			(stroke
				(width 0.1)
				(type default)
			)
			(layer "F.Fab")
		)
		(fp_line
			(start 0.67945 -0.3048)
			(end 0.67945 0.3048)
			(stroke
				(width 0.1)
				(type default)
			)
			(layer "F.Fab")
		)
		(fp_line
			(start -0.67945 -0.305054)
			(end -0.12065 -0.305054)
			(stroke
				(width 0.1)
				(type default)
			)
			(layer "F.Fab")
		)
		(fp_line
			(start -0.12065 -0.305054)
			(end -0.12065 -0.2794)
			(stroke
				(width 0.1)
				(type default)
			)
			(layer "F.Fab")
		)
		(pad "1" smd circle
			(at -0.40005 0 270)
			(size 0 0)
			(layers "F.Cu" "F.Mask" "F.Paste")
			(net "LED_PWRGD_PVCCFA_EHV_CPU1")
		)
		(pad "2" smd circle
			(at 0.40005 0 270)
			(size 0 0)
			(layers "F.Cu" "F.Mask" "F.Paste")
			(net "P3V3_AUX")
		)
	)
	(footprint ""
		(layer "F.Cu")
		(at 205.397608 -399.743422 180)
		(property "Reference" "PC2348"
			(at 0 0 180)
			(layer "F.SilkS")
			(hide yes)
			(effects
				(font
					(size 1.27 1.27)
				)
			)
		)
		(property "Value" ""
			(at 0 0 180)
			(layer "F.Fab")
			(effects
				(font
					(size 1.27 1.27)
				)
			)
		)
		(duplicate_pad_numbers_are_jumpers no)
		(fp_line
			(start 0.7874 0.4064)
			(end -0.7874 0.4064)
			(stroke
				(width 0.1524)
				(type default)
			)
			(layer "F.SilkS")
		)
		(fp_line
			(start 0.7874 -0.4064)
			(end 0.7874 0.4064)
			(stroke
				(width 0.1524)
				(type default)
			)
			(layer "F.SilkS")
		)
		(fp_line
			(start -0.7874 0.4064)
			(end -0.7874 -0.4064)
			(stroke
				(width 0.1524)
				(type default)
			)
			(layer "F.SilkS")
		)
		(fp_line
			(start -0.7874 -0.4064)
			(end 0.7874 -0.4064)
			(stroke
				(width 0.1524)
				(type default)
			)
			(layer "F.SilkS")
		)
		(fp_line
			(start 0.67945 0.3048)
			(end 0.120396 0.3048)
			(stroke
				(width 0.1)
				(type default)
			)
			(layer "F.Fab")
		)
		(fp_line
			(start 0.67945 -0.3048)
			(end 0.67945 0.3048)
			(stroke
				(width 0.1)
				(type default)
			)
			(layer "F.Fab")
		)
		(fp_line
			(start 0.12065 -0.2794)
			(end 0.12065 -0.3048)
			(stroke
				(width 0.1)
				(type default)
			)
			(layer "F.Fab")
		)
		(fp_line
			(start 0.12065 -0.3048)
			(end 0.67945 -0.3048)
			(stroke
				(width 0.1)
				(type default)
			)
			(layer "F.Fab")
		)
		(fp_line
			(start 0.120396 0.3048)
			(end 0.120396 0.2794)
			(stroke
				(width 0.1)
				(type default)
			)
			(layer "F.Fab")
		)
		(fp_line
			(start 0.120396 0.2794)
			(end -0.12065 0.2794)
			(stroke
				(width 0.1)
				(type default)
			)
			(layer "F.Fab")
		)
		(fp_line
			(start -0.12065 0.3048)
			(end -0.67945 0.3048)
			(stroke
				(width 0.1)
				(type default)
			)
			(layer "F.Fab")
		)
		(fp_line
			(start -0.12065 0.2794)
			(end -0.12065 0.3048)
			(stroke
				(width 0.1)
				(type default)
			)
			(layer "F.Fab")
		)
		(fp_line
			(start -0.12065 -0.2794)
			(end 0.12065 -0.2794)
			(stroke
				(width 0.1)
				(type default)
			)
			(layer "F.Fab")
		)
		(fp_line
			(start -0.12065 -0.305054)
			(end -0.12065 -0.2794)
			(stroke
				(width 0.1)
				(type default)
			)
			(layer "F.Fab")
		)
		(fp_line
			(start -0.67945 0.3048)
			(end -0.67945 -0.305054)
			(stroke
				(width 0.1)
				(type default)
			)
			(layer "F.Fab")
		)
		(fp_line
			(start -0.67945 -0.305054)
			(end -0.12065 -0.305054)
			(stroke
				(width 0.1)
				(type default)
			)
			(layer "F.Fab")
		)
		(pad "1" smd circle
			(at -0.40005 0 180)
			(size 0 0)
			(layers "F.Cu" "F.Mask" "F.Paste")
			(net "HSC_OCREF")
		)
		(pad "2" smd circle
			(at 0.40005 0 180)
			(size 0 0)
			(layers "F.Cu" "F.Mask" "F.Paste")
			(net "AGND_HSC")
		)
	)
	(footprint ""
		(layer "F.Cu")
		(at 319.8241 -76.585064 -90)
		(property "Reference" "R2234"
			(at 0 0 270)
			(layer "F.SilkS")
			(hide yes)
			(effects
				(font
					(size 1.27 1.27)
				)
			)
		)
		(property "Value" ""
			(at 0 0 270)
			(layer "F.Fab")
			(effects
				(font
					(size 1.27 1.27)
				)
			)
		)
		(duplicate_pad_numbers_are_jumpers no)
		(fp_line
			(start -0.7874 0.4064)
			(end -0.7874 -0.4064)
			(stroke
				(width 0.1524)
				(type default)
			)
			(layer "F.SilkS")
		)
		(fp_line
			(start 0.7874 0.4064)
			(end -0.7874 0.4064)
			(stroke
				(width 0.1524)
				(type default)
			)
			(layer "F.SilkS")
		)
		(fp_line
			(start -0.7874 -0.4064)
			(end 0.7874 -0.4064)
			(stroke
				(width 0.1524)
				(type default)
			)
			(layer "F.SilkS")
		)
		(fp_line
			(start 0.7874 -0.4064)
			(end 0.7874 0.4064)
			(stroke
				(width 0.1524)
				(type default)
			)
			(layer "F.SilkS")
		)
		(fp_line
			(start -0.67945 0.3048)
			(end -0.67945 -0.305054)
			(stroke
				(width 0.1)
				(type default)
			)
			(layer "F.Fab")
		)
		(fp_line
			(start -0.12065 0.3048)
			(end -0.67945 0.3048)
			(stroke
				(width 0.1)
				(type default)
			)
			(layer "F.Fab")
		)
		(fp_line
			(start 0.120396 0.3048)
			(end 0.120396 0.2794)
			(stroke
				(width 0.1)
				(type default)
			)
			(layer "F.Fab")
		)
		(fp_line
			(start 0.67945 0.3048)
			(end 0.120396 0.3048)
			(stroke
				(width 0.1)
				(type default)
			)
			(layer "F.Fab")
		)
		(fp_line
			(start -0.12065 0.2794)
			(end -0.12065 0.3048)
			(stroke
				(width 0.1)
				(type default)
			)
			(layer "F.Fab")
		)
		(fp_line
			(start 0.120396 0.2794)
			(end -0.12065 0.2794)
			(stroke
				(width 0.1)
				(type default)
			)
			(layer "F.Fab")
		)
		(fp_line
			(start -0.12065 -0.2794)
			(end 0.12065 -0.2794)
			(stroke
				(width 0.1)
				(type default)
			)
			(layer "F.Fab")
		)
		(fp_line
			(start 0.12065 -0.2794)
			(end 0.12065 -0.3048)
			(stroke
				(width 0.1)
				(type default)
			)
			(layer "F.Fab")
		)
		(fp_line
			(start 0.12065 -0.3048)
			(end 0.67945 -0.3048)
			(stroke
				(width 0.1)
				(type default)
			)
			(layer "F.Fab")
		)
		(fp_line
			(start 0.67945 -0.3048)
			(end 0.67945 0.3048)
			(stroke
				(width 0.1)
				(type default)
			)
			(layer "F.Fab")
		)
		(fp_line
			(start -0.67945 -0.305054)
			(end -0.12065 -0.305054)
			(stroke
				(width 0.1)
				(type default)
			)
			(layer "F.Fab")
		)
		(fp_line
			(start -0.12065 -0.305054)
			(end -0.12065 -0.2794)
			(stroke
				(width 0.1)
				(type default)
			)
			(layer "F.Fab")
		)
		(pad "1" smd circle
			(at -0.40005 0 270)
			(size 0 0)
			(layers "F.Cu" "F.Mask" "F.Paste")
			(net "P1V05_PCH_AUX")
		)
		(pad "2" smd circle
			(at 0.40005 0 270)
			(size 0 0)
			(layers "F.Cu" "F.Mask" "F.Paste")
			(net "FM_BOARD_SKU_ID4")
		)
	)
	(footprint ""
		(layer "F.Cu")
		(at 24.050752 -401.790408)
		(property "Reference" "R3321"
			(at 0 0 0)
			(layer "F.SilkS")
			(hide yes)
			(effects
				(font
					(size 1.27 1.27)
				)
			)
		)
		(property "Value" ""
			(at 0 0 0)
			(layer "F.Fab")
			(effects
				(font
					(size 1.27 1.27)
				)
			)
		)
		(duplicate_pad_numbers_are_jumpers no)
		(fp_line
			(start -0.7874 -0.4064)
			(end 0.7874 -0.4064)
			(stroke
				(width 0.1524)
				(type default)
			)
			(layer "F.SilkS")
		)
		(fp_line
			(start -0.7874 0.4064)
			(end -0.7874 -0.4064)
			(stroke
				(width 0.1524)
				(type default)
			)
			(layer "F.SilkS")
		)
		(fp_line
			(start 0.7874 -0.4064)
			(end 0.7874 0.4064)
			(stroke
				(width 0.1524)
				(type default)
			)
			(layer "F.SilkS")
		)
		(fp_line
			(start 0.7874 0.4064)
			(end -0.7874 0.4064)
			(stroke
				(width 0.1524)
				(type default)
			)
			(layer "F.SilkS")
		)
		(fp_line
			(start -0.67945 -0.305054)
			(end -0.12065 -0.305054)
			(stroke
				(width 0.1)
				(type default)
			)
			(layer "F.Fab")
		)
		(fp_line
			(start -0.67945 0.3048)
			(end -0.67945 -0.305054)
			(stroke
				(width 0.1)
				(type default)
			)
			(layer "F.Fab")
		)
		(fp_line
			(start -0.12065 -0.305054)
			(end -0.12065 -0.2794)
			(stroke
				(width 0.1)
				(type default)
			)
			(layer "F.Fab")
		)
		(fp_line
			(start -0.12065 -0.2794)
			(end 0.12065 -0.2794)
			(stroke
				(width 0.1)
				(type default)
			)
			(layer "F.Fab")
		)
		(fp_line
			(start -0.12065 0.2794)
			(end -0.12065 0.3048)
			(stroke
				(width 0.1)
				(type default)
			)
			(layer "F.Fab")
		)
		(fp_line
			(start -0.12065 0.3048)
			(end -0.67945 0.3048)
			(stroke
				(width 0.1)
				(type default)
			)
			(layer "F.Fab")
		)
		(fp_line
			(start 0.120396 0.2794)
			(end -0.12065 0.2794)
			(stroke
				(width 0.1)
				(type default)
			)
			(layer "F.Fab")
		)
		(fp_line
			(start 0.120396 0.3048)
			(end 0.120396 0.2794)
			(stroke
				(width 0.1)
				(type default)
			)
			(layer "F.Fab")
		)
		(fp_line
			(start 0.12065 -0.3048)
			(end 0.67945 -0.3048)
			(stroke
				(width 0.1)
				(type default)
			)
			(layer "F.Fab")
		)
		(fp_line
			(start 0.12065 -0.2794)
			(end 0.12065 -0.3048)
			(stroke
				(width 0.1)
				(type default)
			)
			(layer "F.Fab")
		)
		(fp_line
			(start 0.67945 -0.3048)
			(end 0.67945 0.3048)
			(stroke
				(width 0.1)
				(type default)
			)
			(layer "F.Fab")
		)
		(fp_line
			(start 0.67945 0.3048)
			(end 0.120396 0.3048)
			(stroke
				(width 0.1)
				(type default)
			)
			(layer "F.Fab")
		)
		(pad "1" smd circle
			(at -0.40005 0)
			(size 0 0)
			(layers "F.Cu" "F.Mask" "F.Paste")
			(net "P3V3_AUX")
		)
		(pad "2" smd circle
			(at 0.40005 0)
			(size 0 0)
			(layers "F.Cu" "F.Mask" "F.Paste")
			(net "GPU_FPGA_READY_ISO")
		)
	)
	(footprint ""
		(layer "F.Cu")
		(at 29.93009 -391.65149)
		(property "Reference" "R3386"
			(at 0 0 0)
			(layer "F.SilkS")
			(hide yes)
			(effects
				(font
					(size 1.27 1.27)
				)
			)
		)
		(property "Value" ""
			(at 0 0 0)
			(layer "F.Fab")
			(effects
				(font
					(size 1.27 1.27)
				)
			)
		)
		(duplicate_pad_numbers_are_jumpers no)
		(fp_line
			(start -0.7874 -0.4064)
			(end 0.7874 -0.4064)
			(stroke
				(width 0.1524)
				(type default)
			)
			(layer "F.SilkS")
		)
		(fp_line
			(start -0.7874 0.4064)
			(end -0.7874 -0.4064)
			(stroke
				(width 0.1524)
				(type default)
			)
			(layer "F.SilkS")
		)
		(fp_line
			(start 0.7874 -0.4064)
			(end 0.7874 0.4064)
			(stroke
				(width 0.1524)
				(type default)
			)
			(layer "F.SilkS")
		)
		(fp_line
			(start 0.7874 0.4064)
			(end -0.7874 0.4064)
			(stroke
				(width 0.1524)
				(type default)
			)
			(layer "F.SilkS")
		)
		(fp_line
			(start -0.67945 -0.305054)
			(end -0.12065 -0.305054)
			(stroke
				(width 0.1)
				(type default)
			)
			(layer "F.Fab")
		)
		(fp_line
			(start -0.67945 0.3048)
			(end -0.67945 -0.305054)
			(stroke
				(width 0.1)
				(type default)
			)
			(layer "F.Fab")
		)
		(fp_line
			(start -0.12065 -0.305054)
			(end -0.12065 -0.2794)
			(stroke
				(width 0.1)
				(type default)
			)
			(layer "F.Fab")
		)
		(fp_line
			(start -0.12065 -0.2794)
			(end 0.12065 -0.2794)
			(stroke
				(width 0.1)
				(type default)
			)
			(layer "F.Fab")
		)
		(fp_line
			(start -0.12065 0.2794)
			(end -0.12065 0.3048)
			(stroke
				(width 0.1)
				(type default)
			)
			(layer "F.Fab")
		)
		(fp_line
			(start -0.12065 0.3048)
			(end -0.67945 0.3048)
			(stroke
				(width 0.1)
				(type default)
			)
			(layer "F.Fab")
		)
		(fp_line
			(start 0.120396 0.2794)
			(end -0.12065 0.2794)
			(stroke
				(width 0.1)
				(type default)
			)
			(layer "F.Fab")
		)
		(fp_line
			(start 0.120396 0.3048)
			(end 0.120396 0.2794)
			(stroke
				(width 0.1)
				(type default)
			)
			(layer "F.Fab")
		)
		(fp_line
			(start 0.12065 -0.3048)
			(end 0.67945 -0.3048)
			(stroke
				(width 0.1)
				(type default)
			)
			(layer "F.Fab")
		)
		(fp_line
			(start 0.12065 -0.2794)
			(end 0.12065 -0.3048)
			(stroke
				(width 0.1)
				(type default)
			)
			(layer "F.Fab")
		)
		(fp_line
			(start 0.67945 -0.3048)
			(end 0.67945 0.3048)
			(stroke
				(width 0.1)
				(type default)
			)
			(layer "F.Fab")
		)
		(fp_line
			(start 0.67945 0.3048)
			(end 0.120396 0.3048)
			(stroke
				(width 0.1)
				(type default)
			)
			(layer "F.Fab")
		)
		(pad "1" smd circle
			(at -0.40005 0)
			(size 0 0)
			(layers "F.Cu" "F.Mask" "F.Paste")
			(net "P3V3_AUX")
		)
		(pad "2" smd circle
			(at 0.40005 0)
			(size 0 0)
			(layers "F.Cu" "F.Mask" "F.Paste")
			(net "FM_P2E_BUF2_VOD_SEL")
		)
	)
	(footprint ""
		(layer "F.Cu")
		(at 329.40625 -347.580458 90)
		(property "Reference" "PR1773"
			(at 0 0 90)
			(layer "F.SilkS")
			(hide yes)
			(effects
				(font
					(size 1.27 1.27)
				)
			)
		)
		(property "Value" ""
			(at 0 0 90)
			(layer "F.Fab")
			(effects
				(font
					(size 1.27 1.27)
				)
			)
		)
		(duplicate_pad_numbers_are_jumpers no)
		(fp_line
			(start 0.7874 -0.4064)
			(end 0.7874 0.4064)
			(stroke
				(width 0.1524)
				(type default)
			)
			(layer "F.SilkS")
		)
		(fp_line
			(start -0.7874 -0.4064)
			(end 0.7874 -0.4064)
			(stroke
				(width 0.1524)
				(type default)
			)
			(layer "F.SilkS")
		)
		(fp_line
			(start 0.7874 0.4064)
			(end -0.7874 0.4064)
			(stroke
				(width 0.1524)
				(type default)
			)
			(layer "F.SilkS")
		)
		(fp_line
			(start -0.7874 0.4064)
			(end -0.7874 -0.4064)
			(stroke
				(width 0.1524)
				(type default)
			)
			(layer "F.SilkS")
		)
		(fp_line
			(start -0.12065 -0.305054)
			(end -0.12065 -0.2794)
			(stroke
				(width 0.1)
				(type default)
			)
			(layer "F.Fab")
		)
		(fp_line
			(start -0.67945 -0.305054)
			(end -0.12065 -0.305054)
			(stroke
				(width 0.1)
				(type default)
			)
			(layer "F.Fab")
		)
		(fp_line
			(start 0.67945 -0.3048)
			(end 0.67945 0.3048)
			(stroke
				(width 0.1)
				(type default)
			)
			(layer "F.Fab")
		)
		(fp_line
			(start 0.12065 -0.3048)
			(end 0.67945 -0.3048)
			(stroke
				(width 0.1)
				(type default)
			)
			(layer "F.Fab")
		)
		(fp_line
			(start 0.12065 -0.2794)
			(end 0.12065 -0.3048)
			(stroke
				(width 0.1)
				(type default)
			)
			(layer "F.Fab")
		)
		(fp_line
			(start -0.12065 -0.2794)
			(end 0.12065 -0.2794)
			(stroke
				(width 0.1)
				(type default)
			)
			(layer "F.Fab")
		)
		(fp_line
			(start 0.120396 0.2794)
			(end -0.12065 0.2794)
			(stroke
				(width 0.1)
				(type default)
			)
			(layer "F.Fab")
		)
		(fp_line
			(start -0.12065 0.2794)
			(end -0.12065 0.3048)
			(stroke
				(width 0.1)
				(type default)
			)
			(layer "F.Fab")
		)
		(fp_line
			(start 0.67945 0.3048)
			(end 0.120396 0.3048)
			(stroke
				(width 0.1)
				(type default)
			)
			(layer "F.Fab")
		)
		(fp_line
			(start 0.120396 0.3048)
			(end 0.120396 0.2794)
			(stroke
				(width 0.1)
				(type default)
			)
			(layer "F.Fab")
		)
		(fp_line
			(start -0.12065 0.3048)
			(end -0.67945 0.3048)
			(stroke
				(width 0.1)
				(type default)
			)
			(layer "F.Fab")
		)
		(fp_line
			(start -0.67945 0.3048)
			(end -0.67945 -0.305054)
			(stroke
				(width 0.1)
				(type default)
			)
			(layer "F.Fab")
		)
		(pad "1" smd circle
			(at -0.40005 0 90)
			(size 0 0)
			(layers "F.Cu" "F.Mask" "F.Paste")
			(net "SW_PVCCIN_CPU0_BOOT7")
		)
		(pad "2" smd circle
			(at 0.40005 0 90)
			(size 0 0)
			(layers "F.Cu" "F.Mask" "F.Paste")
			(net "SW_PVCCIN_CPU0_BOOT7_R")
		)
	)
	(footprint ""
		(layer "F.Cu")
		(at 430.600104 -134.494778)
		(property "Reference" "C3274"
			(at 0 0 0)
			(layer "F.SilkS")
			(hide yes)
			(effects
				(font
					(size 1.27 1.27)
				)
			)
		)
		(property "Value" ""
			(at 0 0 0)
			(layer "F.Fab")
			(effects
				(font
					(size 1.27 1.27)
				)
			)
		)
		(duplicate_pad_numbers_are_jumpers no)
		(fp_line
			(start -0.7874 -0.4064)
			(end 0.7874 -0.4064)
			(stroke
				(width 0.1524)
				(type default)
			)
			(layer "F.SilkS")
		)
		(fp_line
			(start -0.7874 0.4064)
			(end -0.7874 -0.4064)
			(stroke
				(width 0.1524)
				(type default)
			)
			(layer "F.SilkS")
		)
		(fp_line
			(start 0.7874 -0.4064)
			(end 0.7874 0.4064)
			(stroke
				(width 0.1524)
				(type default)
			)
			(layer "F.SilkS")
		)
		(fp_line
			(start 0.7874 0.4064)
			(end -0.7874 0.4064)
			(stroke
				(width 0.1524)
				(type default)
			)
			(layer "F.SilkS")
		)
		(fp_line
			(start -0.67945 -0.305054)
			(end -0.12065 -0.305054)
			(stroke
				(width 0.1)
				(type default)
			)
			(layer "F.Fab")
		)
		(fp_line
			(start -0.67945 0.3048)
			(end -0.67945 -0.305054)
			(stroke
				(width 0.1)
				(type default)
			)
			(layer "F.Fab")
		)
		(fp_line
			(start -0.12065 -0.305054)
			(end -0.12065 -0.2794)
			(stroke
				(width 0.1)
				(type default)
			)
			(layer "F.Fab")
		)
		(fp_line
			(start -0.12065 -0.2794)
			(end 0.12065 -0.2794)
			(stroke
				(width 0.1)
				(type default)
			)
			(layer "F.Fab")
		)
		(fp_line
			(start -0.12065 0.2794)
			(end -0.12065 0.3048)
			(stroke
				(width 0.1)
				(type default)
			)
			(layer "F.Fab")
		)
		(fp_line
			(start -0.12065 0.3048)
			(end -0.67945 0.3048)
			(stroke
				(width 0.1)
				(type default)
			)
			(layer "F.Fab")
		)
		(fp_line
			(start 0.120396 0.2794)
			(end -0.12065 0.2794)
			(stroke
				(width 0.1)
				(type default)
			)
			(layer "F.Fab")
		)
		(fp_line
			(start 0.120396 0.3048)
			(end 0.120396 0.2794)
			(stroke
				(width 0.1)
				(type default)
			)
			(layer "F.Fab")
		)
		(fp_line
			(start 0.12065 -0.3048)
			(end 0.67945 -0.3048)
			(stroke
				(width 0.1)
				(type default)
			)
			(layer "F.Fab")
		)
		(fp_line
			(start 0.12065 -0.2794)
			(end 0.12065 -0.3048)
			(stroke
				(width 0.1)
				(type default)
			)
			(layer "F.Fab")
		)
		(fp_line
			(start 0.67945 -0.3048)
			(end 0.67945 0.3048)
			(stroke
				(width 0.1)
				(type default)
			)
			(layer "F.Fab")
		)
		(fp_line
			(start 0.67945 0.3048)
			(end 0.120396 0.3048)
			(stroke
				(width 0.1)
				(type default)
			)
			(layer "F.Fab")
		)
		(pad "1" smd circle
			(at -0.40005 0)
			(size 0 0)
			(layers "F.Cu" "F.Mask" "F.Paste")
			(net "PVCCINFAON_CPU0_EN_R")
		)
		(pad "2" smd circle
			(at 0.40005 0)
			(size 0 0)
			(layers "F.Cu" "F.Mask" "F.Paste")
			(net "GND")
		)
	)
	(footprint ""
		(layer "F.Cu")
		(at 19.812 -410.7942 90)
		(property "Reference" "R4729"
			(at 0 0 90)
			(layer "F.SilkS")
			(hide yes)
			(effects
				(font
					(size 1.27 1.27)
				)
			)
		)
		(property "Value" ""
			(at 0 0 90)
			(layer "F.Fab")
			(effects
				(font
					(size 1.27 1.27)
				)
			)
		)
		(duplicate_pad_numbers_are_jumpers no)
		(fp_line
			(start 0.7874 -0.4064)
			(end 0.7874 0.4064)
			(stroke
				(width 0.1524)
				(type default)
			)
			(layer "F.SilkS")
		)
		(fp_line
			(start -0.7874 -0.4064)
			(end 0.7874 -0.4064)
			(stroke
				(width 0.1524)
				(type default)
			)
			(layer "F.SilkS")
		)
		(fp_line
			(start 0.7874 0.4064)
			(end -0.7874 0.4064)
			(stroke
				(width 0.1524)
				(type default)
			)
			(layer "F.SilkS")
		)
		(fp_line
			(start -0.7874 0.4064)
			(end -0.7874 -0.4064)
			(stroke
				(width 0.1524)
				(type default)
			)
			(layer "F.SilkS")
		)
		(fp_line
			(start -0.12065 -0.305054)
			(end -0.12065 -0.2794)
			(stroke
				(width 0.1)
				(type default)
			)
			(layer "F.Fab")
		)
		(fp_line
			(start -0.67945 -0.305054)
			(end -0.12065 -0.305054)
			(stroke
				(width 0.1)
				(type default)
			)
			(layer "F.Fab")
		)
		(fp_line
			(start 0.67945 -0.3048)
			(end 0.67945 0.3048)
			(stroke
				(width 0.1)
				(type default)
			)
			(layer "F.Fab")
		)
		(fp_line
			(start 0.12065 -0.3048)
			(end 0.67945 -0.3048)
			(stroke
				(width 0.1)
				(type default)
			)
			(layer "F.Fab")
		)
		(fp_line
			(start 0.12065 -0.2794)
			(end 0.12065 -0.3048)
			(stroke
				(width 0.1)
				(type default)
			)
			(layer "F.Fab")
		)
		(fp_line
			(start -0.12065 -0.2794)
			(end 0.12065 -0.2794)
			(stroke
				(width 0.1)
				(type default)
			)
			(layer "F.Fab")
		)
		(fp_line
			(start 0.120396 0.2794)
			(end -0.12065 0.2794)
			(stroke
				(width 0.1)
				(type default)
			)
			(layer "F.Fab")
		)
		(fp_line
			(start -0.12065 0.2794)
			(end -0.12065 0.3048)
			(stroke
				(width 0.1)
				(type default)
			)
			(layer "F.Fab")
		)
		(fp_line
			(start 0.67945 0.3048)
			(end 0.120396 0.3048)
			(stroke
				(width 0.1)
				(type default)
			)
			(layer "F.Fab")
		)
		(fp_line
			(start 0.120396 0.3048)
			(end 0.120396 0.2794)
			(stroke
				(width 0.1)
				(type default)
			)
			(layer "F.Fab")
		)
		(fp_line
			(start -0.12065 0.3048)
			(end -0.67945 0.3048)
			(stroke
				(width 0.1)
				(type default)
			)
			(layer "F.Fab")
		)
		(fp_line
			(start -0.67945 0.3048)
			(end -0.67945 -0.305054)
			(stroke
				(width 0.1)
				(type default)
			)
			(layer "F.Fab")
		)
		(pad "1" smd circle
			(at -0.40005 0 90)
			(size 0 0)
			(layers "F.Cu" "F.Mask" "F.Paste")
			(net "GPU_PRSNT_N_ISO")
		)
		(pad "2" smd circle
			(at 0.40005 0 90)
			(size 0 0)
			(layers "F.Cu" "F.Mask" "F.Paste")
			(net "GPU_PRSNT_N_ISO_R1")
		)
	)
	(footprint ""
		(layer "F.Cu")
		(at 104.8258 -410.2608 180)
		(property "Reference" "R4724"
			(at 0 0 180)
			(layer "F.SilkS")
			(hide yes)
			(effects
				(font
					(size 1.27 1.27)
				)
			)
		)
		(property "Value" ""
			(at 0 0 180)
			(layer "F.Fab")
			(effects
				(font
					(size 1.27 1.27)
				)
			)
		)
		(duplicate_pad_numbers_are_jumpers no)
		(fp_line
			(start 0.7874 0.4064)
			(end -0.7874 0.4064)
			(stroke
				(width 0.1524)
				(type default)
			)
			(layer "F.SilkS")
		)
		(fp_line
			(start 0.7874 -0.4064)
			(end 0.7874 0.4064)
			(stroke
				(width 0.1524)
				(type default)
			)
			(layer "F.SilkS")
		)
		(fp_line
			(start -0.7874 0.4064)
			(end -0.7874 -0.4064)
			(stroke
				(width 0.1524)
				(type default)
			)
			(layer "F.SilkS")
		)
		(fp_line
			(start -0.7874 -0.4064)
			(end 0.7874 -0.4064)
			(stroke
				(width 0.1524)
				(type default)
			)
			(layer "F.SilkS")
		)
		(fp_line
			(start 0.67945 0.3048)
			(end 0.120396 0.3048)
			(stroke
				(width 0.1)
				(type default)
			)
			(layer "F.Fab")
		)
		(fp_line
			(start 0.67945 -0.3048)
			(end 0.67945 0.3048)
			(stroke
				(width 0.1)
				(type default)
			)
			(layer "F.Fab")
		)
		(fp_line
			(start 0.12065 -0.2794)
			(end 0.12065 -0.3048)
			(stroke
				(width 0.1)
				(type default)
			)
			(layer "F.Fab")
		)
		(fp_line
			(start 0.12065 -0.3048)
			(end 0.67945 -0.3048)
			(stroke
				(width 0.1)
				(type default)
			)
			(layer "F.Fab")
		)
		(fp_line
			(start 0.120396 0.3048)
			(end 0.120396 0.2794)
			(stroke
				(width 0.1)
				(type default)
			)
			(layer "F.Fab")
		)
		(fp_line
			(start 0.120396 0.2794)
			(end -0.12065 0.2794)
			(stroke
				(width 0.1)
				(type default)
			)
			(layer "F.Fab")
		)
		(fp_line
			(start -0.12065 0.3048)
			(end -0.67945 0.3048)
			(stroke
				(width 0.1)
				(type default)
			)
			(layer "F.Fab")
		)
		(fp_line
			(start -0.12065 0.2794)
			(end -0.12065 0.3048)
			(stroke
				(width 0.1)
				(type default)
			)
			(layer "F.Fab")
		)
		(fp_line
			(start -0.12065 -0.2794)
			(end 0.12065 -0.2794)
			(stroke
				(width 0.1)
				(type default)
			)
			(layer "F.Fab")
		)
		(fp_line
			(start -0.12065 -0.305054)
			(end -0.12065 -0.2794)
			(stroke
				(width 0.1)
				(type default)
			)
			(layer "F.Fab")
		)
		(fp_line
			(start -0.67945 0.3048)
			(end -0.67945 -0.305054)
			(stroke
				(width 0.1)
				(type default)
			)
			(layer "F.Fab")
		)
		(fp_line
			(start -0.67945 -0.305054)
			(end -0.12065 -0.305054)
			(stroke
				(width 0.1)
				(type default)
			)
			(layer "F.Fab")
		)
		(pad "1" smd circle
			(at -0.40005 0 180)
			(size 0 0)
			(layers "F.Cu" "F.Mask" "F.Paste")
			(net "PRSNT_SWB_N")
		)
		(pad "2" smd circle
			(at 0.40005 0 180)
			(size 0 0)
			(layers "F.Cu" "F.Mask" "F.Paste")
			(net "GND")
		)
	)
	(footprint ""
		(layer "F.Cu")
		(at 123.192794 -402.371052 -90)
		(property "Reference" "C745"
			(at 0 0 270)
			(layer "F.SilkS")
			(hide yes)
			(effects
				(font
					(size 1.27 1.27)
				)
			)
		)
		(property "Value" ""
			(at 0 0 270)
			(layer "F.Fab")
			(effects
				(font
					(size 1.27 1.27)
				)
			)
		)
		(duplicate_pad_numbers_are_jumpers no)
		(fp_line
			(start -0.299974 0.150114)
			(end -0.299974 -0.150114)
			(stroke
				(width 0.1)
				(type default)
			)
			(layer "F.Fab")
		)
		(fp_line
			(start 0.299974 0.150114)
			(end -0.299974 0.150114)
			(stroke
				(width 0.1)
				(type default)
			)
			(layer "F.Fab")
		)
		(fp_line
			(start -0.299974 -0.150114)
			(end 0.299974 -0.150114)
			(stroke
				(width 0.1)
				(type default)
			)
			(layer "F.Fab")
		)
		(fp_line
			(start 0.299974 -0.150114)
			(end 0.299974 0.150114)
			(stroke
				(width 0.1)
				(type default)
			)
			(layer "F.Fab")
		)
		(pad "1" smd rect
			(at -0.2667 0 270)
			(size 0.3048 0.381)
			(layers "F.Cu" "F.Mask" "F.Paste")
			(net "P5E_CPU1_PE2_TX_C_DP<14>")
		)
		(pad "2" smd rect
			(at 0.2667 0 270)
			(size 0.3048 0.381)
			(layers "F.Cu" "F.Mask" "F.Paste")
			(net "P5E_CPU1_PE2_TX_DP<14>")
		)
	)
	(footprint ""
		(layer "F.Cu")
		(at 290.457382 -375.745502)
		(property "Reference" "PC1653"
			(at 0 0 0)
			(layer "F.SilkS")
			(hide yes)
			(effects
				(font
					(size 1.27 1.27)
				)
			)
		)
		(property "Value" ""
			(at 0 0 0)
			(layer "F.Fab")
			(effects
				(font
					(size 1.27 1.27)
				)
			)
		)
		(duplicate_pad_numbers_are_jumpers no)
		(fp_line
			(start -0.7874 -0.4064)
			(end 0.7874 -0.4064)
			(stroke
				(width 0.1524)
				(type default)
			)
			(layer "F.SilkS")
		)
		(fp_line
			(start -0.7874 0.4064)
			(end -0.7874 -0.4064)
			(stroke
				(width 0.1524)
				(type default)
			)
			(layer "F.SilkS")
		)
		(fp_line
			(start 0.7874 -0.4064)
			(end 0.7874 0.4064)
			(stroke
				(width 0.1524)
				(type default)
			)
			(layer "F.SilkS")
		)
		(fp_line
			(start 0.7874 0.4064)
			(end -0.7874 0.4064)
			(stroke
				(width 0.1524)
				(type default)
			)
			(layer "F.SilkS")
		)
		(fp_line
			(start -0.67945 -0.305054)
			(end -0.12065 -0.305054)
			(stroke
				(width 0.1)
				(type default)
			)
			(layer "F.Fab")
		)
		(fp_line
			(start -0.67945 0.3048)
			(end -0.67945 -0.305054)
			(stroke
				(width 0.1)
				(type default)
			)
			(layer "F.Fab")
		)
		(fp_line
			(start -0.12065 -0.305054)
			(end -0.12065 -0.2794)
			(stroke
				(width 0.1)
				(type default)
			)
			(layer "F.Fab")
		)
		(fp_line
			(start -0.12065 -0.2794)
			(end 0.12065 -0.2794)
			(stroke
				(width 0.1)
				(type default)
			)
			(layer "F.Fab")
		)
		(fp_line
			(start -0.12065 0.2794)
			(end -0.12065 0.3048)
			(stroke
				(width 0.1)
				(type default)
			)
			(layer "F.Fab")
		)
		(fp_line
			(start -0.12065 0.3048)
			(end -0.67945 0.3048)
			(stroke
				(width 0.1)
				(type default)
			)
			(layer "F.Fab")
		)
		(fp_line
			(start 0.120396 0.2794)
			(end -0.12065 0.2794)
			(stroke
				(width 0.1)
				(type default)
			)
			(layer "F.Fab")
		)
		(fp_line
			(start 0.120396 0.3048)
			(end 0.120396 0.2794)
			(stroke
				(width 0.1)
				(type default)
			)
			(layer "F.Fab")
		)
		(fp_line
			(start 0.12065 -0.3048)
			(end 0.67945 -0.3048)
			(stroke
				(width 0.1)
				(type default)
			)
			(layer "F.Fab")
		)
		(fp_line
			(start 0.12065 -0.2794)
			(end 0.12065 -0.3048)
			(stroke
				(width 0.1)
				(type default)
			)
			(layer "F.Fab")
		)
		(fp_line
			(start 0.67945 -0.3048)
			(end 0.67945 0.3048)
			(stroke
				(width 0.1)
				(type default)
			)
			(layer "F.Fab")
		)
		(fp_line
			(start 0.67945 0.3048)
			(end 0.120396 0.3048)
			(stroke
				(width 0.1)
				(type default)
			)
			(layer "F.Fab")
		)
		(pad "1" smd circle
			(at -0.40005 0)
			(size 0 0)
			(layers "F.Cu" "F.Mask" "F.Paste")
			(net "P12V_AUX")
		)
		(pad "2" smd circle
			(at 0.40005 0)
			(size 0 0)
			(layers "F.Cu" "F.Mask" "F.Paste")
			(net "GND")
		)
	)
	(footprint ""
		(layer "F.Cu")
		(at 379.36551 -341.729822 -90)
		(property "Reference" "PC257"
			(at 0 0 270)
			(layer "F.SilkS")
			(hide yes)
			(effects
				(font
					(size 1.27 1.27)
				)
			)
		)
		(property "Value" ""
			(at 0 0 270)
			(layer "F.Fab")
			(effects
				(font
					(size 1.27 1.27)
				)
			)
		)
		(duplicate_pad_numbers_are_jumpers no)
		(fp_line
			(start -0.7874 0.4064)
			(end -0.7874 -0.4064)
			(stroke
				(width 0.1524)
				(type default)
			)
			(layer "F.SilkS")
		)
		(fp_line
			(start 0.7874 0.4064)
			(end -0.7874 0.4064)
			(stroke
				(width 0.1524)
				(type default)
			)
			(layer "F.SilkS")
		)
		(fp_line
			(start -0.7874 -0.4064)
			(end 0.7874 -0.4064)
			(stroke
				(width 0.1524)
				(type default)
			)
			(layer "F.SilkS")
		)
		(fp_line
			(start 0.7874 -0.4064)
			(end 0.7874 0.4064)
			(stroke
				(width 0.1524)
				(type default)
			)
			(layer "F.SilkS")
		)
		(fp_line
			(start -0.67945 0.3048)
			(end -0.67945 -0.305054)
			(stroke
				(width 0.1)
				(type default)
			)
			(layer "F.Fab")
		)
		(fp_line
			(start -0.12065 0.3048)
			(end -0.67945 0.3048)
			(stroke
				(width 0.1)
				(type default)
			)
			(layer "F.Fab")
		)
		(fp_line
			(start 0.120396 0.3048)
			(end 0.120396 0.2794)
			(stroke
				(width 0.1)
				(type default)
			)
			(layer "F.Fab")
		)
		(fp_line
			(start 0.67945 0.3048)
			(end 0.120396 0.3048)
			(stroke
				(width 0.1)
				(type default)
			)
			(layer "F.Fab")
		)
		(fp_line
			(start -0.12065 0.2794)
			(end -0.12065 0.3048)
			(stroke
				(width 0.1)
				(type default)
			)
			(layer "F.Fab")
		)
		(fp_line
			(start 0.120396 0.2794)
			(end -0.12065 0.2794)
			(stroke
				(width 0.1)
				(type default)
			)
			(layer "F.Fab")
		)
		(fp_line
			(start -0.12065 -0.2794)
			(end 0.12065 -0.2794)
			(stroke
				(width 0.1)
				(type default)
			)
			(layer "F.Fab")
		)
		(fp_line
			(start 0.12065 -0.2794)
			(end 0.12065 -0.3048)
			(stroke
				(width 0.1)
				(type default)
			)
			(layer "F.Fab")
		)
		(fp_line
			(start 0.12065 -0.3048)
			(end 0.67945 -0.3048)
			(stroke
				(width 0.1)
				(type default)
			)
			(layer "F.Fab")
		)
		(fp_line
			(start 0.67945 -0.3048)
			(end 0.67945 0.3048)
			(stroke
				(width 0.1)
				(type default)
			)
			(layer "F.Fab")
		)
		(fp_line
			(start -0.67945 -0.305054)
			(end -0.12065 -0.305054)
			(stroke
				(width 0.1)
				(type default)
			)
			(layer "F.Fab")
		)
		(fp_line
			(start -0.12065 -0.305054)
			(end -0.12065 -0.2794)
			(stroke
				(width 0.1)
				(type default)
			)
			(layer "F.Fab")
		)
		(pad "1" smd circle
			(at -0.40005 0 270)
			(size 0 0)
			(layers "F.Cu" "F.Mask" "F.Paste")
			(net "SW_PVCCIN_CPU0_BOOT5_R")
		)
		(pad "2" smd circle
			(at 0.40005 0 270)
			(size 0 0)
			(layers "F.Cu" "F.Mask" "F.Paste")
			(net "SW_PVCCIN_CPU0_BOOTR5")
		)
	)
	(footprint ""
		(layer "F.Cu")
		(at 408.15641 -402.371052 -90)
		(property "Reference" "C959"
			(at 0 0 270)
			(layer "F.SilkS")
			(hide yes)
			(effects
				(font
					(size 1.27 1.27)
				)
			)
		)
		(property "Value" ""
			(at 0 0 270)
			(layer "F.Fab")
			(effects
				(font
					(size 1.27 1.27)
				)
			)
		)
		(duplicate_pad_numbers_are_jumpers no)
		(fp_line
			(start -0.299974 0.150114)
			(end -0.299974 -0.150114)
			(stroke
				(width 0.1)
				(type default)
			)
			(layer "F.Fab")
		)
		(fp_line
			(start 0.299974 0.150114)
			(end -0.299974 0.150114)
			(stroke
				(width 0.1)
				(type default)
			)
			(layer "F.Fab")
		)
		(fp_line
			(start -0.299974 -0.150114)
			(end 0.299974 -0.150114)
			(stroke
				(width 0.1)
				(type default)
			)
			(layer "F.Fab")
		)
		(fp_line
			(start 0.299974 -0.150114)
			(end 0.299974 0.150114)
			(stroke
				(width 0.1)
				(type default)
			)
			(layer "F.Fab")
		)
		(pad "1" smd rect
			(at -0.2667 0 270)
			(size 0.3048 0.381)
			(layers "F.Cu" "F.Mask" "F.Paste")
			(net "P5E_CPU0_PE2_TX_C_DP<3>")
		)
		(pad "2" smd rect
			(at 0.2667 0 270)
			(size 0.3048 0.381)
			(layers "F.Cu" "F.Mask" "F.Paste")
			(net "P5E_CPU0_PE2_TX_DP<3>")
		)
	)
	(footprint ""
		(layer "F.Cu")
		(at 190.291466 -126.963678 -90)
		(property "Reference" "R4600"
			(at 0 0 270)
			(layer "F.SilkS")
			(hide yes)
			(effects
				(font
					(size 1.27 1.27)
				)
			)
		)
		(property "Value" ""
			(at 0 0 270)
			(layer "F.Fab")
			(effects
				(font
					(size 1.27 1.27)
				)
			)
		)
		(duplicate_pad_numbers_are_jumpers no)
		(fp_line
			(start -0.7874 0.4064)
			(end -0.7874 -0.4064)
			(stroke
				(width 0.1524)
				(type default)
			)
			(layer "F.SilkS")
		)
		(fp_line
			(start 0.7874 0.4064)
			(end -0.7874 0.4064)
			(stroke
				(width 0.1524)
				(type default)
			)
			(layer "F.SilkS")
		)
		(fp_line
			(start -0.7874 -0.4064)
			(end 0.7874 -0.4064)
			(stroke
				(width 0.1524)
				(type default)
			)
			(layer "F.SilkS")
		)
		(fp_line
			(start 0.7874 -0.4064)
			(end 0.7874 0.4064)
			(stroke
				(width 0.1524)
				(type default)
			)
			(layer "F.SilkS")
		)
		(fp_line
			(start -0.67945 0.3048)
			(end -0.67945 -0.305054)
			(stroke
				(width 0.1)
				(type default)
			)
			(layer "F.Fab")
		)
		(fp_line
			(start -0.12065 0.3048)
			(end -0.67945 0.3048)
			(stroke
				(width 0.1)
				(type default)
			)
			(layer "F.Fab")
		)
		(fp_line
			(start 0.120396 0.3048)
			(end 0.120396 0.2794)
			(stroke
				(width 0.1)
				(type default)
			)
			(layer "F.Fab")
		)
		(fp_line
			(start 0.67945 0.3048)
			(end 0.120396 0.3048)
			(stroke
				(width 0.1)
				(type default)
			)
			(layer "F.Fab")
		)
		(fp_line
			(start -0.12065 0.2794)
			(end -0.12065 0.3048)
			(stroke
				(width 0.1)
				(type default)
			)
			(layer "F.Fab")
		)
		(fp_line
			(start 0.120396 0.2794)
			(end -0.12065 0.2794)
			(stroke
				(width 0.1)
				(type default)
			)
			(layer "F.Fab")
		)
		(fp_line
			(start -0.12065 -0.2794)
			(end 0.12065 -0.2794)
			(stroke
				(width 0.1)
				(type default)
			)
			(layer "F.Fab")
		)
		(fp_line
			(start 0.12065 -0.2794)
			(end 0.12065 -0.3048)
			(stroke
				(width 0.1)
				(type default)
			)
			(layer "F.Fab")
		)
		(fp_line
			(start 0.12065 -0.3048)
			(end 0.67945 -0.3048)
			(stroke
				(width 0.1)
				(type default)
			)
			(layer "F.Fab")
		)
		(fp_line
			(start 0.67945 -0.3048)
			(end 0.67945 0.3048)
			(stroke
				(width 0.1)
				(type default)
			)
			(layer "F.Fab")
		)
		(fp_line
			(start -0.67945 -0.305054)
			(end -0.12065 -0.305054)
			(stroke
				(width 0.1)
				(type default)
			)
			(layer "F.Fab")
		)
		(fp_line
			(start -0.12065 -0.305054)
			(end -0.12065 -0.2794)
			(stroke
				(width 0.1)
				(type default)
			)
			(layer "F.Fab")
		)
		(pad "1" smd circle
			(at -0.40005 0 270)
			(size 0 0)
			(layers "F.Cu" "F.Mask" "F.Paste")
			(net "HP_LVC3_OCP_V3_1_P12V_PWRGD")
		)
		(pad "2" smd circle
			(at 0.40005 0 270)
			(size 0 0)
			(layers "F.Cu" "F.Mask" "F.Paste")
			(net "HP_LVC3_OCP_V3_1_HSC_PWRGD_PLD_")
		)
	)
	(footprint ""
		(layer "F.Cu")
		(at 116.71808 -393.937998 90)
		(property "Reference" "R3029"
			(at 0 0 90)
			(layer "F.SilkS")
			(hide yes)
			(effects
				(font
					(size 1.27 1.27)
				)
			)
		)
		(property "Value" ""
			(at 0 0 90)
			(layer "F.Fab")
			(effects
				(font
					(size 1.27 1.27)
				)
			)
		)
		(duplicate_pad_numbers_are_jumpers no)
		(fp_line
			(start 0.7874 -0.4064)
			(end 0.7874 0.4064)
			(stroke
				(width 0.1524)
				(type default)
			)
			(layer "F.SilkS")
		)
		(fp_line
			(start -0.7874 -0.4064)
			(end 0.7874 -0.4064)
			(stroke
				(width 0.1524)
				(type default)
			)
			(layer "F.SilkS")
		)
		(fp_line
			(start 0.7874 0.4064)
			(end -0.7874 0.4064)
			(stroke
				(width 0.1524)
				(type default)
			)
			(layer "F.SilkS")
		)
		(fp_line
			(start -0.7874 0.4064)
			(end -0.7874 -0.4064)
			(stroke
				(width 0.1524)
				(type default)
			)
			(layer "F.SilkS")
		)
		(fp_line
			(start -0.12065 -0.305054)
			(end -0.12065 -0.2794)
			(stroke
				(width 0.1)
				(type default)
			)
			(layer "F.Fab")
		)
		(fp_line
			(start -0.67945 -0.305054)
			(end -0.12065 -0.305054)
			(stroke
				(width 0.1)
				(type default)
			)
			(layer "F.Fab")
		)
		(fp_line
			(start 0.67945 -0.3048)
			(end 0.67945 0.3048)
			(stroke
				(width 0.1)
				(type default)
			)
			(layer "F.Fab")
		)
		(fp_line
			(start 0.12065 -0.3048)
			(end 0.67945 -0.3048)
			(stroke
				(width 0.1)
				(type default)
			)
			(layer "F.Fab")
		)
		(fp_line
			(start 0.12065 -0.2794)
			(end 0.12065 -0.3048)
			(stroke
				(width 0.1)
				(type default)
			)
			(layer "F.Fab")
		)
		(fp_line
			(start -0.12065 -0.2794)
			(end 0.12065 -0.2794)
			(stroke
				(width 0.1)
				(type default)
			)
			(layer "F.Fab")
		)
		(fp_line
			(start 0.120396 0.2794)
			(end -0.12065 0.2794)
			(stroke
				(width 0.1)
				(type default)
			)
			(layer "F.Fab")
		)
		(fp_line
			(start -0.12065 0.2794)
			(end -0.12065 0.3048)
			(stroke
				(width 0.1)
				(type default)
			)
			(layer "F.Fab")
		)
		(fp_line
			(start 0.67945 0.3048)
			(end 0.120396 0.3048)
			(stroke
				(width 0.1)
				(type default)
			)
			(layer "F.Fab")
		)
		(fp_line
			(start 0.120396 0.3048)
			(end 0.120396 0.2794)
			(stroke
				(width 0.1)
				(type default)
			)
			(layer "F.Fab")
		)
		(fp_line
			(start -0.12065 0.3048)
			(end -0.67945 0.3048)
			(stroke
				(width 0.1)
				(type default)
			)
			(layer "F.Fab")
		)
		(fp_line
			(start -0.67945 0.3048)
			(end -0.67945 -0.305054)
			(stroke
				(width 0.1)
				(type default)
			)
			(layer "F.Fab")
		)
		(pad "1" smd circle
			(at -0.40005 0 90)
			(size 0 0)
			(layers "F.Cu" "F.Mask" "F.Paste")
			(net "P3V3_AUX")
		)
		(pad "2" smd circle
			(at 0.40005 0 90)
			(size 0 0)
			(layers "F.Cu" "F.Mask" "F.Paste")
			(net "FM_SMB_1_ALERT_GPU")
		)
	)
	(footprint ""
		(layer "F.Cu")
		(at 210.840066 -402.722842 180)
		(property "Reference" "PU288"
			(at 0.323596 8.166608 0)
			(unlocked yes)
			(layer "F.SilkS")
			(effects
				(font
					(size 0.7874 0.5842)
					(thickness 0.1524)
				)
			)
		)
		(property "Value" ""
			(at 0 0 180)
			(layer "F.Fab")
			(effects
				(font
					(size 1.27 1.27)
				)
			)
		)
		(duplicate_pad_numbers_are_jumpers no)
		(fp_line
			(start 2.567686 2.567686)
			(end 2.567686 -2.567686)
			(stroke
				(width 0.1524)
				(type default)
			)
			(layer "F.SilkS")
		)
		(fp_line
			(start 2.567686 -2.567686)
			(end -2.567686 -2.567686)
			(stroke
				(width 0.1524)
				(type default)
			)
			(layer "F.SilkS")
		)
		(fp_line
			(start -2.567686 2.567686)
			(end 2.567686 2.567686)
			(stroke
				(width 0.1524)
				(type default)
			)
			(layer "F.SilkS")
		)
		(fp_line
			(start -2.567686 -2.567686)
			(end -2.567686 2.567686)
			(stroke
				(width 0.1524)
				(type default)
			)
			(layer "F.SilkS")
		)
		(fp_poly
			(pts
				(xy -3.120898 -3.448558) (xy -2.761742 -2.370836) (xy -3.83921 -2.729992)
			)
			(stroke
				(width 0)
				(type default)
			)
			(fill yes)
			(layer "F.SilkS")
		)
		(fp_line
			(start 2.549906 2.549906)
			(end 2.549906 -2.549906)
			(stroke
				(width 0.1)
				(type default)
			)
			(layer "F.Fab")
		)
		(fp_line
			(start 2.549906 -2.549906)
			(end -2.549906 -2.549906)
			(stroke
				(width 0.1)
				(type default)
			)
			(layer "F.Fab")
		)
		(fp_line
			(start -2.549906 2.549906)
			(end 2.549906 2.549906)
			(stroke
				(width 0.1)
				(type default)
			)
			(layer "F.Fab")
		)
		(fp_line
			(start -2.549906 -2.549906)
			(end -2.549906 2.549906)
			(stroke
				(width 0.1)
				(type default)
			)
			(layer "F.Fab")
		)
		(fp_poly
			(pts
				(xy -3.806698 -2.25806) (xy -3.806698 -1.24206) (xy -2.790698 -1.75006)
			)
			(stroke
				(width 0)
				(type default)
			)
			(fill yes)
			(layer "F.Fab")
		)
		(pad "1" smd rect
			(at -2.250186 -1.75006 270)
			(size 0.254 0.3556)
			(layers "F.Cu" "F.Mask" "F.Paste")
			(net "P12V_AUX")
		)
		(pad "2" smd rect
			(at -2.237486 -1.249934 270)
			(size 0.254 0.381)
			(layers "F.Cu" "F.Mask" "F.Paste")
			(net "P12V_AUX")
		)
		(pad "3" smd rect
			(at -2.237486 -0.750062 270)
			(size 0.254 0.381)
			(layers "F.Cu" "F.Mask" "F.Paste")
			(net "HSC_D_OC_2")
		)
		(pad "4" smd rect
			(at -2.237486 -0.249936 270)
			(size 0.254 0.381)
			(layers "F.Cu" "F.Mask" "F.Paste")
			(net "HSC_ON")
		)
		(pad "5" smd rect
			(at -2.237486 0.249936 270)
			(size 0.254 0.381)
			(layers "F.Cu" "F.Mask" "F.Paste")
			(net "HSC_FAULT")
		)
		(pad "6" smd rect
			(at -2.237486 0.750062 270)
			(size 0.254 0.381)
			(layers "F.Cu" "F.Mask" "F.Paste")
			(net "HSC_FLT_TYPE_2")
		)
		(pad "7" smd rect
			(at -2.237486 1.249934 270)
			(size 0.254 0.381)
			(layers "F.Cu" "F.Mask" "F.Paste")
			(net "HSC_NC1_2")
		)
		(pad "8" smd rect
			(at -2.250186 1.75006 270)
			(size 0.254 0.3556)
			(layers "F.Cu" "F.Mask" "F.Paste")
			(net "HSC_MODE_2")
		)
		(pad "9" smd rect
			(at -1.75006 2.250186 180)
			(size 0.254 0.3556)
			(layers "F.Cu" "F.Mask" "F.Paste")
			(net "P12V_PSU")
		)
		(pad "10" smd rect
			(at -1.249934 2.237486 180)
			(size 0.254 0.381)
			(layers "F.Cu" "F.Mask" "F.Paste")
			(net "P12V_PSU")
		)
		(pad "11" smd rect
			(at -0.750062 2.237486 180)
			(size 0.254 0.381)
			(layers "F.Cu" "F.Mask" "F.Paste")
			(net "P12V_PSU")
		)
		(pad "12" smd rect
			(at -0.249936 2.237486 180)
			(size 0.254 0.381)
			(layers "F.Cu" "F.Mask" "F.Paste")
			(net "P12V_PSU")
		)
		(pad "13" smd rect
			(at 0.249936 2.237486 180)
			(size 0.254 0.381)
			(layers "F.Cu" "F.Mask" "F.Paste")
			(net "P12V_PSU")
		)
		(pad "14" smd rect
			(at 0.750062 2.237486 180)
			(size 0.254 0.381)
			(layers "F.Cu" "F.Mask" "F.Paste")
			(net "P12V_PSU")
		)
		(pad "15" smd rect
			(at 1.249934 2.237486 180)
			(size 0.254 0.381)
			(layers "F.Cu" "F.Mask" "F.Paste")
			(net "P12V_PSU")
		)
		(pad "16" smd rect
			(at 1.75006 2.250186 180)
			(size 0.254 0.3556)
			(layers "F.Cu" "F.Mask" "F.Paste")
			(net "P12V_PSU")
		)
		(pad "17" smd rect
			(at 2.250186 1.75006 270)
			(size 0.254 0.3556)
			(layers "F.Cu" "F.Mask" "F.Paste")
			(net "HSC_SCREF_2")
		)
		(pad "18" smd rect
			(at 2.237486 1.249934 270)
			(size 0.254 0.381)
			(layers "F.Cu" "F.Mask" "F.Paste")
			(net "HSC_VTEMP")
		)
		(pad "19" smd rect
			(at 2.237486 0.750062 270)
			(size 0.254 0.381)
			(layers "F.Cu" "F.Mask" "F.Paste")
			(net "HSC_SS")
		)
		(pad "20" smd rect
			(at 2.237486 0.249936 270)
			(size 0.254 0.381)
			(layers "F.Cu" "F.Mask" "F.Paste")
			(net "AGND_HSC")
		)
		(pad "21" smd rect
			(at 2.237486 -0.249936 270)
			(size 0.254 0.381)
			(layers "F.Cu" "F.Mask" "F.Paste")
			(net "HSC_VDD_R_2")
		)
		(pad "22" smd rect
			(at 2.237486 -0.750062 270)
			(size 0.254 0.381)
			(layers "F.Cu" "F.Mask" "F.Paste")
			(net "HSC_IMON")
		)
		(pad "23" smd rect
			(at 2.237486 -1.249934 270)
			(size 0.254 0.381)
			(layers "F.Cu" "F.Mask" "F.Paste")
			(net "HSC_CS_2")
		)
		(pad "24" smd rect
			(at 2.250186 -1.75006 270)
			(size 0.254 0.3556)
			(layers "F.Cu" "F.Mask" "F.Paste")
			(net "HSC_OCREF")
		)
		(pad "25" smd rect
			(at 1.75006 -2.250186 180)
			(size 0.254 0.3556)
			(layers "F.Cu" "F.Mask" "F.Paste")
			(net "P12V_AUX")
		)
		(pad "26" smd rect
			(at 1.249934 -2.237486 180)
			(size 0.254 0.381)
			(layers "F.Cu" "F.Mask" "F.Paste")
			(net "P12V_AUX")
		)
		(pad "27" smd rect
			(at 0.750062 -2.237486 180)
			(size 0.254 0.381)
			(layers "F.Cu" "F.Mask" "F.Paste")
			(net "P12V_AUX")
		)
		(pad "28" smd rect
			(at 0.249936 -2.237486 180)
			(size 0.254 0.381)
			(layers "F.Cu" "F.Mask" "F.Paste")
			(net "P12V_AUX")
		)
		(pad "29" smd rect
			(at -0.249936 -2.237486 180)
			(size 0.254 0.381)
			(layers "F.Cu" "F.Mask" "F.Paste")
			(net "P12V_AUX")
		)
		(pad "30" smd rect
			(at -0.750062 -2.237486 180)
			(size 0.254 0.381)
			(layers "F.Cu" "F.Mask" "F.Paste")
			(net "P12V_AUX")
		)
		(pad "31" smd rect
			(at -1.249934 -2.237486 180)
			(size 0.254 0.381)
			(layers "F.Cu" "F.Mask" "F.Paste")
			(net "P12V_AUX")
		)
		(pad "32" smd rect
			(at -1.75006 -2.250186 180)
			(size 0.254 0.3556)
			(layers "F.Cu" "F.Mask" "F.Paste")
			(net "P12V_AUX")
		)
		(pad "33" smd rect
			(at 0 0 180)
			(size 3.4036 3.4036)
			(layers "F.Cu" "F.Mask" "F.Paste")
			(net "P12V_PSU")
		)
		(zone
			(layer "F.Cu")
			(hatch none 0.5)
			(connect_pads
				(clearance 0)
			)
			(min_thickness 0.25)
			(keepout
				(tracks not_allowed)
				(vias allowed)
				(pads allowed)
				(copperpour not_allowed)
				(footprints allowed)
			)
			(placement
				(enabled no)
				(sheetname "")
			)
			(fill
				(thermal_gap 0.5)
				(thermal_bridge_width 0.5)
				(island_removal_mode 0)
			)
			(polygon
				(pts
					(xy 212.861652 -401.275042) (xy 212.861652 -400.815048) (xy 212.74786 -400.701256) (xy 212.287866 -400.701256)
					(xy 212.287866 -400.726656) (xy 209.392266 -400.726656) (xy 209.392266 -400.701256) (xy 208.81848 -400.701256)
					(xy 208.81848 -401.275042) (xy 208.84388 -401.275042) (xy 208.84388 -404.170642) (xy 208.81848 -404.170642)
					(xy 208.81848 -404.475442) (xy 209.087466 -404.475442) (xy 209.087466 -400.970242) (xy 212.592666 -400.970242)
					(xy 212.592666 -403.230842) (xy 212.836252 -403.230842) (xy 212.836252 -401.275042)
				)
			)
		)
	)
	(footprint ""
		(layer "F.Cu")
		(at 131.68122 -75.85837 -90)
		(property "Reference" "D141"
			(at -4.793488 -2.42316 0)
			(unlocked yes)
			(layer "F.SilkS")
			(effects
				(font
					(size 0.7874 0.5842)
					(thickness 0.1524)
				)
				(justify left)
			)
		)
		(property "Value" ""
			(at 0 0 270)
			(layer "F.Fab")
			(effects
				(font
					(size 1.27 1.27)
				)
			)
		)
		(duplicate_pad_numbers_are_jumpers no)
		(fp_line
			(start -2.4638 1.0414)
			(end -2.4638 -1.0414)
			(stroke
				(width 0.1524)
				(type default)
			)
			(layer "F.SilkS")
		)
		(fp_line
			(start 2.7178 1.0414)
			(end -2.4638 1.0414)
			(stroke
				(width 0.1524)
				(type default)
			)
			(layer "F.SilkS")
		)
		(fp_line
			(start -0.508 0.5334)
			(end 0.1778 -0.0254)
			(stroke
				(width 0.1524)
				(type default)
			)
			(layer "F.SilkS")
		)
		(fp_line
			(start 0.1778 -0.0254)
			(end -0.4826 -0.4826)
			(stroke
				(width 0.1524)
				(type default)
			)
			(layer "F.SilkS")
		)
		(fp_line
			(start -0.508 -0.508)
			(end -0.508 0.5334)
			(stroke
				(width 0.1524)
				(type default)
			)
			(layer "F.SilkS")
		)
		(fp_line
			(start 0.254 -0.508)
			(end 0.254 0.5334)
			(stroke
				(width 0.1524)
				(type default)
			)
			(layer "F.SilkS")
		)
		(fp_line
			(start -2.4638 -1.0414)
			(end 2.7178 -1.0414)
			(stroke
				(width 0.1524)
				(type default)
			)
			(layer "F.SilkS")
		)
		(fp_line
			(start 2.4638 -1.0414)
			(end 2.4638 1.0414)
			(stroke
				(width 0.1524)
				(type default)
			)
			(layer "F.SilkS")
		)
		(fp_line
			(start 2.5908 -1.0414)
			(end 2.5908 1.0414)
			(stroke
				(width 0.1524)
				(type default)
			)
			(layer "F.SilkS")
		)
		(fp_line
			(start 2.7178 -1.0414)
			(end 2.7178 1.0414)
			(stroke
				(width 0.1524)
				(type default)
			)
			(layer "F.SilkS")
		)
		(fp_line
			(start -2.4638 1.0414)
			(end -2.4638 -1.0414)
			(stroke
				(width 0.1)
				(type default)
			)
			(layer "F.Fab")
		)
		(fp_line
			(start 2.7178 1.0414)
			(end -2.4638 1.0414)
			(stroke
				(width 0.1)
				(type default)
			)
			(layer "F.Fab")
		)
		(fp_line
			(start -2.4638 -1.0414)
			(end 2.7178 -1.0414)
			(stroke
				(width 0.1)
				(type default)
			)
			(layer "F.Fab")
		)
		(fp_line
			(start 2.7178 -1.0414)
			(end 2.7178 1.0414)
			(stroke
				(width 0.1)
				(type default)
			)
			(layer "F.Fab")
		)
		(fp_text user "-"
			(at 2.538222 1.24841 270)
			(unlocked yes)
			(layer "F.SilkS")
			(effects
				(font
					(size 1.905 1.4224)
					(thickness 0.1524)
				)
				(justify left)
			)
		)
		(fp_text user "+"
			(at -3.9624 -0.17145 270)
			(unlocked yes)
			(layer "F.SilkS")
			(effects
				(font
					(size 1.905 1.4224)
					(thickness 0.1524)
				)
				(justify left)
			)
		)
		(fp_text user "+"
			(at -3.9624 -0.17145 270)
			(unlocked yes)
			(layer "F.Fab")
			(effects
				(font
					(size 1.905 1.4224)
					(thickness 0.1524)
				)
				(justify left)
			)
		)
		(fp_text user "-"
			(at 2.9845 -0.366268 270)
			(unlocked yes)
			(layer "F.Fab")
			(effects
				(font
					(size 1.905 1.4224)
					(thickness 0.1524)
				)
				(justify left)
			)
		)
		(pad "1" smd rect
			(at -1.724914 0 270)
			(size 1.1684 1.7526)
			(layers "F.Cu" "F.Mask" "F.Paste")
			(net "P3V3_AUX")
		)
		(pad "2" smd rect
			(at 1.724914 0 270)
			(size 1.1684 1.7526)
			(layers "F.Cu" "F.Mask" "F.Paste")
			(net "P3V3_AUX_BMC_D")
		)
	)
	(footprint ""
		(layer "F.Cu")
		(at 111.095282 -406.058116 -90)
		(property "Reference" "R3494"
			(at 0 0 270)
			(layer "F.SilkS")
			(hide yes)
			(effects
				(font
					(size 1.27 1.27)
				)
			)
		)
		(property "Value" ""
			(at 0 0 270)
			(layer "F.Fab")
			(effects
				(font
					(size 1.27 1.27)
				)
			)
		)
		(duplicate_pad_numbers_are_jumpers no)
		(fp_line
			(start -0.7874 0.4064)
			(end -0.7874 -0.4064)
			(stroke
				(width 0.1524)
				(type default)
			)
			(layer "F.SilkS")
		)
		(fp_line
			(start 0.7874 0.4064)
			(end -0.7874 0.4064)
			(stroke
				(width 0.1524)
				(type default)
			)
			(layer "F.SilkS")
		)
		(fp_line
			(start -0.7874 -0.4064)
			(end 0.7874 -0.4064)
			(stroke
				(width 0.1524)
				(type default)
			)
			(layer "F.SilkS")
		)
		(fp_line
			(start 0.7874 -0.4064)
			(end 0.7874 0.4064)
			(stroke
				(width 0.1524)
				(type default)
			)
			(layer "F.SilkS")
		)
		(fp_line
			(start -0.67945 0.3048)
			(end -0.67945 -0.305054)
			(stroke
				(width 0.1)
				(type default)
			)
			(layer "F.Fab")
		)
		(fp_line
			(start -0.12065 0.3048)
			(end -0.67945 0.3048)
			(stroke
				(width 0.1)
				(type default)
			)
			(layer "F.Fab")
		)
		(fp_line
			(start 0.120396 0.3048)
			(end 0.120396 0.2794)
			(stroke
				(width 0.1)
				(type default)
			)
			(layer "F.Fab")
		)
		(fp_line
			(start 0.67945 0.3048)
			(end 0.120396 0.3048)
			(stroke
				(width 0.1)
				(type default)
			)
			(layer "F.Fab")
		)
		(fp_line
			(start -0.12065 0.2794)
			(end -0.12065 0.3048)
			(stroke
				(width 0.1)
				(type default)
			)
			(layer "F.Fab")
		)
		(fp_line
			(start 0.120396 0.2794)
			(end -0.12065 0.2794)
			(stroke
				(width 0.1)
				(type default)
			)
			(layer "F.Fab")
		)
		(fp_line
			(start -0.12065 -0.2794)
			(end 0.12065 -0.2794)
			(stroke
				(width 0.1)
				(type default)
			)
			(layer "F.Fab")
		)
		(fp_line
			(start 0.12065 -0.2794)
			(end 0.12065 -0.3048)
			(stroke
				(width 0.1)
				(type default)
			)
			(layer "F.Fab")
		)
		(fp_line
			(start 0.12065 -0.3048)
			(end 0.67945 -0.3048)
			(stroke
				(width 0.1)
				(type default)
			)
			(layer "F.Fab")
		)
		(fp_line
			(start 0.67945 -0.3048)
			(end 0.67945 0.3048)
			(stroke
				(width 0.1)
				(type default)
			)
			(layer "F.Fab")
		)
		(fp_line
			(start -0.67945 -0.305054)
			(end -0.12065 -0.305054)
			(stroke
				(width 0.1)
				(type default)
			)
			(layer "F.Fab")
		)
		(fp_line
			(start -0.12065 -0.305054)
			(end -0.12065 -0.2794)
			(stroke
				(width 0.1)
				(type default)
			)
			(layer "F.Fab")
		)
		(pad "1" smd circle
			(at -0.40005 0 270)
			(size 0 0)
			(layers "F.Cu" "F.Mask" "F.Paste")
			(net "P3V3_AUX")
		)
		(pad "2" smd circle
			(at 0.40005 0 270)
			(size 0 0)
			(layers "F.Cu" "F.Mask" "F.Paste")
			(net "GPU_FPGA_EROT_RECOV_BUF_R_N")
		)
	)
	(footprint ""
		(layer "F.Cu")
		(at 49.347882 -393.30122 180)
		(property "Reference" "R4643"
			(at 0 0 180)
			(layer "F.SilkS")
			(hide yes)
			(effects
				(font
					(size 1.27 1.27)
				)
			)
		)
		(property "Value" ""
			(at 0 0 180)
			(layer "F.Fab")
			(effects
				(font
					(size 1.27 1.27)
				)
			)
		)
		(duplicate_pad_numbers_are_jumpers no)
		(fp_line
			(start 0.7874 0.4064)
			(end -0.7874 0.4064)
			(stroke
				(width 0.1524)
				(type default)
			)
			(layer "F.SilkS")
		)
		(fp_line
			(start 0.7874 -0.4064)
			(end 0.7874 0.4064)
			(stroke
				(width 0.1524)
				(type default)
			)
			(layer "F.SilkS")
		)
		(fp_line
			(start -0.7874 0.4064)
			(end -0.7874 -0.4064)
			(stroke
				(width 0.1524)
				(type default)
			)
			(layer "F.SilkS")
		)
		(fp_line
			(start -0.7874 -0.4064)
			(end 0.7874 -0.4064)
			(stroke
				(width 0.1524)
				(type default)
			)
			(layer "F.SilkS")
		)
		(fp_line
			(start 0.67945 0.3048)
			(end 0.120396 0.3048)
			(stroke
				(width 0.1)
				(type default)
			)
			(layer "F.Fab")
		)
		(fp_line
			(start 0.67945 -0.3048)
			(end 0.67945 0.3048)
			(stroke
				(width 0.1)
				(type default)
			)
			(layer "F.Fab")
		)
		(fp_line
			(start 0.12065 -0.2794)
			(end 0.12065 -0.3048)
			(stroke
				(width 0.1)
				(type default)
			)
			(layer "F.Fab")
		)
		(fp_line
			(start 0.12065 -0.3048)
			(end 0.67945 -0.3048)
			(stroke
				(width 0.1)
				(type default)
			)
			(layer "F.Fab")
		)
		(fp_line
			(start 0.120396 0.3048)
			(end 0.120396 0.2794)
			(stroke
				(width 0.1)
				(type default)
			)
			(layer "F.Fab")
		)
		(fp_line
			(start 0.120396 0.2794)
			(end -0.12065 0.2794)
			(stroke
				(width 0.1)
				(type default)
			)
			(layer "F.Fab")
		)
		(fp_line
			(start -0.12065 0.3048)
			(end -0.67945 0.3048)
			(stroke
				(width 0.1)
				(type default)
			)
			(layer "F.Fab")
		)
		(fp_line
			(start -0.12065 0.2794)
			(end -0.12065 0.3048)
			(stroke
				(width 0.1)
				(type default)
			)
			(layer "F.Fab")
		)
		(fp_line
			(start -0.12065 -0.2794)
			(end 0.12065 -0.2794)
			(stroke
				(width 0.1)
				(type default)
			)
			(layer "F.Fab")
		)
		(fp_line
			(start -0.12065 -0.305054)
			(end -0.12065 -0.2794)
			(stroke
				(width 0.1)
				(type default)
			)
			(layer "F.Fab")
		)
		(fp_line
			(start -0.67945 0.3048)
			(end -0.67945 -0.305054)
			(stroke
				(width 0.1)
				(type default)
			)
			(layer "F.Fab")
		)
		(fp_line
			(start -0.67945 -0.305054)
			(end -0.12065 -0.305054)
			(stroke
				(width 0.1)
				(type default)
			)
			(layer "F.Fab")
		)
		(pad "1" smd circle
			(at -0.40005 0 180)
			(size 0 0)
			(layers "F.Cu" "F.Mask" "F.Paste")
			(net "P3V3_AUX")
		)
		(pad "2" smd circle
			(at 0.40005 0 180)
			(size 0 0)
			(layers "F.Cu" "F.Mask" "F.Paste")
			(net "FM_P2E_BUF2_VODA_DB")
		)
	)
	(footprint ""
		(layer "F.Cu")
		(at 176.63795 -353.62261 -90)
		(property "Reference" "PC397_P1_1"
			(at 0 0 270)
			(layer "F.SilkS")
			(hide yes)
			(effects
				(font
					(size 1.27 1.27)
				)
			)
		)
		(property "Value" ""
			(at 0 0 270)
			(layer "F.Fab")
			(effects
				(font
					(size 1.27 1.27)
				)
			)
		)
		(duplicate_pad_numbers_are_jumpers no)
		(fp_line
			(start -0.7874 0.4064)
			(end -0.7874 -0.4064)
			(stroke
				(width 0.1524)
				(type default)
			)
			(layer "F.SilkS")
		)
		(fp_line
			(start 0.7874 0.4064)
			(end -0.7874 0.4064)
			(stroke
				(width 0.1524)
				(type default)
			)
			(layer "F.SilkS")
		)
		(fp_line
			(start -0.7874 -0.4064)
			(end 0.7874 -0.4064)
			(stroke
				(width 0.1524)
				(type default)
			)
			(layer "F.SilkS")
		)
		(fp_line
			(start 0.7874 -0.4064)
			(end 0.7874 0.4064)
			(stroke
				(width 0.1524)
				(type default)
			)
			(layer "F.SilkS")
		)
		(fp_line
			(start -0.67945 0.3048)
			(end -0.67945 -0.305054)
			(stroke
				(width 0.1)
				(type default)
			)
			(layer "F.Fab")
		)
		(fp_line
			(start -0.12065 0.3048)
			(end -0.67945 0.3048)
			(stroke
				(width 0.1)
				(type default)
			)
			(layer "F.Fab")
		)
		(fp_line
			(start 0.120396 0.3048)
			(end 0.120396 0.2794)
			(stroke
				(width 0.1)
				(type default)
			)
			(layer "F.Fab")
		)
		(fp_line
			(start 0.67945 0.3048)
			(end 0.120396 0.3048)
			(stroke
				(width 0.1)
				(type default)
			)
			(layer "F.Fab")
		)
		(fp_line
			(start -0.12065 0.2794)
			(end -0.12065 0.3048)
			(stroke
				(width 0.1)
				(type default)
			)
			(layer "F.Fab")
		)
		(fp_line
			(start 0.120396 0.2794)
			(end -0.12065 0.2794)
			(stroke
				(width 0.1)
				(type default)
			)
			(layer "F.Fab")
		)
		(fp_line
			(start -0.12065 -0.2794)
			(end 0.12065 -0.2794)
			(stroke
				(width 0.1)
				(type default)
			)
			(layer "F.Fab")
		)
		(fp_line
			(start 0.12065 -0.2794)
			(end 0.12065 -0.3048)
			(stroke
				(width 0.1)
				(type default)
			)
			(layer "F.Fab")
		)
		(fp_line
			(start 0.12065 -0.3048)
			(end 0.67945 -0.3048)
			(stroke
				(width 0.1)
				(type default)
			)
			(layer "F.Fab")
		)
		(fp_line
			(start 0.67945 -0.3048)
			(end 0.67945 0.3048)
			(stroke
				(width 0.1)
				(type default)
			)
			(layer "F.Fab")
		)
		(fp_line
			(start -0.67945 -0.305054)
			(end -0.12065 -0.305054)
			(stroke
				(width 0.1)
				(type default)
			)
			(layer "F.Fab")
		)
		(fp_line
			(start -0.12065 -0.305054)
			(end -0.12065 -0.2794)
			(stroke
				(width 0.1)
				(type default)
			)
			(layer "F.Fab")
		)
		(pad "1" smd circle
			(at -0.40005 0 270)
			(size 0 0)
			(layers "F.Cu" "F.Mask" "F.Paste")
			(net "SW_P12V_PVCCFA_EHV_FIVRA_CPU1_R")
		)
		(pad "2" smd circle
			(at 0.40005 0 270)
			(size 0 0)
			(layers "F.Cu" "F.Mask" "F.Paste")
			(net "GND")
		)
	)
	(footprint ""
		(layer "F.Cu")
		(at 104.3432 -252.956568 -90)
		(property "Reference" "C261"
			(at 0 0 270)
			(layer "F.SilkS")
			(hide yes)
			(effects
				(font
					(size 1.27 1.27)
				)
			)
		)
		(property "Value" ""
			(at 0 0 270)
			(layer "F.Fab")
			(effects
				(font
					(size 1.27 1.27)
				)
			)
		)
		(duplicate_pad_numbers_are_jumpers no)
		(fp_line
			(start -0.7874 0.4064)
			(end -0.7874 -0.4064)
			(stroke
				(width 0.1524)
				(type default)
			)
			(layer "F.SilkS")
		)
		(fp_line
			(start 0.7874 0.4064)
			(end -0.7874 0.4064)
			(stroke
				(width 0.1524)
				(type default)
			)
			(layer "F.SilkS")
		)
		(fp_line
			(start -0.7874 -0.4064)
			(end 0.7874 -0.4064)
			(stroke
				(width 0.1524)
				(type default)
			)
			(layer "F.SilkS")
		)
		(fp_line
			(start 0.7874 -0.4064)
			(end 0.7874 0.4064)
			(stroke
				(width 0.1524)
				(type default)
			)
			(layer "F.SilkS")
		)
		(fp_line
			(start -0.67945 0.3048)
			(end -0.67945 -0.305054)
			(stroke
				(width 0.1)
				(type default)
			)
			(layer "F.Fab")
		)
		(fp_line
			(start -0.12065 0.3048)
			(end -0.67945 0.3048)
			(stroke
				(width 0.1)
				(type default)
			)
			(layer "F.Fab")
		)
		(fp_line
			(start 0.120396 0.3048)
			(end 0.120396 0.2794)
			(stroke
				(width 0.1)
				(type default)
			)
			(layer "F.Fab")
		)
		(fp_line
			(start 0.67945 0.3048)
			(end 0.120396 0.3048)
			(stroke
				(width 0.1)
				(type default)
			)
			(layer "F.Fab")
		)
		(fp_line
			(start -0.12065 0.2794)
			(end -0.12065 0.3048)
			(stroke
				(width 0.1)
				(type default)
			)
			(layer "F.Fab")
		)
		(fp_line
			(start 0.120396 0.2794)
			(end -0.12065 0.2794)
			(stroke
				(width 0.1)
				(type default)
			)
			(layer "F.Fab")
		)
		(fp_line
			(start -0.12065 -0.2794)
			(end 0.12065 -0.2794)
			(stroke
				(width 0.1)
				(type default)
			)
			(layer "F.Fab")
		)
		(fp_line
			(start 0.12065 -0.2794)
			(end 0.12065 -0.3048)
			(stroke
				(width 0.1)
				(type default)
			)
			(layer "F.Fab")
		)
		(fp_line
			(start 0.12065 -0.3048)
			(end 0.67945 -0.3048)
			(stroke
				(width 0.1)
				(type default)
			)
			(layer "F.Fab")
		)
		(fp_line
			(start 0.67945 -0.3048)
			(end 0.67945 0.3048)
			(stroke
				(width 0.1)
				(type default)
			)
			(layer "F.Fab")
		)
		(fp_line
			(start -0.67945 -0.305054)
			(end -0.12065 -0.305054)
			(stroke
				(width 0.1)
				(type default)
			)
			(layer "F.Fab")
		)
		(fp_line
			(start -0.12065 -0.305054)
			(end -0.12065 -0.2794)
			(stroke
				(width 0.1)
				(type default)
			)
			(layer "F.Fab")
		)
		(pad "1" smd circle
			(at -0.40005 0 270)
			(size 0 0)
			(layers "F.Cu" "F.Mask" "F.Paste")
			(net "PVCCIN_CPU1")
		)
		(pad "2" smd circle
			(at 0.40005 0 270)
			(size 0 0)
			(layers "F.Cu" "F.Mask" "F.Paste")
			(net "GND")
		)
	)
	(footprint ""
		(layer "F.Cu")
		(at 421.801544 -46.5455 -90)
		(property "Reference" "D7"
			(at 2.457958 1.281684 0)
			(unlocked yes)
			(layer "F.SilkS")
			(effects
				(font
					(size 0.7874 0.5842)
					(thickness 0.1524)
				)
				(justify left)
			)
		)
		(property "Value" ""
			(at 0 0 270)
			(layer "F.Fab")
			(effects
				(font
					(size 1.27 1.27)
				)
			)
		)
		(duplicate_pad_numbers_are_jumpers no)
		(fp_line
			(start -1.584198 1.500124)
			(end 1.584198 1.500124)
			(stroke
				(width 0.1524)
				(type default)
			)
			(layer "F.SilkS")
		)
		(fp_line
			(start 1.584198 1.500124)
			(end 1.584198 -1.500124)
			(stroke
				(width 0.1524)
				(type default)
			)
			(layer "F.SilkS")
		)
		(fp_line
			(start -1.584198 -1.500124)
			(end -1.584198 1.500124)
			(stroke
				(width 0.1524)
				(type default)
			)
			(layer "F.SilkS")
		)
		(fp_line
			(start 1.584198 -1.500124)
			(end -1.584198 -1.500124)
			(stroke
				(width 0.1524)
				(type default)
			)
			(layer "F.SilkS")
		)
		(fp_line
			(start -0.700024 1.500124)
			(end 0.700024 1.500124)
			(stroke
				(width 0.1)
				(type default)
			)
			(layer "F.Fab")
		)
		(fp_line
			(start 0.700024 1.500124)
			(end 0.700024 -1.500124)
			(stroke
				(width 0.1)
				(type default)
			)
			(layer "F.Fab")
		)
		(fp_line
			(start -0.700024 -1.500124)
			(end -0.700024 1.500124)
			(stroke
				(width 0.1)
				(type default)
			)
			(layer "F.Fab")
		)
		(fp_line
			(start 0.700024 -1.500124)
			(end -0.700024 -1.500124)
			(stroke
				(width 0.1)
				(type default)
			)
			(layer "F.Fab")
		)
		(pad "1" smd rect
			(at -0.999998 -0.94996 180)
			(size 0.8128 0.9144)
			(layers "F.Cu" "F.Mask" "F.Paste")
			(net "P3V3")
		)
		(pad "2" smd rect
			(at -0.999998 0.94996 180)
			(size 0.8128 0.9144)
			(layers "F.Cu" "F.Mask" "F.Paste")
			(net "Net_8589")
		)
		(pad "3" smd rect
			(at 0.999998 0 180)
			(size 0.8128 0.9144)
			(layers "F.Cu" "F.Mask" "F.Paste")
			(net "P5V")
		)
	)
	(footprint ""
		(layer "F.Cu")
		(at 381.93345 -408.517344 -90)
		(property "Reference" "C876"
			(at 0 0 270)
			(layer "F.SilkS")
			(hide yes)
			(effects
				(font
					(size 1.27 1.27)
				)
			)
		)
		(property "Value" ""
			(at 0 0 270)
			(layer "F.Fab")
			(effects
				(font
					(size 1.27 1.27)
				)
			)
		)
		(duplicate_pad_numbers_are_jumpers no)
		(fp_line
			(start -0.299974 0.150114)
			(end -0.299974 -0.150114)
			(stroke
				(width 0.1)
				(type default)
			)
			(layer "F.Fab")
		)
		(fp_line
			(start 0.299974 0.150114)
			(end -0.299974 0.150114)
			(stroke
				(width 0.1)
				(type default)
			)
			(layer "F.Fab")
		)
		(fp_line
			(start -0.299974 -0.150114)
			(end 0.299974 -0.150114)
			(stroke
				(width 0.1)
				(type default)
			)
			(layer "F.Fab")
		)
		(fp_line
			(start 0.299974 -0.150114)
			(end 0.299974 0.150114)
			(stroke
				(width 0.1)
				(type default)
			)
			(layer "F.Fab")
		)
		(pad "1" smd rect
			(at -0.2667 0 270)
			(size 0.3048 0.381)
			(layers "F.Cu" "F.Mask" "F.Paste")
			(net "P5E_CPU0_PE3_TX_C_DN<12>")
		)
		(pad "2" smd rect
			(at 0.2667 0 270)
			(size 0.3048 0.381)
			(layers "F.Cu" "F.Mask" "F.Paste")
			(net "P5E_CPU0_PE3_TX_DN<12>")
		)
	)
	(footprint ""
		(layer "F.Cu")
		(at 235.404406 -250.630436 180)
		(property "Reference" "U247"
			(at -2.7432 -3.012948 180)
			(unlocked yes)
			(layer "F.SilkS")
			(effects
				(font
					(size 0.7874 0.5842)
					(thickness 0.1524)
				)
				(justify left)
			)
		)
		(property "Value" ""
			(at 0 0 180)
			(layer "F.Fab")
			(effects
				(font
					(size 1.27 1.27)
				)
			)
		)
		(duplicate_pad_numbers_are_jumpers no)
		(fp_line
			(start 2.050034 2.050034)
			(end 2.050034 1.516634)
			(stroke
				(width 0.1524)
				(type default)
			)
			(layer "F.SilkS")
		)
		(fp_line
			(start 2.050034 -1.516634)
			(end 2.050034 -2.050034)
			(stroke
				(width 0.1524)
				(type default)
			)
			(layer "F.SilkS")
		)
		(fp_line
			(start 2.050034 -2.050034)
			(end 1.516634 -2.050034)
			(stroke
				(width 0.1524)
				(type default)
			)
			(layer "F.SilkS")
		)
		(fp_line
			(start 1.516634 2.050034)
			(end 2.050034 2.050034)
			(stroke
				(width 0.1524)
				(type default)
			)
			(layer "F.SilkS")
		)
		(fp_line
			(start -1.516634 -2.050034)
			(end -2.050034 -2.050034)
			(stroke
				(width 0.1524)
				(type default)
			)
			(layer "F.SilkS")
		)
		(fp_line
			(start -2.050034 2.050034)
			(end -1.516634 2.050034)
			(stroke
				(width 0.1524)
				(type default)
			)
			(layer "F.SilkS")
		)
		(fp_line
			(start -2.050034 1.516634)
			(end -2.050034 2.050034)
			(stroke
				(width 0.1524)
				(type default)
			)
			(layer "F.SilkS")
		)
		(fp_line
			(start -2.050034 -2.050034)
			(end -2.050034 -1.516634)
			(stroke
				(width 0.1524)
				(type default)
			)
			(layer "F.SilkS")
		)
		(fp_poly
			(pts
				(xy -2.634234 -1.542034) (xy -2.050034 -1.542034) (xy -2.050034 -2.126234) (xy -2.634234 -2.126234)
			)
			(stroke
				(width 0)
				(type default)
			)
			(fill yes)
			(layer "F.SilkS")
		)
		(fp_line
			(start 2.050034 2.050034)
			(end 2.050034 -2.050034)
			(stroke
				(width 0.1)
				(type default)
			)
			(layer "F.Fab")
		)
		(fp_line
			(start 2.050034 -2.050034)
			(end -2.050034 -2.050034)
			(stroke
				(width 0.1)
				(type default)
			)
			(layer "F.Fab")
		)
		(fp_line
			(start -2.050034 2.050034)
			(end 2.050034 2.050034)
			(stroke
				(width 0.1)
				(type default)
			)
			(layer "F.Fab")
		)
		(fp_line
			(start -2.050034 -2.050034)
			(end -2.050034 2.050034)
			(stroke
				(width 0.1)
				(type default)
			)
			(layer "F.Fab")
		)
		(fp_poly
			(pts
				(xy -2.634234 -1.542034) (xy -2.050034 -1.542034) (xy -2.050034 -2.126234) (xy -2.634234 -2.126234)
			)
			(stroke
				(width 0)
				(type default)
			)
			(fill yes)
			(layer "F.Fab")
		)
		(pad "1" smd rect
			(at -1.875028 -1.249934 90)
			(size 0.254 0.5588)
			(layers "F.Cu" "F.Mask" "F.Paste")
			(net "CLK_GEN2_XTAL_IN")
		)
		(pad "2" smd rect
			(at -1.875028 -0.750062 90)
			(size 0.254 0.5588)
			(layers "F.Cu" "F.Mask" "F.Paste")
			(net "CLK_GEN2_XTAL_OUT")
		)
		(pad "3" smd rect
			(at -1.875028 -0.249936 90)
			(size 0.254 0.5588)
			(layers "F.Cu" "F.Mask" "F.Paste")
			(net "VFG3P3_CLK_GEN")
		)
		(pad "4" smd rect
			(at -1.875028 0.249936 90)
			(size 0.254 0.5588)
			(layers "F.Cu" "F.Mask" "F.Paste")
			(net "CLK_GEN2_SMB_SADR")
		)
		(pad "5" smd rect
			(at -1.875028 0.750062 90)
			(size 0.254 0.5588)
			(layers "F.Cu" "F.Mask" "F.Paste")
			(net "GND")
		)
		(pad "6" smd rect
			(at -1.875028 1.249934 90)
			(size 0.254 0.5588)
			(layers "F.Cu" "F.Mask" "F.Paste")
			(net "GND")
		)
		(pad "7" smd rect
			(at -1.249934 1.875028 180)
			(size 0.254 0.5588)
			(layers "F.Cu" "F.Mask" "F.Paste")
			(net "VFG3P3_CLK_GEN")
		)
		(pad "8" smd rect
			(at -0.750062 1.875028 180)
			(size 0.254 0.5588)
			(layers "F.Cu" "F.Mask" "F.Paste")
			(net "SMB_HOST_CLK_GEN2_3V3AUX_SCL")
		)
		(pad "9" smd rect
			(at -0.249936 1.875028 180)
			(size 0.254 0.5588)
			(layers "F.Cu" "F.Mask" "F.Paste")
			(net "SMB_HOST_CLK_GEN2_3V3AUX_SDA")
		)
		(pad "10" smd rect
			(at 0.249936 1.875028 180)
			(size 0.254 0.5588)
			(layers "F.Cu" "F.Mask" "F.Paste")
			(net "GND")
		)
		(pad "11" smd rect
			(at 0.750062 1.875028 180)
			(size 0.254 0.5588)
			(layers "F.Cu" "F.Mask" "F.Paste")
			(net "VFG3P3_CLK_GEN")
		)
		(pad "12" smd rect
			(at 1.249934 1.875028 180)
			(size 0.254 0.5588)
			(layers "F.Cu" "F.Mask" "F.Paste")
			(net "CLK_GEN2_BMC_RC_OE_R3_N")
		)
		(pad "13" smd rect
			(at 1.875028 1.249934 90)
			(size 0.254 0.5588)
			(layers "F.Cu" "F.Mask" "F.Paste")
			(net "CLK_100M_BMC_RC_DP_R")
		)
		(pad "14" smd rect
			(at 1.875028 0.750062 90)
			(size 0.254 0.5588)
			(layers "F.Cu" "F.Mask" "F.Paste")
			(net "CLK_100M_BMC_RC_DN_R")
		)
		(pad "15" smd rect
			(at 1.875028 0.249936 90)
			(size 0.254 0.5588)
			(layers "F.Cu" "F.Mask" "F.Paste")
			(net "GND")
		)
		(pad "16" smd rect
			(at 1.875028 -0.249936 90)
			(size 0.254 0.5588)
			(layers "F.Cu" "F.Mask" "F.Paste")
			(net "VFG_3P3A_CLK_GEN")
		)
		(pad "17" smd rect
			(at 1.875028 -0.750062 90)
			(size 0.254 0.5588)
			(layers "F.Cu" "F.Mask" "F.Paste")
			(net "CLK_100M_GPU_FPGA_DP_R")
		)
		(pad "18" smd rect
			(at 1.875028 -1.249934 90)
			(size 0.254 0.5588)
			(layers "F.Cu" "F.Mask" "F.Paste")
			(net "CLK_100M_GPU_FPGA_DN_R")
		)
		(pad "19" smd rect
			(at 1.249934 -1.875028 180)
			(size 0.254 0.5588)
			(layers "F.Cu" "F.Mask" "F.Paste")
			(net "CLK_GEN2_GPU_OE_N")
		)
		(pad "20" smd rect
			(at 0.750062 -1.875028 180)
			(size 0.254 0.5588)
			(layers "F.Cu" "F.Mask" "F.Paste")
			(net "VFG3P3_CLK_GEN")
		)
		(pad "21" smd rect
			(at 0.249936 -1.875028 180)
			(size 0.254 0.5588)
			(layers "F.Cu" "F.Mask" "F.Paste")
			(net "GND")
		)
		(pad "22" smd rect
			(at -0.249936 -1.875028 180)
			(size 0.254 0.5588)
			(layers "F.Cu" "F.Mask" "F.Paste")
			(net "P3V3_PWRGD_CLKGEN")
		)
		(pad "23" smd rect
			(at -0.750062 -1.875028 180)
			(size 0.254 0.5588)
			(layers "F.Cu" "F.Mask" "F.Paste")
			(net "FG_SS_EN")
		)
		(pad "24" smd rect
			(at -1.249934 -1.875028 180)
			(size 0.254 0.5588)
			(layers "F.Cu" "F.Mask" "F.Paste")
			(net "GND")
		)
		(pad "25" smd circle
			(at 0 0 180)
			(size 0 0)
			(layers "F.Cu" "F.Mask" "F.Paste")
			(net "GND")
		)
	)
	(footprint ""
		(layer "F.Cu")
		(at 176.58588 -130.266948 -90)
		(property "Reference" "R1447"
			(at 0 0 270)
			(layer "F.SilkS")
			(hide yes)
			(effects
				(font
					(size 1.27 1.27)
				)
			)
		)
		(property "Value" ""
			(at 0 0 270)
			(layer "F.Fab")
			(effects
				(font
					(size 1.27 1.27)
				)
			)
		)
		(duplicate_pad_numbers_are_jumpers no)
		(fp_line
			(start -0.7874 0.4064)
			(end -0.7874 -0.4064)
			(stroke
				(width 0.1524)
				(type default)
			)
			(layer "F.SilkS")
		)
		(fp_line
			(start 0.7874 0.4064)
			(end -0.7874 0.4064)
			(stroke
				(width 0.1524)
				(type default)
			)
			(layer "F.SilkS")
		)
		(fp_line
			(start -0.7874 -0.4064)
			(end 0.7874 -0.4064)
			(stroke
				(width 0.1524)
				(type default)
			)
			(layer "F.SilkS")
		)
		(fp_line
			(start 0.7874 -0.4064)
			(end 0.7874 0.4064)
			(stroke
				(width 0.1524)
				(type default)
			)
			(layer "F.SilkS")
		)
		(fp_line
			(start -0.67945 0.3048)
			(end -0.67945 -0.305054)
			(stroke
				(width 0.1)
				(type default)
			)
			(layer "F.Fab")
		)
		(fp_line
			(start -0.12065 0.3048)
			(end -0.67945 0.3048)
			(stroke
				(width 0.1)
				(type default)
			)
			(layer "F.Fab")
		)
		(fp_line
			(start 0.120396 0.3048)
			(end 0.120396 0.2794)
			(stroke
				(width 0.1)
				(type default)
			)
			(layer "F.Fab")
		)
		(fp_line
			(start 0.67945 0.3048)
			(end 0.120396 0.3048)
			(stroke
				(width 0.1)
				(type default)
			)
			(layer "F.Fab")
		)
		(fp_line
			(start -0.12065 0.2794)
			(end -0.12065 0.3048)
			(stroke
				(width 0.1)
				(type default)
			)
			(layer "F.Fab")
		)
		(fp_line
			(start 0.120396 0.2794)
			(end -0.12065 0.2794)
			(stroke
				(width 0.1)
				(type default)
			)
			(layer "F.Fab")
		)
		(fp_line
			(start -0.12065 -0.2794)
			(end 0.12065 -0.2794)
			(stroke
				(width 0.1)
				(type default)
			)
			(layer "F.Fab")
		)
		(fp_line
			(start 0.12065 -0.2794)
			(end 0.12065 -0.3048)
			(stroke
				(width 0.1)
				(type default)
			)
			(layer "F.Fab")
		)
		(fp_line
			(start 0.12065 -0.3048)
			(end 0.67945 -0.3048)
			(stroke
				(width 0.1)
				(type default)
			)
			(layer "F.Fab")
		)
		(fp_line
			(start 0.67945 -0.3048)
			(end 0.67945 0.3048)
			(stroke
				(width 0.1)
				(type default)
			)
			(layer "F.Fab")
		)
		(fp_line
			(start -0.67945 -0.305054)
			(end -0.12065 -0.305054)
			(stroke
				(width 0.1)
				(type default)
			)
			(layer "F.Fab")
		)
		(fp_line
			(start -0.12065 -0.305054)
			(end -0.12065 -0.2794)
			(stroke
				(width 0.1)
				(type default)
			)
			(layer "F.Fab")
		)
		(pad "1" smd circle
			(at -0.40005 0 270)
			(size 0 0)
			(layers "F.Cu" "F.Mask" "F.Paste")
			(net "FM_CPU0_SKTOCC_LVT3_N")
		)
		(pad "2" smd circle
			(at 0.40005 0 270)
			(size 0 0)
			(layers "F.Cu" "F.Mask" "F.Paste")
			(net "FM_CPU0_SKTOCC_LVT3_PLD_N")
		)
	)
	(footprint ""
		(layer "F.Cu")
		(at 118.849902 -409.113228 180)
		(property "Reference" "R2920"
			(at 0 0 180)
			(layer "F.SilkS")
			(hide yes)
			(effects
				(font
					(size 1.27 1.27)
				)
			)
		)
		(property "Value" ""
			(at 0 0 180)
			(layer "F.Fab")
			(effects
				(font
					(size 1.27 1.27)
				)
			)
		)
		(duplicate_pad_numbers_are_jumpers no)
		(fp_line
			(start 0.7874 0.4064)
			(end -0.7874 0.4064)
			(stroke
				(width 0.1524)
				(type default)
			)
			(layer "F.SilkS")
		)
		(fp_line
			(start 0.7874 -0.4064)
			(end 0.7874 0.4064)
			(stroke
				(width 0.1524)
				(type default)
			)
			(layer "F.SilkS")
		)
		(fp_line
			(start -0.7874 0.4064)
			(end -0.7874 -0.4064)
			(stroke
				(width 0.1524)
				(type default)
			)
			(layer "F.SilkS")
		)
		(fp_line
			(start -0.7874 -0.4064)
			(end 0.7874 -0.4064)
			(stroke
				(width 0.1524)
				(type default)
			)
			(layer "F.SilkS")
		)
		(fp_line
			(start 0.67945 0.3048)
			(end 0.120396 0.3048)
			(stroke
				(width 0.1)
				(type default)
			)
			(layer "F.Fab")
		)
		(fp_line
			(start 0.67945 -0.3048)
			(end 0.67945 0.3048)
			(stroke
				(width 0.1)
				(type default)
			)
			(layer "F.Fab")
		)
		(fp_line
			(start 0.12065 -0.2794)
			(end 0.12065 -0.3048)
			(stroke
				(width 0.1)
				(type default)
			)
			(layer "F.Fab")
		)
		(fp_line
			(start 0.12065 -0.3048)
			(end 0.67945 -0.3048)
			(stroke
				(width 0.1)
				(type default)
			)
			(layer "F.Fab")
		)
		(fp_line
			(start 0.120396 0.3048)
			(end 0.120396 0.2794)
			(stroke
				(width 0.1)
				(type default)
			)
			(layer "F.Fab")
		)
		(fp_line
			(start 0.120396 0.2794)
			(end -0.12065 0.2794)
			(stroke
				(width 0.1)
				(type default)
			)
			(layer "F.Fab")
		)
		(fp_line
			(start -0.12065 0.3048)
			(end -0.67945 0.3048)
			(stroke
				(width 0.1)
				(type default)
			)
			(layer "F.Fab")
		)
		(fp_line
			(start -0.12065 0.2794)
			(end -0.12065 0.3048)
			(stroke
				(width 0.1)
				(type default)
			)
			(layer "F.Fab")
		)
		(fp_line
			(start -0.12065 -0.2794)
			(end 0.12065 -0.2794)
			(stroke
				(width 0.1)
				(type default)
			)
			(layer "F.Fab")
		)
		(fp_line
			(start -0.12065 -0.305054)
			(end -0.12065 -0.2794)
			(stroke
				(width 0.1)
				(type default)
			)
			(layer "F.Fab")
		)
		(fp_line
			(start -0.67945 0.3048)
			(end -0.67945 -0.305054)
			(stroke
				(width 0.1)
				(type default)
			)
			(layer "F.Fab")
		)
		(fp_line
			(start -0.67945 -0.305054)
			(end -0.12065 -0.305054)
			(stroke
				(width 0.1)
				(type default)
			)
			(layer "F.Fab")
		)
		(pad "1" smd circle
			(at -0.40005 0 180)
			(size 0 0)
			(layers "F.Cu" "F.Mask" "F.Paste")
			(net "P3V3_AUX")
		)
		(pad "2" smd circle
			(at 0.40005 0 180)
			(size 0 0)
			(layers "F.Cu" "F.Mask" "F.Paste")
			(net "BIC_MONITER_ISO")
		)
	)
	(footprint ""
		(layer "F.Cu")
		(at 52.50688 -434.304948 180)
		(property "Reference" "R3110"
			(at 0 0 180)
			(layer "F.SilkS")
			(hide yes)
			(effects
				(font
					(size 1.27 1.27)
				)
			)
		)
		(property "Value" ""
			(at 0 0 180)
			(layer "F.Fab")
			(effects
				(font
					(size 1.27 1.27)
				)
			)
		)
		(duplicate_pad_numbers_are_jumpers no)
		(fp_line
			(start 0.7874 0.4064)
			(end -0.7874 0.4064)
			(stroke
				(width 0.1524)
				(type default)
			)
			(layer "F.SilkS")
		)
		(fp_line
			(start 0.7874 -0.4064)
			(end 0.7874 0.4064)
			(stroke
				(width 0.1524)
				(type default)
			)
			(layer "F.SilkS")
		)
		(fp_line
			(start -0.7874 0.4064)
			(end -0.7874 -0.4064)
			(stroke
				(width 0.1524)
				(type default)
			)
			(layer "F.SilkS")
		)
		(fp_line
			(start -0.7874 -0.4064)
			(end 0.7874 -0.4064)
			(stroke
				(width 0.1524)
				(type default)
			)
			(layer "F.SilkS")
		)
		(fp_line
			(start 0.67945 0.3048)
			(end 0.120396 0.3048)
			(stroke
				(width 0.1)
				(type default)
			)
			(layer "F.Fab")
		)
		(fp_line
			(start 0.67945 -0.3048)
			(end 0.67945 0.3048)
			(stroke
				(width 0.1)
				(type default)
			)
			(layer "F.Fab")
		)
		(fp_line
			(start 0.12065 -0.2794)
			(end 0.12065 -0.3048)
			(stroke
				(width 0.1)
				(type default)
			)
			(layer "F.Fab")
		)
		(fp_line
			(start 0.12065 -0.3048)
			(end 0.67945 -0.3048)
			(stroke
				(width 0.1)
				(type default)
			)
			(layer "F.Fab")
		)
		(fp_line
			(start 0.120396 0.3048)
			(end 0.120396 0.2794)
			(stroke
				(width 0.1)
				(type default)
			)
			(layer "F.Fab")
		)
		(fp_line
			(start 0.120396 0.2794)
			(end -0.12065 0.2794)
			(stroke
				(width 0.1)
				(type default)
			)
			(layer "F.Fab")
		)
		(fp_line
			(start -0.12065 0.3048)
			(end -0.67945 0.3048)
			(stroke
				(width 0.1)
				(type default)
			)
			(layer "F.Fab")
		)
		(fp_line
			(start -0.12065 0.2794)
			(end -0.12065 0.3048)
			(stroke
				(width 0.1)
				(type default)
			)
			(layer "F.Fab")
		)
		(fp_line
			(start -0.12065 -0.2794)
			(end 0.12065 -0.2794)
			(stroke
				(width 0.1)
				(type default)
			)
			(layer "F.Fab")
		)
		(fp_line
			(start -0.12065 -0.305054)
			(end -0.12065 -0.2794)
			(stroke
				(width 0.1)
				(type default)
			)
			(layer "F.Fab")
		)
		(fp_line
			(start -0.67945 0.3048)
			(end -0.67945 -0.305054)
			(stroke
				(width 0.1)
				(type default)
			)
			(layer "F.Fab")
		)
		(fp_line
			(start -0.67945 -0.305054)
			(end -0.12065 -0.305054)
			(stroke
				(width 0.1)
				(type default)
			)
			(layer "F.Fab")
		)
		(pad "1" smd circle
			(at -0.40005 0 180)
			(size 0 0)
			(layers "F.Cu" "F.Mask" "F.Paste")
			(net "SMB_1_BMC_GPU_SDA")
		)
		(pad "2" smd circle
			(at 0.40005 0 180)
			(size 0 0)
			(layers "F.Cu" "F.Mask" "F.Paste")
			(net "SMB_1_BMC_GPU_R_SDA")
		)
	)
	(footprint ""
		(layer "F.Cu")
		(at 119.508016 -258.72694 90)
		(property "Reference" "C233"
			(at 0 0 90)
			(layer "F.SilkS")
			(hide yes)
			(effects
				(font
					(size 1.27 1.27)
				)
			)
		)
		(property "Value" ""
			(at 0 0 90)
			(layer "F.Fab")
			(effects
				(font
					(size 1.27 1.27)
				)
			)
		)
		(duplicate_pad_numbers_are_jumpers no)
		(fp_line
			(start 0.7874 -0.4064)
			(end 0.7874 0.4064)
			(stroke
				(width 0.1524)
				(type default)
			)
			(layer "F.SilkS")
		)
		(fp_line
			(start -0.7874 -0.4064)
			(end 0.7874 -0.4064)
			(stroke
				(width 0.1524)
				(type default)
			)
			(layer "F.SilkS")
		)
		(fp_line
			(start 0.7874 0.4064)
			(end -0.7874 0.4064)
			(stroke
				(width 0.1524)
				(type default)
			)
			(layer "F.SilkS")
		)
		(fp_line
			(start -0.7874 0.4064)
			(end -0.7874 -0.4064)
			(stroke
				(width 0.1524)
				(type default)
			)
			(layer "F.SilkS")
		)
		(fp_line
			(start -0.12065 -0.305054)
			(end -0.12065 -0.2794)
			(stroke
				(width 0.1)
				(type default)
			)
			(layer "F.Fab")
		)
		(fp_line
			(start -0.67945 -0.305054)
			(end -0.12065 -0.305054)
			(stroke
				(width 0.1)
				(type default)
			)
			(layer "F.Fab")
		)
		(fp_line
			(start 0.67945 -0.3048)
			(end 0.67945 0.3048)
			(stroke
				(width 0.1)
				(type default)
			)
			(layer "F.Fab")
		)
		(fp_line
			(start 0.12065 -0.3048)
			(end 0.67945 -0.3048)
			(stroke
				(width 0.1)
				(type default)
			)
			(layer "F.Fab")
		)
		(fp_line
			(start 0.12065 -0.2794)
			(end 0.12065 -0.3048)
			(stroke
				(width 0.1)
				(type default)
			)
			(layer "F.Fab")
		)
		(fp_line
			(start -0.12065 -0.2794)
			(end 0.12065 -0.2794)
			(stroke
				(width 0.1)
				(type default)
			)
			(layer "F.Fab")
		)
		(fp_line
			(start 0.120396 0.2794)
			(end -0.12065 0.2794)
			(stroke
				(width 0.1)
				(type default)
			)
			(layer "F.Fab")
		)
		(fp_line
			(start -0.12065 0.2794)
			(end -0.12065 0.3048)
			(stroke
				(width 0.1)
				(type default)
			)
			(layer "F.Fab")
		)
		(fp_line
			(start 0.67945 0.3048)
			(end 0.120396 0.3048)
			(stroke
				(width 0.1)
				(type default)
			)
			(layer "F.Fab")
		)
		(fp_line
			(start 0.120396 0.3048)
			(end 0.120396 0.2794)
			(stroke
				(width 0.1)
				(type default)
			)
			(layer "F.Fab")
		)
		(fp_line
			(start -0.12065 0.3048)
			(end -0.67945 0.3048)
			(stroke
				(width 0.1)
				(type default)
			)
			(layer "F.Fab")
		)
		(fp_line
			(start -0.67945 0.3048)
			(end -0.67945 -0.305054)
			(stroke
				(width 0.1)
				(type default)
			)
			(layer "F.Fab")
		)
		(pad "1" smd circle
			(at -0.40005 0 90)
			(size 0 0)
			(layers "F.Cu" "F.Mask" "F.Paste")
			(net "PVCCIN_CPU1")
		)
		(pad "2" smd circle
			(at 0.40005 0 90)
			(size 0 0)
			(layers "F.Cu" "F.Mask" "F.Paste")
			(net "GND")
		)
	)
	(footprint ""
		(layer "F.Cu")
		(at 197.41388 -99.875848 180)
		(property "Reference" "R369"
			(at 0 0 180)
			(layer "F.SilkS")
			(hide yes)
			(effects
				(font
					(size 1.27 1.27)
				)
			)
		)
		(property "Value" ""
			(at 0 0 180)
			(layer "F.Fab")
			(effects
				(font
					(size 1.27 1.27)
				)
			)
		)
		(duplicate_pad_numbers_are_jumpers no)
		(fp_line
			(start 0.7874 0.4064)
			(end -0.7874 0.4064)
			(stroke
				(width 0.1524)
				(type default)
			)
			(layer "F.SilkS")
		)
		(fp_line
			(start 0.7874 -0.4064)
			(end 0.7874 0.4064)
			(stroke
				(width 0.1524)
				(type default)
			)
			(layer "F.SilkS")
		)
		(fp_line
			(start -0.7874 0.4064)
			(end -0.7874 -0.4064)
			(stroke
				(width 0.1524)
				(type default)
			)
			(layer "F.SilkS")
		)
		(fp_line
			(start -0.7874 -0.4064)
			(end 0.7874 -0.4064)
			(stroke
				(width 0.1524)
				(type default)
			)
			(layer "F.SilkS")
		)
		(fp_line
			(start 0.67945 0.3048)
			(end 0.120396 0.3048)
			(stroke
				(width 0.1)
				(type default)
			)
			(layer "F.Fab")
		)
		(fp_line
			(start 0.67945 -0.3048)
			(end 0.67945 0.3048)
			(stroke
				(width 0.1)
				(type default)
			)
			(layer "F.Fab")
		)
		(fp_line
			(start 0.12065 -0.2794)
			(end 0.12065 -0.3048)
			(stroke
				(width 0.1)
				(type default)
			)
			(layer "F.Fab")
		)
		(fp_line
			(start 0.12065 -0.3048)
			(end 0.67945 -0.3048)
			(stroke
				(width 0.1)
				(type default)
			)
			(layer "F.Fab")
		)
		(fp_line
			(start 0.120396 0.3048)
			(end 0.120396 0.2794)
			(stroke
				(width 0.1)
				(type default)
			)
			(layer "F.Fab")
		)
		(fp_line
			(start 0.120396 0.2794)
			(end -0.12065 0.2794)
			(stroke
				(width 0.1)
				(type default)
			)
			(layer "F.Fab")
		)
		(fp_line
			(start -0.12065 0.3048)
			(end -0.67945 0.3048)
			(stroke
				(width 0.1)
				(type default)
			)
			(layer "F.Fab")
		)
		(fp_line
			(start -0.12065 0.2794)
			(end -0.12065 0.3048)
			(stroke
				(width 0.1)
				(type default)
			)
			(layer "F.Fab")
		)
		(fp_line
			(start -0.12065 -0.2794)
			(end 0.12065 -0.2794)
			(stroke
				(width 0.1)
				(type default)
			)
			(layer "F.Fab")
		)
		(fp_line
			(start -0.12065 -0.305054)
			(end -0.12065 -0.2794)
			(stroke
				(width 0.1)
				(type default)
			)
			(layer "F.Fab")
		)
		(fp_line
			(start -0.67945 0.3048)
			(end -0.67945 -0.305054)
			(stroke
				(width 0.1)
				(type default)
			)
			(layer "F.Fab")
		)
		(fp_line
			(start -0.67945 -0.305054)
			(end -0.12065 -0.305054)
			(stroke
				(width 0.1)
				(type default)
			)
			(layer "F.Fab")
		)
		(pad "1" smd circle
			(at -0.40005 0 180)
			(size 0 0)
			(layers "F.Cu" "F.Mask" "F.Paste")
			(net "P3V3_AUX")
		)
		(pad "2" smd circle
			(at 0.40005 0 180)
			(size 0 0)
			(layers "F.Cu" "F.Mask" "F.Paste")
			(net "FM_ADR_ACK")
		)
	)
	(footprint ""
		(layer "F.Cu")
		(at 393.290552 -32.456374 180)
		(property "Reference" "R1514"
			(at 0 0 180)
			(layer "F.SilkS")
			(hide yes)
			(effects
				(font
					(size 1.27 1.27)
				)
			)
		)
		(property "Value" ""
			(at 0 0 180)
			(layer "F.Fab")
			(effects
				(font
					(size 1.27 1.27)
				)
			)
		)
		(duplicate_pad_numbers_are_jumpers no)
		(fp_line
			(start 0.7874 0.4064)
			(end -0.7874 0.4064)
			(stroke
				(width 0.1524)
				(type default)
			)
			(layer "F.SilkS")
		)
		(fp_line
			(start 0.7874 -0.4064)
			(end 0.7874 0.4064)
			(stroke
				(width 0.1524)
				(type default)
			)
			(layer "F.SilkS")
		)
		(fp_line
			(start -0.7874 0.4064)
			(end -0.7874 -0.4064)
			(stroke
				(width 0.1524)
				(type default)
			)
			(layer "F.SilkS")
		)
		(fp_line
			(start -0.7874 -0.4064)
			(end 0.7874 -0.4064)
			(stroke
				(width 0.1524)
				(type default)
			)
			(layer "F.SilkS")
		)
		(fp_line
			(start 0.67945 0.3048)
			(end 0.120396 0.3048)
			(stroke
				(width 0.1)
				(type default)
			)
			(layer "F.Fab")
		)
		(fp_line
			(start 0.67945 -0.3048)
			(end 0.67945 0.3048)
			(stroke
				(width 0.1)
				(type default)
			)
			(layer "F.Fab")
		)
		(fp_line
			(start 0.12065 -0.2794)
			(end 0.12065 -0.3048)
			(stroke
				(width 0.1)
				(type default)
			)
			(layer "F.Fab")
		)
		(fp_line
			(start 0.12065 -0.3048)
			(end 0.67945 -0.3048)
			(stroke
				(width 0.1)
				(type default)
			)
			(layer "F.Fab")
		)
		(fp_line
			(start 0.120396 0.3048)
			(end 0.120396 0.2794)
			(stroke
				(width 0.1)
				(type default)
			)
			(layer "F.Fab")
		)
		(fp_line
			(start 0.120396 0.2794)
			(end -0.12065 0.2794)
			(stroke
				(width 0.1)
				(type default)
			)
			(layer "F.Fab")
		)
		(fp_line
			(start -0.12065 0.3048)
			(end -0.67945 0.3048)
			(stroke
				(width 0.1)
				(type default)
			)
			(layer "F.Fab")
		)
		(fp_line
			(start -0.12065 0.2794)
			(end -0.12065 0.3048)
			(stroke
				(width 0.1)
				(type default)
			)
			(layer "F.Fab")
		)
		(fp_line
			(start -0.12065 -0.2794)
			(end 0.12065 -0.2794)
			(stroke
				(width 0.1)
				(type default)
			)
			(layer "F.Fab")
		)
		(fp_line
			(start -0.12065 -0.305054)
			(end -0.12065 -0.2794)
			(stroke
				(width 0.1)
				(type default)
			)
			(layer "F.Fab")
		)
		(fp_line
			(start -0.67945 0.3048)
			(end -0.67945 -0.305054)
			(stroke
				(width 0.1)
				(type default)
			)
			(layer "F.Fab")
		)
		(fp_line
			(start -0.67945 -0.305054)
			(end -0.12065 -0.305054)
			(stroke
				(width 0.1)
				(type default)
			)
			(layer "F.Fab")
		)
		(pad "1" smd circle
			(at -0.40005 0 180)
			(size 0 0)
			(layers "F.Cu" "F.Mask" "F.Paste")
			(net "RST_PCIE_CPU0_DEV_PERST_N")
		)
		(pad "2" smd circle
			(at 0.40005 0 180)
			(size 0 0)
			(layers "F.Cu" "F.Mask" "F.Paste")
			(net "RST_OCP_V3_1_N")
		)
	)
	(footprint ""
		(layer "F.Cu")
		(at 459.579726 -98.514408)
		(property "Reference" "U66"
			(at -3.89636 -2.009648 0)
			(unlocked yes)
			(layer "F.SilkS")
			(effects
				(font
					(size 0.7874 0.5842)
					(thickness 0.1524)
				)
				(justify left)
			)
		)
		(property "Value" ""
			(at 0 0 0)
			(layer "F.Fab")
			(effects
				(font
					(size 1.27 1.27)
				)
			)
		)
		(duplicate_pad_numbers_are_jumpers no)
		(fp_line
			(start -1.400048 1.100074)
			(end -1.400048 -1.100074)
			(stroke
				(width 0.1524)
				(type default)
			)
			(layer "F.SilkS")
		)
		(fp_line
			(start 1.400048 -1.100074)
			(end -1.400048 -1.100074)
			(stroke
				(width 0.1524)
				(type default)
			)
			(layer "F.SilkS")
		)
		(fp_line
			(start 1.400048 -1.100074)
			(end 1.400048 1.100074)
			(stroke
				(width 0.1524)
				(type default)
			)
			(layer "F.SilkS")
		)
		(fp_line
			(start 1.400048 1.100074)
			(end -1.400048 1.100074)
			(stroke
				(width 0.1524)
				(type default)
			)
			(layer "F.SilkS")
		)
		(fp_poly
			(pts
				(xy -1.03886 -1.265682) (xy -1.54686 -2.281682) (xy -0.53086 -2.281682)
			)
			(stroke
				(width 0)
				(type default)
			)
			(fill yes)
			(layer "F.SilkS")
		)
		(fp_line
			(start -0.674878 -1.100074)
			(end 0.674878 -1.100074)
			(stroke
				(width 0.1)
				(type default)
			)
			(layer "F.Fab")
		)
		(fp_line
			(start -0.674878 1.100074)
			(end -0.674878 -1.100074)
			(stroke
				(width 0.1)
				(type default)
			)
			(layer "F.Fab")
		)
		(fp_line
			(start 0.674878 -1.100074)
			(end 0.674878 1.100074)
			(stroke
				(width 0.1)
				(type default)
			)
			(layer "F.Fab")
		)
		(fp_line
			(start 0.674878 1.100074)
			(end -0.674878 1.100074)
			(stroke
				(width 0.1)
				(type default)
			)
			(layer "F.Fab")
		)
		(fp_poly
			(pts
				(xy -1.590548 -0.649986) (xy -2.606548 -1.157986) (xy -2.606548 -0.141986)
			)
			(stroke
				(width 0)
				(type default)
			)
			(fill yes)
			(layer "F.Fab")
		)
		(pad "1" smd rect
			(at -0.94996 -0.649986 270)
			(size 0.4318 0.6096)
			(layers "F.Cu" "F.Mask" "F.Paste")
			(net "OCP_SFF_AUX_PWR_EN_R1")
		)
		(pad "2" smd rect
			(at -0.94996 0 270)
			(size 0.4318 0.6096)
			(layers "F.Cu" "F.Mask" "F.Paste")
			(net "FM_OCP_SFF_PWR_GOOD")
		)
		(pad "3" smd rect
			(at -0.94996 0.649986 270)
			(size 0.4318 0.6096)
			(layers "F.Cu" "F.Mask" "F.Paste")
			(net "GND")
		)
		(pad "4" smd rect
			(at 0.94996 0.649986 270)
			(size 0.4318 0.6096)
			(layers "F.Cu" "F.Mask" "F.Paste")
			(net "FB_BMC_ISOLATE_R1")
		)
		(pad "5" smd rect
			(at 0.94996 -0.649986 270)
			(size 0.4318 0.6096)
			(layers "F.Cu" "F.Mask" "F.Paste")
			(net "P3V3_AUX")
		)
	)
	(footprint ""
		(layer "F.Cu")
		(at 21.752052 -403.827488)
		(property "Reference" "R3318"
			(at 0 0 0)
			(layer "F.SilkS")
			(hide yes)
			(effects
				(font
					(size 1.27 1.27)
				)
			)
		)
		(property "Value" ""
			(at 0 0 0)
			(layer "F.Fab")
			(effects
				(font
					(size 1.27 1.27)
				)
			)
		)
		(duplicate_pad_numbers_are_jumpers no)
		(fp_line
			(start -0.7874 -0.4064)
			(end 0.7874 -0.4064)
			(stroke
				(width 0.1524)
				(type default)
			)
			(layer "F.SilkS")
		)
		(fp_line
			(start -0.7874 0.4064)
			(end -0.7874 -0.4064)
			(stroke
				(width 0.1524)
				(type default)
			)
			(layer "F.SilkS")
		)
		(fp_line
			(start 0.7874 -0.4064)
			(end 0.7874 0.4064)
			(stroke
				(width 0.1524)
				(type default)
			)
			(layer "F.SilkS")
		)
		(fp_line
			(start 0.7874 0.4064)
			(end -0.7874 0.4064)
			(stroke
				(width 0.1524)
				(type default)
			)
			(layer "F.SilkS")
		)
		(fp_line
			(start -0.67945 -0.305054)
			(end -0.12065 -0.305054)
			(stroke
				(width 0.1)
				(type default)
			)
			(layer "F.Fab")
		)
		(fp_line
			(start -0.67945 0.3048)
			(end -0.67945 -0.305054)
			(stroke
				(width 0.1)
				(type default)
			)
			(layer "F.Fab")
		)
		(fp_line
			(start -0.12065 -0.305054)
			(end -0.12065 -0.2794)
			(stroke
				(width 0.1)
				(type default)
			)
			(layer "F.Fab")
		)
		(fp_line
			(start -0.12065 -0.2794)
			(end 0.12065 -0.2794)
			(stroke
				(width 0.1)
				(type default)
			)
			(layer "F.Fab")
		)
		(fp_line
			(start -0.12065 0.2794)
			(end -0.12065 0.3048)
			(stroke
				(width 0.1)
				(type default)
			)
			(layer "F.Fab")
		)
		(fp_line
			(start -0.12065 0.3048)
			(end -0.67945 0.3048)
			(stroke
				(width 0.1)
				(type default)
			)
			(layer "F.Fab")
		)
		(fp_line
			(start 0.120396 0.2794)
			(end -0.12065 0.2794)
			(stroke
				(width 0.1)
				(type default)
			)
			(layer "F.Fab")
		)
		(fp_line
			(start 0.120396 0.3048)
			(end 0.120396 0.2794)
			(stroke
				(width 0.1)
				(type default)
			)
			(layer "F.Fab")
		)
		(fp_line
			(start 0.12065 -0.3048)
			(end 0.67945 -0.3048)
			(stroke
				(width 0.1)
				(type default)
			)
			(layer "F.Fab")
		)
		(fp_line
			(start 0.12065 -0.2794)
			(end 0.12065 -0.3048)
			(stroke
				(width 0.1)
				(type default)
			)
			(layer "F.Fab")
		)
		(fp_line
			(start 0.67945 -0.3048)
			(end 0.67945 0.3048)
			(stroke
				(width 0.1)
				(type default)
			)
			(layer "F.Fab")
		)
		(fp_line
			(start 0.67945 0.3048)
			(end 0.120396 0.3048)
			(stroke
				(width 0.1)
				(type default)
			)
			(layer "F.Fab")
		)
		(pad "1" smd circle
			(at -0.40005 0)
			(size 0 0)
			(layers "F.Cu" "F.Mask" "F.Paste")
			(net "P3V3_AUX")
		)
		(pad "2" smd circle
			(at 0.40005 0)
			(size 0 0)
			(layers "F.Cu" "F.Mask" "F.Paste")
			(net "GPU_FPGA_READY")
		)
	)
	(footprint ""
		(layer "F.Cu")
		(at 106.3244 -252.956568 -90)
		(property "Reference" "C271"
			(at 0 0 270)
			(layer "F.SilkS")
			(hide yes)
			(effects
				(font
					(size 1.27 1.27)
				)
			)
		)
		(property "Value" ""
			(at 0 0 270)
			(layer "F.Fab")
			(effects
				(font
					(size 1.27 1.27)
				)
			)
		)
		(duplicate_pad_numbers_are_jumpers no)
		(fp_line
			(start -0.7874 0.4064)
			(end -0.7874 -0.4064)
			(stroke
				(width 0.1524)
				(type default)
			)
			(layer "F.SilkS")
		)
		(fp_line
			(start 0.7874 0.4064)
			(end -0.7874 0.4064)
			(stroke
				(width 0.1524)
				(type default)
			)
			(layer "F.SilkS")
		)
		(fp_line
			(start -0.7874 -0.4064)
			(end 0.7874 -0.4064)
			(stroke
				(width 0.1524)
				(type default)
			)
			(layer "F.SilkS")
		)
		(fp_line
			(start 0.7874 -0.4064)
			(end 0.7874 0.4064)
			(stroke
				(width 0.1524)
				(type default)
			)
			(layer "F.SilkS")
		)
		(fp_line
			(start -0.67945 0.3048)
			(end -0.67945 -0.305054)
			(stroke
				(width 0.1)
				(type default)
			)
			(layer "F.Fab")
		)
		(fp_line
			(start -0.12065 0.3048)
			(end -0.67945 0.3048)
			(stroke
				(width 0.1)
				(type default)
			)
			(layer "F.Fab")
		)
		(fp_line
			(start 0.120396 0.3048)
			(end 0.120396 0.2794)
			(stroke
				(width 0.1)
				(type default)
			)
			(layer "F.Fab")
		)
		(fp_line
			(start 0.67945 0.3048)
			(end 0.120396 0.3048)
			(stroke
				(width 0.1)
				(type default)
			)
			(layer "F.Fab")
		)
		(fp_line
			(start -0.12065 0.2794)
			(end -0.12065 0.3048)
			(stroke
				(width 0.1)
				(type default)
			)
			(layer "F.Fab")
		)
		(fp_line
			(start 0.120396 0.2794)
			(end -0.12065 0.2794)
			(stroke
				(width 0.1)
				(type default)
			)
			(layer "F.Fab")
		)
		(fp_line
			(start -0.12065 -0.2794)
			(end 0.12065 -0.2794)
			(stroke
				(width 0.1)
				(type default)
			)
			(layer "F.Fab")
		)
		(fp_line
			(start 0.12065 -0.2794)
			(end 0.12065 -0.3048)
			(stroke
				(width 0.1)
				(type default)
			)
			(layer "F.Fab")
		)
		(fp_line
			(start 0.12065 -0.3048)
			(end 0.67945 -0.3048)
			(stroke
				(width 0.1)
				(type default)
			)
			(layer "F.Fab")
		)
		(fp_line
			(start 0.67945 -0.3048)
			(end 0.67945 0.3048)
			(stroke
				(width 0.1)
				(type default)
			)
			(layer "F.Fab")
		)
		(fp_line
			(start -0.67945 -0.305054)
			(end -0.12065 -0.305054)
			(stroke
				(width 0.1)
				(type default)
			)
			(layer "F.Fab")
		)
		(fp_line
			(start -0.12065 -0.305054)
			(end -0.12065 -0.2794)
			(stroke
				(width 0.1)
				(type default)
			)
			(layer "F.Fab")
		)
		(pad "1" smd circle
			(at -0.40005 0 270)
			(size 0 0)
			(layers "F.Cu" "F.Mask" "F.Paste")
			(net "PVCCIN_CPU1")
		)
		(pad "2" smd circle
			(at 0.40005 0 270)
			(size 0 0)
			(layers "F.Cu" "F.Mask" "F.Paste")
			(net "GND")
		)
	)
	(footprint ""
		(layer "F.Cu")
		(at 422.66616 -143.675608 90)
		(property "Reference" "PR4225"
			(at 0 0 90)
			(layer "F.SilkS")
			(hide yes)
			(effects
				(font
					(size 1.27 1.27)
				)
			)
		)
		(property "Value" ""
			(at 0 0 90)
			(layer "F.Fab")
			(effects
				(font
					(size 1.27 1.27)
				)
			)
		)
		(duplicate_pad_numbers_are_jumpers no)
		(fp_line
			(start 0.7874 -0.4064)
			(end 0.7874 0.4064)
			(stroke
				(width 0.1524)
				(type default)
			)
			(layer "F.SilkS")
		)
		(fp_line
			(start -0.7874 -0.4064)
			(end 0.7874 -0.4064)
			(stroke
				(width 0.1524)
				(type default)
			)
			(layer "F.SilkS")
		)
		(fp_line
			(start 0.7874 0.4064)
			(end -0.7874 0.4064)
			(stroke
				(width 0.1524)
				(type default)
			)
			(layer "F.SilkS")
		)
		(fp_line
			(start -0.7874 0.4064)
			(end -0.7874 -0.4064)
			(stroke
				(width 0.1524)
				(type default)
			)
			(layer "F.SilkS")
		)
		(fp_line
			(start -0.12065 -0.305054)
			(end -0.12065 -0.2794)
			(stroke
				(width 0.1)
				(type default)
			)
			(layer "F.Fab")
		)
		(fp_line
			(start -0.67945 -0.305054)
			(end -0.12065 -0.305054)
			(stroke
				(width 0.1)
				(type default)
			)
			(layer "F.Fab")
		)
		(fp_line
			(start 0.67945 -0.3048)
			(end 0.67945 0.3048)
			(stroke
				(width 0.1)
				(type default)
			)
			(layer "F.Fab")
		)
		(fp_line
			(start 0.12065 -0.3048)
			(end 0.67945 -0.3048)
			(stroke
				(width 0.1)
				(type default)
			)
			(layer "F.Fab")
		)
		(fp_line
			(start 0.12065 -0.2794)
			(end 0.12065 -0.3048)
			(stroke
				(width 0.1)
				(type default)
			)
			(layer "F.Fab")
		)
		(fp_line
			(start -0.12065 -0.2794)
			(end 0.12065 -0.2794)
			(stroke
				(width 0.1)
				(type default)
			)
			(layer "F.Fab")
		)
		(fp_line
			(start 0.120396 0.2794)
			(end -0.12065 0.2794)
			(stroke
				(width 0.1)
				(type default)
			)
			(layer "F.Fab")
		)
		(fp_line
			(start -0.12065 0.2794)
			(end -0.12065 0.3048)
			(stroke
				(width 0.1)
				(type default)
			)
			(layer "F.Fab")
		)
		(fp_line
			(start 0.67945 0.3048)
			(end 0.120396 0.3048)
			(stroke
				(width 0.1)
				(type default)
			)
			(layer "F.Fab")
		)
		(fp_line
			(start 0.120396 0.3048)
			(end 0.120396 0.2794)
			(stroke
				(width 0.1)
				(type default)
			)
			(layer "F.Fab")
		)
		(fp_line
			(start -0.12065 0.3048)
			(end -0.67945 0.3048)
			(stroke
				(width 0.1)
				(type default)
			)
			(layer "F.Fab")
		)
		(fp_line
			(start -0.67945 0.3048)
			(end -0.67945 -0.305054)
			(stroke
				(width 0.1)
				(type default)
			)
			(layer "F.Fab")
		)
		(pad "1" smd circle
			(at -0.40005 0 90)
			(size 0 0)
			(layers "F.Cu" "F.Mask" "F.Paste")
			(net "NC_PVCCINFAON_CPU0_ACSP7")
		)
		(pad "2" smd circle
			(at 0.40005 0 90)
			(size 0 0)
			(layers "F.Cu" "F.Mask" "F.Paste")
			(net "GND")
		)
	)
	(footprint ""
		(layer "F.Cu")
		(at 112.604804 -344.029284 90)
		(property "Reference" "PC582"
			(at 0 0 90)
			(layer "F.SilkS")
			(hide yes)
			(effects
				(font
					(size 1.27 1.27)
				)
			)
		)
		(property "Value" ""
			(at 0 0 90)
			(layer "F.Fab")
			(effects
				(font
					(size 1.27 1.27)
				)
			)
		)
		(duplicate_pad_numbers_are_jumpers no)
		(fp_line
			(start -3.400044 1.249934)
			(end 3.400044 1.249934)
			(stroke
				(width 0.1524)
				(type default)
			)
			(layer "F.SilkS")
		)
		(fp_circle
			(center 0 1.249934)
			(end 0 4.649978)
			(stroke
				(width 0.1524)
				(type default)
			)
			(fill no)
			(layer "F.SilkS")
		)
		(fp_poly
			(pts
				(arc
					(start -3.400044 1.249934)
					(mid 0 4.649978)
					(end 3.400044 1.249934)
				)
			)
			(stroke
				(width 0)
				(type default)
			)
			(fill yes)
			(layer "F.SilkS")
		)
		(fp_circle
			(center 0 1.249934)
			(end 0 4.649978)
			(stroke
				(width 0.1)
				(type default)
			)
			(fill no)
			(layer "F.Fab")
		)
		(pad "1" thru_hole rect
			(at 0 0 90)
			(size 1.524 1.524)
			(drill 1.016)
			(layers "*.Cu" "*.Mask")
			(remove_unused_layers no)
			(net "SW_P12V_PVCCIN_CPU1_FLT")
			(clearance 0)
			(padstack
				(mode front_inner_back)
				(layer "Inner"
					(shape circle)
					(size 1.524 1.524)
					(clearance 0)
				)
				(layer "B.Cu"
					(shape rect)
					(size 1.524 1.524)
					(clearance 0)
				)
			)
		)
		(pad "2" thru_hole circle
			(at 0 2.500122 90)
			(size 1.524 1.524)
			(drill 1.016)
			(layers "*.Cu" "*.Mask")
			(remove_unused_layers no)
			(net "GND")
			(clearance 0)
		)
	)
	(footprint ""
		(layer "F.Cu")
		(at 214.86241 -26.111454 90)
		(property "Reference" "OSC1"
			(at 1.289812 2.894076 0)
			(unlocked yes)
			(layer "F.SilkS")
			(effects
				(font
					(size 0.7874 0.5842)
					(thickness 0.1524)
				)
				(justify left)
			)
		)
		(property "Value" ""
			(at 0 0 90)
			(layer "F.Fab")
			(effects
				(font
					(size 1.27 1.27)
				)
			)
		)
		(duplicate_pad_numbers_are_jumpers no)
		(fp_line
			(start 1.546098 -1.94945)
			(end -1.546098 -1.94945)
			(stroke
				(width 0.1524)
				(type default)
			)
			(layer "F.SilkS")
		)
		(fp_line
			(start -1.546098 -1.94945)
			(end -1.546098 1.94945)
			(stroke
				(width 0.1524)
				(type default)
			)
			(layer "F.SilkS")
		)
		(fp_line
			(start 1.546098 1.94945)
			(end 1.546098 -1.94945)
			(stroke
				(width 0.1524)
				(type default)
			)
			(layer "F.SilkS")
		)
		(fp_line
			(start -1.546098 1.94945)
			(end 1.546098 1.94945)
			(stroke
				(width 0.1524)
				(type default)
			)
			(layer "F.SilkS")
		)
		(fp_poly
			(pts
				(xy -0.947674 -2.054098) (xy -1.430274 -3.374898) (xy -0.312674 -3.374898)
			)
			(stroke
				(width 0)
				(type default)
			)
			(fill yes)
			(layer "F.SilkS")
		)
		(fp_line
			(start 1.299972 -1.649984)
			(end 1.299972 1.649984)
			(stroke
				(width 0.1)
				(type default)
			)
			(layer "F.Fab")
		)
		(fp_line
			(start -1.299972 -1.649984)
			(end 1.299972 -1.649984)
			(stroke
				(width 0.1)
				(type default)
			)
			(layer "F.Fab")
		)
		(fp_line
			(start 1.299972 1.649984)
			(end -1.299972 1.649984)
			(stroke
				(width 0.1)
				(type default)
			)
			(layer "F.Fab")
		)
		(fp_line
			(start -1.299972 1.649984)
			(end -1.299972 -1.649984)
			(stroke
				(width 0.1)
				(type default)
			)
			(layer "F.Fab")
		)
		(fp_poly
			(pts
				(xy -1.768094 -1.059942) (xy -3.088894 -1.694942) (xy -3.088894 -0.577342)
			)
			(stroke
				(width 0)
				(type default)
			)
			(fill yes)
			(layer "F.Fab")
		)
		(pad "1" smd rect
			(at -0.8001 -1.059942 90)
			(size 1.2192 1.4986)
			(layers "F.Cu" "F.Mask" "F.Paste")
			(net "CLK_50M_EN")
		)
		(pad "2" smd rect
			(at -0.8001 1.059942 270)
			(size 1.2192 1.4986)
			(layers "F.Cu" "F.Mask" "F.Paste")
			(net "GND")
		)
		(pad "3" smd rect
			(at 0.8001 1.059942 90)
			(size 1.2192 1.4986)
			(layers "F.Cu" "F.Mask" "F.Paste")
			(net "CLK_50M_RMII")
		)
		(pad "4" smd rect
			(at 0.8001 -1.059942 90)
			(size 1.2192 1.4986)
			(layers "F.Cu" "F.Mask" "F.Paste")
			(net "P3V3_AUX")
		)
	)
	(footprint ""
		(layer "F.Cu")
		(at 237.401608 -402.689822)
		(property "Reference" "PC2225"
			(at 0 0 0)
			(layer "F.SilkS")
			(hide yes)
			(effects
				(font
					(size 1.27 1.27)
				)
			)
		)
		(property "Value" ""
			(at 0 0 0)
			(layer "F.Fab")
			(effects
				(font
					(size 1.27 1.27)
				)
			)
		)
		(duplicate_pad_numbers_are_jumpers no)
		(fp_line
			(start -0.7874 -0.4064)
			(end 0.7874 -0.4064)
			(stroke
				(width 0.1524)
				(type default)
			)
			(layer "F.SilkS")
		)
		(fp_line
			(start -0.7874 0.4064)
			(end -0.7874 -0.4064)
			(stroke
				(width 0.1524)
				(type default)
			)
			(layer "F.SilkS")
		)
		(fp_line
			(start 0.7874 -0.4064)
			(end 0.7874 0.4064)
			(stroke
				(width 0.1524)
				(type default)
			)
			(layer "F.SilkS")
		)
		(fp_line
			(start 0.7874 0.4064)
			(end -0.7874 0.4064)
			(stroke
				(width 0.1524)
				(type default)
			)
			(layer "F.SilkS")
		)
		(fp_line
			(start -0.67945 -0.305054)
			(end -0.12065 -0.305054)
			(stroke
				(width 0.1)
				(type default)
			)
			(layer "F.Fab")
		)
		(fp_line
			(start -0.67945 0.3048)
			(end -0.67945 -0.305054)
			(stroke
				(width 0.1)
				(type default)
			)
			(layer "F.Fab")
		)
		(fp_line
			(start -0.12065 -0.305054)
			(end -0.12065 -0.2794)
			(stroke
				(width 0.1)
				(type default)
			)
			(layer "F.Fab")
		)
		(fp_line
			(start -0.12065 -0.2794)
			(end 0.12065 -0.2794)
			(stroke
				(width 0.1)
				(type default)
			)
			(layer "F.Fab")
		)
		(fp_line
			(start -0.12065 0.2794)
			(end -0.12065 0.3048)
			(stroke
				(width 0.1)
				(type default)
			)
			(layer "F.Fab")
		)
		(fp_line
			(start -0.12065 0.3048)
			(end -0.67945 0.3048)
			(stroke
				(width 0.1)
				(type default)
			)
			(layer "F.Fab")
		)
		(fp_line
			(start 0.120396 0.2794)
			(end -0.12065 0.2794)
			(stroke
				(width 0.1)
				(type default)
			)
			(layer "F.Fab")
		)
		(fp_line
			(start 0.120396 0.3048)
			(end 0.120396 0.2794)
			(stroke
				(width 0.1)
				(type default)
			)
			(layer "F.Fab")
		)
		(fp_line
			(start 0.12065 -0.3048)
			(end 0.67945 -0.3048)
			(stroke
				(width 0.1)
				(type default)
			)
			(layer "F.Fab")
		)
		(fp_line
			(start 0.12065 -0.2794)
			(end 0.12065 -0.3048)
			(stroke
				(width 0.1)
				(type default)
			)
			(layer "F.Fab")
		)
		(fp_line
			(start 0.67945 -0.3048)
			(end 0.67945 0.3048)
			(stroke
				(width 0.1)
				(type default)
			)
			(layer "F.Fab")
		)
		(fp_line
			(start 0.67945 0.3048)
			(end 0.120396 0.3048)
			(stroke
				(width 0.1)
				(type default)
			)
			(layer "F.Fab")
		)
		(pad "1" smd circle
			(at -0.40005 0)
			(size 0 0)
			(layers "F.Cu" "F.Mask" "F.Paste")
			(net "HSC_ON")
		)
		(pad "2" smd circle
			(at 0.40005 0)
			(size 0 0)
			(layers "F.Cu" "F.Mask" "F.Paste")
			(net "AGND_HSC")
		)
	)
	(footprint ""
		(layer "F.Cu")
		(at 27.22118 -385.760468 90)
		(property "Reference" "R4537"
			(at 0 0 90)
			(layer "F.SilkS")
			(hide yes)
			(effects
				(font
					(size 1.27 1.27)
				)
			)
		)
		(property "Value" ""
			(at 0 0 90)
			(layer "F.Fab")
			(effects
				(font
					(size 1.27 1.27)
				)
			)
		)
		(duplicate_pad_numbers_are_jumpers no)
		(fp_line
			(start 0.7874 -0.4064)
			(end 0.7874 0.4064)
			(stroke
				(width 0.1524)
				(type default)
			)
			(layer "F.SilkS")
		)
		(fp_line
			(start -0.7874 -0.4064)
			(end 0.7874 -0.4064)
			(stroke
				(width 0.1524)
				(type default)
			)
			(layer "F.SilkS")
		)
		(fp_line
			(start 0.7874 0.4064)
			(end -0.7874 0.4064)
			(stroke
				(width 0.1524)
				(type default)
			)
			(layer "F.SilkS")
		)
		(fp_line
			(start -0.7874 0.4064)
			(end -0.7874 -0.4064)
			(stroke
				(width 0.1524)
				(type default)
			)
			(layer "F.SilkS")
		)
		(fp_line
			(start -0.12065 -0.305054)
			(end -0.12065 -0.2794)
			(stroke
				(width 0.1)
				(type default)
			)
			(layer "F.Fab")
		)
		(fp_line
			(start -0.67945 -0.305054)
			(end -0.12065 -0.305054)
			(stroke
				(width 0.1)
				(type default)
			)
			(layer "F.Fab")
		)
		(fp_line
			(start 0.67945 -0.3048)
			(end 0.67945 0.3048)
			(stroke
				(width 0.1)
				(type default)
			)
			(layer "F.Fab")
		)
		(fp_line
			(start 0.12065 -0.3048)
			(end 0.67945 -0.3048)
			(stroke
				(width 0.1)
				(type default)
			)
			(layer "F.Fab")
		)
		(fp_line
			(start 0.12065 -0.2794)
			(end 0.12065 -0.3048)
			(stroke
				(width 0.1)
				(type default)
			)
			(layer "F.Fab")
		)
		(fp_line
			(start -0.12065 -0.2794)
			(end 0.12065 -0.2794)
			(stroke
				(width 0.1)
				(type default)
			)
			(layer "F.Fab")
		)
		(fp_line
			(start 0.120396 0.2794)
			(end -0.12065 0.2794)
			(stroke
				(width 0.1)
				(type default)
			)
			(layer "F.Fab")
		)
		(fp_line
			(start -0.12065 0.2794)
			(end -0.12065 0.3048)
			(stroke
				(width 0.1)
				(type default)
			)
			(layer "F.Fab")
		)
		(fp_line
			(start 0.67945 0.3048)
			(end 0.120396 0.3048)
			(stroke
				(width 0.1)
				(type default)
			)
			(layer "F.Fab")
		)
		(fp_line
			(start 0.120396 0.3048)
			(end 0.120396 0.2794)
			(stroke
				(width 0.1)
				(type default)
			)
			(layer "F.Fab")
		)
		(fp_line
			(start -0.12065 0.3048)
			(end -0.67945 0.3048)
			(stroke
				(width 0.1)
				(type default)
			)
			(layer "F.Fab")
		)
		(fp_line
			(start -0.67945 0.3048)
			(end -0.67945 -0.305054)
			(stroke
				(width 0.1)
				(type default)
			)
			(layer "F.Fab")
		)
		(pad "1" smd circle
			(at -0.40005 0 90)
			(size 0 0)
			(layers "F.Cu" "F.Mask" "F.Paste")
			(net "FM_P2E_EN_N")
		)
		(pad "2" smd circle
			(at 0.40005 0 90)
			(size 0 0)
			(layers "F.Cu" "F.Mask" "F.Paste")
			(net "CLK_GEN2_GPU_FPGA_OE_OR_N")
		)
	)
	(footprint ""
		(layer "F.Cu")
		(at 371.545358 -92.962984 -90)
		(property "Reference" "R1347"
			(at 0 0 270)
			(layer "F.SilkS")
			(hide yes)
			(effects
				(font
					(size 1.27 1.27)
				)
			)
		)
		(property "Value" ""
			(at 0 0 270)
			(layer "F.Fab")
			(effects
				(font
					(size 1.27 1.27)
				)
			)
		)
		(duplicate_pad_numbers_are_jumpers no)
		(fp_line
			(start -0.7874 0.4064)
			(end -0.7874 -0.4064)
			(stroke
				(width 0.1524)
				(type default)
			)
			(layer "F.SilkS")
		)
		(fp_line
			(start 0.7874 0.4064)
			(end -0.7874 0.4064)
			(stroke
				(width 0.1524)
				(type default)
			)
			(layer "F.SilkS")
		)
		(fp_line
			(start -0.7874 -0.4064)
			(end 0.7874 -0.4064)
			(stroke
				(width 0.1524)
				(type default)
			)
			(layer "F.SilkS")
		)
		(fp_line
			(start 0.7874 -0.4064)
			(end 0.7874 0.4064)
			(stroke
				(width 0.1524)
				(type default)
			)
			(layer "F.SilkS")
		)
		(fp_line
			(start -0.67945 0.3048)
			(end -0.67945 -0.305054)
			(stroke
				(width 0.1)
				(type default)
			)
			(layer "F.Fab")
		)
		(fp_line
			(start -0.12065 0.3048)
			(end -0.67945 0.3048)
			(stroke
				(width 0.1)
				(type default)
			)
			(layer "F.Fab")
		)
		(fp_line
			(start 0.120396 0.3048)
			(end 0.120396 0.2794)
			(stroke
				(width 0.1)
				(type default)
			)
			(layer "F.Fab")
		)
		(fp_line
			(start 0.67945 0.3048)
			(end 0.120396 0.3048)
			(stroke
				(width 0.1)
				(type default)
			)
			(layer "F.Fab")
		)
		(fp_line
			(start -0.12065 0.2794)
			(end -0.12065 0.3048)
			(stroke
				(width 0.1)
				(type default)
			)
			(layer "F.Fab")
		)
		(fp_line
			(start 0.120396 0.2794)
			(end -0.12065 0.2794)
			(stroke
				(width 0.1)
				(type default)
			)
			(layer "F.Fab")
		)
		(fp_line
			(start -0.12065 -0.2794)
			(end 0.12065 -0.2794)
			(stroke
				(width 0.1)
				(type default)
			)
			(layer "F.Fab")
		)
		(fp_line
			(start 0.12065 -0.2794)
			(end 0.12065 -0.3048)
			(stroke
				(width 0.1)
				(type default)
			)
			(layer "F.Fab")
		)
		(fp_line
			(start 0.12065 -0.3048)
			(end 0.67945 -0.3048)
			(stroke
				(width 0.1)
				(type default)
			)
			(layer "F.Fab")
		)
		(fp_line
			(start 0.67945 -0.3048)
			(end 0.67945 0.3048)
			(stroke
				(width 0.1)
				(type default)
			)
			(layer "F.Fab")
		)
		(fp_line
			(start -0.67945 -0.305054)
			(end -0.12065 -0.305054)
			(stroke
				(width 0.1)
				(type default)
			)
			(layer "F.Fab")
		)
		(fp_line
			(start -0.12065 -0.305054)
			(end -0.12065 -0.2794)
			(stroke
				(width 0.1)
				(type default)
			)
			(layer "F.Fab")
		)
		(pad "1" smd circle
			(at -0.40005 0 270)
			(size 0 0)
			(layers "F.Cu" "F.Mask" "F.Paste")
			(net "PD_GTL2014_BMC_JTAG_VREF_1")
		)
		(pad "2" smd circle
			(at 0.40005 0 270)
			(size 0 0)
			(layers "F.Cu" "F.Mask" "F.Paste")
			(net "GND")
		)
	)
	(footprint ""
		(layer "F.Cu")
		(at 104.352852 -256.6543 -90)
		(property "Reference" "C446"
			(at 0 0 270)
			(layer "F.SilkS")
			(hide yes)
			(effects
				(font
					(size 1.27 1.27)
				)
			)
		)
		(property "Value" ""
			(at 0 0 270)
			(layer "F.Fab")
			(effects
				(font
					(size 1.27 1.27)
				)
			)
		)
		(duplicate_pad_numbers_are_jumpers no)
		(fp_line
			(start -0.7874 0.4064)
			(end -0.7874 -0.4064)
			(stroke
				(width 0.1524)
				(type default)
			)
			(layer "F.SilkS")
		)
		(fp_line
			(start 0.7874 0.4064)
			(end -0.7874 0.4064)
			(stroke
				(width 0.1524)
				(type default)
			)
			(layer "F.SilkS")
		)
		(fp_line
			(start -0.7874 -0.4064)
			(end 0.7874 -0.4064)
			(stroke
				(width 0.1524)
				(type default)
			)
			(layer "F.SilkS")
		)
		(fp_line
			(start 0.7874 -0.4064)
			(end 0.7874 0.4064)
			(stroke
				(width 0.1524)
				(type default)
			)
			(layer "F.SilkS")
		)
		(fp_line
			(start -0.67945 0.3048)
			(end -0.67945 -0.305054)
			(stroke
				(width 0.1)
				(type default)
			)
			(layer "F.Fab")
		)
		(fp_line
			(start -0.12065 0.3048)
			(end -0.67945 0.3048)
			(stroke
				(width 0.1)
				(type default)
			)
			(layer "F.Fab")
		)
		(fp_line
			(start 0.120396 0.3048)
			(end 0.120396 0.2794)
			(stroke
				(width 0.1)
				(type default)
			)
			(layer "F.Fab")
		)
		(fp_line
			(start 0.67945 0.3048)
			(end 0.120396 0.3048)
			(stroke
				(width 0.1)
				(type default)
			)
			(layer "F.Fab")
		)
		(fp_line
			(start -0.12065 0.2794)
			(end -0.12065 0.3048)
			(stroke
				(width 0.1)
				(type default)
			)
			(layer "F.Fab")
		)
		(fp_line
			(start 0.120396 0.2794)
			(end -0.12065 0.2794)
			(stroke
				(width 0.1)
				(type default)
			)
			(layer "F.Fab")
		)
		(fp_line
			(start -0.12065 -0.2794)
			(end 0.12065 -0.2794)
			(stroke
				(width 0.1)
				(type default)
			)
			(layer "F.Fab")
		)
		(fp_line
			(start 0.12065 -0.2794)
			(end 0.12065 -0.3048)
			(stroke
				(width 0.1)
				(type default)
			)
			(layer "F.Fab")
		)
		(fp_line
			(start 0.12065 -0.3048)
			(end 0.67945 -0.3048)
			(stroke
				(width 0.1)
				(type default)
			)
			(layer "F.Fab")
		)
		(fp_line
			(start 0.67945 -0.3048)
			(end 0.67945 0.3048)
			(stroke
				(width 0.1)
				(type default)
			)
			(layer "F.Fab")
		)
		(fp_line
			(start -0.67945 -0.305054)
			(end -0.12065 -0.305054)
			(stroke
				(width 0.1)
				(type default)
			)
			(layer "F.Fab")
		)
		(fp_line
			(start -0.12065 -0.305054)
			(end -0.12065 -0.2794)
			(stroke
				(width 0.1)
				(type default)
			)
			(layer "F.Fab")
		)
		(pad "1" smd circle
			(at -0.40005 0 270)
			(size 0 0)
			(layers "F.Cu" "F.Mask" "F.Paste")
			(net "PVCCFA_EHV_CPU1")
		)
		(pad "2" smd circle
			(at 0.40005 0 270)
			(size 0 0)
			(layers "F.Cu" "F.Mask" "F.Paste")
			(net "GND")
		)
	)
	(footprint ""
		(layer "F.Cu")
		(at 162.34283 -78.984348)
		(property "Reference" "R2210"
			(at 0 0 0)
			(layer "F.SilkS")
			(hide yes)
			(effects
				(font
					(size 1.27 1.27)
				)
			)
		)
		(property "Value" ""
			(at 0 0 0)
			(layer "F.Fab")
			(effects
				(font
					(size 1.27 1.27)
				)
			)
		)
		(duplicate_pad_numbers_are_jumpers no)
		(fp_line
			(start -0.7874 -0.4064)
			(end 0.7874 -0.4064)
			(stroke
				(width 0.1524)
				(type default)
			)
			(layer "F.SilkS")
		)
		(fp_line
			(start -0.7874 0.4064)
			(end -0.7874 -0.4064)
			(stroke
				(width 0.1524)
				(type default)
			)
			(layer "F.SilkS")
		)
		(fp_line
			(start 0.7874 -0.4064)
			(end 0.7874 0.4064)
			(stroke
				(width 0.1524)
				(type default)
			)
			(layer "F.SilkS")
		)
		(fp_line
			(start 0.7874 0.4064)
			(end -0.7874 0.4064)
			(stroke
				(width 0.1524)
				(type default)
			)
			(layer "F.SilkS")
		)
		(fp_line
			(start -0.67945 -0.305054)
			(end -0.12065 -0.305054)
			(stroke
				(width 0.1)
				(type default)
			)
			(layer "F.Fab")
		)
		(fp_line
			(start -0.67945 0.3048)
			(end -0.67945 -0.305054)
			(stroke
				(width 0.1)
				(type default)
			)
			(layer "F.Fab")
		)
		(fp_line
			(start -0.12065 -0.305054)
			(end -0.12065 -0.2794)
			(stroke
				(width 0.1)
				(type default)
			)
			(layer "F.Fab")
		)
		(fp_line
			(start -0.12065 -0.2794)
			(end 0.12065 -0.2794)
			(stroke
				(width 0.1)
				(type default)
			)
			(layer "F.Fab")
		)
		(fp_line
			(start -0.12065 0.2794)
			(end -0.12065 0.3048)
			(stroke
				(width 0.1)
				(type default)
			)
			(layer "F.Fab")
		)
		(fp_line
			(start -0.12065 0.3048)
			(end -0.67945 0.3048)
			(stroke
				(width 0.1)
				(type default)
			)
			(layer "F.Fab")
		)
		(fp_line
			(start 0.120396 0.2794)
			(end -0.12065 0.2794)
			(stroke
				(width 0.1)
				(type default)
			)
			(layer "F.Fab")
		)
		(fp_line
			(start 0.120396 0.3048)
			(end 0.120396 0.2794)
			(stroke
				(width 0.1)
				(type default)
			)
			(layer "F.Fab")
		)
		(fp_line
			(start 0.12065 -0.3048)
			(end 0.67945 -0.3048)
			(stroke
				(width 0.1)
				(type default)
			)
			(layer "F.Fab")
		)
		(fp_line
			(start 0.12065 -0.2794)
			(end 0.12065 -0.3048)
			(stroke
				(width 0.1)
				(type default)
			)
			(layer "F.Fab")
		)
		(fp_line
			(start 0.67945 -0.3048)
			(end 0.67945 0.3048)
			(stroke
				(width 0.1)
				(type default)
			)
			(layer "F.Fab")
		)
		(fp_line
			(start 0.67945 0.3048)
			(end 0.120396 0.3048)
			(stroke
				(width 0.1)
				(type default)
			)
			(layer "F.Fab")
		)
		(pad "1" smd circle
			(at -0.40005 0)
			(size 0 0)
			(layers "F.Cu" "F.Mask" "F.Paste")
			(net "SMB_S3M_CPU1_3V3AUX_SDA_R")
		)
		(pad "2" smd circle
			(at 0.40005 0)
			(size 0 0)
			(layers "F.Cu" "F.Mask" "F.Paste")
			(net "SMB_S3M_CPU1_3V3AUX_SDA")
		)
	)
	(footprint ""
		(layer "F.Cu")
		(at 40.413178 -397.406622 90)
		(property "Reference" "R4654"
			(at 0 0 90)
			(layer "F.SilkS")
			(hide yes)
			(effects
				(font
					(size 1.27 1.27)
				)
			)
		)
		(property "Value" ""
			(at 0 0 90)
			(layer "F.Fab")
			(effects
				(font
					(size 1.27 1.27)
				)
			)
		)
		(duplicate_pad_numbers_are_jumpers no)
		(fp_line
			(start 0.7874 -0.4064)
			(end 0.7874 0.4064)
			(stroke
				(width 0.1524)
				(type default)
			)
			(layer "F.SilkS")
		)
		(fp_line
			(start -0.7874 -0.4064)
			(end 0.7874 -0.4064)
			(stroke
				(width 0.1524)
				(type default)
			)
			(layer "F.SilkS")
		)
		(fp_line
			(start 0.7874 0.4064)
			(end -0.7874 0.4064)
			(stroke
				(width 0.1524)
				(type default)
			)
			(layer "F.SilkS")
		)
		(fp_line
			(start -0.7874 0.4064)
			(end -0.7874 -0.4064)
			(stroke
				(width 0.1524)
				(type default)
			)
			(layer "F.SilkS")
		)
		(fp_line
			(start -0.12065 -0.305054)
			(end -0.12065 -0.2794)
			(stroke
				(width 0.1)
				(type default)
			)
			(layer "F.Fab")
		)
		(fp_line
			(start -0.67945 -0.305054)
			(end -0.12065 -0.305054)
			(stroke
				(width 0.1)
				(type default)
			)
			(layer "F.Fab")
		)
		(fp_line
			(start 0.67945 -0.3048)
			(end 0.67945 0.3048)
			(stroke
				(width 0.1)
				(type default)
			)
			(layer "F.Fab")
		)
		(fp_line
			(start 0.12065 -0.3048)
			(end 0.67945 -0.3048)
			(stroke
				(width 0.1)
				(type default)
			)
			(layer "F.Fab")
		)
		(fp_line
			(start 0.12065 -0.2794)
			(end 0.12065 -0.3048)
			(stroke
				(width 0.1)
				(type default)
			)
			(layer "F.Fab")
		)
		(fp_line
			(start -0.12065 -0.2794)
			(end 0.12065 -0.2794)
			(stroke
				(width 0.1)
				(type default)
			)
			(layer "F.Fab")
		)
		(fp_line
			(start 0.120396 0.2794)
			(end -0.12065 0.2794)
			(stroke
				(width 0.1)
				(type default)
			)
			(layer "F.Fab")
		)
		(fp_line
			(start -0.12065 0.2794)
			(end -0.12065 0.3048)
			(stroke
				(width 0.1)
				(type default)
			)
			(layer "F.Fab")
		)
		(fp_line
			(start 0.67945 0.3048)
			(end 0.120396 0.3048)
			(stroke
				(width 0.1)
				(type default)
			)
			(layer "F.Fab")
		)
		(fp_line
			(start 0.120396 0.3048)
			(end 0.120396 0.2794)
			(stroke
				(width 0.1)
				(type default)
			)
			(layer "F.Fab")
		)
		(fp_line
			(start -0.12065 0.3048)
			(end -0.67945 0.3048)
			(stroke
				(width 0.1)
				(type default)
			)
			(layer "F.Fab")
		)
		(fp_line
			(start -0.67945 0.3048)
			(end -0.67945 -0.305054)
			(stroke
				(width 0.1)
				(type default)
			)
			(layer "F.Fab")
		)
		(pad "1" smd circle
			(at -0.40005 0 90)
			(size 0 0)
			(layers "F.Cu" "F.Mask" "F.Paste")
			(net "FM_P2E_BUF2_EQA1")
		)
		(pad "2" smd circle
			(at 0.40005 0 90)
			(size 0 0)
			(layers "F.Cu" "F.Mask" "F.Paste")
			(net "GND")
		)
	)
	(footprint ""
		(layer "F.Cu")
		(at 208.054956 -30.276292 90)
		(property "Reference" "R3612"
			(at 0 0 90)
			(layer "F.SilkS")
			(hide yes)
			(effects
				(font
					(size 1.27 1.27)
				)
			)
		)
		(property "Value" ""
			(at 0 0 90)
			(layer "F.Fab")
			(effects
				(font
					(size 1.27 1.27)
				)
			)
		)
		(duplicate_pad_numbers_are_jumpers no)
		(fp_line
			(start 0.7874 -0.4064)
			(end 0.7874 0.4064)
			(stroke
				(width 0.1524)
				(type default)
			)
			(layer "F.SilkS")
		)
		(fp_line
			(start -0.7874 -0.4064)
			(end 0.7874 -0.4064)
			(stroke
				(width 0.1524)
				(type default)
			)
			(layer "F.SilkS")
		)
		(fp_line
			(start 0.7874 0.4064)
			(end -0.7874 0.4064)
			(stroke
				(width 0.1524)
				(type default)
			)
			(layer "F.SilkS")
		)
		(fp_line
			(start -0.7874 0.4064)
			(end -0.7874 -0.4064)
			(stroke
				(width 0.1524)
				(type default)
			)
			(layer "F.SilkS")
		)
		(fp_line
			(start -0.12065 -0.305054)
			(end -0.12065 -0.2794)
			(stroke
				(width 0.1)
				(type default)
			)
			(layer "F.Fab")
		)
		(fp_line
			(start -0.67945 -0.305054)
			(end -0.12065 -0.305054)
			(stroke
				(width 0.1)
				(type default)
			)
			(layer "F.Fab")
		)
		(fp_line
			(start 0.67945 -0.3048)
			(end 0.67945 0.3048)
			(stroke
				(width 0.1)
				(type default)
			)
			(layer "F.Fab")
		)
		(fp_line
			(start 0.12065 -0.3048)
			(end 0.67945 -0.3048)
			(stroke
				(width 0.1)
				(type default)
			)
			(layer "F.Fab")
		)
		(fp_line
			(start 0.12065 -0.2794)
			(end 0.12065 -0.3048)
			(stroke
				(width 0.1)
				(type default)
			)
			(layer "F.Fab")
		)
		(fp_line
			(start -0.12065 -0.2794)
			(end 0.12065 -0.2794)
			(stroke
				(width 0.1)
				(type default)
			)
			(layer "F.Fab")
		)
		(fp_line
			(start 0.120396 0.2794)
			(end -0.12065 0.2794)
			(stroke
				(width 0.1)
				(type default)
			)
			(layer "F.Fab")
		)
		(fp_line
			(start -0.12065 0.2794)
			(end -0.12065 0.3048)
			(stroke
				(width 0.1)
				(type default)
			)
			(layer "F.Fab")
		)
		(fp_line
			(start 0.67945 0.3048)
			(end 0.120396 0.3048)
			(stroke
				(width 0.1)
				(type default)
			)
			(layer "F.Fab")
		)
		(fp_line
			(start 0.120396 0.3048)
			(end 0.120396 0.2794)
			(stroke
				(width 0.1)
				(type default)
			)
			(layer "F.Fab")
		)
		(fp_line
			(start -0.12065 0.3048)
			(end -0.67945 0.3048)
			(stroke
				(width 0.1)
				(type default)
			)
			(layer "F.Fab")
		)
		(fp_line
			(start -0.67945 0.3048)
			(end -0.67945 -0.305054)
			(stroke
				(width 0.1)
				(type default)
			)
			(layer "F.Fab")
		)
		(pad "1" smd circle
			(at -0.40005 0 90)
			(size 0 0)
			(layers "F.Cu" "F.Mask" "F.Paste")
			(net "GND")
		)
		(pad "2" smd circle
			(at 0.40005 0 90)
			(size 0 0)
			(layers "F.Cu" "F.Mask" "F.Paste")
			(net "INA230_5_A1")
		)
	)
	(footprint ""
		(layer "F.Cu")
		(at 412.13405 -402.371052 -90)
		(property "Reference" "C960"
			(at 0 0 270)
			(layer "F.SilkS")
			(hide yes)
			(effects
				(font
					(size 1.27 1.27)
				)
			)
		)
		(property "Value" ""
			(at 0 0 270)
			(layer "F.Fab")
			(effects
				(font
					(size 1.27 1.27)
				)
			)
		)
		(duplicate_pad_numbers_are_jumpers no)
		(fp_line
			(start -0.299974 0.150114)
			(end -0.299974 -0.150114)
			(stroke
				(width 0.1)
				(type default)
			)
			(layer "F.Fab")
		)
		(fp_line
			(start 0.299974 0.150114)
			(end -0.299974 0.150114)
			(stroke
				(width 0.1)
				(type default)
			)
			(layer "F.Fab")
		)
		(fp_line
			(start -0.299974 -0.150114)
			(end 0.299974 -0.150114)
			(stroke
				(width 0.1)
				(type default)
			)
			(layer "F.Fab")
		)
		(fp_line
			(start 0.299974 -0.150114)
			(end 0.299974 0.150114)
			(stroke
				(width 0.1)
				(type default)
			)
			(layer "F.Fab")
		)
		(pad "1" smd rect
			(at -0.2667 0 270)
			(size 0.3048 0.381)
			(layers "F.Cu" "F.Mask" "F.Paste")
			(net "P5E_CPU0_PE2_TX_C_DN<2>")
		)
		(pad "2" smd rect
			(at 0.2667 0 270)
			(size 0.3048 0.381)
			(layers "F.Cu" "F.Mask" "F.Paste")
			(net "P5E_CPU0_PE2_TX_DN<2>")
		)
	)
	(footprint ""
		(layer "F.Cu")
		(at 422.74744 -152.024588)
		(property "Reference" "PR1778"
			(at 0 0 0)
			(layer "F.SilkS")
			(hide yes)
			(effects
				(font
					(size 1.27 1.27)
				)
			)
		)
		(property "Value" ""
			(at 0 0 0)
			(layer "F.Fab")
			(effects
				(font
					(size 1.27 1.27)
				)
			)
		)
		(duplicate_pad_numbers_are_jumpers no)
		(fp_line
			(start -0.7874 -0.4064)
			(end 0.7874 -0.4064)
			(stroke
				(width 0.1524)
				(type default)
			)
			(layer "F.SilkS")
		)
		(fp_line
			(start -0.7874 0.4064)
			(end -0.7874 -0.4064)
			(stroke
				(width 0.1524)
				(type default)
			)
			(layer "F.SilkS")
		)
		(fp_line
			(start 0.7874 -0.4064)
			(end 0.7874 0.4064)
			(stroke
				(width 0.1524)
				(type default)
			)
			(layer "F.SilkS")
		)
		(fp_line
			(start 0.7874 0.4064)
			(end -0.7874 0.4064)
			(stroke
				(width 0.1524)
				(type default)
			)
			(layer "F.SilkS")
		)
		(fp_line
			(start -0.67945 -0.305054)
			(end -0.12065 -0.305054)
			(stroke
				(width 0.1)
				(type default)
			)
			(layer "F.Fab")
		)
		(fp_line
			(start -0.67945 0.3048)
			(end -0.67945 -0.305054)
			(stroke
				(width 0.1)
				(type default)
			)
			(layer "F.Fab")
		)
		(fp_line
			(start -0.12065 -0.305054)
			(end -0.12065 -0.2794)
			(stroke
				(width 0.1)
				(type default)
			)
			(layer "F.Fab")
		)
		(fp_line
			(start -0.12065 -0.2794)
			(end 0.12065 -0.2794)
			(stroke
				(width 0.1)
				(type default)
			)
			(layer "F.Fab")
		)
		(fp_line
			(start -0.12065 0.2794)
			(end -0.12065 0.3048)
			(stroke
				(width 0.1)
				(type default)
			)
			(layer "F.Fab")
		)
		(fp_line
			(start -0.12065 0.3048)
			(end -0.67945 0.3048)
			(stroke
				(width 0.1)
				(type default)
			)
			(layer "F.Fab")
		)
		(fp_line
			(start 0.120396 0.2794)
			(end -0.12065 0.2794)
			(stroke
				(width 0.1)
				(type default)
			)
			(layer "F.Fab")
		)
		(fp_line
			(start 0.120396 0.3048)
			(end 0.120396 0.2794)
			(stroke
				(width 0.1)
				(type default)
			)
			(layer "F.Fab")
		)
		(fp_line
			(start 0.12065 -0.3048)
			(end 0.67945 -0.3048)
			(stroke
				(width 0.1)
				(type default)
			)
			(layer "F.Fab")
		)
		(fp_line
			(start 0.12065 -0.2794)
			(end 0.12065 -0.3048)
			(stroke
				(width 0.1)
				(type default)
			)
			(layer "F.Fab")
		)
		(fp_line
			(start 0.67945 -0.3048)
			(end 0.67945 0.3048)
			(stroke
				(width 0.1)
				(type default)
			)
			(layer "F.Fab")
		)
		(fp_line
			(start 0.67945 0.3048)
			(end 0.120396 0.3048)
			(stroke
				(width 0.1)
				(type default)
			)
			(layer "F.Fab")
		)
		(pad "1" smd circle
			(at -0.40005 0)
			(size 0 0)
			(layers "F.Cu" "F.Mask" "F.Paste")
			(net "SW_PVCCFA_EHV_CPU0_BOOT1")
		)
		(pad "2" smd circle
			(at 0.40005 0)
			(size 0 0)
			(layers "F.Cu" "F.Mask" "F.Paste")
			(net "SW_PVCCFA_EHV_CPU0_BOOT1_R")
		)
	)
	(footprint ""
		(layer "F.Cu")
		(at 11.421618 -105.48239 90)
		(property "Reference" "R2786"
			(at 0 0 90)
			(layer "F.SilkS")
			(hide yes)
			(effects
				(font
					(size 1.27 1.27)
				)
			)
		)
		(property "Value" ""
			(at 0 0 90)
			(layer "F.Fab")
			(effects
				(font
					(size 1.27 1.27)
				)
			)
		)
		(duplicate_pad_numbers_are_jumpers no)
		(fp_line
			(start 0.7874 -0.4064)
			(end 0.7874 0.4064)
			(stroke
				(width 0.1524)
				(type default)
			)
			(layer "F.SilkS")
		)
		(fp_line
			(start -0.7874 -0.4064)
			(end 0.7874 -0.4064)
			(stroke
				(width 0.1524)
				(type default)
			)
			(layer "F.SilkS")
		)
		(fp_line
			(start 0.01651 0.4064)
			(end -0.7874 0.4064)
			(stroke
				(width 0.1524)
				(type default)
			)
			(layer "F.SilkS")
		)
		(fp_line
			(start -0.12065 -0.305054)
			(end -0.12065 -0.2794)
			(stroke
				(width 0.1)
				(type default)
			)
			(layer "F.Fab")
		)
		(fp_line
			(start -0.67945 -0.305054)
			(end -0.12065 -0.305054)
			(stroke
				(width 0.1)
				(type default)
			)
			(layer "F.Fab")
		)
		(fp_line
			(start 0.67945 -0.3048)
			(end 0.67945 0.3048)
			(stroke
				(width 0.1)
				(type default)
			)
			(layer "F.Fab")
		)
		(fp_line
			(start 0.12065 -0.3048)
			(end 0.67945 -0.3048)
			(stroke
				(width 0.1)
				(type default)
			)
			(layer "F.Fab")
		)
		(fp_line
			(start 0.12065 -0.2794)
			(end 0.12065 -0.3048)
			(stroke
				(width 0.1)
				(type default)
			)
			(layer "F.Fab")
		)
		(fp_line
			(start -0.12065 -0.2794)
			(end 0.12065 -0.2794)
			(stroke
				(width 0.1)
				(type default)
			)
			(layer "F.Fab")
		)
		(fp_line
			(start 0.120396 0.2794)
			(end -0.12065 0.2794)
			(stroke
				(width 0.1)
				(type default)
			)
			(layer "F.Fab")
		)
		(fp_line
			(start -0.12065 0.2794)
			(end -0.12065 0.3048)
			(stroke
				(width 0.1)
				(type default)
			)
			(layer "F.Fab")
		)
		(fp_line
			(start 0.67945 0.3048)
			(end 0.120396 0.3048)
			(stroke
				(width 0.1)
				(type default)
			)
			(layer "F.Fab")
		)
		(fp_line
			(start 0.120396 0.3048)
			(end 0.120396 0.2794)
			(stroke
				(width 0.1)
				(type default)
			)
			(layer "F.Fab")
		)
		(fp_line
			(start -0.12065 0.3048)
			(end -0.67945 0.3048)
			(stroke
				(width 0.1)
				(type default)
			)
			(layer "F.Fab")
		)
		(fp_line
			(start -0.67945 0.3048)
			(end -0.67945 -0.305054)
			(stroke
				(width 0.1)
				(type default)
			)
			(layer "F.Fab")
		)
		(pad "1" smd rect
			(at -0.40005 0 270)
			(size 0.4572 0.508)
			(layers "F.Cu" "F.Mask" "F.Paste")
			(net "USB2_HUB_SWB_DP")
		)
		(pad "2" smd rect
			(at 0.40005 0 270)
			(size 0.4572 0.508)
			(layers "F.Cu" "F.Mask" "F.Paste")
			(net "USB2_HUB_BUF_SWB_R_DP")
		)
	)
	(footprint ""
		(layer "F.Cu")
		(at 345.98483 -338.180172 90)
		(property "Reference" "PR1787"
			(at 0 0 90)
			(layer "F.SilkS")
			(hide yes)
			(effects
				(font
					(size 1.27 1.27)
				)
			)
		)
		(property "Value" ""
			(at 0 0 90)
			(layer "F.Fab")
			(effects
				(font
					(size 1.27 1.27)
				)
			)
		)
		(duplicate_pad_numbers_are_jumpers no)
		(fp_line
			(start 0.7874 -0.4064)
			(end 0.7874 0.4064)
			(stroke
				(width 0.1524)
				(type default)
			)
			(layer "F.SilkS")
		)
		(fp_line
			(start -0.7874 -0.4064)
			(end 0.7874 -0.4064)
			(stroke
				(width 0.1524)
				(type default)
			)
			(layer "F.SilkS")
		)
		(fp_line
			(start 0.7874 0.4064)
			(end -0.7874 0.4064)
			(stroke
				(width 0.1524)
				(type default)
			)
			(layer "F.SilkS")
		)
		(fp_line
			(start -0.7874 0.4064)
			(end -0.7874 -0.4064)
			(stroke
				(width 0.1524)
				(type default)
			)
			(layer "F.SilkS")
		)
		(fp_line
			(start -0.12065 -0.305054)
			(end -0.12065 -0.2794)
			(stroke
				(width 0.1)
				(type default)
			)
			(layer "F.Fab")
		)
		(fp_line
			(start -0.67945 -0.305054)
			(end -0.12065 -0.305054)
			(stroke
				(width 0.1)
				(type default)
			)
			(layer "F.Fab")
		)
		(fp_line
			(start 0.67945 -0.3048)
			(end 0.67945 0.3048)
			(stroke
				(width 0.1)
				(type default)
			)
			(layer "F.Fab")
		)
		(fp_line
			(start 0.12065 -0.3048)
			(end 0.67945 -0.3048)
			(stroke
				(width 0.1)
				(type default)
			)
			(layer "F.Fab")
		)
		(fp_line
			(start 0.12065 -0.2794)
			(end 0.12065 -0.3048)
			(stroke
				(width 0.1)
				(type default)
			)
			(layer "F.Fab")
		)
		(fp_line
			(start -0.12065 -0.2794)
			(end 0.12065 -0.2794)
			(stroke
				(width 0.1)
				(type default)
			)
			(layer "F.Fab")
		)
		(fp_line
			(start 0.120396 0.2794)
			(end -0.12065 0.2794)
			(stroke
				(width 0.1)
				(type default)
			)
			(layer "F.Fab")
		)
		(fp_line
			(start -0.12065 0.2794)
			(end -0.12065 0.3048)
			(stroke
				(width 0.1)
				(type default)
			)
			(layer "F.Fab")
		)
		(fp_line
			(start 0.67945 0.3048)
			(end 0.120396 0.3048)
			(stroke
				(width 0.1)
				(type default)
			)
			(layer "F.Fab")
		)
		(fp_line
			(start 0.120396 0.3048)
			(end 0.120396 0.2794)
			(stroke
				(width 0.1)
				(type default)
			)
			(layer "F.Fab")
		)
		(fp_line
			(start -0.12065 0.3048)
			(end -0.67945 0.3048)
			(stroke
				(width 0.1)
				(type default)
			)
			(layer "F.Fab")
		)
		(fp_line
			(start -0.67945 0.3048)
			(end -0.67945 -0.305054)
			(stroke
				(width 0.1)
				(type default)
			)
			(layer "F.Fab")
		)
		(pad "1" smd circle
			(at -0.40005 0 90)
			(size 0 0)
			(layers "F.Cu" "F.Mask" "F.Paste")
			(net "SW_PVCCIN_CPU0_BOOT1")
		)
		(pad "2" smd circle
			(at 0.40005 0 90)
			(size 0 0)
			(layers "F.Cu" "F.Mask" "F.Paste")
			(net "SW_PVCCIN_CPU0_BOOT1_R")
		)
	)
	(footprint ""
		(layer "F.Cu")
		(at 381.756666 -340.064598)
		(property "Reference" "PC253_P0_5"
			(at 0 0 0)
			(layer "F.SilkS")
			(hide yes)
			(effects
				(font
					(size 1.27 1.27)
				)
			)
		)
		(property "Value" ""
			(at 0 0 0)
			(layer "F.Fab")
			(effects
				(font
					(size 1.27 1.27)
				)
			)
		)
		(duplicate_pad_numbers_are_jumpers no)
		(fp_line
			(start -0.7874 -0.4064)
			(end 0.7874 -0.4064)
			(stroke
				(width 0.1524)
				(type default)
			)
			(layer "F.SilkS")
		)
		(fp_line
			(start -0.7874 0.4064)
			(end -0.7874 -0.4064)
			(stroke
				(width 0.1524)
				(type default)
			)
			(layer "F.SilkS")
		)
		(fp_line
			(start 0.7874 -0.4064)
			(end 0.7874 0.4064)
			(stroke
				(width 0.1524)
				(type default)
			)
			(layer "F.SilkS")
		)
		(fp_line
			(start 0.7874 0.4064)
			(end -0.7874 0.4064)
			(stroke
				(width 0.1524)
				(type default)
			)
			(layer "F.SilkS")
		)
		(fp_line
			(start -0.67945 -0.305054)
			(end -0.12065 -0.305054)
			(stroke
				(width 0.1)
				(type default)
			)
			(layer "F.Fab")
		)
		(fp_line
			(start -0.67945 0.3048)
			(end -0.67945 -0.305054)
			(stroke
				(width 0.1)
				(type default)
			)
			(layer "F.Fab")
		)
		(fp_line
			(start -0.12065 -0.305054)
			(end -0.12065 -0.2794)
			(stroke
				(width 0.1)
				(type default)
			)
			(layer "F.Fab")
		)
		(fp_line
			(start -0.12065 -0.2794)
			(end 0.12065 -0.2794)
			(stroke
				(width 0.1)
				(type default)
			)
			(layer "F.Fab")
		)
		(fp_line
			(start -0.12065 0.2794)
			(end -0.12065 0.3048)
			(stroke
				(width 0.1)
				(type default)
			)
			(layer "F.Fab")
		)
		(fp_line
			(start -0.12065 0.3048)
			(end -0.67945 0.3048)
			(stroke
				(width 0.1)
				(type default)
			)
			(layer "F.Fab")
		)
		(fp_line
			(start 0.120396 0.2794)
			(end -0.12065 0.2794)
			(stroke
				(width 0.1)
				(type default)
			)
			(layer "F.Fab")
		)
		(fp_line
			(start 0.120396 0.3048)
			(end 0.120396 0.2794)
			(stroke
				(width 0.1)
				(type default)
			)
			(layer "F.Fab")
		)
		(fp_line
			(start 0.12065 -0.3048)
			(end 0.67945 -0.3048)
			(stroke
				(width 0.1)
				(type default)
			)
			(layer "F.Fab")
		)
		(fp_line
			(start 0.12065 -0.2794)
			(end 0.12065 -0.3048)
			(stroke
				(width 0.1)
				(type default)
			)
			(layer "F.Fab")
		)
		(fp_line
			(start 0.67945 -0.3048)
			(end 0.67945 0.3048)
			(stroke
				(width 0.1)
				(type default)
			)
			(layer "F.Fab")
		)
		(fp_line
			(start 0.67945 0.3048)
			(end 0.120396 0.3048)
			(stroke
				(width 0.1)
				(type default)
			)
			(layer "F.Fab")
		)
		(pad "1" smd circle
			(at -0.40005 0)
			(size 0 0)
			(layers "F.Cu" "F.Mask" "F.Paste")
			(net "SW_P12V_PVCCIN_CPU0_FLT")
		)
		(pad "2" smd circle
			(at 0.40005 0)
			(size 0 0)
			(layers "F.Cu" "F.Mask" "F.Paste")
			(net "GND")
		)
	)
	(footprint ""
		(layer "F.Cu")
		(at 243.78666 -253.363984)
		(property "Reference" "R4082"
			(at 0 0 0)
			(layer "F.SilkS")
			(hide yes)
			(effects
				(font
					(size 1.27 1.27)
				)
			)
		)
		(property "Value" ""
			(at 0 0 0)
			(layer "F.Fab")
			(effects
				(font
					(size 1.27 1.27)
				)
			)
		)
		(duplicate_pad_numbers_are_jumpers no)
		(fp_line
			(start -0.7874 -0.4064)
			(end 0.7874 -0.4064)
			(stroke
				(width 0.1524)
				(type default)
			)
			(layer "F.SilkS")
		)
		(fp_line
			(start -0.7874 0.4064)
			(end -0.7874 -0.4064)
			(stroke
				(width 0.1524)
				(type default)
			)
			(layer "F.SilkS")
		)
		(fp_line
			(start 0.7874 -0.4064)
			(end 0.7874 0.4064)
			(stroke
				(width 0.1524)
				(type default)
			)
			(layer "F.SilkS")
		)
		(fp_line
			(start 0.7874 0.4064)
			(end -0.7874 0.4064)
			(stroke
				(width 0.1524)
				(type default)
			)
			(layer "F.SilkS")
		)
		(fp_line
			(start -0.67945 -0.305054)
			(end -0.12065 -0.305054)
			(stroke
				(width 0.1)
				(type default)
			)
			(layer "F.Fab")
		)
		(fp_line
			(start -0.67945 0.3048)
			(end -0.67945 -0.305054)
			(stroke
				(width 0.1)
				(type default)
			)
			(layer "F.Fab")
		)
		(fp_line
			(start -0.12065 -0.305054)
			(end -0.12065 -0.2794)
			(stroke
				(width 0.1)
				(type default)
			)
			(layer "F.Fab")
		)
		(fp_line
			(start -0.12065 -0.2794)
			(end 0.12065 -0.2794)
			(stroke
				(width 0.1)
				(type default)
			)
			(layer "F.Fab")
		)
		(fp_line
			(start -0.12065 0.2794)
			(end -0.12065 0.3048)
			(stroke
				(width 0.1)
				(type default)
			)
			(layer "F.Fab")
		)
		(fp_line
			(start -0.12065 0.3048)
			(end -0.67945 0.3048)
			(stroke
				(width 0.1)
				(type default)
			)
			(layer "F.Fab")
		)
		(fp_line
			(start 0.120396 0.2794)
			(end -0.12065 0.2794)
			(stroke
				(width 0.1)
				(type default)
			)
			(layer "F.Fab")
		)
		(fp_line
			(start 0.120396 0.3048)
			(end 0.120396 0.2794)
			(stroke
				(width 0.1)
				(type default)
			)
			(layer "F.Fab")
		)
		(fp_line
			(start 0.12065 -0.3048)
			(end 0.67945 -0.3048)
			(stroke
				(width 0.1)
				(type default)
			)
			(layer "F.Fab")
		)
		(fp_line
			(start 0.12065 -0.2794)
			(end 0.12065 -0.3048)
			(stroke
				(width 0.1)
				(type default)
			)
			(layer "F.Fab")
		)
		(fp_line
			(start 0.67945 -0.3048)
			(end 0.67945 0.3048)
			(stroke
				(width 0.1)
				(type default)
			)
			(layer "F.Fab")
		)
		(fp_line
			(start 0.67945 0.3048)
			(end 0.120396 0.3048)
			(stroke
				(width 0.1)
				(type default)
			)
			(layer "F.Fab")
		)
		(pad "1" smd circle
			(at -0.40005 0)
			(size 0 0)
			(layers "F.Cu" "F.Mask" "F.Paste")
			(net "CLK_GEN2_SMB_SADR")
		)
		(pad "2" smd circle
			(at 0.40005 0)
			(size 0 0)
			(layers "F.Cu" "F.Mask" "F.Paste")
			(net "GND")
		)
	)
	(footprint ""
		(layer "F.Cu")
		(at 44.295822 -172.301916)
		(property "Reference" "PC460"
			(at 0 0 0)
			(layer "F.SilkS")
			(hide yes)
			(effects
				(font
					(size 1.27 1.27)
				)
			)
		)
		(property "Value" ""
			(at 0 0 0)
			(layer "F.Fab")
			(effects
				(font
					(size 1.27 1.27)
				)
			)
		)
		(duplicate_pad_numbers_are_jumpers no)
		(fp_line
			(start -3.400044 1.249934)
			(end 3.400044 1.249934)
			(stroke
				(width 0.1524)
				(type default)
			)
			(layer "F.SilkS")
		)
		(fp_circle
			(center 0 1.249934)
			(end 3.400044 1.249934)
			(stroke
				(width 0.1524)
				(type default)
			)
			(fill no)
			(layer "F.SilkS")
		)
		(fp_poly
			(pts
				(arc
					(start -3.400044 1.249934)
					(mid 0 4.649978)
					(end 3.400044 1.249934)
				)
			)
			(stroke
				(width 0)
				(type default)
			)
			(fill yes)
			(layer "F.SilkS")
		)
		(fp_circle
			(center 0 1.249934)
			(end 3.400044 1.249934)
			(stroke
				(width 0.1)
				(type default)
			)
			(fill no)
			(layer "F.Fab")
		)
		(pad "1" thru_hole rect
			(at 0 0)
			(size 1.524 1.524)
			(drill 1.016)
			(layers "*.Cu" "*.Mask")
			(remove_unused_layers no)
			(net "SW_P12V_PVCCINFAON_CPU1_FLT")
			(clearance 0)
			(padstack
				(mode front_inner_back)
				(layer "Inner"
					(shape circle)
					(size 1.524 1.524)
					(clearance 0)
				)
				(layer "B.Cu"
					(shape rect)
					(size 1.524 1.524)
					(clearance 0)
				)
			)
		)
		(pad "2" thru_hole circle
			(at 0 2.500122)
			(size 1.524 1.524)
			(drill 1.016)
			(layers "*.Cu" "*.Mask")
			(remove_unused_layers no)
			(net "GND")
			(clearance 0)
		)
	)
	(footprint ""
		(layer "F.Cu")
		(at 119.333264 -354.737924 180)
		(property "Reference" "R2380"
			(at 0 0 180)
			(layer "F.SilkS")
			(hide yes)
			(effects
				(font
					(size 1.27 1.27)
				)
			)
		)
		(property "Value" ""
			(at 0 0 180)
			(layer "F.Fab")
			(effects
				(font
					(size 1.27 1.27)
				)
			)
		)
		(duplicate_pad_numbers_are_jumpers no)
		(fp_line
			(start 0.7874 0.4064)
			(end -0.7874 0.4064)
			(stroke
				(width 0.1524)
				(type default)
			)
			(layer "F.SilkS")
		)
		(fp_line
			(start 0.7874 -0.4064)
			(end 0.7874 0.4064)
			(stroke
				(width 0.1524)
				(type default)
			)
			(layer "F.SilkS")
		)
		(fp_line
			(start -0.7874 0.4064)
			(end -0.7874 -0.4064)
			(stroke
				(width 0.1524)
				(type default)
			)
			(layer "F.SilkS")
		)
		(fp_line
			(start -0.7874 -0.4064)
			(end 0.7874 -0.4064)
			(stroke
				(width 0.1524)
				(type default)
			)
			(layer "F.SilkS")
		)
		(fp_line
			(start 0.67945 0.3048)
			(end 0.120396 0.3048)
			(stroke
				(width 0.1)
				(type default)
			)
			(layer "F.Fab")
		)
		(fp_line
			(start 0.67945 -0.3048)
			(end 0.67945 0.3048)
			(stroke
				(width 0.1)
				(type default)
			)
			(layer "F.Fab")
		)
		(fp_line
			(start 0.12065 -0.2794)
			(end 0.12065 -0.3048)
			(stroke
				(width 0.1)
				(type default)
			)
			(layer "F.Fab")
		)
		(fp_line
			(start 0.12065 -0.3048)
			(end 0.67945 -0.3048)
			(stroke
				(width 0.1)
				(type default)
			)
			(layer "F.Fab")
		)
		(fp_line
			(start 0.120396 0.3048)
			(end 0.120396 0.2794)
			(stroke
				(width 0.1)
				(type default)
			)
			(layer "F.Fab")
		)
		(fp_line
			(start 0.120396 0.2794)
			(end -0.12065 0.2794)
			(stroke
				(width 0.1)
				(type default)
			)
			(layer "F.Fab")
		)
		(fp_line
			(start -0.12065 0.3048)
			(end -0.67945 0.3048)
			(stroke
				(width 0.1)
				(type default)
			)
			(layer "F.Fab")
		)
		(fp_line
			(start -0.12065 0.2794)
			(end -0.12065 0.3048)
			(stroke
				(width 0.1)
				(type default)
			)
			(layer "F.Fab")
		)
		(fp_line
			(start -0.12065 -0.2794)
			(end 0.12065 -0.2794)
			(stroke
				(width 0.1)
				(type default)
			)
			(layer "F.Fab")
		)
		(fp_line
			(start -0.12065 -0.305054)
			(end -0.12065 -0.2794)
			(stroke
				(width 0.1)
				(type default)
			)
			(layer "F.Fab")
		)
		(fp_line
			(start -0.67945 0.3048)
			(end -0.67945 -0.305054)
			(stroke
				(width 0.1)
				(type default)
			)
			(layer "F.Fab")
		)
		(fp_line
			(start -0.67945 -0.305054)
			(end -0.12065 -0.305054)
			(stroke
				(width 0.1)
				(type default)
			)
			(layer "F.Fab")
		)
		(pad "1" smd circle
			(at -0.40005 0 180)
			(size 0 0)
			(layers "F.Cu" "F.Mask" "F.Paste")
			(net "PWRGD_PVPP_HBM_CPU1_R")
		)
		(pad "2" smd circle
			(at 0.40005 0 180)
			(size 0 0)
			(layers "F.Cu" "F.Mask" "F.Paste")
			(net "PWRGD_PVPP_HBM_CPU1")
		)
	)
	(footprint ""
		(layer "F.Cu")
		(at 172.047408 -415.900362 180)
		(property "Reference" "Q103"
			(at 1.022096 1.8669 0)
			(unlocked yes)
			(layer "F.SilkS")
			(effects
				(font
					(size 0.7874 0.5842)
					(thickness 0.1524)
				)
				(justify left)
			)
		)
		(property "Value" ""
			(at 0 0 180)
			(layer "F.Fab")
			(effects
				(font
					(size 1.27 1.27)
				)
			)
		)
		(duplicate_pad_numbers_are_jumpers no)
		(fp_line
			(start 1.332738 1.100074)
			(end -1.332738 1.100074)
			(stroke
				(width 0.1524)
				(type default)
			)
			(layer "F.SilkS")
		)
		(fp_line
			(start 1.332738 -1.100074)
			(end 1.332738 1.100074)
			(stroke
				(width 0.1524)
				(type default)
			)
			(layer "F.SilkS")
		)
		(fp_line
			(start 0.4826 -1.100074)
			(end 1.332738 -1.100074)
			(stroke
				(width 0.1524)
				(type default)
			)
			(layer "F.SilkS")
		)
		(fp_line
			(start 0 -0.541274)
			(end 0.4826 -1.100074)
			(stroke
				(width 0.1524)
				(type default)
			)
			(layer "F.SilkS")
		)
		(fp_line
			(start -0.4826 -1.100074)
			(end 0 -0.541274)
			(stroke
				(width 0.1524)
				(type default)
			)
			(layer "F.SilkS")
		)
		(fp_line
			(start -1.332738 1.100074)
			(end -1.332738 -1.100074)
			(stroke
				(width 0.1524)
				(type default)
			)
			(layer "F.SilkS")
		)
		(fp_line
			(start -1.332738 -1.100074)
			(end -0.4826 -1.100074)
			(stroke
				(width 0.1524)
				(type default)
			)
			(layer "F.SilkS")
		)
		(fp_poly
			(pts
				(xy -0.675132 -1.928622) (xy -1.02616 -1.226566) (xy -1.377188 -1.928622)
			)
			(stroke
				(width 0)
				(type default)
			)
			(fill yes)
			(layer "F.SilkS")
		)
		(fp_line
			(start 0.674878 1.100074)
			(end -0.674878 1.100074)
			(stroke
				(width 0.1)
				(type default)
			)
			(layer "F.Fab")
		)
		(fp_line
			(start 0.674878 -1.100074)
			(end 0.674878 1.100074)
			(stroke
				(width 0.1)
				(type default)
			)
			(layer "F.Fab")
		)
		(fp_line
			(start -0.674878 1.100074)
			(end -0.674878 -1.100074)
			(stroke
				(width 0.1)
				(type default)
			)
			(layer "F.Fab")
		)
		(fp_line
			(start -0.674878 -1.100074)
			(end 0.674878 -1.100074)
			(stroke
				(width 0.1)
				(type default)
			)
			(layer "F.Fab")
		)
		(fp_poly
			(pts
				(xy -2.2352 -0.298958) (xy -2.2352 -1.001014) (xy -1.533144 -0.649986)
			)
			(stroke
				(width 0)
				(type default)
			)
			(fill yes)
			(layer "F.Fab")
		)
		(pad "1" smd rect
			(at -0.94996 -0.649986 270)
			(size 0.4318 0.508)
			(layers "F.Cu" "F.Mask" "F.Paste")
			(net "GND")
		)
		(pad "2" smd rect
			(at -0.94996 0 270)
			(size 0.4318 0.508)
			(layers "F.Cu" "F.Mask" "F.Paste")
			(net "GPU_HMC_PRSNT_N")
		)
		(pad "3" smd rect
			(at -0.94996 0.649986 270)
			(size 0.4318 0.508)
			(layers "F.Cu" "F.Mask" "F.Paste")
			(net "GPU_HMC_PRSNT_ISO_N")
		)
		(pad "4" smd rect
			(at 0.94996 0.649986 270)
			(size 0.4318 0.508)
			(layers "F.Cu" "F.Mask" "F.Paste")
			(net "GND")
		)
		(pad "5" smd rect
			(at 0.94996 0 270)
			(size 0.4318 0.508)
			(layers "F.Cu" "F.Mask" "F.Paste")
			(net "GPU_HMC_PRSNT")
		)
		(pad "6" smd rect
			(at 0.94996 -0.649986 270)
			(size 0.4318 0.508)
			(layers "F.Cu" "F.Mask" "F.Paste")
			(net "GPU_HMC_PRSNT")
		)
	)
	(footprint ""
		(layer "F.Cu")
		(at 194.856608 -401.800822 180)
		(property "Reference" "PR3918"
			(at 0 0 180)
			(layer "F.SilkS")
			(hide yes)
			(effects
				(font
					(size 1.27 1.27)
				)
			)
		)
		(property "Value" ""
			(at 0 0 180)
			(layer "F.Fab")
			(effects
				(font
					(size 1.27 1.27)
				)
			)
		)
		(duplicate_pad_numbers_are_jumpers no)
		(fp_line
			(start 0.7874 0.4064)
			(end -0.7874 0.4064)
			(stroke
				(width 0.1524)
				(type default)
			)
			(layer "F.SilkS")
		)
		(fp_line
			(start 0.7874 -0.4064)
			(end 0.7874 0.4064)
			(stroke
				(width 0.1524)
				(type default)
			)
			(layer "F.SilkS")
		)
		(fp_line
			(start -0.7874 0.4064)
			(end -0.7874 -0.4064)
			(stroke
				(width 0.1524)
				(type default)
			)
			(layer "F.SilkS")
		)
		(fp_line
			(start -0.7874 -0.4064)
			(end 0.7874 -0.4064)
			(stroke
				(width 0.1524)
				(type default)
			)
			(layer "F.SilkS")
		)
		(fp_line
			(start 0.67945 0.3048)
			(end 0.120396 0.3048)
			(stroke
				(width 0.1)
				(type default)
			)
			(layer "F.Fab")
		)
		(fp_line
			(start 0.67945 -0.3048)
			(end 0.67945 0.3048)
			(stroke
				(width 0.1)
				(type default)
			)
			(layer "F.Fab")
		)
		(fp_line
			(start 0.12065 -0.2794)
			(end 0.12065 -0.3048)
			(stroke
				(width 0.1)
				(type default)
			)
			(layer "F.Fab")
		)
		(fp_line
			(start 0.12065 -0.3048)
			(end 0.67945 -0.3048)
			(stroke
				(width 0.1)
				(type default)
			)
			(layer "F.Fab")
		)
		(fp_line
			(start 0.120396 0.3048)
			(end 0.120396 0.2794)
			(stroke
				(width 0.1)
				(type default)
			)
			(layer "F.Fab")
		)
		(fp_line
			(start 0.120396 0.2794)
			(end -0.12065 0.2794)
			(stroke
				(width 0.1)
				(type default)
			)
			(layer "F.Fab")
		)
		(fp_line
			(start -0.12065 0.3048)
			(end -0.67945 0.3048)
			(stroke
				(width 0.1)
				(type default)
			)
			(layer "F.Fab")
		)
		(fp_line
			(start -0.12065 0.2794)
			(end -0.12065 0.3048)
			(stroke
				(width 0.1)
				(type default)
			)
			(layer "F.Fab")
		)
		(fp_line
			(start -0.12065 -0.2794)
			(end 0.12065 -0.2794)
			(stroke
				(width 0.1)
				(type default)
			)
			(layer "F.Fab")
		)
		(fp_line
			(start -0.12065 -0.305054)
			(end -0.12065 -0.2794)
			(stroke
				(width 0.1)
				(type default)
			)
			(layer "F.Fab")
		)
		(fp_line
			(start -0.67945 0.3048)
			(end -0.67945 -0.305054)
			(stroke
				(width 0.1)
				(type default)
			)
			(layer "F.Fab")
		)
		(fp_line
			(start -0.67945 -0.305054)
			(end -0.12065 -0.305054)
			(stroke
				(width 0.1)
				(type default)
			)
			(layer "F.Fab")
		)
		(pad "1" smd circle
			(at -0.40005 0 180)
			(size 0 0)
			(layers "F.Cu" "F.Mask" "F.Paste")
			(net "HSC_IMON")
		)
		(pad "2" smd circle
			(at 0.40005 0 180)
			(size 0 0)
			(layers "F.Cu" "F.Mask" "F.Paste")
			(net "AGND_HSC")
		)
	)
	(footprint ""
		(layer "F.Cu")
		(at 165.275514 -408.517344 -90)
		(property "Reference" "C1545"
			(at 0 0 270)
			(layer "F.SilkS")
			(hide yes)
			(effects
				(font
					(size 1.27 1.27)
				)
			)
		)
		(property "Value" ""
			(at 0 0 270)
			(layer "F.Fab")
			(effects
				(font
					(size 1.27 1.27)
				)
			)
		)
		(duplicate_pad_numbers_are_jumpers no)
		(fp_line
			(start -0.299974 0.150114)
			(end -0.299974 -0.150114)
			(stroke
				(width 0.1)
				(type default)
			)
			(layer "F.Fab")
		)
		(fp_line
			(start 0.299974 0.150114)
			(end -0.299974 0.150114)
			(stroke
				(width 0.1)
				(type default)
			)
			(layer "F.Fab")
		)
		(fp_line
			(start -0.299974 -0.150114)
			(end 0.299974 -0.150114)
			(stroke
				(width 0.1)
				(type default)
			)
			(layer "F.Fab")
		)
		(fp_line
			(start 0.299974 -0.150114)
			(end 0.299974 0.150114)
			(stroke
				(width 0.1)
				(type default)
			)
			(layer "F.Fab")
		)
		(pad "1" smd rect
			(at -0.2667 0 270)
			(size 0.3048 0.381)
			(layers "F.Cu" "F.Mask" "F.Paste")
			(net "P5E_CPU1_PE3_TX_C_DP<1>")
		)
		(pad "2" smd rect
			(at 0.2667 0 270)
			(size 0.3048 0.381)
			(layers "F.Cu" "F.Mask" "F.Paste")
			(net "P5E_CPU1_PE3_TX_DP<1>")
		)
	)
	(footprint ""
		(layer "F.Cu")
		(at 341.339932 -333.525368 -90)
		(property "Reference" "PC295_P0_1"
			(at 0 0 270)
			(layer "F.SilkS")
			(hide yes)
			(effects
				(font
					(size 1.27 1.27)
				)
			)
		)
		(property "Value" ""
			(at 0 0 270)
			(layer "F.Fab")
			(effects
				(font
					(size 1.27 1.27)
				)
			)
		)
		(duplicate_pad_numbers_are_jumpers no)
		(fp_line
			(start -0.7874 0.4064)
			(end -0.7874 -0.4064)
			(stroke
				(width 0.1524)
				(type default)
			)
			(layer "F.SilkS")
		)
		(fp_line
			(start 0.7874 0.4064)
			(end -0.7874 0.4064)
			(stroke
				(width 0.1524)
				(type default)
			)
			(layer "F.SilkS")
		)
		(fp_line
			(start -0.7874 -0.4064)
			(end 0.7874 -0.4064)
			(stroke
				(width 0.1524)
				(type default)
			)
			(layer "F.SilkS")
		)
		(fp_line
			(start 0.7874 -0.4064)
			(end 0.7874 0.4064)
			(stroke
				(width 0.1524)
				(type default)
			)
			(layer "F.SilkS")
		)
		(fp_line
			(start -0.67945 0.3048)
			(end -0.67945 -0.305054)
			(stroke
				(width 0.1)
				(type default)
			)
			(layer "F.Fab")
		)
		(fp_line
			(start -0.12065 0.3048)
			(end -0.67945 0.3048)
			(stroke
				(width 0.1)
				(type default)
			)
			(layer "F.Fab")
		)
		(fp_line
			(start 0.120396 0.3048)
			(end 0.120396 0.2794)
			(stroke
				(width 0.1)
				(type default)
			)
			(layer "F.Fab")
		)
		(fp_line
			(start 0.67945 0.3048)
			(end 0.120396 0.3048)
			(stroke
				(width 0.1)
				(type default)
			)
			(layer "F.Fab")
		)
		(fp_line
			(start -0.12065 0.2794)
			(end -0.12065 0.3048)
			(stroke
				(width 0.1)
				(type default)
			)
			(layer "F.Fab")
		)
		(fp_line
			(start 0.120396 0.2794)
			(end -0.12065 0.2794)
			(stroke
				(width 0.1)
				(type default)
			)
			(layer "F.Fab")
		)
		(fp_line
			(start -0.12065 -0.2794)
			(end 0.12065 -0.2794)
			(stroke
				(width 0.1)
				(type default)
			)
			(layer "F.Fab")
		)
		(fp_line
			(start 0.12065 -0.2794)
			(end 0.12065 -0.3048)
			(stroke
				(width 0.1)
				(type default)
			)
			(layer "F.Fab")
		)
		(fp_line
			(start 0.12065 -0.3048)
			(end 0.67945 -0.3048)
			(stroke
				(width 0.1)
				(type default)
			)
			(layer "F.Fab")
		)
		(fp_line
			(start 0.67945 -0.3048)
			(end 0.67945 0.3048)
			(stroke
				(width 0.1)
				(type default)
			)
			(layer "F.Fab")
		)
		(fp_line
			(start -0.67945 -0.305054)
			(end -0.12065 -0.305054)
			(stroke
				(width 0.1)
				(type default)
			)
			(layer "F.Fab")
		)
		(fp_line
			(start -0.12065 -0.305054)
			(end -0.12065 -0.2794)
			(stroke
				(width 0.1)
				(type default)
			)
			(layer "F.Fab")
		)
		(pad "1" smd circle
			(at -0.40005 0 270)
			(size 0 0)
			(layers "F.Cu" "F.Mask" "F.Paste")
			(net "PVCCIN_CPU0_PVCC")
		)
		(pad "2" smd circle
			(at 0.40005 0 270)
			(size 0 0)
			(layers "F.Cu" "F.Mask" "F.Paste")
			(net "GND")
		)
	)
	(footprint ""
		(layer "F.Cu")
		(at 23.241 -397.025876 -90)
		(property "Reference" "R3283"
			(at 0 0 270)
			(layer "F.SilkS")
			(hide yes)
			(effects
				(font
					(size 1.27 1.27)
				)
			)
		)
		(property "Value" ""
			(at 0 0 270)
			(layer "F.Fab")
			(effects
				(font
					(size 1.27 1.27)
				)
			)
		)
		(duplicate_pad_numbers_are_jumpers no)
		(fp_line
			(start -0.7874 0.4064)
			(end -0.7874 -0.4064)
			(stroke
				(width 0.1524)
				(type default)
			)
			(layer "F.SilkS")
		)
		(fp_line
			(start 0.7874 0.4064)
			(end -0.7874 0.4064)
			(stroke
				(width 0.1524)
				(type default)
			)
			(layer "F.SilkS")
		)
		(fp_line
			(start -0.7874 -0.4064)
			(end 0.7874 -0.4064)
			(stroke
				(width 0.1524)
				(type default)
			)
			(layer "F.SilkS")
		)
		(fp_line
			(start 0.7874 -0.4064)
			(end 0.7874 0.4064)
			(stroke
				(width 0.1524)
				(type default)
			)
			(layer "F.SilkS")
		)
		(fp_line
			(start -0.67945 0.3048)
			(end -0.67945 -0.305054)
			(stroke
				(width 0.1)
				(type default)
			)
			(layer "F.Fab")
		)
		(fp_line
			(start -0.12065 0.3048)
			(end -0.67945 0.3048)
			(stroke
				(width 0.1)
				(type default)
			)
			(layer "F.Fab")
		)
		(fp_line
			(start 0.120396 0.3048)
			(end 0.120396 0.2794)
			(stroke
				(width 0.1)
				(type default)
			)
			(layer "F.Fab")
		)
		(fp_line
			(start 0.67945 0.3048)
			(end 0.120396 0.3048)
			(stroke
				(width 0.1)
				(type default)
			)
			(layer "F.Fab")
		)
		(fp_line
			(start -0.12065 0.2794)
			(end -0.12065 0.3048)
			(stroke
				(width 0.1)
				(type default)
			)
			(layer "F.Fab")
		)
		(fp_line
			(start 0.120396 0.2794)
			(end -0.12065 0.2794)
			(stroke
				(width 0.1)
				(type default)
			)
			(layer "F.Fab")
		)
		(fp_line
			(start -0.12065 -0.2794)
			(end 0.12065 -0.2794)
			(stroke
				(width 0.1)
				(type default)
			)
			(layer "F.Fab")
		)
		(fp_line
			(start 0.12065 -0.2794)
			(end 0.12065 -0.3048)
			(stroke
				(width 0.1)
				(type default)
			)
			(layer "F.Fab")
		)
		(fp_line
			(start 0.12065 -0.3048)
			(end 0.67945 -0.3048)
			(stroke
				(width 0.1)
				(type default)
			)
			(layer "F.Fab")
		)
		(fp_line
			(start 0.67945 -0.3048)
			(end 0.67945 0.3048)
			(stroke
				(width 0.1)
				(type default)
			)
			(layer "F.Fab")
		)
		(fp_line
			(start -0.67945 -0.305054)
			(end -0.12065 -0.305054)
			(stroke
				(width 0.1)
				(type default)
			)
			(layer "F.Fab")
		)
		(fp_line
			(start -0.12065 -0.305054)
			(end -0.12065 -0.2794)
			(stroke
				(width 0.1)
				(type default)
			)
			(layer "F.Fab")
		)
		(pad "1" smd circle
			(at -0.40005 0 270)
			(size 0 0)
			(layers "F.Cu" "F.Mask" "F.Paste")
			(net "P3V3_AUX")
		)
		(pad "2" smd circle
			(at 0.40005 0 270)
			(size 0 0)
			(layers "F.Cu" "F.Mask" "F.Paste")
			(net "FM_P2E_EQB0")
		)
	)
	(footprint ""
		(layer "F.Cu")
		(at 437.10733 -16.248126 -90)
		(property "Reference" "R418"
			(at 0 0 270)
			(layer "F.SilkS")
			(hide yes)
			(effects
				(font
					(size 1.27 1.27)
				)
			)
		)
		(property "Value" ""
			(at 0 0 270)
			(layer "F.Fab")
			(effects
				(font
					(size 1.27 1.27)
				)
			)
		)
		(duplicate_pad_numbers_are_jumpers no)
		(fp_line
			(start -0.7874 0.4064)
			(end -0.7874 -0.4064)
			(stroke
				(width 0.1524)
				(type default)
			)
			(layer "F.SilkS")
		)
		(fp_line
			(start 0.7874 0.4064)
			(end -0.7874 0.4064)
			(stroke
				(width 0.1524)
				(type default)
			)
			(layer "F.SilkS")
		)
		(fp_line
			(start -0.7874 -0.4064)
			(end 0.7874 -0.4064)
			(stroke
				(width 0.1524)
				(type default)
			)
			(layer "F.SilkS")
		)
		(fp_line
			(start 0.7874 -0.4064)
			(end 0.7874 0.4064)
			(stroke
				(width 0.1524)
				(type default)
			)
			(layer "F.SilkS")
		)
		(fp_line
			(start -0.67945 0.3048)
			(end -0.67945 -0.305054)
			(stroke
				(width 0.1)
				(type default)
			)
			(layer "F.Fab")
		)
		(fp_line
			(start -0.12065 0.3048)
			(end -0.67945 0.3048)
			(stroke
				(width 0.1)
				(type default)
			)
			(layer "F.Fab")
		)
		(fp_line
			(start 0.120396 0.3048)
			(end 0.120396 0.2794)
			(stroke
				(width 0.1)
				(type default)
			)
			(layer "F.Fab")
		)
		(fp_line
			(start 0.67945 0.3048)
			(end 0.120396 0.3048)
			(stroke
				(width 0.1)
				(type default)
			)
			(layer "F.Fab")
		)
		(fp_line
			(start -0.12065 0.2794)
			(end -0.12065 0.3048)
			(stroke
				(width 0.1)
				(type default)
			)
			(layer "F.Fab")
		)
		(fp_line
			(start 0.120396 0.2794)
			(end -0.12065 0.2794)
			(stroke
				(width 0.1)
				(type default)
			)
			(layer "F.Fab")
		)
		(fp_line
			(start -0.12065 -0.2794)
			(end 0.12065 -0.2794)
			(stroke
				(width 0.1)
				(type default)
			)
			(layer "F.Fab")
		)
		(fp_line
			(start 0.12065 -0.2794)
			(end 0.12065 -0.3048)
			(stroke
				(width 0.1)
				(type default)
			)
			(layer "F.Fab")
		)
		(fp_line
			(start 0.12065 -0.3048)
			(end 0.67945 -0.3048)
			(stroke
				(width 0.1)
				(type default)
			)
			(layer "F.Fab")
		)
		(fp_line
			(start 0.67945 -0.3048)
			(end 0.67945 0.3048)
			(stroke
				(width 0.1)
				(type default)
			)
			(layer "F.Fab")
		)
		(fp_line
			(start -0.67945 -0.305054)
			(end -0.12065 -0.305054)
			(stroke
				(width 0.1)
				(type default)
			)
			(layer "F.Fab")
		)
		(fp_line
			(start -0.12065 -0.305054)
			(end -0.12065 -0.2794)
			(stroke
				(width 0.1)
				(type default)
			)
			(layer "F.Fab")
		)
		(pad "1" smd circle
			(at -0.40005 0 270)
			(size 0 0)
			(layers "F.Cu" "F.Mask" "F.Paste")
			(net "OCP_SFF_ISO_BIF2_EN")
		)
		(pad "2" smd circle
			(at 0.40005 0 270)
			(size 0 0)
			(layers "F.Cu" "F.Mask" "F.Paste")
			(net "OCP_SFF_BIF2_R_N")
		)
	)
	(footprint ""
		(layer "F.Cu")
		(at 168.40708 -258.091686)
		(property "Reference" "J25"
			(at -3.683 -81.702148 0)
			(unlocked yes)
			(layer "F.SilkS")
			(effects
				(font
					(size 0.7874 0.5842)
					(thickness 0.1524)
				)
				(justify left)
			)
		)
		(property "Value" ""
			(at 0 0 0)
			(layer "F.Fab")
			(effects
				(font
					(size 1.27 1.27)
				)
			)
		)
		(duplicate_pad_numbers_are_jumpers no)
		(fp_line
			(start -3.24993 -81.000092)
			(end -3.24993 81.000092)
			(stroke
				(width 0.1524)
				(type default)
			)
			(layer "F.SilkS")
		)
		(fp_line
			(start -3.24993 81.000092)
			(end 3.24993 81.000092)
			(stroke
				(width 0.1524)
				(type default)
			)
			(layer "F.SilkS")
		)
		(fp_line
			(start 0.22098 -81.000092)
			(end -3.24993 -81.000092)
			(stroke
				(width 0.1524)
				(type default)
			)
			(layer "F.SilkS")
		)
		(fp_line
			(start 3.24993 -72.00011)
			(end -3.24993 -72.00011)
			(stroke
				(width 0.1524)
				(type default)
			)
			(layer "F.SilkS")
		)
		(fp_line
			(start 3.24993 72.00011)
			(end -3.24993 72.00011)
			(stroke
				(width 0.1524)
				(type default)
			)
			(layer "F.SilkS")
		)
		(fp_line
			(start 3.24993 81.000092)
			(end 3.24993 -75.242674)
			(stroke
				(width 0.1524)
				(type default)
			)
			(layer "F.SilkS")
		)
		(fp_poly
			(pts
				(xy -4.445 -63.832994) (xy -4.445 -62.816994) (xy -3.429 -63.324994)
			)
			(stroke
				(width 0)
				(type default)
			)
			(fill yes)
			(layer "F.SilkS")
		)
		(fp_line
			(start -3.24993 -81.000092)
			(end -3.24993 81.000092)
			(stroke
				(width 0.1)
				(type default)
			)
			(layer "F.Fab")
		)
		(fp_line
			(start -3.24993 81.000092)
			(end 3.24993 81.000092)
			(stroke
				(width 0.1)
				(type default)
			)
			(layer "F.Fab")
		)
		(fp_line
			(start 3.24993 -81.000092)
			(end -3.24993 -81.000092)
			(stroke
				(width 0.1)
				(type default)
			)
			(layer "F.Fab")
		)
		(fp_line
			(start 3.24993 -72.00011)
			(end -3.24993 -72.00011)
			(stroke
				(width 0.1)
				(type default)
			)
			(layer "F.Fab")
		)
		(fp_line
			(start 3.24993 -71.000112)
			(end -3.24993 -71.000112)
			(stroke
				(width 0.1)
				(type default)
			)
			(layer "F.Fab")
		)
		(fp_line
			(start 3.24993 71.000112)
			(end -3.24993 71.000112)
			(stroke
				(width 0.1)
				(type default)
			)
			(layer "F.Fab")
		)
		(fp_line
			(start 3.24993 72.00011)
			(end -3.24993 72.00011)
			(stroke
				(width 0.1)
				(type default)
			)
			(layer "F.Fab")
		)
		(fp_line
			(start 3.24993 81.000092)
			(end 3.24993 -81.000092)
			(stroke
				(width 0.1)
				(type default)
			)
			(layer "F.Fab")
		)
		(fp_poly
			(pts
				(xy -4.445 -63.832994) (xy -4.445 -62.816994) (xy -3.429 -63.324994)
			)
			(stroke
				(width 0)
				(type default)
			)
			(fill yes)
			(layer "F.Fab")
		)
		(pad "1" smd rect
			(at -2.050034 -63.324994 270)
			(size 0.519938 1.4986)
			(layers "F.Cu" "F.Mask" "F.Paste")
			(net "P12V_S3_AUX_CPU1_NVDIMM")
		)
		(pad "2" smd rect
			(at -2.050034 -62.47511 270)
			(size 0.519938 1.4986)
			(layers "F.Cu" "F.Mask" "F.Paste")
			(net "TP_CHE_CPU1_DIMM1_FRU_0")
		)
		(pad "3" smd rect
			(at -2.050034 -61.624972 270)
			(size 0.519938 1.4986)
			(layers "F.Cu" "F.Mask" "F.Paste")
			(net "P3V3_AUX")
		)
		(pad "4" smd rect
			(at -2.050034 -60.775088 270)
			(size 0.519938 1.4986)
			(layers "F.Cu" "F.Mask" "F.Paste")
			(net "I3C_SPD_DDREFGH_CPU1_LVC1_SCL_R")
		)
		(pad "5" smd rect
			(at -2.050034 -59.92495 270)
			(size 0.519938 1.4986)
			(layers "F.Cu" "F.Mask" "F.Paste")
			(net "I3C_SPD_DDREFGH_CPU1_LVC1_SDA")
		)
		(pad "6" smd rect
			(at -2.050034 -59.075066 270)
			(size 0.519938 1.4986)
			(layers "F.Cu" "F.Mask" "F.Paste")
			(net "GND")
		)
		(pad "7" smd rect
			(at -2.050034 -58.224928 270)
			(size 0.519938 1.4986)
			(layers "F.Cu" "F.Mask" "F.Paste")
			(net "M_E_CPU1_SA_DQ<0>")
		)
		(pad "8" smd rect
			(at -2.050034 -57.375044 270)
			(size 0.519938 1.4986)
			(layers "F.Cu" "F.Mask" "F.Paste")
			(net "GND")
		)
		(pad "9" smd rect
			(at -2.050034 -56.524906 270)
			(size 0.519938 1.4986)
			(layers "F.Cu" "F.Mask" "F.Paste")
			(net "M_E_CPU1_SA_DQ<1>")
		)
		(pad "10" smd rect
			(at -2.050034 -55.675022 270)
			(size 0.519938 1.4986)
			(layers "F.Cu" "F.Mask" "F.Paste")
			(net "GND")
		)
		(pad "11" smd rect
			(at -2.050034 -54.824884 270)
			(size 0.519938 1.4986)
			(layers "F.Cu" "F.Mask" "F.Paste")
			(net "M_E_CPU1_SA_DQS_DP<0>")
		)
		(pad "12" smd rect
			(at -2.050034 -53.975 270)
			(size 0.519938 1.4986)
			(layers "F.Cu" "F.Mask" "F.Paste")
			(net "M_E_CPU1_SA_DQS_DN<0>")
		)
		(pad "13" smd rect
			(at -2.050034 -53.125116 270)
			(size 0.519938 1.4986)
			(layers "F.Cu" "F.Mask" "F.Paste")
			(net "GND")
		)
		(pad "14" smd rect
			(at -2.050034 -52.274978 270)
			(size 0.519938 1.4986)
			(layers "F.Cu" "F.Mask" "F.Paste")
			(net "M_E_CPU1_SA_DQ<4>")
		)
		(pad "15" smd rect
			(at -2.050034 -51.425094 270)
			(size 0.519938 1.4986)
			(layers "F.Cu" "F.Mask" "F.Paste")
			(net "GND")
		)
		(pad "16" smd rect
			(at -2.050034 -50.574956 270)
			(size 0.519938 1.4986)
			(layers "F.Cu" "F.Mask" "F.Paste")
			(net "M_E_CPU1_SA_DQ<5>")
		)
		(pad "17" smd rect
			(at -2.050034 -49.725072 270)
			(size 0.519938 1.4986)
			(layers "F.Cu" "F.Mask" "F.Paste")
			(net "GND")
		)
		(pad "18" smd rect
			(at -2.050034 -48.874934 270)
			(size 0.519938 1.4986)
			(layers "F.Cu" "F.Mask" "F.Paste")
			(net "M_E_CPU1_SA_DQ<8>")
		)
		(pad "19" smd rect
			(at -2.050034 -48.02505 270)
			(size 0.519938 1.4986)
			(layers "F.Cu" "F.Mask" "F.Paste")
			(net "GND")
		)
		(pad "20" smd rect
			(at -2.050034 -47.174912 270)
			(size 0.519938 1.4986)
			(layers "F.Cu" "F.Mask" "F.Paste")
			(net "M_E_CPU1_SA_DQ<9>")
		)
		(pad "21" smd rect
			(at -2.050034 -46.325028 270)
			(size 0.519938 1.4986)
			(layers "F.Cu" "F.Mask" "F.Paste")
			(net "GND")
		)
		(pad "22" smd rect
			(at -2.050034 -45.47489 270)
			(size 0.519938 1.4986)
			(layers "F.Cu" "F.Mask" "F.Paste")
			(net "M_E_CPU1_SA_DQS_DP<1>")
		)
		(pad "23" smd rect
			(at -2.050034 -44.625006 270)
			(size 0.519938 1.4986)
			(layers "F.Cu" "F.Mask" "F.Paste")
			(net "M_E_CPU1_SA_DQS_DN<1>")
		)
		(pad "24" smd rect
			(at -2.050034 -43.775122 270)
			(size 0.519938 1.4986)
			(layers "F.Cu" "F.Mask" "F.Paste")
			(net "GND")
		)
		(pad "25" smd rect
			(at -2.050034 -42.924984 270)
			(size 0.519938 1.4986)
			(layers "F.Cu" "F.Mask" "F.Paste")
			(net "M_E_CPU1_SA_DQ<12>")
		)
		(pad "26" smd rect
			(at -2.050034 -42.0751 270)
			(size 0.519938 1.4986)
			(layers "F.Cu" "F.Mask" "F.Paste")
			(net "GND")
		)
		(pad "27" smd rect
			(at -2.050034 -41.224962 270)
			(size 0.519938 1.4986)
			(layers "F.Cu" "F.Mask" "F.Paste")
			(net "M_E_CPU1_SA_DQ<13>")
		)
		(pad "28" smd rect
			(at -2.050034 -40.375078 270)
			(size 0.519938 1.4986)
			(layers "F.Cu" "F.Mask" "F.Paste")
			(net "GND")
		)
		(pad "29" smd rect
			(at -2.050034 -39.52494 270)
			(size 0.519938 1.4986)
			(layers "F.Cu" "F.Mask" "F.Paste")
			(net "M_E_CPU1_SA_DQ<16>")
		)
		(pad "30" smd rect
			(at -2.050034 -38.675056 270)
			(size 0.519938 1.4986)
			(layers "F.Cu" "F.Mask" "F.Paste")
			(net "GND")
		)
		(pad "31" smd rect
			(at -2.050034 -37.824918 270)
			(size 0.519938 1.4986)
			(layers "F.Cu" "F.Mask" "F.Paste")
			(net "M_E_CPU1_SA_DQ<17>")
		)
		(pad "32" smd rect
			(at -2.050034 -36.975034 270)
			(size 0.519938 1.4986)
			(layers "F.Cu" "F.Mask" "F.Paste")
			(net "GND")
		)
		(pad "33" smd rect
			(at -2.050034 -36.124896 270)
			(size 0.519938 1.4986)
			(layers "F.Cu" "F.Mask" "F.Paste")
			(net "M_E_CPU1_SA_DQS_DP<2>")
		)
		(pad "34" smd rect
			(at -2.050034 -35.275012 270)
			(size 0.519938 1.4986)
			(layers "F.Cu" "F.Mask" "F.Paste")
			(net "M_E_CPU1_SA_DQS_DN<2>")
		)
		(pad "35" smd rect
			(at -2.050034 -34.425128 270)
			(size 0.519938 1.4986)
			(layers "F.Cu" "F.Mask" "F.Paste")
			(net "GND")
		)
		(pad "36" smd rect
			(at -2.050034 -33.57499 270)
			(size 0.519938 1.4986)
			(layers "F.Cu" "F.Mask" "F.Paste")
			(net "M_E_CPU1_SA_DQ<20>")
		)
		(pad "37" smd rect
			(at -2.050034 -32.725106 270)
			(size 0.519938 1.4986)
			(layers "F.Cu" "F.Mask" "F.Paste")
			(net "GND")
		)
		(pad "38" smd rect
			(at -2.050034 -31.874968 270)
			(size 0.519938 1.4986)
			(layers "F.Cu" "F.Mask" "F.Paste")
			(net "M_E_CPU1_SA_DQ<21>")
		)
		(pad "39" smd rect
			(at -2.050034 -31.025084 270)
			(size 0.519938 1.4986)
			(layers "F.Cu" "F.Mask" "F.Paste")
			(net "GND")
		)
		(pad "40" smd rect
			(at -2.050034 -30.174946 270)
			(size 0.519938 1.4986)
			(layers "F.Cu" "F.Mask" "F.Paste")
			(net "M_E_CPU1_SA_DQ<24>")
		)
		(pad "41" smd rect
			(at -2.050034 -29.325062 270)
			(size 0.519938 1.4986)
			(layers "F.Cu" "F.Mask" "F.Paste")
			(net "GND")
		)
		(pad "42" smd rect
			(at -2.050034 -28.474924 270)
			(size 0.519938 1.4986)
			(layers "F.Cu" "F.Mask" "F.Paste")
			(net "M_E_CPU1_SA_DQ<25>")
		)
		(pad "43" smd rect
			(at -2.050034 -27.62504 270)
			(size 0.519938 1.4986)
			(layers "F.Cu" "F.Mask" "F.Paste")
			(net "GND")
		)
		(pad "44" smd rect
			(at -2.050034 -26.774902 270)
			(size 0.519938 1.4986)
			(layers "F.Cu" "F.Mask" "F.Paste")
			(net "M_E_CPU1_SA_DQS_DP<3>")
		)
		(pad "45" smd rect
			(at -2.050034 -25.925018 270)
			(size 0.519938 1.4986)
			(layers "F.Cu" "F.Mask" "F.Paste")
			(net "M_E_CPU1_SA_DQS_DN<3>")
		)
		(pad "46" smd rect
			(at -2.050034 -25.07488 270)
			(size 0.519938 1.4986)
			(layers "F.Cu" "F.Mask" "F.Paste")
			(net "GND")
		)
		(pad "47" smd rect
			(at -2.050034 -24.224996 270)
			(size 0.519938 1.4986)
			(layers "F.Cu" "F.Mask" "F.Paste")
			(net "M_E_CPU1_SA_DQ<28>")
		)
		(pad "48" smd rect
			(at -2.050034 -23.375112 270)
			(size 0.519938 1.4986)
			(layers "F.Cu" "F.Mask" "F.Paste")
			(net "GND")
		)
		(pad "49" smd rect
			(at -2.050034 -22.524974 270)
			(size 0.519938 1.4986)
			(layers "F.Cu" "F.Mask" "F.Paste")
			(net "M_E_CPU1_SA_DQ<29>")
		)
		(pad "50" smd rect
			(at -2.050034 -21.67509 270)
			(size 0.519938 1.4986)
			(layers "F.Cu" "F.Mask" "F.Paste")
			(net "GND")
		)
		(pad "51" smd rect
			(at -2.050034 -20.824952 270)
			(size 0.519938 1.4986)
			(layers "F.Cu" "F.Mask" "F.Paste")
			(net "M_E_CPU1_SA_CB<0>")
		)
		(pad "52" smd rect
			(at -2.050034 -19.975068 270)
			(size 0.519938 1.4986)
			(layers "F.Cu" "F.Mask" "F.Paste")
			(net "GND")
		)
		(pad "53" smd rect
			(at -2.050034 -19.12493 270)
			(size 0.519938 1.4986)
			(layers "F.Cu" "F.Mask" "F.Paste")
			(net "M_E_CPU1_SA_CB<1>")
		)
		(pad "54" smd rect
			(at -2.050034 -18.275046 270)
			(size 0.519938 1.4986)
			(layers "F.Cu" "F.Mask" "F.Paste")
			(net "GND")
		)
		(pad "55" smd rect
			(at -2.050034 -17.424908 270)
			(size 0.519938 1.4986)
			(layers "F.Cu" "F.Mask" "F.Paste")
			(net "M_E_CPU1_SA_DQS_DP<4>")
		)
		(pad "56" smd rect
			(at -2.050034 -16.575024 270)
			(size 0.519938 1.4986)
			(layers "F.Cu" "F.Mask" "F.Paste")
			(net "M_E_CPU1_SA_DQS_DN<4>")
		)
		(pad "57" smd rect
			(at -2.050034 -15.724886 270)
			(size 0.519938 1.4986)
			(layers "F.Cu" "F.Mask" "F.Paste")
			(net "GND")
		)
		(pad "58" smd rect
			(at -2.050034 -14.875002 270)
			(size 0.519938 1.4986)
			(layers "F.Cu" "F.Mask" "F.Paste")
			(net "M_E_CPU1_SA_CB<4>")
		)
		(pad "59" smd rect
			(at -2.050034 -14.025118 270)
			(size 0.519938 1.4986)
			(layers "F.Cu" "F.Mask" "F.Paste")
			(net "GND")
		)
		(pad "60" smd rect
			(at -2.050034 -13.17498 270)
			(size 0.519938 1.4986)
			(layers "F.Cu" "F.Mask" "F.Paste")
			(net "M_E_CPU1_SA_CB<5>")
		)
		(pad "61" smd rect
			(at -2.050034 -12.325096 270)
			(size 0.519938 1.4986)
			(layers "F.Cu" "F.Mask" "F.Paste")
			(net "GND")
		)
		(pad "62" smd rect
			(at -2.050034 -11.474958 270)
			(size 0.519938 1.4986)
			(layers "F.Cu" "F.Mask" "F.Paste")
			(net "M_E_CPU1_ALERT_N")
		)
		(pad "63" smd rect
			(at -2.050034 -10.625074 270)
			(size 0.519938 1.4986)
			(layers "F.Cu" "F.Mask" "F.Paste")
			(net "GND")
		)
		(pad "64" smd rect
			(at -2.050034 -9.774936 270)
			(size 0.519938 1.4986)
			(layers "F.Cu" "F.Mask" "F.Paste")
			(net "M_E_CPU1_SA_CS_N<0>")
		)
		(pad "65" smd rect
			(at -2.050034 -8.925052 270)
			(size 0.519938 1.4986)
			(layers "F.Cu" "F.Mask" "F.Paste")
			(net "GND")
		)
		(pad "66" smd rect
			(at -2.050034 -8.074914 270)
			(size 0.519938 1.4986)
			(layers "F.Cu" "F.Mask" "F.Paste")
			(net "M_E_CPU1_SA_CA<0>")
		)
		(pad "67" smd rect
			(at -2.050034 -7.22503 270)
			(size 0.519938 1.4986)
			(layers "F.Cu" "F.Mask" "F.Paste")
			(net "GND")
		)
		(pad "68" smd rect
			(at -2.050034 -6.374892 270)
			(size 0.519938 1.4986)
			(layers "F.Cu" "F.Mask" "F.Paste")
			(net "M_E_CPU1_SA_CA<2>")
		)
		(pad "69" smd rect
			(at -2.050034 -5.525008 270)
			(size 0.519938 1.4986)
			(layers "F.Cu" "F.Mask" "F.Paste")
			(net "GND")
		)
		(pad "70" smd rect
			(at -2.050034 -4.675124 270)
			(size 0.519938 1.4986)
			(layers "F.Cu" "F.Mask" "F.Paste")
			(net "M_E_CPU1_SA_CA<4>")
		)
		(pad "71" smd rect
			(at -2.050034 -3.824986 270)
			(size 0.519938 1.4986)
			(layers "F.Cu" "F.Mask" "F.Paste")
			(net "GND")
		)
		(pad "72" smd rect
			(at -2.050034 -2.975102 270)
			(size 0.519938 1.4986)
			(layers "F.Cu" "F.Mask" "F.Paste")
			(net "M_E_CPU1_SA_CA<6>")
		)
		(pad "73" smd rect
			(at -2.050034 -2.124964 270)
			(size 0.519938 1.4986)
			(layers "F.Cu" "F.Mask" "F.Paste")
			(net "GND")
		)
		(pad "74" smd rect
			(at -2.050034 -1.27508 270)
			(size 0.519938 1.4986)
			(layers "F.Cu" "F.Mask" "F.Paste")
			(net "M_E_CPU1_SA_PAR")
		)
		(pad "75" smd rect
			(at -2.050034 -0.424942 270)
			(size 0.519938 1.4986)
			(layers "F.Cu" "F.Mask" "F.Paste")
			(net "GND")
		)
		(pad "76" smd rect
			(at -2.050034 5.525008 270)
			(size 0.519938 1.4986)
			(layers "F.Cu" "F.Mask" "F.Paste")
			(net "M_E_CPU1_SB_CA<0>")
		)
		(pad "77" smd rect
			(at -2.050034 6.374892 270)
			(size 0.519938 1.4986)
			(layers "F.Cu" "F.Mask" "F.Paste")
			(net "GND")
		)
		(pad "78" smd rect
			(at -2.050034 7.22503 270)
			(size 0.519938 1.4986)
			(layers "F.Cu" "F.Mask" "F.Paste")
			(net "M_E_CPU1_SB_CA<2>")
		)
		(pad "79" smd rect
			(at -2.050034 8.074914 270)
			(size 0.519938 1.4986)
			(layers "F.Cu" "F.Mask" "F.Paste")
			(net "GND")
		)
		(pad "80" smd rect
			(at -2.050034 8.925052 270)
			(size 0.519938 1.4986)
			(layers "F.Cu" "F.Mask" "F.Paste")
			(net "M_E_CPU1_SB_CA<4>")
		)
		(pad "81" smd rect
			(at -2.050034 9.774936 270)
			(size 0.519938 1.4986)
			(layers "F.Cu" "F.Mask" "F.Paste")
			(net "GND")
		)
		(pad "82" smd rect
			(at -2.050034 10.625074 270)
			(size 0.519938 1.4986)
			(layers "F.Cu" "F.Mask" "F.Paste")
			(net "M_E_CPU1_SB_CA<6>")
		)
		(pad "83" smd rect
			(at -2.050034 11.474958 270)
			(size 0.519938 1.4986)
			(layers "F.Cu" "F.Mask" "F.Paste")
			(net "GND")
		)
		(pad "84" smd rect
			(at -2.050034 12.325096 270)
			(size 0.519938 1.4986)
			(layers "F.Cu" "F.Mask" "F.Paste")
			(net "M_E_CPU1_SB_CS_N<0>")
		)
		(pad "85" smd rect
			(at -2.050034 13.17498 270)
			(size 0.519938 1.4986)
			(layers "F.Cu" "F.Mask" "F.Paste")
			(net "GND")
		)
		(pad "86" smd rect
			(at -2.050034 14.025118 270)
			(size 0.519938 1.4986)
			(layers "F.Cu" "F.Mask" "F.Paste")
			(net "M_E_CPU1_SA_RSP<0>")
		)
		(pad "87" smd rect
			(at -2.050034 14.875002 270)
			(size 0.519938 1.4986)
			(layers "F.Cu" "F.Mask" "F.Paste")
			(net "M_E_CPU1_SB_RSP<0>")
		)
		(pad "88" smd rect
			(at -2.050034 15.724886 270)
			(size 0.519938 1.4986)
			(layers "F.Cu" "F.Mask" "F.Paste")
			(net "GND")
		)
		(pad "89" smd rect
			(at -2.050034 16.575024 270)
			(size 0.519938 1.4986)
			(layers "F.Cu" "F.Mask" "F.Paste")
			(net "M_E_CPU1_SB_CB<4>")
		)
		(pad "90" smd rect
			(at -2.050034 17.424908 270)
			(size 0.519938 1.4986)
			(layers "F.Cu" "F.Mask" "F.Paste")
			(net "GND")
		)
		(pad "91" smd rect
			(at -2.050034 18.275046 270)
			(size 0.519938 1.4986)
			(layers "F.Cu" "F.Mask" "F.Paste")
			(net "M_E_CPU1_SB_CB<5>")
		)
		(pad "92" smd rect
			(at -2.050034 19.12493 270)
			(size 0.519938 1.4986)
			(layers "F.Cu" "F.Mask" "F.Paste")
			(net "GND")
		)
		(pad "93" smd rect
			(at -2.050034 19.975068 270)
			(size 0.519938 1.4986)
			(layers "F.Cu" "F.Mask" "F.Paste")
			(net "M_E_CPU1_SB_DQS_DP<9>")
		)
		(pad "94" smd rect
			(at -2.050034 20.824952 270)
			(size 0.519938 1.4986)
			(layers "F.Cu" "F.Mask" "F.Paste")
			(net "M_E_CPU1_SB_DQS_DN<9>")
		)
		(pad "95" smd rect
			(at -2.050034 21.67509 270)
			(size 0.519938 1.4986)
			(layers "F.Cu" "F.Mask" "F.Paste")
			(net "GND")
		)
		(pad "96" smd rect
			(at -2.050034 22.524974 270)
			(size 0.519938 1.4986)
			(layers "F.Cu" "F.Mask" "F.Paste")
			(net "M_E_CPU1_SB_CB<0>")
		)
		(pad "97" smd rect
			(at -2.050034 23.375112 270)
			(size 0.519938 1.4986)
			(layers "F.Cu" "F.Mask" "F.Paste")
			(net "GND")
		)
		(pad "98" smd rect
			(at -2.050034 24.224996 270)
			(size 0.519938 1.4986)
			(layers "F.Cu" "F.Mask" "F.Paste")
			(net "M_E_CPU1_SB_CB<1>")
		)
		(pad "99" smd rect
			(at -2.050034 25.07488 270)
			(size 0.519938 1.4986)
			(layers "F.Cu" "F.Mask" "F.Paste")
			(net "GND")
		)
		(pad "100" smd rect
			(at -2.050034 25.925018 270)
			(size 0.519938 1.4986)
			(layers "F.Cu" "F.Mask" "F.Paste")
			(net "M_E_CPU1_SB_DQ<0>")
		)
		(pad "101" smd rect
			(at -2.050034 26.774902 270)
			(size 0.519938 1.4986)
			(layers "F.Cu" "F.Mask" "F.Paste")
			(net "GND")
		)
		(pad "102" smd rect
			(at -2.050034 27.62504 270)
			(size 0.519938 1.4986)
			(layers "F.Cu" "F.Mask" "F.Paste")
			(net "M_E_CPU1_SB_DQ<1>")
		)
		(pad "103" smd rect
			(at -2.050034 28.474924 270)
			(size 0.519938 1.4986)
			(layers "F.Cu" "F.Mask" "F.Paste")
			(net "GND")
		)
		(pad "104" smd rect
			(at -2.050034 29.325062 270)
			(size 0.519938 1.4986)
			(layers "F.Cu" "F.Mask" "F.Paste")
			(net "M_E_CPU1_SB_DQS_DP<0>")
		)
		(pad "105" smd rect
			(at -2.050034 30.174946 270)
			(size 0.519938 1.4986)
			(layers "F.Cu" "F.Mask" "F.Paste")
			(net "M_E_CPU1_SB_DQS_DN<0>")
		)
		(pad "106" smd rect
			(at -2.050034 31.025084 270)
			(size 0.519938 1.4986)
			(layers "F.Cu" "F.Mask" "F.Paste")
			(net "GND")
		)
		(pad "107" smd rect
			(at -2.050034 31.874968 270)
			(size 0.519938 1.4986)
			(layers "F.Cu" "F.Mask" "F.Paste")
			(net "M_E_CPU1_SB_DQ<4>")
		)
		(pad "108" smd rect
			(at -2.050034 32.725106 270)
			(size 0.519938 1.4986)
			(layers "F.Cu" "F.Mask" "F.Paste")
			(net "GND")
		)
		(pad "109" smd rect
			(at -2.050034 33.57499 270)
			(size 0.519938 1.4986)
			(layers "F.Cu" "F.Mask" "F.Paste")
			(net "M_E_CPU1_SB_DQ<5>")
		)
		(pad "110" smd rect
			(at -2.050034 34.425128 270)
			(size 0.519938 1.4986)
			(layers "F.Cu" "F.Mask" "F.Paste")
			(net "GND")
		)
		(pad "111" smd rect
			(at -2.050034 35.275012 270)
			(size 0.519938 1.4986)
			(layers "F.Cu" "F.Mask" "F.Paste")
			(net "M_E_CPU1_SB_DQ<8>")
		)
		(pad "112" smd rect
			(at -2.050034 36.124896 270)
			(size 0.519938 1.4986)
			(layers "F.Cu" "F.Mask" "F.Paste")
			(net "GND")
		)
		(pad "113" smd rect
			(at -2.050034 36.975034 270)
			(size 0.519938 1.4986)
			(layers "F.Cu" "F.Mask" "F.Paste")
			(net "M_E_CPU1_SB_DQ<9>")
		)
		(pad "114" smd rect
			(at -2.050034 37.824918 270)
			(size 0.519938 1.4986)
			(layers "F.Cu" "F.Mask" "F.Paste")
			(net "GND")
		)
		(pad "115" smd rect
			(at -2.050034 38.675056 270)
			(size 0.519938 1.4986)
			(layers "F.Cu" "F.Mask" "F.Paste")
			(net "M_E_CPU1_SB_DQS_DP<1>")
		)
		(pad "116" smd rect
			(at -2.050034 39.52494 270)
			(size 0.519938 1.4986)
			(layers "F.Cu" "F.Mask" "F.Paste")
			(net "M_E_CPU1_SB_DQS_DN<1>")
		)
		(pad "117" smd rect
			(at -2.050034 40.375078 270)
			(size 0.519938 1.4986)
			(layers "F.Cu" "F.Mask" "F.Paste")
			(net "GND")
		)
		(pad "118" smd rect
			(at -2.050034 41.224962 270)
			(size 0.519938 1.4986)
			(layers "F.Cu" "F.Mask" "F.Paste")
			(net "M_E_CPU1_SB_DQ<12>")
		)
		(pad "119" smd rect
			(at -2.050034 42.0751 270)
			(size 0.519938 1.4986)
			(layers "F.Cu" "F.Mask" "F.Paste")
			(net "GND")
		)
		(pad "120" smd rect
			(at -2.050034 42.924984 270)
			(size 0.519938 1.4986)
			(layers "F.Cu" "F.Mask" "F.Paste")
			(net "M_E_CPU1_SB_DQ<13>")
		)
		(pad "121" smd rect
			(at -2.050034 43.775122 270)
			(size 0.519938 1.4986)
			(layers "F.Cu" "F.Mask" "F.Paste")
			(net "GND")
		)
		(pad "122" smd rect
			(at -2.050034 44.625006 270)
			(size 0.519938 1.4986)
			(layers "F.Cu" "F.Mask" "F.Paste")
			(net "M_E_CPU1_SB_DQ<16>")
		)
		(pad "123" smd rect
			(at -2.050034 45.47489 270)
			(size 0.519938 1.4986)
			(layers "F.Cu" "F.Mask" "F.Paste")
			(net "GND")
		)
		(pad "124" smd rect
			(at -2.050034 46.325028 270)
			(size 0.519938 1.4986)
			(layers "F.Cu" "F.Mask" "F.Paste")
			(net "M_E_CPU1_SB_DQ<17>")
		)
		(pad "125" smd rect
			(at -2.050034 47.174912 270)
			(size 0.519938 1.4986)
			(layers "F.Cu" "F.Mask" "F.Paste")
			(net "GND")
		)
		(pad "126" smd rect
			(at -2.050034 48.02505 270)
			(size 0.519938 1.4986)
			(layers "F.Cu" "F.Mask" "F.Paste")
			(net "M_E_CPU1_SB_DQS_DP<2>")
		)
		(pad "127" smd rect
			(at -2.050034 48.874934 270)
			(size 0.519938 1.4986)
			(layers "F.Cu" "F.Mask" "F.Paste")
			(net "M_E_CPU1_SB_DQS_DN<2>")
		)
		(pad "128" smd rect
			(at -2.050034 49.725072 270)
			(size 0.519938 1.4986)
			(layers "F.Cu" "F.Mask" "F.Paste")
			(net "GND")
		)
		(pad "129" smd rect
			(at -2.050034 50.574956 270)
			(size 0.519938 1.4986)
			(layers "F.Cu" "F.Mask" "F.Paste")
			(net "M_E_CPU1_SB_DQ<20>")
		)
		(pad "130" smd rect
			(at -2.050034 51.425094 270)
			(size 0.519938 1.4986)
			(layers "F.Cu" "F.Mask" "F.Paste")
			(net "GND")
		)
		(pad "131" smd rect
			(at -2.050034 52.274978 270)
			(size 0.519938 1.4986)
			(layers "F.Cu" "F.Mask" "F.Paste")
			(net "M_E_CPU1_SB_DQ<21>")
		)
		(pad "132" smd rect
			(at -2.050034 53.125116 270)
			(size 0.519938 1.4986)
			(layers "F.Cu" "F.Mask" "F.Paste")
			(net "GND")
		)
		(pad "133" smd rect
			(at -2.050034 53.975 270)
			(size 0.519938 1.4986)
			(layers "F.Cu" "F.Mask" "F.Paste")
			(net "M_E_CPU1_SB_DQ<24>")
		)
		(pad "134" smd rect
			(at -2.050034 54.824884 270)
			(size 0.519938 1.4986)
			(layers "F.Cu" "F.Mask" "F.Paste")
			(net "GND")
		)
		(pad "135" smd rect
			(at -2.050034 55.675022 270)
			(size 0.519938 1.4986)
			(layers "F.Cu" "F.Mask" "F.Paste")
			(net "M_E_CPU1_SB_DQ<25>")
		)
		(pad "136" smd rect
			(at -2.050034 56.524906 270)
			(size 0.519938 1.4986)
			(layers "F.Cu" "F.Mask" "F.Paste")
			(net "GND")
		)
		(pad "137" smd rect
			(at -2.050034 57.375044 270)
			(size 0.519938 1.4986)
			(layers "F.Cu" "F.Mask" "F.Paste")
			(net "M_E_CPU1_SB_DQS_DP<3>")
		)
		(pad "138" smd rect
			(at -2.050034 58.224928 270)
			(size 0.519938 1.4986)
			(layers "F.Cu" "F.Mask" "F.Paste")
			(net "M_E_CPU1_SB_DQS_DN<3>")
		)
		(pad "139" smd rect
			(at -2.050034 59.075066 270)
			(size 0.519938 1.4986)
			(layers "F.Cu" "F.Mask" "F.Paste")
			(net "GND")
		)
		(pad "140" smd rect
			(at -2.050034 59.92495 270)
			(size 0.519938 1.4986)
			(layers "F.Cu" "F.Mask" "F.Paste")
			(net "M_E_CPU1_SB_DQ<28>")
		)
		(pad "141" smd rect
			(at -2.050034 60.775088 270)
			(size 0.519938 1.4986)
			(layers "F.Cu" "F.Mask" "F.Paste")
			(net "GND")
		)
		(pad "142" smd rect
			(at -2.050034 61.624972 270)
			(size 0.519938 1.4986)
			(layers "F.Cu" "F.Mask" "F.Paste")
			(net "M_E_CPU1_SB_DQ<29>")
		)
		(pad "143" smd rect
			(at -2.050034 62.47511 270)
			(size 0.519938 1.4986)
			(layers "F.Cu" "F.Mask" "F.Paste")
			(net "GND")
		)
		(pad "144" smd rect
			(at -2.050034 63.324994 270)
			(size 0.519938 1.4986)
			(layers "F.Cu" "F.Mask" "F.Paste")
			(net "TP_CHE_CPU1_DIMM1_FRU_1")
		)
		(pad "145" smd rect
			(at 2.050034 -63.324994 270)
			(size 0.519938 1.4986)
			(layers "F.Cu" "F.Mask" "F.Paste")
			(net "P12V_S3_AUX_CPU1_NVDIMM")
		)
		(pad "146" smd rect
			(at 2.050034 -62.47511 270)
			(size 0.519938 1.4986)
			(layers "F.Cu" "F.Mask" "F.Paste")
			(net "P12V_S3_AUX_CPU1_NVDIMM")
		)
		(pad "147" smd rect
			(at 2.050034 -61.624972 270)
			(size 0.519938 1.4986)
			(layers "F.Cu" "F.Mask" "F.Paste")
			(net "PWRGD_CHE_CPU1_DIMM1")
		)
		(pad "148" smd rect
			(at 2.050034 -60.775088 270)
			(size 0.519938 1.4986)
			(layers "F.Cu" "F.Mask" "F.Paste")
			(net "PD_CHE_CPU1_DIMM1_SAA")
		)
		(pad "149" smd rect
			(at 2.050034 -59.92495 270)
			(size 0.519938 1.4986)
			(layers "F.Cu" "F.Mask" "F.Paste")
			(net "TP_CHE_CPU1_DIMM1_FRU_2")
		)
		(pad "150" smd rect
			(at 2.050034 -59.075066 270)
			(size 0.519938 1.4986)
			(layers "F.Cu" "F.Mask" "F.Paste")
			(net "TP_CHE_CPU1_DIMM1_FRU_3")
		)
		(pad "151" smd rect
			(at 2.050034 -58.224928 270)
			(size 0.519938 1.4986)
			(layers "F.Cu" "F.Mask" "F.Paste")
			(net "GND")
		)
		(pad "152" smd rect
			(at 2.050034 -57.375044 270)
			(size 0.519938 1.4986)
			(layers "F.Cu" "F.Mask" "F.Paste")
			(net "M_E_CPU1_SA_DQ<2>")
		)
		(pad "153" smd rect
			(at 2.050034 -56.524906 270)
			(size 0.519938 1.4986)
			(layers "F.Cu" "F.Mask" "F.Paste")
			(net "GND")
		)
		(pad "154" smd rect
			(at 2.050034 -55.675022 270)
			(size 0.519938 1.4986)
			(layers "F.Cu" "F.Mask" "F.Paste")
			(net "M_E_CPU1_SA_DQ<3>")
		)
		(pad "155" smd rect
			(at 2.050034 -54.824884 270)
			(size 0.519938 1.4986)
			(layers "F.Cu" "F.Mask" "F.Paste")
			(net "GND")
		)
		(pad "156" smd rect
			(at 2.050034 -53.975 270)
			(size 0.519938 1.4986)
			(layers "F.Cu" "F.Mask" "F.Paste")
			(net "M_E_CPU1_SA_DQS_DN<5>")
		)
		(pad "157" smd rect
			(at 2.050034 -53.125116 270)
			(size 0.519938 1.4986)
			(layers "F.Cu" "F.Mask" "F.Paste")
			(net "M_E_CPU1_SA_DQS_DP<5>")
		)
		(pad "158" smd rect
			(at 2.050034 -52.274978 270)
			(size 0.519938 1.4986)
			(layers "F.Cu" "F.Mask" "F.Paste")
			(net "GND")
		)
		(pad "159" smd rect
			(at 2.050034 -51.425094 270)
			(size 0.519938 1.4986)
			(layers "F.Cu" "F.Mask" "F.Paste")
			(net "M_E_CPU1_SA_DQ<6>")
		)
		(pad "160" smd rect
			(at 2.050034 -50.574956 270)
			(size 0.519938 1.4986)
			(layers "F.Cu" "F.Mask" "F.Paste")
			(net "GND")
		)
		(pad "161" smd rect
			(at 2.050034 -49.725072 270)
			(size 0.519938 1.4986)
			(layers "F.Cu" "F.Mask" "F.Paste")
			(net "M_E_CPU1_SA_DQ<7>")
		)
		(pad "162" smd rect
			(at 2.050034 -48.874934 270)
			(size 0.519938 1.4986)
			(layers "F.Cu" "F.Mask" "F.Paste")
			(net "GND")
		)
		(pad "163" smd rect
			(at 2.050034 -48.02505 270)
			(size 0.519938 1.4986)
			(layers "F.Cu" "F.Mask" "F.Paste")
			(net "M_E_CPU1_SA_DQ<10>")
		)
		(pad "164" smd rect
			(at 2.050034 -47.174912 270)
			(size 0.519938 1.4986)
			(layers "F.Cu" "F.Mask" "F.Paste")
			(net "GND")
		)
		(pad "165" smd rect
			(at 2.050034 -46.325028 270)
			(size 0.519938 1.4986)
			(layers "F.Cu" "F.Mask" "F.Paste")
			(net "M_E_CPU1_SA_DQ<11>")
		)
		(pad "166" smd rect
			(at 2.050034 -45.47489 270)
			(size 0.519938 1.4986)
			(layers "F.Cu" "F.Mask" "F.Paste")
			(net "GND")
		)
		(pad "167" smd rect
			(at 2.050034 -44.625006 270)
			(size 0.519938 1.4986)
			(layers "F.Cu" "F.Mask" "F.Paste")
			(net "M_E_CPU1_SA_DQS_DN<6>")
		)
		(pad "168" smd rect
			(at 2.050034 -43.775122 270)
			(size 0.519938 1.4986)
			(layers "F.Cu" "F.Mask" "F.Paste")
			(net "M_E_CPU1_SA_DQS_DP<6>")
		)
		(pad "169" smd rect
			(at 2.050034 -42.924984 270)
			(size 0.519938 1.4986)
			(layers "F.Cu" "F.Mask" "F.Paste")
			(net "GND")
		)
		(pad "170" smd rect
			(at 2.050034 -42.0751 270)
			(size 0.519938 1.4986)
			(layers "F.Cu" "F.Mask" "F.Paste")
			(net "M_E_CPU1_SA_DQ<14>")
		)
		(pad "171" smd rect
			(at 2.050034 -41.224962 270)
			(size 0.519938 1.4986)
			(layers "F.Cu" "F.Mask" "F.Paste")
			(net "GND")
		)
		(pad "172" smd rect
			(at 2.050034 -40.375078 270)
			(size 0.519938 1.4986)
			(layers "F.Cu" "F.Mask" "F.Paste")
			(net "M_E_CPU1_SA_DQ<15>")
		)
		(pad "173" smd rect
			(at 2.050034 -39.52494 270)
			(size 0.519938 1.4986)
			(layers "F.Cu" "F.Mask" "F.Paste")
			(net "GND")
		)
		(pad "174" smd rect
			(at 2.050034 -38.675056 270)
			(size 0.519938 1.4986)
			(layers "F.Cu" "F.Mask" "F.Paste")
			(net "M_E_CPU1_SA_DQ<18>")
		)
		(pad "175" smd rect
			(at 2.050034 -37.824918 270)
			(size 0.519938 1.4986)
			(layers "F.Cu" "F.Mask" "F.Paste")
			(net "GND")
		)
		(pad "176" smd rect
			(at 2.050034 -36.975034 270)
			(size 0.519938 1.4986)
			(layers "F.Cu" "F.Mask" "F.Paste")
			(net "M_E_CPU1_SA_DQ<19>")
		)
		(pad "177" smd rect
			(at 2.050034 -36.124896 270)
			(size 0.519938 1.4986)
			(layers "F.Cu" "F.Mask" "F.Paste")
			(net "GND")
		)
		(pad "178" smd rect
			(at 2.050034 -35.275012 270)
			(size 0.519938 1.4986)
			(layers "F.Cu" "F.Mask" "F.Paste")
			(net "M_E_CPU1_SA_DQS_DN<7>")
		)
		(pad "179" smd rect
			(at 2.050034 -34.425128 270)
			(size 0.519938 1.4986)
			(layers "F.Cu" "F.Mask" "F.Paste")
			(net "M_E_CPU1_SA_DQS_DP<7>")
		)
		(pad "180" smd rect
			(at 2.050034 -33.57499 270)
			(size 0.519938 1.4986)
			(layers "F.Cu" "F.Mask" "F.Paste")
			(net "GND")
		)
		(pad "181" smd rect
			(at 2.050034 -32.725106 270)
			(size 0.519938 1.4986)
			(layers "F.Cu" "F.Mask" "F.Paste")
			(net "M_E_CPU1_SA_DQ<22>")
		)
		(pad "182" smd rect
			(at 2.050034 -31.874968 270)
			(size 0.519938 1.4986)
			(layers "F.Cu" "F.Mask" "F.Paste")
			(net "GND")
		)
		(pad "183" smd rect
			(at 2.050034 -31.025084 270)
			(size 0.519938 1.4986)
			(layers "F.Cu" "F.Mask" "F.Paste")
			(net "M_E_CPU1_SA_DQ<23>")
		)
		(pad "184" smd rect
			(at 2.050034 -30.174946 270)
			(size 0.519938 1.4986)
			(layers "F.Cu" "F.Mask" "F.Paste")
			(net "GND")
		)
		(pad "185" smd rect
			(at 2.050034 -29.325062 270)
			(size 0.519938 1.4986)
			(layers "F.Cu" "F.Mask" "F.Paste")
			(net "M_E_CPU1_SA_DQ<26>")
		)
		(pad "186" smd rect
			(at 2.050034 -28.474924 270)
			(size 0.519938 1.4986)
			(layers "F.Cu" "F.Mask" "F.Paste")
			(net "GND")
		)
		(pad "187" smd rect
			(at 2.050034 -27.62504 270)
			(size 0.519938 1.4986)
			(layers "F.Cu" "F.Mask" "F.Paste")
			(net "M_E_CPU1_SA_DQ<27>")
		)
		(pad "188" smd rect
			(at 2.050034 -26.774902 270)
			(size 0.519938 1.4986)
			(layers "F.Cu" "F.Mask" "F.Paste")
			(net "GND")
		)
		(pad "189" smd rect
			(at 2.050034 -25.925018 270)
			(size 0.519938 1.4986)
			(layers "F.Cu" "F.Mask" "F.Paste")
			(net "M_E_CPU1_SA_DQS_DN<8>")
		)
		(pad "190" smd rect
			(at 2.050034 -25.07488 270)
			(size 0.519938 1.4986)
			(layers "F.Cu" "F.Mask" "F.Paste")
			(net "M_E_CPU1_SA_DQS_DP<8>")
		)
		(pad "191" smd rect
			(at 2.050034 -24.224996 270)
			(size 0.519938 1.4986)
			(layers "F.Cu" "F.Mask" "F.Paste")
			(net "GND")
		)
		(pad "192" smd rect
			(at 2.050034 -23.375112 270)
			(size 0.519938 1.4986)
			(layers "F.Cu" "F.Mask" "F.Paste")
			(net "M_E_CPU1_SA_DQ<30>")
		)
		(pad "193" smd rect
			(at 2.050034 -22.524974 270)
			(size 0.519938 1.4986)
			(layers "F.Cu" "F.Mask" "F.Paste")
			(net "GND")
		)
		(pad "194" smd rect
			(at 2.050034 -21.67509 270)
			(size 0.519938 1.4986)
			(layers "F.Cu" "F.Mask" "F.Paste")
			(net "M_E_CPU1_SA_DQ<31>")
		)
		(pad "195" smd rect
			(at 2.050034 -20.824952 270)
			(size 0.519938 1.4986)
			(layers "F.Cu" "F.Mask" "F.Paste")
			(net "GND")
		)
		(pad "196" smd rect
			(at 2.050034 -19.975068 270)
			(size 0.519938 1.4986)
			(layers "F.Cu" "F.Mask" "F.Paste")
			(net "M_E_CPU1_SA_CB<2>")
		)
		(pad "197" smd rect
			(at 2.050034 -19.12493 270)
			(size 0.519938 1.4986)
			(layers "F.Cu" "F.Mask" "F.Paste")
			(net "GND")
		)
		(pad "198" smd rect
			(at 2.050034 -18.275046 270)
			(size 0.519938 1.4986)
			(layers "F.Cu" "F.Mask" "F.Paste")
			(net "M_E_CPU1_SA_CB<3>")
		)
		(pad "199" smd rect
			(at 2.050034 -17.424908 270)
			(size 0.519938 1.4986)
			(layers "F.Cu" "F.Mask" "F.Paste")
			(net "GND")
		)
		(pad "200" smd rect
			(at 2.050034 -16.575024 270)
			(size 0.519938 1.4986)
			(layers "F.Cu" "F.Mask" "F.Paste")
			(net "M_E_CPU1_SA_DQS_DN<9>")
		)
		(pad "201" smd rect
			(at 2.050034 -15.724886 270)
			(size 0.519938 1.4986)
			(layers "F.Cu" "F.Mask" "F.Paste")
			(net "M_E_CPU1_SA_DQS_DP<9>")
		)
		(pad "202" smd rect
			(at 2.050034 -14.875002 270)
			(size 0.519938 1.4986)
			(layers "F.Cu" "F.Mask" "F.Paste")
			(net "GND")
		)
		(pad "203" smd rect
			(at 2.050034 -14.025118 270)
			(size 0.519938 1.4986)
			(layers "F.Cu" "F.Mask" "F.Paste")
			(net "M_E_CPU1_SA_CB<6>")
		)
		(pad "204" smd rect
			(at 2.050034 -13.17498 270)
			(size 0.519938 1.4986)
			(layers "F.Cu" "F.Mask" "F.Paste")
			(net "GND")
		)
		(pad "205" smd rect
			(at 2.050034 -12.325096 270)
			(size 0.519938 1.4986)
			(layers "F.Cu" "F.Mask" "F.Paste")
			(net "M_E_CPU1_SA_CB<7>")
		)
		(pad "206" smd rect
			(at 2.050034 -11.474958 270)
			(size 0.519938 1.4986)
			(layers "F.Cu" "F.Mask" "F.Paste")
			(net "GND")
		)
		(pad "207" smd rect
			(at 2.050034 -10.625074 270)
			(size 0.519938 1.4986)
			(layers "F.Cu" "F.Mask" "F.Paste")
			(net "RST_M_EF_CPU1_FPGA_N")
		)
		(pad "208" smd rect
			(at 2.050034 -9.774936 270)
			(size 0.519938 1.4986)
			(layers "F.Cu" "F.Mask" "F.Paste")
			(net "GND")
		)
		(pad "209" smd rect
			(at 2.050034 -8.925052 270)
			(size 0.519938 1.4986)
			(layers "F.Cu" "F.Mask" "F.Paste")
			(net "M_E_CPU1_SA_CS_N<1>")
		)
		(pad "210" smd rect
			(at 2.050034 -8.074914 270)
			(size 0.519938 1.4986)
			(layers "F.Cu" "F.Mask" "F.Paste")
			(net "GND")
		)
		(pad "211" smd rect
			(at 2.050034 -7.22503 270)
			(size 0.519938 1.4986)
			(layers "F.Cu" "F.Mask" "F.Paste")
			(net "M_E_CPU1_SA_CA<1>")
		)
		(pad "212" smd rect
			(at 2.050034 -6.374892 270)
			(size 0.519938 1.4986)
			(layers "F.Cu" "F.Mask" "F.Paste")
			(net "GND")
		)
		(pad "213" smd rect
			(at 2.050034 -5.525008 270)
			(size 0.519938 1.4986)
			(layers "F.Cu" "F.Mask" "F.Paste")
			(net "M_E_CPU1_SA_CA<3>")
		)
		(pad "214" smd rect
			(at 2.050034 -4.675124 270)
			(size 0.519938 1.4986)
			(layers "F.Cu" "F.Mask" "F.Paste")
			(net "GND")
		)
		(pad "215" smd rect
			(at 2.050034 -3.824986 270)
			(size 0.519938 1.4986)
			(layers "F.Cu" "F.Mask" "F.Paste")
			(net "M_E_CPU1_SA_CA<5>")
		)
		(pad "216" smd rect
			(at 2.050034 -2.975102 270)
			(size 0.519938 1.4986)
			(layers "F.Cu" "F.Mask" "F.Paste")
			(net "GND")
		)
		(pad "217" smd rect
			(at 2.050034 -2.124964 270)
			(size 0.519938 1.4986)
			(layers "F.Cu" "F.Mask" "F.Paste")
			(net "M_E_CPU1_CLK_DP<0>")
		)
		(pad "218" smd rect
			(at 2.050034 -1.27508 270)
			(size 0.519938 1.4986)
			(layers "F.Cu" "F.Mask" "F.Paste")
			(net "M_E_CPU1_CLK_DN<0>")
		)
		(pad "219" smd rect
			(at 2.050034 -0.424942 270)
			(size 0.519938 1.4986)
			(layers "F.Cu" "F.Mask" "F.Paste")
			(net "GND")
		)
		(pad "220" smd rect
			(at 2.050034 5.525008 270)
			(size 0.519938 1.4986)
			(layers "F.Cu" "F.Mask" "F.Paste")
			(net "TP_CHE_CPU1_DIMM1_FRU_4")
		)
		(pad "221" smd rect
			(at 2.050034 6.374892 270)
			(size 0.519938 1.4986)
			(layers "F.Cu" "F.Mask" "F.Paste")
			(net "M_E_CPU1_SB_CA<1>")
		)
		(pad "222" smd rect
			(at 2.050034 7.22503 270)
			(size 0.519938 1.4986)
			(layers "F.Cu" "F.Mask" "F.Paste")
			(net "GND")
		)
		(pad "223" smd rect
			(at 2.050034 8.074914 270)
			(size 0.519938 1.4986)
			(layers "F.Cu" "F.Mask" "F.Paste")
			(net "M_E_CPU1_SB_CA<3>")
		)
		(pad "224" smd rect
			(at 2.050034 8.925052 270)
			(size 0.519938 1.4986)
			(layers "F.Cu" "F.Mask" "F.Paste")
			(net "GND")
		)
		(pad "225" smd rect
			(at 2.050034 9.774936 270)
			(size 0.519938 1.4986)
			(layers "F.Cu" "F.Mask" "F.Paste")
			(net "M_E_CPU1_SB_CA<5>")
		)
		(pad "226" smd rect
			(at 2.050034 10.625074 270)
			(size 0.519938 1.4986)
			(layers "F.Cu" "F.Mask" "F.Paste")
			(net "GND")
		)
		(pad "227" smd rect
			(at 2.050034 11.474958 270)
			(size 0.519938 1.4986)
			(layers "F.Cu" "F.Mask" "F.Paste")
			(net "M_E_CPU1_SB_PAR")
		)
		(pad "228" smd rect
			(at 2.050034 12.325096 270)
			(size 0.519938 1.4986)
			(layers "F.Cu" "F.Mask" "F.Paste")
			(net "GND")
		)
		(pad "229" smd rect
			(at 2.050034 13.17498 270)
			(size 0.519938 1.4986)
			(layers "F.Cu" "F.Mask" "F.Paste")
			(net "M_E_CPU1_SB_CS_N<1>")
		)
		(pad "230" smd rect
			(at 2.050034 14.025118 270)
			(size 0.519938 1.4986)
			(layers "F.Cu" "F.Mask" "F.Paste")
			(net "GND")
		)
		(pad "231" smd rect
			(at 2.050034 14.875002 270)
			(size 0.519938 1.4986)
			(layers "F.Cu" "F.Mask" "F.Paste")
			(net "TP_CHE_CPU1_DIMM1_FRU_5")
		)
		(pad "232" smd rect
			(at 2.050034 15.724886 270)
			(size 0.519938 1.4986)
			(layers "F.Cu" "F.Mask" "F.Paste")
			(net "TP_CHE_CPU1_DIMM1_FRU_6")
		)
		(pad "233" smd rect
			(at 2.050034 16.575024 270)
			(size 0.519938 1.4986)
			(layers "F.Cu" "F.Mask" "F.Paste")
			(net "GND")
		)
		(pad "234" smd rect
			(at 2.050034 17.424908 270)
			(size 0.519938 1.4986)
			(layers "F.Cu" "F.Mask" "F.Paste")
			(net "M_E_CPU1_SB_CB<6>")
		)
		(pad "235" smd rect
			(at 2.050034 18.275046 270)
			(size 0.519938 1.4986)
			(layers "F.Cu" "F.Mask" "F.Paste")
			(net "GND")
		)
		(pad "236" smd rect
			(at 2.050034 19.12493 270)
			(size 0.519938 1.4986)
			(layers "F.Cu" "F.Mask" "F.Paste")
			(net "M_E_CPU1_SB_CB<7>")
		)
		(pad "237" smd rect
			(at 2.050034 19.975068 270)
			(size 0.519938 1.4986)
			(layers "F.Cu" "F.Mask" "F.Paste")
			(net "GND")
		)
		(pad "238" smd rect
			(at 2.050034 20.824952 270)
			(size 0.519938 1.4986)
			(layers "F.Cu" "F.Mask" "F.Paste")
			(net "M_E_CPU1_SB_DQS_DN<4>")
		)
		(pad "239" smd rect
			(at 2.050034 21.67509 270)
			(size 0.519938 1.4986)
			(layers "F.Cu" "F.Mask" "F.Paste")
			(net "M_E_CPU1_SB_DQS_DP<4>")
		)
		(pad "240" smd rect
			(at 2.050034 22.524974 270)
			(size 0.519938 1.4986)
			(layers "F.Cu" "F.Mask" "F.Paste")
			(net "GND")
		)
		(pad "241" smd rect
			(at 2.050034 23.375112 270)
			(size 0.519938 1.4986)
			(layers "F.Cu" "F.Mask" "F.Paste")
			(net "M_E_CPU1_SB_CB<2>")
		)
		(pad "242" smd rect
			(at 2.050034 24.224996 270)
			(size 0.519938 1.4986)
			(layers "F.Cu" "F.Mask" "F.Paste")
			(net "GND")
		)
		(pad "243" smd rect
			(at 2.050034 25.07488 270)
			(size 0.519938 1.4986)
			(layers "F.Cu" "F.Mask" "F.Paste")
			(net "M_E_CPU1_SB_CB<3>")
		)
		(pad "244" smd rect
			(at 2.050034 25.925018 270)
			(size 0.519938 1.4986)
			(layers "F.Cu" "F.Mask" "F.Paste")
			(net "GND")
		)
		(pad "245" smd rect
			(at 2.050034 26.774902 270)
			(size 0.519938 1.4986)
			(layers "F.Cu" "F.Mask" "F.Paste")
			(net "M_E_CPU1_SB_DQ<2>")
		)
		(pad "246" smd rect
			(at 2.050034 27.62504 270)
			(size 0.519938 1.4986)
			(layers "F.Cu" "F.Mask" "F.Paste")
			(net "GND")
		)
		(pad "247" smd rect
			(at 2.050034 28.474924 270)
			(size 0.519938 1.4986)
			(layers "F.Cu" "F.Mask" "F.Paste")
			(net "M_E_CPU1_SB_DQ<3>")
		)
		(pad "248" smd rect
			(at 2.050034 29.325062 270)
			(size 0.519938 1.4986)
			(layers "F.Cu" "F.Mask" "F.Paste")
			(net "GND")
		)
		(pad "249" smd rect
			(at 2.050034 30.174946 270)
			(size 0.519938 1.4986)
			(layers "F.Cu" "F.Mask" "F.Paste")
			(net "M_E_CPU1_SB_DQS_DN<5>")
		)
		(pad "250" smd rect
			(at 2.050034 31.025084 270)
			(size 0.519938 1.4986)
			(layers "F.Cu" "F.Mask" "F.Paste")
			(net "M_E_CPU1_SB_DQS_DP<5>")
		)
		(pad "251" smd rect
			(at 2.050034 31.874968 270)
			(size 0.519938 1.4986)
			(layers "F.Cu" "F.Mask" "F.Paste")
			(net "GND")
		)
		(pad "252" smd rect
			(at 2.050034 32.725106 270)
			(size 0.519938 1.4986)
			(layers "F.Cu" "F.Mask" "F.Paste")
			(net "M_E_CPU1_SB_DQ<6>")
		)
		(pad "253" smd rect
			(at 2.050034 33.57499 270)
			(size 0.519938 1.4986)
			(layers "F.Cu" "F.Mask" "F.Paste")
			(net "GND")
		)
		(pad "254" smd rect
			(at 2.050034 34.425128 270)
			(size 0.519938 1.4986)
			(layers "F.Cu" "F.Mask" "F.Paste")
			(net "M_E_CPU1_SB_DQ<7>")
		)
		(pad "255" smd rect
			(at 2.050034 35.275012 270)
			(size 0.519938 1.4986)
			(layers "F.Cu" "F.Mask" "F.Paste")
			(net "GND")
		)
		(pad "256" smd rect
			(at 2.050034 36.124896 270)
			(size 0.519938 1.4986)
			(layers "F.Cu" "F.Mask" "F.Paste")
			(net "M_E_CPU1_SB_DQ<10>")
		)
		(pad "257" smd rect
			(at 2.050034 36.975034 270)
			(size 0.519938 1.4986)
			(layers "F.Cu" "F.Mask" "F.Paste")
			(net "GND")
		)
		(pad "258" smd rect
			(at 2.050034 37.824918 270)
			(size 0.519938 1.4986)
			(layers "F.Cu" "F.Mask" "F.Paste")
			(net "M_E_CPU1_SB_DQ<11>")
		)
		(pad "259" smd rect
			(at 2.050034 38.675056 270)
			(size 0.519938 1.4986)
			(layers "F.Cu" "F.Mask" "F.Paste")
			(net "GND")
		)
		(pad "260" smd rect
			(at 2.050034 39.52494 270)
			(size 0.519938 1.4986)
			(layers "F.Cu" "F.Mask" "F.Paste")
			(net "M_E_CPU1_SB_DQS_DN<6>")
		)
		(pad "261" smd rect
			(at 2.050034 40.375078 270)
			(size 0.519938 1.4986)
			(layers "F.Cu" "F.Mask" "F.Paste")
			(net "M_E_CPU1_SB_DQS_DP<6>")
		)
		(pad "262" smd rect
			(at 2.050034 41.224962 270)
			(size 0.519938 1.4986)
			(layers "F.Cu" "F.Mask" "F.Paste")
			(net "GND")
		)
		(pad "263" smd rect
			(at 2.050034 42.0751 270)
			(size 0.519938 1.4986)
			(layers "F.Cu" "F.Mask" "F.Paste")
			(net "M_E_CPU1_SB_DQ<14>")
		)
		(pad "264" smd rect
			(at 2.050034 42.924984 270)
			(size 0.519938 1.4986)
			(layers "F.Cu" "F.Mask" "F.Paste")
			(net "GND")
		)
		(pad "265" smd rect
			(at 2.050034 43.775122 270)
			(size 0.519938 1.4986)
			(layers "F.Cu" "F.Mask" "F.Paste")
			(net "M_E_CPU1_SB_DQ<15>")
		)
		(pad "266" smd rect
			(at 2.050034 44.625006 270)
			(size 0.519938 1.4986)
			(layers "F.Cu" "F.Mask" "F.Paste")
			(net "GND")
		)
		(pad "267" smd rect
			(at 2.050034 45.47489 270)
			(size 0.519938 1.4986)
			(layers "F.Cu" "F.Mask" "F.Paste")
			(net "M_E_CPU1_SB_DQ<18>")
		)
		(pad "268" smd rect
			(at 2.050034 46.325028 270)
			(size 0.519938 1.4986)
			(layers "F.Cu" "F.Mask" "F.Paste")
			(net "GND")
		)
		(pad "269" smd rect
			(at 2.050034 47.174912 270)
			(size 0.519938 1.4986)
			(layers "F.Cu" "F.Mask" "F.Paste")
			(net "M_E_CPU1_SB_DQ<19>")
		)
		(pad "270" smd rect
			(at 2.050034 48.02505 270)
			(size 0.519938 1.4986)
			(layers "F.Cu" "F.Mask" "F.Paste")
			(net "GND")
		)
		(pad "271" smd rect
			(at 2.050034 48.874934 270)
			(size 0.519938 1.4986)
			(layers "F.Cu" "F.Mask" "F.Paste")
			(net "M_E_CPU1_SB_DQS_DN<7>")
		)
		(pad "272" smd rect
			(at 2.050034 49.725072 270)
			(size 0.519938 1.4986)
			(layers "F.Cu" "F.Mask" "F.Paste")
			(net "M_E_CPU1_SB_DQS_DP<7>")
		)
		(pad "273" smd rect
			(at 2.050034 50.574956 270)
			(size 0.519938 1.4986)
			(layers "F.Cu" "F.Mask" "F.Paste")
			(net "GND")
		)
		(pad "274" smd rect
			(at 2.050034 51.425094 270)
			(size 0.519938 1.4986)
			(layers "F.Cu" "F.Mask" "F.Paste")
			(net "M_E_CPU1_SB_DQ<22>")
		)
		(pad "275" smd rect
			(at 2.050034 52.274978 270)
			(size 0.519938 1.4986)
			(layers "F.Cu" "F.Mask" "F.Paste")
			(net "GND")
		)
		(pad "276" smd rect
			(at 2.050034 53.125116 270)
			(size 0.519938 1.4986)
			(layers "F.Cu" "F.Mask" "F.Paste")
			(net "M_E_CPU1_SB_DQ<23>")
		)
		(pad "277" smd rect
			(at 2.050034 53.975 270)
			(size 0.519938 1.4986)
			(layers "F.Cu" "F.Mask" "F.Paste")
			(net "GND")
		)
		(pad "278" smd rect
			(at 2.050034 54.824884 270)
			(size 0.519938 1.4986)
			(layers "F.Cu" "F.Mask" "F.Paste")
			(net "M_E_CPU1_SB_DQ<26>")
		)
		(pad "279" smd rect
			(at 2.050034 55.675022 270)
			(size 0.519938 1.4986)
			(layers "F.Cu" "F.Mask" "F.Paste")
			(net "GND")
		)
		(pad "280" smd rect
			(at 2.050034 56.524906 270)
			(size 0.519938 1.4986)
			(layers "F.Cu" "F.Mask" "F.Paste")
			(net "M_E_CPU1_SB_DQ<27>")
		)
		(pad "281" smd rect
			(at 2.050034 57.375044 270)
			(size 0.519938 1.4986)
			(layers "F.Cu" "F.Mask" "F.Paste")
			(net "GND")
		)
		(pad "282" smd rect
			(at 2.050034 58.224928 270)
			(size 0.519938 1.4986)
			(layers "F.Cu" "F.Mask" "F.Paste")
			(net "M_E_CPU1_SB_DQS_DN<8>")
		)
		(pad "283" smd rect
			(at 2.050034 59.075066 270)
			(size 0.519938 1.4986)
			(layers "F.Cu" "F.Mask" "F.Paste")
			(net "M_E_CPU1_SB_DQS_DP<8>")
		)
		(pad "284" smd rect
			(at 2.050034 59.92495 270)
			(size 0.519938 1.4986)
			(layers "F.Cu" "F.Mask" "F.Paste")
			(net "GND")
		)
		(pad "285" smd rect
			(at 2.050034 60.775088 270)
			(size 0.519938 1.4986)
			(layers "F.Cu" "F.Mask" "F.Paste")
			(net "M_E_CPU1_SB_DQ<30>")
		)
		(pad "286" smd rect
			(at 2.050034 61.624972 270)
			(size 0.519938 1.4986)
			(layers "F.Cu" "F.Mask" "F.Paste")
			(net "GND")
		)
		(pad "287" smd rect
			(at 2.050034 62.47511 270)
			(size 0.519938 1.4986)
			(layers "F.Cu" "F.Mask" "F.Paste")
			(net "M_E_CPU1_SB_DQ<31>")
		)
		(pad "288" smd rect
			(at 2.050034 63.324994 270)
			(size 0.519938 1.4986)
			(layers "F.Cu" "F.Mask" "F.Paste")
			(net "GND")
		)
		(pad "G1" thru_hole oval
			(at 0 -68.97497)
			(size 2.8194 1.5748)
			(drill oval 2.4384 1.1938)
			(layers "*.Cu" "*.Mask")
			(remove_unused_layers no)
			(net "GND")
			(clearance 0.127)
			(thermal_gap 0.127)
		)
		(pad "G2" thru_hole oval
			(at 0 3.875024)
			(size 2.8194 1.5748)
			(drill oval 2.4384 1.1938)
			(layers "*.Cu" "*.Mask")
			(remove_unused_layers no)
			(net "GND")
			(clearance 0.127)
			(thermal_gap 0.127)
		)
		(pad "G3" thru_hole oval
			(at 0 68.97497)
			(size 2.8194 1.5748)
			(drill oval 2.4384 1.1938)
			(layers "*.Cu" "*.Mask")
			(remove_unused_layers no)
			(net "GND")
			(clearance 0.127)
			(thermal_gap 0.127)
		)
	)
	(footprint ""
		(layer "F.Cu")
		(at 160.83788 -120.106948 180)
		(property "Reference" "R1407"
			(at 0 0 180)
			(layer "F.SilkS")
			(hide yes)
			(effects
				(font
					(size 1.27 1.27)
				)
			)
		)
		(property "Value" ""
			(at 0 0 180)
			(layer "F.Fab")
			(effects
				(font
					(size 1.27 1.27)
				)
			)
		)
		(duplicate_pad_numbers_are_jumpers no)
		(fp_line
			(start 0.7874 0.4064)
			(end -0.7874 0.4064)
			(stroke
				(width 0.1524)
				(type default)
			)
			(layer "F.SilkS")
		)
		(fp_line
			(start 0.7874 -0.4064)
			(end 0.7874 0.4064)
			(stroke
				(width 0.1524)
				(type default)
			)
			(layer "F.SilkS")
		)
		(fp_line
			(start -0.7874 0.4064)
			(end -0.7874 -0.4064)
			(stroke
				(width 0.1524)
				(type default)
			)
			(layer "F.SilkS")
		)
		(fp_line
			(start -0.7874 -0.4064)
			(end 0.7874 -0.4064)
			(stroke
				(width 0.1524)
				(type default)
			)
			(layer "F.SilkS")
		)
		(fp_line
			(start 0.67945 0.3048)
			(end 0.120396 0.3048)
			(stroke
				(width 0.1)
				(type default)
			)
			(layer "F.Fab")
		)
		(fp_line
			(start 0.67945 -0.3048)
			(end 0.67945 0.3048)
			(stroke
				(width 0.1)
				(type default)
			)
			(layer "F.Fab")
		)
		(fp_line
			(start 0.12065 -0.2794)
			(end 0.12065 -0.3048)
			(stroke
				(width 0.1)
				(type default)
			)
			(layer "F.Fab")
		)
		(fp_line
			(start 0.12065 -0.3048)
			(end 0.67945 -0.3048)
			(stroke
				(width 0.1)
				(type default)
			)
			(layer "F.Fab")
		)
		(fp_line
			(start 0.120396 0.3048)
			(end 0.120396 0.2794)
			(stroke
				(width 0.1)
				(type default)
			)
			(layer "F.Fab")
		)
		(fp_line
			(start 0.120396 0.2794)
			(end -0.12065 0.2794)
			(stroke
				(width 0.1)
				(type default)
			)
			(layer "F.Fab")
		)
		(fp_line
			(start -0.12065 0.3048)
			(end -0.67945 0.3048)
			(stroke
				(width 0.1)
				(type default)
			)
			(layer "F.Fab")
		)
		(fp_line
			(start -0.12065 0.2794)
			(end -0.12065 0.3048)
			(stroke
				(width 0.1)
				(type default)
			)
			(layer "F.Fab")
		)
		(fp_line
			(start -0.12065 -0.2794)
			(end 0.12065 -0.2794)
			(stroke
				(width 0.1)
				(type default)
			)
			(layer "F.Fab")
		)
		(fp_line
			(start -0.12065 -0.305054)
			(end -0.12065 -0.2794)
			(stroke
				(width 0.1)
				(type default)
			)
			(layer "F.Fab")
		)
		(fp_line
			(start -0.67945 0.3048)
			(end -0.67945 -0.305054)
			(stroke
				(width 0.1)
				(type default)
			)
			(layer "F.Fab")
		)
		(fp_line
			(start -0.67945 -0.305054)
			(end -0.12065 -0.305054)
			(stroke
				(width 0.1)
				(type default)
			)
			(layer "F.Fab")
		)
		(pad "1" smd circle
			(at -0.40005 0 180)
			(size 0 0)
			(layers "F.Cu" "F.Mask" "F.Paste")
			(net "FM_PVCCINFAON_CPU0_R_EN")
		)
		(pad "2" smd circle
			(at 0.40005 0 180)
			(size 0 0)
			(layers "F.Cu" "F.Mask" "F.Paste")
			(net "GND")
		)
	)
	(footprint ""
		(layer "F.Cu")
		(at 105.315004 -244.032024 90)
		(property "Reference" "C257"
			(at 0 0 90)
			(layer "F.SilkS")
			(hide yes)
			(effects
				(font
					(size 1.27 1.27)
				)
			)
		)
		(property "Value" ""
			(at 0 0 90)
			(layer "F.Fab")
			(effects
				(font
					(size 1.27 1.27)
				)
			)
		)
		(duplicate_pad_numbers_are_jumpers no)
		(fp_line
			(start 0.7874 -0.4064)
			(end 0.7874 0.4064)
			(stroke
				(width 0.1524)
				(type default)
			)
			(layer "F.SilkS")
		)
		(fp_line
			(start -0.7874 -0.4064)
			(end 0.7874 -0.4064)
			(stroke
				(width 0.1524)
				(type default)
			)
			(layer "F.SilkS")
		)
		(fp_line
			(start 0.7874 0.4064)
			(end -0.7874 0.4064)
			(stroke
				(width 0.1524)
				(type default)
			)
			(layer "F.SilkS")
		)
		(fp_line
			(start -0.7874 0.4064)
			(end -0.7874 -0.4064)
			(stroke
				(width 0.1524)
				(type default)
			)
			(layer "F.SilkS")
		)
		(fp_line
			(start -0.12065 -0.305054)
			(end -0.12065 -0.2794)
			(stroke
				(width 0.1)
				(type default)
			)
			(layer "F.Fab")
		)
		(fp_line
			(start -0.67945 -0.305054)
			(end -0.12065 -0.305054)
			(stroke
				(width 0.1)
				(type default)
			)
			(layer "F.Fab")
		)
		(fp_line
			(start 0.67945 -0.3048)
			(end 0.67945 0.3048)
			(stroke
				(width 0.1)
				(type default)
			)
			(layer "F.Fab")
		)
		(fp_line
			(start 0.12065 -0.3048)
			(end 0.67945 -0.3048)
			(stroke
				(width 0.1)
				(type default)
			)
			(layer "F.Fab")
		)
		(fp_line
			(start 0.12065 -0.2794)
			(end 0.12065 -0.3048)
			(stroke
				(width 0.1)
				(type default)
			)
			(layer "F.Fab")
		)
		(fp_line
			(start -0.12065 -0.2794)
			(end 0.12065 -0.2794)
			(stroke
				(width 0.1)
				(type default)
			)
			(layer "F.Fab")
		)
		(fp_line
			(start 0.120396 0.2794)
			(end -0.12065 0.2794)
			(stroke
				(width 0.1)
				(type default)
			)
			(layer "F.Fab")
		)
		(fp_line
			(start -0.12065 0.2794)
			(end -0.12065 0.3048)
			(stroke
				(width 0.1)
				(type default)
			)
			(layer "F.Fab")
		)
		(fp_line
			(start 0.67945 0.3048)
			(end 0.120396 0.3048)
			(stroke
				(width 0.1)
				(type default)
			)
			(layer "F.Fab")
		)
		(fp_line
			(start 0.120396 0.3048)
			(end 0.120396 0.2794)
			(stroke
				(width 0.1)
				(type default)
			)
			(layer "F.Fab")
		)
		(fp_line
			(start -0.12065 0.3048)
			(end -0.67945 0.3048)
			(stroke
				(width 0.1)
				(type default)
			)
			(layer "F.Fab")
		)
		(fp_line
			(start -0.67945 0.3048)
			(end -0.67945 -0.305054)
			(stroke
				(width 0.1)
				(type default)
			)
			(layer "F.Fab")
		)
		(pad "1" smd circle
			(at -0.40005 0 90)
			(size 0 0)
			(layers "F.Cu" "F.Mask" "F.Paste")
			(net "PVCCIN_CPU1")
		)
		(pad "2" smd circle
			(at 0.40005 0 90)
			(size 0 0)
			(layers "F.Cu" "F.Mask" "F.Paste")
			(net "GND")
		)
	)
	(footprint ""
		(layer "F.Cu")
		(at 236.93628 -332.849728)
		(property "Reference" ""
			(at 0 0 0)
			(layer "F.SilkS")
			(hide yes)
			(effects
				(font
					(size 1.27 1.27)
				)
			)
		)
		(property "Value" ""
			(at 0 0 0)
			(layer "F.Fab")
			(effects
				(font
					(size 1.27 1.27)
				)
			)
		)
		(duplicate_pad_numbers_are_jumpers no)
		(pad "1" smd circle
			(at 0 0)
			(size 0.9906 0.9906)
			(layers "F.Cu" "F.Mask" "F.Paste")
			(net "Net_294")
		)
		(zone
			(layer "F.Cu")
			(hatch none 0.5)
			(connect_pads
				(clearance 0)
			)
			(min_thickness 0.25)
			(keepout
				(tracks not_allowed)
				(vias allowed)
				(pads allowed)
				(copperpour not_allowed)
				(footprints allowed)
			)
			(placement
				(enabled no)
				(sheetname "")
			)
			(fill
				(thermal_gap 0.5)
				(thermal_bridge_width 0.5)
				(island_removal_mode 0)
			)
			(polygon
				(pts
					(arc
						(start 238.56188 -332.849728)
						(mid 235.31068 -332.849728)
						(end 238.56188 -332.849728)
					)
				)
			)
		)
	)
	(footprint ""
		(layer "F.Cu")
		(at 440.395868 -16.700246 180)
		(property "Reference" "C1236"
			(at 0 0 180)
			(layer "F.SilkS")
			(hide yes)
			(effects
				(font
					(size 1.27 1.27)
				)
			)
		)
		(property "Value" ""
			(at 0 0 180)
			(layer "F.Fab")
			(effects
				(font
					(size 1.27 1.27)
				)
			)
		)
		(duplicate_pad_numbers_are_jumpers no)
		(fp_line
			(start 0.7874 0.4064)
			(end -0.7874 0.4064)
			(stroke
				(width 0.1524)
				(type default)
			)
			(layer "F.SilkS")
		)
		(fp_line
			(start 0.7874 -0.4064)
			(end 0.7874 0.4064)
			(stroke
				(width 0.1524)
				(type default)
			)
			(layer "F.SilkS")
		)
		(fp_line
			(start -0.7874 0.4064)
			(end -0.7874 -0.4064)
			(stroke
				(width 0.1524)
				(type default)
			)
			(layer "F.SilkS")
		)
		(fp_line
			(start -0.7874 -0.4064)
			(end 0.7874 -0.4064)
			(stroke
				(width 0.1524)
				(type default)
			)
			(layer "F.SilkS")
		)
		(fp_line
			(start 0.67945 0.3048)
			(end 0.120396 0.3048)
			(stroke
				(width 0.1)
				(type default)
			)
			(layer "F.Fab")
		)
		(fp_line
			(start 0.67945 -0.3048)
			(end 0.67945 0.3048)
			(stroke
				(width 0.1)
				(type default)
			)
			(layer "F.Fab")
		)
		(fp_line
			(start 0.12065 -0.2794)
			(end 0.12065 -0.3048)
			(stroke
				(width 0.1)
				(type default)
			)
			(layer "F.Fab")
		)
		(fp_line
			(start 0.12065 -0.3048)
			(end 0.67945 -0.3048)
			(stroke
				(width 0.1)
				(type default)
			)
			(layer "F.Fab")
		)
		(fp_line
			(start 0.120396 0.3048)
			(end 0.120396 0.2794)
			(stroke
				(width 0.1)
				(type default)
			)
			(layer "F.Fab")
		)
		(fp_line
			(start 0.120396 0.2794)
			(end -0.12065 0.2794)
			(stroke
				(width 0.1)
				(type default)
			)
			(layer "F.Fab")
		)
		(fp_line
			(start -0.12065 0.3048)
			(end -0.67945 0.3048)
			(stroke
				(width 0.1)
				(type default)
			)
			(layer "F.Fab")
		)
		(fp_line
			(start -0.12065 0.2794)
			(end -0.12065 0.3048)
			(stroke
				(width 0.1)
				(type default)
			)
			(layer "F.Fab")
		)
		(fp_line
			(start -0.12065 -0.2794)
			(end 0.12065 -0.2794)
			(stroke
				(width 0.1)
				(type default)
			)
			(layer "F.Fab")
		)
		(fp_line
			(start -0.12065 -0.305054)
			(end -0.12065 -0.2794)
			(stroke
				(width 0.1)
				(type default)
			)
			(layer "F.Fab")
		)
		(fp_line
			(start -0.67945 0.3048)
			(end -0.67945 -0.305054)
			(stroke
				(width 0.1)
				(type default)
			)
			(layer "F.Fab")
		)
		(fp_line
			(start -0.67945 -0.305054)
			(end -0.12065 -0.305054)
			(stroke
				(width 0.1)
				(type default)
			)
			(layer "F.Fab")
		)
		(pad "1" smd circle
			(at -0.40005 0 180)
			(size 0 0)
			(layers "F.Cu" "F.Mask" "F.Paste")
			(net "P12V_OCP_SFF")
		)
		(pad "2" smd circle
			(at 0.40005 0 180)
			(size 0 0)
			(layers "F.Cu" "F.Mask" "F.Paste")
			(net "GND")
		)
	)
	(footprint ""
		(layer "F.Cu")
		(at 143.433292 -92.634308 -90)
		(property "Reference" "R4393"
			(at 0 0 270)
			(layer "F.SilkS")
			(hide yes)
			(effects
				(font
					(size 1.27 1.27)
				)
			)
		)
		(property "Value" ""
			(at 0 0 270)
			(layer "F.Fab")
			(effects
				(font
					(size 1.27 1.27)
				)
			)
		)
		(duplicate_pad_numbers_are_jumpers no)
		(fp_line
			(start -0.7874 0.4064)
			(end -0.7874 -0.4064)
			(stroke
				(width 0.1524)
				(type default)
			)
			(layer "F.SilkS")
		)
		(fp_line
			(start 0.7874 0.4064)
			(end -0.7874 0.4064)
			(stroke
				(width 0.1524)
				(type default)
			)
			(layer "F.SilkS")
		)
		(fp_line
			(start -0.7874 -0.4064)
			(end 0.7874 -0.4064)
			(stroke
				(width 0.1524)
				(type default)
			)
			(layer "F.SilkS")
		)
		(fp_line
			(start 0.7874 -0.4064)
			(end 0.7874 0.4064)
			(stroke
				(width 0.1524)
				(type default)
			)
			(layer "F.SilkS")
		)
		(fp_line
			(start -0.67945 0.3048)
			(end -0.67945 -0.305054)
			(stroke
				(width 0.1)
				(type default)
			)
			(layer "F.Fab")
		)
		(fp_line
			(start -0.12065 0.3048)
			(end -0.67945 0.3048)
			(stroke
				(width 0.1)
				(type default)
			)
			(layer "F.Fab")
		)
		(fp_line
			(start 0.120396 0.3048)
			(end 0.120396 0.2794)
			(stroke
				(width 0.1)
				(type default)
			)
			(layer "F.Fab")
		)
		(fp_line
			(start 0.67945 0.3048)
			(end 0.120396 0.3048)
			(stroke
				(width 0.1)
				(type default)
			)
			(layer "F.Fab")
		)
		(fp_line
			(start -0.12065 0.2794)
			(end -0.12065 0.3048)
			(stroke
				(width 0.1)
				(type default)
			)
			(layer "F.Fab")
		)
		(fp_line
			(start 0.120396 0.2794)
			(end -0.12065 0.2794)
			(stroke
				(width 0.1)
				(type default)
			)
			(layer "F.Fab")
		)
		(fp_line
			(start -0.12065 -0.2794)
			(end 0.12065 -0.2794)
			(stroke
				(width 0.1)
				(type default)
			)
			(layer "F.Fab")
		)
		(fp_line
			(start 0.12065 -0.2794)
			(end 0.12065 -0.3048)
			(stroke
				(width 0.1)
				(type default)
			)
			(layer "F.Fab")
		)
		(fp_line
			(start 0.12065 -0.3048)
			(end 0.67945 -0.3048)
			(stroke
				(width 0.1)
				(type default)
			)
			(layer "F.Fab")
		)
		(fp_line
			(start 0.67945 -0.3048)
			(end 0.67945 0.3048)
			(stroke
				(width 0.1)
				(type default)
			)
			(layer "F.Fab")
		)
		(fp_line
			(start -0.67945 -0.305054)
			(end -0.12065 -0.305054)
			(stroke
				(width 0.1)
				(type default)
			)
			(layer "F.Fab")
		)
		(fp_line
			(start -0.12065 -0.305054)
			(end -0.12065 -0.2794)
			(stroke
				(width 0.1)
				(type default)
			)
			(layer "F.Fab")
		)
		(pad "1" smd circle
			(at -0.40005 0 270)
			(size 0 0)
			(layers "F.Cu" "F.Mask" "F.Paste")
			(net "H_CPU_ERR1_LVC2_R_N")
		)
		(pad "2" smd circle
			(at 0.40005 0 270)
			(size 0 0)
			(layers "F.Cu" "F.Mask" "F.Paste")
			(net "H_CPU_ERR1_PCH_R_N")
		)
	)
	(footprint ""
		(layer "F.Cu")
		(at 55.090314 -152.903174)
		(property "Reference" "PC2950"
			(at 0 0 0)
			(layer "F.SilkS")
			(hide yes)
			(effects
				(font
					(size 1.27 1.27)
				)
			)
		)
		(property "Value" ""
			(at 0 0 0)
			(layer "F.Fab")
			(effects
				(font
					(size 1.27 1.27)
				)
			)
		)
		(duplicate_pad_numbers_are_jumpers no)
		(fp_line
			(start -0.7874 -0.4064)
			(end 0.7874 -0.4064)
			(stroke
				(width 0.1524)
				(type default)
			)
			(layer "F.SilkS")
		)
		(fp_line
			(start -0.7874 0.4064)
			(end -0.7874 -0.4064)
			(stroke
				(width 0.1524)
				(type default)
			)
			(layer "F.SilkS")
		)
		(fp_line
			(start 0.7874 -0.4064)
			(end 0.7874 0.4064)
			(stroke
				(width 0.1524)
				(type default)
			)
			(layer "F.SilkS")
		)
		(fp_line
			(start 0.7874 0.4064)
			(end -0.7874 0.4064)
			(stroke
				(width 0.1524)
				(type default)
			)
			(layer "F.SilkS")
		)
		(fp_line
			(start -0.67945 -0.305054)
			(end -0.12065 -0.305054)
			(stroke
				(width 0.1)
				(type default)
			)
			(layer "F.Fab")
		)
		(fp_line
			(start -0.67945 0.3048)
			(end -0.67945 -0.305054)
			(stroke
				(width 0.1)
				(type default)
			)
			(layer "F.Fab")
		)
		(fp_line
			(start -0.12065 -0.305054)
			(end -0.12065 -0.2794)
			(stroke
				(width 0.1)
				(type default)
			)
			(layer "F.Fab")
		)
		(fp_line
			(start -0.12065 -0.2794)
			(end 0.12065 -0.2794)
			(stroke
				(width 0.1)
				(type default)
			)
			(layer "F.Fab")
		)
		(fp_line
			(start -0.12065 0.2794)
			(end -0.12065 0.3048)
			(stroke
				(width 0.1)
				(type default)
			)
			(layer "F.Fab")
		)
		(fp_line
			(start -0.12065 0.3048)
			(end -0.67945 0.3048)
			(stroke
				(width 0.1)
				(type default)
			)
			(layer "F.Fab")
		)
		(fp_line
			(start 0.120396 0.2794)
			(end -0.12065 0.2794)
			(stroke
				(width 0.1)
				(type default)
			)
			(layer "F.Fab")
		)
		(fp_line
			(start 0.120396 0.3048)
			(end 0.120396 0.2794)
			(stroke
				(width 0.1)
				(type default)
			)
			(layer "F.Fab")
		)
		(fp_line
			(start 0.12065 -0.3048)
			(end 0.67945 -0.3048)
			(stroke
				(width 0.1)
				(type default)
			)
			(layer "F.Fab")
		)
		(fp_line
			(start 0.12065 -0.2794)
			(end 0.12065 -0.3048)
			(stroke
				(width 0.1)
				(type default)
			)
			(layer "F.Fab")
		)
		(fp_line
			(start 0.67945 -0.3048)
			(end 0.67945 0.3048)
			(stroke
				(width 0.1)
				(type default)
			)
			(layer "F.Fab")
		)
		(fp_line
			(start 0.67945 0.3048)
			(end 0.120396 0.3048)
			(stroke
				(width 0.1)
				(type default)
			)
			(layer "F.Fab")
		)
		(pad "1" smd circle
			(at -0.40005 0)
			(size 0 0)
			(layers "F.Cu" "F.Mask" "F.Paste")
			(net "PVCCFA_EHV_CPU1_PVCC")
		)
		(pad "2" smd circle
			(at 0.40005 0)
			(size 0 0)
			(layers "F.Cu" "F.Mask" "F.Paste")
			(net "GND")
		)
	)
	(footprint ""
		(layer "F.Cu")
		(at 37.990272 -356.02418 90)
		(property "Reference" "PC1192"
			(at 0 0 90)
			(layer "F.SilkS")
			(hide yes)
			(effects
				(font
					(size 1.27 1.27)
				)
			)
		)
		(property "Value" ""
			(at 0 0 90)
			(layer "F.Fab")
			(effects
				(font
					(size 1.27 1.27)
				)
			)
		)
		(duplicate_pad_numbers_are_jumpers no)
		(fp_line
			(start 0.7874 -0.4064)
			(end 0.7874 0.4064)
			(stroke
				(width 0.1524)
				(type default)
			)
			(layer "F.SilkS")
		)
		(fp_line
			(start -0.7874 -0.4064)
			(end 0.7874 -0.4064)
			(stroke
				(width 0.1524)
				(type default)
			)
			(layer "F.SilkS")
		)
		(fp_line
			(start 0.7874 0.4064)
			(end -0.7874 0.4064)
			(stroke
				(width 0.1524)
				(type default)
			)
			(layer "F.SilkS")
		)
		(fp_line
			(start -0.7874 0.4064)
			(end -0.7874 -0.4064)
			(stroke
				(width 0.1524)
				(type default)
			)
			(layer "F.SilkS")
		)
		(fp_line
			(start -0.12065 -0.305054)
			(end -0.12065 -0.2794)
			(stroke
				(width 0.1)
				(type default)
			)
			(layer "F.Fab")
		)
		(fp_line
			(start -0.67945 -0.305054)
			(end -0.12065 -0.305054)
			(stroke
				(width 0.1)
				(type default)
			)
			(layer "F.Fab")
		)
		(fp_line
			(start 0.67945 -0.3048)
			(end 0.67945 0.3048)
			(stroke
				(width 0.1)
				(type default)
			)
			(layer "F.Fab")
		)
		(fp_line
			(start 0.12065 -0.3048)
			(end 0.67945 -0.3048)
			(stroke
				(width 0.1)
				(type default)
			)
			(layer "F.Fab")
		)
		(fp_line
			(start 0.12065 -0.2794)
			(end 0.12065 -0.3048)
			(stroke
				(width 0.1)
				(type default)
			)
			(layer "F.Fab")
		)
		(fp_line
			(start -0.12065 -0.2794)
			(end 0.12065 -0.2794)
			(stroke
				(width 0.1)
				(type default)
			)
			(layer "F.Fab")
		)
		(fp_line
			(start 0.120396 0.2794)
			(end -0.12065 0.2794)
			(stroke
				(width 0.1)
				(type default)
			)
			(layer "F.Fab")
		)
		(fp_line
			(start -0.12065 0.2794)
			(end -0.12065 0.3048)
			(stroke
				(width 0.1)
				(type default)
			)
			(layer "F.Fab")
		)
		(fp_line
			(start 0.67945 0.3048)
			(end 0.120396 0.3048)
			(stroke
				(width 0.1)
				(type default)
			)
			(layer "F.Fab")
		)
		(fp_line
			(start 0.120396 0.3048)
			(end 0.120396 0.2794)
			(stroke
				(width 0.1)
				(type default)
			)
			(layer "F.Fab")
		)
		(fp_line
			(start -0.12065 0.3048)
			(end -0.67945 0.3048)
			(stroke
				(width 0.1)
				(type default)
			)
			(layer "F.Fab")
		)
		(fp_line
			(start -0.67945 0.3048)
			(end -0.67945 -0.305054)
			(stroke
				(width 0.1)
				(type default)
			)
			(layer "F.Fab")
		)
		(pad "1" smd circle
			(at -0.40005 0 90)
			(size 0 0)
			(layers "F.Cu" "F.Mask" "F.Paste")
			(net "PVCCFA_EHV_FIVRA_CPU1_VDD4")
		)
		(pad "2" smd circle
			(at 0.40005 0 90)
			(size 0 0)
			(layers "F.Cu" "F.Mask" "F.Paste")
			(net "GND")
		)
	)
	(footprint ""
		(layer "F.Cu")
		(at 117.526816 -251.375672 90)
		(property "Reference" "C297"
			(at 0 0 90)
			(layer "F.SilkS")
			(hide yes)
			(effects
				(font
					(size 1.27 1.27)
				)
			)
		)
		(property "Value" ""
			(at 0 0 90)
			(layer "F.Fab")
			(effects
				(font
					(size 1.27 1.27)
				)
			)
		)
		(duplicate_pad_numbers_are_jumpers no)
		(fp_line
			(start 0.7874 -0.4064)
			(end 0.7874 0.4064)
			(stroke
				(width 0.1524)
				(type default)
			)
			(layer "F.SilkS")
		)
		(fp_line
			(start -0.7874 -0.4064)
			(end 0.7874 -0.4064)
			(stroke
				(width 0.1524)
				(type default)
			)
			(layer "F.SilkS")
		)
		(fp_line
			(start 0.7874 0.4064)
			(end -0.7874 0.4064)
			(stroke
				(width 0.1524)
				(type default)
			)
			(layer "F.SilkS")
		)
		(fp_line
			(start -0.7874 0.4064)
			(end -0.7874 -0.4064)
			(stroke
				(width 0.1524)
				(type default)
			)
			(layer "F.SilkS")
		)
		(fp_line
			(start -0.12065 -0.305054)
			(end -0.12065 -0.2794)
			(stroke
				(width 0.1)
				(type default)
			)
			(layer "F.Fab")
		)
		(fp_line
			(start -0.67945 -0.305054)
			(end -0.12065 -0.305054)
			(stroke
				(width 0.1)
				(type default)
			)
			(layer "F.Fab")
		)
		(fp_line
			(start 0.67945 -0.3048)
			(end 0.67945 0.3048)
			(stroke
				(width 0.1)
				(type default)
			)
			(layer "F.Fab")
		)
		(fp_line
			(start 0.12065 -0.3048)
			(end 0.67945 -0.3048)
			(stroke
				(width 0.1)
				(type default)
			)
			(layer "F.Fab")
		)
		(fp_line
			(start 0.12065 -0.2794)
			(end 0.12065 -0.3048)
			(stroke
				(width 0.1)
				(type default)
			)
			(layer "F.Fab")
		)
		(fp_line
			(start -0.12065 -0.2794)
			(end 0.12065 -0.2794)
			(stroke
				(width 0.1)
				(type default)
			)
			(layer "F.Fab")
		)
		(fp_line
			(start 0.120396 0.2794)
			(end -0.12065 0.2794)
			(stroke
				(width 0.1)
				(type default)
			)
			(layer "F.Fab")
		)
		(fp_line
			(start -0.12065 0.2794)
			(end -0.12065 0.3048)
			(stroke
				(width 0.1)
				(type default)
			)
			(layer "F.Fab")
		)
		(fp_line
			(start 0.67945 0.3048)
			(end 0.120396 0.3048)
			(stroke
				(width 0.1)
				(type default)
			)
			(layer "F.Fab")
		)
		(fp_line
			(start 0.120396 0.3048)
			(end 0.120396 0.2794)
			(stroke
				(width 0.1)
				(type default)
			)
			(layer "F.Fab")
		)
		(fp_line
			(start -0.12065 0.3048)
			(end -0.67945 0.3048)
			(stroke
				(width 0.1)
				(type default)
			)
			(layer "F.Fab")
		)
		(fp_line
			(start -0.67945 0.3048)
			(end -0.67945 -0.305054)
			(stroke
				(width 0.1)
				(type default)
			)
			(layer "F.Fab")
		)
		(pad "1" smd circle
			(at -0.40005 0 90)
			(size 0 0)
			(layers "F.Cu" "F.Mask" "F.Paste")
			(net "PVCCIN_CPU1")
		)
		(pad "2" smd circle
			(at 0.40005 0 90)
			(size 0 0)
			(layers "F.Cu" "F.Mask" "F.Paste")
			(net "GND")
		)
	)
	(footprint ""
		(layer "F.Cu")
		(at 378.303536 -105.483152 -90)
		(property "Reference" "R1367"
			(at 0 0 270)
			(layer "F.SilkS")
			(hide yes)
			(effects
				(font
					(size 1.27 1.27)
				)
			)
		)
		(property "Value" ""
			(at 0 0 270)
			(layer "F.Fab")
			(effects
				(font
					(size 1.27 1.27)
				)
			)
		)
		(duplicate_pad_numbers_are_jumpers no)
		(fp_line
			(start -0.7874 0.4064)
			(end -0.7874 -0.4064)
			(stroke
				(width 0.1524)
				(type default)
			)
			(layer "F.SilkS")
		)
		(fp_line
			(start 0.7874 0.4064)
			(end -0.7874 0.4064)
			(stroke
				(width 0.1524)
				(type default)
			)
			(layer "F.SilkS")
		)
		(fp_line
			(start -0.7874 -0.4064)
			(end 0.7874 -0.4064)
			(stroke
				(width 0.1524)
				(type default)
			)
			(layer "F.SilkS")
		)
		(fp_line
			(start 0.7874 -0.4064)
			(end 0.7874 0.4064)
			(stroke
				(width 0.1524)
				(type default)
			)
			(layer "F.SilkS")
		)
		(fp_line
			(start -0.67945 0.3048)
			(end -0.67945 -0.305054)
			(stroke
				(width 0.1)
				(type default)
			)
			(layer "F.Fab")
		)
		(fp_line
			(start -0.12065 0.3048)
			(end -0.67945 0.3048)
			(stroke
				(width 0.1)
				(type default)
			)
			(layer "F.Fab")
		)
		(fp_line
			(start 0.120396 0.3048)
			(end 0.120396 0.2794)
			(stroke
				(width 0.1)
				(type default)
			)
			(layer "F.Fab")
		)
		(fp_line
			(start 0.67945 0.3048)
			(end 0.120396 0.3048)
			(stroke
				(width 0.1)
				(type default)
			)
			(layer "F.Fab")
		)
		(fp_line
			(start -0.12065 0.2794)
			(end -0.12065 0.3048)
			(stroke
				(width 0.1)
				(type default)
			)
			(layer "F.Fab")
		)
		(fp_line
			(start 0.120396 0.2794)
			(end -0.12065 0.2794)
			(stroke
				(width 0.1)
				(type default)
			)
			(layer "F.Fab")
		)
		(fp_line
			(start -0.12065 -0.2794)
			(end 0.12065 -0.2794)
			(stroke
				(width 0.1)
				(type default)
			)
			(layer "F.Fab")
		)
		(fp_line
			(start 0.12065 -0.2794)
			(end 0.12065 -0.3048)
			(stroke
				(width 0.1)
				(type default)
			)
			(layer "F.Fab")
		)
		(fp_line
			(start 0.12065 -0.3048)
			(end 0.67945 -0.3048)
			(stroke
				(width 0.1)
				(type default)
			)
			(layer "F.Fab")
		)
		(fp_line
			(start 0.67945 -0.3048)
			(end 0.67945 0.3048)
			(stroke
				(width 0.1)
				(type default)
			)
			(layer "F.Fab")
		)
		(fp_line
			(start -0.67945 -0.305054)
			(end -0.12065 -0.305054)
			(stroke
				(width 0.1)
				(type default)
			)
			(layer "F.Fab")
		)
		(fp_line
			(start -0.12065 -0.305054)
			(end -0.12065 -0.2794)
			(stroke
				(width 0.1)
				(type default)
			)
			(layer "F.Fab")
		)
		(pad "1" smd circle
			(at -0.40005 0 270)
			(size 0 0)
			(layers "F.Cu" "F.Mask" "F.Paste")
			(net "JTAG_DBP_PRDY_N")
		)
		(pad "2" smd circle
			(at 0.40005 0 270)
			(size 0 0)
			(layers "F.Cu" "F.Mask" "F.Paste")
			(net "JTAG_DBP_PRDY_R_N")
		)
	)
	(footprint ""
		(layer "F.Cu")
		(at 527.948906 -153.205688 -90)
		(property "Reference" "X7"
			(at -1.2954 2.72923 90)
			(unlocked yes)
			(layer "F.SilkS")
			(effects
				(font
					(size 0.7874 0.5842)
					(thickness 0.1524)
				)
				(justify left)
			)
		)
		(property "Value" ""
			(at 0 0 270)
			(layer "F.Fab")
			(effects
				(font
					(size 1.27 1.27)
				)
			)
		)
		(property "Device Type" "TP_TDR_4P_FTS_MPKT4_H025P0200_I"
			(at 1.30175 1.27 0)
			(unlocked yes)
			(layer "F.Fab")
			(hide yes)
			(effects
				(font
					(size 0.635 0.4064)
					(thickness 0.1524)
				)
			)
		)
		(property "User Part Number" "TP15"
			(at 1.30175 1.27 0)
			(unlocked yes)
			(layer "Cmts.User")
			(hide yes)
			(effects
				(font
					(size 0.635 0.4064)
					(thickness 0.1524)
				)
			)
		)
		(duplicate_pad_numbers_are_jumpers no)
		(fp_line
			(start 0 3.81)
			(end 2.54 3.81)
			(stroke
				(width 0.1524)
				(type default)
			)
			(layer "F.SilkS")
		)
		(fp_line
			(start 2.54 3.81)
			(end 2.54 3.6703)
			(stroke
				(width 0.1524)
				(type default)
			)
			(layer "F.SilkS")
		)
		(fp_line
			(start 0 3.175)
			(end 0 3.81)
			(stroke
				(width 0.1524)
				(type default)
			)
			(layer "F.SilkS")
		)
		(fp_line
			(start 2.54 1.4097)
			(end 2.54 1.1303)
			(stroke
				(width 0.1524)
				(type default)
			)
			(layer "F.SilkS")
		)
		(fp_line
			(start 0 0.635)
			(end 0 1.905)
			(stroke
				(width 0.1524)
				(type default)
			)
			(layer "F.SilkS")
		)
		(fp_line
			(start 2.54 -1.1303)
			(end 2.54 -1.27)
			(stroke
				(width 0.1524)
				(type default)
			)
			(layer "F.SilkS")
		)
		(fp_line
			(start 0 -1.27)
			(end 0 -0.635)
			(stroke
				(width 0.1524)
				(type default)
			)
			(layer "F.SilkS")
		)
		(fp_line
			(start 2.54 -1.27)
			(end 0 -1.27)
			(stroke
				(width 0.1524)
				(type default)
			)
			(layer "F.SilkS")
		)
		(fp_poly
			(pts
				(xy -1.287526 0.08382) (xy -2.811526 0.84582) (xy -2.811526 -0.67818)
			)
			(stroke
				(width 0)
				(type default)
			)
			(fill yes)
			(layer "F.SilkS")
		)
		(fp_line
			(start 0 3.81)
			(end 2.54 3.81)
			(stroke
				(width 0.1)
				(type default)
			)
			(layer "F.Fab")
		)
		(fp_line
			(start 2.54 3.81)
			(end 2.54 -1.27)
			(stroke
				(width 0.1)
				(type default)
			)
			(layer "F.Fab")
		)
		(fp_line
			(start 0 -1.27)
			(end 0 3.81)
			(stroke
				(width 0.1)
				(type default)
			)
			(layer "F.Fab")
		)
		(fp_line
			(start 2.54 -1.27)
			(end 0 -1.27)
			(stroke
				(width 0.1)
				(type default)
			)
			(layer "F.Fab")
		)
		(fp_poly
			(pts
				(xy -0.761746 0) (xy -2.285746 -0.762) (xy -2.285746 0.762)
			)
			(stroke
				(width 0)
				(type default)
			)
			(fill yes)
			(layer "F.Fab")
		)
		(pad "1" thru_hole circle
			(at 0 0 270)
			(size 1.0033 1.0033)
			(drill 0.249936)
			(layers "*.Cu" "*.Mask")
			(remove_unused_layers no)
			(net "TDR_DIFF_85_TOP_DN")
			(clearance 0.10795)
			(thermal_gap 0.10795)
			(padstack
				(mode front_inner_back)
				(layer "Inner"
					(shape circle)
					(size 0.8001 0.8001)
					(clearance 0.1524)
				)
				(layer "B.Cu"
					(shape circle)
					(size 1.0033 1.0033)
					(clearance 0.10795)
				)
			)
		)
		(pad "2" thru_hole circle
			(at 2.54 0 270)
			(size 1.9939 1.9939)
			(drill 0.249936)
			(layers "*.Cu" "*.Mask")
			(remove_unused_layers no)
			(net "T1_GND")
			(clearance 0.10795)
			(thermal_gap 0.10795)
			(padstack
				(mode front_inner_back)
				(layer "Inner"
					(shape circle)
					(size 0.8001 0.8001)
					(clearance 0.1524)
				)
				(layer "B.Cu"
					(shape circle)
					(size 1.9939 1.9939)
					(clearance 0.10795)
				)
			)
		)
		(pad "3" thru_hole circle
			(at 2.54 2.54 270)
			(size 1.9939 1.9939)
			(drill 0.249936)
			(layers "*.Cu" "*.Mask")
			(remove_unused_layers no)
			(net "T1_GND")
			(clearance 0.10795)
			(thermal_gap 0.10795)
			(padstack
				(mode front_inner_back)
				(layer "Inner"
					(shape circle)
					(size 0.8001 0.8001)
					(clearance 0.1524)
				)
				(layer "B.Cu"
					(shape circle)
					(size 1.9939 1.9939)
					(clearance 0.10795)
				)
			)
		)
		(pad "4" thru_hole circle
			(at 0 2.54 270)
			(size 1.0033 1.0033)
			(drill 0.249936)
			(layers "*.Cu" "*.Mask")
			(remove_unused_layers no)
			(net "TDR_DIFF_85_TOP_DP")
			(clearance 0.10795)
			(thermal_gap 0.10795)
			(padstack
				(mode front_inner_back)
				(layer "Inner"
					(shape circle)
					(size 0.8001 0.8001)
					(clearance 0.1524)
				)
				(layer "B.Cu"
					(shape circle)
					(size 1.0033 1.0033)
					(clearance 0.10795)
				)
			)
		)
	)
	(footprint ""
		(layer "F.Cu")
		(at 15.436596 -386.103876)
		(property "Reference" "R3266"
			(at 0 0 0)
			(layer "F.SilkS")
			(hide yes)
			(effects
				(font
					(size 1.27 1.27)
				)
			)
		)
		(property "Value" ""
			(at 0 0 0)
			(layer "F.Fab")
			(effects
				(font
					(size 1.27 1.27)
				)
			)
		)
		(duplicate_pad_numbers_are_jumpers no)
		(fp_line
			(start -0.7874 -0.4064)
			(end 0.7874 -0.4064)
			(stroke
				(width 0.1524)
				(type default)
			)
			(layer "F.SilkS")
		)
		(fp_line
			(start -0.7874 0.4064)
			(end -0.7874 -0.4064)
			(stroke
				(width 0.1524)
				(type default)
			)
			(layer "F.SilkS")
		)
		(fp_line
			(start 0.7874 -0.4064)
			(end 0.7874 0.4064)
			(stroke
				(width 0.1524)
				(type default)
			)
			(layer "F.SilkS")
		)
		(fp_line
			(start 0.7874 0.4064)
			(end -0.7874 0.4064)
			(stroke
				(width 0.1524)
				(type default)
			)
			(layer "F.SilkS")
		)
		(fp_line
			(start -0.67945 -0.305054)
			(end -0.12065 -0.305054)
			(stroke
				(width 0.1)
				(type default)
			)
			(layer "F.Fab")
		)
		(fp_line
			(start -0.67945 0.3048)
			(end -0.67945 -0.305054)
			(stroke
				(width 0.1)
				(type default)
			)
			(layer "F.Fab")
		)
		(fp_line
			(start -0.12065 -0.305054)
			(end -0.12065 -0.2794)
			(stroke
				(width 0.1)
				(type default)
			)
			(layer "F.Fab")
		)
		(fp_line
			(start -0.12065 -0.2794)
			(end 0.12065 -0.2794)
			(stroke
				(width 0.1)
				(type default)
			)
			(layer "F.Fab")
		)
		(fp_line
			(start -0.12065 0.2794)
			(end -0.12065 0.3048)
			(stroke
				(width 0.1)
				(type default)
			)
			(layer "F.Fab")
		)
		(fp_line
			(start -0.12065 0.3048)
			(end -0.67945 0.3048)
			(stroke
				(width 0.1)
				(type default)
			)
			(layer "F.Fab")
		)
		(fp_line
			(start 0.120396 0.2794)
			(end -0.12065 0.2794)
			(stroke
				(width 0.1)
				(type default)
			)
			(layer "F.Fab")
		)
		(fp_line
			(start 0.120396 0.3048)
			(end 0.120396 0.2794)
			(stroke
				(width 0.1)
				(type default)
			)
			(layer "F.Fab")
		)
		(fp_line
			(start 0.12065 -0.3048)
			(end 0.67945 -0.3048)
			(stroke
				(width 0.1)
				(type default)
			)
			(layer "F.Fab")
		)
		(fp_line
			(start 0.12065 -0.2794)
			(end 0.12065 -0.3048)
			(stroke
				(width 0.1)
				(type default)
			)
			(layer "F.Fab")
		)
		(fp_line
			(start 0.67945 -0.3048)
			(end 0.67945 0.3048)
			(stroke
				(width 0.1)
				(type default)
			)
			(layer "F.Fab")
		)
		(fp_line
			(start 0.67945 0.3048)
			(end 0.120396 0.3048)
			(stroke
				(width 0.1)
				(type default)
			)
			(layer "F.Fab")
		)
		(pad "1" smd circle
			(at -0.40005 0)
			(size 0 0)
			(layers "F.Cu" "F.Mask" "F.Paste")
			(net "P3V3_AUX")
		)
		(pad "2" smd circle
			(at 0.40005 0)
			(size 0 0)
			(layers "F.Cu" "F.Mask" "F.Paste")
			(net "FM_P2E_MODE")
		)
	)
	(footprint ""
		(layer "F.Cu")
		(at 102.827074 -354.847652)
		(property "Reference" "R2550"
			(at 0 0 0)
			(layer "F.SilkS")
			(hide yes)
			(effects
				(font
					(size 1.27 1.27)
				)
			)
		)
		(property "Value" ""
			(at 0 0 0)
			(layer "F.Fab")
			(effects
				(font
					(size 1.27 1.27)
				)
			)
		)
		(duplicate_pad_numbers_are_jumpers no)
		(fp_line
			(start -0.7874 -0.4064)
			(end 0.7874 -0.4064)
			(stroke
				(width 0.1524)
				(type default)
			)
			(layer "F.SilkS")
		)
		(fp_line
			(start -0.7874 0.4064)
			(end -0.7874 -0.4064)
			(stroke
				(width 0.1524)
				(type default)
			)
			(layer "F.SilkS")
		)
		(fp_line
			(start 0.7874 -0.4064)
			(end 0.7874 0.4064)
			(stroke
				(width 0.1524)
				(type default)
			)
			(layer "F.SilkS")
		)
		(fp_line
			(start 0.7874 0.4064)
			(end -0.7874 0.4064)
			(stroke
				(width 0.1524)
				(type default)
			)
			(layer "F.SilkS")
		)
		(fp_line
			(start -0.67945 -0.305054)
			(end -0.12065 -0.305054)
			(stroke
				(width 0.1)
				(type default)
			)
			(layer "F.Fab")
		)
		(fp_line
			(start -0.67945 0.3048)
			(end -0.67945 -0.305054)
			(stroke
				(width 0.1)
				(type default)
			)
			(layer "F.Fab")
		)
		(fp_line
			(start -0.12065 -0.305054)
			(end -0.12065 -0.2794)
			(stroke
				(width 0.1)
				(type default)
			)
			(layer "F.Fab")
		)
		(fp_line
			(start -0.12065 -0.2794)
			(end 0.12065 -0.2794)
			(stroke
				(width 0.1)
				(type default)
			)
			(layer "F.Fab")
		)
		(fp_line
			(start -0.12065 0.2794)
			(end -0.12065 0.3048)
			(stroke
				(width 0.1)
				(type default)
			)
			(layer "F.Fab")
		)
		(fp_line
			(start -0.12065 0.3048)
			(end -0.67945 0.3048)
			(stroke
				(width 0.1)
				(type default)
			)
			(layer "F.Fab")
		)
		(fp_line
			(start 0.120396 0.2794)
			(end -0.12065 0.2794)
			(stroke
				(width 0.1)
				(type default)
			)
			(layer "F.Fab")
		)
		(fp_line
			(start 0.120396 0.3048)
			(end 0.120396 0.2794)
			(stroke
				(width 0.1)
				(type default)
			)
			(layer "F.Fab")
		)
		(fp_line
			(start 0.12065 -0.3048)
			(end 0.67945 -0.3048)
			(stroke
				(width 0.1)
				(type default)
			)
			(layer "F.Fab")
		)
		(fp_line
			(start 0.12065 -0.2794)
			(end 0.12065 -0.3048)
			(stroke
				(width 0.1)
				(type default)
			)
			(layer "F.Fab")
		)
		(fp_line
			(start 0.67945 -0.3048)
			(end 0.67945 0.3048)
			(stroke
				(width 0.1)
				(type default)
			)
			(layer "F.Fab")
		)
		(fp_line
			(start 0.67945 0.3048)
			(end 0.120396 0.3048)
			(stroke
				(width 0.1)
				(type default)
			)
			(layer "F.Fab")
		)
		(pad "1" smd circle
			(at -0.40005 0)
			(size 0 0)
			(layers "F.Cu" "F.Mask" "F.Paste")
			(net "FM_PVCCFA_EHV_FIVRA_CPU1_EN")
		)
		(pad "2" smd circle
			(at 0.40005 0)
			(size 0 0)
			(layers "F.Cu" "F.Mask" "F.Paste")
			(net "PVCCFA_EHV_FIVRA_CPU1_EN_R")
		)
	)
	(footprint ""
		(layer "F.Cu")
		(at 279.6032 -65.877948)
		(property "Reference" "PC1227"
			(at 0 0 0)
			(layer "F.SilkS")
			(hide yes)
			(effects
				(font
					(size 1.27 1.27)
				)
			)
		)
		(property "Value" ""
			(at 0 0 0)
			(layer "F.Fab")
			(effects
				(font
					(size 1.27 1.27)
				)
			)
		)
		(duplicate_pad_numbers_are_jumpers no)
		(fp_line
			(start 2.750058 0.999998)
			(end -2.750058 0.999998)
			(stroke
				(width 0.1524)
				(type default)
			)
			(layer "F.SilkS")
		)
		(fp_circle
			(center 0 0.999998)
			(end 2.750058 0.999998)
			(stroke
				(width 0.1524)
				(type default)
			)
			(fill no)
			(layer "F.SilkS")
		)
		(fp_poly
			(pts
				(arc
					(start 2.750058 0.999998)
					(mid 0 3.750056)
					(end -2.750058 0.999998)
				)
			)
			(stroke
				(width 0)
				(type default)
			)
			(fill yes)
			(layer "F.SilkS")
		)
		(fp_circle
			(center 0 0.999998)
			(end 2.750058 0.999998)
			(stroke
				(width 0.1)
				(type default)
			)
			(fill no)
			(layer "F.Fab")
		)
		(pad "1" thru_hole rect
			(at 0 0)
			(size 1.5748 1.5748)
			(drill 1.0668)
			(layers "*.Cu" "*.Mask")
			(remove_unused_layers no)
			(net "P1V05_PCH_AUX")
			(clearance 0)
			(padstack
				(mode front_inner_back)
				(layer "Inner"
					(shape circle)
					(size 1.5748 1.5748)
					(clearance 0)
				)
				(layer "B.Cu"
					(shape rect)
					(size 1.5748 1.5748)
					(clearance 0)
				)
			)
		)
		(pad "2" thru_hole circle
			(at 0 1.999996)
			(size 1.5748 1.5748)
			(drill 1.0668)
			(layers "*.Cu" "*.Mask")
			(remove_unused_layers no)
			(net "GND")
			(clearance 0)
		)
	)
	(footprint ""
		(layer "F.Cu")
		(at 216.065608 -406.855422)
		(property "Reference" "PR3922"
			(at 0 0 0)
			(layer "F.SilkS")
			(hide yes)
			(effects
				(font
					(size 1.27 1.27)
				)
			)
		)
		(property "Value" ""
			(at 0 0 0)
			(layer "F.Fab")
			(effects
				(font
					(size 1.27 1.27)
				)
			)
		)
		(duplicate_pad_numbers_are_jumpers no)
		(fp_line
			(start -0.7874 -0.4064)
			(end 0.7874 -0.4064)
			(stroke
				(width 0.1524)
				(type default)
			)
			(layer "F.SilkS")
		)
		(fp_line
			(start -0.7874 0.4064)
			(end -0.7874 -0.4064)
			(stroke
				(width 0.1524)
				(type default)
			)
			(layer "F.SilkS")
		)
		(fp_line
			(start 0.7874 -0.4064)
			(end 0.7874 0.4064)
			(stroke
				(width 0.1524)
				(type default)
			)
			(layer "F.SilkS")
		)
		(fp_line
			(start 0.7874 0.4064)
			(end -0.7874 0.4064)
			(stroke
				(width 0.1524)
				(type default)
			)
			(layer "F.SilkS")
		)
		(fp_line
			(start -0.67945 -0.305054)
			(end -0.12065 -0.305054)
			(stroke
				(width 0.1)
				(type default)
			)
			(layer "F.Fab")
		)
		(fp_line
			(start -0.67945 0.3048)
			(end -0.67945 -0.305054)
			(stroke
				(width 0.1)
				(type default)
			)
			(layer "F.Fab")
		)
		(fp_line
			(start -0.12065 -0.305054)
			(end -0.12065 -0.2794)
			(stroke
				(width 0.1)
				(type default)
			)
			(layer "F.Fab")
		)
		(fp_line
			(start -0.12065 -0.2794)
			(end 0.12065 -0.2794)
			(stroke
				(width 0.1)
				(type default)
			)
			(layer "F.Fab")
		)
		(fp_line
			(start -0.12065 0.2794)
			(end -0.12065 0.3048)
			(stroke
				(width 0.1)
				(type default)
			)
			(layer "F.Fab")
		)
		(fp_line
			(start -0.12065 0.3048)
			(end -0.67945 0.3048)
			(stroke
				(width 0.1)
				(type default)
			)
			(layer "F.Fab")
		)
		(fp_line
			(start 0.120396 0.2794)
			(end -0.12065 0.2794)
			(stroke
				(width 0.1)
				(type default)
			)
			(layer "F.Fab")
		)
		(fp_line
			(start 0.120396 0.3048)
			(end 0.120396 0.2794)
			(stroke
				(width 0.1)
				(type default)
			)
			(layer "F.Fab")
		)
		(fp_line
			(start 0.12065 -0.3048)
			(end 0.67945 -0.3048)
			(stroke
				(width 0.1)
				(type default)
			)
			(layer "F.Fab")
		)
		(fp_line
			(start 0.12065 -0.2794)
			(end 0.12065 -0.3048)
			(stroke
				(width 0.1)
				(type default)
			)
			(layer "F.Fab")
		)
		(fp_line
			(start 0.67945 -0.3048)
			(end 0.67945 0.3048)
			(stroke
				(width 0.1)
				(type default)
			)
			(layer "F.Fab")
		)
		(fp_line
			(start 0.67945 0.3048)
			(end 0.120396 0.3048)
			(stroke
				(width 0.1)
				(type default)
			)
			(layer "F.Fab")
		)
		(pad "1" smd circle
			(at -0.40005 0)
			(size 0 0)
			(layers "F.Cu" "F.Mask" "F.Paste")
			(net "HSC_FLT_TYPE_2")
		)
		(pad "2" smd circle
			(at 0.40005 0)
			(size 0 0)
			(layers "F.Cu" "F.Mask" "F.Paste")
			(net "HSC_FLT_TYPE")
		)
	)
	(footprint ""
		(layer "F.Cu")
		(at 434.06568 -178.069748 180)
		(property "Reference" "PC27"
			(at 0 0 180)
			(layer "F.SilkS")
			(hide yes)
			(effects
				(font
					(size 1.27 1.27)
				)
			)
		)
		(property "Value" ""
			(at 0 0 180)
			(layer "F.Fab")
			(effects
				(font
					(size 1.27 1.27)
				)
			)
		)
		(duplicate_pad_numbers_are_jumpers no)
		(fp_line
			(start 0.7874 0.4064)
			(end -0.7874 0.4064)
			(stroke
				(width 0.1524)
				(type default)
			)
			(layer "F.SilkS")
		)
		(fp_line
			(start 0.7874 -0.4064)
			(end 0.7874 0.4064)
			(stroke
				(width 0.1524)
				(type default)
			)
			(layer "F.SilkS")
		)
		(fp_line
			(start -0.7874 0.4064)
			(end -0.7874 -0.4064)
			(stroke
				(width 0.1524)
				(type default)
			)
			(layer "F.SilkS")
		)
		(fp_line
			(start -0.7874 -0.4064)
			(end 0.7874 -0.4064)
			(stroke
				(width 0.1524)
				(type default)
			)
			(layer "F.SilkS")
		)
		(fp_line
			(start 0.67945 0.3048)
			(end 0.120396 0.3048)
			(stroke
				(width 0.1)
				(type default)
			)
			(layer "F.Fab")
		)
		(fp_line
			(start 0.67945 -0.3048)
			(end 0.67945 0.3048)
			(stroke
				(width 0.1)
				(type default)
			)
			(layer "F.Fab")
		)
		(fp_line
			(start 0.12065 -0.2794)
			(end 0.12065 -0.3048)
			(stroke
				(width 0.1)
				(type default)
			)
			(layer "F.Fab")
		)
		(fp_line
			(start 0.12065 -0.3048)
			(end 0.67945 -0.3048)
			(stroke
				(width 0.1)
				(type default)
			)
			(layer "F.Fab")
		)
		(fp_line
			(start 0.120396 0.3048)
			(end 0.120396 0.2794)
			(stroke
				(width 0.1)
				(type default)
			)
			(layer "F.Fab")
		)
		(fp_line
			(start 0.120396 0.2794)
			(end -0.12065 0.2794)
			(stroke
				(width 0.1)
				(type default)
			)
			(layer "F.Fab")
		)
		(fp_line
			(start -0.12065 0.3048)
			(end -0.67945 0.3048)
			(stroke
				(width 0.1)
				(type default)
			)
			(layer "F.Fab")
		)
		(fp_line
			(start -0.12065 0.2794)
			(end -0.12065 0.3048)
			(stroke
				(width 0.1)
				(type default)
			)
			(layer "F.Fab")
		)
		(fp_line
			(start -0.12065 -0.2794)
			(end 0.12065 -0.2794)
			(stroke
				(width 0.1)
				(type default)
			)
			(layer "F.Fab")
		)
		(fp_line
			(start -0.12065 -0.305054)
			(end -0.12065 -0.2794)
			(stroke
				(width 0.1)
				(type default)
			)
			(layer "F.Fab")
		)
		(fp_line
			(start -0.67945 0.3048)
			(end -0.67945 -0.305054)
			(stroke
				(width 0.1)
				(type default)
			)
			(layer "F.Fab")
		)
		(fp_line
			(start -0.67945 -0.305054)
			(end -0.12065 -0.305054)
			(stroke
				(width 0.1)
				(type default)
			)
			(layer "F.Fab")
		)
		(pad "1" smd circle
			(at -0.40005 0 180)
			(size 0 0)
			(layers "F.Cu" "F.Mask" "F.Paste")
			(net "PVNN_MAIN_CPU0_REF")
		)
		(pad "2" smd circle
			(at 0.40005 0 180)
			(size 0 0)
			(layers "F.Cu" "F.Mask" "F.Paste")
			(net "GND")
		)
	)
	(footprint ""
		(layer "F.Cu")
		(at 485.20985 -216.092532 -90)
		(property "Reference" "X42"
			(at -0.1778 -1.92913 270)
			(unlocked yes)
			(layer "F.SilkS")
			(effects
				(font
					(size 0.7874 0.5842)
					(thickness 0.1524)
				)
				(justify left)
			)
		)
		(property "Value" ""
			(at 0 0 270)
			(layer "F.Fab")
			(effects
				(font
					(size 1.27 1.27)
				)
			)
		)
		(property "Device Type" "TP_TDR_4P_FTS_TH-TP_TDR_4P_DIPA"
			(at 1.30175 1.27 0)
			(unlocked yes)
			(layer "F.Fab")
			(hide yes)
			(effects
				(font
					(size 0.635 0.4064)
					(thickness 0.1524)
				)
			)
		)
		(property "User Part Number" "N_A"
			(at 1.30175 1.27 0)
			(unlocked yes)
			(layer "Cmts.User")
			(hide yes)
			(effects
				(font
					(size 0.635 0.4064)
					(thickness 0.1524)
				)
			)
		)
		(duplicate_pad_numbers_are_jumpers no)
		(fp_line
			(start 0 3.81)
			(end 2.54 3.81)
			(stroke
				(width 0.1524)
				(type default)
			)
			(layer "F.SilkS")
		)
		(fp_line
			(start 2.54 3.81)
			(end 2.54 3.6703)
			(stroke
				(width 0.1524)
				(type default)
			)
			(layer "F.SilkS")
		)
		(fp_line
			(start 0 3.175)
			(end 0 3.81)
			(stroke
				(width 0.1524)
				(type default)
			)
			(layer "F.SilkS")
		)
		(fp_line
			(start 2.54 1.4097)
			(end 2.54 1.1303)
			(stroke
				(width 0.1524)
				(type default)
			)
			(layer "F.SilkS")
		)
		(fp_line
			(start 0 0.635)
			(end 0 1.905)
			(stroke
				(width 0.1524)
				(type default)
			)
			(layer "F.SilkS")
		)
		(fp_line
			(start 2.54 -1.1303)
			(end 2.54 -1.27)
			(stroke
				(width 0.1524)
				(type default)
			)
			(layer "F.SilkS")
		)
		(fp_line
			(start 0 -1.27)
			(end 0 -0.635)
			(stroke
				(width 0.1524)
				(type default)
			)
			(layer "F.SilkS")
		)
		(fp_line
			(start 2.54 -1.27)
			(end 0 -1.27)
			(stroke
				(width 0.1524)
				(type default)
			)
			(layer "F.SilkS")
		)
		(fp_poly
			(pts
				(xy -0.761746 0) (xy -2.285746 -0.762) (xy -2.285746 0.762)
			)
			(stroke
				(width 0)
				(type default)
			)
			(fill yes)
			(layer "F.SilkS")
		)
		(fp_line
			(start 0 3.81)
			(end 2.54 3.81)
			(stroke
				(width 0.1)
				(type default)
			)
			(layer "F.Fab")
		)
		(fp_line
			(start 2.54 3.81)
			(end 2.54 -1.27)
			(stroke
				(width 0.1)
				(type default)
			)
			(layer "F.Fab")
		)
		(fp_line
			(start 0 -1.27)
			(end 0 3.81)
			(stroke
				(width 0.1)
				(type default)
			)
			(layer "F.Fab")
		)
		(fp_line
			(start 2.54 -1.27)
			(end 0 -1.27)
			(stroke
				(width 0.1)
				(type default)
			)
			(layer "F.Fab")
		)
		(fp_poly
			(pts
				(xy -0.761746 0) (xy -2.285746 -0.762) (xy -2.285746 0.762)
			)
			(stroke
				(width 0)
				(type default)
			)
			(fill yes)
			(layer "F.Fab")
		)
		(pad "1" thru_hole circle
			(at 0 0 270)
			(size 1.0033 1.0033)
			(drill 0.249936)
			(layers "*.Cu" "*.Mask")
			(remove_unused_layers no)
			(net "TDR_DIFF_85_NECK_IN1_DN")
			(clearance 0.10795)
			(thermal_gap 0.10795)
			(padstack
				(mode front_inner_back)
				(layer "Inner"
					(shape circle)
					(size 0.8001 0.8001)
					(clearance 0.1524)
				)
				(layer "B.Cu"
					(shape circle)
					(size 1.0033 1.0033)
					(clearance 0.10795)
				)
			)
		)
		(pad "2" thru_hole circle
			(at 2.54 0 270)
			(size 1.9939 1.9939)
			(drill 0.249936)
			(layers "*.Cu" "*.Mask")
			(remove_unused_layers no)
			(net "T1_GND")
			(clearance 0.10795)
			(thermal_gap 0.10795)
			(padstack
				(mode front_inner_back)
				(layer "Inner"
					(shape circle)
					(size 0.8001 0.8001)
					(clearance 0.1524)
				)
				(layer "B.Cu"
					(shape circle)
					(size 1.9939 1.9939)
					(clearance 0.10795)
				)
			)
		)
		(pad "3" thru_hole circle
			(at 2.54 2.54 270)
			(size 1.9939 1.9939)
			(drill 0.249936)
			(layers "*.Cu" "*.Mask")
			(remove_unused_layers no)
			(net "T1_GND")
			(clearance 0.10795)
			(thermal_gap 0.10795)
			(padstack
				(mode front_inner_back)
				(layer "Inner"
					(shape circle)
					(size 0.8001 0.8001)
					(clearance 0.1524)
				)
				(layer "B.Cu"
					(shape circle)
					(size 1.9939 1.9939)
					(clearance 0.10795)
				)
			)
		)
		(pad "4" thru_hole circle
			(at 0 2.54 270)
			(size 1.0033 1.0033)
			(drill 0.249936)
			(layers "*.Cu" "*.Mask")
			(remove_unused_layers no)
			(net "TDR_DIFF_85_NECK_IN1_DP")
			(clearance 0.10795)
			(thermal_gap 0.10795)
			(padstack
				(mode front_inner_back)
				(layer "Inner"
					(shape circle)
					(size 0.8001 0.8001)
					(clearance 0.1524)
				)
				(layer "B.Cu"
					(shape circle)
					(size 1.0033 1.0033)
					(clearance 0.10795)
				)
			)
		)
	)
	(footprint ""
		(layer "F.Cu")
		(at 187.221622 -22.727158 -90)
		(property "Reference" "PR4001"
			(at 0 0 270)
			(layer "F.SilkS")
			(hide yes)
			(effects
				(font
					(size 1.27 1.27)
				)
			)
		)
		(property "Value" ""
			(at 0 0 270)
			(layer "F.Fab")
			(effects
				(font
					(size 1.27 1.27)
				)
			)
		)
		(duplicate_pad_numbers_are_jumpers no)
		(fp_line
			(start -0.7874 0.4064)
			(end -0.7874 -0.4064)
			(stroke
				(width 0.1524)
				(type default)
			)
			(layer "F.SilkS")
		)
		(fp_line
			(start 0.7874 0.4064)
			(end -0.7874 0.4064)
			(stroke
				(width 0.1524)
				(type default)
			)
			(layer "F.SilkS")
		)
		(fp_line
			(start -0.7874 -0.4064)
			(end 0.7874 -0.4064)
			(stroke
				(width 0.1524)
				(type default)
			)
			(layer "F.SilkS")
		)
		(fp_line
			(start 0.7874 -0.4064)
			(end 0.7874 0.4064)
			(stroke
				(width 0.1524)
				(type default)
			)
			(layer "F.SilkS")
		)
		(fp_line
			(start -0.67945 0.3048)
			(end -0.67945 -0.305054)
			(stroke
				(width 0.1)
				(type default)
			)
			(layer "F.Fab")
		)
		(fp_line
			(start -0.12065 0.3048)
			(end -0.67945 0.3048)
			(stroke
				(width 0.1)
				(type default)
			)
			(layer "F.Fab")
		)
		(fp_line
			(start 0.120396 0.3048)
			(end 0.120396 0.2794)
			(stroke
				(width 0.1)
				(type default)
			)
			(layer "F.Fab")
		)
		(fp_line
			(start 0.67945 0.3048)
			(end 0.120396 0.3048)
			(stroke
				(width 0.1)
				(type default)
			)
			(layer "F.Fab")
		)
		(fp_line
			(start -0.12065 0.2794)
			(end -0.12065 0.3048)
			(stroke
				(width 0.1)
				(type default)
			)
			(layer "F.Fab")
		)
		(fp_line
			(start 0.120396 0.2794)
			(end -0.12065 0.2794)
			(stroke
				(width 0.1)
				(type default)
			)
			(layer "F.Fab")
		)
		(fp_line
			(start -0.12065 -0.2794)
			(end 0.12065 -0.2794)
			(stroke
				(width 0.1)
				(type default)
			)
			(layer "F.Fab")
		)
		(fp_line
			(start 0.12065 -0.2794)
			(end 0.12065 -0.3048)
			(stroke
				(width 0.1)
				(type default)
			)
			(layer "F.Fab")
		)
		(fp_line
			(start 0.12065 -0.3048)
			(end 0.67945 -0.3048)
			(stroke
				(width 0.1)
				(type default)
			)
			(layer "F.Fab")
		)
		(fp_line
			(start 0.67945 -0.3048)
			(end 0.67945 0.3048)
			(stroke
				(width 0.1)
				(type default)
			)
			(layer "F.Fab")
		)
		(fp_line
			(start -0.67945 -0.305054)
			(end -0.12065 -0.305054)
			(stroke
				(width 0.1)
				(type default)
			)
			(layer "F.Fab")
		)
		(fp_line
			(start -0.12065 -0.305054)
			(end -0.12065 -0.2794)
			(stroke
				(width 0.1)
				(type default)
			)
			(layer "F.Fab")
		)
		(pad "1" smd circle
			(at -0.40005 0 270)
			(size 0 0)
			(layers "F.Cu" "F.Mask" "F.Paste")
			(net "P12V_SCM_UV")
		)
		(pad "2" smd circle
			(at 0.40005 0 270)
			(size 0 0)
			(layers "F.Cu" "F.Mask" "F.Paste")
			(net "P12V_SCM_OV")
		)
	)
	(footprint ""
		(layer "F.Cu")
		(at 353.266248 -247.715024 90)
		(property "Reference" "C971"
			(at 0 0 90)
			(layer "F.SilkS")
			(hide yes)
			(effects
				(font
					(size 1.27 1.27)
				)
			)
		)
		(property "Value" ""
			(at 0 0 90)
			(layer "F.Fab")
			(effects
				(font
					(size 1.27 1.27)
				)
			)
		)
		(duplicate_pad_numbers_are_jumpers no)
		(fp_line
			(start 0.7874 -0.4064)
			(end 0.7874 0.4064)
			(stroke
				(width 0.1524)
				(type default)
			)
			(layer "F.SilkS")
		)
		(fp_line
			(start -0.7874 -0.4064)
			(end 0.7874 -0.4064)
			(stroke
				(width 0.1524)
				(type default)
			)
			(layer "F.SilkS")
		)
		(fp_line
			(start 0.7874 0.4064)
			(end -0.7874 0.4064)
			(stroke
				(width 0.1524)
				(type default)
			)
			(layer "F.SilkS")
		)
		(fp_line
			(start -0.7874 0.4064)
			(end -0.7874 -0.4064)
			(stroke
				(width 0.1524)
				(type default)
			)
			(layer "F.SilkS")
		)
		(fp_line
			(start -0.12065 -0.305054)
			(end -0.12065 -0.2794)
			(stroke
				(width 0.1)
				(type default)
			)
			(layer "F.Fab")
		)
		(fp_line
			(start -0.67945 -0.305054)
			(end -0.12065 -0.305054)
			(stroke
				(width 0.1)
				(type default)
			)
			(layer "F.Fab")
		)
		(fp_line
			(start 0.67945 -0.3048)
			(end 0.67945 0.3048)
			(stroke
				(width 0.1)
				(type default)
			)
			(layer "F.Fab")
		)
		(fp_line
			(start 0.12065 -0.3048)
			(end 0.67945 -0.3048)
			(stroke
				(width 0.1)
				(type default)
			)
			(layer "F.Fab")
		)
		(fp_line
			(start 0.12065 -0.2794)
			(end 0.12065 -0.3048)
			(stroke
				(width 0.1)
				(type default)
			)
			(layer "F.Fab")
		)
		(fp_line
			(start -0.12065 -0.2794)
			(end 0.12065 -0.2794)
			(stroke
				(width 0.1)
				(type default)
			)
			(layer "F.Fab")
		)
		(fp_line
			(start 0.120396 0.2794)
			(end -0.12065 0.2794)
			(stroke
				(width 0.1)
				(type default)
			)
			(layer "F.Fab")
		)
		(fp_line
			(start -0.12065 0.2794)
			(end -0.12065 0.3048)
			(stroke
				(width 0.1)
				(type default)
			)
			(layer "F.Fab")
		)
		(fp_line
			(start 0.67945 0.3048)
			(end 0.120396 0.3048)
			(stroke
				(width 0.1)
				(type default)
			)
			(layer "F.Fab")
		)
		(fp_line
			(start 0.120396 0.3048)
			(end 0.120396 0.2794)
			(stroke
				(width 0.1)
				(type default)
			)
			(layer "F.Fab")
		)
		(fp_line
			(start -0.12065 0.3048)
			(end -0.67945 0.3048)
			(stroke
				(width 0.1)
				(type default)
			)
			(layer "F.Fab")
		)
		(fp_line
			(start -0.67945 0.3048)
			(end -0.67945 -0.305054)
			(stroke
				(width 0.1)
				(type default)
			)
			(layer "F.Fab")
		)
		(pad "1" smd circle
			(at -0.40005 0 90)
			(size 0 0)
			(layers "F.Cu" "F.Mask" "F.Paste")
			(net "PVCCIN_CPU0")
		)
		(pad "2" smd circle
			(at 0.40005 0 90)
			(size 0 0)
			(layers "F.Cu" "F.Mask" "F.Paste")
			(net "GND")
		)
	)
	(footprint ""
		(layer "F.Cu")
		(at 372.83136 -413.918908 -90)
		(property "Reference" "R3033"
			(at 0 0 270)
			(layer "F.SilkS")
			(hide yes)
			(effects
				(font
					(size 1.27 1.27)
				)
			)
		)
		(property "Value" ""
			(at 0 0 270)
			(layer "F.Fab")
			(effects
				(font
					(size 1.27 1.27)
				)
			)
		)
		(duplicate_pad_numbers_are_jumpers no)
		(fp_line
			(start -0.7874 0.4064)
			(end -0.7874 -0.4064)
			(stroke
				(width 0.1524)
				(type default)
			)
			(layer "F.SilkS")
		)
		(fp_line
			(start 0.7874 0.4064)
			(end -0.7874 0.4064)
			(stroke
				(width 0.1524)
				(type default)
			)
			(layer "F.SilkS")
		)
		(fp_line
			(start -0.7874 -0.4064)
			(end 0.7874 -0.4064)
			(stroke
				(width 0.1524)
				(type default)
			)
			(layer "F.SilkS")
		)
		(fp_line
			(start 0.7874 -0.4064)
			(end 0.7874 0.4064)
			(stroke
				(width 0.1524)
				(type default)
			)
			(layer "F.SilkS")
		)
		(fp_line
			(start -0.67945 0.3048)
			(end -0.67945 -0.305054)
			(stroke
				(width 0.1)
				(type default)
			)
			(layer "F.Fab")
		)
		(fp_line
			(start -0.12065 0.3048)
			(end -0.67945 0.3048)
			(stroke
				(width 0.1)
				(type default)
			)
			(layer "F.Fab")
		)
		(fp_line
			(start 0.120396 0.3048)
			(end 0.120396 0.2794)
			(stroke
				(width 0.1)
				(type default)
			)
			(layer "F.Fab")
		)
		(fp_line
			(start 0.67945 0.3048)
			(end 0.120396 0.3048)
			(stroke
				(width 0.1)
				(type default)
			)
			(layer "F.Fab")
		)
		(fp_line
			(start -0.12065 0.2794)
			(end -0.12065 0.3048)
			(stroke
				(width 0.1)
				(type default)
			)
			(layer "F.Fab")
		)
		(fp_line
			(start 0.120396 0.2794)
			(end -0.12065 0.2794)
			(stroke
				(width 0.1)
				(type default)
			)
			(layer "F.Fab")
		)
		(fp_line
			(start -0.12065 -0.2794)
			(end 0.12065 -0.2794)
			(stroke
				(width 0.1)
				(type default)
			)
			(layer "F.Fab")
		)
		(fp_line
			(start 0.12065 -0.2794)
			(end 0.12065 -0.3048)
			(stroke
				(width 0.1)
				(type default)
			)
			(layer "F.Fab")
		)
		(fp_line
			(start 0.12065 -0.3048)
			(end 0.67945 -0.3048)
			(stroke
				(width 0.1)
				(type default)
			)
			(layer "F.Fab")
		)
		(fp_line
			(start 0.67945 -0.3048)
			(end 0.67945 0.3048)
			(stroke
				(width 0.1)
				(type default)
			)
			(layer "F.Fab")
		)
		(fp_line
			(start -0.67945 -0.305054)
			(end -0.12065 -0.305054)
			(stroke
				(width 0.1)
				(type default)
			)
			(layer "F.Fab")
		)
		(fp_line
			(start -0.12065 -0.305054)
			(end -0.12065 -0.2794)
			(stroke
				(width 0.1)
				(type default)
			)
			(layer "F.Fab")
		)
		(pad "1" smd circle
			(at -0.40005 0 270)
			(size 0 0)
			(layers "F.Cu" "F.Mask" "F.Paste")
			(net "UART_BMC_BIC_RX")
		)
		(pad "2" smd circle
			(at 0.40005 0 270)
			(size 0 0)
			(layers "F.Cu" "F.Mask" "F.Paste")
			(net "UART_BMC_BIC_R_RX")
		)
	)
	(footprint ""
		(layer "F.Cu")
		(at 390.69137 -402.371052 -90)
		(property "Reference" "C946"
			(at 0 0 270)
			(layer "F.SilkS")
			(hide yes)
			(effects
				(font
					(size 1.27 1.27)
				)
			)
		)
		(property "Value" ""
			(at 0 0 270)
			(layer "F.Fab")
			(effects
				(font
					(size 1.27 1.27)
				)
			)
		)
		(duplicate_pad_numbers_are_jumpers no)
		(fp_line
			(start -0.299974 0.150114)
			(end -0.299974 -0.150114)
			(stroke
				(width 0.1)
				(type default)
			)
			(layer "F.Fab")
		)
		(fp_line
			(start 0.299974 0.150114)
			(end -0.299974 0.150114)
			(stroke
				(width 0.1)
				(type default)
			)
			(layer "F.Fab")
		)
		(fp_line
			(start -0.299974 -0.150114)
			(end 0.299974 -0.150114)
			(stroke
				(width 0.1)
				(type default)
			)
			(layer "F.Fab")
		)
		(fp_line
			(start 0.299974 -0.150114)
			(end 0.299974 0.150114)
			(stroke
				(width 0.1)
				(type default)
			)
			(layer "F.Fab")
		)
		(pad "1" smd rect
			(at -0.2667 0 270)
			(size 0.3048 0.381)
			(layers "F.Cu" "F.Mask" "F.Paste")
			(net "P5E_CPU0_PE2_TX_C_DN<9>")
		)
		(pad "2" smd rect
			(at 0.2667 0 270)
			(size 0.3048 0.381)
			(layers "F.Cu" "F.Mask" "F.Paste")
			(net "P5E_CPU0_PE2_TX_DN<9>")
		)
	)
	(footprint ""
		(layer "F.Cu")
		(at 164.64788 -115.026948)
		(property "Reference" "R2346"
			(at 0 0 0)
			(layer "F.SilkS")
			(hide yes)
			(effects
				(font
					(size 1.27 1.27)
				)
			)
		)
		(property "Value" ""
			(at 0 0 0)
			(layer "F.Fab")
			(effects
				(font
					(size 1.27 1.27)
				)
			)
		)
		(duplicate_pad_numbers_are_jumpers no)
		(fp_line
			(start -0.7874 -0.4064)
			(end 0.7874 -0.4064)
			(stroke
				(width 0.1524)
				(type default)
			)
			(layer "F.SilkS")
		)
		(fp_line
			(start -0.7874 0.4064)
			(end -0.7874 -0.4064)
			(stroke
				(width 0.1524)
				(type default)
			)
			(layer "F.SilkS")
		)
		(fp_line
			(start 0.7874 -0.4064)
			(end 0.7874 0.4064)
			(stroke
				(width 0.1524)
				(type default)
			)
			(layer "F.SilkS")
		)
		(fp_line
			(start 0.7874 0.4064)
			(end -0.7874 0.4064)
			(stroke
				(width 0.1524)
				(type default)
			)
			(layer "F.SilkS")
		)
		(fp_line
			(start -0.67945 -0.305054)
			(end -0.12065 -0.305054)
			(stroke
				(width 0.1)
				(type default)
			)
			(layer "F.Fab")
		)
		(fp_line
			(start -0.67945 0.3048)
			(end -0.67945 -0.305054)
			(stroke
				(width 0.1)
				(type default)
			)
			(layer "F.Fab")
		)
		(fp_line
			(start -0.12065 -0.305054)
			(end -0.12065 -0.2794)
			(stroke
				(width 0.1)
				(type default)
			)
			(layer "F.Fab")
		)
		(fp_line
			(start -0.12065 -0.2794)
			(end 0.12065 -0.2794)
			(stroke
				(width 0.1)
				(type default)
			)
			(layer "F.Fab")
		)
		(fp_line
			(start -0.12065 0.2794)
			(end -0.12065 0.3048)
			(stroke
				(width 0.1)
				(type default)
			)
			(layer "F.Fab")
		)
		(fp_line
			(start -0.12065 0.3048)
			(end -0.67945 0.3048)
			(stroke
				(width 0.1)
				(type default)
			)
			(layer "F.Fab")
		)
		(fp_line
			(start 0.120396 0.2794)
			(end -0.12065 0.2794)
			(stroke
				(width 0.1)
				(type default)
			)
			(layer "F.Fab")
		)
		(fp_line
			(start 0.120396 0.3048)
			(end 0.120396 0.2794)
			(stroke
				(width 0.1)
				(type default)
			)
			(layer "F.Fab")
		)
		(fp_line
			(start 0.12065 -0.3048)
			(end 0.67945 -0.3048)
			(stroke
				(width 0.1)
				(type default)
			)
			(layer "F.Fab")
		)
		(fp_line
			(start 0.12065 -0.2794)
			(end 0.12065 -0.3048)
			(stroke
				(width 0.1)
				(type default)
			)
			(layer "F.Fab")
		)
		(fp_line
			(start 0.67945 -0.3048)
			(end 0.67945 0.3048)
			(stroke
				(width 0.1)
				(type default)
			)
			(layer "F.Fab")
		)
		(fp_line
			(start 0.67945 0.3048)
			(end 0.120396 0.3048)
			(stroke
				(width 0.1)
				(type default)
			)
			(layer "F.Fab")
		)
		(pad "1" smd circle
			(at -0.40005 0)
			(size 0 0)
			(layers "F.Cu" "F.Mask" "F.Paste")
			(net "P3V3_AUX")
		)
		(pad "2" smd circle
			(at 0.40005 0)
			(size 0 0)
			(layers "F.Cu" "F.Mask" "F.Paste")
			(net "PWRGD_P5V_AUX_R2")
		)
	)
	(footprint ""
		(layer "F.Cu")
		(at 452.482712 -74.136504)
		(property "Reference" "PC568"
			(at 0 0 0)
			(layer "F.SilkS")
			(hide yes)
			(effects
				(font
					(size 1.27 1.27)
				)
			)
		)
		(property "Value" ""
			(at 0 0 0)
			(layer "F.Fab")
			(effects
				(font
					(size 1.27 1.27)
				)
			)
		)
		(duplicate_pad_numbers_are_jumpers no)
		(fp_line
			(start -0.7874 -0.4064)
			(end 0.7874 -0.4064)
			(stroke
				(width 0.1524)
				(type default)
			)
			(layer "F.SilkS")
		)
		(fp_line
			(start -0.7874 0.4064)
			(end -0.7874 -0.4064)
			(stroke
				(width 0.1524)
				(type default)
			)
			(layer "F.SilkS")
		)
		(fp_line
			(start 0.7874 -0.4064)
			(end 0.7874 0.4064)
			(stroke
				(width 0.1524)
				(type default)
			)
			(layer "F.SilkS")
		)
		(fp_line
			(start 0.7874 0.4064)
			(end -0.7874 0.4064)
			(stroke
				(width 0.1524)
				(type default)
			)
			(layer "F.SilkS")
		)
		(fp_line
			(start -0.67945 -0.305054)
			(end -0.12065 -0.305054)
			(stroke
				(width 0.1)
				(type default)
			)
			(layer "F.Fab")
		)
		(fp_line
			(start -0.67945 0.3048)
			(end -0.67945 -0.305054)
			(stroke
				(width 0.1)
				(type default)
			)
			(layer "F.Fab")
		)
		(fp_line
			(start -0.12065 -0.305054)
			(end -0.12065 -0.2794)
			(stroke
				(width 0.1)
				(type default)
			)
			(layer "F.Fab")
		)
		(fp_line
			(start -0.12065 -0.2794)
			(end 0.12065 -0.2794)
			(stroke
				(width 0.1)
				(type default)
			)
			(layer "F.Fab")
		)
		(fp_line
			(start -0.12065 0.2794)
			(end -0.12065 0.3048)
			(stroke
				(width 0.1)
				(type default)
			)
			(layer "F.Fab")
		)
		(fp_line
			(start -0.12065 0.3048)
			(end -0.67945 0.3048)
			(stroke
				(width 0.1)
				(type default)
			)
			(layer "F.Fab")
		)
		(fp_line
			(start 0.120396 0.2794)
			(end -0.12065 0.2794)
			(stroke
				(width 0.1)
				(type default)
			)
			(layer "F.Fab")
		)
		(fp_line
			(start 0.120396 0.3048)
			(end 0.120396 0.2794)
			(stroke
				(width 0.1)
				(type default)
			)
			(layer "F.Fab")
		)
		(fp_line
			(start 0.12065 -0.3048)
			(end 0.67945 -0.3048)
			(stroke
				(width 0.1)
				(type default)
			)
			(layer "F.Fab")
		)
		(fp_line
			(start 0.12065 -0.2794)
			(end 0.12065 -0.3048)
			(stroke
				(width 0.1)
				(type default)
			)
			(layer "F.Fab")
		)
		(fp_line
			(start 0.67945 -0.3048)
			(end 0.67945 0.3048)
			(stroke
				(width 0.1)
				(type default)
			)
			(layer "F.Fab")
		)
		(fp_line
			(start 0.67945 0.3048)
			(end 0.120396 0.3048)
			(stroke
				(width 0.1)
				(type default)
			)
			(layer "F.Fab")
		)
		(pad "1" smd circle
			(at -0.40005 0)
			(size 0 0)
			(layers "F.Cu" "F.Mask" "F.Paste")
			(net "SW_P3V3_AUX_BOOTR")
		)
		(pad "2" smd circle
			(at 0.40005 0)
			(size 0 0)
			(layers "F.Cu" "F.Mask" "F.Paste")
			(net "SW_P3V3_AUX_BOOT_R")
		)
	)
	(footprint ""
		(layer "F.Cu")
		(at 157.02788 -121.376948 180)
		(property "Reference" "R981"
			(at 0 0 180)
			(layer "F.SilkS")
			(hide yes)
			(effects
				(font
					(size 1.27 1.27)
				)
			)
		)
		(property "Value" ""
			(at 0 0 180)
			(layer "F.Fab")
			(effects
				(font
					(size 1.27 1.27)
				)
			)
		)
		(duplicate_pad_numbers_are_jumpers no)
		(fp_line
			(start 0.7874 0.4064)
			(end -0.7874 0.4064)
			(stroke
				(width 0.1524)
				(type default)
			)
			(layer "F.SilkS")
		)
		(fp_line
			(start 0.7874 -0.4064)
			(end 0.7874 0.4064)
			(stroke
				(width 0.1524)
				(type default)
			)
			(layer "F.SilkS")
		)
		(fp_line
			(start -0.7874 0.4064)
			(end -0.7874 -0.4064)
			(stroke
				(width 0.1524)
				(type default)
			)
			(layer "F.SilkS")
		)
		(fp_line
			(start -0.7874 -0.4064)
			(end 0.7874 -0.4064)
			(stroke
				(width 0.1524)
				(type default)
			)
			(layer "F.SilkS")
		)
		(fp_line
			(start 0.67945 0.3048)
			(end 0.120396 0.3048)
			(stroke
				(width 0.1)
				(type default)
			)
			(layer "F.Fab")
		)
		(fp_line
			(start 0.67945 -0.3048)
			(end 0.67945 0.3048)
			(stroke
				(width 0.1)
				(type default)
			)
			(layer "F.Fab")
		)
		(fp_line
			(start 0.12065 -0.2794)
			(end 0.12065 -0.3048)
			(stroke
				(width 0.1)
				(type default)
			)
			(layer "F.Fab")
		)
		(fp_line
			(start 0.12065 -0.3048)
			(end 0.67945 -0.3048)
			(stroke
				(width 0.1)
				(type default)
			)
			(layer "F.Fab")
		)
		(fp_line
			(start 0.120396 0.3048)
			(end 0.120396 0.2794)
			(stroke
				(width 0.1)
				(type default)
			)
			(layer "F.Fab")
		)
		(fp_line
			(start 0.120396 0.2794)
			(end -0.12065 0.2794)
			(stroke
				(width 0.1)
				(type default)
			)
			(layer "F.Fab")
		)
		(fp_line
			(start -0.12065 0.3048)
			(end -0.67945 0.3048)
			(stroke
				(width 0.1)
				(type default)
			)
			(layer "F.Fab")
		)
		(fp_line
			(start -0.12065 0.2794)
			(end -0.12065 0.3048)
			(stroke
				(width 0.1)
				(type default)
			)
			(layer "F.Fab")
		)
		(fp_line
			(start -0.12065 -0.2794)
			(end 0.12065 -0.2794)
			(stroke
				(width 0.1)
				(type default)
			)
			(layer "F.Fab")
		)
		(fp_line
			(start -0.12065 -0.305054)
			(end -0.12065 -0.2794)
			(stroke
				(width 0.1)
				(type default)
			)
			(layer "F.Fab")
		)
		(fp_line
			(start -0.67945 0.3048)
			(end -0.67945 -0.305054)
			(stroke
				(width 0.1)
				(type default)
			)
			(layer "F.Fab")
		)
		(fp_line
			(start -0.67945 -0.305054)
			(end -0.12065 -0.305054)
			(stroke
				(width 0.1)
				(type default)
			)
			(layer "F.Fab")
		)
		(pad "1" smd circle
			(at -0.40005 0 180)
			(size 0 0)
			(layers "F.Cu" "F.Mask" "F.Paste")
			(net "FM_PVCCIN_CPU0_R_EN")
		)
		(pad "2" smd circle
			(at 0.40005 0 180)
			(size 0 0)
			(layers "F.Cu" "F.Mask" "F.Paste")
			(net "FM_PVCCIN_CPU0_EN")
		)
	)
	(footprint ""
		(layer "F.Cu")
		(at 40.627554 -106.015282)
		(property "Reference" "R3687"
			(at 0 0 0)
			(layer "F.SilkS")
			(hide yes)
			(effects
				(font
					(size 1.27 1.27)
				)
			)
		)
		(property "Value" ""
			(at 0 0 0)
			(layer "F.Fab")
			(effects
				(font
					(size 1.27 1.27)
				)
			)
		)
		(duplicate_pad_numbers_are_jumpers no)
		(fp_line
			(start -0.7874 -0.4064)
			(end 0.7874 -0.4064)
			(stroke
				(width 0.1524)
				(type default)
			)
			(layer "F.SilkS")
		)
		(fp_line
			(start -0.7874 0.4064)
			(end -0.7874 -0.4064)
			(stroke
				(width 0.1524)
				(type default)
			)
			(layer "F.SilkS")
		)
		(fp_line
			(start 0.7874 -0.4064)
			(end 0.7874 0.4064)
			(stroke
				(width 0.1524)
				(type default)
			)
			(layer "F.SilkS")
		)
		(fp_line
			(start 0.7874 0.4064)
			(end -0.7874 0.4064)
			(stroke
				(width 0.1524)
				(type default)
			)
			(layer "F.SilkS")
		)
		(fp_line
			(start -0.67945 -0.305054)
			(end -0.12065 -0.305054)
			(stroke
				(width 0.1)
				(type default)
			)
			(layer "F.Fab")
		)
		(fp_line
			(start -0.67945 0.3048)
			(end -0.67945 -0.305054)
			(stroke
				(width 0.1)
				(type default)
			)
			(layer "F.Fab")
		)
		(fp_line
			(start -0.12065 -0.305054)
			(end -0.12065 -0.2794)
			(stroke
				(width 0.1)
				(type default)
			)
			(layer "F.Fab")
		)
		(fp_line
			(start -0.12065 -0.2794)
			(end 0.12065 -0.2794)
			(stroke
				(width 0.1)
				(type default)
			)
			(layer "F.Fab")
		)
		(fp_line
			(start -0.12065 0.2794)
			(end -0.12065 0.3048)
			(stroke
				(width 0.1)
				(type default)
			)
			(layer "F.Fab")
		)
		(fp_line
			(start -0.12065 0.3048)
			(end -0.67945 0.3048)
			(stroke
				(width 0.1)
				(type default)
			)
			(layer "F.Fab")
		)
		(fp_line
			(start 0.120396 0.2794)
			(end -0.12065 0.2794)
			(stroke
				(width 0.1)
				(type default)
			)
			(layer "F.Fab")
		)
		(fp_line
			(start 0.120396 0.3048)
			(end 0.120396 0.2794)
			(stroke
				(width 0.1)
				(type default)
			)
			(layer "F.Fab")
		)
		(fp_line
			(start 0.12065 -0.3048)
			(end 0.67945 -0.3048)
			(stroke
				(width 0.1)
				(type default)
			)
			(layer "F.Fab")
		)
		(fp_line
			(start 0.12065 -0.2794)
			(end 0.12065 -0.3048)
			(stroke
				(width 0.1)
				(type default)
			)
			(layer "F.Fab")
		)
		(fp_line
			(start 0.67945 -0.3048)
			(end 0.67945 0.3048)
			(stroke
				(width 0.1)
				(type default)
			)
			(layer "F.Fab")
		)
		(fp_line
			(start 0.67945 0.3048)
			(end 0.120396 0.3048)
			(stroke
				(width 0.1)
				(type default)
			)
			(layer "F.Fab")
		)
		(pad "1" smd rect
			(at -0.40005 0 180)
			(size 0.4572 0.508)
			(layers "F.Cu" "F.Mask" "F.Paste")
			(net "P1V581_PDB_ADC")
		)
		(pad "2" smd rect
			(at 0.40005 0 180)
			(size 0.4572 0.508)
			(layers "F.Cu" "F.Mask" "F.Paste")
			(net "P3V3_PDB_AUX_ADC_MAM")
		)
	)
	(footprint ""
		(layer "F.Cu")
		(at 64.614298 -24.798782 180)
		(property "Reference" "PC1320"
			(at 0 0 180)
			(layer "F.SilkS")
			(hide yes)
			(effects
				(font
					(size 1.27 1.27)
				)
			)
		)
		(property "Value" ""
			(at 0 0 180)
			(layer "F.Fab")
			(effects
				(font
					(size 1.27 1.27)
				)
			)
		)
		(duplicate_pad_numbers_are_jumpers no)
		(fp_line
			(start 1.2954 0.5842)
			(end -1.2954 0.5842)
			(stroke
				(width 0.1524)
				(type default)
			)
			(layer "F.SilkS")
		)
		(fp_line
			(start 1.2954 -0.5842)
			(end 1.2954 0.5842)
			(stroke
				(width 0.1524)
				(type default)
			)
			(layer "F.SilkS")
		)
		(fp_line
			(start 0 -0.5842)
			(end 0 0.5842)
			(stroke
				(width 0.1524)
				(type default)
			)
			(layer "F.SilkS")
		)
		(fp_line
			(start -1.2954 0.5842)
			(end -1.2954 -0.5842)
			(stroke
				(width 0.1524)
				(type default)
			)
			(layer "F.SilkS")
		)
		(fp_line
			(start -1.2954 -0.5842)
			(end 1.2954 -0.5842)
			(stroke
				(width 0.1524)
				(type default)
			)
			(layer "F.SilkS")
		)
		(fp_line
			(start 1.1938 0.4064)
			(end 0.8636 0.4064)
			(stroke
				(width 0.1)
				(type default)
			)
			(layer "F.Fab")
		)
		(fp_line
			(start 1.1938 -0.4064)
			(end 1.1938 0.4064)
			(stroke
				(width 0.1)
				(type default)
			)
			(layer "F.Fab")
		)
		(fp_line
			(start 0.8636 0.4572)
			(end -0.8636 0.4572)
			(stroke
				(width 0.1)
				(type default)
			)
			(layer "F.Fab")
		)
		(fp_line
			(start 0.8636 0.4064)
			(end 0.8636 0.4572)
			(stroke
				(width 0.1)
				(type default)
			)
			(layer "F.Fab")
		)
		(fp_line
			(start 0.8636 -0.4064)
			(end 1.1938 -0.4064)
			(stroke
				(width 0.1)
				(type default)
			)
			(layer "F.Fab")
		)
		(fp_line
			(start 0.8636 -0.4572)
			(end 0.8636 -0.4064)
			(stroke
				(width 0.1)
				(type default)
			)
			(layer "F.Fab")
		)
		(fp_line
			(start -0.8636 0.4572)
			(end -0.8636 0.4064)
			(stroke
				(width 0.1)
				(type default)
			)
			(layer "F.Fab")
		)
		(fp_line
			(start -0.8636 0.4064)
			(end -1.1938 0.4064)
			(stroke
				(width 0.1)
				(type default)
			)
			(layer "F.Fab")
		)
		(fp_line
			(start -0.8636 -0.4064)
			(end -0.8636 -0.4572)
			(stroke
				(width 0.1)
				(type default)
			)
			(layer "F.Fab")
		)
		(fp_line
			(start -0.8636 -0.4572)
			(end 0.8636 -0.4572)
			(stroke
				(width 0.1)
				(type default)
			)
			(layer "F.Fab")
		)
		(fp_line
			(start -1.1938 0.4064)
			(end -1.1938 -0.4064)
			(stroke
				(width 0.1)
				(type default)
			)
			(layer "F.Fab")
		)
		(fp_line
			(start -1.1938 -0.4064)
			(end -0.8636 -0.4064)
			(stroke
				(width 0.1)
				(type default)
			)
			(layer "F.Fab")
		)
		(pad "1" smd rect
			(at -0.7366 0 90)
			(size 0.7112 0.8128)
			(layers "F.Cu" "F.Mask" "F.Paste")
			(net "P12V_OCP_AVIN_PD_2")
		)
		(pad "2" smd rect
			(at 0.7366 0 90)
			(size 0.7112 0.8128)
			(layers "F.Cu" "F.Mask" "F.Paste")
			(net "GND")
		)
	)
	(footprint ""
		(layer "F.Cu")
		(at 468.49284 -43.735498 180)
		(property "Reference" "R2488"
			(at 0 0 180)
			(layer "F.SilkS")
			(hide yes)
			(effects
				(font
					(size 1.27 1.27)
				)
			)
		)
		(property "Value" ""
			(at 0 0 180)
			(layer "F.Fab")
			(effects
				(font
					(size 1.27 1.27)
				)
			)
		)
		(duplicate_pad_numbers_are_jumpers no)
		(fp_line
			(start 0.7874 0.4064)
			(end -0.7874 0.4064)
			(stroke
				(width 0.1524)
				(type default)
			)
			(layer "F.SilkS")
		)
		(fp_line
			(start 0.7874 -0.4064)
			(end 0.7874 0.4064)
			(stroke
				(width 0.1524)
				(type default)
			)
			(layer "F.SilkS")
		)
		(fp_line
			(start -0.7874 0.4064)
			(end -0.7874 -0.4064)
			(stroke
				(width 0.1524)
				(type default)
			)
			(layer "F.SilkS")
		)
		(fp_line
			(start -0.7874 -0.4064)
			(end 0.7874 -0.4064)
			(stroke
				(width 0.1524)
				(type default)
			)
			(layer "F.SilkS")
		)
		(fp_line
			(start 0.67945 0.3048)
			(end 0.120396 0.3048)
			(stroke
				(width 0.1)
				(type default)
			)
			(layer "F.Fab")
		)
		(fp_line
			(start 0.67945 -0.3048)
			(end 0.67945 0.3048)
			(stroke
				(width 0.1)
				(type default)
			)
			(layer "F.Fab")
		)
		(fp_line
			(start 0.12065 -0.2794)
			(end 0.12065 -0.3048)
			(stroke
				(width 0.1)
				(type default)
			)
			(layer "F.Fab")
		)
		(fp_line
			(start 0.12065 -0.3048)
			(end 0.67945 -0.3048)
			(stroke
				(width 0.1)
				(type default)
			)
			(layer "F.Fab")
		)
		(fp_line
			(start 0.120396 0.3048)
			(end 0.120396 0.2794)
			(stroke
				(width 0.1)
				(type default)
			)
			(layer "F.Fab")
		)
		(fp_line
			(start 0.120396 0.2794)
			(end -0.12065 0.2794)
			(stroke
				(width 0.1)
				(type default)
			)
			(layer "F.Fab")
		)
		(fp_line
			(start -0.12065 0.3048)
			(end -0.67945 0.3048)
			(stroke
				(width 0.1)
				(type default)
			)
			(layer "F.Fab")
		)
		(fp_line
			(start -0.12065 0.2794)
			(end -0.12065 0.3048)
			(stroke
				(width 0.1)
				(type default)
			)
			(layer "F.Fab")
		)
		(fp_line
			(start -0.12065 -0.2794)
			(end 0.12065 -0.2794)
			(stroke
				(width 0.1)
				(type default)
			)
			(layer "F.Fab")
		)
		(fp_line
			(start -0.12065 -0.305054)
			(end -0.12065 -0.2794)
			(stroke
				(width 0.1)
				(type default)
			)
			(layer "F.Fab")
		)
		(fp_line
			(start -0.67945 0.3048)
			(end -0.67945 -0.305054)
			(stroke
				(width 0.1)
				(type default)
			)
			(layer "F.Fab")
		)
		(fp_line
			(start -0.67945 -0.305054)
			(end -0.12065 -0.305054)
			(stroke
				(width 0.1)
				(type default)
			)
			(layer "F.Fab")
		)
		(pad "1" smd circle
			(at -0.40005 0 180)
			(size 0 0)
			(layers "F.Cu" "F.Mask" "F.Paste")
			(net "P3V3_AUX")
		)
		(pad "2" smd circle
			(at 0.40005 0 180)
			(size 0 0)
			(layers "F.Cu" "F.Mask" "F.Paste")
			(net "OCP_SFF_WAKE_BUFF_N")
		)
	)
	(footprint ""
		(layer "F.Cu")
		(at 164.247576 -39.20363 180)
		(property "Reference" "R4456"
			(at 0 0 180)
			(layer "F.SilkS")
			(hide yes)
			(effects
				(font
					(size 1.27 1.27)
				)
			)
		)
		(property "Value" ""
			(at 0 0 180)
			(layer "F.Fab")
			(effects
				(font
					(size 1.27 1.27)
				)
			)
		)
		(duplicate_pad_numbers_are_jumpers no)
		(fp_line
			(start 0.7874 0.4064)
			(end -0.7874 0.4064)
			(stroke
				(width 0.1524)
				(type default)
			)
			(layer "F.SilkS")
		)
		(fp_line
			(start 0.7874 -0.4064)
			(end 0.7874 0.4064)
			(stroke
				(width 0.1524)
				(type default)
			)
			(layer "F.SilkS")
		)
		(fp_line
			(start -0.7874 0.4064)
			(end -0.7874 -0.4064)
			(stroke
				(width 0.1524)
				(type default)
			)
			(layer "F.SilkS")
		)
		(fp_line
			(start -0.7874 -0.4064)
			(end 0.7874 -0.4064)
			(stroke
				(width 0.1524)
				(type default)
			)
			(layer "F.SilkS")
		)
		(fp_line
			(start 0.67945 0.3048)
			(end 0.120396 0.3048)
			(stroke
				(width 0.1)
				(type default)
			)
			(layer "F.Fab")
		)
		(fp_line
			(start 0.67945 -0.3048)
			(end 0.67945 0.3048)
			(stroke
				(width 0.1)
				(type default)
			)
			(layer "F.Fab")
		)
		(fp_line
			(start 0.12065 -0.2794)
			(end 0.12065 -0.3048)
			(stroke
				(width 0.1)
				(type default)
			)
			(layer "F.Fab")
		)
		(fp_line
			(start 0.12065 -0.3048)
			(end 0.67945 -0.3048)
			(stroke
				(width 0.1)
				(type default)
			)
			(layer "F.Fab")
		)
		(fp_line
			(start 0.120396 0.3048)
			(end 0.120396 0.2794)
			(stroke
				(width 0.1)
				(type default)
			)
			(layer "F.Fab")
		)
		(fp_line
			(start 0.120396 0.2794)
			(end -0.12065 0.2794)
			(stroke
				(width 0.1)
				(type default)
			)
			(layer "F.Fab")
		)
		(fp_line
			(start -0.12065 0.3048)
			(end -0.67945 0.3048)
			(stroke
				(width 0.1)
				(type default)
			)
			(layer "F.Fab")
		)
		(fp_line
			(start -0.12065 0.2794)
			(end -0.12065 0.3048)
			(stroke
				(width 0.1)
				(type default)
			)
			(layer "F.Fab")
		)
		(fp_line
			(start -0.12065 -0.2794)
			(end 0.12065 -0.2794)
			(stroke
				(width 0.1)
				(type default)
			)
			(layer "F.Fab")
		)
		(fp_line
			(start -0.12065 -0.305054)
			(end -0.12065 -0.2794)
			(stroke
				(width 0.1)
				(type default)
			)
			(layer "F.Fab")
		)
		(fp_line
			(start -0.67945 0.3048)
			(end -0.67945 -0.305054)
			(stroke
				(width 0.1)
				(type default)
			)
			(layer "F.Fab")
		)
		(fp_line
			(start -0.67945 -0.305054)
			(end -0.12065 -0.305054)
			(stroke
				(width 0.1)
				(type default)
			)
			(layer "F.Fab")
		)
		(pad "1" smd circle
			(at -0.40005 0 180)
			(size 0 0)
			(layers "F.Cu" "F.Mask" "F.Paste")
			(net "P3V3_AUX")
		)
		(pad "2" smd circle
			(at 0.40005 0 180)
			(size 0 0)
			(layers "F.Cu" "F.Mask" "F.Paste")
			(net "USB_HUB_2_OVCUR1")
		)
	)
	(footprint ""
		(layer "F.Cu")
		(at 322.263516 -22.497288)
		(property "Reference" "R1455"
			(at 0 0 0)
			(layer "F.SilkS")
			(hide yes)
			(effects
				(font
					(size 1.27 1.27)
				)
			)
		)
		(property "Value" ""
			(at 0 0 0)
			(layer "F.Fab")
			(effects
				(font
					(size 1.27 1.27)
				)
			)
		)
		(duplicate_pad_numbers_are_jumpers no)
		(fp_line
			(start -0.7874 -0.4064)
			(end 0.7874 -0.4064)
			(stroke
				(width 0.1524)
				(type default)
			)
			(layer "F.SilkS")
		)
		(fp_line
			(start -0.7874 0.4064)
			(end -0.7874 -0.4064)
			(stroke
				(width 0.1524)
				(type default)
			)
			(layer "F.SilkS")
		)
		(fp_line
			(start 0.7874 -0.4064)
			(end 0.7874 0.4064)
			(stroke
				(width 0.1524)
				(type default)
			)
			(layer "F.SilkS")
		)
		(fp_line
			(start 0.7874 0.4064)
			(end -0.7874 0.4064)
			(stroke
				(width 0.1524)
				(type default)
			)
			(layer "F.SilkS")
		)
		(fp_line
			(start -0.67945 -0.305054)
			(end -0.12065 -0.305054)
			(stroke
				(width 0.1)
				(type default)
			)
			(layer "F.Fab")
		)
		(fp_line
			(start -0.67945 0.3048)
			(end -0.67945 -0.305054)
			(stroke
				(width 0.1)
				(type default)
			)
			(layer "F.Fab")
		)
		(fp_line
			(start -0.12065 -0.305054)
			(end -0.12065 -0.2794)
			(stroke
				(width 0.1)
				(type default)
			)
			(layer "F.Fab")
		)
		(fp_line
			(start -0.12065 -0.2794)
			(end 0.12065 -0.2794)
			(stroke
				(width 0.1)
				(type default)
			)
			(layer "F.Fab")
		)
		(fp_line
			(start -0.12065 0.2794)
			(end -0.12065 0.3048)
			(stroke
				(width 0.1)
				(type default)
			)
			(layer "F.Fab")
		)
		(fp_line
			(start -0.12065 0.3048)
			(end -0.67945 0.3048)
			(stroke
				(width 0.1)
				(type default)
			)
			(layer "F.Fab")
		)
		(fp_line
			(start 0.120396 0.2794)
			(end -0.12065 0.2794)
			(stroke
				(width 0.1)
				(type default)
			)
			(layer "F.Fab")
		)
		(fp_line
			(start 0.120396 0.3048)
			(end 0.120396 0.2794)
			(stroke
				(width 0.1)
				(type default)
			)
			(layer "F.Fab")
		)
		(fp_line
			(start 0.12065 -0.3048)
			(end 0.67945 -0.3048)
			(stroke
				(width 0.1)
				(type default)
			)
			(layer "F.Fab")
		)
		(fp_line
			(start 0.12065 -0.2794)
			(end 0.12065 -0.3048)
			(stroke
				(width 0.1)
				(type default)
			)
			(layer "F.Fab")
		)
		(fp_line
			(start 0.67945 -0.3048)
			(end 0.67945 0.3048)
			(stroke
				(width 0.1)
				(type default)
			)
			(layer "F.Fab")
		)
		(fp_line
			(start 0.67945 0.3048)
			(end 0.120396 0.3048)
			(stroke
				(width 0.1)
				(type default)
			)
			(layer "F.Fab")
		)
		(pad "1" smd circle
			(at -0.40005 0)
			(size 0 0)
			(layers "F.Cu" "F.Mask" "F.Paste")
			(net "FM_ADR_MODE0_R")
		)
		(pad "2" smd circle
			(at 0.40005 0)
			(size 0 0)
			(layers "F.Cu" "F.Mask" "F.Paste")
			(net "FM_ADR_MODE0")
		)
	)
	(footprint ""
		(layer "F.Cu")
		(at 106.3117 -256.6543 -90)
		(property "Reference" "C231"
			(at 0 0 270)
			(layer "F.SilkS")
			(hide yes)
			(effects
				(font
					(size 1.27 1.27)
				)
			)
		)
		(property "Value" ""
			(at 0 0 270)
			(layer "F.Fab")
			(effects
				(font
					(size 1.27 1.27)
				)
			)
		)
		(duplicate_pad_numbers_are_jumpers no)
		(fp_line
			(start -0.7874 0.4064)
			(end -0.7874 -0.4064)
			(stroke
				(width 0.1524)
				(type default)
			)
			(layer "F.SilkS")
		)
		(fp_line
			(start 0.7874 0.4064)
			(end -0.7874 0.4064)
			(stroke
				(width 0.1524)
				(type default)
			)
			(layer "F.SilkS")
		)
		(fp_line
			(start -0.7874 -0.4064)
			(end 0.7874 -0.4064)
			(stroke
				(width 0.1524)
				(type default)
			)
			(layer "F.SilkS")
		)
		(fp_line
			(start 0.7874 -0.4064)
			(end 0.7874 0.4064)
			(stroke
				(width 0.1524)
				(type default)
			)
			(layer "F.SilkS")
		)
		(fp_line
			(start -0.67945 0.3048)
			(end -0.67945 -0.305054)
			(stroke
				(width 0.1)
				(type default)
			)
			(layer "F.Fab")
		)
		(fp_line
			(start -0.12065 0.3048)
			(end -0.67945 0.3048)
			(stroke
				(width 0.1)
				(type default)
			)
			(layer "F.Fab")
		)
		(fp_line
			(start 0.120396 0.3048)
			(end 0.120396 0.2794)
			(stroke
				(width 0.1)
				(type default)
			)
			(layer "F.Fab")
		)
		(fp_line
			(start 0.67945 0.3048)
			(end 0.120396 0.3048)
			(stroke
				(width 0.1)
				(type default)
			)
			(layer "F.Fab")
		)
		(fp_line
			(start -0.12065 0.2794)
			(end -0.12065 0.3048)
			(stroke
				(width 0.1)
				(type default)
			)
			(layer "F.Fab")
		)
		(fp_line
			(start 0.120396 0.2794)
			(end -0.12065 0.2794)
			(stroke
				(width 0.1)
				(type default)
			)
			(layer "F.Fab")
		)
		(fp_line
			(start -0.12065 -0.2794)
			(end 0.12065 -0.2794)
			(stroke
				(width 0.1)
				(type default)
			)
			(layer "F.Fab")
		)
		(fp_line
			(start 0.12065 -0.2794)
			(end 0.12065 -0.3048)
			(stroke
				(width 0.1)
				(type default)
			)
			(layer "F.Fab")
		)
		(fp_line
			(start 0.12065 -0.3048)
			(end 0.67945 -0.3048)
			(stroke
				(width 0.1)
				(type default)
			)
			(layer "F.Fab")
		)
		(fp_line
			(start 0.67945 -0.3048)
			(end 0.67945 0.3048)
			(stroke
				(width 0.1)
				(type default)
			)
			(layer "F.Fab")
		)
		(fp_line
			(start -0.67945 -0.305054)
			(end -0.12065 -0.305054)
			(stroke
				(width 0.1)
				(type default)
			)
			(layer "F.Fab")
		)
		(fp_line
			(start -0.12065 -0.305054)
			(end -0.12065 -0.2794)
			(stroke
				(width 0.1)
				(type default)
			)
			(layer "F.Fab")
		)
		(pad "1" smd circle
			(at -0.40005 0 270)
			(size 0 0)
			(layers "F.Cu" "F.Mask" "F.Paste")
			(net "PVCCIN_CPU1")
		)
		(pad "2" smd circle
			(at 0.40005 0 270)
			(size 0 0)
			(layers "F.Cu" "F.Mask" "F.Paste")
			(net "GND")
		)
	)
	(footprint ""
		(layer "F.Cu")
		(at 367.44783 -244.03177 90)
		(property "Reference" "C1021"
			(at 0 0 90)
			(layer "F.SilkS")
			(hide yes)
			(effects
				(font
					(size 1.27 1.27)
				)
			)
		)
		(property "Value" ""
			(at 0 0 90)
			(layer "F.Fab")
			(effects
				(font
					(size 1.27 1.27)
				)
			)
		)
		(duplicate_pad_numbers_are_jumpers no)
		(fp_line
			(start 0.7874 -0.4064)
			(end 0.7874 0.4064)
			(stroke
				(width 0.1524)
				(type default)
			)
			(layer "F.SilkS")
		)
		(fp_line
			(start -0.7874 -0.4064)
			(end 0.7874 -0.4064)
			(stroke
				(width 0.1524)
				(type default)
			)
			(layer "F.SilkS")
		)
		(fp_line
			(start 0.7874 0.4064)
			(end -0.7874 0.4064)
			(stroke
				(width 0.1524)
				(type default)
			)
			(layer "F.SilkS")
		)
		(fp_line
			(start -0.7874 0.4064)
			(end -0.7874 -0.4064)
			(stroke
				(width 0.1524)
				(type default)
			)
			(layer "F.SilkS")
		)
		(fp_line
			(start -0.12065 -0.305054)
			(end -0.12065 -0.2794)
			(stroke
				(width 0.1)
				(type default)
			)
			(layer "F.Fab")
		)
		(fp_line
			(start -0.67945 -0.305054)
			(end -0.12065 -0.305054)
			(stroke
				(width 0.1)
				(type default)
			)
			(layer "F.Fab")
		)
		(fp_line
			(start 0.67945 -0.3048)
			(end 0.67945 0.3048)
			(stroke
				(width 0.1)
				(type default)
			)
			(layer "F.Fab")
		)
		(fp_line
			(start 0.12065 -0.3048)
			(end 0.67945 -0.3048)
			(stroke
				(width 0.1)
				(type default)
			)
			(layer "F.Fab")
		)
		(fp_line
			(start 0.12065 -0.2794)
			(end 0.12065 -0.3048)
			(stroke
				(width 0.1)
				(type default)
			)
			(layer "F.Fab")
		)
		(fp_line
			(start -0.12065 -0.2794)
			(end 0.12065 -0.2794)
			(stroke
				(width 0.1)
				(type default)
			)
			(layer "F.Fab")
		)
		(fp_line
			(start 0.120396 0.2794)
			(end -0.12065 0.2794)
			(stroke
				(width 0.1)
				(type default)
			)
			(layer "F.Fab")
		)
		(fp_line
			(start -0.12065 0.2794)
			(end -0.12065 0.3048)
			(stroke
				(width 0.1)
				(type default)
			)
			(layer "F.Fab")
		)
		(fp_line
			(start 0.67945 0.3048)
			(end 0.120396 0.3048)
			(stroke
				(width 0.1)
				(type default)
			)
			(layer "F.Fab")
		)
		(fp_line
			(start 0.120396 0.3048)
			(end 0.120396 0.2794)
			(stroke
				(width 0.1)
				(type default)
			)
			(layer "F.Fab")
		)
		(fp_line
			(start -0.12065 0.3048)
			(end -0.67945 0.3048)
			(stroke
				(width 0.1)
				(type default)
			)
			(layer "F.Fab")
		)
		(fp_line
			(start -0.67945 0.3048)
			(end -0.67945 -0.305054)
			(stroke
				(width 0.1)
				(type default)
			)
			(layer "F.Fab")
		)
		(pad "1" smd circle
			(at -0.40005 0 90)
			(size 0 0)
			(layers "F.Cu" "F.Mask" "F.Paste")
			(net "PVCCIN_CPU0")
		)
		(pad "2" smd circle
			(at 0.40005 0 90)
			(size 0 0)
			(layers "F.Cu" "F.Mask" "F.Paste")
			(net "GND")
		)
	)
	(footprint ""
		(layer "F.Cu")
		(at 193.95948 -350.510348 180)
		(property "Reference" "R1235"
			(at 0 0 180)
			(layer "F.SilkS")
			(hide yes)
			(effects
				(font
					(size 1.27 1.27)
				)
			)
		)
		(property "Value" ""
			(at 0 0 180)
			(layer "F.Fab")
			(effects
				(font
					(size 1.27 1.27)
				)
			)
		)
		(duplicate_pad_numbers_are_jumpers no)
		(fp_line
			(start 0.7874 0.4064)
			(end -0.7874 0.4064)
			(stroke
				(width 0.1524)
				(type default)
			)
			(layer "F.SilkS")
		)
		(fp_line
			(start 0.7874 -0.4064)
			(end 0.7874 0.4064)
			(stroke
				(width 0.1524)
				(type default)
			)
			(layer "F.SilkS")
		)
		(fp_line
			(start -0.7874 0.4064)
			(end -0.7874 -0.4064)
			(stroke
				(width 0.1524)
				(type default)
			)
			(layer "F.SilkS")
		)
		(fp_line
			(start -0.7874 -0.4064)
			(end 0.7874 -0.4064)
			(stroke
				(width 0.1524)
				(type default)
			)
			(layer "F.SilkS")
		)
		(fp_line
			(start 0.67945 0.3048)
			(end 0.120396 0.3048)
			(stroke
				(width 0.1)
				(type default)
			)
			(layer "F.Fab")
		)
		(fp_line
			(start 0.67945 -0.3048)
			(end 0.67945 0.3048)
			(stroke
				(width 0.1)
				(type default)
			)
			(layer "F.Fab")
		)
		(fp_line
			(start 0.12065 -0.2794)
			(end 0.12065 -0.3048)
			(stroke
				(width 0.1)
				(type default)
			)
			(layer "F.Fab")
		)
		(fp_line
			(start 0.12065 -0.3048)
			(end 0.67945 -0.3048)
			(stroke
				(width 0.1)
				(type default)
			)
			(layer "F.Fab")
		)
		(fp_line
			(start 0.120396 0.3048)
			(end 0.120396 0.2794)
			(stroke
				(width 0.1)
				(type default)
			)
			(layer "F.Fab")
		)
		(fp_line
			(start 0.120396 0.2794)
			(end -0.12065 0.2794)
			(stroke
				(width 0.1)
				(type default)
			)
			(layer "F.Fab")
		)
		(fp_line
			(start -0.12065 0.3048)
			(end -0.67945 0.3048)
			(stroke
				(width 0.1)
				(type default)
			)
			(layer "F.Fab")
		)
		(fp_line
			(start -0.12065 0.2794)
			(end -0.12065 0.3048)
			(stroke
				(width 0.1)
				(type default)
			)
			(layer "F.Fab")
		)
		(fp_line
			(start -0.12065 -0.2794)
			(end 0.12065 -0.2794)
			(stroke
				(width 0.1)
				(type default)
			)
			(layer "F.Fab")
		)
		(fp_line
			(start -0.12065 -0.305054)
			(end -0.12065 -0.2794)
			(stroke
				(width 0.1)
				(type default)
			)
			(layer "F.Fab")
		)
		(fp_line
			(start -0.67945 0.3048)
			(end -0.67945 -0.305054)
			(stroke
				(width 0.1)
				(type default)
			)
			(layer "F.Fab")
		)
		(fp_line
			(start -0.67945 -0.305054)
			(end -0.12065 -0.305054)
			(stroke
				(width 0.1)
				(type default)
			)
			(layer "F.Fab")
		)
		(pad "1" smd circle
			(at -0.40005 0 180)
			(size 0 0)
			(layers "F.Cu" "F.Mask" "F.Paste")
			(net "GND")
		)
		(pad "2" smd circle
			(at 0.40005 0 180)
			(size 0 0)
			(layers "F.Cu" "F.Mask" "F.Paste")
			(net "PUD_XTAL_CPU1_MODE0")
		)
	)
	(footprint ""
		(layer "F.Cu")
		(at 31.856426 -70.83425 180)
		(property "Reference" "R3147"
			(at 0 0 180)
			(layer "F.SilkS")
			(hide yes)
			(effects
				(font
					(size 1.27 1.27)
				)
			)
		)
		(property "Value" ""
			(at 0 0 180)
			(layer "F.Fab")
			(effects
				(font
					(size 1.27 1.27)
				)
			)
		)
		(duplicate_pad_numbers_are_jumpers no)
		(fp_line
			(start 0.7874 0.4064)
			(end -0.7874 0.4064)
			(stroke
				(width 0.1524)
				(type default)
			)
			(layer "F.SilkS")
		)
		(fp_line
			(start 0.7874 -0.4064)
			(end 0.7874 0.4064)
			(stroke
				(width 0.1524)
				(type default)
			)
			(layer "F.SilkS")
		)
		(fp_line
			(start -0.7874 0.4064)
			(end -0.7874 -0.4064)
			(stroke
				(width 0.1524)
				(type default)
			)
			(layer "F.SilkS")
		)
		(fp_line
			(start -0.7874 -0.4064)
			(end 0.7874 -0.4064)
			(stroke
				(width 0.1524)
				(type default)
			)
			(layer "F.SilkS")
		)
		(fp_line
			(start 0.67945 0.3048)
			(end 0.120396 0.3048)
			(stroke
				(width 0.1)
				(type default)
			)
			(layer "F.Fab")
		)
		(fp_line
			(start 0.67945 -0.3048)
			(end 0.67945 0.3048)
			(stroke
				(width 0.1)
				(type default)
			)
			(layer "F.Fab")
		)
		(fp_line
			(start 0.12065 -0.2794)
			(end 0.12065 -0.3048)
			(stroke
				(width 0.1)
				(type default)
			)
			(layer "F.Fab")
		)
		(fp_line
			(start 0.12065 -0.3048)
			(end 0.67945 -0.3048)
			(stroke
				(width 0.1)
				(type default)
			)
			(layer "F.Fab")
		)
		(fp_line
			(start 0.120396 0.3048)
			(end 0.120396 0.2794)
			(stroke
				(width 0.1)
				(type default)
			)
			(layer "F.Fab")
		)
		(fp_line
			(start 0.120396 0.2794)
			(end -0.12065 0.2794)
			(stroke
				(width 0.1)
				(type default)
			)
			(layer "F.Fab")
		)
		(fp_line
			(start -0.12065 0.3048)
			(end -0.67945 0.3048)
			(stroke
				(width 0.1)
				(type default)
			)
			(layer "F.Fab")
		)
		(fp_line
			(start -0.12065 0.2794)
			(end -0.12065 0.3048)
			(stroke
				(width 0.1)
				(type default)
			)
			(layer "F.Fab")
		)
		(fp_line
			(start -0.12065 -0.2794)
			(end 0.12065 -0.2794)
			(stroke
				(width 0.1)
				(type default)
			)
			(layer "F.Fab")
		)
		(fp_line
			(start -0.12065 -0.305054)
			(end -0.12065 -0.2794)
			(stroke
				(width 0.1)
				(type default)
			)
			(layer "F.Fab")
		)
		(fp_line
			(start -0.67945 0.3048)
			(end -0.67945 -0.305054)
			(stroke
				(width 0.1)
				(type default)
			)
			(layer "F.Fab")
		)
		(fp_line
			(start -0.67945 -0.305054)
			(end -0.12065 -0.305054)
			(stroke
				(width 0.1)
				(type default)
			)
			(layer "F.Fab")
		)
		(pad "1" smd circle
			(at -0.40005 0 180)
			(size 0 0)
			(layers "F.Cu" "F.Mask" "F.Paste")
			(net "P3V3_AUX")
		)
		(pad "2" smd circle
			(at 0.40005 0 180)
			(size 0 0)
			(layers "F.Cu" "F.Mask" "F.Paste")
			(net "HP_LVC3_OCP_V3_2_PRSNT2_N")
		)
	)
	(footprint ""
		(layer "F.Cu")
		(at 195.00088 -112.613948 -90)
		(property "Reference" "OSC2"
			(at 2.15773 2.276602 0)
			(unlocked yes)
			(layer "F.SilkS")
			(effects
				(font
					(size 0.7874 0.5842)
					(thickness 0.1524)
				)
				(justify left)
			)
		)
		(property "Value" ""
			(at 0 0 270)
			(layer "F.Fab")
			(effects
				(font
					(size 1.27 1.27)
				)
			)
		)
		(duplicate_pad_numbers_are_jumpers no)
		(fp_line
			(start -1.299972 1.599946)
			(end -1.299972 -1.599946)
			(stroke
				(width 0.1524)
				(type default)
			)
			(layer "F.SilkS")
		)
		(fp_line
			(start 1.299972 1.599946)
			(end -1.299972 1.599946)
			(stroke
				(width 0.1524)
				(type default)
			)
			(layer "F.SilkS")
		)
		(fp_line
			(start -1.299972 -1.599946)
			(end 1.299972 -1.599946)
			(stroke
				(width 0.1524)
				(type default)
			)
			(layer "F.SilkS")
		)
		(fp_line
			(start 1.299972 -1.599946)
			(end 1.299972 1.599946)
			(stroke
				(width 0.1524)
				(type default)
			)
			(layer "F.SilkS")
		)
		(fp_poly
			(pts
				(xy -2.4892 -1.26492) (xy -1.4732 -0.75692) (xy -2.4892 -0.24892)
			)
			(stroke
				(width 0)
				(type default)
			)
			(fill yes)
			(layer "F.SilkS")
		)
		(fp_line
			(start -1.050036 1.299972)
			(end -1.050036 -1.299972)
			(stroke
				(width 0.1)
				(type default)
			)
			(layer "F.Fab")
		)
		(fp_line
			(start 1.050036 1.299972)
			(end -1.050036 1.299972)
			(stroke
				(width 0.1)
				(type default)
			)
			(layer "F.Fab")
		)
		(fp_line
			(start -1.050036 -1.299972)
			(end 1.050036 -1.299972)
			(stroke
				(width 0.1)
				(type default)
			)
			(layer "F.Fab")
		)
		(fp_line
			(start 1.050036 -1.299972)
			(end 1.050036 1.299972)
			(stroke
				(width 0.1)
				(type default)
			)
			(layer "F.Fab")
		)
		(fp_poly
			(pts
				(xy -2.4892 -0.24892) (xy -2.4892 -1.26492) (xy -1.4732 -0.75692)
			)
			(stroke
				(width 0)
				(type default)
			)
			(fill yes)
			(layer "F.Fab")
		)
		(pad "1" smd rect
			(at -0.649986 -0.849884 270)
			(size 1.016 1.2192)
			(layers "F.Cu" "F.Mask" "F.Paste")
			(net "PU_CLK25M_OSC_FPGA_EN")
		)
		(pad "2" smd rect
			(at -0.649986 0.849884 270)
			(size 1.016 1.2192)
			(layers "F.Cu" "F.Mask" "F.Paste")
			(net "GND")
		)
		(pad "3" smd rect
			(at 0.649986 0.849884 270)
			(size 1.016 1.2192)
			(layers "F.Cu" "F.Mask" "F.Paste")
			(net "CLK_25M_OSC_FPGA_R")
		)
		(pad "4" smd rect
			(at 0.649986 -0.849884 270)
			(size 1.016 1.2192)
			(layers "F.Cu" "F.Mask" "F.Paste")
			(net "P3V3_AUX")
		)
	)
	(footprint ""
		(layer "F.Cu")
		(at 442.76518 -103.3272 90)
		(property "Reference" "R4749"
			(at 0 0 90)
			(layer "F.SilkS")
			(hide yes)
			(effects
				(font
					(size 1.27 1.27)
				)
			)
		)
		(property "Value" ""
			(at 0 0 90)
			(layer "F.Fab")
			(effects
				(font
					(size 1.27 1.27)
				)
			)
		)
		(duplicate_pad_numbers_are_jumpers no)
		(fp_line
			(start 0.7874 -0.4064)
			(end 0.7874 0.4064)
			(stroke
				(width 0.1524)
				(type default)
			)
			(layer "F.SilkS")
		)
		(fp_line
			(start -0.7874 -0.4064)
			(end 0.7874 -0.4064)
			(stroke
				(width 0.1524)
				(type default)
			)
			(layer "F.SilkS")
		)
		(fp_line
			(start 0.7874 0.4064)
			(end -0.7874 0.4064)
			(stroke
				(width 0.1524)
				(type default)
			)
			(layer "F.SilkS")
		)
		(fp_line
			(start -0.7874 0.4064)
			(end -0.7874 -0.4064)
			(stroke
				(width 0.1524)
				(type default)
			)
			(layer "F.SilkS")
		)
		(fp_line
			(start -0.12065 -0.305054)
			(end -0.12065 -0.2794)
			(stroke
				(width 0.1)
				(type default)
			)
			(layer "F.Fab")
		)
		(fp_line
			(start -0.67945 -0.305054)
			(end -0.12065 -0.305054)
			(stroke
				(width 0.1)
				(type default)
			)
			(layer "F.Fab")
		)
		(fp_line
			(start 0.67945 -0.3048)
			(end 0.67945 0.3048)
			(stroke
				(width 0.1)
				(type default)
			)
			(layer "F.Fab")
		)
		(fp_line
			(start 0.12065 -0.3048)
			(end 0.67945 -0.3048)
			(stroke
				(width 0.1)
				(type default)
			)
			(layer "F.Fab")
		)
		(fp_line
			(start 0.12065 -0.2794)
			(end 0.12065 -0.3048)
			(stroke
				(width 0.1)
				(type default)
			)
			(layer "F.Fab")
		)
		(fp_line
			(start -0.12065 -0.2794)
			(end 0.12065 -0.2794)
			(stroke
				(width 0.1)
				(type default)
			)
			(layer "F.Fab")
		)
		(fp_line
			(start 0.120396 0.2794)
			(end -0.12065 0.2794)
			(stroke
				(width 0.1)
				(type default)
			)
			(layer "F.Fab")
		)
		(fp_line
			(start -0.12065 0.2794)
			(end -0.12065 0.3048)
			(stroke
				(width 0.1)
				(type default)
			)
			(layer "F.Fab")
		)
		(fp_line
			(start 0.67945 0.3048)
			(end 0.120396 0.3048)
			(stroke
				(width 0.1)
				(type default)
			)
			(layer "F.Fab")
		)
		(fp_line
			(start 0.120396 0.3048)
			(end 0.120396 0.2794)
			(stroke
				(width 0.1)
				(type default)
			)
			(layer "F.Fab")
		)
		(fp_line
			(start -0.12065 0.3048)
			(end -0.67945 0.3048)
			(stroke
				(width 0.1)
				(type default)
			)
			(layer "F.Fab")
		)
		(fp_line
			(start -0.67945 0.3048)
			(end -0.67945 -0.305054)
			(stroke
				(width 0.1)
				(type default)
			)
			(layer "F.Fab")
		)
		(pad "1" smd circle
			(at -0.40005 0 90)
			(size 0 0)
			(layers "F.Cu" "F.Mask" "F.Paste")
			(net "OCP_SFF_AUX_PWR_PLD_EN_R")
		)
		(pad "2" smd circle
			(at 0.40005 0 90)
			(size 0 0)
			(layers "F.Cu" "F.Mask" "F.Paste")
			(net "OCP_SFF_AUX_PWR_EN_R2")
		)
	)
	(footprint ""
		(layer "F.Cu")
		(at 95.123 -417.683188 -90)
		(property "Reference" "R4545"
			(at 0 0 270)
			(layer "F.SilkS")
			(hide yes)
			(effects
				(font
					(size 1.27 1.27)
				)
			)
		)
		(property "Value" ""
			(at 0 0 270)
			(layer "F.Fab")
			(effects
				(font
					(size 1.27 1.27)
				)
			)
		)
		(duplicate_pad_numbers_are_jumpers no)
		(fp_line
			(start -0.7874 0.4064)
			(end -0.7874 -0.4064)
			(stroke
				(width 0.1524)
				(type default)
			)
			(layer "F.SilkS")
		)
		(fp_line
			(start 0.7874 0.4064)
			(end -0.7874 0.4064)
			(stroke
				(width 0.1524)
				(type default)
			)
			(layer "F.SilkS")
		)
		(fp_line
			(start -0.7874 -0.4064)
			(end 0.7874 -0.4064)
			(stroke
				(width 0.1524)
				(type default)
			)
			(layer "F.SilkS")
		)
		(fp_line
			(start 0.7874 -0.4064)
			(end 0.7874 0.4064)
			(stroke
				(width 0.1524)
				(type default)
			)
			(layer "F.SilkS")
		)
		(fp_line
			(start -0.67945 0.3048)
			(end -0.67945 -0.305054)
			(stroke
				(width 0.1)
				(type default)
			)
			(layer "F.Fab")
		)
		(fp_line
			(start -0.12065 0.3048)
			(end -0.67945 0.3048)
			(stroke
				(width 0.1)
				(type default)
			)
			(layer "F.Fab")
		)
		(fp_line
			(start 0.120396 0.3048)
			(end 0.120396 0.2794)
			(stroke
				(width 0.1)
				(type default)
			)
			(layer "F.Fab")
		)
		(fp_line
			(start 0.67945 0.3048)
			(end 0.120396 0.3048)
			(stroke
				(width 0.1)
				(type default)
			)
			(layer "F.Fab")
		)
		(fp_line
			(start -0.12065 0.2794)
			(end -0.12065 0.3048)
			(stroke
				(width 0.1)
				(type default)
			)
			(layer "F.Fab")
		)
		(fp_line
			(start 0.120396 0.2794)
			(end -0.12065 0.2794)
			(stroke
				(width 0.1)
				(type default)
			)
			(layer "F.Fab")
		)
		(fp_line
			(start -0.12065 -0.2794)
			(end 0.12065 -0.2794)
			(stroke
				(width 0.1)
				(type default)
			)
			(layer "F.Fab")
		)
		(fp_line
			(start 0.12065 -0.2794)
			(end 0.12065 -0.3048)
			(stroke
				(width 0.1)
				(type default)
			)
			(layer "F.Fab")
		)
		(fp_line
			(start 0.12065 -0.3048)
			(end 0.67945 -0.3048)
			(stroke
				(width 0.1)
				(type default)
			)
			(layer "F.Fab")
		)
		(fp_line
			(start 0.67945 -0.3048)
			(end 0.67945 0.3048)
			(stroke
				(width 0.1)
				(type default)
			)
			(layer "F.Fab")
		)
		(fp_line
			(start -0.67945 -0.305054)
			(end -0.12065 -0.305054)
			(stroke
				(width 0.1)
				(type default)
			)
			(layer "F.Fab")
		)
		(fp_line
			(start -0.12065 -0.305054)
			(end -0.12065 -0.2794)
			(stroke
				(width 0.1)
				(type default)
			)
			(layer "F.Fab")
		)
		(pad "1" smd circle
			(at -0.40005 0 270)
			(size 0 0)
			(layers "F.Cu" "F.Mask" "F.Paste")
			(net "P3V3_AUX")
		)
		(pad "2" smd circle
			(at 0.40005 0 270)
			(size 0 0)
			(layers "F.Cu" "F.Mask" "F.Paste")
			(net "HGX_DETECT")
		)
	)
	(footprint ""
		(layer "F.Cu")
		(at 362.13034 -410.700728)
		(property "Reference" "R4550"
			(at 0 0 0)
			(layer "F.SilkS")
			(hide yes)
			(effects
				(font
					(size 1.27 1.27)
				)
			)
		)
		(property "Value" ""
			(at 0 0 0)
			(layer "F.Fab")
			(effects
				(font
					(size 1.27 1.27)
				)
			)
		)
		(duplicate_pad_numbers_are_jumpers no)
		(fp_line
			(start -0.7874 -0.4064)
			(end 0.7874 -0.4064)
			(stroke
				(width 0.1524)
				(type default)
			)
			(layer "F.SilkS")
		)
		(fp_line
			(start -0.7874 0.4064)
			(end -0.7874 -0.4064)
			(stroke
				(width 0.1524)
				(type default)
			)
			(layer "F.SilkS")
		)
		(fp_line
			(start 0.7874 -0.4064)
			(end 0.7874 0.4064)
			(stroke
				(width 0.1524)
				(type default)
			)
			(layer "F.SilkS")
		)
		(fp_line
			(start 0.7874 0.4064)
			(end -0.7874 0.4064)
			(stroke
				(width 0.1524)
				(type default)
			)
			(layer "F.SilkS")
		)
		(fp_line
			(start -0.67945 -0.305054)
			(end -0.12065 -0.305054)
			(stroke
				(width 0.1)
				(type default)
			)
			(layer "F.Fab")
		)
		(fp_line
			(start -0.67945 0.3048)
			(end -0.67945 -0.305054)
			(stroke
				(width 0.1)
				(type default)
			)
			(layer "F.Fab")
		)
		(fp_line
			(start -0.12065 -0.305054)
			(end -0.12065 -0.2794)
			(stroke
				(width 0.1)
				(type default)
			)
			(layer "F.Fab")
		)
		(fp_line
			(start -0.12065 -0.2794)
			(end 0.12065 -0.2794)
			(stroke
				(width 0.1)
				(type default)
			)
			(layer "F.Fab")
		)
		(fp_line
			(start -0.12065 0.2794)
			(end -0.12065 0.3048)
			(stroke
				(width 0.1)
				(type default)
			)
			(layer "F.Fab")
		)
		(fp_line
			(start -0.12065 0.3048)
			(end -0.67945 0.3048)
			(stroke
				(width 0.1)
				(type default)
			)
			(layer "F.Fab")
		)
		(fp_line
			(start 0.120396 0.2794)
			(end -0.12065 0.2794)
			(stroke
				(width 0.1)
				(type default)
			)
			(layer "F.Fab")
		)
		(fp_line
			(start 0.120396 0.3048)
			(end 0.120396 0.2794)
			(stroke
				(width 0.1)
				(type default)
			)
			(layer "F.Fab")
		)
		(fp_line
			(start 0.12065 -0.3048)
			(end 0.67945 -0.3048)
			(stroke
				(width 0.1)
				(type default)
			)
			(layer "F.Fab")
		)
		(fp_line
			(start 0.12065 -0.2794)
			(end 0.12065 -0.3048)
			(stroke
				(width 0.1)
				(type default)
			)
			(layer "F.Fab")
		)
		(fp_line
			(start 0.67945 -0.3048)
			(end 0.67945 0.3048)
			(stroke
				(width 0.1)
				(type default)
			)
			(layer "F.Fab")
		)
		(fp_line
			(start 0.67945 0.3048)
			(end 0.120396 0.3048)
			(stroke
				(width 0.1)
				(type default)
			)
			(layer "F.Fab")
		)
		(pad "1" smd circle
			(at -0.40005 0)
			(size 0 0)
			(layers "F.Cu" "F.Mask" "F.Paste")
			(net "SWB_HSC_EN_BUF_R")
		)
		(pad "2" smd circle
			(at 0.40005 0)
			(size 0 0)
			(layers "F.Cu" "F.Mask" "F.Paste")
			(net "SWB_HSC_EN_BUF")
		)
	)
	(footprint ""
		(layer "F.Cu")
		(at 36.930584 -109.571282)
		(property "Reference" "C2049"
			(at 0 0 0)
			(layer "F.SilkS")
			(hide yes)
			(effects
				(font
					(size 1.27 1.27)
				)
			)
		)
		(property "Value" ""
			(at 0 0 0)
			(layer "F.Fab")
			(effects
				(font
					(size 1.27 1.27)
				)
			)
		)
		(duplicate_pad_numbers_are_jumpers no)
		(fp_line
			(start -0.7874 -0.4064)
			(end 0.7874 -0.4064)
			(stroke
				(width 0.1524)
				(type default)
			)
			(layer "F.SilkS")
		)
		(fp_line
			(start -0.7874 0.4064)
			(end -0.7874 -0.4064)
			(stroke
				(width 0.1524)
				(type default)
			)
			(layer "F.SilkS")
		)
		(fp_line
			(start 0.7874 -0.4064)
			(end 0.7874 0.4064)
			(stroke
				(width 0.1524)
				(type default)
			)
			(layer "F.SilkS")
		)
		(fp_line
			(start 0.7874 0.4064)
			(end -0.7874 0.4064)
			(stroke
				(width 0.1524)
				(type default)
			)
			(layer "F.SilkS")
		)
		(fp_line
			(start -0.67945 -0.305054)
			(end -0.12065 -0.305054)
			(stroke
				(width 0.1)
				(type default)
			)
			(layer "F.Fab")
		)
		(fp_line
			(start -0.67945 0.3048)
			(end -0.67945 -0.305054)
			(stroke
				(width 0.1)
				(type default)
			)
			(layer "F.Fab")
		)
		(fp_line
			(start -0.12065 -0.305054)
			(end -0.12065 -0.2794)
			(stroke
				(width 0.1)
				(type default)
			)
			(layer "F.Fab")
		)
		(fp_line
			(start -0.12065 -0.2794)
			(end 0.12065 -0.2794)
			(stroke
				(width 0.1)
				(type default)
			)
			(layer "F.Fab")
		)
		(fp_line
			(start -0.12065 0.2794)
			(end -0.12065 0.3048)
			(stroke
				(width 0.1)
				(type default)
			)
			(layer "F.Fab")
		)
		(fp_line
			(start -0.12065 0.3048)
			(end -0.67945 0.3048)
			(stroke
				(width 0.1)
				(type default)
			)
			(layer "F.Fab")
		)
		(fp_line
			(start 0.120396 0.2794)
			(end -0.12065 0.2794)
			(stroke
				(width 0.1)
				(type default)
			)
			(layer "F.Fab")
		)
		(fp_line
			(start 0.120396 0.3048)
			(end 0.120396 0.2794)
			(stroke
				(width 0.1)
				(type default)
			)
			(layer "F.Fab")
		)
		(fp_line
			(start 0.12065 -0.3048)
			(end 0.67945 -0.3048)
			(stroke
				(width 0.1)
				(type default)
			)
			(layer "F.Fab")
		)
		(fp_line
			(start 0.12065 -0.2794)
			(end 0.12065 -0.3048)
			(stroke
				(width 0.1)
				(type default)
			)
			(layer "F.Fab")
		)
		(fp_line
			(start 0.67945 -0.3048)
			(end 0.67945 0.3048)
			(stroke
				(width 0.1)
				(type default)
			)
			(layer "F.Fab")
		)
		(fp_line
			(start 0.67945 0.3048)
			(end 0.120396 0.3048)
			(stroke
				(width 0.1)
				(type default)
			)
			(layer "F.Fab")
		)
		(pad "1" smd circle
			(at -0.40005 0)
			(size 0 0)
			(layers "F.Cu" "F.Mask" "F.Paste")
			(net "P5V_ADC_TIC")
		)
		(pad "2" smd circle
			(at 0.40005 0)
			(size 0 0)
			(layers "F.Cu" "F.Mask" "F.Paste")
			(net "GND")
		)
	)
	(footprint ""
		(layer "F.Cu")
		(at 107.28833 -241.97691 -90)
		(property "Reference" "C284"
			(at 0 0 270)
			(layer "F.SilkS")
			(hide yes)
			(effects
				(font
					(size 1.27 1.27)
				)
			)
		)
		(property "Value" ""
			(at 0 0 270)
			(layer "F.Fab")
			(effects
				(font
					(size 1.27 1.27)
				)
			)
		)
		(duplicate_pad_numbers_are_jumpers no)
		(fp_line
			(start -0.7874 0.4064)
			(end -0.7874 -0.4064)
			(stroke
				(width 0.1524)
				(type default)
			)
			(layer "F.SilkS")
		)
		(fp_line
			(start 0.7874 0.4064)
			(end -0.7874 0.4064)
			(stroke
				(width 0.1524)
				(type default)
			)
			(layer "F.SilkS")
		)
		(fp_line
			(start -0.7874 -0.4064)
			(end 0.7874 -0.4064)
			(stroke
				(width 0.1524)
				(type default)
			)
			(layer "F.SilkS")
		)
		(fp_line
			(start 0.7874 -0.4064)
			(end 0.7874 0.4064)
			(stroke
				(width 0.1524)
				(type default)
			)
			(layer "F.SilkS")
		)
		(fp_line
			(start -0.67945 0.3048)
			(end -0.67945 -0.305054)
			(stroke
				(width 0.1)
				(type default)
			)
			(layer "F.Fab")
		)
		(fp_line
			(start -0.12065 0.3048)
			(end -0.67945 0.3048)
			(stroke
				(width 0.1)
				(type default)
			)
			(layer "F.Fab")
		)
		(fp_line
			(start 0.120396 0.3048)
			(end 0.120396 0.2794)
			(stroke
				(width 0.1)
				(type default)
			)
			(layer "F.Fab")
		)
		(fp_line
			(start 0.67945 0.3048)
			(end 0.120396 0.3048)
			(stroke
				(width 0.1)
				(type default)
			)
			(layer "F.Fab")
		)
		(fp_line
			(start -0.12065 0.2794)
			(end -0.12065 0.3048)
			(stroke
				(width 0.1)
				(type default)
			)
			(layer "F.Fab")
		)
		(fp_line
			(start 0.120396 0.2794)
			(end -0.12065 0.2794)
			(stroke
				(width 0.1)
				(type default)
			)
			(layer "F.Fab")
		)
		(fp_line
			(start -0.12065 -0.2794)
			(end 0.12065 -0.2794)
			(stroke
				(width 0.1)
				(type default)
			)
			(layer "F.Fab")
		)
		(fp_line
			(start 0.12065 -0.2794)
			(end 0.12065 -0.3048)
			(stroke
				(width 0.1)
				(type default)
			)
			(layer "F.Fab")
		)
		(fp_line
			(start 0.12065 -0.3048)
			(end 0.67945 -0.3048)
			(stroke
				(width 0.1)
				(type default)
			)
			(layer "F.Fab")
		)
		(fp_line
			(start 0.67945 -0.3048)
			(end 0.67945 0.3048)
			(stroke
				(width 0.1)
				(type default)
			)
			(layer "F.Fab")
		)
		(fp_line
			(start -0.67945 -0.305054)
			(end -0.12065 -0.305054)
			(stroke
				(width 0.1)
				(type default)
			)
			(layer "F.Fab")
		)
		(fp_line
			(start -0.12065 -0.305054)
			(end -0.12065 -0.2794)
			(stroke
				(width 0.1)
				(type default)
			)
			(layer "F.Fab")
		)
		(pad "1" smd circle
			(at -0.40005 0 270)
			(size 0 0)
			(layers "F.Cu" "F.Mask" "F.Paste")
			(net "PVCCIN_CPU1")
		)
		(pad "2" smd circle
			(at 0.40005 0 270)
			(size 0 0)
			(layers "F.Cu" "F.Mask" "F.Paste")
			(net "GND")
		)
	)
	(footprint ""
		(layer "F.Cu")
		(at 448.61988 -94.602808 180)
		(property "Reference" "R4094"
			(at 0 0 180)
			(layer "F.SilkS")
			(hide yes)
			(effects
				(font
					(size 1.27 1.27)
				)
			)
		)
		(property "Value" ""
			(at 0 0 180)
			(layer "F.Fab")
			(effects
				(font
					(size 1.27 1.27)
				)
			)
		)
		(duplicate_pad_numbers_are_jumpers no)
		(fp_line
			(start 0.7874 0.4064)
			(end -0.7874 0.4064)
			(stroke
				(width 0.1524)
				(type default)
			)
			(layer "F.SilkS")
		)
		(fp_line
			(start 0.7874 -0.4064)
			(end 0.7874 0.4064)
			(stroke
				(width 0.1524)
				(type default)
			)
			(layer "F.SilkS")
		)
		(fp_line
			(start -0.7874 0.4064)
			(end -0.7874 -0.4064)
			(stroke
				(width 0.1524)
				(type default)
			)
			(layer "F.SilkS")
		)
		(fp_line
			(start -0.7874 -0.4064)
			(end 0.7874 -0.4064)
			(stroke
				(width 0.1524)
				(type default)
			)
			(layer "F.SilkS")
		)
		(fp_line
			(start 0.67945 0.3048)
			(end 0.120396 0.3048)
			(stroke
				(width 0.1)
				(type default)
			)
			(layer "F.Fab")
		)
		(fp_line
			(start 0.67945 -0.3048)
			(end 0.67945 0.3048)
			(stroke
				(width 0.1)
				(type default)
			)
			(layer "F.Fab")
		)
		(fp_line
			(start 0.12065 -0.2794)
			(end 0.12065 -0.3048)
			(stroke
				(width 0.1)
				(type default)
			)
			(layer "F.Fab")
		)
		(fp_line
			(start 0.12065 -0.3048)
			(end 0.67945 -0.3048)
			(stroke
				(width 0.1)
				(type default)
			)
			(layer "F.Fab")
		)
		(fp_line
			(start 0.120396 0.3048)
			(end 0.120396 0.2794)
			(stroke
				(width 0.1)
				(type default)
			)
			(layer "F.Fab")
		)
		(fp_line
			(start 0.120396 0.2794)
			(end -0.12065 0.2794)
			(stroke
				(width 0.1)
				(type default)
			)
			(layer "F.Fab")
		)
		(fp_line
			(start -0.12065 0.3048)
			(end -0.67945 0.3048)
			(stroke
				(width 0.1)
				(type default)
			)
			(layer "F.Fab")
		)
		(fp_line
			(start -0.12065 0.2794)
			(end -0.12065 0.3048)
			(stroke
				(width 0.1)
				(type default)
			)
			(layer "F.Fab")
		)
		(fp_line
			(start -0.12065 -0.2794)
			(end 0.12065 -0.2794)
			(stroke
				(width 0.1)
				(type default)
			)
			(layer "F.Fab")
		)
		(fp_line
			(start -0.12065 -0.305054)
			(end -0.12065 -0.2794)
			(stroke
				(width 0.1)
				(type default)
			)
			(layer "F.Fab")
		)
		(fp_line
			(start -0.67945 0.3048)
			(end -0.67945 -0.305054)
			(stroke
				(width 0.1)
				(type default)
			)
			(layer "F.Fab")
		)
		(fp_line
			(start -0.67945 -0.305054)
			(end -0.12065 -0.305054)
			(stroke
				(width 0.1)
				(type default)
			)
			(layer "F.Fab")
		)
		(pad "1" smd circle
			(at -0.40005 0 180)
			(size 0 0)
			(layers "F.Cu" "F.Mask" "F.Paste")
			(net "P3V3_AUX")
		)
		(pad "2" smd circle
			(at 0.40005 0 180)
			(size 0 0)
			(layers "F.Cu" "F.Mask" "F.Paste")
			(net "OCP_SFF_P3V3_ADC_ALERT_R")
		)
	)
	(footprint ""
		(layer "F.Cu")
		(at 36.930584 -107.539282)
		(property "Reference" "C2047"
			(at 0 0 0)
			(layer "F.SilkS")
			(hide yes)
			(effects
				(font
					(size 1.27 1.27)
				)
			)
		)
		(property "Value" ""
			(at 0 0 0)
			(layer "F.Fab")
			(effects
				(font
					(size 1.27 1.27)
				)
			)
		)
		(duplicate_pad_numbers_are_jumpers no)
		(fp_line
			(start -0.7874 -0.4064)
			(end 0.7874 -0.4064)
			(stroke
				(width 0.1524)
				(type default)
			)
			(layer "F.SilkS")
		)
		(fp_line
			(start -0.7874 0.4064)
			(end -0.7874 -0.4064)
			(stroke
				(width 0.1524)
				(type default)
			)
			(layer "F.SilkS")
		)
		(fp_line
			(start 0.7874 -0.4064)
			(end 0.7874 0.4064)
			(stroke
				(width 0.1524)
				(type default)
			)
			(layer "F.SilkS")
		)
		(fp_line
			(start 0.7874 0.4064)
			(end -0.7874 0.4064)
			(stroke
				(width 0.1524)
				(type default)
			)
			(layer "F.SilkS")
		)
		(fp_line
			(start -0.67945 -0.305054)
			(end -0.12065 -0.305054)
			(stroke
				(width 0.1)
				(type default)
			)
			(layer "F.Fab")
		)
		(fp_line
			(start -0.67945 0.3048)
			(end -0.67945 -0.305054)
			(stroke
				(width 0.1)
				(type default)
			)
			(layer "F.Fab")
		)
		(fp_line
			(start -0.12065 -0.305054)
			(end -0.12065 -0.2794)
			(stroke
				(width 0.1)
				(type default)
			)
			(layer "F.Fab")
		)
		(fp_line
			(start -0.12065 -0.2794)
			(end 0.12065 -0.2794)
			(stroke
				(width 0.1)
				(type default)
			)
			(layer "F.Fab")
		)
		(fp_line
			(start -0.12065 0.2794)
			(end -0.12065 0.3048)
			(stroke
				(width 0.1)
				(type default)
			)
			(layer "F.Fab")
		)
		(fp_line
			(start -0.12065 0.3048)
			(end -0.67945 0.3048)
			(stroke
				(width 0.1)
				(type default)
			)
			(layer "F.Fab")
		)
		(fp_line
			(start 0.120396 0.2794)
			(end -0.12065 0.2794)
			(stroke
				(width 0.1)
				(type default)
			)
			(layer "F.Fab")
		)
		(fp_line
			(start 0.120396 0.3048)
			(end 0.120396 0.2794)
			(stroke
				(width 0.1)
				(type default)
			)
			(layer "F.Fab")
		)
		(fp_line
			(start 0.12065 -0.3048)
			(end 0.67945 -0.3048)
			(stroke
				(width 0.1)
				(type default)
			)
			(layer "F.Fab")
		)
		(fp_line
			(start 0.12065 -0.2794)
			(end 0.12065 -0.3048)
			(stroke
				(width 0.1)
				(type default)
			)
			(layer "F.Fab")
		)
		(fp_line
			(start 0.67945 -0.3048)
			(end 0.67945 0.3048)
			(stroke
				(width 0.1)
				(type default)
			)
			(layer "F.Fab")
		)
		(fp_line
			(start 0.67945 0.3048)
			(end 0.120396 0.3048)
			(stroke
				(width 0.1)
				(type default)
			)
			(layer "F.Fab")
		)
		(pad "1" smd circle
			(at -0.40005 0)
			(size 0 0)
			(layers "F.Cu" "F.Mask" "F.Paste")
			(net "P3V3_AUX_ADC_TIC")
		)
		(pad "2" smd circle
			(at 0.40005 0)
			(size 0 0)
			(layers "F.Cu" "F.Mask" "F.Paste")
			(net "GND")
		)
	)
	(footprint ""
		(layer "F.Cu")
		(at 140.562076 -113.384584)
		(property "Reference" "U335"
			(at 0.4572 2.244852 0)
			(unlocked yes)
			(layer "F.SilkS")
			(effects
				(font
					(size 0.7874 0.5842)
					(thickness 0.1524)
				)
				(justify left)
			)
		)
		(property "Value" ""
			(at 0 0 0)
			(layer "F.Fab")
			(effects
				(font
					(size 1.27 1.27)
				)
			)
		)
		(duplicate_pad_numbers_are_jumpers no)
		(fp_line
			(start -1.733296 -1.549908)
			(end -1.733296 1.549908)
			(stroke
				(width 0.1524)
				(type default)
			)
			(layer "F.SilkS")
		)
		(fp_line
			(start -1.733296 1.549908)
			(end 1.733296 1.549908)
			(stroke
				(width 0.1524)
				(type default)
			)
			(layer "F.SilkS")
		)
		(fp_line
			(start -0.660908 -1.549908)
			(end -1.733296 -1.549908)
			(stroke
				(width 0.1524)
				(type default)
			)
			(layer "F.SilkS")
		)
		(fp_line
			(start 0 -0.889)
			(end -0.660908 -1.549908)
			(stroke
				(width 0.1524)
				(type default)
			)
			(layer "F.SilkS")
		)
		(fp_line
			(start 0.660908 -1.549908)
			(end 0 -0.889)
			(stroke
				(width 0.1524)
				(type default)
			)
			(layer "F.SilkS")
		)
		(fp_line
			(start 1.733296 -1.549908)
			(end 0.660908 -1.549908)
			(stroke
				(width 0.1524)
				(type default)
			)
			(layer "F.SilkS")
		)
		(fp_line
			(start 1.733296 1.549908)
			(end 1.733296 -1.549908)
			(stroke
				(width 0.1524)
				(type default)
			)
			(layer "F.SilkS")
		)
		(fp_poly
			(pts
				(xy -2.064512 -1.853438) (xy -2.423922 -1.494282) (xy -1.884934 -1.314704)
			)
			(stroke
				(width 0)
				(type default)
			)
			(fill yes)
			(layer "F.SilkS")
		)
		(fp_line
			(start -0.849884 -1.549908)
			(end -0.849884 1.549908)
			(stroke
				(width 0.1)
				(type default)
			)
			(layer "F.Fab")
		)
		(fp_line
			(start -0.849884 1.549908)
			(end 0.849884 1.549908)
			(stroke
				(width 0.1)
				(type default)
			)
			(layer "F.Fab")
		)
		(fp_line
			(start 0.849884 -1.549908)
			(end -0.849884 -1.549908)
			(stroke
				(width 0.1)
				(type default)
			)
			(layer "F.Fab")
		)
		(fp_line
			(start 0.849884 1.549908)
			(end 0.849884 -1.549908)
			(stroke
				(width 0.1)
				(type default)
			)
			(layer "F.Fab")
		)
		(fp_poly
			(pts
				(xy -2.4384 -1.20396) (xy -2.4384 -0.69596) (xy -1.9304 -0.94996)
			)
			(stroke
				(width 0)
				(type default)
			)
			(fill yes)
			(layer "F.Fab")
		)
		(pad "1" smd rect
			(at -1.199896 -0.94996 270)
			(size 0.5588 0.8128)
			(layers "F.Cu" "F.Mask" "F.Paste")
			(net "HP_LVC3_OCP_V3_2_PWRGD_R2")
		)
		(pad "2" smd rect
			(at -1.199896 0 270)
			(size 0.5588 0.8128)
			(layers "F.Cu" "F.Mask" "F.Paste")
			(net "OCP_V3_2_AUX_PWR_PLD_EN_R")
		)
		(pad "3" smd rect
			(at -1.199896 0.94996 270)
			(size 0.5588 0.8128)
			(layers "F.Cu" "F.Mask" "F.Paste")
			(net "GND")
		)
		(pad "4" smd rect
			(at 1.199896 0.94996 270)
			(size 0.5588 0.8128)
			(layers "F.Cu" "F.Mask" "F.Paste")
			(net "OCP_V3_2_AUX_PWR_EN_R2")
		)
		(pad "5" smd rect
			(at 1.199896 -0.94996 270)
			(size 0.5588 0.8128)
			(layers "F.Cu" "F.Mask" "F.Paste")
			(net "P3V3_AUX")
		)
	)
	(footprint ""
		(layer "F.Cu")
		(at 364.50143 -258.726686 90)
		(property "Reference" "C968"
			(at 0 0 90)
			(layer "F.SilkS")
			(hide yes)
			(effects
				(font
					(size 1.27 1.27)
				)
			)
		)
		(property "Value" ""
			(at 0 0 90)
			(layer "F.Fab")
			(effects
				(font
					(size 1.27 1.27)
				)
			)
		)
		(duplicate_pad_numbers_are_jumpers no)
		(fp_line
			(start 0.7874 -0.4064)
			(end 0.7874 0.4064)
			(stroke
				(width 0.1524)
				(type default)
			)
			(layer "F.SilkS")
		)
		(fp_line
			(start -0.7874 -0.4064)
			(end 0.7874 -0.4064)
			(stroke
				(width 0.1524)
				(type default)
			)
			(layer "F.SilkS")
		)
		(fp_line
			(start 0.7874 0.4064)
			(end -0.7874 0.4064)
			(stroke
				(width 0.1524)
				(type default)
			)
			(layer "F.SilkS")
		)
		(fp_line
			(start -0.7874 0.4064)
			(end -0.7874 -0.4064)
			(stroke
				(width 0.1524)
				(type default)
			)
			(layer "F.SilkS")
		)
		(fp_line
			(start -0.12065 -0.305054)
			(end -0.12065 -0.2794)
			(stroke
				(width 0.1)
				(type default)
			)
			(layer "F.Fab")
		)
		(fp_line
			(start -0.67945 -0.305054)
			(end -0.12065 -0.305054)
			(stroke
				(width 0.1)
				(type default)
			)
			(layer "F.Fab")
		)
		(fp_line
			(start 0.67945 -0.3048)
			(end 0.67945 0.3048)
			(stroke
				(width 0.1)
				(type default)
			)
			(layer "F.Fab")
		)
		(fp_line
			(start 0.12065 -0.3048)
			(end 0.67945 -0.3048)
			(stroke
				(width 0.1)
				(type default)
			)
			(layer "F.Fab")
		)
		(fp_line
			(start 0.12065 -0.2794)
			(end 0.12065 -0.3048)
			(stroke
				(width 0.1)
				(type default)
			)
			(layer "F.Fab")
		)
		(fp_line
			(start -0.12065 -0.2794)
			(end 0.12065 -0.2794)
			(stroke
				(width 0.1)
				(type default)
			)
			(layer "F.Fab")
		)
		(fp_line
			(start 0.120396 0.2794)
			(end -0.12065 0.2794)
			(stroke
				(width 0.1)
				(type default)
			)
			(layer "F.Fab")
		)
		(fp_line
			(start -0.12065 0.2794)
			(end -0.12065 0.3048)
			(stroke
				(width 0.1)
				(type default)
			)
			(layer "F.Fab")
		)
		(fp_line
			(start 0.67945 0.3048)
			(end 0.120396 0.3048)
			(stroke
				(width 0.1)
				(type default)
			)
			(layer "F.Fab")
		)
		(fp_line
			(start 0.120396 0.3048)
			(end 0.120396 0.2794)
			(stroke
				(width 0.1)
				(type default)
			)
			(layer "F.Fab")
		)
		(fp_line
			(start -0.12065 0.3048)
			(end -0.67945 0.3048)
			(stroke
				(width 0.1)
				(type default)
			)
			(layer "F.Fab")
		)
		(fp_line
			(start -0.67945 0.3048)
			(end -0.67945 -0.305054)
			(stroke
				(width 0.1)
				(type default)
			)
			(layer "F.Fab")
		)
		(pad "1" smd circle
			(at -0.40005 0 90)
			(size 0 0)
			(layers "F.Cu" "F.Mask" "F.Paste")
			(net "PVCCIN_CPU0")
		)
		(pad "2" smd circle
			(at 0.40005 0 90)
			(size 0 0)
			(layers "F.Cu" "F.Mask" "F.Paste")
			(net "GND")
		)
	)
	(footprint ""
		(layer "F.Cu")
		(at 351.116138 -354.483162 90)
		(property "Reference" "R4216"
			(at 0 0 90)
			(layer "F.SilkS")
			(hide yes)
			(effects
				(font
					(size 1.27 1.27)
				)
			)
		)
		(property "Value" ""
			(at 0 0 90)
			(layer "F.Fab")
			(effects
				(font
					(size 1.27 1.27)
				)
			)
		)
		(duplicate_pad_numbers_are_jumpers no)
		(fp_line
			(start 0.7874 -0.4064)
			(end 0.7874 0.4064)
			(stroke
				(width 0.1524)
				(type default)
			)
			(layer "F.SilkS")
		)
		(fp_line
			(start -0.7874 -0.4064)
			(end 0.7874 -0.4064)
			(stroke
				(width 0.1524)
				(type default)
			)
			(layer "F.SilkS")
		)
		(fp_line
			(start 0.7874 0.4064)
			(end -0.7874 0.4064)
			(stroke
				(width 0.1524)
				(type default)
			)
			(layer "F.SilkS")
		)
		(fp_line
			(start -0.7874 0.4064)
			(end -0.7874 -0.4064)
			(stroke
				(width 0.1524)
				(type default)
			)
			(layer "F.SilkS")
		)
		(fp_line
			(start -0.12065 -0.305054)
			(end -0.12065 -0.2794)
			(stroke
				(width 0.1)
				(type default)
			)
			(layer "F.Fab")
		)
		(fp_line
			(start -0.67945 -0.305054)
			(end -0.12065 -0.305054)
			(stroke
				(width 0.1)
				(type default)
			)
			(layer "F.Fab")
		)
		(fp_line
			(start 0.67945 -0.3048)
			(end 0.67945 0.3048)
			(stroke
				(width 0.1)
				(type default)
			)
			(layer "F.Fab")
		)
		(fp_line
			(start 0.12065 -0.3048)
			(end 0.67945 -0.3048)
			(stroke
				(width 0.1)
				(type default)
			)
			(layer "F.Fab")
		)
		(fp_line
			(start 0.12065 -0.2794)
			(end 0.12065 -0.3048)
			(stroke
				(width 0.1)
				(type default)
			)
			(layer "F.Fab")
		)
		(fp_line
			(start -0.12065 -0.2794)
			(end 0.12065 -0.2794)
			(stroke
				(width 0.1)
				(type default)
			)
			(layer "F.Fab")
		)
		(fp_line
			(start 0.120396 0.2794)
			(end -0.12065 0.2794)
			(stroke
				(width 0.1)
				(type default)
			)
			(layer "F.Fab")
		)
		(fp_line
			(start -0.12065 0.2794)
			(end -0.12065 0.3048)
			(stroke
				(width 0.1)
				(type default)
			)
			(layer "F.Fab")
		)
		(fp_line
			(start 0.67945 0.3048)
			(end 0.120396 0.3048)
			(stroke
				(width 0.1)
				(type default)
			)
			(layer "F.Fab")
		)
		(fp_line
			(start 0.120396 0.3048)
			(end 0.120396 0.2794)
			(stroke
				(width 0.1)
				(type default)
			)
			(layer "F.Fab")
		)
		(fp_line
			(start -0.12065 0.3048)
			(end -0.67945 0.3048)
			(stroke
				(width 0.1)
				(type default)
			)
			(layer "F.Fab")
		)
		(fp_line
			(start -0.67945 0.3048)
			(end -0.67945 -0.305054)
			(stroke
				(width 0.1)
				(type default)
			)
			(layer "F.Fab")
		)
		(pad "1" smd circle
			(at -0.40005 0 90)
			(size 0 0)
			(layers "F.Cu" "F.Mask" "F.Paste")
			(net "FM_PVCCFA_EHV_FIVRA_CPU0_EN")
		)
		(pad "2" smd circle
			(at 0.40005 0 90)
			(size 0 0)
			(layers "F.Cu" "F.Mask" "F.Paste")
			(net "PVCCFA_EHV_FIVRA_CPU0_EN_R")
		)
	)
	(footprint ""
		(layer "F.Cu")
		(at 410.488384 -17.612614 90)
		(property "Reference" "C853"
			(at 0 0 90)
			(layer "F.SilkS")
			(hide yes)
			(effects
				(font
					(size 1.27 1.27)
				)
			)
		)
		(property "Value" ""
			(at 0 0 90)
			(layer "F.Fab")
			(effects
				(font
					(size 1.27 1.27)
				)
			)
		)
		(duplicate_pad_numbers_are_jumpers no)
		(fp_line
			(start 0.299974 -0.150114)
			(end 0.299974 0.150114)
			(stroke
				(width 0.1)
				(type default)
			)
			(layer "F.Fab")
		)
		(fp_line
			(start -0.299974 -0.150114)
			(end 0.299974 -0.150114)
			(stroke
				(width 0.1)
				(type default)
			)
			(layer "F.Fab")
		)
		(fp_line
			(start 0.299974 0.150114)
			(end -0.299974 0.150114)
			(stroke
				(width 0.1)
				(type default)
			)
			(layer "F.Fab")
		)
		(fp_line
			(start -0.299974 0.150114)
			(end -0.299974 -0.150114)
			(stroke
				(width 0.1)
				(type default)
			)
			(layer "F.Fab")
		)
		(pad "1" smd rect
			(at -0.2667 0 90)
			(size 0.3048 0.381)
			(layers "F.Cu" "F.Mask" "F.Paste")
			(net "P5E_CPU0_PE1_TX_C_DP<8>")
		)
		(pad "2" smd rect
			(at 0.2667 0 90)
			(size 0.3048 0.381)
			(layers "F.Cu" "F.Mask" "F.Paste")
			(net "P5E_CPU0_PE1_TX_DP<8>")
		)
	)
	(footprint ""
		(layer "F.Cu")
		(at 19.927824 -396.011908 90)
		(property "Reference" "C1871"
			(at 0 0 90)
			(layer "F.SilkS")
			(hide yes)
			(effects
				(font
					(size 1.27 1.27)
				)
			)
		)
		(property "Value" ""
			(at 0 0 90)
			(layer "F.Fab")
			(effects
				(font
					(size 1.27 1.27)
				)
			)
		)
		(duplicate_pad_numbers_are_jumpers no)
		(fp_line
			(start 0.7874 -0.4064)
			(end 0.7874 0.4064)
			(stroke
				(width 0.1524)
				(type default)
			)
			(layer "F.SilkS")
		)
		(fp_line
			(start -0.7874 -0.4064)
			(end -0.018288 -0.4064)
			(stroke
				(width 0.1524)
				(type default)
			)
			(layer "F.SilkS")
		)
		(fp_line
			(start 0.7874 0.4064)
			(end -0.7874 0.4064)
			(stroke
				(width 0.1524)
				(type default)
			)
			(layer "F.SilkS")
		)
		(fp_line
			(start 0.6858 -0.3048)
			(end 0.6858 0.3048)
			(stroke
				(width 0.1)
				(type default)
			)
			(layer "F.Fab")
		)
		(fp_line
			(start 0.1016 -0.3048)
			(end 0.6858 -0.3048)
			(stroke
				(width 0.1)
				(type default)
			)
			(layer "F.Fab")
		)
		(fp_line
			(start -0.1016 -0.3048)
			(end -0.1016 -0.2794)
			(stroke
				(width 0.1)
				(type default)
			)
			(layer "F.Fab")
		)
		(fp_line
			(start -0.6858 -0.3048)
			(end -0.1016 -0.3048)
			(stroke
				(width 0.1)
				(type default)
			)
			(layer "F.Fab")
		)
		(fp_line
			(start 0.1016 -0.2794)
			(end 0.1016 -0.3048)
			(stroke
				(width 0.1)
				(type default)
			)
			(layer "F.Fab")
		)
		(fp_line
			(start -0.1016 -0.2794)
			(end 0.1016 -0.2794)
			(stroke
				(width 0.1)
				(type default)
			)
			(layer "F.Fab")
		)
		(fp_line
			(start 0.1016 0.2794)
			(end -0.1016 0.2794)
			(stroke
				(width 0.1)
				(type default)
			)
			(layer "F.Fab")
		)
		(fp_line
			(start -0.1016 0.2794)
			(end -0.1016 0.3048)
			(stroke
				(width 0.1)
				(type default)
			)
			(layer "F.Fab")
		)
		(fp_line
			(start 0.6858 0.3048)
			(end 0.1016 0.3048)
			(stroke
				(width 0.1)
				(type default)
			)
			(layer "F.Fab")
		)
		(fp_line
			(start 0.1016 0.3048)
			(end 0.1016 0.2794)
			(stroke
				(width 0.1)
				(type default)
			)
			(layer "F.Fab")
		)
		(fp_line
			(start -0.1016 0.3048)
			(end -0.6858 0.3048)
			(stroke
				(width 0.1)
				(type default)
			)
			(layer "F.Fab")
		)
		(fp_line
			(start -0.6858 0.3048)
			(end -0.6858 -0.3048)
			(stroke
				(width 0.1)
				(type default)
			)
			(layer "F.Fab")
		)
		(pad "1" smd rect
			(at -0.40005 0 270)
			(size 0.4572 0.508)
			(layers "F.Cu" "F.Mask" "F.Paste")
			(net "P2E_MB_BMC_TX_BUF_DN<0>")
		)
		(pad "2" smd rect
			(at 0.40005 0 270)
			(size 0.4572 0.508)
			(layers "F.Cu" "F.Mask" "F.Paste")
			(net "P2E_MB_BMC_TX_BUF_C_DN<0>")
		)
	)
	(footprint ""
		(layer "F.Cu")
		(at 54.995318 -402.371052 -90)
		(property "Reference" "C715"
			(at 0 0 270)
			(layer "F.SilkS")
			(hide yes)
			(effects
				(font
					(size 1.27 1.27)
				)
			)
		)
		(property "Value" ""
			(at 0 0 270)
			(layer "F.Fab")
			(effects
				(font
					(size 1.27 1.27)
				)
			)
		)
		(duplicate_pad_numbers_are_jumpers no)
		(fp_line
			(start -0.299974 0.150114)
			(end -0.299974 -0.150114)
			(stroke
				(width 0.1)
				(type default)
			)
			(layer "F.Fab")
		)
		(fp_line
			(start 0.299974 0.150114)
			(end -0.299974 0.150114)
			(stroke
				(width 0.1)
				(type default)
			)
			(layer "F.Fab")
		)
		(fp_line
			(start -0.299974 -0.150114)
			(end 0.299974 -0.150114)
			(stroke
				(width 0.1)
				(type default)
			)
			(layer "F.Fab")
		)
		(fp_line
			(start 0.299974 -0.150114)
			(end 0.299974 0.150114)
			(stroke
				(width 0.1)
				(type default)
			)
			(layer "F.Fab")
		)
		(pad "1" smd rect
			(at -0.2667 0 270)
			(size 0.3048 0.381)
			(layers "F.Cu" "F.Mask" "F.Paste")
			(net "P5E_CPU1_PE0_TX_C_DP<13>")
		)
		(pad "2" smd rect
			(at 0.2667 0 270)
			(size 0.3048 0.381)
			(layers "F.Cu" "F.Mask" "F.Paste")
			(net "P5E_CPU1_PE0_TX_DP<13>")
		)
	)
	(footprint ""
		(layer "F.Cu")
		(at 49.755552 -155.186634 90)
		(property "Reference" "PR1726"
			(at 0 0 90)
			(layer "F.SilkS")
			(hide yes)
			(effects
				(font
					(size 1.27 1.27)
				)
			)
		)
		(property "Value" ""
			(at 0 0 90)
			(layer "F.Fab")
			(effects
				(font
					(size 1.27 1.27)
				)
			)
		)
		(duplicate_pad_numbers_are_jumpers no)
		(fp_line
			(start 0.7874 -0.4064)
			(end 0.7874 0.4064)
			(stroke
				(width 0.1524)
				(type default)
			)
			(layer "F.SilkS")
		)
		(fp_line
			(start -0.7874 -0.4064)
			(end 0.7874 -0.4064)
			(stroke
				(width 0.1524)
				(type default)
			)
			(layer "F.SilkS")
		)
		(fp_line
			(start 0.7874 0.4064)
			(end -0.7874 0.4064)
			(stroke
				(width 0.1524)
				(type default)
			)
			(layer "F.SilkS")
		)
		(fp_line
			(start -0.7874 0.4064)
			(end -0.7874 -0.4064)
			(stroke
				(width 0.1524)
				(type default)
			)
			(layer "F.SilkS")
		)
		(fp_line
			(start -0.12065 -0.305054)
			(end -0.12065 -0.2794)
			(stroke
				(width 0.1)
				(type default)
			)
			(layer "F.Fab")
		)
		(fp_line
			(start -0.67945 -0.305054)
			(end -0.12065 -0.305054)
			(stroke
				(width 0.1)
				(type default)
			)
			(layer "F.Fab")
		)
		(fp_line
			(start 0.67945 -0.3048)
			(end 0.67945 0.3048)
			(stroke
				(width 0.1)
				(type default)
			)
			(layer "F.Fab")
		)
		(fp_line
			(start 0.12065 -0.3048)
			(end 0.67945 -0.3048)
			(stroke
				(width 0.1)
				(type default)
			)
			(layer "F.Fab")
		)
		(fp_line
			(start 0.12065 -0.2794)
			(end 0.12065 -0.3048)
			(stroke
				(width 0.1)
				(type default)
			)
			(layer "F.Fab")
		)
		(fp_line
			(start -0.12065 -0.2794)
			(end 0.12065 -0.2794)
			(stroke
				(width 0.1)
				(type default)
			)
			(layer "F.Fab")
		)
		(fp_line
			(start 0.120396 0.2794)
			(end -0.12065 0.2794)
			(stroke
				(width 0.1)
				(type default)
			)
			(layer "F.Fab")
		)
		(fp_line
			(start -0.12065 0.2794)
			(end -0.12065 0.3048)
			(stroke
				(width 0.1)
				(type default)
			)
			(layer "F.Fab")
		)
		(fp_line
			(start 0.67945 0.3048)
			(end 0.120396 0.3048)
			(stroke
				(width 0.1)
				(type default)
			)
			(layer "F.Fab")
		)
		(fp_line
			(start 0.120396 0.3048)
			(end 0.120396 0.2794)
			(stroke
				(width 0.1)
				(type default)
			)
			(layer "F.Fab")
		)
		(fp_line
			(start -0.12065 0.3048)
			(end -0.67945 0.3048)
			(stroke
				(width 0.1)
				(type default)
			)
			(layer "F.Fab")
		)
		(fp_line
			(start -0.67945 0.3048)
			(end -0.67945 -0.305054)
			(stroke
				(width 0.1)
				(type default)
			)
			(layer "F.Fab")
		)
		(pad "1" smd circle
			(at -0.40005 0 90)
			(size 0 0)
			(layers "F.Cu" "F.Mask" "F.Paste")
			(net "PVCCINFAON_CPU1_LSET1")
		)
		(pad "2" smd circle
			(at 0.40005 0 90)
			(size 0 0)
			(layers "F.Cu" "F.Mask" "F.Paste")
			(net "GND")
		)
	)
	(footprint ""
		(layer "F.Cu")
		(at 339.483446 -27.92603 -90)
		(property "Reference" "R770"
			(at 0 0 270)
			(layer "F.SilkS")
			(hide yes)
			(effects
				(font
					(size 1.27 1.27)
				)
			)
		)
		(property "Value" ""
			(at 0 0 270)
			(layer "F.Fab")
			(effects
				(font
					(size 1.27 1.27)
				)
			)
		)
		(duplicate_pad_numbers_are_jumpers no)
		(fp_line
			(start -0.7874 0.4064)
			(end -0.7874 -0.4064)
			(stroke
				(width 0.1524)
				(type default)
			)
			(layer "F.SilkS")
		)
		(fp_line
			(start 0.7874 0.4064)
			(end -0.7874 0.4064)
			(stroke
				(width 0.1524)
				(type default)
			)
			(layer "F.SilkS")
		)
		(fp_line
			(start -0.7874 -0.4064)
			(end 0.7874 -0.4064)
			(stroke
				(width 0.1524)
				(type default)
			)
			(layer "F.SilkS")
		)
		(fp_line
			(start 0.7874 -0.4064)
			(end 0.7874 0.4064)
			(stroke
				(width 0.1524)
				(type default)
			)
			(layer "F.SilkS")
		)
		(fp_line
			(start -0.67945 0.3048)
			(end -0.67945 -0.305054)
			(stroke
				(width 0.1)
				(type default)
			)
			(layer "F.Fab")
		)
		(fp_line
			(start -0.12065 0.3048)
			(end -0.67945 0.3048)
			(stroke
				(width 0.1)
				(type default)
			)
			(layer "F.Fab")
		)
		(fp_line
			(start 0.120396 0.3048)
			(end 0.120396 0.2794)
			(stroke
				(width 0.1)
				(type default)
			)
			(layer "F.Fab")
		)
		(fp_line
			(start 0.67945 0.3048)
			(end 0.120396 0.3048)
			(stroke
				(width 0.1)
				(type default)
			)
			(layer "F.Fab")
		)
		(fp_line
			(start -0.12065 0.2794)
			(end -0.12065 0.3048)
			(stroke
				(width 0.1)
				(type default)
			)
			(layer "F.Fab")
		)
		(fp_line
			(start 0.120396 0.2794)
			(end -0.12065 0.2794)
			(stroke
				(width 0.1)
				(type default)
			)
			(layer "F.Fab")
		)
		(fp_line
			(start -0.12065 -0.2794)
			(end 0.12065 -0.2794)
			(stroke
				(width 0.1)
				(type default)
			)
			(layer "F.Fab")
		)
		(fp_line
			(start 0.12065 -0.2794)
			(end 0.12065 -0.3048)
			(stroke
				(width 0.1)
				(type default)
			)
			(layer "F.Fab")
		)
		(fp_line
			(start 0.12065 -0.3048)
			(end 0.67945 -0.3048)
			(stroke
				(width 0.1)
				(type default)
			)
			(layer "F.Fab")
		)
		(fp_line
			(start 0.67945 -0.3048)
			(end 0.67945 0.3048)
			(stroke
				(width 0.1)
				(type default)
			)
			(layer "F.Fab")
		)
		(fp_line
			(start -0.67945 -0.305054)
			(end -0.12065 -0.305054)
			(stroke
				(width 0.1)
				(type default)
			)
			(layer "F.Fab")
		)
		(fp_line
			(start -0.12065 -0.305054)
			(end -0.12065 -0.2794)
			(stroke
				(width 0.1)
				(type default)
			)
			(layer "F.Fab")
		)
		(pad "1" smd circle
			(at -0.40005 0 270)
			(size 0 0)
			(layers "F.Cu" "F.Mask" "F.Paste")
			(net "PU_OC5_USB_N")
		)
		(pad "2" smd circle
			(at 0.40005 0 270)
			(size 0 0)
			(layers "F.Cu" "F.Mask" "F.Paste")
			(net "P3V3_AUX")
		)
	)
	(footprint ""
		(layer "F.Cu")
		(at 51.593496 -115.12677)
		(property "Reference" "R3724"
			(at 0 0 0)
			(layer "F.SilkS")
			(hide yes)
			(effects
				(font
					(size 1.27 1.27)
				)
			)
		)
		(property "Value" ""
			(at 0 0 0)
			(layer "F.Fab")
			(effects
				(font
					(size 1.27 1.27)
				)
			)
		)
		(duplicate_pad_numbers_are_jumpers no)
		(fp_line
			(start -0.7874 -0.4064)
			(end 0.7874 -0.4064)
			(stroke
				(width 0.1524)
				(type default)
			)
			(layer "F.SilkS")
		)
		(fp_line
			(start -0.7874 0.4064)
			(end -0.7874 -0.4064)
			(stroke
				(width 0.1524)
				(type default)
			)
			(layer "F.SilkS")
		)
		(fp_line
			(start 0.7874 -0.4064)
			(end 0.7874 0.4064)
			(stroke
				(width 0.1524)
				(type default)
			)
			(layer "F.SilkS")
		)
		(fp_line
			(start 0.7874 0.4064)
			(end -0.7874 0.4064)
			(stroke
				(width 0.1524)
				(type default)
			)
			(layer "F.SilkS")
		)
		(fp_line
			(start -0.67945 -0.305054)
			(end -0.12065 -0.305054)
			(stroke
				(width 0.1)
				(type default)
			)
			(layer "F.Fab")
		)
		(fp_line
			(start -0.67945 0.3048)
			(end -0.67945 -0.305054)
			(stroke
				(width 0.1)
				(type default)
			)
			(layer "F.Fab")
		)
		(fp_line
			(start -0.12065 -0.305054)
			(end -0.12065 -0.2794)
			(stroke
				(width 0.1)
				(type default)
			)
			(layer "F.Fab")
		)
		(fp_line
			(start -0.12065 -0.2794)
			(end 0.12065 -0.2794)
			(stroke
				(width 0.1)
				(type default)
			)
			(layer "F.Fab")
		)
		(fp_line
			(start -0.12065 0.2794)
			(end -0.12065 0.3048)
			(stroke
				(width 0.1)
				(type default)
			)
			(layer "F.Fab")
		)
		(fp_line
			(start -0.12065 0.3048)
			(end -0.67945 0.3048)
			(stroke
				(width 0.1)
				(type default)
			)
			(layer "F.Fab")
		)
		(fp_line
			(start 0.120396 0.2794)
			(end -0.12065 0.2794)
			(stroke
				(width 0.1)
				(type default)
			)
			(layer "F.Fab")
		)
		(fp_line
			(start 0.120396 0.3048)
			(end 0.120396 0.2794)
			(stroke
				(width 0.1)
				(type default)
			)
			(layer "F.Fab")
		)
		(fp_line
			(start 0.12065 -0.3048)
			(end 0.67945 -0.3048)
			(stroke
				(width 0.1)
				(type default)
			)
			(layer "F.Fab")
		)
		(fp_line
			(start 0.12065 -0.2794)
			(end 0.12065 -0.3048)
			(stroke
				(width 0.1)
				(type default)
			)
			(layer "F.Fab")
		)
		(fp_line
			(start 0.67945 -0.3048)
			(end 0.67945 0.3048)
			(stroke
				(width 0.1)
				(type default)
			)
			(layer "F.Fab")
		)
		(fp_line
			(start 0.67945 0.3048)
			(end 0.120396 0.3048)
			(stroke
				(width 0.1)
				(type default)
			)
			(layer "F.Fab")
		)
		(pad "1" smd circle
			(at -0.40005 0)
			(size 0 0)
			(layers "F.Cu" "F.Mask" "F.Paste")
			(net "P3V3_AUX")
		)
		(pad "2" smd circle
			(at 0.40005 0)
			(size 0 0)
			(layers "F.Cu" "F.Mask" "F.Paste")
			(net "SMB_VR_3V3AUX_SDA")
		)
	)
	(footprint ""
		(layer "F.Cu")
		(at 148.197824 -53.436012)
		(property "Reference" "R3610"
			(at 0 0 0)
			(layer "F.SilkS")
			(hide yes)
			(effects
				(font
					(size 1.27 1.27)
				)
			)
		)
		(property "Value" ""
			(at 0 0 0)
			(layer "F.Fab")
			(effects
				(font
					(size 1.27 1.27)
				)
			)
		)
		(duplicate_pad_numbers_are_jumpers no)
		(fp_line
			(start -0.7874 -0.4064)
			(end 0.7874 -0.4064)
			(stroke
				(width 0.1524)
				(type default)
			)
			(layer "F.SilkS")
		)
		(fp_line
			(start -0.7874 0.4064)
			(end -0.7874 -0.4064)
			(stroke
				(width 0.1524)
				(type default)
			)
			(layer "F.SilkS")
		)
		(fp_line
			(start 0.7874 -0.4064)
			(end 0.7874 0.4064)
			(stroke
				(width 0.1524)
				(type default)
			)
			(layer "F.SilkS")
		)
		(fp_line
			(start 0.7874 0.4064)
			(end -0.7874 0.4064)
			(stroke
				(width 0.1524)
				(type default)
			)
			(layer "F.SilkS")
		)
		(fp_line
			(start -0.67945 -0.305054)
			(end -0.12065 -0.305054)
			(stroke
				(width 0.1)
				(type default)
			)
			(layer "F.Fab")
		)
		(fp_line
			(start -0.67945 0.3048)
			(end -0.67945 -0.305054)
			(stroke
				(width 0.1)
				(type default)
			)
			(layer "F.Fab")
		)
		(fp_line
			(start -0.12065 -0.305054)
			(end -0.12065 -0.2794)
			(stroke
				(width 0.1)
				(type default)
			)
			(layer "F.Fab")
		)
		(fp_line
			(start -0.12065 -0.2794)
			(end 0.12065 -0.2794)
			(stroke
				(width 0.1)
				(type default)
			)
			(layer "F.Fab")
		)
		(fp_line
			(start -0.12065 0.2794)
			(end -0.12065 0.3048)
			(stroke
				(width 0.1)
				(type default)
			)
			(layer "F.Fab")
		)
		(fp_line
			(start -0.12065 0.3048)
			(end -0.67945 0.3048)
			(stroke
				(width 0.1)
				(type default)
			)
			(layer "F.Fab")
		)
		(fp_line
			(start 0.120396 0.2794)
			(end -0.12065 0.2794)
			(stroke
				(width 0.1)
				(type default)
			)
			(layer "F.Fab")
		)
		(fp_line
			(start 0.120396 0.3048)
			(end 0.120396 0.2794)
			(stroke
				(width 0.1)
				(type default)
			)
			(layer "F.Fab")
		)
		(fp_line
			(start 0.12065 -0.3048)
			(end 0.67945 -0.3048)
			(stroke
				(width 0.1)
				(type default)
			)
			(layer "F.Fab")
		)
		(fp_line
			(start 0.12065 -0.2794)
			(end 0.12065 -0.3048)
			(stroke
				(width 0.1)
				(type default)
			)
			(layer "F.Fab")
		)
		(fp_line
			(start 0.67945 -0.3048)
			(end 0.67945 0.3048)
			(stroke
				(width 0.1)
				(type default)
			)
			(layer "F.Fab")
		)
		(fp_line
			(start 0.67945 0.3048)
			(end 0.120396 0.3048)
			(stroke
				(width 0.1)
				(type default)
			)
			(layer "F.Fab")
		)
		(pad "1" smd circle
			(at -0.40005 0)
			(size 0 0)
			(layers "F.Cu" "F.Mask" "F.Paste")
			(net "GND")
		)
		(pad "2" smd circle
			(at 0.40005 0)
			(size 0 0)
			(layers "F.Cu" "F.Mask" "F.Paste")
			(net "INA230_4_A1")
		)
	)
	(footprint ""
		(layer "F.Cu")
		(at 186.23788 -97.119948 -90)
		(property "Reference" "R168"
			(at 0 0 270)
			(layer "F.SilkS")
			(hide yes)
			(effects
				(font
					(size 1.27 1.27)
				)
			)
		)
		(property "Value" ""
			(at 0 0 270)
			(layer "F.Fab")
			(effects
				(font
					(size 1.27 1.27)
				)
			)
		)
		(duplicate_pad_numbers_are_jumpers no)
		(fp_line
			(start -0.7874 0.4064)
			(end -0.7874 -0.4064)
			(stroke
				(width 0.1524)
				(type default)
			)
			(layer "F.SilkS")
		)
		(fp_line
			(start 0.7874 0.4064)
			(end -0.7874 0.4064)
			(stroke
				(width 0.1524)
				(type default)
			)
			(layer "F.SilkS")
		)
		(fp_line
			(start -0.7874 -0.4064)
			(end 0.7874 -0.4064)
			(stroke
				(width 0.1524)
				(type default)
			)
			(layer "F.SilkS")
		)
		(fp_line
			(start 0.7874 -0.4064)
			(end 0.7874 0.4064)
			(stroke
				(width 0.1524)
				(type default)
			)
			(layer "F.SilkS")
		)
		(fp_line
			(start -0.67945 0.3048)
			(end -0.67945 -0.305054)
			(stroke
				(width 0.1)
				(type default)
			)
			(layer "F.Fab")
		)
		(fp_line
			(start -0.12065 0.3048)
			(end -0.67945 0.3048)
			(stroke
				(width 0.1)
				(type default)
			)
			(layer "F.Fab")
		)
		(fp_line
			(start 0.120396 0.3048)
			(end 0.120396 0.2794)
			(stroke
				(width 0.1)
				(type default)
			)
			(layer "F.Fab")
		)
		(fp_line
			(start 0.67945 0.3048)
			(end 0.120396 0.3048)
			(stroke
				(width 0.1)
				(type default)
			)
			(layer "F.Fab")
		)
		(fp_line
			(start -0.12065 0.2794)
			(end -0.12065 0.3048)
			(stroke
				(width 0.1)
				(type default)
			)
			(layer "F.Fab")
		)
		(fp_line
			(start 0.120396 0.2794)
			(end -0.12065 0.2794)
			(stroke
				(width 0.1)
				(type default)
			)
			(layer "F.Fab")
		)
		(fp_line
			(start -0.12065 -0.2794)
			(end 0.12065 -0.2794)
			(stroke
				(width 0.1)
				(type default)
			)
			(layer "F.Fab")
		)
		(fp_line
			(start 0.12065 -0.2794)
			(end 0.12065 -0.3048)
			(stroke
				(width 0.1)
				(type default)
			)
			(layer "F.Fab")
		)
		(fp_line
			(start 0.12065 -0.3048)
			(end 0.67945 -0.3048)
			(stroke
				(width 0.1)
				(type default)
			)
			(layer "F.Fab")
		)
		(fp_line
			(start 0.67945 -0.3048)
			(end 0.67945 0.3048)
			(stroke
				(width 0.1)
				(type default)
			)
			(layer "F.Fab")
		)
		(fp_line
			(start -0.67945 -0.305054)
			(end -0.12065 -0.305054)
			(stroke
				(width 0.1)
				(type default)
			)
			(layer "F.Fab")
		)
		(fp_line
			(start -0.12065 -0.305054)
			(end -0.12065 -0.2794)
			(stroke
				(width 0.1)
				(type default)
			)
			(layer "F.Fab")
		)
		(pad "1" smd circle
			(at -0.40005 0 270)
			(size 0 0)
			(layers "F.Cu" "F.Mask" "F.Paste")
			(net "PWRGD_CPU0_LVC1_R")
		)
		(pad "2" smd circle
			(at 0.40005 0 270)
			(size 0 0)
			(layers "F.Cu" "F.Mask" "F.Paste")
			(net "PWRGD_CPU0_BUF_R")
		)
	)
	(footprint ""
		(layer "F.Cu")
		(at 314.65012 -440.489848)
		(property "Reference" "J108"
			(at 12.6238 23.28799 0)
			(unlocked yes)
			(layer "F.SilkS")
			(effects
				(font
					(size 0.7874 0.5842)
					(thickness 0.1524)
				)
				(justify left)
			)
		)
		(property "Value" ""
			(at 0 0 0)
			(layer "F.Fab")
			(effects
				(font
					(size 1.27 1.27)
				)
			)
		)
		(duplicate_pad_numbers_are_jumpers no)
		(fp_line
			(start -4.249928 -11.999976)
			(end 18.64995 -11.999976)
			(stroke
				(width 0.1524)
				(type default)
			)
			(layer "F.SilkS")
		)
		(fp_line
			(start -4.249928 22.400006)
			(end -4.249928 -11.999976)
			(stroke
				(width 0.1524)
				(type default)
			)
			(layer "F.SilkS")
		)
		(fp_line
			(start -1.249934 -8.999982)
			(end -1.249934 19.400012)
			(stroke
				(width 0.1524)
				(type default)
			)
			(layer "F.SilkS")
		)
		(fp_line
			(start -1.249934 -1.500124)
			(end 15.649956 -1.500124)
			(stroke
				(width 0.1524)
				(type default)
			)
			(layer "F.SilkS")
		)
		(fp_line
			(start -1.249934 19.400012)
			(end 15.649956 19.400012)
			(stroke
				(width 0.1524)
				(type default)
			)
			(layer "F.SilkS")
		)
		(fp_line
			(start 0.0254 -0.9144)
			(end 1.0414 -0.9144)
			(stroke
				(width 0.1524)
				(type default)
			)
			(layer "F.SilkS")
		)
		(fp_line
			(start 0.5334 -1.4224)
			(end 0.0254 -0.9144)
			(stroke
				(width 0.1524)
				(type default)
			)
			(layer "F.SilkS")
		)
		(fp_line
			(start 0.5334 -1.4224)
			(end 0.5334 -0.5588)
			(stroke
				(width 0.1524)
				(type default)
			)
			(layer "F.SilkS")
		)
		(fp_line
			(start 0.5334 -0.5588)
			(end 1.8034 -0.5588)
			(stroke
				(width 0.1524)
				(type default)
			)
			(layer "F.SilkS")
		)
		(fp_line
			(start 1.0414 -0.9144)
			(end 0.5334 -1.4224)
			(stroke
				(width 0.1524)
				(type default)
			)
			(layer "F.SilkS")
		)
		(fp_line
			(start 1.8034 -0.5588)
			(end 2.032 -0.7874)
			(stroke
				(width 0.1524)
				(type default)
			)
			(layer "F.SilkS")
		)
		(fp_line
			(start 15.649956 -8.999982)
			(end -1.249934 -8.999982)
			(stroke
				(width 0.1524)
				(type default)
			)
			(layer "F.SilkS")
		)
		(fp_line
			(start 15.649956 19.400012)
			(end 15.649956 -8.999982)
			(stroke
				(width 0.1524)
				(type default)
			)
			(layer "F.SilkS")
		)
		(fp_line
			(start 18.64995 -11.999976)
			(end 18.64995 -1.254252)
			(stroke
				(width 0.1524)
				(type default)
			)
			(layer "F.SilkS")
		)
		(fp_line
			(start 18.64995 16.744188)
			(end 18.64995 22.400006)
			(stroke
				(width 0.1524)
				(type default)
			)
			(layer "F.SilkS")
		)
		(fp_line
			(start 18.64995 22.400006)
			(end -4.249928 22.400006)
			(stroke
				(width 0.1524)
				(type default)
			)
			(layer "F.SilkS")
		)
		(fp_poly
			(pts
				(xy -2.659888 -0.35052) (xy -1.643888 0.15748) (xy -2.659888 0.66548)
			)
			(stroke
				(width 0)
				(type default)
			)
			(fill yes)
			(layer "F.SilkS")
		)
		(fp_line
			(start -4.249928 -11.999976)
			(end 18.64995 -11.999976)
			(stroke
				(width 0.1524)
				(type default)
			)
			(layer "B.SilkS")
		)
		(fp_line
			(start -4.249928 22.400006)
			(end -4.249928 -11.999976)
			(stroke
				(width 0.1524)
				(type default)
			)
			(layer "B.SilkS")
		)
		(fp_line
			(start 18.64995 -11.999976)
			(end 18.64995 -1.086612)
			(stroke
				(width 0.1524)
				(type default)
			)
			(layer "B.SilkS")
		)
		(fp_line
			(start 18.64995 16.932148)
			(end 18.64995 18.151348)
			(stroke
				(width 0.1524)
				(type default)
			)
			(layer "B.SilkS")
		)
		(fp_line
			(start 18.64995 19.352768)
			(end 18.64995 22.400006)
			(stroke
				(width 0.1524)
				(type default)
			)
			(layer "B.SilkS")
		)
		(fp_line
			(start 18.64995 22.400006)
			(end -4.249928 22.400006)
			(stroke
				(width 0.1524)
				(type default)
			)
			(layer "B.SilkS")
		)
		(fp_line
			(start -4.249928 -11.999976)
			(end 18.64995 -11.999976)
			(stroke
				(width 0.1)
				(type default)
			)
			(layer "B.Fab")
		)
		(fp_line
			(start -4.249928 22.400006)
			(end -4.249928 -11.999976)
			(stroke
				(width 0.1)
				(type default)
			)
			(layer "B.Fab")
		)
		(fp_line
			(start 18.64995 -11.999976)
			(end 18.64995 22.400006)
			(stroke
				(width 0.1)
				(type default)
			)
			(layer "B.Fab")
		)
		(fp_line
			(start 18.64995 22.400006)
			(end -4.249928 22.400006)
			(stroke
				(width 0.1)
				(type default)
			)
			(layer "B.Fab")
		)
		(fp_line
			(start -1.249934 -8.999982)
			(end -1.249934 19.400012)
			(stroke
				(width 0.1)
				(type default)
			)
			(layer "F.Fab")
		)
		(fp_line
			(start -1.249934 19.400012)
			(end 15.649956 19.400012)
			(stroke
				(width 0.1)
				(type default)
			)
			(layer "F.Fab")
		)
		(fp_line
			(start 15.649956 -8.999982)
			(end -1.249934 -8.999982)
			(stroke
				(width 0.1)
				(type default)
			)
			(layer "F.Fab")
		)
		(fp_line
			(start 15.649956 19.400012)
			(end 15.649956 -8.999982)
			(stroke
				(width 0.1)
				(type default)
			)
			(layer "F.Fab")
		)
		(fp_poly
			(pts
				(xy -2.670048 -0.508) (xy -2.670048 0.508) (xy -1.654048 0)
			)
			(stroke
				(width 0)
				(type default)
			)
			(fill yes)
			(layer "F.Fab")
		)
		(fp_text user "PRESS-FIT"
			(at -4.45516 24.02205 0)
			(unlocked yes)
			(layer "F.SilkS")
			(effects
				(font
					(size 1.905 1.4224)
					(thickness 0.1524)
				)
				(justify left)
			)
		)
		(fp_text user "B"
			(at -2.356612 1.384046 0)
			(unlocked yes)
			(layer "F.SilkS")
			(effects
				(font
					(size 0.7874 0.5842)
					(thickness 0.1524)
				)
			)
		)
		(fp_text user "C"
			(at -2.356612 2.584196 0)
			(unlocked yes)
			(layer "F.SilkS")
			(effects
				(font
					(size 0.7874 0.5842)
					(thickness 0.1524)
				)
			)
		)
		(fp_text user "D"
			(at -2.356612 3.784092 0)
			(unlocked yes)
			(layer "F.SilkS")
			(effects
				(font
					(size 0.7874 0.5842)
					(thickness 0.1524)
				)
			)
		)
		(fp_text user "E"
			(at -2.356612 4.984242 0)
			(unlocked yes)
			(layer "F.SilkS")
			(effects
				(font
					(size 0.7874 0.5842)
					(thickness 0.1524)
				)
			)
		)
		(fp_text user "F"
			(at -2.356612 6.184138 0)
			(unlocked yes)
			(layer "F.SilkS")
			(effects
				(font
					(size 0.7874 0.5842)
					(thickness 0.1524)
				)
			)
		)
		(fp_text user "G"
			(at -2.356612 7.384034 0)
			(unlocked yes)
			(layer "F.SilkS")
			(effects
				(font
					(size 0.7874 0.5842)
					(thickness 0.1524)
				)
			)
		)
		(fp_text user "H"
			(at -2.356612 8.584184 0)
			(unlocked yes)
			(layer "F.SilkS")
			(effects
				(font
					(size 0.7874 0.5842)
					(thickness 0.1524)
				)
			)
		)
		(fp_text user "I"
			(at -2.356612 9.78408 0)
			(unlocked yes)
			(layer "F.SilkS")
			(effects
				(font
					(size 0.7874 0.5842)
					(thickness 0.1524)
				)
			)
		)
		(fp_text user "J"
			(at -2.356612 10.98423 0)
			(unlocked yes)
			(layer "F.SilkS")
			(effects
				(font
					(size 0.7874 0.5842)
					(thickness 0.1524)
				)
			)
		)
		(fp_text user "K"
			(at -2.356612 12.184126 0)
			(unlocked yes)
			(layer "F.SilkS")
			(effects
				(font
					(size 0.7874 0.5842)
					(thickness 0.1524)
				)
			)
		)
		(fp_text user "L"
			(at -2.356612 13.384276 0)
			(unlocked yes)
			(layer "F.SilkS")
			(effects
				(font
					(size 0.7874 0.5842)
					(thickness 0.1524)
				)
			)
		)
		(fp_text user "M"
			(at -2.356612 14.584172 0)
			(unlocked yes)
			(layer "F.SilkS")
			(effects
				(font
					(size 0.7874 0.5842)
					(thickness 0.1524)
				)
			)
		)
		(fp_text user "N"
			(at -2.356612 15.784068 0)
			(unlocked yes)
			(layer "F.SilkS")
			(effects
				(font
					(size 0.7874 0.5842)
					(thickness 0.1524)
				)
			)
		)
		(fp_text user "1"
			(at 0.132842 20.09013 0)
			(unlocked yes)
			(layer "F.SilkS")
			(effects
				(font
					(size 0.7874 0.5842)
					(thickness 0.1524)
				)
			)
		)
		(fp_text user "2"
			(at 2.132838 20.09013 0)
			(unlocked yes)
			(layer "F.SilkS")
			(effects
				(font
					(size 0.7874 0.5842)
					(thickness 0.1524)
				)
			)
		)
		(fp_text user "EDGE OF DAUGHTER CARD"
			(at 2.2479 -0.899668 0)
			(unlocked yes)
			(layer "F.SilkS")
			(effects
				(font
					(size 0.635 0.4064)
					(thickness 0.1524)
				)
				(justify left)
			)
		)
		(fp_text user "3"
			(at 4.132834 20.09013 0)
			(unlocked yes)
			(layer "F.SilkS")
			(effects
				(font
					(size 0.7874 0.5842)
					(thickness 0.1524)
				)
			)
		)
		(fp_text user "4"
			(at 6.13283 20.09013 0)
			(unlocked yes)
			(layer "F.SilkS")
			(effects
				(font
					(size 0.7874 0.5842)
					(thickness 0.1524)
				)
			)
		)
		(fp_text user "5"
			(at 8.132826 20.09013 0)
			(unlocked yes)
			(layer "F.SilkS")
			(effects
				(font
					(size 0.7874 0.5842)
					(thickness 0.1524)
				)
			)
		)
		(fp_text user "6"
			(at 10.132822 20.09013 0)
			(unlocked yes)
			(layer "F.SilkS")
			(effects
				(font
					(size 0.7874 0.5842)
					(thickness 0.1524)
				)
			)
		)
		(fp_text user "7"
			(at 12.132818 20.09013 0)
			(unlocked yes)
			(layer "F.SilkS")
			(effects
				(font
					(size 0.7874 0.5842)
					(thickness 0.1524)
				)
			)
		)
		(fp_text user "8"
			(at 14.132814 20.09013 0)
			(unlocked yes)
			(layer "F.SilkS")
			(effects
				(font
					(size 0.7874 0.5842)
					(thickness 0.1524)
				)
			)
		)
		(fp_text user "A"
			(at -1.266444 0.44831 0)
			(unlocked yes)
			(layer "B.SilkS")
			(effects
				(font
					(size 0.7874 0.5842)
					(thickness 0.1524)
				)
				(justify mirror)
			)
		)
		(fp_text user "G"
			(at -1.241044 7.86511 0)
			(unlocked yes)
			(layer "B.SilkS")
			(effects
				(font
					(size 0.7874 0.5842)
					(thickness 0.1524)
				)
				(justify mirror)
			)
		)
		(fp_text user "H"
			(at -1.215644 9.08431 0)
			(unlocked yes)
			(layer "B.SilkS")
			(effects
				(font
					(size 0.7874 0.5842)
					(thickness 0.1524)
				)
				(justify mirror)
			)
		)
		(fp_text user "B"
			(at -1.21412 1.775206 0)
			(unlocked yes)
			(layer "B.SilkS")
			(effects
				(font
					(size 0.7874 0.5842)
					(thickness 0.1524)
				)
				(justify mirror)
			)
		)
		(fp_text user "C"
			(at -1.21412 2.975356 0)
			(unlocked yes)
			(layer "B.SilkS")
			(effects
				(font
					(size 0.7874 0.5842)
					(thickness 0.1524)
				)
				(justify mirror)
			)
		)
		(fp_text user "D"
			(at -1.21412 4.175252 0)
			(unlocked yes)
			(layer "B.SilkS")
			(effects
				(font
					(size 0.7874 0.5842)
					(thickness 0.1524)
				)
				(justify mirror)
			)
		)
		(fp_text user "E"
			(at -1.21412 5.375402 0)
			(unlocked yes)
			(layer "B.SilkS")
			(effects
				(font
					(size 0.7874 0.5842)
					(thickness 0.1524)
				)
				(justify mirror)
			)
		)
		(fp_text user "F"
			(at -1.21412 6.575298 0)
			(unlocked yes)
			(layer "B.SilkS")
			(effects
				(font
					(size 0.7874 0.5842)
					(thickness 0.1524)
				)
				(justify mirror)
			)
		)
		(fp_text user "I"
			(at -1.21412 10.17524 0)
			(unlocked yes)
			(layer "B.SilkS")
			(effects
				(font
					(size 0.7874 0.5842)
					(thickness 0.1524)
				)
				(justify mirror)
			)
		)
		(fp_text user "J"
			(at -1.21412 11.37539 0)
			(unlocked yes)
			(layer "B.SilkS")
			(effects
				(font
					(size 0.7874 0.5842)
					(thickness 0.1524)
				)
				(justify mirror)
			)
		)
		(fp_text user "K"
			(at -1.21412 12.575286 0)
			(unlocked yes)
			(layer "B.SilkS")
			(effects
				(font
					(size 0.7874 0.5842)
					(thickness 0.1524)
				)
				(justify mirror)
			)
		)
		(fp_text user "L"
			(at -1.21412 13.775436 0)
			(unlocked yes)
			(layer "B.SilkS")
			(effects
				(font
					(size 0.7874 0.5842)
					(thickness 0.1524)
				)
				(justify mirror)
			)
		)
		(fp_text user "M"
			(at -1.21412 14.975332 0)
			(unlocked yes)
			(layer "B.SilkS")
			(effects
				(font
					(size 0.7874 0.5842)
					(thickness 0.1524)
				)
				(justify mirror)
			)
		)
		(fp_text user "N"
			(at -1.21412 16.175228 0)
			(unlocked yes)
			(layer "B.SilkS")
			(effects
				(font
					(size 0.7874 0.5842)
					(thickness 0.1524)
				)
				(justify mirror)
			)
		)
		(fp_text user "1"
			(at -0.006858 17.02181 0)
			(unlocked yes)
			(layer "B.SilkS")
			(effects
				(font
					(size 0.7874 0.5842)
					(thickness 0.1524)
				)
				(justify mirror)
			)
		)
		(fp_text user "2"
			(at 1.993138 17.02181 0)
			(unlocked yes)
			(layer "B.SilkS")
			(effects
				(font
					(size 0.7874 0.5842)
					(thickness 0.1524)
				)
				(justify mirror)
			)
		)
		(fp_text user "3"
			(at 3.993134 17.02181 0)
			(unlocked yes)
			(layer "B.SilkS")
			(effects
				(font
					(size 0.7874 0.5842)
					(thickness 0.1524)
				)
				(justify mirror)
			)
		)
		(fp_text user "4"
			(at 5.99313 17.02181 0)
			(unlocked yes)
			(layer "B.SilkS")
			(effects
				(font
					(size 0.7874 0.5842)
					(thickness 0.1524)
				)
				(justify mirror)
			)
		)
		(fp_text user "5"
			(at 7.993126 17.02181 0)
			(unlocked yes)
			(layer "B.SilkS")
			(effects
				(font
					(size 0.7874 0.5842)
					(thickness 0.1524)
				)
				(justify mirror)
			)
		)
		(fp_text user "6"
			(at 9.993122 17.02181 0)
			(unlocked yes)
			(layer "B.SilkS")
			(effects
				(font
					(size 0.7874 0.5842)
					(thickness 0.1524)
				)
				(justify mirror)
			)
		)
		(fp_text user "7"
			(at 11.993118 17.02181 0)
			(unlocked yes)
			(layer "B.SilkS")
			(effects
				(font
					(size 0.7874 0.5842)
					(thickness 0.1524)
				)
				(justify mirror)
			)
		)
		(fp_text user "PRESS-FIT"
			(at 12.63904 21.172678 0)
			(unlocked yes)
			(layer "B.SilkS")
			(effects
				(font
					(size 1.905 1.4224)
					(thickness 0.1524)
				)
				(justify left mirror)
			)
		)
		(fp_text user "8"
			(at 13.993114 17.02181 0)
			(unlocked yes)
			(layer "B.SilkS")
			(effects
				(font
					(size 0.7874 0.5842)
					(thickness 0.1524)
				)
				(justify mirror)
			)
		)
		(fp_text user "A"
			(at -1.199134 0 90)
			(unlocked yes)
			(layer "B.Fab")
			(effects
				(font
					(size 0.7874 0.5842)
					(thickness 0.1524)
				)
				(justify mirror)
			)
		)
		(fp_text user "G"
			(at -1.173734 7.4168 90)
			(unlocked yes)
			(layer "B.Fab")
			(effects
				(font
					(size 0.7874 0.5842)
					(thickness 0.1524)
				)
				(justify mirror)
			)
		)
		(fp_text user "H"
			(at -1.148334 8.636 90)
			(unlocked yes)
			(layer "B.Fab")
			(effects
				(font
					(size 0.7874 0.5842)
					(thickness 0.1524)
				)
				(justify mirror)
			)
		)
		(fp_text user "B"
			(at -1.14681 1.326896 90)
			(unlocked yes)
			(layer "B.Fab")
			(effects
				(font
					(size 0.7874 0.5842)
					(thickness 0.1524)
				)
				(justify mirror)
			)
		)
		(fp_text user "C"
			(at -1.14681 2.527046 90)
			(unlocked yes)
			(layer "B.Fab")
			(effects
				(font
					(size 0.7874 0.5842)
					(thickness 0.1524)
				)
				(justify mirror)
			)
		)
		(fp_text user "D"
			(at -1.14681 3.726942 90)
			(unlocked yes)
			(layer "B.Fab")
			(effects
				(font
					(size 0.7874 0.5842)
					(thickness 0.1524)
				)
				(justify mirror)
			)
		)
		(fp_text user "E"
			(at -1.14681 4.927092 90)
			(unlocked yes)
			(layer "B.Fab")
			(effects
				(font
					(size 0.7874 0.5842)
					(thickness 0.1524)
				)
				(justify mirror)
			)
		)
		(fp_text user "F"
			(at -1.14681 6.126988 90)
			(unlocked yes)
			(layer "B.Fab")
			(effects
				(font
					(size 0.7874 0.5842)
					(thickness 0.1524)
				)
				(justify mirror)
			)
		)
		(fp_text user "I"
			(at -1.14681 9.72693 90)
			(unlocked yes)
			(layer "B.Fab")
			(effects
				(font
					(size 0.7874 0.5842)
					(thickness 0.1524)
				)
				(justify mirror)
			)
		)
		(fp_text user "J"
			(at -1.14681 10.92708 90)
			(unlocked yes)
			(layer "B.Fab")
			(effects
				(font
					(size 0.7874 0.5842)
					(thickness 0.1524)
				)
				(justify mirror)
			)
		)
		(fp_text user "K"
			(at -1.14681 12.126976 90)
			(unlocked yes)
			(layer "B.Fab")
			(effects
				(font
					(size 0.7874 0.5842)
					(thickness 0.1524)
				)
				(justify mirror)
			)
		)
		(fp_text user "L"
			(at -1.14681 13.327126 90)
			(unlocked yes)
			(layer "B.Fab")
			(effects
				(font
					(size 0.7874 0.5842)
					(thickness 0.1524)
				)
				(justify mirror)
			)
		)
		(fp_text user "M"
			(at -1.14681 14.527022 90)
			(unlocked yes)
			(layer "B.Fab")
			(effects
				(font
					(size 0.7874 0.5842)
					(thickness 0.1524)
				)
				(justify mirror)
			)
		)
		(fp_text user "N"
			(at -1.14681 15.726918 90)
			(unlocked yes)
			(layer "B.Fab")
			(effects
				(font
					(size 0.7874 0.5842)
					(thickness 0.1524)
				)
				(justify mirror)
			)
		)
		(fp_text user "1"
			(at 0.060452 16.764 90)
			(unlocked yes)
			(layer "B.Fab")
			(effects
				(font
					(size 0.7874 0.5842)
					(thickness 0.1524)
				)
				(justify mirror)
			)
		)
		(fp_text user "2"
			(at 2.060448 16.764 90)
			(unlocked yes)
			(layer "B.Fab")
			(effects
				(font
					(size 0.7874 0.5842)
					(thickness 0.1524)
				)
				(justify mirror)
			)
		)
		(fp_text user "3"
			(at 4.060444 16.764 90)
			(unlocked yes)
			(layer "B.Fab")
			(effects
				(font
					(size 0.7874 0.5842)
					(thickness 0.1524)
				)
				(justify mirror)
			)
		)
		(fp_text user "4"
			(at 6.06044 16.764 90)
			(unlocked yes)
			(layer "B.Fab")
			(effects
				(font
					(size 0.7874 0.5842)
					(thickness 0.1524)
				)
				(justify mirror)
			)
		)
		(fp_text user "5"
			(at 8.060436 16.764 90)
			(unlocked yes)
			(layer "B.Fab")
			(effects
				(font
					(size 0.7874 0.5842)
					(thickness 0.1524)
				)
				(justify mirror)
			)
		)
		(fp_text user "6"
			(at 10.060432 16.764 90)
			(unlocked yes)
			(layer "B.Fab")
			(effects
				(font
					(size 0.7874 0.5842)
					(thickness 0.1524)
				)
				(justify mirror)
			)
		)
		(fp_text user "7"
			(at 12.060428 16.764 90)
			(unlocked yes)
			(layer "B.Fab")
			(effects
				(font
					(size 0.7874 0.5842)
					(thickness 0.1524)
				)
				(justify mirror)
			)
		)
		(fp_text user "8"
			(at 14.060424 16.764 90)
			(unlocked yes)
			(layer "B.Fab")
			(effects
				(font
					(size 0.7874 0.5842)
					(thickness 0.1524)
				)
				(justify mirror)
			)
		)
		(fp_text user "PRESS-FIT"
			(at 17.23771 -0.0762 90)
			(unlocked yes)
			(layer "B.Fab")
			(effects
				(font
					(size 1.905 1.4224)
					(thickness 0.1524)
				)
				(justify left mirror)
			)
		)
		(fp_text user "B"
			(at -2.253742 1.199896 90)
			(unlocked yes)
			(layer "F.Fab")
			(effects
				(font
					(size 0.7874 0.5842)
					(thickness 0.1524)
				)
			)
		)
		(fp_text user "C"
			(at -2.253742 2.400046 90)
			(unlocked yes)
			(layer "F.Fab")
			(effects
				(font
					(size 0.7874 0.5842)
					(thickness 0.1524)
				)
			)
		)
		(fp_text user "D"
			(at -2.253742 3.599942 90)
			(unlocked yes)
			(layer "F.Fab")
			(effects
				(font
					(size 0.7874 0.5842)
					(thickness 0.1524)
				)
			)
		)
		(fp_text user "E"
			(at -2.253742 4.800092 90)
			(unlocked yes)
			(layer "F.Fab")
			(effects
				(font
					(size 0.7874 0.5842)
					(thickness 0.1524)
				)
			)
		)
		(fp_text user "F"
			(at -2.253742 5.999988 90)
			(unlocked yes)
			(layer "F.Fab")
			(effects
				(font
					(size 0.7874 0.5842)
					(thickness 0.1524)
				)
			)
		)
		(fp_text user "G"
			(at -2.253742 7.199884 90)
			(unlocked yes)
			(layer "F.Fab")
			(effects
				(font
					(size 0.7874 0.5842)
					(thickness 0.1524)
				)
			)
		)
		(fp_text user "H"
			(at -2.253742 8.400034 90)
			(unlocked yes)
			(layer "F.Fab")
			(effects
				(font
					(size 0.7874 0.5842)
					(thickness 0.1524)
				)
			)
		)
		(fp_text user "I"
			(at -2.253742 9.59993 90)
			(unlocked yes)
			(layer "F.Fab")
			(effects
				(font
					(size 0.7874 0.5842)
					(thickness 0.1524)
				)
			)
		)
		(fp_text user "J"
			(at -2.253742 10.80008 90)
			(unlocked yes)
			(layer "F.Fab")
			(effects
				(font
					(size 0.7874 0.5842)
					(thickness 0.1524)
				)
			)
		)
		(fp_text user "K"
			(at -2.253742 11.999976 90)
			(unlocked yes)
			(layer "F.Fab")
			(effects
				(font
					(size 0.7874 0.5842)
					(thickness 0.1524)
				)
			)
		)
		(fp_text user "L"
			(at -2.253742 13.200126 90)
			(unlocked yes)
			(layer "F.Fab")
			(effects
				(font
					(size 0.7874 0.5842)
					(thickness 0.1524)
				)
			)
		)
		(fp_text user "M"
			(at -2.253742 14.400022 90)
			(unlocked yes)
			(layer "F.Fab")
			(effects
				(font
					(size 0.7874 0.5842)
					(thickness 0.1524)
				)
			)
		)
		(fp_text user "N"
			(at -2.253742 15.599918 90)
			(unlocked yes)
			(layer "F.Fab")
			(effects
				(font
					(size 0.7874 0.5842)
					(thickness 0.1524)
				)
			)
		)
		(fp_text user "1"
			(at 0.111252 19.8628 90)
			(unlocked yes)
			(layer "F.Fab")
			(effects
				(font
					(size 0.7874 0.5842)
					(thickness 0.1524)
				)
			)
		)
		(fp_text user "2"
			(at 2.111248 19.8628 90)
			(unlocked yes)
			(layer "F.Fab")
			(effects
				(font
					(size 0.7874 0.5842)
					(thickness 0.1524)
				)
			)
		)
		(fp_text user "3"
			(at 4.111244 19.8628 90)
			(unlocked yes)
			(layer "F.Fab")
			(effects
				(font
					(size 0.7874 0.5842)
					(thickness 0.1524)
				)
			)
		)
		(fp_text user "4"
			(at 6.11124 19.8628 90)
			(unlocked yes)
			(layer "F.Fab")
			(effects
				(font
					(size 0.7874 0.5842)
					(thickness 0.1524)
				)
			)
		)
		(fp_text user "5"
			(at 8.111236 19.8628 90)
			(unlocked yes)
			(layer "F.Fab")
			(effects
				(font
					(size 0.7874 0.5842)
					(thickness 0.1524)
				)
			)
		)
		(fp_text user "6"
			(at 10.111232 19.8628 90)
			(unlocked yes)
			(layer "F.Fab")
			(effects
				(font
					(size 0.7874 0.5842)
					(thickness 0.1524)
				)
			)
		)
		(fp_text user "7"
			(at 12.111228 19.8628 90)
			(unlocked yes)
			(layer "F.Fab")
			(effects
				(font
					(size 0.7874 0.5842)
					(thickness 0.1524)
				)
			)
		)
		(fp_text user "8"
			(at 14.111224 19.8628 90)
			(unlocked yes)
			(layer "F.Fab")
			(effects
				(font
					(size 0.7874 0.5842)
					(thickness 0.1524)
				)
			)
		)
		(fp_text user "PRESS-FIT"
			(at 17.240758 16.521684 90)
			(unlocked yes)
			(layer "F.Fab")
			(effects
				(font
					(size 1.905 1.4224)
					(thickness 0.1524)
				)
				(justify left)
			)
		)
		(pad "A1" thru_hole rect
			(at 0 0 180)
			(size 0.766318 0.766318)
			(drill 0.359918)
			(layers "*.Cu" "*.Mask")
			(remove_unused_layers no)
			(net "GPU_3V3IO_RSVD3_FFU")
			(clearance 0.0508)
			(thermal_gap 0.0508)
			(padstack
				(mode front_inner_back)
				(layer "Inner"
					(shape circle)
					(size 0.766318 0.766318)
					(clearance 0.0508)
				)
				(layer "B.Cu"
					(shape rect)
					(size 0.766318 0.766318)
					(clearance 0.0508)
				)
			)
		)
		(pad "A2" thru_hole circle
			(at 1.999996 0.199898 180)
			(size 0.906272 0.906272)
			(drill 0.499872)
			(layers "*.Cu" "*.Mask")
			(remove_unused_layers no)
			(net "GND")
			(clearance 0.0508)
			(thermal_gap 0.0508)
		)
		(pad "A3" thru_hole circle
			(at 3.999992 0 180)
			(size 0.766318 0.766318)
			(drill 0.359918)
			(layers "*.Cu" "*.Mask")
			(remove_unused_layers no)
			(net "PRSNT_CABLE_GPU_A2_N")
			(clearance 0.0508)
			(thermal_gap 0.0508)
		)
		(pad "A4" thru_hole circle
			(at 5.999988 0.199898 180)
			(size 0.906272 0.906272)
			(drill 0.499872)
			(layers "*.Cu" "*.Mask")
			(remove_unused_layers no)
			(net "GND")
			(clearance 0.0508)
			(thermal_gap 0.0508)
		)
		(pad "A5" thru_hole circle
			(at 7.999984 0 180)
			(size 0.766318 0.766318)
			(drill 0.359918)
			(layers "*.Cu" "*.Mask")
			(remove_unused_layers no)
			(net "GPU_3V3IO_RSVD5_FFU")
			(clearance 0.0508)
			(thermal_gap 0.0508)
		)
		(pad "A6" thru_hole circle
			(at 9.99998 0.199898 180)
			(size 0.906272 0.906272)
			(drill 0.499872)
			(layers "*.Cu" "*.Mask")
			(remove_unused_layers no)
			(net "GND")
			(clearance 0.0508)
			(thermal_gap 0.0508)
		)
		(pad "A7" thru_hole circle
			(at 11.999976 0 180)
			(size 0.766318 0.766318)
			(drill 0.359918)
			(layers "*.Cu" "*.Mask")
			(remove_unused_layers no)
			(net "GPU_FPGA_OVERT_N")
			(clearance 0.0508)
			(thermal_gap 0.0508)
		)
		(pad "A8" thru_hole circle
			(at 13.999972 0.199898 180)
			(size 0.906272 0.906272)
			(drill 0.499872)
			(layers "*.Cu" "*.Mask")
			(remove_unused_layers no)
			(net "GND")
			(clearance 0.0508)
			(thermal_gap 0.0508)
		)
		(pad "B1" thru_hole circle
			(at 0 1.199896 180)
			(size 0.906272 0.906272)
			(drill 0.499872)
			(layers "*.Cu" "*.Mask")
			(remove_unused_layers no)
			(net "GND")
			(clearance 0.0508)
			(thermal_gap 0.0508)
		)
		(pad "B3" thru_hole circle
			(at 3.999992 1.199896 180)
			(size 0.906272 0.906272)
			(drill 0.499872)
			(layers "*.Cu" "*.Mask")
			(remove_unused_layers no)
			(net "GND")
			(clearance 0.0508)
			(thermal_gap 0.0508)
		)
		(pad "B5" thru_hole circle
			(at 7.999984 1.199896 180)
			(size 0.906272 0.906272)
			(drill 0.499872)
			(layers "*.Cu" "*.Mask")
			(remove_unused_layers no)
			(net "GND")
			(clearance 0.0508)
			(thermal_gap 0.0508)
		)
		(pad "B7" thru_hole circle
			(at 11.999976 1.199896 180)
			(size 0.906272 0.906272)
			(drill 0.499872)
			(layers "*.Cu" "*.Mask")
			(remove_unused_layers no)
			(net "GND")
			(clearance 0.0508)
			(thermal_gap 0.0508)
		)
		(pad "D2" thru_hole circle
			(at 1.999996 3.800094 180)
			(size 0.906272 0.906272)
			(drill 0.499872)
			(layers "*.Cu" "*.Mask")
			(remove_unused_layers no)
			(net "GND")
			(clearance 0.0508)
			(thermal_gap 0.0508)
		)
		(pad "D4" thru_hole circle
			(at 5.999988 3.800094 180)
			(size 0.906272 0.906272)
			(drill 0.499872)
			(layers "*.Cu" "*.Mask")
			(remove_unused_layers no)
			(net "GND")
			(clearance 0.0508)
			(thermal_gap 0.0508)
		)
		(pad "D6" thru_hole circle
			(at 9.99998 3.800094 180)
			(size 0.906272 0.906272)
			(drill 0.499872)
			(layers "*.Cu" "*.Mask")
			(remove_unused_layers no)
			(net "GND")
			(clearance 0.0508)
			(thermal_gap 0.0508)
		)
		(pad "D8" thru_hole circle
			(at 13.999972 3.800094 180)
			(size 0.906272 0.906272)
			(drill 0.499872)
			(layers "*.Cu" "*.Mask")
			(remove_unused_layers no)
			(net "GND")
			(clearance 0.0508)
			(thermal_gap 0.0508)
		)
		(pad "E1" thru_hole circle
			(at 0 4.800092 180)
			(size 0.906272 0.906272)
			(drill 0.499872)
			(layers "*.Cu" "*.Mask")
			(remove_unused_layers no)
			(net "GND")
			(clearance 0.0508)
			(thermal_gap 0.0508)
		)
		(pad "E3" thru_hole circle
			(at 3.999992 4.800092 180)
			(size 0.906272 0.906272)
			(drill 0.499872)
			(layers "*.Cu" "*.Mask")
			(remove_unused_layers no)
			(net "GND")
			(clearance 0.0508)
			(thermal_gap 0.0508)
		)
		(pad "E5" thru_hole circle
			(at 7.999984 4.800092 180)
			(size 0.906272 0.906272)
			(drill 0.499872)
			(layers "*.Cu" "*.Mask")
			(remove_unused_layers no)
			(net "GND")
			(clearance 0.0508)
			(thermal_gap 0.0508)
		)
		(pad "E7" thru_hole circle
			(at 11.999976 4.800092 180)
			(size 0.906272 0.906272)
			(drill 0.499872)
			(layers "*.Cu" "*.Mask")
			(remove_unused_layers no)
			(net "GND")
			(clearance 0.0508)
			(thermal_gap 0.0508)
		)
		(pad "G2" thru_hole circle
			(at 1.999996 7.400036 180)
			(size 0.906272 0.906272)
			(drill 0.499872)
			(layers "*.Cu" "*.Mask")
			(remove_unused_layers no)
			(net "GND")
			(clearance 0.0508)
			(thermal_gap 0.0508)
		)
		(pad "G4" thru_hole circle
			(at 5.999988 7.400036 180)
			(size 0.906272 0.906272)
			(drill 0.499872)
			(layers "*.Cu" "*.Mask")
			(remove_unused_layers no)
			(net "GND")
			(clearance 0.0508)
			(thermal_gap 0.0508)
		)
		(pad "G6" thru_hole circle
			(at 9.99998 7.400036 180)
			(size 0.906272 0.906272)
			(drill 0.499872)
			(layers "*.Cu" "*.Mask")
			(remove_unused_layers no)
			(net "GND")
			(clearance 0.0508)
			(thermal_gap 0.0508)
		)
		(pad "G8" thru_hole circle
			(at 13.999972 7.400036 180)
			(size 0.906272 0.906272)
			(drill 0.499872)
			(layers "*.Cu" "*.Mask")
			(remove_unused_layers no)
			(net "GND")
			(clearance 0.0508)
			(thermal_gap 0.0508)
		)
		(pad "H1" thru_hole circle
			(at 0 8.400034 180)
			(size 0.906272 0.906272)
			(drill 0.499872)
			(layers "*.Cu" "*.Mask")
			(remove_unused_layers no)
			(net "GND")
			(clearance 0.0508)
			(thermal_gap 0.0508)
		)
		(pad "H3" thru_hole circle
			(at 3.999992 8.400034 180)
			(size 0.906272 0.906272)
			(drill 0.499872)
			(layers "*.Cu" "*.Mask")
			(remove_unused_layers no)
			(net "GND")
			(clearance 0.0508)
			(thermal_gap 0.0508)
		)
		(pad "H5" thru_hole circle
			(at 7.999984 8.400034 180)
			(size 0.906272 0.906272)
			(drill 0.499872)
			(layers "*.Cu" "*.Mask")
			(remove_unused_layers no)
			(net "GND")
			(clearance 0.0508)
			(thermal_gap 0.0508)
		)
		(pad "H7" thru_hole circle
			(at 11.999976 8.400034 180)
			(size 0.906272 0.906272)
			(drill 0.499872)
			(layers "*.Cu" "*.Mask")
			(remove_unused_layers no)
			(net "GND")
			(clearance 0.0508)
			(thermal_gap 0.0508)
		)
		(pad "J2" thru_hole circle
			(at 1.999996 10.999978 180)
			(size 0.906272 0.906272)
			(drill 0.499872)
			(layers "*.Cu" "*.Mask")
			(remove_unused_layers no)
			(net "GND")
			(clearance 0.0508)
			(thermal_gap 0.0508)
		)
		(pad "J4" thru_hole circle
			(at 5.999988 10.999978 180)
			(size 0.906272 0.906272)
			(drill 0.499872)
			(layers "*.Cu" "*.Mask")
			(remove_unused_layers no)
			(net "GND")
			(clearance 0.0508)
			(thermal_gap 0.0508)
		)
		(pad "J6" thru_hole circle
			(at 9.99998 10.999978 180)
			(size 0.906272 0.906272)
			(drill 0.499872)
			(layers "*.Cu" "*.Mask")
			(remove_unused_layers no)
			(net "GND")
			(clearance 0.0508)
			(thermal_gap 0.0508)
		)
		(pad "J8" thru_hole circle
			(at 13.999972 10.999978 180)
			(size 0.906272 0.906272)
			(drill 0.499872)
			(layers "*.Cu" "*.Mask")
			(remove_unused_layers no)
			(net "GND")
			(clearance 0.0508)
			(thermal_gap 0.0508)
		)
		(pad "K1" thru_hole circle
			(at 0 11.999976 180)
			(size 0.906272 0.906272)
			(drill 0.499872)
			(layers "*.Cu" "*.Mask")
			(remove_unused_layers no)
			(net "GND")
			(clearance 0.0508)
			(thermal_gap 0.0508)
		)
		(pad "K3" thru_hole circle
			(at 3.999992 11.999976 180)
			(size 0.906272 0.906272)
			(drill 0.499872)
			(layers "*.Cu" "*.Mask")
			(remove_unused_layers no)
			(net "GND")
			(clearance 0.0508)
			(thermal_gap 0.0508)
		)
		(pad "K5" thru_hole circle
			(at 7.999984 11.999976 180)
			(size 0.906272 0.906272)
			(drill 0.499872)
			(layers "*.Cu" "*.Mask")
			(remove_unused_layers no)
			(net "GND")
			(clearance 0.0508)
			(thermal_gap 0.0508)
		)
		(pad "K7" thru_hole circle
			(at 11.999976 11.999976 180)
			(size 0.906272 0.906272)
			(drill 0.499872)
			(layers "*.Cu" "*.Mask")
			(remove_unused_layers no)
			(net "GND")
			(clearance 0.0508)
			(thermal_gap 0.0508)
		)
		(pad "M2" thru_hole circle
			(at 1.999996 14.59992 180)
			(size 0.906272 0.906272)
			(drill 0.499872)
			(layers "*.Cu" "*.Mask")
			(remove_unused_layers no)
			(net "GND")
			(clearance 0.0508)
			(thermal_gap 0.0508)
		)
		(pad "M4" thru_hole circle
			(at 5.999988 14.59992 180)
			(size 0.906272 0.906272)
			(drill 0.499872)
			(layers "*.Cu" "*.Mask")
			(remove_unused_layers no)
			(net "GND")
			(clearance 0.0508)
			(thermal_gap 0.0508)
		)
		(pad "M6" thru_hole circle
			(at 9.99998 14.59992 180)
			(size 0.906272 0.906272)
			(drill 0.499872)
			(layers "*.Cu" "*.Mask")
			(remove_unused_layers no)
			(net "GND")
			(clearance 0.0508)
			(thermal_gap 0.0508)
		)
		(pad "M8" thru_hole circle
			(at 13.999972 14.59992 180)
			(size 0.906272 0.906272)
			(drill 0.499872)
			(layers "*.Cu" "*.Mask")
			(remove_unused_layers no)
			(net "GND")
			(clearance 0.0508)
			(thermal_gap 0.0508)
		)
		(pad "N1" thru_hole circle
			(at 0 15.599918 180)
			(size 0.906272 0.906272)
			(drill 0.499872)
			(layers "*.Cu" "*.Mask")
			(remove_unused_layers no)
			(net "GND")
			(clearance 0.0508)
			(thermal_gap 0.0508)
		)
		(pad "N2" thru_hole circle
			(at 1.999996 15.80007 180)
			(size 0.766318 0.766318)
			(drill 0.359918)
			(layers "*.Cu" "*.Mask")
			(remove_unused_layers no)
			(net "NC_J108_N2")
			(clearance 0.0508)
			(thermal_gap 0.0508)
		)
		(pad "N3" thru_hole circle
			(at 3.999992 15.599918 180)
			(size 0.906272 0.906272)
			(drill 0.499872)
			(layers "*.Cu" "*.Mask")
			(remove_unused_layers no)
			(net "GND")
			(clearance 0.0508)
			(thermal_gap 0.0508)
		)
		(pad "N4" thru_hole circle
			(at 5.999988 15.80007 180)
			(size 0.766318 0.766318)
			(drill 0.359918)
			(layers "*.Cu" "*.Mask")
			(remove_unused_layers no)
			(net "NC_J108_N4")
			(clearance 0.0508)
			(thermal_gap 0.0508)
		)
		(pad "N5" thru_hole circle
			(at 7.999984 15.599918 180)
			(size 0.906272 0.906272)
			(drill 0.499872)
			(layers "*.Cu" "*.Mask")
			(remove_unused_layers no)
			(net "GND")
			(clearance 0.0508)
			(thermal_gap 0.0508)
		)
		(pad "N6" thru_hole circle
			(at 9.99998 15.80007 180)
			(size 0.766318 0.766318)
			(drill 0.359918)
			(layers "*.Cu" "*.Mask")
			(remove_unused_layers no)
			(net "NC_J108_N6")
			(clearance 0.0508)
			(thermal_gap 0.0508)
		)
		(pad "N7" thru_hole circle
			(at 11.999976 15.599918 180)
			(size 0.906272 0.906272)
			(drill 0.499872)
			(layers "*.Cu" "*.Mask")
			(remove_unused_layers no)
			(net "GND")
			(clearance 0.0508)
			(thermal_gap 0.0508)
		)
		(pad "N8" thru_hole circle
			(at 13.999972 15.80007 180)
			(size 0.766318 0.766318)
			(drill 0.359918)
			(layers "*.Cu" "*.Mask")
			(remove_unused_layers no)
			(net "PRSNT_CABLE_GPU_A3_N")
			(clearance 0.0508)
			(thermal_gap 0.0508)
		)
	)
	(footprint ""
		(layer "F.Cu")
		(at 58.93308 -40.404034 180)
		(property "Reference" "R4066"
			(at 0 0 180)
			(layer "F.SilkS")
			(hide yes)
			(effects
				(font
					(size 1.27 1.27)
				)
			)
		)
		(property "Value" ""
			(at 0 0 180)
			(layer "F.Fab")
			(effects
				(font
					(size 1.27 1.27)
				)
			)
		)
		(duplicate_pad_numbers_are_jumpers no)
		(fp_line
			(start 0.7874 0.4064)
			(end -0.7874 0.4064)
			(stroke
				(width 0.1524)
				(type default)
			)
			(layer "F.SilkS")
		)
		(fp_line
			(start 0.7874 -0.4064)
			(end 0.7874 0.4064)
			(stroke
				(width 0.1524)
				(type default)
			)
			(layer "F.SilkS")
		)
		(fp_line
			(start -0.7874 0.4064)
			(end -0.7874 -0.4064)
			(stroke
				(width 0.1524)
				(type default)
			)
			(layer "F.SilkS")
		)
		(fp_line
			(start -0.7874 -0.4064)
			(end 0.7874 -0.4064)
			(stroke
				(width 0.1524)
				(type default)
			)
			(layer "F.SilkS")
		)
		(fp_line
			(start 0.67945 0.3048)
			(end 0.120396 0.3048)
			(stroke
				(width 0.1)
				(type default)
			)
			(layer "F.Fab")
		)
		(fp_line
			(start 0.67945 -0.3048)
			(end 0.67945 0.3048)
			(stroke
				(width 0.1)
				(type default)
			)
			(layer "F.Fab")
		)
		(fp_line
			(start 0.12065 -0.2794)
			(end 0.12065 -0.3048)
			(stroke
				(width 0.1)
				(type default)
			)
			(layer "F.Fab")
		)
		(fp_line
			(start 0.12065 -0.3048)
			(end 0.67945 -0.3048)
			(stroke
				(width 0.1)
				(type default)
			)
			(layer "F.Fab")
		)
		(fp_line
			(start 0.120396 0.3048)
			(end 0.120396 0.2794)
			(stroke
				(width 0.1)
				(type default)
			)
			(layer "F.Fab")
		)
		(fp_line
			(start 0.120396 0.2794)
			(end -0.12065 0.2794)
			(stroke
				(width 0.1)
				(type default)
			)
			(layer "F.Fab")
		)
		(fp_line
			(start -0.12065 0.3048)
			(end -0.67945 0.3048)
			(stroke
				(width 0.1)
				(type default)
			)
			(layer "F.Fab")
		)
		(fp_line
			(start -0.12065 0.2794)
			(end -0.12065 0.3048)
			(stroke
				(width 0.1)
				(type default)
			)
			(layer "F.Fab")
		)
		(fp_line
			(start -0.12065 -0.2794)
			(end 0.12065 -0.2794)
			(stroke
				(width 0.1)
				(type default)
			)
			(layer "F.Fab")
		)
		(fp_line
			(start -0.12065 -0.305054)
			(end -0.12065 -0.2794)
			(stroke
				(width 0.1)
				(type default)
			)
			(layer "F.Fab")
		)
		(fp_line
			(start -0.67945 0.3048)
			(end -0.67945 -0.305054)
			(stroke
				(width 0.1)
				(type default)
			)
			(layer "F.Fab")
		)
		(fp_line
			(start -0.67945 -0.305054)
			(end -0.12065 -0.305054)
			(stroke
				(width 0.1)
				(type default)
			)
			(layer "F.Fab")
		)
		(pad "1" smd circle
			(at -0.40005 0 180)
			(size 0 0)
			(layers "F.Cu" "F.Mask" "F.Paste")
			(net "P3V3_OCP_EN_2_R")
		)
		(pad "2" smd circle
			(at 0.40005 0 180)
			(size 0 0)
			(layers "F.Cu" "F.Mask" "F.Paste")
			(net "GND")
		)
	)
	(footprint ""
		(layer "F.Cu")
		(at 230.248206 -252.179836 180)
		(property "Reference" "R3335"
			(at 0 0 180)
			(layer "F.SilkS")
			(hide yes)
			(effects
				(font
					(size 1.27 1.27)
				)
			)
		)
		(property "Value" ""
			(at 0 0 180)
			(layer "F.Fab")
			(effects
				(font
					(size 1.27 1.27)
				)
			)
		)
		(duplicate_pad_numbers_are_jumpers no)
		(fp_line
			(start 0.7874 0.4064)
			(end -0.7874 0.4064)
			(stroke
				(width 0.1524)
				(type default)
			)
			(layer "F.SilkS")
		)
		(fp_line
			(start 0.7874 -0.4064)
			(end 0.7874 0.4064)
			(stroke
				(width 0.1524)
				(type default)
			)
			(layer "F.SilkS")
		)
		(fp_line
			(start -0.7874 0.4064)
			(end -0.7874 -0.4064)
			(stroke
				(width 0.1524)
				(type default)
			)
			(layer "F.SilkS")
		)
		(fp_line
			(start -0.7874 -0.4064)
			(end 0.7874 -0.4064)
			(stroke
				(width 0.1524)
				(type default)
			)
			(layer "F.SilkS")
		)
		(fp_line
			(start 0.67945 0.3048)
			(end 0.120396 0.3048)
			(stroke
				(width 0.1)
				(type default)
			)
			(layer "F.Fab")
		)
		(fp_line
			(start 0.67945 -0.3048)
			(end 0.67945 0.3048)
			(stroke
				(width 0.1)
				(type default)
			)
			(layer "F.Fab")
		)
		(fp_line
			(start 0.12065 -0.2794)
			(end 0.12065 -0.3048)
			(stroke
				(width 0.1)
				(type default)
			)
			(layer "F.Fab")
		)
		(fp_line
			(start 0.12065 -0.3048)
			(end 0.67945 -0.3048)
			(stroke
				(width 0.1)
				(type default)
			)
			(layer "F.Fab")
		)
		(fp_line
			(start 0.120396 0.3048)
			(end 0.120396 0.2794)
			(stroke
				(width 0.1)
				(type default)
			)
			(layer "F.Fab")
		)
		(fp_line
			(start 0.120396 0.2794)
			(end -0.12065 0.2794)
			(stroke
				(width 0.1)
				(type default)
			)
			(layer "F.Fab")
		)
		(fp_line
			(start -0.12065 0.3048)
			(end -0.67945 0.3048)
			(stroke
				(width 0.1)
				(type default)
			)
			(layer "F.Fab")
		)
		(fp_line
			(start -0.12065 0.2794)
			(end -0.12065 0.3048)
			(stroke
				(width 0.1)
				(type default)
			)
			(layer "F.Fab")
		)
		(fp_line
			(start -0.12065 -0.2794)
			(end 0.12065 -0.2794)
			(stroke
				(width 0.1)
				(type default)
			)
			(layer "F.Fab")
		)
		(fp_line
			(start -0.12065 -0.305054)
			(end -0.12065 -0.2794)
			(stroke
				(width 0.1)
				(type default)
			)
			(layer "F.Fab")
		)
		(fp_line
			(start -0.67945 0.3048)
			(end -0.67945 -0.305054)
			(stroke
				(width 0.1)
				(type default)
			)
			(layer "F.Fab")
		)
		(fp_line
			(start -0.67945 -0.305054)
			(end -0.12065 -0.305054)
			(stroke
				(width 0.1)
				(type default)
			)
			(layer "F.Fab")
		)
		(pad "1" smd circle
			(at -0.40005 0 180)
			(size 0 0)
			(layers "F.Cu" "F.Mask" "F.Paste")
			(net "CLK_100M_BMC_RC_DP_R")
		)
		(pad "2" smd circle
			(at 0.40005 0 180)
			(size 0 0)
			(layers "F.Cu" "F.Mask" "F.Paste")
			(net "CLK_100M_BMC_RC_DP")
		)
	)
	(footprint ""
		(layer "F.Cu")
		(at 48.501046 -358.129586 -90)
		(property "Reference" "PC1368"
			(at 0 0 270)
			(layer "F.SilkS")
			(hide yes)
			(effects
				(font
					(size 1.27 1.27)
				)
			)
		)
		(property "Value" ""
			(at 0 0 270)
			(layer "F.Fab")
			(effects
				(font
					(size 1.27 1.27)
				)
			)
		)
		(duplicate_pad_numbers_are_jumpers no)
		(fp_line
			(start -0.7874 0.4064)
			(end -0.7874 -0.4064)
			(stroke
				(width 0.1524)
				(type default)
			)
			(layer "F.SilkS")
		)
		(fp_line
			(start 0.7874 0.4064)
			(end -0.7874 0.4064)
			(stroke
				(width 0.1524)
				(type default)
			)
			(layer "F.SilkS")
		)
		(fp_line
			(start -0.7874 -0.4064)
			(end 0.7874 -0.4064)
			(stroke
				(width 0.1524)
				(type default)
			)
			(layer "F.SilkS")
		)
		(fp_line
			(start 0.7874 -0.4064)
			(end 0.7874 0.4064)
			(stroke
				(width 0.1524)
				(type default)
			)
			(layer "F.SilkS")
		)
		(fp_line
			(start -0.67945 0.3048)
			(end -0.67945 -0.305054)
			(stroke
				(width 0.1)
				(type default)
			)
			(layer "F.Fab")
		)
		(fp_line
			(start -0.12065 0.3048)
			(end -0.67945 0.3048)
			(stroke
				(width 0.1)
				(type default)
			)
			(layer "F.Fab")
		)
		(fp_line
			(start 0.120396 0.3048)
			(end 0.120396 0.2794)
			(stroke
				(width 0.1)
				(type default)
			)
			(layer "F.Fab")
		)
		(fp_line
			(start 0.67945 0.3048)
			(end 0.120396 0.3048)
			(stroke
				(width 0.1)
				(type default)
			)
			(layer "F.Fab")
		)
		(fp_line
			(start -0.12065 0.2794)
			(end -0.12065 0.3048)
			(stroke
				(width 0.1)
				(type default)
			)
			(layer "F.Fab")
		)
		(fp_line
			(start 0.120396 0.2794)
			(end -0.12065 0.2794)
			(stroke
				(width 0.1)
				(type default)
			)
			(layer "F.Fab")
		)
		(fp_line
			(start -0.12065 -0.2794)
			(end 0.12065 -0.2794)
			(stroke
				(width 0.1)
				(type default)
			)
			(layer "F.Fab")
		)
		(fp_line
			(start 0.12065 -0.2794)
			(end 0.12065 -0.3048)
			(stroke
				(width 0.1)
				(type default)
			)
			(layer "F.Fab")
		)
		(fp_line
			(start 0.12065 -0.3048)
			(end 0.67945 -0.3048)
			(stroke
				(width 0.1)
				(type default)
			)
			(layer "F.Fab")
		)
		(fp_line
			(start 0.67945 -0.3048)
			(end 0.67945 0.3048)
			(stroke
				(width 0.1)
				(type default)
			)
			(layer "F.Fab")
		)
		(fp_line
			(start -0.67945 -0.305054)
			(end -0.12065 -0.305054)
			(stroke
				(width 0.1)
				(type default)
			)
			(layer "F.Fab")
		)
		(fp_line
			(start -0.12065 -0.305054)
			(end -0.12065 -0.2794)
			(stroke
				(width 0.1)
				(type default)
			)
			(layer "F.Fab")
		)
		(pad "1" smd circle
			(at -0.40005 0 270)
			(size 0 0)
			(layers "F.Cu" "F.Mask" "F.Paste")
			(net "GND")
		)
		(pad "2" smd circle
			(at 0.40005 0 270)
			(size 0 0)
			(layers "F.Cu" "F.Mask" "F.Paste")
			(net "PVCCIN_CPU1_VREF")
		)
	)
	(footprint ""
		(layer "F.Cu")
		(at 158.901384 -44.632626 90)
		(property "Reference" "R4473"
			(at 0 0 90)
			(layer "F.SilkS")
			(hide yes)
			(effects
				(font
					(size 1.27 1.27)
				)
			)
		)
		(property "Value" ""
			(at 0 0 90)
			(layer "F.Fab")
			(effects
				(font
					(size 1.27 1.27)
				)
			)
		)
		(duplicate_pad_numbers_are_jumpers no)
		(fp_line
			(start -0.7874 -0.4064)
			(end 0.7874 -0.4064)
			(stroke
				(width 0.1524)
				(type default)
			)
			(layer "F.SilkS")
		)
		(fp_line
			(start -0.7874 0.4064)
			(end -0.7874 -0.4064)
			(stroke
				(width 0.1524)
				(type default)
			)
			(layer "F.SilkS")
		)
		(fp_line
			(start -0.12065 -0.305054)
			(end -0.12065 -0.2794)
			(stroke
				(width 0.1)
				(type default)
			)
			(layer "F.Fab")
		)
		(fp_line
			(start -0.67945 -0.305054)
			(end -0.12065 -0.305054)
			(stroke
				(width 0.1)
				(type default)
			)
			(layer "F.Fab")
		)
		(fp_line
			(start 0.67945 -0.3048)
			(end 0.67945 0.3048)
			(stroke
				(width 0.1)
				(type default)
			)
			(layer "F.Fab")
		)
		(fp_line
			(start 0.12065 -0.3048)
			(end 0.67945 -0.3048)
			(stroke
				(width 0.1)
				(type default)
			)
			(layer "F.Fab")
		)
		(fp_line
			(start 0.12065 -0.2794)
			(end 0.12065 -0.3048)
			(stroke
				(width 0.1)
				(type default)
			)
			(layer "F.Fab")
		)
		(fp_line
			(start -0.12065 -0.2794)
			(end 0.12065 -0.2794)
			(stroke
				(width 0.1)
				(type default)
			)
			(layer "F.Fab")
		)
		(fp_line
			(start 0.120396 0.2794)
			(end -0.12065 0.2794)
			(stroke
				(width 0.1)
				(type default)
			)
			(layer "F.Fab")
		)
		(fp_line
			(start -0.12065 0.2794)
			(end -0.12065 0.3048)
			(stroke
				(width 0.1)
				(type default)
			)
			(layer "F.Fab")
		)
		(fp_line
			(start 0.67945 0.3048)
			(end 0.120396 0.3048)
			(stroke
				(width 0.1)
				(type default)
			)
			(layer "F.Fab")
		)
		(fp_line
			(start 0.120396 0.3048)
			(end 0.120396 0.2794)
			(stroke
				(width 0.1)
				(type default)
			)
			(layer "F.Fab")
		)
		(fp_line
			(start -0.12065 0.3048)
			(end -0.67945 0.3048)
			(stroke
				(width 0.1)
				(type default)
			)
			(layer "F.Fab")
		)
		(fp_line
			(start -0.67945 0.3048)
			(end -0.67945 -0.305054)
			(stroke
				(width 0.1)
				(type default)
			)
			(layer "F.Fab")
		)
		(pad "1" smd rect
			(at -0.40005 0 270)
			(size 0.4572 0.508)
			(layers "F.Cu" "F.Mask" "F.Paste")
			(net "USB2_0_DP")
		)
		(pad "2" smd rect
			(at 0.40005 0 270)
			(size 0.4572 0.508)
			(layers "F.Cu" "F.Mask" "F.Paste")
			(net "USB2_HOST_PCH_0_DP")
		)
	)
	(footprint ""
		(layer "F.Cu")
		(at 312.443622 -45.202348 180)
		(property "Reference" "R698"
			(at 0 0 180)
			(layer "F.SilkS")
			(hide yes)
			(effects
				(font
					(size 1.27 1.27)
				)
			)
		)
		(property "Value" ""
			(at 0 0 180)
			(layer "F.Fab")
			(effects
				(font
					(size 1.27 1.27)
				)
			)
		)
		(duplicate_pad_numbers_are_jumpers no)
		(fp_line
			(start 0.7874 0.4064)
			(end -0.7874 0.4064)
			(stroke
				(width 0.1524)
				(type default)
			)
			(layer "F.SilkS")
		)
		(fp_line
			(start 0.7874 -0.4064)
			(end 0.7874 0.4064)
			(stroke
				(width 0.1524)
				(type default)
			)
			(layer "F.SilkS")
		)
		(fp_line
			(start -0.7874 0.4064)
			(end -0.7874 -0.4064)
			(stroke
				(width 0.1524)
				(type default)
			)
			(layer "F.SilkS")
		)
		(fp_line
			(start -0.7874 -0.4064)
			(end 0.7874 -0.4064)
			(stroke
				(width 0.1524)
				(type default)
			)
			(layer "F.SilkS")
		)
		(fp_line
			(start 0.67945 0.3048)
			(end 0.120396 0.3048)
			(stroke
				(width 0.1)
				(type default)
			)
			(layer "F.Fab")
		)
		(fp_line
			(start 0.67945 -0.3048)
			(end 0.67945 0.3048)
			(stroke
				(width 0.1)
				(type default)
			)
			(layer "F.Fab")
		)
		(fp_line
			(start 0.12065 -0.2794)
			(end 0.12065 -0.3048)
			(stroke
				(width 0.1)
				(type default)
			)
			(layer "F.Fab")
		)
		(fp_line
			(start 0.12065 -0.3048)
			(end 0.67945 -0.3048)
			(stroke
				(width 0.1)
				(type default)
			)
			(layer "F.Fab")
		)
		(fp_line
			(start 0.120396 0.3048)
			(end 0.120396 0.2794)
			(stroke
				(width 0.1)
				(type default)
			)
			(layer "F.Fab")
		)
		(fp_line
			(start 0.120396 0.2794)
			(end -0.12065 0.2794)
			(stroke
				(width 0.1)
				(type default)
			)
			(layer "F.Fab")
		)
		(fp_line
			(start -0.12065 0.3048)
			(end -0.67945 0.3048)
			(stroke
				(width 0.1)
				(type default)
			)
			(layer "F.Fab")
		)
		(fp_line
			(start -0.12065 0.2794)
			(end -0.12065 0.3048)
			(stroke
				(width 0.1)
				(type default)
			)
			(layer "F.Fab")
		)
		(fp_line
			(start -0.12065 -0.2794)
			(end 0.12065 -0.2794)
			(stroke
				(width 0.1)
				(type default)
			)
			(layer "F.Fab")
		)
		(fp_line
			(start -0.12065 -0.305054)
			(end -0.12065 -0.2794)
			(stroke
				(width 0.1)
				(type default)
			)
			(layer "F.Fab")
		)
		(fp_line
			(start -0.67945 0.3048)
			(end -0.67945 -0.305054)
			(stroke
				(width 0.1)
				(type default)
			)
			(layer "F.Fab")
		)
		(fp_line
			(start -0.67945 -0.305054)
			(end -0.12065 -0.305054)
			(stroke
				(width 0.1)
				(type default)
			)
			(layer "F.Fab")
		)
		(pad "1" smd circle
			(at -0.40005 0 180)
			(size 0 0)
			(layers "F.Cu" "F.Mask" "F.Paste")
			(net "FM_ADR_TRIGGER_R_N")
		)
		(pad "2" smd circle
			(at 0.40005 0 180)
			(size 0 0)
			(layers "F.Cu" "F.Mask" "F.Paste")
			(net "FM_ADR_TRIGGER_N")
		)
	)
	(footprint ""
		(layer "F.Cu")
		(at 67.994276 -79.078836)
		(property "Reference" "D82"
			(at -35.91941 34.331402 90)
			(unlocked yes)
			(layer "F.SilkS")
			(effects
				(font
					(size 0.635 0.4064)
					(thickness 0.1524)
				)
				(justify left)
			)
		)
		(property "Value" ""
			(at 0 0 0)
			(layer "F.Fab")
			(effects
				(font
					(size 1.27 1.27)
				)
			)
		)
		(duplicate_pad_numbers_are_jumpers no)
		(fp_line
			(start -0.90678 0.4826)
			(end -0.90678 -0.4699)
			(stroke
				(width 0.1524)
				(type default)
			)
			(layer "F.SilkS")
		)
		(fp_line
			(start -0.89408 -0.4826)
			(end 0.90678 -0.4826)
			(stroke
				(width 0.1524)
				(type default)
			)
			(layer "F.SilkS")
		)
		(fp_line
			(start -0.79248 -0.4826)
			(end 1.03378 -0.4826)
			(stroke
				(width 0.1524)
				(type default)
			)
			(layer "F.SilkS")
		)
		(fp_line
			(start -0.64008 -0.4826)
			(end 1.16078 -0.4826)
			(stroke
				(width 0.1524)
				(type default)
			)
			(layer "F.SilkS")
		)
		(fp_line
			(start 0.90678 -0.4826)
			(end 0.90678 0.4826)
			(stroke
				(width 0.1524)
				(type default)
			)
			(layer "F.SilkS")
		)
		(fp_line
			(start 0.90678 0.4826)
			(end -0.90678 0.4826)
			(stroke
				(width 0.1524)
				(type default)
			)
			(layer "F.SilkS")
		)
		(fp_line
			(start 1.03378 -0.4826)
			(end 1.03378 0.4826)
			(stroke
				(width 0.1524)
				(type default)
			)
			(layer "F.SilkS")
		)
		(fp_line
			(start 1.03378 0.4826)
			(end -0.79248 0.4826)
			(stroke
				(width 0.1524)
				(type default)
			)
			(layer "F.SilkS")
		)
		(fp_line
			(start 1.16078 -0.4826)
			(end 1.16078 0.4826)
			(stroke
				(width 0.1524)
				(type default)
			)
			(layer "F.SilkS")
		)
		(fp_line
			(start 1.16078 0.4826)
			(end -0.64008 0.4826)
			(stroke
				(width 0.1524)
				(type default)
			)
			(layer "F.SilkS")
		)
		(fp_line
			(start -0.499872 -0.249936)
			(end 0.499872 -0.249936)
			(stroke
				(width 0.1)
				(type default)
			)
			(layer "F.Fab")
		)
		(fp_line
			(start -0.499872 0.249936)
			(end -0.499872 -0.249936)
			(stroke
				(width 0.1)
				(type default)
			)
			(layer "F.Fab")
		)
		(fp_line
			(start 0.499872 -0.249936)
			(end 0.499872 0.249936)
			(stroke
				(width 0.1)
				(type default)
			)
			(layer "F.Fab")
		)
		(fp_line
			(start 0.499872 0.249936)
			(end -0.499872 0.249936)
			(stroke
				(width 0.1)
				(type default)
			)
			(layer "F.Fab")
		)
		(pad "A" smd rect
			(at -0.47498 0)
			(size 0.6096 0.7112)
			(layers "F.Cu" "F.Mask" "F.Paste")
			(net "LED_PWRGD_PVCCFA_EHV_CPU1")
		)
		(pad "C" smd rect
			(at 0.47498 0)
			(size 0.6096 0.7112)
			(layers "F.Cu" "F.Mask" "F.Paste")
			(net "LED_PWRGD_PVCCFA_EHV_CPU1_D")
		)
	)
	(footprint ""
		(layer "F.Cu")
		(at 260.561582 -75.505056)
		(property "Reference" "PR187"
			(at 0 0 0)
			(layer "F.SilkS")
			(hide yes)
			(effects
				(font
					(size 1.27 1.27)
				)
			)
		)
		(property "Value" ""
			(at 0 0 0)
			(layer "F.Fab")
			(effects
				(font
					(size 1.27 1.27)
				)
			)
		)
		(duplicate_pad_numbers_are_jumpers no)
		(fp_line
			(start -0.7874 -0.4064)
			(end 0.7874 -0.4064)
			(stroke
				(width 0.1524)
				(type default)
			)
			(layer "F.SilkS")
		)
		(fp_line
			(start -0.7874 0.4064)
			(end -0.7874 -0.4064)
			(stroke
				(width 0.1524)
				(type default)
			)
			(layer "F.SilkS")
		)
		(fp_line
			(start 0.7874 -0.4064)
			(end 0.7874 0.4064)
			(stroke
				(width 0.1524)
				(type default)
			)
			(layer "F.SilkS")
		)
		(fp_line
			(start 0.7874 0.4064)
			(end -0.7874 0.4064)
			(stroke
				(width 0.1524)
				(type default)
			)
			(layer "F.SilkS")
		)
		(fp_line
			(start -0.67945 -0.305054)
			(end -0.12065 -0.305054)
			(stroke
				(width 0.1)
				(type default)
			)
			(layer "F.Fab")
		)
		(fp_line
			(start -0.67945 0.3048)
			(end -0.67945 -0.305054)
			(stroke
				(width 0.1)
				(type default)
			)
			(layer "F.Fab")
		)
		(fp_line
			(start -0.12065 -0.305054)
			(end -0.12065 -0.2794)
			(stroke
				(width 0.1)
				(type default)
			)
			(layer "F.Fab")
		)
		(fp_line
			(start -0.12065 -0.2794)
			(end 0.12065 -0.2794)
			(stroke
				(width 0.1)
				(type default)
			)
			(layer "F.Fab")
		)
		(fp_line
			(start -0.12065 0.2794)
			(end -0.12065 0.3048)
			(stroke
				(width 0.1)
				(type default)
			)
			(layer "F.Fab")
		)
		(fp_line
			(start -0.12065 0.3048)
			(end -0.67945 0.3048)
			(stroke
				(width 0.1)
				(type default)
			)
			(layer "F.Fab")
		)
		(fp_line
			(start 0.120396 0.2794)
			(end -0.12065 0.2794)
			(stroke
				(width 0.1)
				(type default)
			)
			(layer "F.Fab")
		)
		(fp_line
			(start 0.120396 0.3048)
			(end 0.120396 0.2794)
			(stroke
				(width 0.1)
				(type default)
			)
			(layer "F.Fab")
		)
		(fp_line
			(start 0.12065 -0.3048)
			(end 0.67945 -0.3048)
			(stroke
				(width 0.1)
				(type default)
			)
			(layer "F.Fab")
		)
		(fp_line
			(start 0.12065 -0.2794)
			(end 0.12065 -0.3048)
			(stroke
				(width 0.1)
				(type default)
			)
			(layer "F.Fab")
		)
		(fp_line
			(start 0.67945 -0.3048)
			(end 0.67945 0.3048)
			(stroke
				(width 0.1)
				(type default)
			)
			(layer "F.Fab")
		)
		(fp_line
			(start 0.67945 0.3048)
			(end 0.120396 0.3048)
			(stroke
				(width 0.1)
				(type default)
			)
			(layer "F.Fab")
		)
		(pad "1" smd circle
			(at -0.40005 0)
			(size 0 0)
			(layers "F.Cu" "F.Mask" "F.Paste")
			(net "P1V05_PCH_AUX_FB")
		)
		(pad "2" smd circle
			(at 0.40005 0)
			(size 0 0)
			(layers "F.Cu" "F.Mask" "F.Paste")
			(net "SH_P1V05_PCH_AUX_N")
		)
	)
	(footprint ""
		(layer "F.Cu")
		(at 356.616 -413.095948)
		(property "Reference" "R4563"
			(at 0 0 0)
			(layer "F.SilkS")
			(hide yes)
			(effects
				(font
					(size 1.27 1.27)
				)
			)
		)
		(property "Value" ""
			(at 0 0 0)
			(layer "F.Fab")
			(effects
				(font
					(size 1.27 1.27)
				)
			)
		)
		(duplicate_pad_numbers_are_jumpers no)
		(fp_line
			(start -0.7874 -0.4064)
			(end 0.7874 -0.4064)
			(stroke
				(width 0.1524)
				(type default)
			)
			(layer "F.SilkS")
		)
		(fp_line
			(start -0.7874 0.4064)
			(end -0.7874 -0.4064)
			(stroke
				(width 0.1524)
				(type default)
			)
			(layer "F.SilkS")
		)
		(fp_line
			(start 0.7874 -0.4064)
			(end 0.7874 0.4064)
			(stroke
				(width 0.1524)
				(type default)
			)
			(layer "F.SilkS")
		)
		(fp_line
			(start 0.7874 0.4064)
			(end -0.7874 0.4064)
			(stroke
				(width 0.1524)
				(type default)
			)
			(layer "F.SilkS")
		)
		(fp_line
			(start -0.67945 -0.305054)
			(end -0.12065 -0.305054)
			(stroke
				(width 0.1)
				(type default)
			)
			(layer "F.Fab")
		)
		(fp_line
			(start -0.67945 0.3048)
			(end -0.67945 -0.305054)
			(stroke
				(width 0.1)
				(type default)
			)
			(layer "F.Fab")
		)
		(fp_line
			(start -0.12065 -0.305054)
			(end -0.12065 -0.2794)
			(stroke
				(width 0.1)
				(type default)
			)
			(layer "F.Fab")
		)
		(fp_line
			(start -0.12065 -0.2794)
			(end 0.12065 -0.2794)
			(stroke
				(width 0.1)
				(type default)
			)
			(layer "F.Fab")
		)
		(fp_line
			(start -0.12065 0.2794)
			(end -0.12065 0.3048)
			(stroke
				(width 0.1)
				(type default)
			)
			(layer "F.Fab")
		)
		(fp_line
			(start -0.12065 0.3048)
			(end -0.67945 0.3048)
			(stroke
				(width 0.1)
				(type default)
			)
			(layer "F.Fab")
		)
		(fp_line
			(start 0.120396 0.2794)
			(end -0.12065 0.2794)
			(stroke
				(width 0.1)
				(type default)
			)
			(layer "F.Fab")
		)
		(fp_line
			(start 0.120396 0.3048)
			(end 0.120396 0.2794)
			(stroke
				(width 0.1)
				(type default)
			)
			(layer "F.Fab")
		)
		(fp_line
			(start 0.12065 -0.3048)
			(end 0.67945 -0.3048)
			(stroke
				(width 0.1)
				(type default)
			)
			(layer "F.Fab")
		)
		(fp_line
			(start 0.12065 -0.2794)
			(end 0.12065 -0.3048)
			(stroke
				(width 0.1)
				(type default)
			)
			(layer "F.Fab")
		)
		(fp_line
			(start 0.67945 -0.3048)
			(end 0.67945 0.3048)
			(stroke
				(width 0.1)
				(type default)
			)
			(layer "F.Fab")
		)
		(fp_line
			(start 0.67945 0.3048)
			(end 0.120396 0.3048)
			(stroke
				(width 0.1)
				(type default)
			)
			(layer "F.Fab")
		)
		(pad "1" smd circle
			(at -0.40005 0)
			(size 0 0)
			(layers "F.Cu" "F.Mask" "F.Paste")
			(net "SWB_HSC_PWRGD_ISO_R")
		)
		(pad "2" smd circle
			(at 0.40005 0)
			(size 0 0)
			(layers "F.Cu" "F.Mask" "F.Paste")
			(net "SWB_HSC_PWRGD_ISO")
		)
	)
	(footprint ""
		(layer "F.Cu")
		(at 306.83454 -430.6697 -90)
		(property "Reference" "C2269"
			(at 0 0 270)
			(layer "F.SilkS")
			(hide yes)
			(effects
				(font
					(size 1.27 1.27)
				)
			)
		)
		(property "Value" ""
			(at 0 0 270)
			(layer "F.Fab")
			(effects
				(font
					(size 1.27 1.27)
				)
			)
		)
		(duplicate_pad_numbers_are_jumpers no)
		(fp_line
			(start -0.7874 0.4064)
			(end -0.7874 -0.4064)
			(stroke
				(width 0.1524)
				(type default)
			)
			(layer "F.SilkS")
		)
		(fp_line
			(start 0.7874 0.4064)
			(end -0.7874 0.4064)
			(stroke
				(width 0.1524)
				(type default)
			)
			(layer "F.SilkS")
		)
		(fp_line
			(start -0.7874 -0.4064)
			(end 0.7874 -0.4064)
			(stroke
				(width 0.1524)
				(type default)
			)
			(layer "F.SilkS")
		)
		(fp_line
			(start 0.7874 -0.4064)
			(end 0.7874 0.4064)
			(stroke
				(width 0.1524)
				(type default)
			)
			(layer "F.SilkS")
		)
		(fp_line
			(start -0.67945 0.3048)
			(end -0.67945 -0.305054)
			(stroke
				(width 0.1)
				(type default)
			)
			(layer "F.Fab")
		)
		(fp_line
			(start -0.12065 0.3048)
			(end -0.67945 0.3048)
			(stroke
				(width 0.1)
				(type default)
			)
			(layer "F.Fab")
		)
		(fp_line
			(start 0.120396 0.3048)
			(end 0.120396 0.2794)
			(stroke
				(width 0.1)
				(type default)
			)
			(layer "F.Fab")
		)
		(fp_line
			(start 0.67945 0.3048)
			(end 0.120396 0.3048)
			(stroke
				(width 0.1)
				(type default)
			)
			(layer "F.Fab")
		)
		(fp_line
			(start -0.12065 0.2794)
			(end -0.12065 0.3048)
			(stroke
				(width 0.1)
				(type default)
			)
			(layer "F.Fab")
		)
		(fp_line
			(start 0.120396 0.2794)
			(end -0.12065 0.2794)
			(stroke
				(width 0.1)
				(type default)
			)
			(layer "F.Fab")
		)
		(fp_line
			(start -0.12065 -0.2794)
			(end 0.12065 -0.2794)
			(stroke
				(width 0.1)
				(type default)
			)
			(layer "F.Fab")
		)
		(fp_line
			(start 0.12065 -0.2794)
			(end 0.12065 -0.3048)
			(stroke
				(width 0.1)
				(type default)
			)
			(layer "F.Fab")
		)
		(fp_line
			(start 0.12065 -0.3048)
			(end 0.67945 -0.3048)
			(stroke
				(width 0.1)
				(type default)
			)
			(layer "F.Fab")
		)
		(fp_line
			(start 0.67945 -0.3048)
			(end 0.67945 0.3048)
			(stroke
				(width 0.1)
				(type default)
			)
			(layer "F.Fab")
		)
		(fp_line
			(start -0.67945 -0.305054)
			(end -0.12065 -0.305054)
			(stroke
				(width 0.1)
				(type default)
			)
			(layer "F.Fab")
		)
		(fp_line
			(start -0.12065 -0.305054)
			(end -0.12065 -0.2794)
			(stroke
				(width 0.1)
				(type default)
			)
			(layer "F.Fab")
		)
		(pad "1" smd circle
			(at -0.40005 0 270)
			(size 0 0)
			(layers "F.Cu" "F.Mask" "F.Paste")
			(net "PRSNT_CABLE_GPU_A2_ISO_N")
		)
		(pad "2" smd circle
			(at 0.40005 0 270)
			(size 0 0)
			(layers "F.Cu" "F.Mask" "F.Paste")
			(net "GND")
		)
	)
	(footprint ""
		(layer "F.Cu")
		(at 139.423394 -402.371052 -90)
		(property "Reference" "C754"
			(at 0 0 270)
			(layer "F.SilkS")
			(hide yes)
			(effects
				(font
					(size 1.27 1.27)
				)
			)
		)
		(property "Value" ""
			(at 0 0 270)
			(layer "F.Fab")
			(effects
				(font
					(size 1.27 1.27)
				)
			)
		)
		(duplicate_pad_numbers_are_jumpers no)
		(fp_line
			(start -0.299974 0.150114)
			(end -0.299974 -0.150114)
			(stroke
				(width 0.1)
				(type default)
			)
			(layer "F.Fab")
		)
		(fp_line
			(start 0.299974 0.150114)
			(end -0.299974 0.150114)
			(stroke
				(width 0.1)
				(type default)
			)
			(layer "F.Fab")
		)
		(fp_line
			(start -0.299974 -0.150114)
			(end 0.299974 -0.150114)
			(stroke
				(width 0.1)
				(type default)
			)
			(layer "F.Fab")
		)
		(fp_line
			(start 0.299974 -0.150114)
			(end 0.299974 0.150114)
			(stroke
				(width 0.1)
				(type default)
			)
			(layer "F.Fab")
		)
		(pad "1" smd rect
			(at -0.2667 0 270)
			(size 0.3048 0.381)
			(layers "F.Cu" "F.Mask" "F.Paste")
			(net "P5E_CPU1_PE2_TX_C_DN<9>")
		)
		(pad "2" smd rect
			(at 0.2667 0 270)
			(size 0.3048 0.381)
			(layers "F.Cu" "F.Mask" "F.Paste")
			(net "P5E_CPU1_PE2_TX_DN<9>")
		)
	)
	(footprint ""
		(layer "F.Cu")
		(at 61.980572 -178.662838 180)
		(property "Reference" "PC434"
			(at 0 0 180)
			(layer "F.SilkS")
			(hide yes)
			(effects
				(font
					(size 1.27 1.27)
				)
			)
		)
		(property "Value" ""
			(at 0 0 180)
			(layer "F.Fab")
			(effects
				(font
					(size 1.27 1.27)
				)
			)
		)
		(duplicate_pad_numbers_are_jumpers no)
		(fp_line
			(start 0.7874 0.4064)
			(end -0.7874 0.4064)
			(stroke
				(width 0.1524)
				(type default)
			)
			(layer "F.SilkS")
		)
		(fp_line
			(start 0.7874 -0.4064)
			(end 0.7874 0.4064)
			(stroke
				(width 0.1524)
				(type default)
			)
			(layer "F.SilkS")
		)
		(fp_line
			(start -0.7874 0.4064)
			(end -0.7874 -0.4064)
			(stroke
				(width 0.1524)
				(type default)
			)
			(layer "F.SilkS")
		)
		(fp_line
			(start -0.7874 -0.4064)
			(end 0.7874 -0.4064)
			(stroke
				(width 0.1524)
				(type default)
			)
			(layer "F.SilkS")
		)
		(fp_line
			(start 0.67945 0.3048)
			(end 0.120396 0.3048)
			(stroke
				(width 0.1)
				(type default)
			)
			(layer "F.Fab")
		)
		(fp_line
			(start 0.67945 -0.3048)
			(end 0.67945 0.3048)
			(stroke
				(width 0.1)
				(type default)
			)
			(layer "F.Fab")
		)
		(fp_line
			(start 0.12065 -0.2794)
			(end 0.12065 -0.3048)
			(stroke
				(width 0.1)
				(type default)
			)
			(layer "F.Fab")
		)
		(fp_line
			(start 0.12065 -0.3048)
			(end 0.67945 -0.3048)
			(stroke
				(width 0.1)
				(type default)
			)
			(layer "F.Fab")
		)
		(fp_line
			(start 0.120396 0.3048)
			(end 0.120396 0.2794)
			(stroke
				(width 0.1)
				(type default)
			)
			(layer "F.Fab")
		)
		(fp_line
			(start 0.120396 0.2794)
			(end -0.12065 0.2794)
			(stroke
				(width 0.1)
				(type default)
			)
			(layer "F.Fab")
		)
		(fp_line
			(start -0.12065 0.3048)
			(end -0.67945 0.3048)
			(stroke
				(width 0.1)
				(type default)
			)
			(layer "F.Fab")
		)
		(fp_line
			(start -0.12065 0.2794)
			(end -0.12065 0.3048)
			(stroke
				(width 0.1)
				(type default)
			)
			(layer "F.Fab")
		)
		(fp_line
			(start -0.12065 -0.2794)
			(end 0.12065 -0.2794)
			(stroke
				(width 0.1)
				(type default)
			)
			(layer "F.Fab")
		)
		(fp_line
			(start -0.12065 -0.305054)
			(end -0.12065 -0.2794)
			(stroke
				(width 0.1)
				(type default)
			)
			(layer "F.Fab")
		)
		(fp_line
			(start -0.67945 0.3048)
			(end -0.67945 -0.305054)
			(stroke
				(width 0.1)
				(type default)
			)
			(layer "F.Fab")
		)
		(fp_line
			(start -0.67945 -0.305054)
			(end -0.12065 -0.305054)
			(stroke
				(width 0.1)
				(type default)
			)
			(layer "F.Fab")
		)
		(pad "1" smd circle
			(at -0.40005 0 180)
			(size 0 0)
			(layers "F.Cu" "F.Mask" "F.Paste")
			(net "PVCCFA_EHV_CPU1")
		)
		(pad "2" smd circle
			(at 0.40005 0 180)
			(size 0 0)
			(layers "F.Cu" "F.Mask" "F.Paste")
			(net "GND")
		)
	)
	(footprint ""
		(layer "F.Cu")
		(at 211.99221 -26.868374 -90)
		(property "Reference" "C1274"
			(at 0 0 270)
			(layer "F.SilkS")
			(hide yes)
			(effects
				(font
					(size 1.27 1.27)
				)
			)
		)
		(property "Value" ""
			(at 0 0 270)
			(layer "F.Fab")
			(effects
				(font
					(size 1.27 1.27)
				)
			)
		)
		(duplicate_pad_numbers_are_jumpers no)
		(fp_line
			(start -0.7874 0.4064)
			(end -0.7874 -0.4064)
			(stroke
				(width 0.1524)
				(type default)
			)
			(layer "F.SilkS")
		)
		(fp_line
			(start 0.7874 0.4064)
			(end -0.7874 0.4064)
			(stroke
				(width 0.1524)
				(type default)
			)
			(layer "F.SilkS")
		)
		(fp_line
			(start -0.7874 -0.4064)
			(end 0.7874 -0.4064)
			(stroke
				(width 0.1524)
				(type default)
			)
			(layer "F.SilkS")
		)
		(fp_line
			(start 0.7874 -0.4064)
			(end 0.7874 0.4064)
			(stroke
				(width 0.1524)
				(type default)
			)
			(layer "F.SilkS")
		)
		(fp_line
			(start -0.67945 0.3048)
			(end -0.67945 -0.305054)
			(stroke
				(width 0.1)
				(type default)
			)
			(layer "F.Fab")
		)
		(fp_line
			(start -0.12065 0.3048)
			(end -0.67945 0.3048)
			(stroke
				(width 0.1)
				(type default)
			)
			(layer "F.Fab")
		)
		(fp_line
			(start 0.120396 0.3048)
			(end 0.120396 0.2794)
			(stroke
				(width 0.1)
				(type default)
			)
			(layer "F.Fab")
		)
		(fp_line
			(start 0.67945 0.3048)
			(end 0.120396 0.3048)
			(stroke
				(width 0.1)
				(type default)
			)
			(layer "F.Fab")
		)
		(fp_line
			(start -0.12065 0.2794)
			(end -0.12065 0.3048)
			(stroke
				(width 0.1)
				(type default)
			)
			(layer "F.Fab")
		)
		(fp_line
			(start 0.120396 0.2794)
			(end -0.12065 0.2794)
			(stroke
				(width 0.1)
				(type default)
			)
			(layer "F.Fab")
		)
		(fp_line
			(start -0.12065 -0.2794)
			(end 0.12065 -0.2794)
			(stroke
				(width 0.1)
				(type default)
			)
			(layer "F.Fab")
		)
		(fp_line
			(start 0.12065 -0.2794)
			(end 0.12065 -0.3048)
			(stroke
				(width 0.1)
				(type default)
			)
			(layer "F.Fab")
		)
		(fp_line
			(start 0.12065 -0.3048)
			(end 0.67945 -0.3048)
			(stroke
				(width 0.1)
				(type default)
			)
			(layer "F.Fab")
		)
		(fp_line
			(start 0.67945 -0.3048)
			(end 0.67945 0.3048)
			(stroke
				(width 0.1)
				(type default)
			)
			(layer "F.Fab")
		)
		(fp_line
			(start -0.67945 -0.305054)
			(end -0.12065 -0.305054)
			(stroke
				(width 0.1)
				(type default)
			)
			(layer "F.Fab")
		)
		(fp_line
			(start -0.12065 -0.305054)
			(end -0.12065 -0.2794)
			(stroke
				(width 0.1)
				(type default)
			)
			(layer "F.Fab")
		)
		(pad "1" smd circle
			(at -0.40005 0 270)
			(size 0 0)
			(layers "F.Cu" "F.Mask" "F.Paste")
			(net "P3V3_AUX")
		)
		(pad "2" smd circle
			(at 0.40005 0 270)
			(size 0 0)
			(layers "F.Cu" "F.Mask" "F.Paste")
			(net "GND")
		)
	)
	(footprint ""
		(layer "F.Cu")
		(at 24.046942 -416.143948 180)
		(property "Reference" "R3513"
			(at 0 0 180)
			(layer "F.SilkS")
			(hide yes)
			(effects
				(font
					(size 1.27 1.27)
				)
			)
		)
		(property "Value" ""
			(at 0 0 180)
			(layer "F.Fab")
			(effects
				(font
					(size 1.27 1.27)
				)
			)
		)
		(duplicate_pad_numbers_are_jumpers no)
		(fp_line
			(start 0.7874 0.4064)
			(end -0.7874 0.4064)
			(stroke
				(width 0.1524)
				(type default)
			)
			(layer "F.SilkS")
		)
		(fp_line
			(start 0.7874 -0.4064)
			(end 0.7874 0.4064)
			(stroke
				(width 0.1524)
				(type default)
			)
			(layer "F.SilkS")
		)
		(fp_line
			(start -0.7874 0.4064)
			(end -0.7874 -0.4064)
			(stroke
				(width 0.1524)
				(type default)
			)
			(layer "F.SilkS")
		)
		(fp_line
			(start -0.7874 -0.4064)
			(end 0.7874 -0.4064)
			(stroke
				(width 0.1524)
				(type default)
			)
			(layer "F.SilkS")
		)
		(fp_line
			(start 0.67945 0.3048)
			(end 0.120396 0.3048)
			(stroke
				(width 0.1)
				(type default)
			)
			(layer "F.Fab")
		)
		(fp_line
			(start 0.67945 -0.3048)
			(end 0.67945 0.3048)
			(stroke
				(width 0.1)
				(type default)
			)
			(layer "F.Fab")
		)
		(fp_line
			(start 0.12065 -0.2794)
			(end 0.12065 -0.3048)
			(stroke
				(width 0.1)
				(type default)
			)
			(layer "F.Fab")
		)
		(fp_line
			(start 0.12065 -0.3048)
			(end 0.67945 -0.3048)
			(stroke
				(width 0.1)
				(type default)
			)
			(layer "F.Fab")
		)
		(fp_line
			(start 0.120396 0.3048)
			(end 0.120396 0.2794)
			(stroke
				(width 0.1)
				(type default)
			)
			(layer "F.Fab")
		)
		(fp_line
			(start 0.120396 0.2794)
			(end -0.12065 0.2794)
			(stroke
				(width 0.1)
				(type default)
			)
			(layer "F.Fab")
		)
		(fp_line
			(start -0.12065 0.3048)
			(end -0.67945 0.3048)
			(stroke
				(width 0.1)
				(type default)
			)
			(layer "F.Fab")
		)
		(fp_line
			(start -0.12065 0.2794)
			(end -0.12065 0.3048)
			(stroke
				(width 0.1)
				(type default)
			)
			(layer "F.Fab")
		)
		(fp_line
			(start -0.12065 -0.2794)
			(end 0.12065 -0.2794)
			(stroke
				(width 0.1)
				(type default)
			)
			(layer "F.Fab")
		)
		(fp_line
			(start -0.12065 -0.305054)
			(end -0.12065 -0.2794)
			(stroke
				(width 0.1)
				(type default)
			)
			(layer "F.Fab")
		)
		(fp_line
			(start -0.67945 0.3048)
			(end -0.67945 -0.305054)
			(stroke
				(width 0.1)
				(type default)
			)
			(layer "F.Fab")
		)
		(fp_line
			(start -0.67945 -0.305054)
			(end -0.12065 -0.305054)
			(stroke
				(width 0.1)
				(type default)
			)
			(layer "F.Fab")
		)
		(pad "1" smd circle
			(at -0.40005 0 180)
			(size 0 0)
			(layers "F.Cu" "F.Mask" "F.Paste")
			(net "FM_GPU_PWRGD")
		)
		(pad "2" smd circle
			(at 0.40005 0 180)
			(size 0 0)
			(layers "F.Cu" "F.Mask" "F.Paste")
			(net "GND")
		)
	)
	(footprint ""
		(layer "F.Cu")
		(at 173.216062 -29.430472)
		(property "Reference" "R3836"
			(at 0 0 0)
			(layer "F.SilkS")
			(hide yes)
			(effects
				(font
					(size 1.27 1.27)
				)
			)
		)
		(property "Value" ""
			(at 0 0 0)
			(layer "F.Fab")
			(effects
				(font
					(size 1.27 1.27)
				)
			)
		)
		(duplicate_pad_numbers_are_jumpers no)
		(fp_line
			(start -0.7874 -0.4064)
			(end 0.7874 -0.4064)
			(stroke
				(width 0.1524)
				(type default)
			)
			(layer "F.SilkS")
		)
		(fp_line
			(start -0.7874 0.4064)
			(end -0.7874 -0.4064)
			(stroke
				(width 0.1524)
				(type default)
			)
			(layer "F.SilkS")
		)
		(fp_line
			(start 0.7874 -0.4064)
			(end 0.7874 0.4064)
			(stroke
				(width 0.1524)
				(type default)
			)
			(layer "F.SilkS")
		)
		(fp_line
			(start 0.7874 0.4064)
			(end -0.7874 0.4064)
			(stroke
				(width 0.1524)
				(type default)
			)
			(layer "F.SilkS")
		)
		(fp_line
			(start -0.67945 -0.305054)
			(end -0.12065 -0.305054)
			(stroke
				(width 0.1)
				(type default)
			)
			(layer "F.Fab")
		)
		(fp_line
			(start -0.67945 0.3048)
			(end -0.67945 -0.305054)
			(stroke
				(width 0.1)
				(type default)
			)
			(layer "F.Fab")
		)
		(fp_line
			(start -0.12065 -0.305054)
			(end -0.12065 -0.2794)
			(stroke
				(width 0.1)
				(type default)
			)
			(layer "F.Fab")
		)
		(fp_line
			(start -0.12065 -0.2794)
			(end 0.12065 -0.2794)
			(stroke
				(width 0.1)
				(type default)
			)
			(layer "F.Fab")
		)
		(fp_line
			(start -0.12065 0.2794)
			(end -0.12065 0.3048)
			(stroke
				(width 0.1)
				(type default)
			)
			(layer "F.Fab")
		)
		(fp_line
			(start -0.12065 0.3048)
			(end -0.67945 0.3048)
			(stroke
				(width 0.1)
				(type default)
			)
			(layer "F.Fab")
		)
		(fp_line
			(start 0.120396 0.2794)
			(end -0.12065 0.2794)
			(stroke
				(width 0.1)
				(type default)
			)
			(layer "F.Fab")
		)
		(fp_line
			(start 0.120396 0.3048)
			(end 0.120396 0.2794)
			(stroke
				(width 0.1)
				(type default)
			)
			(layer "F.Fab")
		)
		(fp_line
			(start 0.12065 -0.3048)
			(end 0.67945 -0.3048)
			(stroke
				(width 0.1)
				(type default)
			)
			(layer "F.Fab")
		)
		(fp_line
			(start 0.12065 -0.2794)
			(end 0.12065 -0.3048)
			(stroke
				(width 0.1)
				(type default)
			)
			(layer "F.Fab")
		)
		(fp_line
			(start 0.67945 -0.3048)
			(end 0.67945 0.3048)
			(stroke
				(width 0.1)
				(type default)
			)
			(layer "F.Fab")
		)
		(fp_line
			(start 0.67945 0.3048)
			(end 0.120396 0.3048)
			(stroke
				(width 0.1)
				(type default)
			)
			(layer "F.Fab")
		)
		(pad "1" smd circle
			(at -0.40005 0)
			(size 0 0)
			(layers "F.Cu" "F.Mask" "F.Paste")
			(net "P3V3_AUX")
		)
		(pad "2" smd circle
			(at 0.40005 0)
			(size 0 0)
			(layers "F.Cu" "F.Mask" "F.Paste")
			(net "HP_LVC3_SCM_HSC_PWRGD_R")
		)
	)
	(footprint ""
		(layer "F.Cu")
		(at 209.35188 -108.422948 90)
		(property "Reference" "R2339"
			(at 0 0 90)
			(layer "F.SilkS")
			(hide yes)
			(effects
				(font
					(size 1.27 1.27)
				)
			)
		)
		(property "Value" ""
			(at 0 0 90)
			(layer "F.Fab")
			(effects
				(font
					(size 1.27 1.27)
				)
			)
		)
		(duplicate_pad_numbers_are_jumpers no)
		(fp_line
			(start 0.7874 -0.4064)
			(end 0.7874 0.4064)
			(stroke
				(width 0.1524)
				(type default)
			)
			(layer "F.SilkS")
		)
		(fp_line
			(start -0.7874 -0.4064)
			(end 0.7874 -0.4064)
			(stroke
				(width 0.1524)
				(type default)
			)
			(layer "F.SilkS")
		)
		(fp_line
			(start 0.7874 0.4064)
			(end -0.7874 0.4064)
			(stroke
				(width 0.1524)
				(type default)
			)
			(layer "F.SilkS")
		)
		(fp_line
			(start -0.7874 0.4064)
			(end -0.7874 -0.4064)
			(stroke
				(width 0.1524)
				(type default)
			)
			(layer "F.SilkS")
		)
		(fp_line
			(start -0.12065 -0.305054)
			(end -0.12065 -0.2794)
			(stroke
				(width 0.1)
				(type default)
			)
			(layer "F.Fab")
		)
		(fp_line
			(start -0.67945 -0.305054)
			(end -0.12065 -0.305054)
			(stroke
				(width 0.1)
				(type default)
			)
			(layer "F.Fab")
		)
		(fp_line
			(start 0.67945 -0.3048)
			(end 0.67945 0.3048)
			(stroke
				(width 0.1)
				(type default)
			)
			(layer "F.Fab")
		)
		(fp_line
			(start 0.12065 -0.3048)
			(end 0.67945 -0.3048)
			(stroke
				(width 0.1)
				(type default)
			)
			(layer "F.Fab")
		)
		(fp_line
			(start 0.12065 -0.2794)
			(end 0.12065 -0.3048)
			(stroke
				(width 0.1)
				(type default)
			)
			(layer "F.Fab")
		)
		(fp_line
			(start -0.12065 -0.2794)
			(end 0.12065 -0.2794)
			(stroke
				(width 0.1)
				(type default)
			)
			(layer "F.Fab")
		)
		(fp_line
			(start 0.120396 0.2794)
			(end -0.12065 0.2794)
			(stroke
				(width 0.1)
				(type default)
			)
			(layer "F.Fab")
		)
		(fp_line
			(start -0.12065 0.2794)
			(end -0.12065 0.3048)
			(stroke
				(width 0.1)
				(type default)
			)
			(layer "F.Fab")
		)
		(fp_line
			(start 0.67945 0.3048)
			(end 0.120396 0.3048)
			(stroke
				(width 0.1)
				(type default)
			)
			(layer "F.Fab")
		)
		(fp_line
			(start 0.120396 0.3048)
			(end 0.120396 0.2794)
			(stroke
				(width 0.1)
				(type default)
			)
			(layer "F.Fab")
		)
		(fp_line
			(start -0.12065 0.3048)
			(end -0.67945 0.3048)
			(stroke
				(width 0.1)
				(type default)
			)
			(layer "F.Fab")
		)
		(fp_line
			(start -0.67945 0.3048)
			(end -0.67945 -0.305054)
			(stroke
				(width 0.1)
				(type default)
			)
			(layer "F.Fab")
		)
		(pad "1" smd circle
			(at -0.40005 0 90)
			(size 0 0)
			(layers "F.Cu" "F.Mask" "F.Paste")
			(net "LED_CPU_RMCA_CATERR_R")
		)
		(pad "2" smd circle
			(at 0.40005 0 90)
			(size 0 0)
			(layers "F.Cu" "F.Mask" "F.Paste")
			(net "GND")
		)
	)
	(footprint ""
		(layer "F.Cu")
		(at 191.861186 -438.17413 -90)
		(property "Reference" "R3770"
			(at 0 0 270)
			(layer "F.SilkS")
			(hide yes)
			(effects
				(font
					(size 1.27 1.27)
				)
			)
		)
		(property "Value" ""
			(at 0 0 270)
			(layer "F.Fab")
			(effects
				(font
					(size 1.27 1.27)
				)
			)
		)
		(duplicate_pad_numbers_are_jumpers no)
		(fp_line
			(start -0.7874 0.4064)
			(end -0.7874 -0.4064)
			(stroke
				(width 0.1524)
				(type default)
			)
			(layer "F.SilkS")
		)
		(fp_line
			(start 0.7874 0.4064)
			(end -0.7874 0.4064)
			(stroke
				(width 0.1524)
				(type default)
			)
			(layer "F.SilkS")
		)
		(fp_line
			(start -0.7874 -0.4064)
			(end 0.7874 -0.4064)
			(stroke
				(width 0.1524)
				(type default)
			)
			(layer "F.SilkS")
		)
		(fp_line
			(start 0.7874 -0.4064)
			(end 0.7874 0.4064)
			(stroke
				(width 0.1524)
				(type default)
			)
			(layer "F.SilkS")
		)
		(fp_line
			(start -0.67945 0.3048)
			(end -0.67945 -0.305054)
			(stroke
				(width 0.1)
				(type default)
			)
			(layer "F.Fab")
		)
		(fp_line
			(start -0.12065 0.3048)
			(end -0.67945 0.3048)
			(stroke
				(width 0.1)
				(type default)
			)
			(layer "F.Fab")
		)
		(fp_line
			(start 0.120396 0.3048)
			(end 0.120396 0.2794)
			(stroke
				(width 0.1)
				(type default)
			)
			(layer "F.Fab")
		)
		(fp_line
			(start 0.67945 0.3048)
			(end 0.120396 0.3048)
			(stroke
				(width 0.1)
				(type default)
			)
			(layer "F.Fab")
		)
		(fp_line
			(start -0.12065 0.2794)
			(end -0.12065 0.3048)
			(stroke
				(width 0.1)
				(type default)
			)
			(layer "F.Fab")
		)
		(fp_line
			(start 0.120396 0.2794)
			(end -0.12065 0.2794)
			(stroke
				(width 0.1)
				(type default)
			)
			(layer "F.Fab")
		)
		(fp_line
			(start -0.12065 -0.2794)
			(end 0.12065 -0.2794)
			(stroke
				(width 0.1)
				(type default)
			)
			(layer "F.Fab")
		)
		(fp_line
			(start 0.12065 -0.2794)
			(end 0.12065 -0.3048)
			(stroke
				(width 0.1)
				(type default)
			)
			(layer "F.Fab")
		)
		(fp_line
			(start 0.12065 -0.3048)
			(end 0.67945 -0.3048)
			(stroke
				(width 0.1)
				(type default)
			)
			(layer "F.Fab")
		)
		(fp_line
			(start 0.67945 -0.3048)
			(end 0.67945 0.3048)
			(stroke
				(width 0.1)
				(type default)
			)
			(layer "F.Fab")
		)
		(fp_line
			(start -0.67945 -0.305054)
			(end -0.12065 -0.305054)
			(stroke
				(width 0.1)
				(type default)
			)
			(layer "F.Fab")
		)
		(fp_line
			(start -0.12065 -0.305054)
			(end -0.12065 -0.2794)
			(stroke
				(width 0.1)
				(type default)
			)
			(layer "F.Fab")
		)
		(pad "1" smd circle
			(at -0.40005 0 270)
			(size 0 0)
			(layers "F.Cu" "F.Mask" "F.Paste")
			(net "GPU_PRSNT")
		)
		(pad "2" smd circle
			(at 0.40005 0 270)
			(size 0 0)
			(layers "F.Cu" "F.Mask" "F.Paste")
			(net "GPU_PRSNT_R")
		)
	)
	(footprint ""
		(layer "F.Cu")
		(at 160.28035 -44.632626 90)
		(property "Reference" "R4474"
			(at 0 0 90)
			(layer "F.SilkS")
			(hide yes)
			(effects
				(font
					(size 1.27 1.27)
				)
			)
		)
		(property "Value" ""
			(at 0 0 90)
			(layer "F.Fab")
			(effects
				(font
					(size 1.27 1.27)
				)
			)
		)
		(duplicate_pad_numbers_are_jumpers no)
		(fp_line
			(start 0.7874 0.4064)
			(end -0.7874 0.4064)
			(stroke
				(width 0.1524)
				(type default)
			)
			(layer "F.SilkS")
		)
		(fp_line
			(start -0.7874 0.4064)
			(end -0.7874 -0.4064)
			(stroke
				(width 0.1524)
				(type default)
			)
			(layer "F.SilkS")
		)
		(fp_line
			(start -0.12065 -0.305054)
			(end -0.12065 -0.2794)
			(stroke
				(width 0.1)
				(type default)
			)
			(layer "F.Fab")
		)
		(fp_line
			(start -0.67945 -0.305054)
			(end -0.12065 -0.305054)
			(stroke
				(width 0.1)
				(type default)
			)
			(layer "F.Fab")
		)
		(fp_line
			(start 0.67945 -0.3048)
			(end 0.67945 0.3048)
			(stroke
				(width 0.1)
				(type default)
			)
			(layer "F.Fab")
		)
		(fp_line
			(start 0.12065 -0.3048)
			(end 0.67945 -0.3048)
			(stroke
				(width 0.1)
				(type default)
			)
			(layer "F.Fab")
		)
		(fp_line
			(start 0.12065 -0.2794)
			(end 0.12065 -0.3048)
			(stroke
				(width 0.1)
				(type default)
			)
			(layer "F.Fab")
		)
		(fp_line
			(start -0.12065 -0.2794)
			(end 0.12065 -0.2794)
			(stroke
				(width 0.1)
				(type default)
			)
			(layer "F.Fab")
		)
		(fp_line
			(start 0.120396 0.2794)
			(end -0.12065 0.2794)
			(stroke
				(width 0.1)
				(type default)
			)
			(layer "F.Fab")
		)
		(fp_line
			(start -0.12065 0.2794)
			(end -0.12065 0.3048)
			(stroke
				(width 0.1)
				(type default)
			)
			(layer "F.Fab")
		)
		(fp_line
			(start 0.67945 0.3048)
			(end 0.120396 0.3048)
			(stroke
				(width 0.1)
				(type default)
			)
			(layer "F.Fab")
		)
		(fp_line
			(start 0.120396 0.3048)
			(end 0.120396 0.2794)
			(stroke
				(width 0.1)
				(type default)
			)
			(layer "F.Fab")
		)
		(fp_line
			(start -0.12065 0.3048)
			(end -0.67945 0.3048)
			(stroke
				(width 0.1)
				(type default)
			)
			(layer "F.Fab")
		)
		(fp_line
			(start -0.67945 0.3048)
			(end -0.67945 -0.305054)
			(stroke
				(width 0.1)
				(type default)
			)
			(layer "F.Fab")
		)
		(pad "1" smd rect
			(at -0.40005 0 270)
			(size 0.4572 0.508)
			(layers "F.Cu" "F.Mask" "F.Paste")
			(net "USB2_0_DN")
		)
		(pad "2" smd rect
			(at 0.40005 0 270)
			(size 0.4572 0.508)
			(layers "F.Cu" "F.Mask" "F.Paste")
			(net "USB2_HOST_PCH_0_DN")
		)
	)
	(footprint ""
		(layer "F.Cu")
		(at 80.67675 -342.917018)
		(property "Reference" "PU24_P1_7"
			(at -11.33475 4.14274 0)
			(unlocked yes)
			(layer "F.SilkS")
			(effects
				(font
					(size 0.7874 0.5842)
					(thickness 0.1524)
				)
				(justify left)
			)
		)
		(property "Value" ""
			(at 0 0 0)
			(layer "F.Fab")
			(effects
				(font
					(size 1.27 1.27)
				)
			)
		)
		(duplicate_pad_numbers_are_jumpers no)
		(fp_line
			(start -2.500122 -2.999994)
			(end -2.24409 -2.999994)
			(stroke
				(width 0.1524)
				(type default)
			)
			(layer "F.SilkS")
		)
		(fp_line
			(start -2.500122 -2.529078)
			(end -2.500122 -2.999994)
			(stroke
				(width 0.1524)
				(type default)
			)
			(layer "F.SilkS")
		)
		(fp_line
			(start -2.500122 0.6604)
			(end -2.500122 0.229108)
			(stroke
				(width 0.1524)
				(type default)
			)
			(layer "F.SilkS")
		)
		(fp_line
			(start -2.500122 2.999994)
			(end -2.500122 2.339594)
			(stroke
				(width 0.1524)
				(type default)
			)
			(layer "F.SilkS")
		)
		(fp_line
			(start -2.2987 2.999994)
			(end -2.500122 2.999994)
			(stroke
				(width 0.1524)
				(type default)
			)
			(layer "F.SilkS")
		)
		(fp_line
			(start 2.31394 -2.999994)
			(end 2.500122 -2.999994)
			(stroke
				(width 0.1524)
				(type default)
			)
			(layer "F.SilkS")
		)
		(fp_line
			(start 2.500122 -2.999994)
			(end 2.500122 -2.44348)
			(stroke
				(width 0.1524)
				(type default)
			)
			(layer "F.SilkS")
		)
		(fp_line
			(start 2.500122 2.339594)
			(end 2.500122 2.999994)
			(stroke
				(width 0.1524)
				(type default)
			)
			(layer "F.SilkS")
		)
		(fp_line
			(start 2.500122 2.999994)
			(end 2.2987 2.999994)
			(stroke
				(width 0.1524)
				(type default)
			)
			(layer "F.SilkS")
		)
		(fp_poly
			(pts
				(xy -3.36423 -3.401822) (xy -2.648712 -2.831592) (xy -2.622296 -3.736594)
			)
			(stroke
				(width 0)
				(type default)
			)
			(fill yes)
			(layer "F.SilkS")
		)
		(fp_line
			(start -2.500122 -2.999994)
			(end 2.500122 -2.999994)
			(stroke
				(width 0.1)
				(type default)
			)
			(layer "F.Fab")
		)
		(fp_line
			(start -2.500122 2.999994)
			(end -2.500122 -2.999994)
			(stroke
				(width 0.1)
				(type default)
			)
			(layer "F.Fab")
		)
		(fp_line
			(start 2.500122 -2.999994)
			(end 2.500122 2.999994)
			(stroke
				(width 0.1)
				(type default)
			)
			(layer "F.Fab")
		)
		(fp_line
			(start 2.500122 2.999994)
			(end -2.500122 2.999994)
			(stroke
				(width 0.1)
				(type default)
			)
			(layer "F.Fab")
		)
		(fp_poly
			(pts
				(xy -4.218432 -2.783078) (xy -4.218432 -1.767078) (xy -3.202432 -2.275078)
			)
			(stroke
				(width 0)
				(type default)
			)
			(fill yes)
			(layer "F.Fab")
		)
		(pad "1" smd rect
			(at -2.400046 -2.275078 90)
			(size 0.2286 0.6096)
			(layers "F.Cu" "F.Mask" "F.Paste")
			(net "PVCCIN_CPU1_VOS7")
		)
		(pad "2" smd rect
			(at -2.400046 -1.82499 90)
			(size 0.2286 0.6096)
			(layers "F.Cu" "F.Mask" "F.Paste")
			(net "GND")
		)
		(pad "3" smd rect
			(at -2.400046 -1.374902 90)
			(size 0.2286 0.6096)
			(layers "F.Cu" "F.Mask" "F.Paste")
			(net "PVCCIN_CPU1_VDD7")
		)
		(pad "4" smd rect
			(at -2.400046 -0.925068 90)
			(size 0.2286 0.6096)
			(layers "F.Cu" "F.Mask" "F.Paste")
			(net "PVCCIN_CPU1_PVCC")
		)
		(pad "5" smd rect
			(at -2.400046 -0.47498 90)
			(size 0.2286 0.6096)
			(layers "F.Cu" "F.Mask" "F.Paste")
			(net "GND")
		)
		(pad "6" smd rect
			(at -2.400046 -0.024892 90)
			(size 0.2286 0.6096)
			(layers "F.Cu" "F.Mask" "F.Paste")
			(net "Net_8538")
		)
		(pad "7_9-20_24" smd circle
			(at 0 1.150112 90)
			(size 0 0)
			(layers "F.Cu" "F.Mask" "F.Paste")
			(net "GND")
		)
		(pad "10_19" smd rect
			(at 0 2.899918 90)
			(size 0.6096 4.318)
			(layers "F.Cu" "F.Mask" "F.Paste")
			(net "SW_PVCCIN_CPU1_SW7")
		)
		(pad "25_29" smd rect
			(at 1.549908 -1.279906 270)
			(size 2.0574 2.3114)
			(layers "F.Cu" "F.Mask" "F.Paste")
			(net "SW_P12V_PVCCIN_CPU1_FLT")
		)
		(pad "30" smd rect
			(at 2.05994 -2.899918)
			(size 0.2286 0.6096)
			(layers "F.Cu" "F.Mask" "F.Paste")
			(net "SW_P12V_PVCCIN_CPU1_FLT")
		)
		(pad "31" smd rect
			(at 1.610106 -2.899918)
			(size 0.2286 0.6096)
			(layers "F.Cu" "F.Mask" "F.Paste")
			(net "Net_8539")
		)
		(pad "32" smd rect
			(at 1.160018 -2.899918)
			(size 0.2286 0.6096)
			(layers "F.Cu" "F.Mask" "F.Paste")
			(net "SW_PVCCIN_CPU1_BOOTR7")
		)
		(pad "33" smd rect
			(at 0.70993 -2.899918)
			(size 0.2286 0.6096)
			(layers "F.Cu" "F.Mask" "F.Paste")
			(net "SW_PVCCIN_CPU1_BOOT7")
		)
		(pad "34" smd rect
			(at 0.260096 -2.899918)
			(size 0.2286 0.6096)
			(layers "F.Cu" "F.Mask" "F.Paste")
			(net "PVCCIN_CPU1_PWM7")
		)
		(pad "35" smd rect
			(at -0.189992 -2.899918)
			(size 0.2286 0.6096)
			(layers "F.Cu" "F.Mask" "F.Paste")
			(net "PVCCIN_CPU1_VDD7")
		)
		(pad "36" smd rect
			(at -0.64008 -2.899918)
			(size 0.2286 0.6096)
			(layers "F.Cu" "F.Mask" "F.Paste")
			(net "PVCCIN_CPU1_ATSEN")
		)
		(pad "37" smd rect
			(at -1.089914 -2.899918)
			(size 0.2286 0.6096)
			(layers "F.Cu" "F.Mask" "F.Paste")
			(net "PVCCIN_CPU1_LSET7")
		)
		(pad "38" smd rect
			(at -1.540002 -2.899918)
			(size 0.2286 0.6096)
			(layers "F.Cu" "F.Mask" "F.Paste")
			(net "PVCCIN_CPU1_IMON7")
		)
		(pad "39" smd rect
			(at -1.99009 -2.899918)
			(size 0.2286 0.6096)
			(layers "F.Cu" "F.Mask" "F.Paste")
			(net "PVCCIN_CPU1_VREF")
		)
		(pad "40" smd rect
			(at -0.87503 -1.27508)
			(size 1.7526 1.9558)
			(layers "F.Cu" "F.Mask" "F.Paste")
			(net "GND")
		)
		(pad "41" smd rect
			(at -1.525016 0.249936 270)
			(size 0.3048 0.4572)
			(layers "F.Cu" "F.Mask" "F.Paste")
			(net "Net_8537")
		)
		(zone
			(layer "F.Cu")
			(hatch none 0.5)
			(connect_pads
				(clearance 0)
			)
			(min_thickness 0.25)
			(keepout
				(tracks not_allowed)
				(vias allowed)
				(pads allowed)
				(copperpour not_allowed)
				(footprints allowed)
			)
			(placement
				(enabled no)
				(sheetname "")
			)
			(fill
				(thermal_gap 0.5)
				(thermal_bridge_width 0.5)
				(island_removal_mode 0)
			)
			(polygon
				(pts
					(xy 78.176628 -339.917024) (xy 78.176628 -340.666324) (xy 83.176872 -340.666324) (xy 83.176872 -339.917024)
					(xy 82.9691 -339.917024) (xy 82.9691 -340.23427) (xy 82.88655 -340.31682) (xy 82.88655 -340.3727)
					(xy 78.46695 -340.3727) (xy 78.46695 -340.24316) (xy 78.41488 -340.19109) (xy 78.41488 -339.917024)
				)
			)
		)
	)
	(footprint ""
		(layer "F.Cu")
		(at 226.733608 -406.855422)
		(property "Reference" "PR3993"
			(at 0 0 0)
			(layer "F.SilkS")
			(hide yes)
			(effects
				(font
					(size 1.27 1.27)
				)
			)
		)
		(property "Value" ""
			(at 0 0 0)
			(layer "F.Fab")
			(effects
				(font
					(size 1.27 1.27)
				)
			)
		)
		(duplicate_pad_numbers_are_jumpers no)
		(fp_line
			(start -0.7874 -0.4064)
			(end 0.7874 -0.4064)
			(stroke
				(width 0.1524)
				(type default)
			)
			(layer "F.SilkS")
		)
		(fp_line
			(start -0.7874 0.4064)
			(end -0.7874 -0.4064)
			(stroke
				(width 0.1524)
				(type default)
			)
			(layer "F.SilkS")
		)
		(fp_line
			(start 0.7874 -0.4064)
			(end 0.7874 0.4064)
			(stroke
				(width 0.1524)
				(type default)
			)
			(layer "F.SilkS")
		)
		(fp_line
			(start 0.7874 0.4064)
			(end -0.7874 0.4064)
			(stroke
				(width 0.1524)
				(type default)
			)
			(layer "F.SilkS")
		)
		(fp_line
			(start -0.67945 -0.305054)
			(end -0.12065 -0.305054)
			(stroke
				(width 0.1)
				(type default)
			)
			(layer "F.Fab")
		)
		(fp_line
			(start -0.67945 0.3048)
			(end -0.67945 -0.305054)
			(stroke
				(width 0.1)
				(type default)
			)
			(layer "F.Fab")
		)
		(fp_line
			(start -0.12065 -0.305054)
			(end -0.12065 -0.2794)
			(stroke
				(width 0.1)
				(type default)
			)
			(layer "F.Fab")
		)
		(fp_line
			(start -0.12065 -0.2794)
			(end 0.12065 -0.2794)
			(stroke
				(width 0.1)
				(type default)
			)
			(layer "F.Fab")
		)
		(fp_line
			(start -0.12065 0.2794)
			(end -0.12065 0.3048)
			(stroke
				(width 0.1)
				(type default)
			)
			(layer "F.Fab")
		)
		(fp_line
			(start -0.12065 0.3048)
			(end -0.67945 0.3048)
			(stroke
				(width 0.1)
				(type default)
			)
			(layer "F.Fab")
		)
		(fp_line
			(start 0.120396 0.2794)
			(end -0.12065 0.2794)
			(stroke
				(width 0.1)
				(type default)
			)
			(layer "F.Fab")
		)
		(fp_line
			(start 0.120396 0.3048)
			(end 0.120396 0.2794)
			(stroke
				(width 0.1)
				(type default)
			)
			(layer "F.Fab")
		)
		(fp_line
			(start 0.12065 -0.3048)
			(end 0.67945 -0.3048)
			(stroke
				(width 0.1)
				(type default)
			)
			(layer "F.Fab")
		)
		(fp_line
			(start 0.12065 -0.2794)
			(end 0.12065 -0.3048)
			(stroke
				(width 0.1)
				(type default)
			)
			(layer "F.Fab")
		)
		(fp_line
			(start 0.67945 -0.3048)
			(end 0.67945 0.3048)
			(stroke
				(width 0.1)
				(type default)
			)
			(layer "F.Fab")
		)
		(fp_line
			(start 0.67945 0.3048)
			(end 0.120396 0.3048)
			(stroke
				(width 0.1)
				(type default)
			)
			(layer "F.Fab")
		)
		(pad "1" smd circle
			(at -0.40005 0)
			(size 0 0)
			(layers "F.Cu" "F.Mask" "F.Paste")
			(net "HSC_FLT_TYPE_3")
		)
		(pad "2" smd circle
			(at 0.40005 0)
			(size 0 0)
			(layers "F.Cu" "F.Mask" "F.Paste")
			(net "HSC_FLT_TYPE")
		)
	)
	(footprint ""
		(layer "F.Cu")
		(at 104.22001 -353.14255)
		(property "Reference" "PR317"
			(at 0 0 0)
			(layer "F.SilkS")
			(hide yes)
			(effects
				(font
					(size 1.27 1.27)
				)
			)
		)
		(property "Value" ""
			(at 0 0 0)
			(layer "F.Fab")
			(effects
				(font
					(size 1.27 1.27)
				)
			)
		)
		(duplicate_pad_numbers_are_jumpers no)
		(fp_line
			(start -0.7874 -0.4064)
			(end 0.7874 -0.4064)
			(stroke
				(width 0.1524)
				(type default)
			)
			(layer "F.SilkS")
		)
		(fp_line
			(start -0.7874 0.4064)
			(end -0.7874 -0.4064)
			(stroke
				(width 0.1524)
				(type default)
			)
			(layer "F.SilkS")
		)
		(fp_line
			(start 0.7874 -0.4064)
			(end 0.7874 0.4064)
			(stroke
				(width 0.1524)
				(type default)
			)
			(layer "F.SilkS")
		)
		(fp_line
			(start 0.7874 0.4064)
			(end -0.7874 0.4064)
			(stroke
				(width 0.1524)
				(type default)
			)
			(layer "F.SilkS")
		)
		(fp_line
			(start -0.67945 -0.305054)
			(end -0.12065 -0.305054)
			(stroke
				(width 0.1)
				(type default)
			)
			(layer "F.Fab")
		)
		(fp_line
			(start -0.67945 0.3048)
			(end -0.67945 -0.305054)
			(stroke
				(width 0.1)
				(type default)
			)
			(layer "F.Fab")
		)
		(fp_line
			(start -0.12065 -0.305054)
			(end -0.12065 -0.2794)
			(stroke
				(width 0.1)
				(type default)
			)
			(layer "F.Fab")
		)
		(fp_line
			(start -0.12065 -0.2794)
			(end 0.12065 -0.2794)
			(stroke
				(width 0.1)
				(type default)
			)
			(layer "F.Fab")
		)
		(fp_line
			(start -0.12065 0.2794)
			(end -0.12065 0.3048)
			(stroke
				(width 0.1)
				(type default)
			)
			(layer "F.Fab")
		)
		(fp_line
			(start -0.12065 0.3048)
			(end -0.67945 0.3048)
			(stroke
				(width 0.1)
				(type default)
			)
			(layer "F.Fab")
		)
		(fp_line
			(start 0.120396 0.2794)
			(end -0.12065 0.2794)
			(stroke
				(width 0.1)
				(type default)
			)
			(layer "F.Fab")
		)
		(fp_line
			(start 0.120396 0.3048)
			(end 0.120396 0.2794)
			(stroke
				(width 0.1)
				(type default)
			)
			(layer "F.Fab")
		)
		(fp_line
			(start 0.12065 -0.3048)
			(end 0.67945 -0.3048)
			(stroke
				(width 0.1)
				(type default)
			)
			(layer "F.Fab")
		)
		(fp_line
			(start 0.12065 -0.2794)
			(end 0.12065 -0.3048)
			(stroke
				(width 0.1)
				(type default)
			)
			(layer "F.Fab")
		)
		(fp_line
			(start 0.67945 -0.3048)
			(end 0.67945 0.3048)
			(stroke
				(width 0.1)
				(type default)
			)
			(layer "F.Fab")
		)
		(fp_line
			(start 0.67945 0.3048)
			(end 0.120396 0.3048)
			(stroke
				(width 0.1)
				(type default)
			)
			(layer "F.Fab")
		)
		(pad "1" smd circle
			(at -0.40005 0)
			(size 0 0)
			(layers "F.Cu" "F.Mask" "F.Paste")
			(net "SH_PVCCIN_CPU1")
		)
		(pad "2" smd circle
			(at 0.40005 0)
			(size 0 0)
			(layers "F.Cu" "F.Mask" "F.Paste")
			(net "SH_PVCCIN_CPU1_R")
		)
	)
	(footprint ""
		(layer "F.Cu")
		(at 424.204892 -380.329948 180)
		(property "Reference" "C1772"
			(at 0 0 180)
			(layer "F.SilkS")
			(hide yes)
			(effects
				(font
					(size 1.27 1.27)
				)
			)
		)
		(property "Value" ""
			(at 0 0 180)
			(layer "F.Fab")
			(effects
				(font
					(size 1.27 1.27)
				)
			)
		)
		(duplicate_pad_numbers_are_jumpers no)
		(fp_line
			(start 0.7874 0.4064)
			(end -0.7874 0.4064)
			(stroke
				(width 0.1524)
				(type default)
			)
			(layer "F.SilkS")
		)
		(fp_line
			(start 0.7874 -0.4064)
			(end 0.7874 0.4064)
			(stroke
				(width 0.1524)
				(type default)
			)
			(layer "F.SilkS")
		)
		(fp_line
			(start -0.7874 0.4064)
			(end -0.7874 -0.4064)
			(stroke
				(width 0.1524)
				(type default)
			)
			(layer "F.SilkS")
		)
		(fp_line
			(start -0.7874 -0.4064)
			(end 0.7874 -0.4064)
			(stroke
				(width 0.1524)
				(type default)
			)
			(layer "F.SilkS")
		)
		(fp_line
			(start 0.67945 0.3048)
			(end 0.120396 0.3048)
			(stroke
				(width 0.1)
				(type default)
			)
			(layer "F.Fab")
		)
		(fp_line
			(start 0.67945 -0.3048)
			(end 0.67945 0.3048)
			(stroke
				(width 0.1)
				(type default)
			)
			(layer "F.Fab")
		)
		(fp_line
			(start 0.12065 -0.2794)
			(end 0.12065 -0.3048)
			(stroke
				(width 0.1)
				(type default)
			)
			(layer "F.Fab")
		)
		(fp_line
			(start 0.12065 -0.3048)
			(end 0.67945 -0.3048)
			(stroke
				(width 0.1)
				(type default)
			)
			(layer "F.Fab")
		)
		(fp_line
			(start 0.120396 0.3048)
			(end 0.120396 0.2794)
			(stroke
				(width 0.1)
				(type default)
			)
			(layer "F.Fab")
		)
		(fp_line
			(start 0.120396 0.2794)
			(end -0.12065 0.2794)
			(stroke
				(width 0.1)
				(type default)
			)
			(layer "F.Fab")
		)
		(fp_line
			(start -0.12065 0.3048)
			(end -0.67945 0.3048)
			(stroke
				(width 0.1)
				(type default)
			)
			(layer "F.Fab")
		)
		(fp_line
			(start -0.12065 0.2794)
			(end -0.12065 0.3048)
			(stroke
				(width 0.1)
				(type default)
			)
			(layer "F.Fab")
		)
		(fp_line
			(start -0.12065 -0.2794)
			(end 0.12065 -0.2794)
			(stroke
				(width 0.1)
				(type default)
			)
			(layer "F.Fab")
		)
		(fp_line
			(start -0.12065 -0.305054)
			(end -0.12065 -0.2794)
			(stroke
				(width 0.1)
				(type default)
			)
			(layer "F.Fab")
		)
		(fp_line
			(start -0.67945 0.3048)
			(end -0.67945 -0.305054)
			(stroke
				(width 0.1)
				(type default)
			)
			(layer "F.Fab")
		)
		(fp_line
			(start -0.67945 -0.305054)
			(end -0.12065 -0.305054)
			(stroke
				(width 0.1)
				(type default)
			)
			(layer "F.Fab")
		)
		(pad "1" smd circle
			(at -0.40005 0 180)
			(size 0 0)
			(layers "F.Cu" "F.Mask" "F.Paste")
			(net "RST_BMC_FROM_SWB_ISO_N")
		)
		(pad "2" smd circle
			(at 0.40005 0 180)
			(size 0 0)
			(layers "F.Cu" "F.Mask" "F.Paste")
			(net "GND")
		)
	)
	(footprint ""
		(layer "F.Cu")
		(at 115.060222 -19.30019)
		(property "Reference" "C2274"
			(at 0 0 0)
			(layer "F.SilkS")
			(hide yes)
			(effects
				(font
					(size 1.27 1.27)
				)
			)
		)
		(property "Value" ""
			(at 0 0 0)
			(layer "F.Fab")
			(effects
				(font
					(size 1.27 1.27)
				)
			)
		)
		(duplicate_pad_numbers_are_jumpers no)
		(fp_line
			(start -0.7874 -0.4064)
			(end 0.7874 -0.4064)
			(stroke
				(width 0.1524)
				(type default)
			)
			(layer "F.SilkS")
		)
		(fp_line
			(start -0.7874 0.4064)
			(end -0.7874 -0.4064)
			(stroke
				(width 0.1524)
				(type default)
			)
			(layer "F.SilkS")
		)
		(fp_line
			(start 0.7874 -0.4064)
			(end 0.7874 0.4064)
			(stroke
				(width 0.1524)
				(type default)
			)
			(layer "F.SilkS")
		)
		(fp_line
			(start 0.7874 0.4064)
			(end -0.7874 0.4064)
			(stroke
				(width 0.1524)
				(type default)
			)
			(layer "F.SilkS")
		)
		(fp_line
			(start -0.67945 -0.305054)
			(end -0.12065 -0.305054)
			(stroke
				(width 0.1)
				(type default)
			)
			(layer "F.Fab")
		)
		(fp_line
			(start -0.67945 0.3048)
			(end -0.67945 -0.305054)
			(stroke
				(width 0.1)
				(type default)
			)
			(layer "F.Fab")
		)
		(fp_line
			(start -0.12065 -0.305054)
			(end -0.12065 -0.2794)
			(stroke
				(width 0.1)
				(type default)
			)
			(layer "F.Fab")
		)
		(fp_line
			(start -0.12065 -0.2794)
			(end 0.12065 -0.2794)
			(stroke
				(width 0.1)
				(type default)
			)
			(layer "F.Fab")
		)
		(fp_line
			(start -0.12065 0.2794)
			(end -0.12065 0.3048)
			(stroke
				(width 0.1)
				(type default)
			)
			(layer "F.Fab")
		)
		(fp_line
			(start -0.12065 0.3048)
			(end -0.67945 0.3048)
			(stroke
				(width 0.1)
				(type default)
			)
			(layer "F.Fab")
		)
		(fp_line
			(start 0.120396 0.2794)
			(end -0.12065 0.2794)
			(stroke
				(width 0.1)
				(type default)
			)
			(layer "F.Fab")
		)
		(fp_line
			(start 0.120396 0.3048)
			(end 0.120396 0.2794)
			(stroke
				(width 0.1)
				(type default)
			)
			(layer "F.Fab")
		)
		(fp_line
			(start 0.12065 -0.3048)
			(end 0.67945 -0.3048)
			(stroke
				(width 0.1)
				(type default)
			)
			(layer "F.Fab")
		)
		(fp_line
			(start 0.12065 -0.2794)
			(end 0.12065 -0.3048)
			(stroke
				(width 0.1)
				(type default)
			)
			(layer "F.Fab")
		)
		(fp_line
			(start 0.67945 -0.3048)
			(end 0.67945 0.3048)
			(stroke
				(width 0.1)
				(type default)
			)
			(layer "F.Fab")
		)
		(fp_line
			(start 0.67945 0.3048)
			(end 0.120396 0.3048)
			(stroke
				(width 0.1)
				(type default)
			)
			(layer "F.Fab")
		)
		(pad "1" smd circle
			(at -0.40005 0)
			(size 0 0)
			(layers "F.Cu" "F.Mask" "F.Paste")
			(net "P3V3_AUX")
		)
		(pad "2" smd circle
			(at 0.40005 0)
			(size 0 0)
			(layers "F.Cu" "F.Mask" "F.Paste")
			(net "GND")
		)
	)
	(footprint ""
		(layer "F.Cu")
		(at 113.494312 -131.440682 180)
		(property "Reference" "R2968"
			(at 0 0 180)
			(layer "F.SilkS")
			(hide yes)
			(effects
				(font
					(size 1.27 1.27)
				)
			)
		)
		(property "Value" ""
			(at 0 0 180)
			(layer "F.Fab")
			(effects
				(font
					(size 1.27 1.27)
				)
			)
		)
		(duplicate_pad_numbers_are_jumpers no)
		(fp_line
			(start 0.7874 0.4064)
			(end -0.7874 0.4064)
			(stroke
				(width 0.1524)
				(type default)
			)
			(layer "F.SilkS")
		)
		(fp_line
			(start 0.7874 -0.4064)
			(end 0.7874 0.4064)
			(stroke
				(width 0.1524)
				(type default)
			)
			(layer "F.SilkS")
		)
		(fp_line
			(start -0.7874 0.4064)
			(end -0.7874 -0.4064)
			(stroke
				(width 0.1524)
				(type default)
			)
			(layer "F.SilkS")
		)
		(fp_line
			(start -0.7874 -0.4064)
			(end 0.7874 -0.4064)
			(stroke
				(width 0.1524)
				(type default)
			)
			(layer "F.SilkS")
		)
		(fp_line
			(start 0.67945 0.3048)
			(end 0.120396 0.3048)
			(stroke
				(width 0.1)
				(type default)
			)
			(layer "F.Fab")
		)
		(fp_line
			(start 0.67945 -0.3048)
			(end 0.67945 0.3048)
			(stroke
				(width 0.1)
				(type default)
			)
			(layer "F.Fab")
		)
		(fp_line
			(start 0.12065 -0.2794)
			(end 0.12065 -0.3048)
			(stroke
				(width 0.1)
				(type default)
			)
			(layer "F.Fab")
		)
		(fp_line
			(start 0.12065 -0.3048)
			(end 0.67945 -0.3048)
			(stroke
				(width 0.1)
				(type default)
			)
			(layer "F.Fab")
		)
		(fp_line
			(start 0.120396 0.3048)
			(end 0.120396 0.2794)
			(stroke
				(width 0.1)
				(type default)
			)
			(layer "F.Fab")
		)
		(fp_line
			(start 0.120396 0.2794)
			(end -0.12065 0.2794)
			(stroke
				(width 0.1)
				(type default)
			)
			(layer "F.Fab")
		)
		(fp_line
			(start -0.12065 0.3048)
			(end -0.67945 0.3048)
			(stroke
				(width 0.1)
				(type default)
			)
			(layer "F.Fab")
		)
		(fp_line
			(start -0.12065 0.2794)
			(end -0.12065 0.3048)
			(stroke
				(width 0.1)
				(type default)
			)
			(layer "F.Fab")
		)
		(fp_line
			(start -0.12065 -0.2794)
			(end 0.12065 -0.2794)
			(stroke
				(width 0.1)
				(type default)
			)
			(layer "F.Fab")
		)
		(fp_line
			(start -0.12065 -0.305054)
			(end -0.12065 -0.2794)
			(stroke
				(width 0.1)
				(type default)
			)
			(layer "F.Fab")
		)
		(fp_line
			(start -0.67945 0.3048)
			(end -0.67945 -0.305054)
			(stroke
				(width 0.1)
				(type default)
			)
			(layer "F.Fab")
		)
		(fp_line
			(start -0.67945 -0.305054)
			(end -0.12065 -0.305054)
			(stroke
				(width 0.1)
				(type default)
			)
			(layer "F.Fab")
		)
		(pad "1" smd circle
			(at -0.40005 0 180)
			(size 0 0)
			(layers "F.Cu" "F.Mask" "F.Paste")
			(net "SMB_PCIE0_3V3AUX_SDA_R3")
		)
		(pad "2" smd circle
			(at 0.40005 0 180)
			(size 0 0)
			(layers "F.Cu" "F.Mask" "F.Paste")
			(net "SMB_SENSOR_M2_P0_3V3AUX_SDA")
		)
	)
	(footprint ""
		(layer "F.Cu")
		(at 300.754034 -15.572994)
		(property "Reference" "R4197"
			(at 0 0 0)
			(layer "F.SilkS")
			(hide yes)
			(effects
				(font
					(size 1.27 1.27)
				)
			)
		)
		(property "Value" ""
			(at 0 0 0)
			(layer "F.Fab")
			(effects
				(font
					(size 1.27 1.27)
				)
			)
		)
		(duplicate_pad_numbers_are_jumpers no)
		(fp_line
			(start -0.7874 -0.4064)
			(end 0.7874 -0.4064)
			(stroke
				(width 0.1524)
				(type default)
			)
			(layer "F.SilkS")
		)
		(fp_line
			(start -0.7874 0.4064)
			(end -0.7874 -0.4064)
			(stroke
				(width 0.1524)
				(type default)
			)
			(layer "F.SilkS")
		)
		(fp_line
			(start 0.7874 -0.4064)
			(end 0.7874 0.4064)
			(stroke
				(width 0.1524)
				(type default)
			)
			(layer "F.SilkS")
		)
		(fp_line
			(start 0.7874 0.4064)
			(end -0.7874 0.4064)
			(stroke
				(width 0.1524)
				(type default)
			)
			(layer "F.SilkS")
		)
		(fp_line
			(start -0.67945 -0.305054)
			(end -0.12065 -0.305054)
			(stroke
				(width 0.1)
				(type default)
			)
			(layer "F.Fab")
		)
		(fp_line
			(start -0.67945 0.3048)
			(end -0.67945 -0.305054)
			(stroke
				(width 0.1)
				(type default)
			)
			(layer "F.Fab")
		)
		(fp_line
			(start -0.12065 -0.305054)
			(end -0.12065 -0.2794)
			(stroke
				(width 0.1)
				(type default)
			)
			(layer "F.Fab")
		)
		(fp_line
			(start -0.12065 -0.2794)
			(end 0.12065 -0.2794)
			(stroke
				(width 0.1)
				(type default)
			)
			(layer "F.Fab")
		)
		(fp_line
			(start -0.12065 0.2794)
			(end -0.12065 0.3048)
			(stroke
				(width 0.1)
				(type default)
			)
			(layer "F.Fab")
		)
		(fp_line
			(start -0.12065 0.3048)
			(end -0.67945 0.3048)
			(stroke
				(width 0.1)
				(type default)
			)
			(layer "F.Fab")
		)
		(fp_line
			(start 0.120396 0.2794)
			(end -0.12065 0.2794)
			(stroke
				(width 0.1)
				(type default)
			)
			(layer "F.Fab")
		)
		(fp_line
			(start 0.120396 0.3048)
			(end 0.120396 0.2794)
			(stroke
				(width 0.1)
				(type default)
			)
			(layer "F.Fab")
		)
		(fp_line
			(start 0.12065 -0.3048)
			(end 0.67945 -0.3048)
			(stroke
				(width 0.1)
				(type default)
			)
			(layer "F.Fab")
		)
		(fp_line
			(start 0.12065 -0.2794)
			(end 0.12065 -0.3048)
			(stroke
				(width 0.1)
				(type default)
			)
			(layer "F.Fab")
		)
		(fp_line
			(start 0.67945 -0.3048)
			(end 0.67945 0.3048)
			(stroke
				(width 0.1)
				(type default)
			)
			(layer "F.Fab")
		)
		(fp_line
			(start 0.67945 0.3048)
			(end 0.120396 0.3048)
			(stroke
				(width 0.1)
				(type default)
			)
			(layer "F.Fab")
		)
		(pad "1" smd circle
			(at -0.40005 0)
			(size 0 0)
			(layers "F.Cu" "F.Mask" "F.Paste")
			(net "U271_1_ADD1")
		)
		(pad "2" smd circle
			(at 0.40005 0)
			(size 0 0)
			(layers "F.Cu" "F.Mask" "F.Paste")
			(net "GND")
		)
	)
	(footprint ""
		(layer "F.Cu")
		(at 366.48263 -252.956314 -90)
		(property "Reference" "C1024"
			(at 0 0 270)
			(layer "F.SilkS")
			(hide yes)
			(effects
				(font
					(size 1.27 1.27)
				)
			)
		)
		(property "Value" ""
			(at 0 0 270)
			(layer "F.Fab")
			(effects
				(font
					(size 1.27 1.27)
				)
			)
		)
		(duplicate_pad_numbers_are_jumpers no)
		(fp_line
			(start -0.7874 0.4064)
			(end -0.7874 -0.4064)
			(stroke
				(width 0.1524)
				(type default)
			)
			(layer "F.SilkS")
		)
		(fp_line
			(start 0.7874 0.4064)
			(end -0.7874 0.4064)
			(stroke
				(width 0.1524)
				(type default)
			)
			(layer "F.SilkS")
		)
		(fp_line
			(start -0.7874 -0.4064)
			(end 0.7874 -0.4064)
			(stroke
				(width 0.1524)
				(type default)
			)
			(layer "F.SilkS")
		)
		(fp_line
			(start 0.7874 -0.4064)
			(end 0.7874 0.4064)
			(stroke
				(width 0.1524)
				(type default)
			)
			(layer "F.SilkS")
		)
		(fp_line
			(start -0.67945 0.3048)
			(end -0.67945 -0.305054)
			(stroke
				(width 0.1)
				(type default)
			)
			(layer "F.Fab")
		)
		(fp_line
			(start -0.12065 0.3048)
			(end -0.67945 0.3048)
			(stroke
				(width 0.1)
				(type default)
			)
			(layer "F.Fab")
		)
		(fp_line
			(start 0.120396 0.3048)
			(end 0.120396 0.2794)
			(stroke
				(width 0.1)
				(type default)
			)
			(layer "F.Fab")
		)
		(fp_line
			(start 0.67945 0.3048)
			(end 0.120396 0.3048)
			(stroke
				(width 0.1)
				(type default)
			)
			(layer "F.Fab")
		)
		(fp_line
			(start -0.12065 0.2794)
			(end -0.12065 0.3048)
			(stroke
				(width 0.1)
				(type default)
			)
			(layer "F.Fab")
		)
		(fp_line
			(start 0.120396 0.2794)
			(end -0.12065 0.2794)
			(stroke
				(width 0.1)
				(type default)
			)
			(layer "F.Fab")
		)
		(fp_line
			(start -0.12065 -0.2794)
			(end 0.12065 -0.2794)
			(stroke
				(width 0.1)
				(type default)
			)
			(layer "F.Fab")
		)
		(fp_line
			(start 0.12065 -0.2794)
			(end 0.12065 -0.3048)
			(stroke
				(width 0.1)
				(type default)
			)
			(layer "F.Fab")
		)
		(fp_line
			(start 0.12065 -0.3048)
			(end 0.67945 -0.3048)
			(stroke
				(width 0.1)
				(type default)
			)
			(layer "F.Fab")
		)
		(fp_line
			(start 0.67945 -0.3048)
			(end 0.67945 0.3048)
			(stroke
				(width 0.1)
				(type default)
			)
			(layer "F.Fab")
		)
		(fp_line
			(start -0.67945 -0.305054)
			(end -0.12065 -0.305054)
			(stroke
				(width 0.1)
				(type default)
			)
			(layer "F.Fab")
		)
		(fp_line
			(start -0.12065 -0.305054)
			(end -0.12065 -0.2794)
			(stroke
				(width 0.1)
				(type default)
			)
			(layer "F.Fab")
		)
		(pad "1" smd circle
			(at -0.40005 0 270)
			(size 0 0)
			(layers "F.Cu" "F.Mask" "F.Paste")
			(net "PVCCIN_CPU0")
		)
		(pad "2" smd circle
			(at 0.40005 0 270)
			(size 0 0)
			(layers "F.Cu" "F.Mask" "F.Paste")
			(net "GND")
		)
	)
	(footprint ""
		(layer "F.Cu")
		(at 27.628596 -390.294876)
		(property "Reference" "R3285"
			(at 0 0 0)
			(layer "F.SilkS")
			(hide yes)
			(effects
				(font
					(size 1.27 1.27)
				)
			)
		)
		(property "Value" ""
			(at 0 0 0)
			(layer "F.Fab")
			(effects
				(font
					(size 1.27 1.27)
				)
			)
		)
		(duplicate_pad_numbers_are_jumpers no)
		(fp_line
			(start -0.7874 -0.4064)
			(end 0.7874 -0.4064)
			(stroke
				(width 0.1524)
				(type default)
			)
			(layer "F.SilkS")
		)
		(fp_line
			(start -0.7874 0.4064)
			(end -0.7874 -0.4064)
			(stroke
				(width 0.1524)
				(type default)
			)
			(layer "F.SilkS")
		)
		(fp_line
			(start 0.7874 -0.4064)
			(end 0.7874 0.4064)
			(stroke
				(width 0.1524)
				(type default)
			)
			(layer "F.SilkS")
		)
		(fp_line
			(start 0.7874 0.4064)
			(end -0.7874 0.4064)
			(stroke
				(width 0.1524)
				(type default)
			)
			(layer "F.SilkS")
		)
		(fp_line
			(start -0.67945 -0.305054)
			(end -0.12065 -0.305054)
			(stroke
				(width 0.1)
				(type default)
			)
			(layer "F.Fab")
		)
		(fp_line
			(start -0.67945 0.3048)
			(end -0.67945 -0.305054)
			(stroke
				(width 0.1)
				(type default)
			)
			(layer "F.Fab")
		)
		(fp_line
			(start -0.12065 -0.305054)
			(end -0.12065 -0.2794)
			(stroke
				(width 0.1)
				(type default)
			)
			(layer "F.Fab")
		)
		(fp_line
			(start -0.12065 -0.2794)
			(end 0.12065 -0.2794)
			(stroke
				(width 0.1)
				(type default)
			)
			(layer "F.Fab")
		)
		(fp_line
			(start -0.12065 0.2794)
			(end -0.12065 0.3048)
			(stroke
				(width 0.1)
				(type default)
			)
			(layer "F.Fab")
		)
		(fp_line
			(start -0.12065 0.3048)
			(end -0.67945 0.3048)
			(stroke
				(width 0.1)
				(type default)
			)
			(layer "F.Fab")
		)
		(fp_line
			(start 0.120396 0.2794)
			(end -0.12065 0.2794)
			(stroke
				(width 0.1)
				(type default)
			)
			(layer "F.Fab")
		)
		(fp_line
			(start 0.120396 0.3048)
			(end 0.120396 0.2794)
			(stroke
				(width 0.1)
				(type default)
			)
			(layer "F.Fab")
		)
		(fp_line
			(start 0.12065 -0.3048)
			(end 0.67945 -0.3048)
			(stroke
				(width 0.1)
				(type default)
			)
			(layer "F.Fab")
		)
		(fp_line
			(start 0.12065 -0.2794)
			(end 0.12065 -0.3048)
			(stroke
				(width 0.1)
				(type default)
			)
			(layer "F.Fab")
		)
		(fp_line
			(start 0.67945 -0.3048)
			(end 0.67945 0.3048)
			(stroke
				(width 0.1)
				(type default)
			)
			(layer "F.Fab")
		)
		(fp_line
			(start 0.67945 0.3048)
			(end 0.120396 0.3048)
			(stroke
				(width 0.1)
				(type default)
			)
			(layer "F.Fab")
		)
		(pad "1" smd circle
			(at -0.40005 0)
			(size 0 0)
			(layers "F.Cu" "F.Mask" "F.Paste")
			(net "FM_P2E_SWB")
		)
		(pad "2" smd circle
			(at 0.40005 0)
			(size 0 0)
			(layers "F.Cu" "F.Mask" "F.Paste")
			(net "GND")
		)
	)
	(footprint ""
		(layer "F.Cu")
		(at 302.566324 -34.937446 90)
		(property "Reference" "R1340"
			(at 0 0 90)
			(layer "F.SilkS")
			(hide yes)
			(effects
				(font
					(size 1.27 1.27)
				)
			)
		)
		(property "Value" ""
			(at 0 0 90)
			(layer "F.Fab")
			(effects
				(font
					(size 1.27 1.27)
				)
			)
		)
		(duplicate_pad_numbers_are_jumpers no)
		(fp_line
			(start 0.7874 -0.4064)
			(end 0.7874 0.4064)
			(stroke
				(width 0.1524)
				(type default)
			)
			(layer "F.SilkS")
		)
		(fp_line
			(start -0.7874 -0.4064)
			(end 0.7874 -0.4064)
			(stroke
				(width 0.1524)
				(type default)
			)
			(layer "F.SilkS")
		)
		(fp_line
			(start 0.7874 0.4064)
			(end -0.7874 0.4064)
			(stroke
				(width 0.1524)
				(type default)
			)
			(layer "F.SilkS")
		)
		(fp_line
			(start -0.7874 0.4064)
			(end -0.7874 -0.4064)
			(stroke
				(width 0.1524)
				(type default)
			)
			(layer "F.SilkS")
		)
		(fp_line
			(start -0.12065 -0.305054)
			(end -0.12065 -0.2794)
			(stroke
				(width 0.1)
				(type default)
			)
			(layer "F.Fab")
		)
		(fp_line
			(start -0.67945 -0.305054)
			(end -0.12065 -0.305054)
			(stroke
				(width 0.1)
				(type default)
			)
			(layer "F.Fab")
		)
		(fp_line
			(start 0.67945 -0.3048)
			(end 0.67945 0.3048)
			(stroke
				(width 0.1)
				(type default)
			)
			(layer "F.Fab")
		)
		(fp_line
			(start 0.12065 -0.3048)
			(end 0.67945 -0.3048)
			(stroke
				(width 0.1)
				(type default)
			)
			(layer "F.Fab")
		)
		(fp_line
			(start 0.12065 -0.2794)
			(end 0.12065 -0.3048)
			(stroke
				(width 0.1)
				(type default)
			)
			(layer "F.Fab")
		)
		(fp_line
			(start -0.12065 -0.2794)
			(end 0.12065 -0.2794)
			(stroke
				(width 0.1)
				(type default)
			)
			(layer "F.Fab")
		)
		(fp_line
			(start 0.120396 0.2794)
			(end -0.12065 0.2794)
			(stroke
				(width 0.1)
				(type default)
			)
			(layer "F.Fab")
		)
		(fp_line
			(start -0.12065 0.2794)
			(end -0.12065 0.3048)
			(stroke
				(width 0.1)
				(type default)
			)
			(layer "F.Fab")
		)
		(fp_line
			(start 0.67945 0.3048)
			(end 0.120396 0.3048)
			(stroke
				(width 0.1)
				(type default)
			)
			(layer "F.Fab")
		)
		(fp_line
			(start 0.120396 0.3048)
			(end 0.120396 0.2794)
			(stroke
				(width 0.1)
				(type default)
			)
			(layer "F.Fab")
		)
		(fp_line
			(start -0.12065 0.3048)
			(end -0.67945 0.3048)
			(stroke
				(width 0.1)
				(type default)
			)
			(layer "F.Fab")
		)
		(fp_line
			(start -0.67945 0.3048)
			(end -0.67945 -0.305054)
			(stroke
				(width 0.1)
				(type default)
			)
			(layer "F.Fab")
		)
		(pad "1" smd circle
			(at -0.40005 0 90)
			(size 0 0)
			(layers "F.Cu" "F.Mask" "F.Paste")
			(net "P3V3_RTC_AUX")
		)
		(pad "2" smd circle
			(at 0.40005 0 90)
			(size 0 0)
			(layers "F.Cu" "F.Mask" "F.Paste")
			(net "RST_RTCRST_N")
		)
	)
	(footprint ""
		(layer "F.Cu")
		(at 100.183696 -70.78599)
		(property "Reference" "D79"
			(at -50.276506 50.178462 90)
			(unlocked yes)
			(layer "F.SilkS")
			(effects
				(font
					(size 0.635 0.4064)
					(thickness 0.1524)
				)
				(justify left)
			)
		)
		(property "Value" ""
			(at 0 0 0)
			(layer "F.Fab")
			(effects
				(font
					(size 1.27 1.27)
				)
			)
		)
		(duplicate_pad_numbers_are_jumpers no)
		(fp_line
			(start -0.90678 0.4826)
			(end -0.90678 -0.4699)
			(stroke
				(width 0.1524)
				(type default)
			)
			(layer "F.SilkS")
		)
		(fp_line
			(start -0.89408 -0.4826)
			(end 0.90678 -0.4826)
			(stroke
				(width 0.1524)
				(type default)
			)
			(layer "F.SilkS")
		)
		(fp_line
			(start -0.79248 -0.4826)
			(end 1.03378 -0.4826)
			(stroke
				(width 0.1524)
				(type default)
			)
			(layer "F.SilkS")
		)
		(fp_line
			(start -0.64008 -0.4826)
			(end 1.16078 -0.4826)
			(stroke
				(width 0.1524)
				(type default)
			)
			(layer "F.SilkS")
		)
		(fp_line
			(start 0.90678 -0.4826)
			(end 0.90678 0.4826)
			(stroke
				(width 0.1524)
				(type default)
			)
			(layer "F.SilkS")
		)
		(fp_line
			(start 0.90678 0.4826)
			(end -0.90678 0.4826)
			(stroke
				(width 0.1524)
				(type default)
			)
			(layer "F.SilkS")
		)
		(fp_line
			(start 1.03378 -0.4826)
			(end 1.03378 0.4826)
			(stroke
				(width 0.1524)
				(type default)
			)
			(layer "F.SilkS")
		)
		(fp_line
			(start 1.03378 0.4826)
			(end -0.79248 0.4826)
			(stroke
				(width 0.1524)
				(type default)
			)
			(layer "F.SilkS")
		)
		(fp_line
			(start 1.16078 -0.4826)
			(end 1.16078 0.4826)
			(stroke
				(width 0.1524)
				(type default)
			)
			(layer "F.SilkS")
		)
		(fp_line
			(start 1.16078 0.4826)
			(end -0.64008 0.4826)
			(stroke
				(width 0.1524)
				(type default)
			)
			(layer "F.SilkS")
		)
		(fp_line
			(start -0.499872 -0.249936)
			(end 0.499872 -0.249936)
			(stroke
				(width 0.1)
				(type default)
			)
			(layer "F.Fab")
		)
		(fp_line
			(start -0.499872 0.249936)
			(end -0.499872 -0.249936)
			(stroke
				(width 0.1)
				(type default)
			)
			(layer "F.Fab")
		)
		(fp_line
			(start 0.499872 -0.249936)
			(end 0.499872 0.249936)
			(stroke
				(width 0.1)
				(type default)
			)
			(layer "F.Fab")
		)
		(fp_line
			(start 0.499872 0.249936)
			(end -0.499872 0.249936)
			(stroke
				(width 0.1)
				(type default)
			)
			(layer "F.Fab")
		)
		(pad "A" smd rect
			(at -0.47498 0)
			(size 0.6096 0.7112)
			(layers "F.Cu" "F.Mask" "F.Paste")
			(net "LED_PWRGD_PVCCIN_CPU0")
		)
		(pad "C" smd rect
			(at 0.47498 0)
			(size 0.6096 0.7112)
			(layers "F.Cu" "F.Mask" "F.Paste")
			(net "LED_PWRGD_PVCCIN_CPU0_D")
		)
	)
	(footprint ""
		(layer "F.Cu")
		(at 13.87348 -15.320518 90)
		(property "Reference" "R3178"
			(at 0 0 90)
			(layer "F.SilkS")
			(hide yes)
			(effects
				(font
					(size 1.27 1.27)
				)
			)
		)
		(property "Value" ""
			(at 0 0 90)
			(layer "F.Fab")
			(effects
				(font
					(size 1.27 1.27)
				)
			)
		)
		(duplicate_pad_numbers_are_jumpers no)
		(fp_line
			(start 0.7874 -0.4064)
			(end 0.7874 0.4064)
			(stroke
				(width 0.1524)
				(type default)
			)
			(layer "F.SilkS")
		)
		(fp_line
			(start -0.7874 -0.4064)
			(end 0.7874 -0.4064)
			(stroke
				(width 0.1524)
				(type default)
			)
			(layer "F.SilkS")
		)
		(fp_line
			(start 0.7874 0.4064)
			(end -0.7874 0.4064)
			(stroke
				(width 0.1524)
				(type default)
			)
			(layer "F.SilkS")
		)
		(fp_line
			(start -0.7874 0.4064)
			(end -0.7874 -0.4064)
			(stroke
				(width 0.1524)
				(type default)
			)
			(layer "F.SilkS")
		)
		(fp_line
			(start -0.12065 -0.305054)
			(end -0.12065 -0.2794)
			(stroke
				(width 0.1)
				(type default)
			)
			(layer "F.Fab")
		)
		(fp_line
			(start -0.67945 -0.305054)
			(end -0.12065 -0.305054)
			(stroke
				(width 0.1)
				(type default)
			)
			(layer "F.Fab")
		)
		(fp_line
			(start 0.67945 -0.3048)
			(end 0.67945 0.3048)
			(stroke
				(width 0.1)
				(type default)
			)
			(layer "F.Fab")
		)
		(fp_line
			(start 0.12065 -0.3048)
			(end 0.67945 -0.3048)
			(stroke
				(width 0.1)
				(type default)
			)
			(layer "F.Fab")
		)
		(fp_line
			(start 0.12065 -0.2794)
			(end 0.12065 -0.3048)
			(stroke
				(width 0.1)
				(type default)
			)
			(layer "F.Fab")
		)
		(fp_line
			(start -0.12065 -0.2794)
			(end 0.12065 -0.2794)
			(stroke
				(width 0.1)
				(type default)
			)
			(layer "F.Fab")
		)
		(fp_line
			(start 0.120396 0.2794)
			(end -0.12065 0.2794)
			(stroke
				(width 0.1)
				(type default)
			)
			(layer "F.Fab")
		)
		(fp_line
			(start -0.12065 0.2794)
			(end -0.12065 0.3048)
			(stroke
				(width 0.1)
				(type default)
			)
			(layer "F.Fab")
		)
		(fp_line
			(start 0.67945 0.3048)
			(end 0.120396 0.3048)
			(stroke
				(width 0.1)
				(type default)
			)
			(layer "F.Fab")
		)
		(fp_line
			(start 0.120396 0.3048)
			(end 0.120396 0.2794)
			(stroke
				(width 0.1)
				(type default)
			)
			(layer "F.Fab")
		)
		(fp_line
			(start -0.12065 0.3048)
			(end -0.67945 0.3048)
			(stroke
				(width 0.1)
				(type default)
			)
			(layer "F.Fab")
		)
		(fp_line
			(start -0.67945 0.3048)
			(end -0.67945 -0.305054)
			(stroke
				(width 0.1)
				(type default)
			)
			(layer "F.Fab")
		)
		(pad "1" smd circle
			(at -0.40005 0 90)
			(size 0 0)
			(layers "F.Cu" "F.Mask" "F.Paste")
			(net "USB2_5_R1_DP")
		)
		(pad "2" smd circle
			(at 0.40005 0 90)
			(size 0 0)
			(layers "F.Cu" "F.Mask" "F.Paste")
			(net "USB2_5_DP")
		)
	)
	(footprint ""
		(layer "F.Cu")
		(at 287.83788 -408.75966 -90)
		(property "Reference" "C2459"
			(at 0 0 270)
			(layer "F.SilkS")
			(hide yes)
			(effects
				(font
					(size 1.27 1.27)
				)
			)
		)
		(property "Value" ""
			(at 0 0 270)
			(layer "F.Fab")
			(effects
				(font
					(size 1.27 1.27)
				)
			)
		)
		(duplicate_pad_numbers_are_jumpers no)
		(fp_line
			(start -1.2954 0.5842)
			(end -1.2954 -0.5842)
			(stroke
				(width 0.1524)
				(type default)
			)
			(layer "F.SilkS")
		)
		(fp_line
			(start 1.2954 0.5842)
			(end -1.2954 0.5842)
			(stroke
				(width 0.1524)
				(type default)
			)
			(layer "F.SilkS")
		)
		(fp_line
			(start -1.2954 -0.5842)
			(end 1.2954 -0.5842)
			(stroke
				(width 0.1524)
				(type default)
			)
			(layer "F.SilkS")
		)
		(fp_line
			(start 0 -0.5842)
			(end 0 0.5842)
			(stroke
				(width 0.1524)
				(type default)
			)
			(layer "F.SilkS")
		)
		(fp_line
			(start 1.2954 -0.5842)
			(end 1.2954 0.5842)
			(stroke
				(width 0.1524)
				(type default)
			)
			(layer "F.SilkS")
		)
		(fp_line
			(start -0.8636 0.4572)
			(end -0.8636 0.4064)
			(stroke
				(width 0.1)
				(type default)
			)
			(layer "F.Fab")
		)
		(fp_line
			(start 0.8636 0.4572)
			(end -0.8636 0.4572)
			(stroke
				(width 0.1)
				(type default)
			)
			(layer "F.Fab")
		)
		(fp_line
			(start -1.1938 0.4064)
			(end -1.1938 -0.4064)
			(stroke
				(width 0.1)
				(type default)
			)
			(layer "F.Fab")
		)
		(fp_line
			(start -0.8636 0.4064)
			(end -1.1938 0.4064)
			(stroke
				(width 0.1)
				(type default)
			)
			(layer "F.Fab")
		)
		(fp_line
			(start 0.8636 0.4064)
			(end 0.8636 0.4572)
			(stroke
				(width 0.1)
				(type default)
			)
			(layer "F.Fab")
		)
		(fp_line
			(start 1.1938 0.4064)
			(end 0.8636 0.4064)
			(stroke
				(width 0.1)
				(type default)
			)
			(layer "F.Fab")
		)
		(fp_line
			(start -1.1938 -0.4064)
			(end -0.8636 -0.4064)
			(stroke
				(width 0.1)
				(type default)
			)
			(layer "F.Fab")
		)
		(fp_line
			(start -0.8636 -0.4064)
			(end -0.8636 -0.4572)
			(stroke
				(width 0.1)
				(type default)
			)
			(layer "F.Fab")
		)
		(fp_line
			(start 0.8636 -0.4064)
			(end 1.1938 -0.4064)
			(stroke
				(width 0.1)
				(type default)
			)
			(layer "F.Fab")
		)
		(fp_line
			(start 1.1938 -0.4064)
			(end 1.1938 0.4064)
			(stroke
				(width 0.1)
				(type default)
			)
			(layer "F.Fab")
		)
		(fp_line
			(start -0.8636 -0.4572)
			(end 0.8636 -0.4572)
			(stroke
				(width 0.1)
				(type default)
			)
			(layer "F.Fab")
		)
		(fp_line
			(start 0.8636 -0.4572)
			(end 0.8636 -0.4064)
			(stroke
				(width 0.1)
				(type default)
			)
			(layer "F.Fab")
		)
		(pad "1" smd rect
			(at -0.7366 0 180)
			(size 0.7112 0.8128)
			(layers "F.Cu" "F.Mask" "F.Paste")
			(net "P12V_HSC_TEMP_D+")
		)
		(pad "2" smd rect
			(at 0.7366 0 180)
			(size 0.7112 0.8128)
			(layers "F.Cu" "F.Mask" "F.Paste")
			(net "P12V_HSC_TEMP_D-")
		)
	)
	(footprint ""
		(layer "F.Cu")
		(at 332.124812 -18.797016 -90)
		(property "Reference" "R1255"
			(at 0 0 270)
			(layer "F.SilkS")
			(hide yes)
			(effects
				(font
					(size 1.27 1.27)
				)
			)
		)
		(property "Value" ""
			(at 0 0 270)
			(layer "F.Fab")
			(effects
				(font
					(size 1.27 1.27)
				)
			)
		)
		(duplicate_pad_numbers_are_jumpers no)
		(fp_line
			(start -0.7874 0.4064)
			(end -0.7874 -0.4064)
			(stroke
				(width 0.1524)
				(type default)
			)
			(layer "F.SilkS")
		)
		(fp_line
			(start 0.7874 0.4064)
			(end -0.7874 0.4064)
			(stroke
				(width 0.1524)
				(type default)
			)
			(layer "F.SilkS")
		)
		(fp_line
			(start -0.7874 -0.4064)
			(end 0.7874 -0.4064)
			(stroke
				(width 0.1524)
				(type default)
			)
			(layer "F.SilkS")
		)
		(fp_line
			(start 0.7874 -0.4064)
			(end 0.7874 0.4064)
			(stroke
				(width 0.1524)
				(type default)
			)
			(layer "F.SilkS")
		)
		(fp_line
			(start -0.67945 0.3048)
			(end -0.67945 -0.305054)
			(stroke
				(width 0.1)
				(type default)
			)
			(layer "F.Fab")
		)
		(fp_line
			(start -0.12065 0.3048)
			(end -0.67945 0.3048)
			(stroke
				(width 0.1)
				(type default)
			)
			(layer "F.Fab")
		)
		(fp_line
			(start 0.120396 0.3048)
			(end 0.120396 0.2794)
			(stroke
				(width 0.1)
				(type default)
			)
			(layer "F.Fab")
		)
		(fp_line
			(start 0.67945 0.3048)
			(end 0.120396 0.3048)
			(stroke
				(width 0.1)
				(type default)
			)
			(layer "F.Fab")
		)
		(fp_line
			(start -0.12065 0.2794)
			(end -0.12065 0.3048)
			(stroke
				(width 0.1)
				(type default)
			)
			(layer "F.Fab")
		)
		(fp_line
			(start 0.120396 0.2794)
			(end -0.12065 0.2794)
			(stroke
				(width 0.1)
				(type default)
			)
			(layer "F.Fab")
		)
		(fp_line
			(start -0.12065 -0.2794)
			(end 0.12065 -0.2794)
			(stroke
				(width 0.1)
				(type default)
			)
			(layer "F.Fab")
		)
		(fp_line
			(start 0.12065 -0.2794)
			(end 0.12065 -0.3048)
			(stroke
				(width 0.1)
				(type default)
			)
			(layer "F.Fab")
		)
		(fp_line
			(start 0.12065 -0.3048)
			(end 0.67945 -0.3048)
			(stroke
				(width 0.1)
				(type default)
			)
			(layer "F.Fab")
		)
		(fp_line
			(start 0.67945 -0.3048)
			(end 0.67945 0.3048)
			(stroke
				(width 0.1)
				(type default)
			)
			(layer "F.Fab")
		)
		(fp_line
			(start -0.67945 -0.305054)
			(end -0.12065 -0.305054)
			(stroke
				(width 0.1)
				(type default)
			)
			(layer "F.Fab")
		)
		(fp_line
			(start -0.12065 -0.305054)
			(end -0.12065 -0.2794)
			(stroke
				(width 0.1)
				(type default)
			)
			(layer "F.Fab")
		)
		(pad "1" smd circle
			(at -0.40005 0 270)
			(size 0 0)
			(layers "F.Cu" "F.Mask" "F.Paste")
			(net "PGPPA_AUX")
		)
		(pad "2" smd circle
			(at 0.40005 0 270)
			(size 0 0)
			(layers "F.Cu" "F.Mask" "F.Paste")
			(net "ESPI_ALERT1_N_LPC_RCIN_N")
		)
	)
	(footprint ""
		(layer "F.Cu")
		(at 145.175224 -95.643446 -90)
		(property "Reference" "C2248"
			(at 0 0 270)
			(layer "F.SilkS")
			(hide yes)
			(effects
				(font
					(size 1.27 1.27)
				)
			)
		)
		(property "Value" ""
			(at 0 0 270)
			(layer "F.Fab")
			(effects
				(font
					(size 1.27 1.27)
				)
			)
		)
		(duplicate_pad_numbers_are_jumpers no)
		(fp_line
			(start -0.7874 0.4064)
			(end -0.7874 -0.4064)
			(stroke
				(width 0.1524)
				(type default)
			)
			(layer "F.SilkS")
		)
		(fp_line
			(start 0.7874 0.4064)
			(end -0.7874 0.4064)
			(stroke
				(width 0.1524)
				(type default)
			)
			(layer "F.SilkS")
		)
		(fp_line
			(start -0.7874 -0.4064)
			(end 0.7874 -0.4064)
			(stroke
				(width 0.1524)
				(type default)
			)
			(layer "F.SilkS")
		)
		(fp_line
			(start 0.7874 -0.4064)
			(end 0.7874 0.4064)
			(stroke
				(width 0.1524)
				(type default)
			)
			(layer "F.SilkS")
		)
		(fp_line
			(start -0.67945 0.3048)
			(end -0.67945 -0.305054)
			(stroke
				(width 0.1)
				(type default)
			)
			(layer "F.Fab")
		)
		(fp_line
			(start -0.12065 0.3048)
			(end -0.67945 0.3048)
			(stroke
				(width 0.1)
				(type default)
			)
			(layer "F.Fab")
		)
		(fp_line
			(start 0.120396 0.3048)
			(end 0.120396 0.2794)
			(stroke
				(width 0.1)
				(type default)
			)
			(layer "F.Fab")
		)
		(fp_line
			(start 0.67945 0.3048)
			(end 0.120396 0.3048)
			(stroke
				(width 0.1)
				(type default)
			)
			(layer "F.Fab")
		)
		(fp_line
			(start -0.12065 0.2794)
			(end -0.12065 0.3048)
			(stroke
				(width 0.1)
				(type default)
			)
			(layer "F.Fab")
		)
		(fp_line
			(start 0.120396 0.2794)
			(end -0.12065 0.2794)
			(stroke
				(width 0.1)
				(type default)
			)
			(layer "F.Fab")
		)
		(fp_line
			(start -0.12065 -0.2794)
			(end 0.12065 -0.2794)
			(stroke
				(width 0.1)
				(type default)
			)
			(layer "F.Fab")
		)
		(fp_line
			(start 0.12065 -0.2794)
			(end 0.12065 -0.3048)
			(stroke
				(width 0.1)
				(type default)
			)
			(layer "F.Fab")
		)
		(fp_line
			(start 0.12065 -0.3048)
			(end 0.67945 -0.3048)
			(stroke
				(width 0.1)
				(type default)
			)
			(layer "F.Fab")
		)
		(fp_line
			(start 0.67945 -0.3048)
			(end 0.67945 0.3048)
			(stroke
				(width 0.1)
				(type default)
			)
			(layer "F.Fab")
		)
		(fp_line
			(start -0.67945 -0.305054)
			(end -0.12065 -0.305054)
			(stroke
				(width 0.1)
				(type default)
			)
			(layer "F.Fab")
		)
		(fp_line
			(start -0.12065 -0.305054)
			(end -0.12065 -0.2794)
			(stroke
				(width 0.1)
				(type default)
			)
			(layer "F.Fab")
		)
		(pad "1" smd circle
			(at -0.40005 0 270)
			(size 0 0)
			(layers "F.Cu" "F.Mask" "F.Paste")
			(net "P3V3")
		)
		(pad "2" smd circle
			(at 0.40005 0 270)
			(size 0 0)
			(layers "F.Cu" "F.Mask" "F.Paste")
			(net "GND")
		)
	)
	(footprint ""
		(layer "F.Cu")
		(at 115.95608 -119.846598 -90)
		(property "Reference" "R853"
			(at 0 0 270)
			(layer "F.SilkS")
			(hide yes)
			(effects
				(font
					(size 1.27 1.27)
				)
			)
		)
		(property "Value" ""
			(at 0 0 270)
			(layer "F.Fab")
			(effects
				(font
					(size 1.27 1.27)
				)
			)
		)
		(duplicate_pad_numbers_are_jumpers no)
		(fp_line
			(start -0.7874 0.4064)
			(end -0.7874 -0.4064)
			(stroke
				(width 0.1524)
				(type default)
			)
			(layer "F.SilkS")
		)
		(fp_line
			(start 0.7874 0.4064)
			(end -0.7874 0.4064)
			(stroke
				(width 0.1524)
				(type default)
			)
			(layer "F.SilkS")
		)
		(fp_line
			(start -0.7874 -0.4064)
			(end 0.7874 -0.4064)
			(stroke
				(width 0.1524)
				(type default)
			)
			(layer "F.SilkS")
		)
		(fp_line
			(start 0.7874 -0.4064)
			(end 0.7874 0.4064)
			(stroke
				(width 0.1524)
				(type default)
			)
			(layer "F.SilkS")
		)
		(fp_line
			(start -0.67945 0.3048)
			(end -0.67945 -0.305054)
			(stroke
				(width 0.1)
				(type default)
			)
			(layer "F.Fab")
		)
		(fp_line
			(start -0.12065 0.3048)
			(end -0.67945 0.3048)
			(stroke
				(width 0.1)
				(type default)
			)
			(layer "F.Fab")
		)
		(fp_line
			(start 0.120396 0.3048)
			(end 0.120396 0.2794)
			(stroke
				(width 0.1)
				(type default)
			)
			(layer "F.Fab")
		)
		(fp_line
			(start 0.67945 0.3048)
			(end 0.120396 0.3048)
			(stroke
				(width 0.1)
				(type default)
			)
			(layer "F.Fab")
		)
		(fp_line
			(start -0.12065 0.2794)
			(end -0.12065 0.3048)
			(stroke
				(width 0.1)
				(type default)
			)
			(layer "F.Fab")
		)
		(fp_line
			(start 0.120396 0.2794)
			(end -0.12065 0.2794)
			(stroke
				(width 0.1)
				(type default)
			)
			(layer "F.Fab")
		)
		(fp_line
			(start -0.12065 -0.2794)
			(end 0.12065 -0.2794)
			(stroke
				(width 0.1)
				(type default)
			)
			(layer "F.Fab")
		)
		(fp_line
			(start 0.12065 -0.2794)
			(end 0.12065 -0.3048)
			(stroke
				(width 0.1)
				(type default)
			)
			(layer "F.Fab")
		)
		(fp_line
			(start 0.12065 -0.3048)
			(end 0.67945 -0.3048)
			(stroke
				(width 0.1)
				(type default)
			)
			(layer "F.Fab")
		)
		(fp_line
			(start 0.67945 -0.3048)
			(end 0.67945 0.3048)
			(stroke
				(width 0.1)
				(type default)
			)
			(layer "F.Fab")
		)
		(fp_line
			(start -0.67945 -0.305054)
			(end -0.12065 -0.305054)
			(stroke
				(width 0.1)
				(type default)
			)
			(layer "F.Fab")
		)
		(fp_line
			(start -0.12065 -0.305054)
			(end -0.12065 -0.2794)
			(stroke
				(width 0.1)
				(type default)
			)
			(layer "F.Fab")
		)
		(pad "1" smd circle
			(at -0.40005 0 270)
			(size 0 0)
			(layers "F.Cu" "F.Mask" "F.Paste")
			(net "RST_CPU0_DRAM_EF_N")
		)
		(pad "2" smd circle
			(at 0.40005 0 270)
			(size 0 0)
			(layers "F.Cu" "F.Mask" "F.Paste")
			(net "RST_CPU0_DRAM_EF_PLD_N")
		)
	)
	(footprint ""
		(layer "F.Cu")
		(at 412.585662 -361.896914 -90)
		(property "Reference" "PC1211_P0_1"
			(at 0 0 270)
			(layer "F.SilkS")
			(hide yes)
			(effects
				(font
					(size 1.27 1.27)
				)
			)
		)
		(property "Value" ""
			(at 0 0 270)
			(layer "F.Fab")
			(effects
				(font
					(size 1.27 1.27)
				)
			)
		)
		(duplicate_pad_numbers_are_jumpers no)
		(fp_line
			(start -0.7874 0.4064)
			(end -0.7874 -0.4064)
			(stroke
				(width 0.1524)
				(type default)
			)
			(layer "F.SilkS")
		)
		(fp_line
			(start 0.7874 0.4064)
			(end -0.7874 0.4064)
			(stroke
				(width 0.1524)
				(type default)
			)
			(layer "F.SilkS")
		)
		(fp_line
			(start -0.7874 -0.4064)
			(end 0.7874 -0.4064)
			(stroke
				(width 0.1524)
				(type default)
			)
			(layer "F.SilkS")
		)
		(fp_line
			(start 0.7874 -0.4064)
			(end 0.7874 0.4064)
			(stroke
				(width 0.1524)
				(type default)
			)
			(layer "F.SilkS")
		)
		(fp_line
			(start -0.67945 0.3048)
			(end -0.67945 -0.305054)
			(stroke
				(width 0.1)
				(type default)
			)
			(layer "F.Fab")
		)
		(fp_line
			(start -0.12065 0.3048)
			(end -0.67945 0.3048)
			(stroke
				(width 0.1)
				(type default)
			)
			(layer "F.Fab")
		)
		(fp_line
			(start 0.120396 0.3048)
			(end 0.120396 0.2794)
			(stroke
				(width 0.1)
				(type default)
			)
			(layer "F.Fab")
		)
		(fp_line
			(start 0.67945 0.3048)
			(end 0.120396 0.3048)
			(stroke
				(width 0.1)
				(type default)
			)
			(layer "F.Fab")
		)
		(fp_line
			(start -0.12065 0.2794)
			(end -0.12065 0.3048)
			(stroke
				(width 0.1)
				(type default)
			)
			(layer "F.Fab")
		)
		(fp_line
			(start 0.120396 0.2794)
			(end -0.12065 0.2794)
			(stroke
				(width 0.1)
				(type default)
			)
			(layer "F.Fab")
		)
		(fp_line
			(start -0.12065 -0.2794)
			(end 0.12065 -0.2794)
			(stroke
				(width 0.1)
				(type default)
			)
			(layer "F.Fab")
		)
		(fp_line
			(start 0.12065 -0.2794)
			(end 0.12065 -0.3048)
			(stroke
				(width 0.1)
				(type default)
			)
			(layer "F.Fab")
		)
		(fp_line
			(start 0.12065 -0.3048)
			(end 0.67945 -0.3048)
			(stroke
				(width 0.1)
				(type default)
			)
			(layer "F.Fab")
		)
		(fp_line
			(start 0.67945 -0.3048)
			(end 0.67945 0.3048)
			(stroke
				(width 0.1)
				(type default)
			)
			(layer "F.Fab")
		)
		(fp_line
			(start -0.67945 -0.305054)
			(end -0.12065 -0.305054)
			(stroke
				(width 0.1)
				(type default)
			)
			(layer "F.Fab")
		)
		(fp_line
			(start -0.12065 -0.305054)
			(end -0.12065 -0.2794)
			(stroke
				(width 0.1)
				(type default)
			)
			(layer "F.Fab")
		)
		(pad "1" smd circle
			(at -0.40005 0 270)
			(size 0 0)
			(layers "F.Cu" "F.Mask" "F.Paste")
			(net "PVCCFA_EHV_FIVRA_CPU0_PVCC1")
		)
		(pad "2" smd circle
			(at 0.40005 0 270)
			(size 0 0)
			(layers "F.Cu" "F.Mask" "F.Paste")
			(net "GND")
		)
	)
	(footprint ""
		(layer "F.Cu")
		(at 315.10224 -48.584866)
		(property "Reference" "R699"
			(at 0 0 0)
			(layer "F.SilkS")
			(hide yes)
			(effects
				(font
					(size 1.27 1.27)
				)
			)
		)
		(property "Value" ""
			(at 0 0 0)
			(layer "F.Fab")
			(effects
				(font
					(size 1.27 1.27)
				)
			)
		)
		(duplicate_pad_numbers_are_jumpers no)
		(fp_line
			(start -0.7874 -0.4064)
			(end 0.7874 -0.4064)
			(stroke
				(width 0.1524)
				(type default)
			)
			(layer "F.SilkS")
		)
		(fp_line
			(start -0.7874 0.4064)
			(end -0.7874 -0.4064)
			(stroke
				(width 0.1524)
				(type default)
			)
			(layer "F.SilkS")
		)
		(fp_line
			(start 0.7874 -0.4064)
			(end 0.7874 0.4064)
			(stroke
				(width 0.1524)
				(type default)
			)
			(layer "F.SilkS")
		)
		(fp_line
			(start 0.7874 0.4064)
			(end -0.7874 0.4064)
			(stroke
				(width 0.1524)
				(type default)
			)
			(layer "F.SilkS")
		)
		(fp_line
			(start -0.67945 -0.305054)
			(end -0.12065 -0.305054)
			(stroke
				(width 0.1)
				(type default)
			)
			(layer "F.Fab")
		)
		(fp_line
			(start -0.67945 0.3048)
			(end -0.67945 -0.305054)
			(stroke
				(width 0.1)
				(type default)
			)
			(layer "F.Fab")
		)
		(fp_line
			(start -0.12065 -0.305054)
			(end -0.12065 -0.2794)
			(stroke
				(width 0.1)
				(type default)
			)
			(layer "F.Fab")
		)
		(fp_line
			(start -0.12065 -0.2794)
			(end 0.12065 -0.2794)
			(stroke
				(width 0.1)
				(type default)
			)
			(layer "F.Fab")
		)
		(fp_line
			(start -0.12065 0.2794)
			(end -0.12065 0.3048)
			(stroke
				(width 0.1)
				(type default)
			)
			(layer "F.Fab")
		)
		(fp_line
			(start -0.12065 0.3048)
			(end -0.67945 0.3048)
			(stroke
				(width 0.1)
				(type default)
			)
			(layer "F.Fab")
		)
		(fp_line
			(start 0.120396 0.2794)
			(end -0.12065 0.2794)
			(stroke
				(width 0.1)
				(type default)
			)
			(layer "F.Fab")
		)
		(fp_line
			(start 0.120396 0.3048)
			(end 0.120396 0.2794)
			(stroke
				(width 0.1)
				(type default)
			)
			(layer "F.Fab")
		)
		(fp_line
			(start 0.12065 -0.3048)
			(end 0.67945 -0.3048)
			(stroke
				(width 0.1)
				(type default)
			)
			(layer "F.Fab")
		)
		(fp_line
			(start 0.12065 -0.2794)
			(end 0.12065 -0.3048)
			(stroke
				(width 0.1)
				(type default)
			)
			(layer "F.Fab")
		)
		(fp_line
			(start 0.67945 -0.3048)
			(end 0.67945 0.3048)
			(stroke
				(width 0.1)
				(type default)
			)
			(layer "F.Fab")
		)
		(fp_line
			(start 0.67945 0.3048)
			(end 0.120396 0.3048)
			(stroke
				(width 0.1)
				(type default)
			)
			(layer "F.Fab")
		)
		(pad "1" smd circle
			(at -0.40005 0)
			(size 0 0)
			(layers "F.Cu" "F.Mask" "F.Paste")
			(net "FM_PCH_CRASHLOG_TRIG_R_N")
		)
		(pad "2" smd circle
			(at 0.40005 0)
			(size 0 0)
			(layers "F.Cu" "F.Mask" "F.Paste")
			(net "FM_PCH_CRASHLOG_TRIG_N")
		)
	)
	(footprint ""
		(layer "F.Cu")
		(at 299.02023 -54.400196)
		(property "Reference" "R2976"
			(at 0 0 0)
			(layer "F.SilkS")
			(hide yes)
			(effects
				(font
					(size 1.27 1.27)
				)
			)
		)
		(property "Value" ""
			(at 0 0 0)
			(layer "F.Fab")
			(effects
				(font
					(size 1.27 1.27)
				)
			)
		)
		(duplicate_pad_numbers_are_jumpers no)
		(fp_line
			(start -0.7874 -0.4064)
			(end 0.7874 -0.4064)
			(stroke
				(width 0.1524)
				(type default)
			)
			(layer "F.SilkS")
		)
		(fp_line
			(start -0.7874 0.4064)
			(end -0.7874 -0.4064)
			(stroke
				(width 0.1524)
				(type default)
			)
			(layer "F.SilkS")
		)
		(fp_line
			(start 0.7874 -0.4064)
			(end 0.7874 0.4064)
			(stroke
				(width 0.1524)
				(type default)
			)
			(layer "F.SilkS")
		)
		(fp_line
			(start 0.7874 0.4064)
			(end -0.7874 0.4064)
			(stroke
				(width 0.1524)
				(type default)
			)
			(layer "F.SilkS")
		)
		(fp_line
			(start -0.67945 -0.305054)
			(end -0.12065 -0.305054)
			(stroke
				(width 0.1)
				(type default)
			)
			(layer "F.Fab")
		)
		(fp_line
			(start -0.67945 0.3048)
			(end -0.67945 -0.305054)
			(stroke
				(width 0.1)
				(type default)
			)
			(layer "F.Fab")
		)
		(fp_line
			(start -0.12065 -0.305054)
			(end -0.12065 -0.2794)
			(stroke
				(width 0.1)
				(type default)
			)
			(layer "F.Fab")
		)
		(fp_line
			(start -0.12065 -0.2794)
			(end 0.12065 -0.2794)
			(stroke
				(width 0.1)
				(type default)
			)
			(layer "F.Fab")
		)
		(fp_line
			(start -0.12065 0.2794)
			(end -0.12065 0.3048)
			(stroke
				(width 0.1)
				(type default)
			)
			(layer "F.Fab")
		)
		(fp_line
			(start -0.12065 0.3048)
			(end -0.67945 0.3048)
			(stroke
				(width 0.1)
				(type default)
			)
			(layer "F.Fab")
		)
		(fp_line
			(start 0.120396 0.2794)
			(end -0.12065 0.2794)
			(stroke
				(width 0.1)
				(type default)
			)
			(layer "F.Fab")
		)
		(fp_line
			(start 0.120396 0.3048)
			(end 0.120396 0.2794)
			(stroke
				(width 0.1)
				(type default)
			)
			(layer "F.Fab")
		)
		(fp_line
			(start 0.12065 -0.3048)
			(end 0.67945 -0.3048)
			(stroke
				(width 0.1)
				(type default)
			)
			(layer "F.Fab")
		)
		(fp_line
			(start 0.12065 -0.2794)
			(end 0.12065 -0.3048)
			(stroke
				(width 0.1)
				(type default)
			)
			(layer "F.Fab")
		)
		(fp_line
			(start 0.67945 -0.3048)
			(end 0.67945 0.3048)
			(stroke
				(width 0.1)
				(type default)
			)
			(layer "F.Fab")
		)
		(fp_line
			(start 0.67945 0.3048)
			(end 0.120396 0.3048)
			(stroke
				(width 0.1)
				(type default)
			)
			(layer "F.Fab")
		)
		(pad "1" smd circle
			(at -0.40005 0)
			(size 0 0)
			(layers "F.Cu" "F.Mask" "F.Paste")
			(net "P1V05_PCH_AUX")
		)
		(pad "2" smd circle
			(at 0.40005 0)
			(size 0 0)
			(layers "F.Cu" "F.Mask" "F.Paste")
			(net "FM_BOARD_SKU_ID3")
		)
	)
	(footprint ""
		(layer "F.Cu")
		(at 495.599212 -342.797638)
		(property "Reference" "DB1"
			(at 2.19837 2.397506 90)
			(unlocked yes)
			(layer "F.SilkS")
			(effects
				(font
					(size 0.7874 0.5842)
					(thickness 0.1524)
				)
				(justify left)
			)
		)
		(property "Value" ""
			(at 0 0 0)
			(layer "F.Fab")
			(effects
				(font
					(size 1.27 1.27)
				)
			)
		)
		(duplicate_pad_numbers_are_jumpers no)
		(fp_line
			(start -3.330702 -4.771136)
			(end 3.330702 -4.771136)
			(stroke
				(width 0.1524)
				(type default)
			)
			(layer "F.SilkS")
		)
		(fp_line
			(start 0 4.011168)
			(end -3.330702 -4.771136)
			(stroke
				(width 0.1524)
				(type default)
			)
			(layer "F.SilkS")
		)
		(fp_line
			(start 3.330702 -4.771136)
			(end 0 4.011168)
			(stroke
				(width 0.1524)
				(type default)
			)
			(layer "F.SilkS")
		)
		(fp_line
			(start -3.330702 -4.771136)
			(end 3.330702 -4.771136)
			(stroke
				(width 0.1)
				(type default)
			)
			(layer "F.Fab")
		)
		(fp_line
			(start 0 4.011168)
			(end -3.330702 -4.771136)
			(stroke
				(width 0.1)
				(type default)
			)
			(layer "F.Fab")
		)
		(fp_line
			(start 3.330702 -4.771136)
			(end 0 4.011168)
			(stroke
				(width 0.1)
				(type default)
			)
			(layer "F.Fab")
		)
		(pad "1" thru_hole circle
			(at 0 0)
			(size 2.159 2.159)
			(drill 1.7018)
			(layers "*.Cu" "*.Mask")
			(remove_unused_layers no)
			(net "T1_GND")
			(clearance 0.0254)
			(thermal_gap 0.0254)
		)
		(pad "2" thru_hole circle
			(at -1.27 -3.348736)
			(size 2.159 2.159)
			(drill 1.7018)
			(layers "*.Cu" "*.Mask")
			(remove_unused_layers no)
			(net "TDR_SE_40_OHM_TOP")
			(clearance 0.0254)
			(thermal_gap 0.0254)
		)
		(pad "3" thru_hole circle
			(at 1.27 -3.348736)
			(size 2.159 2.159)
			(drill 1.7018)
			(layers "*.Cu" "*.Mask")
			(remove_unused_layers no)
			(net "TDR_SE_40_OHM_TOP")
			(clearance 0.0254)
			(thermal_gap 0.0254)
		)
	)
	(footprint ""
		(layer "F.Cu")
		(at 398.397984 -17.612614 90)
		(property "Reference" "C844"
			(at 0 0 90)
			(layer "F.SilkS")
			(hide yes)
			(effects
				(font
					(size 1.27 1.27)
				)
			)
		)
		(property "Value" ""
			(at 0 0 90)
			(layer "F.Fab")
			(effects
				(font
					(size 1.27 1.27)
				)
			)
		)
		(duplicate_pad_numbers_are_jumpers no)
		(fp_line
			(start 0.299974 -0.150114)
			(end 0.299974 0.150114)
			(stroke
				(width 0.1)
				(type default)
			)
			(layer "F.Fab")
		)
		(fp_line
			(start -0.299974 -0.150114)
			(end 0.299974 -0.150114)
			(stroke
				(width 0.1)
				(type default)
			)
			(layer "F.Fab")
		)
		(fp_line
			(start 0.299974 0.150114)
			(end -0.299974 0.150114)
			(stroke
				(width 0.1)
				(type default)
			)
			(layer "F.Fab")
		)
		(fp_line
			(start -0.299974 0.150114)
			(end -0.299974 -0.150114)
			(stroke
				(width 0.1)
				(type default)
			)
			(layer "F.Fab")
		)
		(pad "1" smd rect
			(at -0.2667 0 90)
			(size 0.3048 0.381)
			(layers "F.Cu" "F.Mask" "F.Paste")
			(net "P5E_CPU0_PE1_TX_C_DN<12>")
		)
		(pad "2" smd rect
			(at 0.2667 0 90)
			(size 0.3048 0.381)
			(layers "F.Cu" "F.Mask" "F.Paste")
			(net "P5E_CPU0_PE1_TX_DN<12>")
		)
	)
	(footprint ""
		(layer "F.Cu")
		(at 449.044314 -25.10028 -90)
		(property "Reference" "PC2079"
			(at 0 0 270)
			(layer "F.SilkS")
			(hide yes)
			(effects
				(font
					(size 1.27 1.27)
				)
			)
		)
		(property "Value" ""
			(at 0 0 270)
			(layer "F.Fab")
			(effects
				(font
					(size 1.27 1.27)
				)
			)
		)
		(duplicate_pad_numbers_are_jumpers no)
		(fp_line
			(start -0.7874 0.4064)
			(end -0.7874 -0.4064)
			(stroke
				(width 0.1524)
				(type default)
			)
			(layer "F.SilkS")
		)
		(fp_line
			(start 0.7874 0.4064)
			(end -0.7874 0.4064)
			(stroke
				(width 0.1524)
				(type default)
			)
			(layer "F.SilkS")
		)
		(fp_line
			(start -0.7874 -0.4064)
			(end 0.7874 -0.4064)
			(stroke
				(width 0.1524)
				(type default)
			)
			(layer "F.SilkS")
		)
		(fp_line
			(start 0.7874 -0.4064)
			(end 0.7874 0.4064)
			(stroke
				(width 0.1524)
				(type default)
			)
			(layer "F.SilkS")
		)
		(fp_line
			(start -0.67945 0.3048)
			(end -0.67945 -0.305054)
			(stroke
				(width 0.1)
				(type default)
			)
			(layer "F.Fab")
		)
		(fp_line
			(start -0.12065 0.3048)
			(end -0.67945 0.3048)
			(stroke
				(width 0.1)
				(type default)
			)
			(layer "F.Fab")
		)
		(fp_line
			(start 0.120396 0.3048)
			(end 0.120396 0.2794)
			(stroke
				(width 0.1)
				(type default)
			)
			(layer "F.Fab")
		)
		(fp_line
			(start 0.67945 0.3048)
			(end 0.120396 0.3048)
			(stroke
				(width 0.1)
				(type default)
			)
			(layer "F.Fab")
		)
		(fp_line
			(start -0.12065 0.2794)
			(end -0.12065 0.3048)
			(stroke
				(width 0.1)
				(type default)
			)
			(layer "F.Fab")
		)
		(fp_line
			(start 0.120396 0.2794)
			(end -0.12065 0.2794)
			(stroke
				(width 0.1)
				(type default)
			)
			(layer "F.Fab")
		)
		(fp_line
			(start -0.12065 -0.2794)
			(end 0.12065 -0.2794)
			(stroke
				(width 0.1)
				(type default)
			)
			(layer "F.Fab")
		)
		(fp_line
			(start 0.12065 -0.2794)
			(end 0.12065 -0.3048)
			(stroke
				(width 0.1)
				(type default)
			)
			(layer "F.Fab")
		)
		(fp_line
			(start 0.12065 -0.3048)
			(end 0.67945 -0.3048)
			(stroke
				(width 0.1)
				(type default)
			)
			(layer "F.Fab")
		)
		(fp_line
			(start 0.67945 -0.3048)
			(end 0.67945 0.3048)
			(stroke
				(width 0.1)
				(type default)
			)
			(layer "F.Fab")
		)
		(fp_line
			(start -0.67945 -0.305054)
			(end -0.12065 -0.305054)
			(stroke
				(width 0.1)
				(type default)
			)
			(layer "F.Fab")
		)
		(fp_line
			(start -0.12065 -0.305054)
			(end -0.12065 -0.2794)
			(stroke
				(width 0.1)
				(type default)
			)
			(layer "F.Fab")
		)
		(pad "1" smd circle
			(at -0.40005 0 270)
			(size 0 0)
			(layers "F.Cu" "F.Mask" "F.Paste")
			(net "P12V_AUX")
		)
		(pad "2" smd circle
			(at 0.40005 0 270)
			(size 0 0)
			(layers "F.Cu" "F.Mask" "F.Paste")
			(net "GND")
		)
	)
	(footprint ""
		(layer "F.Cu")
		(at 151.844756 -65.413128)
		(property "Reference" "R3775"
			(at 0 0 0)
			(layer "F.SilkS")
			(hide yes)
			(effects
				(font
					(size 1.27 1.27)
				)
			)
		)
		(property "Value" ""
			(at 0 0 0)
			(layer "F.Fab")
			(effects
				(font
					(size 1.27 1.27)
				)
			)
		)
		(duplicate_pad_numbers_are_jumpers no)
		(fp_line
			(start -0.7874 -0.4064)
			(end 0.7874 -0.4064)
			(stroke
				(width 0.1524)
				(type default)
			)
			(layer "F.SilkS")
		)
		(fp_line
			(start -0.7874 0.4064)
			(end -0.7874 -0.4064)
			(stroke
				(width 0.1524)
				(type default)
			)
			(layer "F.SilkS")
		)
		(fp_line
			(start 0.7874 -0.4064)
			(end 0.7874 0.4064)
			(stroke
				(width 0.1524)
				(type default)
			)
			(layer "F.SilkS")
		)
		(fp_line
			(start 0.7874 0.4064)
			(end -0.7874 0.4064)
			(stroke
				(width 0.1524)
				(type default)
			)
			(layer "F.SilkS")
		)
		(fp_line
			(start -0.67945 -0.305054)
			(end -0.12065 -0.305054)
			(stroke
				(width 0.1)
				(type default)
			)
			(layer "F.Fab")
		)
		(fp_line
			(start -0.67945 0.3048)
			(end -0.67945 -0.305054)
			(stroke
				(width 0.1)
				(type default)
			)
			(layer "F.Fab")
		)
		(fp_line
			(start -0.12065 -0.305054)
			(end -0.12065 -0.2794)
			(stroke
				(width 0.1)
				(type default)
			)
			(layer "F.Fab")
		)
		(fp_line
			(start -0.12065 -0.2794)
			(end 0.12065 -0.2794)
			(stroke
				(width 0.1)
				(type default)
			)
			(layer "F.Fab")
		)
		(fp_line
			(start -0.12065 0.2794)
			(end -0.12065 0.3048)
			(stroke
				(width 0.1)
				(type default)
			)
			(layer "F.Fab")
		)
		(fp_line
			(start -0.12065 0.3048)
			(end -0.67945 0.3048)
			(stroke
				(width 0.1)
				(type default)
			)
			(layer "F.Fab")
		)
		(fp_line
			(start 0.120396 0.2794)
			(end -0.12065 0.2794)
			(stroke
				(width 0.1)
				(type default)
			)
			(layer "F.Fab")
		)
		(fp_line
			(start 0.120396 0.3048)
			(end 0.120396 0.2794)
			(stroke
				(width 0.1)
				(type default)
			)
			(layer "F.Fab")
		)
		(fp_line
			(start 0.12065 -0.3048)
			(end 0.67945 -0.3048)
			(stroke
				(width 0.1)
				(type default)
			)
			(layer "F.Fab")
		)
		(fp_line
			(start 0.12065 -0.2794)
			(end 0.12065 -0.3048)
			(stroke
				(width 0.1)
				(type default)
			)
			(layer "F.Fab")
		)
		(fp_line
			(start 0.67945 -0.3048)
			(end 0.67945 0.3048)
			(stroke
				(width 0.1)
				(type default)
			)
			(layer "F.Fab")
		)
		(fp_line
			(start 0.67945 0.3048)
			(end 0.120396 0.3048)
			(stroke
				(width 0.1)
				(type default)
			)
			(layer "F.Fab")
		)
		(pad "1" smd circle
			(at -0.40005 0)
			(size 0 0)
			(layers "F.Cu" "F.Mask" "F.Paste")
			(net "RST_SMB_SWITCH_N")
		)
		(pad "2" smd circle
			(at 0.40005 0)
			(size 0 0)
			(layers "F.Cu" "F.Mask" "F.Paste")
			(net "RST_SMB_E1S_N")
		)
	)
	(footprint ""
		(layer "F.Cu")
		(at 460.523844 -70.271386 -90)
		(property "Reference" "PC2263"
			(at 0 0 270)
			(layer "F.SilkS")
			(hide yes)
			(effects
				(font
					(size 1.27 1.27)
				)
			)
		)
		(property "Value" ""
			(at 0 0 270)
			(layer "F.Fab")
			(effects
				(font
					(size 1.27 1.27)
				)
			)
		)
		(duplicate_pad_numbers_are_jumpers no)
		(fp_line
			(start -1.524 0.762)
			(end -1.524 -0.762)
			(stroke
				(width 0.1524)
				(type default)
			)
			(layer "F.SilkS")
		)
		(fp_line
			(start 1.524 0.762)
			(end -1.524 0.762)
			(stroke
				(width 0.1524)
				(type default)
			)
			(layer "F.SilkS")
		)
		(fp_line
			(start -1.524 -0.762)
			(end 1.524 -0.762)
			(stroke
				(width 0.1524)
				(type default)
			)
			(layer "F.SilkS")
		)
		(fp_line
			(start 1.524 -0.762)
			(end 1.524 0.762)
			(stroke
				(width 0.1524)
				(type default)
			)
			(layer "F.SilkS")
		)
		(fp_line
			(start -1.1049 0.724916)
			(end 1.1049 0.724916)
			(stroke
				(width 0.1)
				(type default)
			)
			(layer "F.Fab")
		)
		(fp_line
			(start 1.1049 0.724916)
			(end 1.1049 -0.724916)
			(stroke
				(width 0.1)
				(type default)
			)
			(layer "F.Fab")
		)
		(fp_line
			(start -1.1049 -0.724916)
			(end -1.1049 0.724916)
			(stroke
				(width 0.1)
				(type default)
			)
			(layer "F.Fab")
		)
		(fp_line
			(start 1.1049 -0.724916)
			(end -1.1049 -0.724916)
			(stroke
				(width 0.1)
				(type default)
			)
			(layer "F.Fab")
		)
		(pad "1" smd rect
			(at -0.889 0 90)
			(size 1.016 1.27)
			(layers "F.Cu" "F.Mask" "F.Paste")
			(net "SW_P3V3_AUX_FLT")
		)
		(pad "2" smd rect
			(at 0.889 0 90)
			(size 1.016 1.27)
			(layers "F.Cu" "F.Mask" "F.Paste")
			(net "GND")
		)
	)
	(footprint ""
		(layer "F.Cu")
		(at 308.00294 -56.045608 90)
		(property "Reference" "R149"
			(at 0 0 90)
			(layer "F.SilkS")
			(hide yes)
			(effects
				(font
					(size 1.27 1.27)
				)
			)
		)
		(property "Value" ""
			(at 0 0 90)
			(layer "F.Fab")
			(effects
				(font
					(size 1.27 1.27)
				)
			)
		)
		(duplicate_pad_numbers_are_jumpers no)
		(fp_line
			(start 0.7874 -0.4064)
			(end 0.7874 0.4064)
			(stroke
				(width 0.1524)
				(type default)
			)
			(layer "F.SilkS")
		)
		(fp_line
			(start -0.7874 -0.4064)
			(end 0.7874 -0.4064)
			(stroke
				(width 0.1524)
				(type default)
			)
			(layer "F.SilkS")
		)
		(fp_line
			(start 0.7874 0.4064)
			(end -0.7874 0.4064)
			(stroke
				(width 0.1524)
				(type default)
			)
			(layer "F.SilkS")
		)
		(fp_line
			(start -0.7874 0.4064)
			(end -0.7874 -0.4064)
			(stroke
				(width 0.1524)
				(type default)
			)
			(layer "F.SilkS")
		)
		(fp_line
			(start -0.12065 -0.305054)
			(end -0.12065 -0.2794)
			(stroke
				(width 0.1)
				(type default)
			)
			(layer "F.Fab")
		)
		(fp_line
			(start -0.67945 -0.305054)
			(end -0.12065 -0.305054)
			(stroke
				(width 0.1)
				(type default)
			)
			(layer "F.Fab")
		)
		(fp_line
			(start 0.67945 -0.3048)
			(end 0.67945 0.3048)
			(stroke
				(width 0.1)
				(type default)
			)
			(layer "F.Fab")
		)
		(fp_line
			(start 0.12065 -0.3048)
			(end 0.67945 -0.3048)
			(stroke
				(width 0.1)
				(type default)
			)
			(layer "F.Fab")
		)
		(fp_line
			(start 0.12065 -0.2794)
			(end 0.12065 -0.3048)
			(stroke
				(width 0.1)
				(type default)
			)
			(layer "F.Fab")
		)
		(fp_line
			(start -0.12065 -0.2794)
			(end 0.12065 -0.2794)
			(stroke
				(width 0.1)
				(type default)
			)
			(layer "F.Fab")
		)
		(fp_line
			(start 0.120396 0.2794)
			(end -0.12065 0.2794)
			(stroke
				(width 0.1)
				(type default)
			)
			(layer "F.Fab")
		)
		(fp_line
			(start -0.12065 0.2794)
			(end -0.12065 0.3048)
			(stroke
				(width 0.1)
				(type default)
			)
			(layer "F.Fab")
		)
		(fp_line
			(start 0.67945 0.3048)
			(end 0.120396 0.3048)
			(stroke
				(width 0.1)
				(type default)
			)
			(layer "F.Fab")
		)
		(fp_line
			(start 0.120396 0.3048)
			(end 0.120396 0.2794)
			(stroke
				(width 0.1)
				(type default)
			)
			(layer "F.Fab")
		)
		(fp_line
			(start -0.12065 0.3048)
			(end -0.67945 0.3048)
			(stroke
				(width 0.1)
				(type default)
			)
			(layer "F.Fab")
		)
		(fp_line
			(start -0.67945 0.3048)
			(end -0.67945 -0.305054)
			(stroke
				(width 0.1)
				(type default)
			)
			(layer "F.Fab")
		)
		(pad "1" smd circle
			(at -0.40005 0 90)
			(size 0 0)
			(layers "F.Cu" "F.Mask" "F.Paste")
			(net "PECI_PCH_R")
		)
		(pad "2" smd circle
			(at 0.40005 0 90)
			(size 0 0)
			(layers "F.Cu" "F.Mask" "F.Paste")
			(net "PECI_PCH_B1")
		)
	)
	(footprint ""
		(layer "F.Cu")
		(at 15.436596 -396.263876)
		(property "Reference" "R3271"
			(at 0 0 0)
			(layer "F.SilkS")
			(hide yes)
			(effects
				(font
					(size 1.27 1.27)
				)
			)
		)
		(property "Value" ""
			(at 0 0 0)
			(layer "F.Fab")
			(effects
				(font
					(size 1.27 1.27)
				)
			)
		)
		(duplicate_pad_numbers_are_jumpers no)
		(fp_line
			(start -0.7874 -0.4064)
			(end 0.7874 -0.4064)
			(stroke
				(width 0.1524)
				(type default)
			)
			(layer "F.SilkS")
		)
		(fp_line
			(start -0.7874 0.4064)
			(end -0.7874 -0.4064)
			(stroke
				(width 0.1524)
				(type default)
			)
			(layer "F.SilkS")
		)
		(fp_line
			(start 0.7874 -0.4064)
			(end 0.7874 0.4064)
			(stroke
				(width 0.1524)
				(type default)
			)
			(layer "F.SilkS")
		)
		(fp_line
			(start 0.7874 0.4064)
			(end -0.7874 0.4064)
			(stroke
				(width 0.1524)
				(type default)
			)
			(layer "F.SilkS")
		)
		(fp_line
			(start -0.67945 -0.305054)
			(end -0.12065 -0.305054)
			(stroke
				(width 0.1)
				(type default)
			)
			(layer "F.Fab")
		)
		(fp_line
			(start -0.67945 0.3048)
			(end -0.67945 -0.305054)
			(stroke
				(width 0.1)
				(type default)
			)
			(layer "F.Fab")
		)
		(fp_line
			(start -0.12065 -0.305054)
			(end -0.12065 -0.2794)
			(stroke
				(width 0.1)
				(type default)
			)
			(layer "F.Fab")
		)
		(fp_line
			(start -0.12065 -0.2794)
			(end 0.12065 -0.2794)
			(stroke
				(width 0.1)
				(type default)
			)
			(layer "F.Fab")
		)
		(fp_line
			(start -0.12065 0.2794)
			(end -0.12065 0.3048)
			(stroke
				(width 0.1)
				(type default)
			)
			(layer "F.Fab")
		)
		(fp_line
			(start -0.12065 0.3048)
			(end -0.67945 0.3048)
			(stroke
				(width 0.1)
				(type default)
			)
			(layer "F.Fab")
		)
		(fp_line
			(start 0.120396 0.2794)
			(end -0.12065 0.2794)
			(stroke
				(width 0.1)
				(type default)
			)
			(layer "F.Fab")
		)
		(fp_line
			(start 0.120396 0.3048)
			(end 0.120396 0.2794)
			(stroke
				(width 0.1)
				(type default)
			)
			(layer "F.Fab")
		)
		(fp_line
			(start 0.12065 -0.3048)
			(end 0.67945 -0.3048)
			(stroke
				(width 0.1)
				(type default)
			)
			(layer "F.Fab")
		)
		(fp_line
			(start 0.12065 -0.2794)
			(end 0.12065 -0.3048)
			(stroke
				(width 0.1)
				(type default)
			)
			(layer "F.Fab")
		)
		(fp_line
			(start 0.67945 -0.3048)
			(end 0.67945 0.3048)
			(stroke
				(width 0.1)
				(type default)
			)
			(layer "F.Fab")
		)
		(fp_line
			(start 0.67945 0.3048)
			(end 0.120396 0.3048)
			(stroke
				(width 0.1)
				(type default)
			)
			(layer "F.Fab")
		)
		(pad "1" smd circle
			(at -0.40005 0)
			(size 0 0)
			(layers "F.Cu" "F.Mask" "F.Paste")
			(net "P3V3_AUX")
		)
		(pad "2" smd circle
			(at 0.40005 0)
			(size 0 0)
			(layers "F.Cu" "F.Mask" "F.Paste")
			(net "FM_P2E_EQA1")
		)
	)
	(footprint ""
		(layer "F.Cu")
		(at 115.82908 -400.414998 90)
		(property "Reference" "C1802"
			(at 0 0 90)
			(layer "F.SilkS")
			(hide yes)
			(effects
				(font
					(size 1.27 1.27)
				)
			)
		)
		(property "Value" ""
			(at 0 0 90)
			(layer "F.Fab")
			(effects
				(font
					(size 1.27 1.27)
				)
			)
		)
		(duplicate_pad_numbers_are_jumpers no)
		(fp_line
			(start 0.7874 -0.4064)
			(end 0.7874 0.4064)
			(stroke
				(width 0.1524)
				(type default)
			)
			(layer "F.SilkS")
		)
		(fp_line
			(start -0.7874 -0.4064)
			(end 0.7874 -0.4064)
			(stroke
				(width 0.1524)
				(type default)
			)
			(layer "F.SilkS")
		)
		(fp_line
			(start 0.7874 0.4064)
			(end -0.7874 0.4064)
			(stroke
				(width 0.1524)
				(type default)
			)
			(layer "F.SilkS")
		)
		(fp_line
			(start -0.7874 0.4064)
			(end -0.7874 -0.4064)
			(stroke
				(width 0.1524)
				(type default)
			)
			(layer "F.SilkS")
		)
		(fp_line
			(start -0.12065 -0.305054)
			(end -0.12065 -0.2794)
			(stroke
				(width 0.1)
				(type default)
			)
			(layer "F.Fab")
		)
		(fp_line
			(start -0.67945 -0.305054)
			(end -0.12065 -0.305054)
			(stroke
				(width 0.1)
				(type default)
			)
			(layer "F.Fab")
		)
		(fp_line
			(start 0.67945 -0.3048)
			(end 0.67945 0.3048)
			(stroke
				(width 0.1)
				(type default)
			)
			(layer "F.Fab")
		)
		(fp_line
			(start 0.12065 -0.3048)
			(end 0.67945 -0.3048)
			(stroke
				(width 0.1)
				(type default)
			)
			(layer "F.Fab")
		)
		(fp_line
			(start 0.12065 -0.2794)
			(end 0.12065 -0.3048)
			(stroke
				(width 0.1)
				(type default)
			)
			(layer "F.Fab")
		)
		(fp_line
			(start -0.12065 -0.2794)
			(end 0.12065 -0.2794)
			(stroke
				(width 0.1)
				(type default)
			)
			(layer "F.Fab")
		)
		(fp_line
			(start 0.120396 0.2794)
			(end -0.12065 0.2794)
			(stroke
				(width 0.1)
				(type default)
			)
			(layer "F.Fab")
		)
		(fp_line
			(start -0.12065 0.2794)
			(end -0.12065 0.3048)
			(stroke
				(width 0.1)
				(type default)
			)
			(layer "F.Fab")
		)
		(fp_line
			(start 0.67945 0.3048)
			(end 0.120396 0.3048)
			(stroke
				(width 0.1)
				(type default)
			)
			(layer "F.Fab")
		)
		(fp_line
			(start 0.120396 0.3048)
			(end 0.120396 0.2794)
			(stroke
				(width 0.1)
				(type default)
			)
			(layer "F.Fab")
		)
		(fp_line
			(start -0.12065 0.3048)
			(end -0.67945 0.3048)
			(stroke
				(width 0.1)
				(type default)
			)
			(layer "F.Fab")
		)
		(fp_line
			(start -0.67945 0.3048)
			(end -0.67945 -0.305054)
			(stroke
				(width 0.1)
				(type default)
			)
			(layer "F.Fab")
		)
		(pad "1" smd circle
			(at -0.40005 0 90)
			(size 0 0)
			(layers "F.Cu" "F.Mask" "F.Paste")
			(net "FM_SMB_1_ALERT_GPU_ISO_N")
		)
		(pad "2" smd circle
			(at 0.40005 0 90)
			(size 0 0)
			(layers "F.Cu" "F.Mask" "F.Paste")
			(net "GND")
		)
	)
	(footprint ""
		(layer "F.Cu")
		(at 246.22506 -52.981606 90)
		(property "Reference" "PC2219"
			(at 0 0 90)
			(layer "F.SilkS")
			(hide yes)
			(effects
				(font
					(size 1.27 1.27)
				)
			)
		)
		(property "Value" ""
			(at 0 0 90)
			(layer "F.Fab")
			(effects
				(font
					(size 1.27 1.27)
				)
			)
		)
		(duplicate_pad_numbers_are_jumpers no)
		(fp_line
			(start 1.524 -0.762)
			(end 1.524 0.762)
			(stroke
				(width 0.1524)
				(type default)
			)
			(layer "F.SilkS")
		)
		(fp_line
			(start -1.524 -0.762)
			(end 1.524 -0.762)
			(stroke
				(width 0.1524)
				(type default)
			)
			(layer "F.SilkS")
		)
		(fp_line
			(start 1.524 0.762)
			(end -1.524 0.762)
			(stroke
				(width 0.1524)
				(type default)
			)
			(layer "F.SilkS")
		)
		(fp_line
			(start -1.524 0.762)
			(end -1.524 -0.762)
			(stroke
				(width 0.1524)
				(type default)
			)
			(layer "F.SilkS")
		)
		(fp_line
			(start 1.1049 -0.724916)
			(end -1.1049 -0.724916)
			(stroke
				(width 0.1)
				(type default)
			)
			(layer "F.Fab")
		)
		(fp_line
			(start -1.1049 -0.724916)
			(end -1.1049 0.724916)
			(stroke
				(width 0.1)
				(type default)
			)
			(layer "F.Fab")
		)
		(fp_line
			(start 1.1049 0.724916)
			(end 1.1049 -0.724916)
			(stroke
				(width 0.1)
				(type default)
			)
			(layer "F.Fab")
		)
		(fp_line
			(start -1.1049 0.724916)
			(end 1.1049 0.724916)
			(stroke
				(width 0.1)
				(type default)
			)
			(layer "F.Fab")
		)
		(pad "1" smd rect
			(at -0.889 0 270)
			(size 1.016 1.27)
			(layers "F.Cu" "F.Mask" "F.Paste")
			(net "P12V_E1S_0")
		)
		(pad "2" smd rect
			(at 0.889 0 270)
			(size 1.016 1.27)
			(layers "F.Cu" "F.Mask" "F.Paste")
			(net "GND")
		)
	)
	(footprint ""
		(layer "F.Cu")
		(at 450.43725 -43.155362)
		(property "Reference" "R3263"
			(at 0 0 0)
			(layer "F.SilkS")
			(hide yes)
			(effects
				(font
					(size 1.27 1.27)
				)
			)
		)
		(property "Value" ""
			(at 0 0 0)
			(layer "F.Fab")
			(effects
				(font
					(size 1.27 1.27)
				)
			)
		)
		(duplicate_pad_numbers_are_jumpers no)
		(fp_line
			(start -0.7874 -0.4064)
			(end 0.7874 -0.4064)
			(stroke
				(width 0.1524)
				(type default)
			)
			(layer "F.SilkS")
		)
		(fp_line
			(start -0.7874 0.4064)
			(end -0.7874 -0.4064)
			(stroke
				(width 0.1524)
				(type default)
			)
			(layer "F.SilkS")
		)
		(fp_line
			(start 0.7874 -0.4064)
			(end 0.7874 0.4064)
			(stroke
				(width 0.1524)
				(type default)
			)
			(layer "F.SilkS")
		)
		(fp_line
			(start 0.7874 0.4064)
			(end -0.7874 0.4064)
			(stroke
				(width 0.1524)
				(type default)
			)
			(layer "F.SilkS")
		)
		(fp_line
			(start -0.67945 -0.305054)
			(end -0.12065 -0.305054)
			(stroke
				(width 0.1)
				(type default)
			)
			(layer "F.Fab")
		)
		(fp_line
			(start -0.67945 0.3048)
			(end -0.67945 -0.305054)
			(stroke
				(width 0.1)
				(type default)
			)
			(layer "F.Fab")
		)
		(fp_line
			(start -0.12065 -0.305054)
			(end -0.12065 -0.2794)
			(stroke
				(width 0.1)
				(type default)
			)
			(layer "F.Fab")
		)
		(fp_line
			(start -0.12065 -0.2794)
			(end 0.12065 -0.2794)
			(stroke
				(width 0.1)
				(type default)
			)
			(layer "F.Fab")
		)
		(fp_line
			(start -0.12065 0.2794)
			(end -0.12065 0.3048)
			(stroke
				(width 0.1)
				(type default)
			)
			(layer "F.Fab")
		)
		(fp_line
			(start -0.12065 0.3048)
			(end -0.67945 0.3048)
			(stroke
				(width 0.1)
				(type default)
			)
			(layer "F.Fab")
		)
		(fp_line
			(start 0.120396 0.2794)
			(end -0.12065 0.2794)
			(stroke
				(width 0.1)
				(type default)
			)
			(layer "F.Fab")
		)
		(fp_line
			(start 0.120396 0.3048)
			(end 0.120396 0.2794)
			(stroke
				(width 0.1)
				(type default)
			)
			(layer "F.Fab")
		)
		(fp_line
			(start 0.12065 -0.3048)
			(end 0.67945 -0.3048)
			(stroke
				(width 0.1)
				(type default)
			)
			(layer "F.Fab")
		)
		(fp_line
			(start 0.12065 -0.2794)
			(end 0.12065 -0.3048)
			(stroke
				(width 0.1)
				(type default)
			)
			(layer "F.Fab")
		)
		(fp_line
			(start 0.67945 -0.3048)
			(end 0.67945 0.3048)
			(stroke
				(width 0.1)
				(type default)
			)
			(layer "F.Fab")
		)
		(fp_line
			(start 0.67945 0.3048)
			(end 0.120396 0.3048)
			(stroke
				(width 0.1)
				(type default)
			)
			(layer "F.Fab")
		)
		(pad "1" smd circle
			(at -0.40005 0)
			(size 0 0)
			(layers "F.Cu" "F.Mask" "F.Paste")
			(net "HP_LVC3_OCP_V3_1_R_EN")
		)
		(pad "2" smd circle
			(at 0.40005 0)
			(size 0 0)
			(layers "F.Cu" "F.Mask" "F.Paste")
			(net "HP_LVC3_OCP_V3_1_EN")
		)
	)
	(footprint ""
		(layer "F.Cu")
		(at 498.58549 -470.89187)
		(property "Reference" "U2_BP"
			(at -1.6764 -1.07823 0)
			(unlocked yes)
			(layer "F.SilkS")
			(effects
				(font
					(size 0.7874 0.5842)
					(thickness 0.1524)
				)
				(justify left)
			)
		)
		(property "Value" ""
			(at 0 0 0)
			(layer "F.Fab")
			(effects
				(font
					(size 1.27 1.27)
				)
			)
		)
		(duplicate_pad_numbers_are_jumpers no)
		(pad "1" smd circle
			(at 0 0)
			(size 0.762 0.762)
			(layers "F.Cu" "F.Mask" "F.Paste")
			(net "Net_8484")
		)
	)
	(footprint ""
		(layer "F.Cu")
		(at 409.65628 -149.037548)
		(property "Reference" "PC181"
			(at 0 0 0)
			(layer "F.SilkS")
			(hide yes)
			(effects
				(font
					(size 1.27 1.27)
				)
			)
		)
		(property "Value" ""
			(at 0 0 0)
			(layer "F.Fab")
			(effects
				(font
					(size 1.27 1.27)
				)
			)
		)
		(duplicate_pad_numbers_are_jumpers no)
		(fp_line
			(start -0.7874 -0.4064)
			(end 0.7874 -0.4064)
			(stroke
				(width 0.1524)
				(type default)
			)
			(layer "F.SilkS")
		)
		(fp_line
			(start -0.7874 0.4064)
			(end -0.7874 -0.4064)
			(stroke
				(width 0.1524)
				(type default)
			)
			(layer "F.SilkS")
		)
		(fp_line
			(start 0.7874 -0.4064)
			(end 0.7874 0.4064)
			(stroke
				(width 0.1524)
				(type default)
			)
			(layer "F.SilkS")
		)
		(fp_line
			(start 0.7874 0.4064)
			(end -0.7874 0.4064)
			(stroke
				(width 0.1524)
				(type default)
			)
			(layer "F.SilkS")
		)
		(fp_line
			(start -0.67945 -0.305054)
			(end -0.12065 -0.305054)
			(stroke
				(width 0.1)
				(type default)
			)
			(layer "F.Fab")
		)
		(fp_line
			(start -0.67945 0.3048)
			(end -0.67945 -0.305054)
			(stroke
				(width 0.1)
				(type default)
			)
			(layer "F.Fab")
		)
		(fp_line
			(start -0.12065 -0.305054)
			(end -0.12065 -0.2794)
			(stroke
				(width 0.1)
				(type default)
			)
			(layer "F.Fab")
		)
		(fp_line
			(start -0.12065 -0.2794)
			(end 0.12065 -0.2794)
			(stroke
				(width 0.1)
				(type default)
			)
			(layer "F.Fab")
		)
		(fp_line
			(start -0.12065 0.2794)
			(end -0.12065 0.3048)
			(stroke
				(width 0.1)
				(type default)
			)
			(layer "F.Fab")
		)
		(fp_line
			(start -0.12065 0.3048)
			(end -0.67945 0.3048)
			(stroke
				(width 0.1)
				(type default)
			)
			(layer "F.Fab")
		)
		(fp_line
			(start 0.120396 0.2794)
			(end -0.12065 0.2794)
			(stroke
				(width 0.1)
				(type default)
			)
			(layer "F.Fab")
		)
		(fp_line
			(start 0.120396 0.3048)
			(end 0.120396 0.2794)
			(stroke
				(width 0.1)
				(type default)
			)
			(layer "F.Fab")
		)
		(fp_line
			(start 0.12065 -0.3048)
			(end 0.67945 -0.3048)
			(stroke
				(width 0.1)
				(type default)
			)
			(layer "F.Fab")
		)
		(fp_line
			(start 0.12065 -0.2794)
			(end 0.12065 -0.3048)
			(stroke
				(width 0.1)
				(type default)
			)
			(layer "F.Fab")
		)
		(fp_line
			(start 0.67945 -0.3048)
			(end 0.67945 0.3048)
			(stroke
				(width 0.1)
				(type default)
			)
			(layer "F.Fab")
		)
		(fp_line
			(start 0.67945 0.3048)
			(end 0.120396 0.3048)
			(stroke
				(width 0.1)
				(type default)
			)
			(layer "F.Fab")
		)
		(pad "1" smd circle
			(at -0.40005 0)
			(size 0 0)
			(layers "F.Cu" "F.Mask" "F.Paste")
			(net "PVCCFA_EHV_CPU0")
		)
		(pad "2" smd circle
			(at 0.40005 0)
			(size 0 0)
			(layers "F.Cu" "F.Mask" "F.Paste")
			(net "GND")
		)
	)
	(footprint ""
		(layer "F.Cu")
		(at 430.600104 -131.599178 180)
		(property "Reference" "R2390"
			(at 0 0 180)
			(layer "F.SilkS")
			(hide yes)
			(effects
				(font
					(size 1.27 1.27)
				)
			)
		)
		(property "Value" ""
			(at 0 0 180)
			(layer "F.Fab")
			(effects
				(font
					(size 1.27 1.27)
				)
			)
		)
		(duplicate_pad_numbers_are_jumpers no)
		(fp_line
			(start 0.7874 0.4064)
			(end -0.7874 0.4064)
			(stroke
				(width 0.1524)
				(type default)
			)
			(layer "F.SilkS")
		)
		(fp_line
			(start 0.7874 -0.4064)
			(end 0.7874 0.4064)
			(stroke
				(width 0.1524)
				(type default)
			)
			(layer "F.SilkS")
		)
		(fp_line
			(start -0.7874 0.4064)
			(end -0.7874 -0.4064)
			(stroke
				(width 0.1524)
				(type default)
			)
			(layer "F.SilkS")
		)
		(fp_line
			(start -0.7874 -0.4064)
			(end 0.7874 -0.4064)
			(stroke
				(width 0.1524)
				(type default)
			)
			(layer "F.SilkS")
		)
		(fp_line
			(start 0.67945 0.3048)
			(end 0.120396 0.3048)
			(stroke
				(width 0.1)
				(type default)
			)
			(layer "F.Fab")
		)
		(fp_line
			(start 0.67945 -0.3048)
			(end 0.67945 0.3048)
			(stroke
				(width 0.1)
				(type default)
			)
			(layer "F.Fab")
		)
		(fp_line
			(start 0.12065 -0.2794)
			(end 0.12065 -0.3048)
			(stroke
				(width 0.1)
				(type default)
			)
			(layer "F.Fab")
		)
		(fp_line
			(start 0.12065 -0.3048)
			(end 0.67945 -0.3048)
			(stroke
				(width 0.1)
				(type default)
			)
			(layer "F.Fab")
		)
		(fp_line
			(start 0.120396 0.3048)
			(end 0.120396 0.2794)
			(stroke
				(width 0.1)
				(type default)
			)
			(layer "F.Fab")
		)
		(fp_line
			(start 0.120396 0.2794)
			(end -0.12065 0.2794)
			(stroke
				(width 0.1)
				(type default)
			)
			(layer "F.Fab")
		)
		(fp_line
			(start -0.12065 0.3048)
			(end -0.67945 0.3048)
			(stroke
				(width 0.1)
				(type default)
			)
			(layer "F.Fab")
		)
		(fp_line
			(start -0.12065 0.2794)
			(end -0.12065 0.3048)
			(stroke
				(width 0.1)
				(type default)
			)
			(layer "F.Fab")
		)
		(fp_line
			(start -0.12065 -0.2794)
			(end 0.12065 -0.2794)
			(stroke
				(width 0.1)
				(type default)
			)
			(layer "F.Fab")
		)
		(fp_line
			(start -0.12065 -0.305054)
			(end -0.12065 -0.2794)
			(stroke
				(width 0.1)
				(type default)
			)
			(layer "F.Fab")
		)
		(fp_line
			(start -0.67945 0.3048)
			(end -0.67945 -0.305054)
			(stroke
				(width 0.1)
				(type default)
			)
			(layer "F.Fab")
		)
		(fp_line
			(start -0.67945 -0.305054)
			(end -0.12065 -0.305054)
			(stroke
				(width 0.1)
				(type default)
			)
			(layer "F.Fab")
		)
		(pad "1" smd circle
			(at -0.40005 0 180)
			(size 0 0)
			(layers "F.Cu" "F.Mask" "F.Paste")
			(net "SMB_VR_3V3AUX_SCL_R2")
		)
		(pad "2" smd circle
			(at 0.40005 0 180)
			(size 0 0)
			(layers "F.Cu" "F.Mask" "F.Paste")
			(net "SMB_CLK_PVCCINFAON_CPU0")
		)
	)
	(footprint ""
		(layer "F.Cu")
		(at 228.764592 -125.297946 180)
		(property "Reference" "R565"
			(at 0 0 180)
			(layer "F.SilkS")
			(hide yes)
			(effects
				(font
					(size 1.27 1.27)
				)
			)
		)
		(property "Value" ""
			(at 0 0 180)
			(layer "F.Fab")
			(effects
				(font
					(size 1.27 1.27)
				)
			)
		)
		(duplicate_pad_numbers_are_jumpers no)
		(fp_line
			(start 0.7874 0.4064)
			(end -0.7874 0.4064)
			(stroke
				(width 0.1524)
				(type default)
			)
			(layer "F.SilkS")
		)
		(fp_line
			(start 0.7874 -0.050546)
			(end 0.7874 0.4064)
			(stroke
				(width 0.1524)
				(type default)
			)
			(layer "F.SilkS")
		)
		(fp_line
			(start -0.429768 -0.4064)
			(end 0.520192 -0.4064)
			(stroke
				(width 0.1524)
				(type default)
			)
			(layer "F.SilkS")
		)
		(fp_line
			(start -0.7874 0.4064)
			(end -0.7874 -0.083566)
			(stroke
				(width 0.1524)
				(type default)
			)
			(layer "F.SilkS")
		)
		(fp_line
			(start 0.67945 0.3048)
			(end 0.120396 0.3048)
			(stroke
				(width 0.1)
				(type default)
			)
			(layer "F.Fab")
		)
		(fp_line
			(start 0.67945 -0.3048)
			(end 0.67945 0.3048)
			(stroke
				(width 0.1)
				(type default)
			)
			(layer "F.Fab")
		)
		(fp_line
			(start 0.12065 -0.2794)
			(end 0.12065 -0.3048)
			(stroke
				(width 0.1)
				(type default)
			)
			(layer "F.Fab")
		)
		(fp_line
			(start 0.12065 -0.3048)
			(end 0.67945 -0.3048)
			(stroke
				(width 0.1)
				(type default)
			)
			(layer "F.Fab")
		)
		(fp_line
			(start 0.120396 0.3048)
			(end 0.120396 0.2794)
			(stroke
				(width 0.1)
				(type default)
			)
			(layer "F.Fab")
		)
		(fp_line
			(start 0.120396 0.2794)
			(end -0.12065 0.2794)
			(stroke
				(width 0.1)
				(type default)
			)
			(layer "F.Fab")
		)
		(fp_line
			(start -0.12065 0.3048)
			(end -0.67945 0.3048)
			(stroke
				(width 0.1)
				(type default)
			)
			(layer "F.Fab")
		)
		(fp_line
			(start -0.12065 0.2794)
			(end -0.12065 0.3048)
			(stroke
				(width 0.1)
				(type default)
			)
			(layer "F.Fab")
		)
		(fp_line
			(start -0.12065 -0.2794)
			(end 0.12065 -0.2794)
			(stroke
				(width 0.1)
				(type default)
			)
			(layer "F.Fab")
		)
		(fp_line
			(start -0.12065 -0.305054)
			(end -0.12065 -0.2794)
			(stroke
				(width 0.1)
				(type default)
			)
			(layer "F.Fab")
		)
		(fp_line
			(start -0.67945 0.3048)
			(end -0.67945 -0.305054)
			(stroke
				(width 0.1)
				(type default)
			)
			(layer "F.Fab")
		)
		(fp_line
			(start -0.67945 -0.305054)
			(end -0.12065 -0.305054)
			(stroke
				(width 0.1)
				(type default)
			)
			(layer "F.Fab")
		)
		(pad "1" smd circle
			(at -0.40005 0 180)
			(size 0 0)
			(layers "F.Cu" "F.Mask" "F.Paste")
			(net "CLK_100M_OCP_SFF_1_R_DP")
		)
		(pad "2" smd circle
			(at 0.40005 0 180)
			(size 0 0)
			(layers "F.Cu" "F.Mask" "F.Paste")
			(net "CLK_100M_OCP_SFF_1_DP")
		)
	)
	(footprint ""
		(layer "F.Cu")
		(at 428.179992 -401.655534)
		(property "Reference" "Q106"
			(at -1.071372 -3.402584 0)
			(unlocked yes)
			(layer "F.SilkS")
			(effects
				(font
					(size 0.7874 0.5842)
					(thickness 0.1524)
				)
				(justify left)
			)
		)
		(property "Value" ""
			(at 0 0 0)
			(layer "F.Fab")
			(effects
				(font
					(size 1.27 1.27)
				)
			)
		)
		(duplicate_pad_numbers_are_jumpers no)
		(fp_line
			(start -1.332738 -1.100074)
			(end -0.4826 -1.100074)
			(stroke
				(width 0.1524)
				(type default)
			)
			(layer "F.SilkS")
		)
		(fp_line
			(start -1.332738 1.100074)
			(end -1.332738 -1.100074)
			(stroke
				(width 0.1524)
				(type default)
			)
			(layer "F.SilkS")
		)
		(fp_line
			(start -0.4826 -1.100074)
			(end 0 -0.541274)
			(stroke
				(width 0.1524)
				(type default)
			)
			(layer "F.SilkS")
		)
		(fp_line
			(start 0 -0.541274)
			(end 0.4826 -1.100074)
			(stroke
				(width 0.1524)
				(type default)
			)
			(layer "F.SilkS")
		)
		(fp_line
			(start 0.4826 -1.100074)
			(end 1.332738 -1.100074)
			(stroke
				(width 0.1524)
				(type default)
			)
			(layer "F.SilkS")
		)
		(fp_line
			(start 1.332738 -1.100074)
			(end 1.332738 1.100074)
			(stroke
				(width 0.1524)
				(type default)
			)
			(layer "F.SilkS")
		)
		(fp_line
			(start 1.332738 1.100074)
			(end -1.332738 1.100074)
			(stroke
				(width 0.1524)
				(type default)
			)
			(layer "F.SilkS")
		)
		(fp_poly
			(pts
				(xy -0.672592 -2.035302) (xy -1.02362 -1.333246) (xy -1.374648 -2.035302)
			)
			(stroke
				(width 0)
				(type default)
			)
			(fill yes)
			(layer "F.SilkS")
		)
		(fp_line
			(start -0.674878 -1.100074)
			(end 0.674878 -1.100074)
			(stroke
				(width 0.1)
				(type default)
			)
			(layer "F.Fab")
		)
		(fp_line
			(start -0.674878 1.100074)
			(end -0.674878 -1.100074)
			(stroke
				(width 0.1)
				(type default)
			)
			(layer "F.Fab")
		)
		(fp_line
			(start 0.674878 -1.100074)
			(end 0.674878 1.100074)
			(stroke
				(width 0.1)
				(type default)
			)
			(layer "F.Fab")
		)
		(fp_line
			(start 0.674878 1.100074)
			(end -0.674878 1.100074)
			(stroke
				(width 0.1)
				(type default)
			)
			(layer "F.Fab")
		)
		(fp_poly
			(pts
				(xy -2.2352 -0.298958) (xy -2.2352 -1.001014) (xy -1.533144 -0.649986)
			)
			(stroke
				(width 0)
				(type default)
			)
			(fill yes)
			(layer "F.Fab")
		)
		(pad "1" smd rect
			(at -0.94996 -0.649986 90)
			(size 0.4318 0.508)
			(layers "F.Cu" "F.Mask" "F.Paste")
			(net "GND")
		)
		(pad "2" smd rect
			(at -0.94996 0 90)
			(size 0.4318 0.508)
			(layers "F.Cu" "F.Mask" "F.Paste")
			(net "GPU_WP_HW_CTRL_N")
		)
		(pad "3" smd rect
			(at -0.94996 0.649986 90)
			(size 0.4318 0.508)
			(layers "F.Cu" "F.Mask" "F.Paste")
			(net "Net_27")
		)
		(pad "4" smd rect
			(at 0.94996 0.649986 90)
			(size 0.4318 0.508)
			(layers "F.Cu" "F.Mask" "F.Paste")
			(net "Net_25")
		)
		(pad "5" smd rect
			(at 0.94996 0 90)
			(size 0.4318 0.508)
			(layers "F.Cu" "F.Mask" "F.Paste")
			(net "Net_26")
		)
		(pad "6" smd rect
			(at 0.94996 -0.649986 90)
			(size 0.4318 0.508)
			(layers "F.Cu" "F.Mask" "F.Paste")
			(net "GPU_WP_HW_CTRL_ISO")
		)
	)
	(footprint ""
		(layer "F.Cu")
		(at 412.56585 -408.517344 -90)
		(property "Reference" "C896"
			(at 0 0 270)
			(layer "F.SilkS")
			(hide yes)
			(effects
				(font
					(size 1.27 1.27)
				)
			)
		)
		(property "Value" ""
			(at 0 0 270)
			(layer "F.Fab")
			(effects
				(font
					(size 1.27 1.27)
				)
			)
		)
		(duplicate_pad_numbers_are_jumpers no)
		(fp_line
			(start -0.299974 0.150114)
			(end -0.299974 -0.150114)
			(stroke
				(width 0.1)
				(type default)
			)
			(layer "F.Fab")
		)
		(fp_line
			(start 0.299974 0.150114)
			(end -0.299974 0.150114)
			(stroke
				(width 0.1)
				(type default)
			)
			(layer "F.Fab")
		)
		(fp_line
			(start -0.299974 -0.150114)
			(end 0.299974 -0.150114)
			(stroke
				(width 0.1)
				(type default)
			)
			(layer "F.Fab")
		)
		(fp_line
			(start 0.299974 -0.150114)
			(end 0.299974 0.150114)
			(stroke
				(width 0.1)
				(type default)
			)
			(layer "F.Fab")
		)
		(pad "1" smd rect
			(at -0.2667 0 270)
			(size 0.3048 0.381)
			(layers "F.Cu" "F.Mask" "F.Paste")
			(net "P5E_CPU0_PE3_TX_C_DN<2>")
		)
		(pad "2" smd rect
			(at 0.2667 0 270)
			(size 0.3048 0.381)
			(layers "F.Cu" "F.Mask" "F.Paste")
			(net "P5E_CPU0_PE3_TX_DN<2>")
		)
	)
	(footprint ""
		(layer "F.Cu")
		(at 135.445754 -402.371052 -90)
		(property "Reference" "C753"
			(at 0 0 270)
			(layer "F.SilkS")
			(hide yes)
			(effects
				(font
					(size 1.27 1.27)
				)
			)
		)
		(property "Value" ""
			(at 0 0 270)
			(layer "F.Fab")
			(effects
				(font
					(size 1.27 1.27)
				)
			)
		)
		(duplicate_pad_numbers_are_jumpers no)
		(fp_line
			(start -0.299974 0.150114)
			(end -0.299974 -0.150114)
			(stroke
				(width 0.1)
				(type default)
			)
			(layer "F.Fab")
		)
		(fp_line
			(start 0.299974 0.150114)
			(end -0.299974 0.150114)
			(stroke
				(width 0.1)
				(type default)
			)
			(layer "F.Fab")
		)
		(fp_line
			(start -0.299974 -0.150114)
			(end 0.299974 -0.150114)
			(stroke
				(width 0.1)
				(type default)
			)
			(layer "F.Fab")
		)
		(fp_line
			(start 0.299974 -0.150114)
			(end 0.299974 0.150114)
			(stroke
				(width 0.1)
				(type default)
			)
			(layer "F.Fab")
		)
		(pad "1" smd rect
			(at -0.2667 0 270)
			(size 0.3048 0.381)
			(layers "F.Cu" "F.Mask" "F.Paste")
			(net "P5E_CPU1_PE2_TX_C_DP<10>")
		)
		(pad "2" smd rect
			(at 0.2667 0 270)
			(size 0.3048 0.381)
			(layers "F.Cu" "F.Mask" "F.Paste")
			(net "P5E_CPU1_PE2_TX_DP<10>")
		)
	)
	(footprint ""
		(layer "F.Cu")
		(at 155.171394 -408.517344 -90)
		(property "Reference" "C1538"
			(at 0 0 270)
			(layer "F.SilkS")
			(hide yes)
			(effects
				(font
					(size 1.27 1.27)
				)
			)
		)
		(property "Value" ""
			(at 0 0 270)
			(layer "F.Fab")
			(effects
				(font
					(size 1.27 1.27)
				)
			)
		)
		(duplicate_pad_numbers_are_jumpers no)
		(fp_line
			(start -0.299974 0.150114)
			(end -0.299974 -0.150114)
			(stroke
				(width 0.1)
				(type default)
			)
			(layer "F.Fab")
		)
		(fp_line
			(start 0.299974 0.150114)
			(end -0.299974 0.150114)
			(stroke
				(width 0.1)
				(type default)
			)
			(layer "F.Fab")
		)
		(fp_line
			(start -0.299974 -0.150114)
			(end 0.299974 -0.150114)
			(stroke
				(width 0.1)
				(type default)
			)
			(layer "F.Fab")
		)
		(fp_line
			(start 0.299974 -0.150114)
			(end 0.299974 0.150114)
			(stroke
				(width 0.1)
				(type default)
			)
			(layer "F.Fab")
		)
		(pad "1" smd rect
			(at -0.2667 0 270)
			(size 0.3048 0.381)
			(layers "F.Cu" "F.Mask" "F.Paste")
			(net "P5E_CPU1_PE3_TX_C_DN<4>")
		)
		(pad "2" smd rect
			(at 0.2667 0 270)
			(size 0.3048 0.381)
			(layers "F.Cu" "F.Mask" "F.Paste")
			(net "P5E_CPU1_PE3_TX_DN<4>")
		)
	)
	(footprint ""
		(layer "F.Cu")
		(at 174.87138 -99.863148 -90)
		(property "Reference" "R124"
			(at 0 0 270)
			(layer "F.SilkS")
			(hide yes)
			(effects
				(font
					(size 1.27 1.27)
				)
			)
		)
		(property "Value" ""
			(at 0 0 270)
			(layer "F.Fab")
			(effects
				(font
					(size 1.27 1.27)
				)
			)
		)
		(duplicate_pad_numbers_are_jumpers no)
		(fp_line
			(start -0.7874 0.4064)
			(end -0.7874 -0.4064)
			(stroke
				(width 0.1524)
				(type default)
			)
			(layer "F.SilkS")
		)
		(fp_line
			(start 0.7874 0.4064)
			(end -0.7874 0.4064)
			(stroke
				(width 0.1524)
				(type default)
			)
			(layer "F.SilkS")
		)
		(fp_line
			(start -0.7874 -0.4064)
			(end 0.7874 -0.4064)
			(stroke
				(width 0.1524)
				(type default)
			)
			(layer "F.SilkS")
		)
		(fp_line
			(start 0.7874 -0.4064)
			(end 0.7874 0.4064)
			(stroke
				(width 0.1524)
				(type default)
			)
			(layer "F.SilkS")
		)
		(fp_line
			(start -0.67945 0.3048)
			(end -0.67945 -0.305054)
			(stroke
				(width 0.1)
				(type default)
			)
			(layer "F.Fab")
		)
		(fp_line
			(start -0.12065 0.3048)
			(end -0.67945 0.3048)
			(stroke
				(width 0.1)
				(type default)
			)
			(layer "F.Fab")
		)
		(fp_line
			(start 0.120396 0.3048)
			(end 0.120396 0.2794)
			(stroke
				(width 0.1)
				(type default)
			)
			(layer "F.Fab")
		)
		(fp_line
			(start 0.67945 0.3048)
			(end 0.120396 0.3048)
			(stroke
				(width 0.1)
				(type default)
			)
			(layer "F.Fab")
		)
		(fp_line
			(start -0.12065 0.2794)
			(end -0.12065 0.3048)
			(stroke
				(width 0.1)
				(type default)
			)
			(layer "F.Fab")
		)
		(fp_line
			(start 0.120396 0.2794)
			(end -0.12065 0.2794)
			(stroke
				(width 0.1)
				(type default)
			)
			(layer "F.Fab")
		)
		(fp_line
			(start -0.12065 -0.2794)
			(end 0.12065 -0.2794)
			(stroke
				(width 0.1)
				(type default)
			)
			(layer "F.Fab")
		)
		(fp_line
			(start 0.12065 -0.2794)
			(end 0.12065 -0.3048)
			(stroke
				(width 0.1)
				(type default)
			)
			(layer "F.Fab")
		)
		(fp_line
			(start 0.12065 -0.3048)
			(end 0.67945 -0.3048)
			(stroke
				(width 0.1)
				(type default)
			)
			(layer "F.Fab")
		)
		(fp_line
			(start 0.67945 -0.3048)
			(end 0.67945 0.3048)
			(stroke
				(width 0.1)
				(type default)
			)
			(layer "F.Fab")
		)
		(fp_line
			(start -0.67945 -0.305054)
			(end -0.12065 -0.305054)
			(stroke
				(width 0.1)
				(type default)
			)
			(layer "F.Fab")
		)
		(fp_line
			(start -0.12065 -0.305054)
			(end -0.12065 -0.2794)
			(stroke
				(width 0.1)
				(type default)
			)
			(layer "F.Fab")
		)
		(pad "1" smd circle
			(at -0.40005 0 270)
			(size 0 0)
			(layers "F.Cu" "F.Mask" "F.Paste")
			(net "PWRGD_DRAMPWRGD_CPU1_CD_R_LVC1")
		)
		(pad "2" smd circle
			(at 0.40005 0 270)
			(size 0 0)
			(layers "F.Cu" "F.Mask" "F.Paste")
			(net "PWRGD_DRAMPWRGD_CPU1_CD_LVC1_R2")
		)
	)
	(footprint ""
		(layer "F.Cu")
		(at 376.468132 -80.354424)
		(property "Reference" "PC1238"
			(at 0 0 0)
			(layer "F.SilkS")
			(hide yes)
			(effects
				(font
					(size 1.27 1.27)
				)
			)
		)
		(property "Value" ""
			(at 0 0 0)
			(layer "F.Fab")
			(effects
				(font
					(size 1.27 1.27)
				)
			)
		)
		(duplicate_pad_numbers_are_jumpers no)
		(fp_line
			(start -1.524 -0.762)
			(end 1.524 -0.762)
			(stroke
				(width 0.1524)
				(type default)
			)
			(layer "F.SilkS")
		)
		(fp_line
			(start -1.524 0.762)
			(end -1.524 -0.762)
			(stroke
				(width 0.1524)
				(type default)
			)
			(layer "F.SilkS")
		)
		(fp_line
			(start 1.524 -0.762)
			(end 1.524 0.762)
			(stroke
				(width 0.1524)
				(type default)
			)
			(layer "F.SilkS")
		)
		(fp_line
			(start 1.524 0.762)
			(end -1.524 0.762)
			(stroke
				(width 0.1524)
				(type default)
			)
			(layer "F.SilkS")
		)
		(fp_line
			(start -1.1049 -0.724916)
			(end -1.1049 0.724916)
			(stroke
				(width 0.1)
				(type default)
			)
			(layer "F.Fab")
		)
		(fp_line
			(start -1.1049 0.724916)
			(end 1.1049 0.724916)
			(stroke
				(width 0.1)
				(type default)
			)
			(layer "F.Fab")
		)
		(fp_line
			(start 1.1049 -0.724916)
			(end -1.1049 -0.724916)
			(stroke
				(width 0.1)
				(type default)
			)
			(layer "F.Fab")
		)
		(fp_line
			(start 1.1049 0.724916)
			(end 1.1049 -0.724916)
			(stroke
				(width 0.1)
				(type default)
			)
			(layer "F.Fab")
		)
		(pad "1" smd rect
			(at -0.889 0 180)
			(size 1.016 1.27)
			(layers "F.Cu" "F.Mask" "F.Paste")
			(net "P1V8_PCH_AUX")
		)
		(pad "2" smd rect
			(at 0.889 0 180)
			(size 1.016 1.27)
			(layers "F.Cu" "F.Mask" "F.Paste")
			(net "GND")
		)
	)
	(footprint ""
		(layer "F.Cu")
		(at 159.82188 -59.527948 180)
		(property "Reference" "C1305"
			(at 0 0 180)
			(layer "F.SilkS")
			(hide yes)
			(effects
				(font
					(size 1.27 1.27)
				)
			)
		)
		(property "Value" ""
			(at 0 0 180)
			(layer "F.Fab")
			(effects
				(font
					(size 1.27 1.27)
				)
			)
		)
		(duplicate_pad_numbers_are_jumpers no)
		(fp_line
			(start 0.7874 0.4064)
			(end -0.7874 0.4064)
			(stroke
				(width 0.1524)
				(type default)
			)
			(layer "F.SilkS")
		)
		(fp_line
			(start 0.7874 -0.4064)
			(end 0.7874 0.4064)
			(stroke
				(width 0.1524)
				(type default)
			)
			(layer "F.SilkS")
		)
		(fp_line
			(start -0.7874 0.4064)
			(end -0.7874 -0.4064)
			(stroke
				(width 0.1524)
				(type default)
			)
			(layer "F.SilkS")
		)
		(fp_line
			(start -0.7874 -0.4064)
			(end 0.7874 -0.4064)
			(stroke
				(width 0.1524)
				(type default)
			)
			(layer "F.SilkS")
		)
		(fp_line
			(start 0.67945 0.3048)
			(end 0.120396 0.3048)
			(stroke
				(width 0.1)
				(type default)
			)
			(layer "F.Fab")
		)
		(fp_line
			(start 0.67945 -0.3048)
			(end 0.67945 0.3048)
			(stroke
				(width 0.1)
				(type default)
			)
			(layer "F.Fab")
		)
		(fp_line
			(start 0.12065 -0.2794)
			(end 0.12065 -0.3048)
			(stroke
				(width 0.1)
				(type default)
			)
			(layer "F.Fab")
		)
		(fp_line
			(start 0.12065 -0.3048)
			(end 0.67945 -0.3048)
			(stroke
				(width 0.1)
				(type default)
			)
			(layer "F.Fab")
		)
		(fp_line
			(start 0.120396 0.3048)
			(end 0.120396 0.2794)
			(stroke
				(width 0.1)
				(type default)
			)
			(layer "F.Fab")
		)
		(fp_line
			(start 0.120396 0.2794)
			(end -0.12065 0.2794)
			(stroke
				(width 0.1)
				(type default)
			)
			(layer "F.Fab")
		)
		(fp_line
			(start -0.12065 0.3048)
			(end -0.67945 0.3048)
			(stroke
				(width 0.1)
				(type default)
			)
			(layer "F.Fab")
		)
		(fp_line
			(start -0.12065 0.2794)
			(end -0.12065 0.3048)
			(stroke
				(width 0.1)
				(type default)
			)
			(layer "F.Fab")
		)
		(fp_line
			(start -0.12065 -0.2794)
			(end 0.12065 -0.2794)
			(stroke
				(width 0.1)
				(type default)
			)
			(layer "F.Fab")
		)
		(fp_line
			(start -0.12065 -0.305054)
			(end -0.12065 -0.2794)
			(stroke
				(width 0.1)
				(type default)
			)
			(layer "F.Fab")
		)
		(fp_line
			(start -0.67945 0.3048)
			(end -0.67945 -0.305054)
			(stroke
				(width 0.1)
				(type default)
			)
			(layer "F.Fab")
		)
		(fp_line
			(start -0.67945 -0.305054)
			(end -0.12065 -0.305054)
			(stroke
				(width 0.1)
				(type default)
			)
			(layer "F.Fab")
		)
		(pad "1" smd circle
			(at -0.40005 0 180)
			(size 0 0)
			(layers "F.Cu" "F.Mask" "F.Paste")
			(net "P3V3_AUX")
		)
		(pad "2" smd circle
			(at 0.40005 0 180)
			(size 0 0)
			(layers "F.Cu" "F.Mask" "F.Paste")
			(net "GND")
		)
	)
	(footprint ""
		(layer "F.Cu")
		(at 432.061112 -397.270478 180)
		(property "Reference" "R3435"
			(at 0 0 180)
			(layer "F.SilkS")
			(hide yes)
			(effects
				(font
					(size 1.27 1.27)
				)
			)
		)
		(property "Value" ""
			(at 0 0 180)
			(layer "F.Fab")
			(effects
				(font
					(size 1.27 1.27)
				)
			)
		)
		(duplicate_pad_numbers_are_jumpers no)
		(fp_line
			(start 0.7874 0.4064)
			(end -0.7874 0.4064)
			(stroke
				(width 0.1524)
				(type default)
			)
			(layer "F.SilkS")
		)
		(fp_line
			(start 0.7874 -0.4064)
			(end 0.7874 0.4064)
			(stroke
				(width 0.1524)
				(type default)
			)
			(layer "F.SilkS")
		)
		(fp_line
			(start -0.7874 0.4064)
			(end -0.7874 -0.4064)
			(stroke
				(width 0.1524)
				(type default)
			)
			(layer "F.SilkS")
		)
		(fp_line
			(start -0.7874 -0.4064)
			(end 0.7874 -0.4064)
			(stroke
				(width 0.1524)
				(type default)
			)
			(layer "F.SilkS")
		)
		(fp_line
			(start 0.67945 0.3048)
			(end 0.120396 0.3048)
			(stroke
				(width 0.1)
				(type default)
			)
			(layer "F.Fab")
		)
		(fp_line
			(start 0.67945 -0.3048)
			(end 0.67945 0.3048)
			(stroke
				(width 0.1)
				(type default)
			)
			(layer "F.Fab")
		)
		(fp_line
			(start 0.12065 -0.2794)
			(end 0.12065 -0.3048)
			(stroke
				(width 0.1)
				(type default)
			)
			(layer "F.Fab")
		)
		(fp_line
			(start 0.12065 -0.3048)
			(end 0.67945 -0.3048)
			(stroke
				(width 0.1)
				(type default)
			)
			(layer "F.Fab")
		)
		(fp_line
			(start 0.120396 0.3048)
			(end 0.120396 0.2794)
			(stroke
				(width 0.1)
				(type default)
			)
			(layer "F.Fab")
		)
		(fp_line
			(start 0.120396 0.2794)
			(end -0.12065 0.2794)
			(stroke
				(width 0.1)
				(type default)
			)
			(layer "F.Fab")
		)
		(fp_line
			(start -0.12065 0.3048)
			(end -0.67945 0.3048)
			(stroke
				(width 0.1)
				(type default)
			)
			(layer "F.Fab")
		)
		(fp_line
			(start -0.12065 0.2794)
			(end -0.12065 0.3048)
			(stroke
				(width 0.1)
				(type default)
			)
			(layer "F.Fab")
		)
		(fp_line
			(start -0.12065 -0.2794)
			(end 0.12065 -0.2794)
			(stroke
				(width 0.1)
				(type default)
			)
			(layer "F.Fab")
		)
		(fp_line
			(start -0.12065 -0.305054)
			(end -0.12065 -0.2794)
			(stroke
				(width 0.1)
				(type default)
			)
			(layer "F.Fab")
		)
		(fp_line
			(start -0.67945 0.3048)
			(end -0.67945 -0.305054)
			(stroke
				(width 0.1)
				(type default)
			)
			(layer "F.Fab")
		)
		(fp_line
			(start -0.67945 -0.305054)
			(end -0.12065 -0.305054)
			(stroke
				(width 0.1)
				(type default)
			)
			(layer "F.Fab")
		)
		(pad "1" smd circle
			(at -0.40005 0 180)
			(size 0 0)
			(layers "F.Cu" "F.Mask" "F.Paste")
			(net "P3V3_AUX")
		)
		(pad "2" smd circle
			(at 0.40005 0 180)
			(size 0 0)
			(layers "F.Cu" "F.Mask" "F.Paste")
			(net "GPU_FPGA_OVERT")
		)
	)
	(footprint ""
		(layer "F.Cu")
		(at 306.09159 -427.168818 180)
		(property "Reference" "R4265"
			(at 0 0 180)
			(layer "F.SilkS")
			(hide yes)
			(effects
				(font
					(size 1.27 1.27)
				)
			)
		)
		(property "Value" ""
			(at 0 0 180)
			(layer "F.Fab")
			(effects
				(font
					(size 1.27 1.27)
				)
			)
		)
		(duplicate_pad_numbers_are_jumpers no)
		(fp_line
			(start 0.7874 0.4064)
			(end -0.7874 0.4064)
			(stroke
				(width 0.1524)
				(type default)
			)
			(layer "F.SilkS")
		)
		(fp_line
			(start 0.7874 -0.4064)
			(end 0.7874 0.4064)
			(stroke
				(width 0.1524)
				(type default)
			)
			(layer "F.SilkS")
		)
		(fp_line
			(start -0.7874 0.4064)
			(end -0.7874 -0.4064)
			(stroke
				(width 0.1524)
				(type default)
			)
			(layer "F.SilkS")
		)
		(fp_line
			(start -0.7874 -0.4064)
			(end 0.7874 -0.4064)
			(stroke
				(width 0.1524)
				(type default)
			)
			(layer "F.SilkS")
		)
		(fp_line
			(start 0.67945 0.3048)
			(end 0.120396 0.3048)
			(stroke
				(width 0.1)
				(type default)
			)
			(layer "F.Fab")
		)
		(fp_line
			(start 0.67945 -0.3048)
			(end 0.67945 0.3048)
			(stroke
				(width 0.1)
				(type default)
			)
			(layer "F.Fab")
		)
		(fp_line
			(start 0.12065 -0.2794)
			(end 0.12065 -0.3048)
			(stroke
				(width 0.1)
				(type default)
			)
			(layer "F.Fab")
		)
		(fp_line
			(start 0.12065 -0.3048)
			(end 0.67945 -0.3048)
			(stroke
				(width 0.1)
				(type default)
			)
			(layer "F.Fab")
		)
		(fp_line
			(start 0.120396 0.3048)
			(end 0.120396 0.2794)
			(stroke
				(width 0.1)
				(type default)
			)
			(layer "F.Fab")
		)
		(fp_line
			(start 0.120396 0.2794)
			(end -0.12065 0.2794)
			(stroke
				(width 0.1)
				(type default)
			)
			(layer "F.Fab")
		)
		(fp_line
			(start -0.12065 0.3048)
			(end -0.67945 0.3048)
			(stroke
				(width 0.1)
				(type default)
			)
			(layer "F.Fab")
		)
		(fp_line
			(start -0.12065 0.2794)
			(end -0.12065 0.3048)
			(stroke
				(width 0.1)
				(type default)
			)
			(layer "F.Fab")
		)
		(fp_line
			(start -0.12065 -0.2794)
			(end 0.12065 -0.2794)
			(stroke
				(width 0.1)
				(type default)
			)
			(layer "F.Fab")
		)
		(fp_line
			(start -0.12065 -0.305054)
			(end -0.12065 -0.2794)
			(stroke
				(width 0.1)
				(type default)
			)
			(layer "F.Fab")
		)
		(fp_line
			(start -0.67945 0.3048)
			(end -0.67945 -0.305054)
			(stroke
				(width 0.1)
				(type default)
			)
			(layer "F.Fab")
		)
		(fp_line
			(start -0.67945 -0.305054)
			(end -0.12065 -0.305054)
			(stroke
				(width 0.1)
				(type default)
			)
			(layer "F.Fab")
		)
		(pad "1" smd circle
			(at -0.40005 0 180)
			(size 0 0)
			(layers "F.Cu" "F.Mask" "F.Paste")
			(net "PWRGD_P3V3_AUX_PDB_BUF_R")
		)
		(pad "2" smd circle
			(at 0.40005 0 180)
			(size 0 0)
			(layers "F.Cu" "F.Mask" "F.Paste")
			(net "GND")
		)
	)
	(footprint ""
		(layer "F.Cu")
		(at 497.43868 -468.007446)
		(property "Reference" "DM9"
			(at -0.3937 -0.588518 0)
			(unlocked yes)
			(layer "F.SilkS")
			(effects
				(font
					(size 0.254 0.127)
					(thickness 0.000001)
				)
				(justify left)
			)
		)
		(property "Value" ""
			(at 0 0 0)
			(layer "F.Fab")
			(effects
				(font
					(size 1.27 1.27)
				)
			)
		)
		(duplicate_pad_numbers_are_jumpers no)
		(pad "1" smd circle
			(at 0 0)
			(size 0.762 0.762)
			(layers "F.Cu" "F.Mask" "F.Paste")
			(net "Net_8587")
		)
	)
	(footprint ""
		(layer "F.Cu")
		(at 437.515 -94.071948 90)
		(property "Reference" "C2024"
			(at 0 0 90)
			(layer "F.SilkS")
			(hide yes)
			(effects
				(font
					(size 1.27 1.27)
				)
			)
		)
		(property "Value" ""
			(at 0 0 90)
			(layer "F.Fab")
			(effects
				(font
					(size 1.27 1.27)
				)
			)
		)
		(duplicate_pad_numbers_are_jumpers no)
		(fp_line
			(start 0.7874 -0.4064)
			(end 0.7874 0.4064)
			(stroke
				(width 0.1524)
				(type default)
			)
			(layer "F.SilkS")
		)
		(fp_line
			(start -0.7874 -0.4064)
			(end 0.7874 -0.4064)
			(stroke
				(width 0.1524)
				(type default)
			)
			(layer "F.SilkS")
		)
		(fp_line
			(start 0.7874 0.4064)
			(end -0.7874 0.4064)
			(stroke
				(width 0.1524)
				(type default)
			)
			(layer "F.SilkS")
		)
		(fp_line
			(start -0.7874 0.4064)
			(end -0.7874 -0.4064)
			(stroke
				(width 0.1524)
				(type default)
			)
			(layer "F.SilkS")
		)
		(fp_line
			(start -0.12065 -0.305054)
			(end -0.12065 -0.2794)
			(stroke
				(width 0.1)
				(type default)
			)
			(layer "F.Fab")
		)
		(fp_line
			(start -0.67945 -0.305054)
			(end -0.12065 -0.305054)
			(stroke
				(width 0.1)
				(type default)
			)
			(layer "F.Fab")
		)
		(fp_line
			(start 0.67945 -0.3048)
			(end 0.67945 0.3048)
			(stroke
				(width 0.1)
				(type default)
			)
			(layer "F.Fab")
		)
		(fp_line
			(start 0.12065 -0.3048)
			(end 0.67945 -0.3048)
			(stroke
				(width 0.1)
				(type default)
			)
			(layer "F.Fab")
		)
		(fp_line
			(start 0.12065 -0.2794)
			(end 0.12065 -0.3048)
			(stroke
				(width 0.1)
				(type default)
			)
			(layer "F.Fab")
		)
		(fp_line
			(start -0.12065 -0.2794)
			(end 0.12065 -0.2794)
			(stroke
				(width 0.1)
				(type default)
			)
			(layer "F.Fab")
		)
		(fp_line
			(start 0.120396 0.2794)
			(end -0.12065 0.2794)
			(stroke
				(width 0.1)
				(type default)
			)
			(layer "F.Fab")
		)
		(fp_line
			(start -0.12065 0.2794)
			(end -0.12065 0.3048)
			(stroke
				(width 0.1)
				(type default)
			)
			(layer "F.Fab")
		)
		(fp_line
			(start 0.67945 0.3048)
			(end 0.120396 0.3048)
			(stroke
				(width 0.1)
				(type default)
			)
			(layer "F.Fab")
		)
		(fp_line
			(start 0.120396 0.3048)
			(end 0.120396 0.2794)
			(stroke
				(width 0.1)
				(type default)
			)
			(layer "F.Fab")
		)
		(fp_line
			(start -0.12065 0.3048)
			(end -0.67945 0.3048)
			(stroke
				(width 0.1)
				(type default)
			)
			(layer "F.Fab")
		)
		(fp_line
			(start -0.67945 0.3048)
			(end -0.67945 -0.305054)
			(stroke
				(width 0.1)
				(type default)
			)
			(layer "F.Fab")
		)
		(pad "1" smd circle
			(at -0.40005 0 90)
			(size 0 0)
			(layers "F.Cu" "F.Mask" "F.Paste")
			(net "P3V3_OCP_SFF_R")
		)
		(pad "2" smd circle
			(at 0.40005 0 90)
			(size 0 0)
			(layers "F.Cu" "F.Mask" "F.Paste")
			(net "GND")
		)
	)
	(footprint ""
		(layer "F.Cu")
		(at 166.992554 -402.371052 -90)
		(property "Reference" "C772"
			(at 0 0 270)
			(layer "F.SilkS")
			(hide yes)
			(effects
				(font
					(size 1.27 1.27)
				)
			)
		)
		(property "Value" ""
			(at 0 0 270)
			(layer "F.Fab")
			(effects
				(font
					(size 1.27 1.27)
				)
			)
		)
		(duplicate_pad_numbers_are_jumpers no)
		(fp_line
			(start -0.299974 0.150114)
			(end -0.299974 -0.150114)
			(stroke
				(width 0.1)
				(type default)
			)
			(layer "F.Fab")
		)
		(fp_line
			(start 0.299974 0.150114)
			(end -0.299974 0.150114)
			(stroke
				(width 0.1)
				(type default)
			)
			(layer "F.Fab")
		)
		(fp_line
			(start -0.299974 -0.150114)
			(end 0.299974 -0.150114)
			(stroke
				(width 0.1)
				(type default)
			)
			(layer "F.Fab")
		)
		(fp_line
			(start 0.299974 -0.150114)
			(end 0.299974 0.150114)
			(stroke
				(width 0.1)
				(type default)
			)
			(layer "F.Fab")
		)
		(pad "1" smd rect
			(at -0.2667 0 270)
			(size 0.3048 0.381)
			(layers "F.Cu" "F.Mask" "F.Paste")
			(net "P5E_CPU1_PE2_TX_C_DN<0>")
		)
		(pad "2" smd rect
			(at 0.2667 0 270)
			(size 0.3048 0.381)
			(layers "F.Cu" "F.Mask" "F.Paste")
			(net "P5E_CPU1_PE2_TX_DN<0>")
		)
	)
	(footprint ""
		(layer "F.Cu")
		(at 41.874694 -17.623536 90)
		(property "Reference" "C825"
			(at 0 0 90)
			(layer "F.SilkS")
			(hide yes)
			(effects
				(font
					(size 1.27 1.27)
				)
			)
		)
		(property "Value" ""
			(at 0 0 90)
			(layer "F.Fab")
			(effects
				(font
					(size 1.27 1.27)
				)
			)
		)
		(duplicate_pad_numbers_are_jumpers no)
		(fp_line
			(start 0.299974 -0.150114)
			(end 0.299974 0.150114)
			(stroke
				(width 0.1)
				(type default)
			)
			(layer "F.Fab")
		)
		(fp_line
			(start -0.299974 -0.150114)
			(end 0.299974 -0.150114)
			(stroke
				(width 0.1)
				(type default)
			)
			(layer "F.Fab")
		)
		(fp_line
			(start 0.299974 0.150114)
			(end -0.299974 0.150114)
			(stroke
				(width 0.1)
				(type default)
			)
			(layer "F.Fab")
		)
		(fp_line
			(start -0.299974 0.150114)
			(end -0.299974 -0.150114)
			(stroke
				(width 0.1)
				(type default)
			)
			(layer "F.Fab")
		)
		(pad "1" smd rect
			(at -0.2667 0 90)
			(size 0.3048 0.381)
			(layers "F.Cu" "F.Mask" "F.Paste")
			(net "P5E_CPU1_PE1_TX_C_DP<6>")
		)
		(pad "2" smd rect
			(at 0.2667 0 90)
			(size 0.3048 0.381)
			(layers "F.Cu" "F.Mask" "F.Paste")
			(net "P5E_CPU1_PE1_TX_DP<6>")
		)
	)
	(footprint ""
		(layer "F.Cu")
		(at 87.776558 -402.371052 -90)
		(property "Reference" "C736"
			(at 0 0 270)
			(layer "F.SilkS")
			(hide yes)
			(effects
				(font
					(size 1.27 1.27)
				)
			)
		)
		(property "Value" ""
			(at 0 0 270)
			(layer "F.Fab")
			(effects
				(font
					(size 1.27 1.27)
				)
			)
		)
		(duplicate_pad_numbers_are_jumpers no)
		(fp_line
			(start -0.299974 0.150114)
			(end -0.299974 -0.150114)
			(stroke
				(width 0.1)
				(type default)
			)
			(layer "F.Fab")
		)
		(fp_line
			(start 0.299974 0.150114)
			(end -0.299974 0.150114)
			(stroke
				(width 0.1)
				(type default)
			)
			(layer "F.Fab")
		)
		(fp_line
			(start -0.299974 -0.150114)
			(end 0.299974 -0.150114)
			(stroke
				(width 0.1)
				(type default)
			)
			(layer "F.Fab")
		)
		(fp_line
			(start 0.299974 -0.150114)
			(end 0.299974 0.150114)
			(stroke
				(width 0.1)
				(type default)
			)
			(layer "F.Fab")
		)
		(pad "1" smd rect
			(at -0.2667 0 270)
			(size 0.3048 0.381)
			(layers "F.Cu" "F.Mask" "F.Paste")
			(net "P5E_CPU1_PE0_TX_C_DN<2>")
		)
		(pad "2" smd rect
			(at 0.2667 0 270)
			(size 0.3048 0.381)
			(layers "F.Cu" "F.Mask" "F.Paste")
			(net "P5E_CPU1_PE0_TX_DN<2>")
		)
	)
	(footprint ""
		(layer "F.Cu")
		(at 76.53401 -24.713946 -90)
		(property "Reference" "PC2139"
			(at 0 0 270)
			(layer "F.SilkS")
			(hide yes)
			(effects
				(font
					(size 1.27 1.27)
				)
			)
		)
		(property "Value" ""
			(at 0 0 270)
			(layer "F.Fab")
			(effects
				(font
					(size 1.27 1.27)
				)
			)
		)
		(duplicate_pad_numbers_are_jumpers no)
		(fp_line
			(start -0.7874 0.4064)
			(end -0.7874 -0.4064)
			(stroke
				(width 0.1524)
				(type default)
			)
			(layer "F.SilkS")
		)
		(fp_line
			(start 0.7874 0.4064)
			(end -0.7874 0.4064)
			(stroke
				(width 0.1524)
				(type default)
			)
			(layer "F.SilkS")
		)
		(fp_line
			(start -0.7874 -0.4064)
			(end 0.7874 -0.4064)
			(stroke
				(width 0.1524)
				(type default)
			)
			(layer "F.SilkS")
		)
		(fp_line
			(start 0.7874 -0.4064)
			(end 0.7874 0.4064)
			(stroke
				(width 0.1524)
				(type default)
			)
			(layer "F.SilkS")
		)
		(fp_line
			(start -0.67945 0.3048)
			(end -0.67945 -0.305054)
			(stroke
				(width 0.1)
				(type default)
			)
			(layer "F.Fab")
		)
		(fp_line
			(start -0.12065 0.3048)
			(end -0.67945 0.3048)
			(stroke
				(width 0.1)
				(type default)
			)
			(layer "F.Fab")
		)
		(fp_line
			(start 0.120396 0.3048)
			(end 0.120396 0.2794)
			(stroke
				(width 0.1)
				(type default)
			)
			(layer "F.Fab")
		)
		(fp_line
			(start 0.67945 0.3048)
			(end 0.120396 0.3048)
			(stroke
				(width 0.1)
				(type default)
			)
			(layer "F.Fab")
		)
		(fp_line
			(start -0.12065 0.2794)
			(end -0.12065 0.3048)
			(stroke
				(width 0.1)
				(type default)
			)
			(layer "F.Fab")
		)
		(fp_line
			(start 0.120396 0.2794)
			(end -0.12065 0.2794)
			(stroke
				(width 0.1)
				(type default)
			)
			(layer "F.Fab")
		)
		(fp_line
			(start -0.12065 -0.2794)
			(end 0.12065 -0.2794)
			(stroke
				(width 0.1)
				(type default)
			)
			(layer "F.Fab")
		)
		(fp_line
			(start 0.12065 -0.2794)
			(end 0.12065 -0.3048)
			(stroke
				(width 0.1)
				(type default)
			)
			(layer "F.Fab")
		)
		(fp_line
			(start 0.12065 -0.3048)
			(end 0.67945 -0.3048)
			(stroke
				(width 0.1)
				(type default)
			)
			(layer "F.Fab")
		)
		(fp_line
			(start 0.67945 -0.3048)
			(end 0.67945 0.3048)
			(stroke
				(width 0.1)
				(type default)
			)
			(layer "F.Fab")
		)
		(fp_line
			(start -0.67945 -0.305054)
			(end -0.12065 -0.305054)
			(stroke
				(width 0.1)
				(type default)
			)
			(layer "F.Fab")
		)
		(fp_line
			(start -0.12065 -0.305054)
			(end -0.12065 -0.2794)
			(stroke
				(width 0.1)
				(type default)
			)
			(layer "F.Fab")
		)
		(pad "1" smd circle
			(at -0.40005 0 270)
			(size 0 0)
			(layers "F.Cu" "F.Mask" "F.Paste")
			(net "P12V_AUX")
		)
		(pad "2" smd circle
			(at 0.40005 0 270)
			(size 0 0)
			(layers "F.Cu" "F.Mask" "F.Paste")
			(net "GND")
		)
	)
	(footprint ""
		(layer "F.Cu")
		(at 337.792314 -24.212042 -90)
		(property "Reference" "R1253"
			(at 0 0 270)
			(layer "F.SilkS")
			(hide yes)
			(effects
				(font
					(size 1.27 1.27)
				)
			)
		)
		(property "Value" ""
			(at 0 0 270)
			(layer "F.Fab")
			(effects
				(font
					(size 1.27 1.27)
				)
			)
		)
		(duplicate_pad_numbers_are_jumpers no)
		(fp_line
			(start -0.7874 0.4064)
			(end -0.7874 -0.4064)
			(stroke
				(width 0.1524)
				(type default)
			)
			(layer "F.SilkS")
		)
		(fp_line
			(start 0.7874 0.4064)
			(end -0.7874 0.4064)
			(stroke
				(width 0.1524)
				(type default)
			)
			(layer "F.SilkS")
		)
		(fp_line
			(start -0.7874 -0.4064)
			(end 0.7874 -0.4064)
			(stroke
				(width 0.1524)
				(type default)
			)
			(layer "F.SilkS")
		)
		(fp_line
			(start 0.7874 -0.4064)
			(end 0.7874 0.4064)
			(stroke
				(width 0.1524)
				(type default)
			)
			(layer "F.SilkS")
		)
		(fp_line
			(start -0.67945 0.3048)
			(end -0.67945 -0.305054)
			(stroke
				(width 0.1)
				(type default)
			)
			(layer "F.Fab")
		)
		(fp_line
			(start -0.12065 0.3048)
			(end -0.67945 0.3048)
			(stroke
				(width 0.1)
				(type default)
			)
			(layer "F.Fab")
		)
		(fp_line
			(start 0.120396 0.3048)
			(end 0.120396 0.2794)
			(stroke
				(width 0.1)
				(type default)
			)
			(layer "F.Fab")
		)
		(fp_line
			(start 0.67945 0.3048)
			(end 0.120396 0.3048)
			(stroke
				(width 0.1)
				(type default)
			)
			(layer "F.Fab")
		)
		(fp_line
			(start -0.12065 0.2794)
			(end -0.12065 0.3048)
			(stroke
				(width 0.1)
				(type default)
			)
			(layer "F.Fab")
		)
		(fp_line
			(start 0.120396 0.2794)
			(end -0.12065 0.2794)
			(stroke
				(width 0.1)
				(type default)
			)
			(layer "F.Fab")
		)
		(fp_line
			(start -0.12065 -0.2794)
			(end 0.12065 -0.2794)
			(stroke
				(width 0.1)
				(type default)
			)
			(layer "F.Fab")
		)
		(fp_line
			(start 0.12065 -0.2794)
			(end 0.12065 -0.3048)
			(stroke
				(width 0.1)
				(type default)
			)
			(layer "F.Fab")
		)
		(fp_line
			(start 0.12065 -0.3048)
			(end 0.67945 -0.3048)
			(stroke
				(width 0.1)
				(type default)
			)
			(layer "F.Fab")
		)
		(fp_line
			(start 0.67945 -0.3048)
			(end 0.67945 0.3048)
			(stroke
				(width 0.1)
				(type default)
			)
			(layer "F.Fab")
		)
		(fp_line
			(start -0.67945 -0.305054)
			(end -0.12065 -0.305054)
			(stroke
				(width 0.1)
				(type default)
			)
			(layer "F.Fab")
		)
		(fp_line
			(start -0.12065 -0.305054)
			(end -0.12065 -0.2794)
			(stroke
				(width 0.1)
				(type default)
			)
			(layer "F.Fab")
		)
		(pad "1" smd circle
			(at -0.40005 0 270)
			(size 0 0)
			(layers "F.Cu" "F.Mask" "F.Paste")
			(net "PGPPA_AUX")
		)
		(pad "2" smd circle
			(at 0.40005 0 270)
			(size 0 0)
			(layers "F.Cu" "F.Mask" "F.Paste")
			(net "IRQ_LPC_PIRQA_N_ESPI_ALERT0_N")
		)
	)
	(footprint ""
		(layer "F.Cu")
		(at 149.044914 -408.517344 -90)
		(property "Reference" "C1534"
			(at 0 0 270)
			(layer "F.SilkS")
			(hide yes)
			(effects
				(font
					(size 1.27 1.27)
				)
			)
		)
		(property "Value" ""
			(at 0 0 270)
			(layer "F.Fab")
			(effects
				(font
					(size 1.27 1.27)
				)
			)
		)
		(duplicate_pad_numbers_are_jumpers no)
		(fp_line
			(start -0.299974 0.150114)
			(end -0.299974 -0.150114)
			(stroke
				(width 0.1)
				(type default)
			)
			(layer "F.Fab")
		)
		(fp_line
			(start 0.299974 0.150114)
			(end -0.299974 0.150114)
			(stroke
				(width 0.1)
				(type default)
			)
			(layer "F.Fab")
		)
		(fp_line
			(start -0.299974 -0.150114)
			(end 0.299974 -0.150114)
			(stroke
				(width 0.1)
				(type default)
			)
			(layer "F.Fab")
		)
		(fp_line
			(start 0.299974 -0.150114)
			(end 0.299974 0.150114)
			(stroke
				(width 0.1)
				(type default)
			)
			(layer "F.Fab")
		)
		(pad "1" smd rect
			(at -0.2667 0 270)
			(size 0.3048 0.381)
			(layers "F.Cu" "F.Mask" "F.Paste")
			(net "P5E_CPU1_PE3_TX_C_DN<6>")
		)
		(pad "2" smd rect
			(at 0.2667 0 270)
			(size 0.3048 0.381)
			(layers "F.Cu" "F.Mask" "F.Paste")
			(net "P5E_CPU1_PE3_TX_DN<6>")
		)
	)
	(footprint ""
		(layer "F.Cu")
		(at 303.600612 -34.937446 -90)
		(property "Reference" "C1177"
			(at 0 0 270)
			(layer "F.SilkS")
			(hide yes)
			(effects
				(font
					(size 1.27 1.27)
				)
			)
		)
		(property "Value" ""
			(at 0 0 270)
			(layer "F.Fab")
			(effects
				(font
					(size 1.27 1.27)
				)
			)
		)
		(duplicate_pad_numbers_are_jumpers no)
		(fp_line
			(start -0.7874 0.4064)
			(end -0.7874 -0.4064)
			(stroke
				(width 0.1524)
				(type default)
			)
			(layer "F.SilkS")
		)
		(fp_line
			(start 0.7874 0.4064)
			(end -0.7874 0.4064)
			(stroke
				(width 0.1524)
				(type default)
			)
			(layer "F.SilkS")
		)
		(fp_line
			(start -0.7874 -0.4064)
			(end 0.7874 -0.4064)
			(stroke
				(width 0.1524)
				(type default)
			)
			(layer "F.SilkS")
		)
		(fp_line
			(start 0.7874 -0.4064)
			(end 0.7874 0.4064)
			(stroke
				(width 0.1524)
				(type default)
			)
			(layer "F.SilkS")
		)
		(fp_line
			(start -0.67945 0.3048)
			(end -0.67945 -0.305054)
			(stroke
				(width 0.1)
				(type default)
			)
			(layer "F.Fab")
		)
		(fp_line
			(start -0.12065 0.3048)
			(end -0.67945 0.3048)
			(stroke
				(width 0.1)
				(type default)
			)
			(layer "F.Fab")
		)
		(fp_line
			(start 0.120396 0.3048)
			(end 0.120396 0.2794)
			(stroke
				(width 0.1)
				(type default)
			)
			(layer "F.Fab")
		)
		(fp_line
			(start 0.67945 0.3048)
			(end 0.120396 0.3048)
			(stroke
				(width 0.1)
				(type default)
			)
			(layer "F.Fab")
		)
		(fp_line
			(start -0.12065 0.2794)
			(end -0.12065 0.3048)
			(stroke
				(width 0.1)
				(type default)
			)
			(layer "F.Fab")
		)
		(fp_line
			(start 0.120396 0.2794)
			(end -0.12065 0.2794)
			(stroke
				(width 0.1)
				(type default)
			)
			(layer "F.Fab")
		)
		(fp_line
			(start -0.12065 -0.2794)
			(end 0.12065 -0.2794)
			(stroke
				(width 0.1)
				(type default)
			)
			(layer "F.Fab")
		)
		(fp_line
			(start 0.12065 -0.2794)
			(end 0.12065 -0.3048)
			(stroke
				(width 0.1)
				(type default)
			)
			(layer "F.Fab")
		)
		(fp_line
			(start 0.12065 -0.3048)
			(end 0.67945 -0.3048)
			(stroke
				(width 0.1)
				(type default)
			)
			(layer "F.Fab")
		)
		(fp_line
			(start 0.67945 -0.3048)
			(end 0.67945 0.3048)
			(stroke
				(width 0.1)
				(type default)
			)
			(layer "F.Fab")
		)
		(fp_line
			(start -0.67945 -0.305054)
			(end -0.12065 -0.305054)
			(stroke
				(width 0.1)
				(type default)
			)
			(layer "F.Fab")
		)
		(fp_line
			(start -0.12065 -0.305054)
			(end -0.12065 -0.2794)
			(stroke
				(width 0.1)
				(type default)
			)
			(layer "F.Fab")
		)
		(pad "1" smd circle
			(at -0.40005 0 270)
			(size 0 0)
			(layers "F.Cu" "F.Mask" "F.Paste")
			(net "RST_RTCRST_N")
		)
		(pad "2" smd circle
			(at 0.40005 0 270)
			(size 0 0)
			(layers "F.Cu" "F.Mask" "F.Paste")
			(net "GND")
		)
	)
	(footprint ""
		(layer "F.Cu")
		(at 164.64788 -122.646948 180)
		(property "Reference" "R1413"
			(at 0 0 180)
			(layer "F.SilkS")
			(hide yes)
			(effects
				(font
					(size 1.27 1.27)
				)
			)
		)
		(property "Value" ""
			(at 0 0 180)
			(layer "F.Fab")
			(effects
				(font
					(size 1.27 1.27)
				)
			)
		)
		(duplicate_pad_numbers_are_jumpers no)
		(fp_line
			(start 0.7874 0.4064)
			(end -0.7874 0.4064)
			(stroke
				(width 0.1524)
				(type default)
			)
			(layer "F.SilkS")
		)
		(fp_line
			(start 0.7874 -0.4064)
			(end 0.7874 0.4064)
			(stroke
				(width 0.1524)
				(type default)
			)
			(layer "F.SilkS")
		)
		(fp_line
			(start -0.7874 0.4064)
			(end -0.7874 -0.4064)
			(stroke
				(width 0.1524)
				(type default)
			)
			(layer "F.SilkS")
		)
		(fp_line
			(start -0.7874 -0.4064)
			(end 0.7874 -0.4064)
			(stroke
				(width 0.1524)
				(type default)
			)
			(layer "F.SilkS")
		)
		(fp_line
			(start 0.67945 0.3048)
			(end 0.120396 0.3048)
			(stroke
				(width 0.1)
				(type default)
			)
			(layer "F.Fab")
		)
		(fp_line
			(start 0.67945 -0.3048)
			(end 0.67945 0.3048)
			(stroke
				(width 0.1)
				(type default)
			)
			(layer "F.Fab")
		)
		(fp_line
			(start 0.12065 -0.2794)
			(end 0.12065 -0.3048)
			(stroke
				(width 0.1)
				(type default)
			)
			(layer "F.Fab")
		)
		(fp_line
			(start 0.12065 -0.3048)
			(end 0.67945 -0.3048)
			(stroke
				(width 0.1)
				(type default)
			)
			(layer "F.Fab")
		)
		(fp_line
			(start 0.120396 0.3048)
			(end 0.120396 0.2794)
			(stroke
				(width 0.1)
				(type default)
			)
			(layer "F.Fab")
		)
		(fp_line
			(start 0.120396 0.2794)
			(end -0.12065 0.2794)
			(stroke
				(width 0.1)
				(type default)
			)
			(layer "F.Fab")
		)
		(fp_line
			(start -0.12065 0.3048)
			(end -0.67945 0.3048)
			(stroke
				(width 0.1)
				(type default)
			)
			(layer "F.Fab")
		)
		(fp_line
			(start -0.12065 0.2794)
			(end -0.12065 0.3048)
			(stroke
				(width 0.1)
				(type default)
			)
			(layer "F.Fab")
		)
		(fp_line
			(start -0.12065 -0.2794)
			(end 0.12065 -0.2794)
			(stroke
				(width 0.1)
				(type default)
			)
			(layer "F.Fab")
		)
		(fp_line
			(start -0.12065 -0.305054)
			(end -0.12065 -0.2794)
			(stroke
				(width 0.1)
				(type default)
			)
			(layer "F.Fab")
		)
		(fp_line
			(start -0.67945 0.3048)
			(end -0.67945 -0.305054)
			(stroke
				(width 0.1)
				(type default)
			)
			(layer "F.Fab")
		)
		(fp_line
			(start -0.67945 -0.305054)
			(end -0.12065 -0.305054)
			(stroke
				(width 0.1)
				(type default)
			)
			(layer "F.Fab")
		)
		(pad "1" smd circle
			(at -0.40005 0 180)
			(size 0 0)
			(layers "F.Cu" "F.Mask" "F.Paste")
			(net "FM_PVCCD_HV_CPU0_EN")
		)
		(pad "2" smd circle
			(at 0.40005 0 180)
			(size 0 0)
			(layers "F.Cu" "F.Mask" "F.Paste")
			(net "GND")
		)
	)
	(footprint ""
		(layer "F.Cu")
		(at 197.41388 -113.502948 90)
		(property "Reference" "R1099"
			(at 0 0 90)
			(layer "F.SilkS")
			(hide yes)
			(effects
				(font
					(size 1.27 1.27)
				)
			)
		)
		(property "Value" ""
			(at 0 0 90)
			(layer "F.Fab")
			(effects
				(font
					(size 1.27 1.27)
				)
			)
		)
		(duplicate_pad_numbers_are_jumpers no)
		(fp_line
			(start 0.7874 -0.4064)
			(end 0.7874 0.4064)
			(stroke
				(width 0.1524)
				(type default)
			)
			(layer "F.SilkS")
		)
		(fp_line
			(start -0.7874 -0.4064)
			(end 0.7874 -0.4064)
			(stroke
				(width 0.1524)
				(type default)
			)
			(layer "F.SilkS")
		)
		(fp_line
			(start 0.7874 0.4064)
			(end -0.7874 0.4064)
			(stroke
				(width 0.1524)
				(type default)
			)
			(layer "F.SilkS")
		)
		(fp_line
			(start -0.7874 0.4064)
			(end -0.7874 -0.4064)
			(stroke
				(width 0.1524)
				(type default)
			)
			(layer "F.SilkS")
		)
		(fp_line
			(start -0.12065 -0.305054)
			(end -0.12065 -0.2794)
			(stroke
				(width 0.1)
				(type default)
			)
			(layer "F.Fab")
		)
		(fp_line
			(start -0.67945 -0.305054)
			(end -0.12065 -0.305054)
			(stroke
				(width 0.1)
				(type default)
			)
			(layer "F.Fab")
		)
		(fp_line
			(start 0.67945 -0.3048)
			(end 0.67945 0.3048)
			(stroke
				(width 0.1)
				(type default)
			)
			(layer "F.Fab")
		)
		(fp_line
			(start 0.12065 -0.3048)
			(end 0.67945 -0.3048)
			(stroke
				(width 0.1)
				(type default)
			)
			(layer "F.Fab")
		)
		(fp_line
			(start 0.12065 -0.2794)
			(end 0.12065 -0.3048)
			(stroke
				(width 0.1)
				(type default)
			)
			(layer "F.Fab")
		)
		(fp_line
			(start -0.12065 -0.2794)
			(end 0.12065 -0.2794)
			(stroke
				(width 0.1)
				(type default)
			)
			(layer "F.Fab")
		)
		(fp_line
			(start 0.120396 0.2794)
			(end -0.12065 0.2794)
			(stroke
				(width 0.1)
				(type default)
			)
			(layer "F.Fab")
		)
		(fp_line
			(start -0.12065 0.2794)
			(end -0.12065 0.3048)
			(stroke
				(width 0.1)
				(type default)
			)
			(layer "F.Fab")
		)
		(fp_line
			(start 0.67945 0.3048)
			(end 0.120396 0.3048)
			(stroke
				(width 0.1)
				(type default)
			)
			(layer "F.Fab")
		)
		(fp_line
			(start 0.120396 0.3048)
			(end 0.120396 0.2794)
			(stroke
				(width 0.1)
				(type default)
			)
			(layer "F.Fab")
		)
		(fp_line
			(start -0.12065 0.3048)
			(end -0.67945 0.3048)
			(stroke
				(width 0.1)
				(type default)
			)
			(layer "F.Fab")
		)
		(fp_line
			(start -0.67945 0.3048)
			(end -0.67945 -0.305054)
			(stroke
				(width 0.1)
				(type default)
			)
			(layer "F.Fab")
		)
		(pad "1" smd circle
			(at -0.40005 0 90)
			(size 0 0)
			(layers "F.Cu" "F.Mask" "F.Paste")
			(net "P3V3_AUX")
		)
		(pad "2" smd circle
			(at 0.40005 0 90)
			(size 0 0)
			(layers "F.Cu" "F.Mask" "F.Paste")
			(net "PU_CLK25M_OSC_FPGA_EN")
		)
	)
	(footprint ""
		(layer "F.Cu")
		(at 103.40975 -360.934762 90)
		(property "Reference" "C2859"
			(at 0 0 90)
			(layer "F.SilkS")
			(hide yes)
			(effects
				(font
					(size 1.27 1.27)
				)
			)
		)
		(property "Value" ""
			(at 0 0 90)
			(layer "F.Fab")
			(effects
				(font
					(size 1.27 1.27)
				)
			)
		)
		(duplicate_pad_numbers_are_jumpers no)
		(fp_line
			(start 0.7874 -0.4064)
			(end 0.7874 0.4064)
			(stroke
				(width 0.1524)
				(type default)
			)
			(layer "F.SilkS")
		)
		(fp_line
			(start -0.7874 -0.4064)
			(end 0.7874 -0.4064)
			(stroke
				(width 0.1524)
				(type default)
			)
			(layer "F.SilkS")
		)
		(fp_line
			(start 0.7874 0.4064)
			(end -0.7874 0.4064)
			(stroke
				(width 0.1524)
				(type default)
			)
			(layer "F.SilkS")
		)
		(fp_line
			(start -0.7874 0.4064)
			(end -0.7874 -0.4064)
			(stroke
				(width 0.1524)
				(type default)
			)
			(layer "F.SilkS")
		)
		(fp_line
			(start -0.12065 -0.305054)
			(end -0.12065 -0.2794)
			(stroke
				(width 0.1)
				(type default)
			)
			(layer "F.Fab")
		)
		(fp_line
			(start -0.67945 -0.305054)
			(end -0.12065 -0.305054)
			(stroke
				(width 0.1)
				(type default)
			)
			(layer "F.Fab")
		)
		(fp_line
			(start 0.67945 -0.3048)
			(end 0.67945 0.3048)
			(stroke
				(width 0.1)
				(type default)
			)
			(layer "F.Fab")
		)
		(fp_line
			(start 0.12065 -0.3048)
			(end 0.67945 -0.3048)
			(stroke
				(width 0.1)
				(type default)
			)
			(layer "F.Fab")
		)
		(fp_line
			(start 0.12065 -0.2794)
			(end 0.12065 -0.3048)
			(stroke
				(width 0.1)
				(type default)
			)
			(layer "F.Fab")
		)
		(fp_line
			(start -0.12065 -0.2794)
			(end 0.12065 -0.2794)
			(stroke
				(width 0.1)
				(type default)
			)
			(layer "F.Fab")
		)
		(fp_line
			(start 0.120396 0.2794)
			(end -0.12065 0.2794)
			(stroke
				(width 0.1)
				(type default)
			)
			(layer "F.Fab")
		)
		(fp_line
			(start -0.12065 0.2794)
			(end -0.12065 0.3048)
			(stroke
				(width 0.1)
				(type default)
			)
			(layer "F.Fab")
		)
		(fp_line
			(start 0.67945 0.3048)
			(end 0.120396 0.3048)
			(stroke
				(width 0.1)
				(type default)
			)
			(layer "F.Fab")
		)
		(fp_line
			(start 0.120396 0.3048)
			(end 0.120396 0.2794)
			(stroke
				(width 0.1)
				(type default)
			)
			(layer "F.Fab")
		)
		(fp_line
			(start -0.12065 0.3048)
			(end -0.67945 0.3048)
			(stroke
				(width 0.1)
				(type default)
			)
			(layer "F.Fab")
		)
		(fp_line
			(start -0.67945 0.3048)
			(end -0.67945 -0.305054)
			(stroke
				(width 0.1)
				(type default)
			)
			(layer "F.Fab")
		)
		(pad "1" smd circle
			(at -0.40005 0 90)
			(size 0 0)
			(layers "F.Cu" "F.Mask" "F.Paste")
			(net "PWRGD_PVCCIN_CPU1_R")
		)
		(pad "2" smd circle
			(at 0.40005 0 90)
			(size 0 0)
			(layers "F.Cu" "F.Mask" "F.Paste")
			(net "GND")
		)
	)
	(footprint ""
		(layer "F.Cu")
		(at 119.02948 -357.114348 90)
		(property "Reference" "PR2381"
			(at 0 0 90)
			(layer "F.SilkS")
			(hide yes)
			(effects
				(font
					(size 1.27 1.27)
				)
			)
		)
		(property "Value" ""
			(at 0 0 90)
			(layer "F.Fab")
			(effects
				(font
					(size 1.27 1.27)
				)
			)
		)
		(duplicate_pad_numbers_are_jumpers no)
		(fp_line
			(start 0.7874 -0.4064)
			(end 0.7874 0.4064)
			(stroke
				(width 0.1524)
				(type default)
			)
			(layer "F.SilkS")
		)
		(fp_line
			(start -0.7874 -0.4064)
			(end 0.7874 -0.4064)
			(stroke
				(width 0.1524)
				(type default)
			)
			(layer "F.SilkS")
		)
		(fp_line
			(start 0.7874 0.4064)
			(end -0.7874 0.4064)
			(stroke
				(width 0.1524)
				(type default)
			)
			(layer "F.SilkS")
		)
		(fp_line
			(start -0.7874 0.4064)
			(end -0.7874 -0.4064)
			(stroke
				(width 0.1524)
				(type default)
			)
			(layer "F.SilkS")
		)
		(fp_line
			(start -0.12065 -0.305054)
			(end -0.12065 -0.2794)
			(stroke
				(width 0.1)
				(type default)
			)
			(layer "F.Fab")
		)
		(fp_line
			(start -0.67945 -0.305054)
			(end -0.12065 -0.305054)
			(stroke
				(width 0.1)
				(type default)
			)
			(layer "F.Fab")
		)
		(fp_line
			(start 0.67945 -0.3048)
			(end 0.67945 0.3048)
			(stroke
				(width 0.1)
				(type default)
			)
			(layer "F.Fab")
		)
		(fp_line
			(start 0.12065 -0.3048)
			(end 0.67945 -0.3048)
			(stroke
				(width 0.1)
				(type default)
			)
			(layer "F.Fab")
		)
		(fp_line
			(start 0.12065 -0.2794)
			(end 0.12065 -0.3048)
			(stroke
				(width 0.1)
				(type default)
			)
			(layer "F.Fab")
		)
		(fp_line
			(start -0.12065 -0.2794)
			(end 0.12065 -0.2794)
			(stroke
				(width 0.1)
				(type default)
			)
			(layer "F.Fab")
		)
		(fp_line
			(start 0.120396 0.2794)
			(end -0.12065 0.2794)
			(stroke
				(width 0.1)
				(type default)
			)
			(layer "F.Fab")
		)
		(fp_line
			(start -0.12065 0.2794)
			(end -0.12065 0.3048)
			(stroke
				(width 0.1)
				(type default)
			)
			(layer "F.Fab")
		)
		(fp_line
			(start 0.67945 0.3048)
			(end 0.120396 0.3048)
			(stroke
				(width 0.1)
				(type default)
			)
			(layer "F.Fab")
		)
		(fp_line
			(start 0.120396 0.3048)
			(end 0.120396 0.2794)
			(stroke
				(width 0.1)
				(type default)
			)
			(layer "F.Fab")
		)
		(fp_line
			(start -0.12065 0.3048)
			(end -0.67945 0.3048)
			(stroke
				(width 0.1)
				(type default)
			)
			(layer "F.Fab")
		)
		(fp_line
			(start -0.67945 0.3048)
			(end -0.67945 -0.305054)
			(stroke
				(width 0.1)
				(type default)
			)
			(layer "F.Fab")
		)
		(pad "1" smd circle
			(at -0.40005 0 90)
			(size 0 0)
			(layers "F.Cu" "F.Mask" "F.Paste")
			(net "PVPP_HBM_CPU1_FB")
		)
		(pad "2" smd circle
			(at 0.40005 0 90)
			(size 0 0)
			(layers "F.Cu" "F.Mask" "F.Paste")
			(net "FM_HBM_VPP_SEL_CPU1_D")
		)
	)
	(footprint ""
		(layer "F.Cu")
		(at 22.13356 -163.719256)
		(property "Reference" "R2580"
			(at 0 0 0)
			(layer "F.SilkS")
			(hide yes)
			(effects
				(font
					(size 1.27 1.27)
				)
			)
		)
		(property "Value" ""
			(at 0 0 0)
			(layer "F.Fab")
			(effects
				(font
					(size 1.27 1.27)
				)
			)
		)
		(duplicate_pad_numbers_are_jumpers no)
		(fp_line
			(start -0.7874 -0.4064)
			(end 0.7874 -0.4064)
			(stroke
				(width 0.1524)
				(type default)
			)
			(layer "F.SilkS")
		)
		(fp_line
			(start -0.7874 0.4064)
			(end -0.7874 -0.4064)
			(stroke
				(width 0.1524)
				(type default)
			)
			(layer "F.SilkS")
		)
		(fp_line
			(start 0.7874 -0.4064)
			(end 0.7874 0.4064)
			(stroke
				(width 0.1524)
				(type default)
			)
			(layer "F.SilkS")
		)
		(fp_line
			(start 0.7874 0.4064)
			(end -0.7874 0.4064)
			(stroke
				(width 0.1524)
				(type default)
			)
			(layer "F.SilkS")
		)
		(fp_line
			(start -0.67945 -0.305054)
			(end -0.12065 -0.305054)
			(stroke
				(width 0.1)
				(type default)
			)
			(layer "F.Fab")
		)
		(fp_line
			(start -0.67945 0.3048)
			(end -0.67945 -0.305054)
			(stroke
				(width 0.1)
				(type default)
			)
			(layer "F.Fab")
		)
		(fp_line
			(start -0.12065 -0.305054)
			(end -0.12065 -0.2794)
			(stroke
				(width 0.1)
				(type default)
			)
			(layer "F.Fab")
		)
		(fp_line
			(start -0.12065 -0.2794)
			(end 0.12065 -0.2794)
			(stroke
				(width 0.1)
				(type default)
			)
			(layer "F.Fab")
		)
		(fp_line
			(start -0.12065 0.2794)
			(end -0.12065 0.3048)
			(stroke
				(width 0.1)
				(type default)
			)
			(layer "F.Fab")
		)
		(fp_line
			(start -0.12065 0.3048)
			(end -0.67945 0.3048)
			(stroke
				(width 0.1)
				(type default)
			)
			(layer "F.Fab")
		)
		(fp_line
			(start 0.120396 0.2794)
			(end -0.12065 0.2794)
			(stroke
				(width 0.1)
				(type default)
			)
			(layer "F.Fab")
		)
		(fp_line
			(start 0.120396 0.3048)
			(end 0.120396 0.2794)
			(stroke
				(width 0.1)
				(type default)
			)
			(layer "F.Fab")
		)
		(fp_line
			(start 0.12065 -0.3048)
			(end 0.67945 -0.3048)
			(stroke
				(width 0.1)
				(type default)
			)
			(layer "F.Fab")
		)
		(fp_line
			(start 0.12065 -0.2794)
			(end 0.12065 -0.3048)
			(stroke
				(width 0.1)
				(type default)
			)
			(layer "F.Fab")
		)
		(fp_line
			(start 0.67945 -0.3048)
			(end 0.67945 0.3048)
			(stroke
				(width 0.1)
				(type default)
			)
			(layer "F.Fab")
		)
		(fp_line
			(start 0.67945 0.3048)
			(end 0.120396 0.3048)
			(stroke
				(width 0.1)
				(type default)
			)
			(layer "F.Fab")
		)
		(pad "1" smd circle
			(at -0.40005 0)
			(size 0 0)
			(layers "F.Cu" "F.Mask" "F.Paste")
			(net "SVID_ALERT1_CPU1_R_N")
		)
		(pad "2" smd circle
			(at 0.40005 0)
			(size 0 0)
			(layers "F.Cu" "F.Mask" "F.Paste")
			(net "SVID_ALERT_PVCCD_HV_CPU1_R")
		)
	)
	(footprint ""
		(layer "F.Cu")
		(at 105.944416 -338.180172 90)
		(property "Reference" "PR1766"
			(at 0 0 90)
			(layer "F.SilkS")
			(hide yes)
			(effects
				(font
					(size 1.27 1.27)
				)
			)
		)
		(property "Value" ""
			(at 0 0 90)
			(layer "F.Fab")
			(effects
				(font
					(size 1.27 1.27)
				)
			)
		)
		(duplicate_pad_numbers_are_jumpers no)
		(fp_line
			(start 0.7874 -0.4064)
			(end 0.7874 0.4064)
			(stroke
				(width 0.1524)
				(type default)
			)
			(layer "F.SilkS")
		)
		(fp_line
			(start -0.7874 -0.4064)
			(end 0.7874 -0.4064)
			(stroke
				(width 0.1524)
				(type default)
			)
			(layer "F.SilkS")
		)
		(fp_line
			(start 0.7874 0.4064)
			(end -0.7874 0.4064)
			(stroke
				(width 0.1524)
				(type default)
			)
			(layer "F.SilkS")
		)
		(fp_line
			(start -0.7874 0.4064)
			(end -0.7874 -0.4064)
			(stroke
				(width 0.1524)
				(type default)
			)
			(layer "F.SilkS")
		)
		(fp_line
			(start -0.12065 -0.305054)
			(end -0.12065 -0.2794)
			(stroke
				(width 0.1)
				(type default)
			)
			(layer "F.Fab")
		)
		(fp_line
			(start -0.67945 -0.305054)
			(end -0.12065 -0.305054)
			(stroke
				(width 0.1)
				(type default)
			)
			(layer "F.Fab")
		)
		(fp_line
			(start 0.67945 -0.3048)
			(end 0.67945 0.3048)
			(stroke
				(width 0.1)
				(type default)
			)
			(layer "F.Fab")
		)
		(fp_line
			(start 0.12065 -0.3048)
			(end 0.67945 -0.3048)
			(stroke
				(width 0.1)
				(type default)
			)
			(layer "F.Fab")
		)
		(fp_line
			(start 0.12065 -0.2794)
			(end 0.12065 -0.3048)
			(stroke
				(width 0.1)
				(type default)
			)
			(layer "F.Fab")
		)
		(fp_line
			(start -0.12065 -0.2794)
			(end 0.12065 -0.2794)
			(stroke
				(width 0.1)
				(type default)
			)
			(layer "F.Fab")
		)
		(fp_line
			(start 0.120396 0.2794)
			(end -0.12065 0.2794)
			(stroke
				(width 0.1)
				(type default)
			)
			(layer "F.Fab")
		)
		(fp_line
			(start -0.12065 0.2794)
			(end -0.12065 0.3048)
			(stroke
				(width 0.1)
				(type default)
			)
			(layer "F.Fab")
		)
		(fp_line
			(start 0.67945 0.3048)
			(end 0.120396 0.3048)
			(stroke
				(width 0.1)
				(type default)
			)
			(layer "F.Fab")
		)
		(fp_line
			(start 0.120396 0.3048)
			(end 0.120396 0.2794)
			(stroke
				(width 0.1)
				(type default)
			)
			(layer "F.Fab")
		)
		(fp_line
			(start -0.12065 0.3048)
			(end -0.67945 0.3048)
			(stroke
				(width 0.1)
				(type default)
			)
			(layer "F.Fab")
		)
		(fp_line
			(start -0.67945 0.3048)
			(end -0.67945 -0.305054)
			(stroke
				(width 0.1)
				(type default)
			)
			(layer "F.Fab")
		)
		(pad "1" smd circle
			(at -0.40005 0 90)
			(size 0 0)
			(layers "F.Cu" "F.Mask" "F.Paste")
			(net "SW_PVCCIN_CPU1_BOOT2")
		)
		(pad "2" smd circle
			(at 0.40005 0 90)
			(size 0 0)
			(layers "F.Cu" "F.Mask" "F.Paste")
			(net "SW_PVCCIN_CPU1_BOOT2_R")
		)
	)
	(footprint ""
		(layer "F.Cu")
		(at 216.065608 -401.775422 180)
		(property "Reference" "PR3986"
			(at 0 0 180)
			(layer "F.SilkS")
			(hide yes)
			(effects
				(font
					(size 1.27 1.27)
				)
			)
		)
		(property "Value" ""
			(at 0 0 180)
			(layer "F.Fab")
			(effects
				(font
					(size 1.27 1.27)
				)
			)
		)
		(duplicate_pad_numbers_are_jumpers no)
		(fp_line
			(start 0.7874 0.4064)
			(end -0.7874 0.4064)
			(stroke
				(width 0.1524)
				(type default)
			)
			(layer "F.SilkS")
		)
		(fp_line
			(start 0.7874 -0.4064)
			(end 0.7874 0.4064)
			(stroke
				(width 0.1524)
				(type default)
			)
			(layer "F.SilkS")
		)
		(fp_line
			(start -0.7874 0.4064)
			(end -0.7874 -0.4064)
			(stroke
				(width 0.1524)
				(type default)
			)
			(layer "F.SilkS")
		)
		(fp_line
			(start -0.7874 -0.4064)
			(end 0.7874 -0.4064)
			(stroke
				(width 0.1524)
				(type default)
			)
			(layer "F.SilkS")
		)
		(fp_line
			(start 0.67945 0.3048)
			(end 0.120396 0.3048)
			(stroke
				(width 0.1)
				(type default)
			)
			(layer "F.Fab")
		)
		(fp_line
			(start 0.67945 -0.3048)
			(end 0.67945 0.3048)
			(stroke
				(width 0.1)
				(type default)
			)
			(layer "F.Fab")
		)
		(fp_line
			(start 0.12065 -0.2794)
			(end 0.12065 -0.3048)
			(stroke
				(width 0.1)
				(type default)
			)
			(layer "F.Fab")
		)
		(fp_line
			(start 0.12065 -0.3048)
			(end 0.67945 -0.3048)
			(stroke
				(width 0.1)
				(type default)
			)
			(layer "F.Fab")
		)
		(fp_line
			(start 0.120396 0.3048)
			(end 0.120396 0.2794)
			(stroke
				(width 0.1)
				(type default)
			)
			(layer "F.Fab")
		)
		(fp_line
			(start 0.120396 0.2794)
			(end -0.12065 0.2794)
			(stroke
				(width 0.1)
				(type default)
			)
			(layer "F.Fab")
		)
		(fp_line
			(start -0.12065 0.3048)
			(end -0.67945 0.3048)
			(stroke
				(width 0.1)
				(type default)
			)
			(layer "F.Fab")
		)
		(fp_line
			(start -0.12065 0.2794)
			(end -0.12065 0.3048)
			(stroke
				(width 0.1)
				(type default)
			)
			(layer "F.Fab")
		)
		(fp_line
			(start -0.12065 -0.2794)
			(end 0.12065 -0.2794)
			(stroke
				(width 0.1)
				(type default)
			)
			(layer "F.Fab")
		)
		(fp_line
			(start -0.12065 -0.305054)
			(end -0.12065 -0.2794)
			(stroke
				(width 0.1)
				(type default)
			)
			(layer "F.Fab")
		)
		(fp_line
			(start -0.67945 0.3048)
			(end -0.67945 -0.305054)
			(stroke
				(width 0.1)
				(type default)
			)
			(layer "F.Fab")
		)
		(fp_line
			(start -0.67945 -0.305054)
			(end -0.12065 -0.305054)
			(stroke
				(width 0.1)
				(type default)
			)
			(layer "F.Fab")
		)
		(pad "1" smd circle
			(at -0.40005 0 180)
			(size 0 0)
			(layers "F.Cu" "F.Mask" "F.Paste")
			(net "HSC_CS_3")
		)
		(pad "2" smd circle
			(at 0.40005 0 180)
			(size 0 0)
			(layers "F.Cu" "F.Mask" "F.Paste")
			(net "AGND_HSC")
		)
	)
	(footprint ""
		(layer "F.Cu")
		(at 25.636474 -178.759358 90)
		(property "Reference" "PR4272"
			(at 0 0 90)
			(layer "F.SilkS")
			(hide yes)
			(effects
				(font
					(size 1.27 1.27)
				)
			)
		)
		(property "Value" ""
			(at 0 0 90)
			(layer "F.Fab")
			(effects
				(font
					(size 1.27 1.27)
				)
			)
		)
		(duplicate_pad_numbers_are_jumpers no)
		(fp_line
			(start 0.7874 -0.4064)
			(end 0.7874 0.4064)
			(stroke
				(width 0.1524)
				(type default)
			)
			(layer "F.SilkS")
		)
		(fp_line
			(start -0.7874 -0.4064)
			(end 0.7874 -0.4064)
			(stroke
				(width 0.1524)
				(type default)
			)
			(layer "F.SilkS")
		)
		(fp_line
			(start 0.7874 0.4064)
			(end -0.7874 0.4064)
			(stroke
				(width 0.1524)
				(type default)
			)
			(layer "F.SilkS")
		)
		(fp_line
			(start -0.7874 0.4064)
			(end -0.7874 -0.4064)
			(stroke
				(width 0.1524)
				(type default)
			)
			(layer "F.SilkS")
		)
		(fp_line
			(start -0.12065 -0.305054)
			(end -0.12065 -0.2794)
			(stroke
				(width 0.1)
				(type default)
			)
			(layer "F.Fab")
		)
		(fp_line
			(start -0.67945 -0.305054)
			(end -0.12065 -0.305054)
			(stroke
				(width 0.1)
				(type default)
			)
			(layer "F.Fab")
		)
		(fp_line
			(start 0.67945 -0.3048)
			(end 0.67945 0.3048)
			(stroke
				(width 0.1)
				(type default)
			)
			(layer "F.Fab")
		)
		(fp_line
			(start 0.12065 -0.3048)
			(end 0.67945 -0.3048)
			(stroke
				(width 0.1)
				(type default)
			)
			(layer "F.Fab")
		)
		(fp_line
			(start 0.12065 -0.2794)
			(end 0.12065 -0.3048)
			(stroke
				(width 0.1)
				(type default)
			)
			(layer "F.Fab")
		)
		(fp_line
			(start -0.12065 -0.2794)
			(end 0.12065 -0.2794)
			(stroke
				(width 0.1)
				(type default)
			)
			(layer "F.Fab")
		)
		(fp_line
			(start 0.120396 0.2794)
			(end -0.12065 0.2794)
			(stroke
				(width 0.1)
				(type default)
			)
			(layer "F.Fab")
		)
		(fp_line
			(start -0.12065 0.2794)
			(end -0.12065 0.3048)
			(stroke
				(width 0.1)
				(type default)
			)
			(layer "F.Fab")
		)
		(fp_line
			(start 0.67945 0.3048)
			(end 0.120396 0.3048)
			(stroke
				(width 0.1)
				(type default)
			)
			(layer "F.Fab")
		)
		(fp_line
			(start 0.120396 0.3048)
			(end 0.120396 0.2794)
			(stroke
				(width 0.1)
				(type default)
			)
			(layer "F.Fab")
		)
		(fp_line
			(start -0.12065 0.3048)
			(end -0.67945 0.3048)
			(stroke
				(width 0.1)
				(type default)
			)
			(layer "F.Fab")
		)
		(fp_line
			(start -0.67945 0.3048)
			(end -0.67945 -0.305054)
			(stroke
				(width 0.1)
				(type default)
			)
			(layer "F.Fab")
		)
		(pad "1" smd circle
			(at -0.40005 0 90)
			(size 0 0)
			(layers "F.Cu" "F.Mask" "F.Paste")
			(net "SW_PVNN_MAIN_CPU1_BST")
		)
		(pad "2" smd circle
			(at 0.40005 0 90)
			(size 0 0)
			(layers "F.Cu" "F.Mask" "F.Paste")
			(net "SW_PVNN_MAIN_CPU1_BST_R")
		)
	)
	(footprint ""
		(layer "F.Cu")
		(at 118.83898 -411.131004)
		(property "Reference" "R4492"
			(at 0 0 0)
			(layer "F.SilkS")
			(hide yes)
			(effects
				(font
					(size 1.27 1.27)
				)
			)
		)
		(property "Value" ""
			(at 0 0 0)
			(layer "F.Fab")
			(effects
				(font
					(size 1.27 1.27)
				)
			)
		)
		(duplicate_pad_numbers_are_jumpers no)
		(fp_line
			(start -0.7874 -0.4064)
			(end 0.7874 -0.4064)
			(stroke
				(width 0.1524)
				(type default)
			)
			(layer "F.SilkS")
		)
		(fp_line
			(start -0.7874 0.4064)
			(end -0.7874 -0.4064)
			(stroke
				(width 0.1524)
				(type default)
			)
			(layer "F.SilkS")
		)
		(fp_line
			(start 0.7874 -0.4064)
			(end 0.7874 0.4064)
			(stroke
				(width 0.1524)
				(type default)
			)
			(layer "F.SilkS")
		)
		(fp_line
			(start 0.7874 0.4064)
			(end -0.7874 0.4064)
			(stroke
				(width 0.1524)
				(type default)
			)
			(layer "F.SilkS")
		)
		(fp_line
			(start -0.67945 -0.305054)
			(end -0.12065 -0.305054)
			(stroke
				(width 0.1)
				(type default)
			)
			(layer "F.Fab")
		)
		(fp_line
			(start -0.67945 0.3048)
			(end -0.67945 -0.305054)
			(stroke
				(width 0.1)
				(type default)
			)
			(layer "F.Fab")
		)
		(fp_line
			(start -0.12065 -0.305054)
			(end -0.12065 -0.2794)
			(stroke
				(width 0.1)
				(type default)
			)
			(layer "F.Fab")
		)
		(fp_line
			(start -0.12065 -0.2794)
			(end 0.12065 -0.2794)
			(stroke
				(width 0.1)
				(type default)
			)
			(layer "F.Fab")
		)
		(fp_line
			(start -0.12065 0.2794)
			(end -0.12065 0.3048)
			(stroke
				(width 0.1)
				(type default)
			)
			(layer "F.Fab")
		)
		(fp_line
			(start -0.12065 0.3048)
			(end -0.67945 0.3048)
			(stroke
				(width 0.1)
				(type default)
			)
			(layer "F.Fab")
		)
		(fp_line
			(start 0.120396 0.2794)
			(end -0.12065 0.2794)
			(stroke
				(width 0.1)
				(type default)
			)
			(layer "F.Fab")
		)
		(fp_line
			(start 0.120396 0.3048)
			(end 0.120396 0.2794)
			(stroke
				(width 0.1)
				(type default)
			)
			(layer "F.Fab")
		)
		(fp_line
			(start 0.12065 -0.3048)
			(end 0.67945 -0.3048)
			(stroke
				(width 0.1)
				(type default)
			)
			(layer "F.Fab")
		)
		(fp_line
			(start 0.12065 -0.2794)
			(end 0.12065 -0.3048)
			(stroke
				(width 0.1)
				(type default)
			)
			(layer "F.Fab")
		)
		(fp_line
			(start 0.67945 -0.3048)
			(end 0.67945 0.3048)
			(stroke
				(width 0.1)
				(type default)
			)
			(layer "F.Fab")
		)
		(fp_line
			(start 0.67945 0.3048)
			(end 0.120396 0.3048)
			(stroke
				(width 0.1)
				(type default)
			)
			(layer "F.Fab")
		)
		(pad "1" smd circle
			(at -0.40005 0)
			(size 0 0)
			(layers "F.Cu" "F.Mask" "F.Paste")
			(net "CLK_9ZXL045_HIBW")
		)
		(pad "2" smd circle
			(at 0.40005 0)
			(size 0 0)
			(layers "F.Cu" "F.Mask" "F.Paste")
			(net "GND")
		)
	)
	(footprint ""
		(layer "F.Cu")
		(at 26.6446 -409.0416 90)
		(property "Reference" "R3475"
			(at 0 0 90)
			(layer "F.SilkS")
			(hide yes)
			(effects
				(font
					(size 1.27 1.27)
				)
			)
		)
		(property "Value" ""
			(at 0 0 90)
			(layer "F.Fab")
			(effects
				(font
					(size 1.27 1.27)
				)
			)
		)
		(duplicate_pad_numbers_are_jumpers no)
		(fp_line
			(start 0.7874 -0.4064)
			(end 0.7874 0.4064)
			(stroke
				(width 0.1524)
				(type default)
			)
			(layer "F.SilkS")
		)
		(fp_line
			(start -0.7874 -0.4064)
			(end 0.7874 -0.4064)
			(stroke
				(width 0.1524)
				(type default)
			)
			(layer "F.SilkS")
		)
		(fp_line
			(start 0.7874 0.4064)
			(end -0.7874 0.4064)
			(stroke
				(width 0.1524)
				(type default)
			)
			(layer "F.SilkS")
		)
		(fp_line
			(start -0.7874 0.4064)
			(end -0.7874 -0.4064)
			(stroke
				(width 0.1524)
				(type default)
			)
			(layer "F.SilkS")
		)
		(fp_line
			(start -0.12065 -0.305054)
			(end -0.12065 -0.2794)
			(stroke
				(width 0.1)
				(type default)
			)
			(layer "F.Fab")
		)
		(fp_line
			(start -0.67945 -0.305054)
			(end -0.12065 -0.305054)
			(stroke
				(width 0.1)
				(type default)
			)
			(layer "F.Fab")
		)
		(fp_line
			(start 0.67945 -0.3048)
			(end 0.67945 0.3048)
			(stroke
				(width 0.1)
				(type default)
			)
			(layer "F.Fab")
		)
		(fp_line
			(start 0.12065 -0.3048)
			(end 0.67945 -0.3048)
			(stroke
				(width 0.1)
				(type default)
			)
			(layer "F.Fab")
		)
		(fp_line
			(start 0.12065 -0.2794)
			(end 0.12065 -0.3048)
			(stroke
				(width 0.1)
				(type default)
			)
			(layer "F.Fab")
		)
		(fp_line
			(start -0.12065 -0.2794)
			(end 0.12065 -0.2794)
			(stroke
				(width 0.1)
				(type default)
			)
			(layer "F.Fab")
		)
		(fp_line
			(start 0.120396 0.2794)
			(end -0.12065 0.2794)
			(stroke
				(width 0.1)
				(type default)
			)
			(layer "F.Fab")
		)
		(fp_line
			(start -0.12065 0.2794)
			(end -0.12065 0.3048)
			(stroke
				(width 0.1)
				(type default)
			)
			(layer "F.Fab")
		)
		(fp_line
			(start 0.67945 0.3048)
			(end 0.120396 0.3048)
			(stroke
				(width 0.1)
				(type default)
			)
			(layer "F.Fab")
		)
		(fp_line
			(start 0.120396 0.3048)
			(end 0.120396 0.2794)
			(stroke
				(width 0.1)
				(type default)
			)
			(layer "F.Fab")
		)
		(fp_line
			(start -0.12065 0.3048)
			(end -0.67945 0.3048)
			(stroke
				(width 0.1)
				(type default)
			)
			(layer "F.Fab")
		)
		(fp_line
			(start -0.67945 0.3048)
			(end -0.67945 -0.305054)
			(stroke
				(width 0.1)
				(type default)
			)
			(layer "F.Fab")
		)
		(pad "1" smd circle
			(at -0.40005 0 90)
			(size 0 0)
			(layers "F.Cu" "F.Mask" "F.Paste")
			(net "P3V3_AUX")
		)
		(pad "2" smd circle
			(at 0.40005 0 90)
			(size 0 0)
			(layers "F.Cu" "F.Mask" "F.Paste")
			(net "GPU_PRSNT_N_ISO")
		)
	)
	(footprint ""
		(layer "F.Cu")
		(at 317.122048 -402.371052 -90)
		(property "Reference" "C1571"
			(at 0 0 270)
			(layer "F.SilkS")
			(hide yes)
			(effects
				(font
					(size 1.27 1.27)
				)
			)
		)
		(property "Value" ""
			(at 0 0 270)
			(layer "F.Fab")
			(effects
				(font
					(size 1.27 1.27)
				)
			)
		)
		(duplicate_pad_numbers_are_jumpers no)
		(fp_line
			(start -0.299974 0.150114)
			(end -0.299974 -0.150114)
			(stroke
				(width 0.1)
				(type default)
			)
			(layer "F.Fab")
		)
		(fp_line
			(start 0.299974 0.150114)
			(end -0.299974 0.150114)
			(stroke
				(width 0.1)
				(type default)
			)
			(layer "F.Fab")
		)
		(fp_line
			(start -0.299974 -0.150114)
			(end 0.299974 -0.150114)
			(stroke
				(width 0.1)
				(type default)
			)
			(layer "F.Fab")
		)
		(fp_line
			(start 0.299974 -0.150114)
			(end 0.299974 0.150114)
			(stroke
				(width 0.1)
				(type default)
			)
			(layer "F.Fab")
		)
		(pad "1" smd rect
			(at -0.2667 0 270)
			(size 0.3048 0.381)
			(layers "F.Cu" "F.Mask" "F.Paste")
			(net "P5E_CPU0_PE4_TX_C_DP<4>")
		)
		(pad "2" smd rect
			(at 0.2667 0 270)
			(size 0.3048 0.381)
			(layers "F.Cu" "F.Mask" "F.Paste")
			(net "P5E_CPU0_PE4_TX_DP<4>")
		)
	)
	(footprint ""
		(layer "F.Cu")
		(at 362.646468 -359.94975)
		(property "Reference" "PC329"
			(at 0 0 0)
			(layer "F.SilkS")
			(hide yes)
			(effects
				(font
					(size 1.27 1.27)
				)
			)
		)
		(property "Value" ""
			(at 0 0 0)
			(layer "F.Fab")
			(effects
				(font
					(size 1.27 1.27)
				)
			)
		)
		(duplicate_pad_numbers_are_jumpers no)
		(fp_line
			(start -0.7874 -0.4064)
			(end 0.7874 -0.4064)
			(stroke
				(width 0.1524)
				(type default)
			)
			(layer "F.SilkS")
		)
		(fp_line
			(start -0.7874 0.4064)
			(end -0.7874 -0.4064)
			(stroke
				(width 0.1524)
				(type default)
			)
			(layer "F.SilkS")
		)
		(fp_line
			(start 0.7874 -0.4064)
			(end 0.7874 0.4064)
			(stroke
				(width 0.1524)
				(type default)
			)
			(layer "F.SilkS")
		)
		(fp_line
			(start 0.7874 0.4064)
			(end -0.7874 0.4064)
			(stroke
				(width 0.1524)
				(type default)
			)
			(layer "F.SilkS")
		)
		(fp_line
			(start -0.67945 -0.305054)
			(end -0.12065 -0.305054)
			(stroke
				(width 0.1)
				(type default)
			)
			(layer "F.Fab")
		)
		(fp_line
			(start -0.67945 0.3048)
			(end -0.67945 -0.305054)
			(stroke
				(width 0.1)
				(type default)
			)
			(layer "F.Fab")
		)
		(fp_line
			(start -0.12065 -0.305054)
			(end -0.12065 -0.2794)
			(stroke
				(width 0.1)
				(type default)
			)
			(layer "F.Fab")
		)
		(fp_line
			(start -0.12065 -0.2794)
			(end 0.12065 -0.2794)
			(stroke
				(width 0.1)
				(type default)
			)
			(layer "F.Fab")
		)
		(fp_line
			(start -0.12065 0.2794)
			(end -0.12065 0.3048)
			(stroke
				(width 0.1)
				(type default)
			)
			(layer "F.Fab")
		)
		(fp_line
			(start -0.12065 0.3048)
			(end -0.67945 0.3048)
			(stroke
				(width 0.1)
				(type default)
			)
			(layer "F.Fab")
		)
		(fp_line
			(start 0.120396 0.2794)
			(end -0.12065 0.2794)
			(stroke
				(width 0.1)
				(type default)
			)
			(layer "F.Fab")
		)
		(fp_line
			(start 0.120396 0.3048)
			(end 0.120396 0.2794)
			(stroke
				(width 0.1)
				(type default)
			)
			(layer "F.Fab")
		)
		(fp_line
			(start 0.12065 -0.3048)
			(end 0.67945 -0.3048)
			(stroke
				(width 0.1)
				(type default)
			)
			(layer "F.Fab")
		)
		(fp_line
			(start 0.12065 -0.2794)
			(end 0.12065 -0.3048)
			(stroke
				(width 0.1)
				(type default)
			)
			(layer "F.Fab")
		)
		(fp_line
			(start 0.67945 -0.3048)
			(end 0.67945 0.3048)
			(stroke
				(width 0.1)
				(type default)
			)
			(layer "F.Fab")
		)
		(fp_line
			(start 0.67945 0.3048)
			(end 0.120396 0.3048)
			(stroke
				(width 0.1)
				(type default)
			)
			(layer "F.Fab")
		)
		(pad "1" smd circle
			(at -0.40005 0)
			(size 0 0)
			(layers "F.Cu" "F.Mask" "F.Paste")
			(net "PVCCIN_CPU0_CSPIN")
		)
		(pad "2" smd circle
			(at 0.40005 0)
			(size 0 0)
			(layers "F.Cu" "F.Mask" "F.Paste")
			(net "GND")
		)
	)
	(footprint ""
		(layer "F.Cu")
		(at 417.34613 -402.371052 -90)
		(property "Reference" "C965"
			(at 0 0 270)
			(layer "F.SilkS")
			(hide yes)
			(effects
				(font
					(size 1.27 1.27)
				)
			)
		)
		(property "Value" ""
			(at 0 0 270)
			(layer "F.Fab")
			(effects
				(font
					(size 1.27 1.27)
				)
			)
		)
		(duplicate_pad_numbers_are_jumpers no)
		(fp_line
			(start -0.299974 0.150114)
			(end -0.299974 -0.150114)
			(stroke
				(width 0.1)
				(type default)
			)
			(layer "F.Fab")
		)
		(fp_line
			(start 0.299974 0.150114)
			(end -0.299974 0.150114)
			(stroke
				(width 0.1)
				(type default)
			)
			(layer "F.Fab")
		)
		(fp_line
			(start -0.299974 -0.150114)
			(end 0.299974 -0.150114)
			(stroke
				(width 0.1)
				(type default)
			)
			(layer "F.Fab")
		)
		(fp_line
			(start 0.299974 -0.150114)
			(end 0.299974 0.150114)
			(stroke
				(width 0.1)
				(type default)
			)
			(layer "F.Fab")
		)
		(pad "1" smd rect
			(at -0.2667 0 270)
			(size 0.3048 0.381)
			(layers "F.Cu" "F.Mask" "F.Paste")
			(net "P5E_CPU0_PE2_TX_C_DP<0>")
		)
		(pad "2" smd rect
			(at 0.2667 0 270)
			(size 0.3048 0.381)
			(layers "F.Cu" "F.Mask" "F.Paste")
			(net "P5E_CPU0_PE2_TX_DP<0>")
		)
	)
	(footprint ""
		(layer "F.Cu")
		(at 315.946028 -24.132032 180)
		(property "Reference" "R1403"
			(at 0 0 180)
			(layer "F.SilkS")
			(hide yes)
			(effects
				(font
					(size 1.27 1.27)
				)
			)
		)
		(property "Value" ""
			(at 0 0 180)
			(layer "F.Fab")
			(effects
				(font
					(size 1.27 1.27)
				)
			)
		)
		(duplicate_pad_numbers_are_jumpers no)
		(fp_line
			(start 0.7874 0.4064)
			(end -0.7874 0.4064)
			(stroke
				(width 0.1524)
				(type default)
			)
			(layer "F.SilkS")
		)
		(fp_line
			(start 0.7874 -0.4064)
			(end 0.7874 0.4064)
			(stroke
				(width 0.1524)
				(type default)
			)
			(layer "F.SilkS")
		)
		(fp_line
			(start -0.7874 0.4064)
			(end -0.7874 -0.4064)
			(stroke
				(width 0.1524)
				(type default)
			)
			(layer "F.SilkS")
		)
		(fp_line
			(start -0.7874 -0.4064)
			(end 0.7874 -0.4064)
			(stroke
				(width 0.1524)
				(type default)
			)
			(layer "F.SilkS")
		)
		(fp_line
			(start 0.67945 0.3048)
			(end 0.120396 0.3048)
			(stroke
				(width 0.1)
				(type default)
			)
			(layer "F.Fab")
		)
		(fp_line
			(start 0.67945 -0.3048)
			(end 0.67945 0.3048)
			(stroke
				(width 0.1)
				(type default)
			)
			(layer "F.Fab")
		)
		(fp_line
			(start 0.12065 -0.2794)
			(end 0.12065 -0.3048)
			(stroke
				(width 0.1)
				(type default)
			)
			(layer "F.Fab")
		)
		(fp_line
			(start 0.12065 -0.3048)
			(end 0.67945 -0.3048)
			(stroke
				(width 0.1)
				(type default)
			)
			(layer "F.Fab")
		)
		(fp_line
			(start 0.120396 0.3048)
			(end 0.120396 0.2794)
			(stroke
				(width 0.1)
				(type default)
			)
			(layer "F.Fab")
		)
		(fp_line
			(start 0.120396 0.2794)
			(end -0.12065 0.2794)
			(stroke
				(width 0.1)
				(type default)
			)
			(layer "F.Fab")
		)
		(fp_line
			(start -0.12065 0.3048)
			(end -0.67945 0.3048)
			(stroke
				(width 0.1)
				(type default)
			)
			(layer "F.Fab")
		)
		(fp_line
			(start -0.12065 0.2794)
			(end -0.12065 0.3048)
			(stroke
				(width 0.1)
				(type default)
			)
			(layer "F.Fab")
		)
		(fp_line
			(start -0.12065 -0.2794)
			(end 0.12065 -0.2794)
			(stroke
				(width 0.1)
				(type default)
			)
			(layer "F.Fab")
		)
		(fp_line
			(start -0.12065 -0.305054)
			(end -0.12065 -0.2794)
			(stroke
				(width 0.1)
				(type default)
			)
			(layer "F.Fab")
		)
		(fp_line
			(start -0.67945 0.3048)
			(end -0.67945 -0.305054)
			(stroke
				(width 0.1)
				(type default)
			)
			(layer "F.Fab")
		)
		(fp_line
			(start -0.67945 -0.305054)
			(end -0.12065 -0.305054)
			(stroke
				(width 0.1)
				(type default)
			)
			(layer "F.Fab")
		)
		(pad "1" smd circle
			(at -0.40005 0 180)
			(size 0 0)
			(layers "F.Cu" "F.Mask" "F.Paste")
			(net "PWRGD_PCH_PWROK")
		)
		(pad "2" smd circle
			(at 0.40005 0 180)
			(size 0 0)
			(layers "F.Cu" "F.Mask" "F.Paste")
			(net "GND")
		)
	)
	(footprint ""
		(layer "F.Cu")
		(at 284.39491 -94.42069)
		(property "Reference" "U64"
			(at -1.4986 -3.597148 0)
			(unlocked yes)
			(layer "F.SilkS")
			(effects
				(font
					(size 0.7874 0.5842)
					(thickness 0.1524)
				)
				(justify left)
			)
		)
		(property "Value" ""
			(at 0 0 0)
			(layer "F.Fab")
			(effects
				(font
					(size 1.27 1.27)
				)
			)
		)
		(duplicate_pad_numbers_are_jumpers no)
		(fp_line
			(start -1.8288 -2.500122)
			(end -1.8288 2.500122)
			(stroke
				(width 0.1524)
				(type default)
			)
			(layer "F.SilkS")
		)
		(fp_line
			(start -1.8288 2.500122)
			(end 1.8288 2.500122)
			(stroke
				(width 0.1524)
				(type default)
			)
			(layer "F.SilkS")
		)
		(fp_line
			(start -1.077722 -2.500122)
			(end -1.8288 -2.500122)
			(stroke
				(width 0.1524)
				(type default)
			)
			(layer "F.SilkS")
		)
		(fp_line
			(start 0 -1.4224)
			(end -1.077722 -2.500122)
			(stroke
				(width 0.1524)
				(type default)
			)
			(layer "F.SilkS")
		)
		(fp_line
			(start 1.077722 -2.500122)
			(end 0 -1.4224)
			(stroke
				(width 0.1524)
				(type default)
			)
			(layer "F.SilkS")
		)
		(fp_line
			(start 1.8288 -2.500122)
			(end 1.077722 -2.500122)
			(stroke
				(width 0.1524)
				(type default)
			)
			(layer "F.SilkS")
		)
		(fp_line
			(start 1.8288 2.500122)
			(end 1.8288 -2.500122)
			(stroke
				(width 0.1524)
				(type default)
			)
			(layer "F.SilkS")
		)
		(fp_poly
			(pts
				(xy -2.291588 -3.983228) (xy -2.799588 -2.967228) (xy -3.307588 -3.983228)
			)
			(stroke
				(width 0)
				(type default)
			)
			(fill yes)
			(layer "F.SilkS")
		)
		(fp_line
			(start -1.999996 -2.500122)
			(end -1.999996 2.500122)
			(stroke
				(width 0.1)
				(type default)
			)
			(layer "F.Fab")
		)
		(fp_line
			(start -1.999996 2.500122)
			(end 1.999996 2.500122)
			(stroke
				(width 0.1)
				(type default)
			)
			(layer "F.Fab")
		)
		(fp_line
			(start 1.999996 -2.500122)
			(end -1.999996 -2.500122)
			(stroke
				(width 0.1)
				(type default)
			)
			(layer "F.Fab")
		)
		(fp_line
			(start 1.999996 2.500122)
			(end 1.999996 -2.500122)
			(stroke
				(width 0.1)
				(type default)
			)
			(layer "F.Fab")
		)
		(fp_poly
			(pts
				(xy -4.5085 -2.413) (xy -4.5085 -1.397) (xy -3.4925 -1.905)
			)
			(stroke
				(width 0)
				(type default)
			)
			(fill yes)
			(layer "F.Fab")
		)
		(pad "1" smd rect
			(at -2.599944 -1.905 270)
			(size 0.889 1.27)
			(layers "F.Cu" "F.Mask" "F.Paste")
			(net "MB_FRU_ADDR0")
		)
		(pad "2" smd rect
			(at -2.599944 -0.635 270)
			(size 0.889 1.27)
			(layers "F.Cu" "F.Mask" "F.Paste")
			(net "MB_FRU_ADDR1")
		)
		(pad "3" smd rect
			(at -2.599944 0.635 270)
			(size 0.889 1.27)
			(layers "F.Cu" "F.Mask" "F.Paste")
			(net "MB_FRU_ADDR2")
		)
		(pad "4" smd rect
			(at -2.599944 1.905 270)
			(size 0.889 1.27)
			(layers "F.Cu" "F.Mask" "F.Paste")
			(net "GND")
		)
		(pad "5" smd rect
			(at 2.599944 1.905 270)
			(size 0.889 1.27)
			(layers "F.Cu" "F.Mask" "F.Paste")
			(net "SMB_FRU_3V3AUX_SDA")
		)
		(pad "6" smd rect
			(at 2.599944 0.635 270)
			(size 0.889 1.27)
			(layers "F.Cu" "F.Mask" "F.Paste")
			(net "SMB_FRU_3V3AUX_SCL")
		)
		(pad "7" smd rect
			(at 2.599944 -0.635 270)
			(size 0.889 1.27)
			(layers "F.Cu" "F.Mask" "F.Paste")
			(net "PD_MB_FRU_WP")
		)
		(pad "8" smd rect
			(at 2.599944 -1.905 270)
			(size 0.889 1.27)
			(layers "F.Cu" "F.Mask" "F.Paste")
			(net "P3V3_AUX")
		)
	)
	(footprint ""
		(layer "F.Cu")
		(at 6.43128 -37.252148)
		(property "Reference" ""
			(at 0 0 0)
			(layer "F.SilkS")
			(hide yes)
			(effects
				(font
					(size 1.27 1.27)
				)
			)
		)
		(property "Value" ""
			(at 0 0 0)
			(layer "F.Fab")
			(effects
				(font
					(size 1.27 1.27)
				)
			)
		)
		(duplicate_pad_numbers_are_jumpers no)
		(pad "1" smd circle
			(at 0 0)
			(size 0.9906 0.9906)
			(layers "F.Cu" "F.Mask" "F.Paste")
			(net "Net_8482")
		)
		(zone
			(layer "F.Cu")
			(hatch none 0.5)
			(connect_pads
				(clearance 0)
			)
			(min_thickness 0.25)
			(keepout
				(tracks not_allowed)
				(vias allowed)
				(pads allowed)
				(copperpour not_allowed)
				(footprints allowed)
			)
			(placement
				(enabled no)
				(sheetname "")
			)
			(fill
				(thermal_gap 0.5)
				(thermal_bridge_width 0.5)
				(island_removal_mode 0)
			)
			(polygon
				(pts
					(arc
						(start 8.05688 -37.252148)
						(mid 4.80568 -37.252148)
						(end 8.05688 -37.252148)
					)
				)
			)
		)
	)
	(footprint ""
		(layer "F.Cu")
		(at 454.662794 -384.301492 -90)
		(property "Reference" "PC1846"
			(at 0 0 270)
			(layer "F.SilkS")
			(hide yes)
			(effects
				(font
					(size 1.27 1.27)
				)
			)
		)
		(property "Value" ""
			(at 0 0 270)
			(layer "F.Fab")
			(effects
				(font
					(size 1.27 1.27)
				)
			)
		)
		(duplicate_pad_numbers_are_jumpers no)
		(fp_line
			(start -0.7874 0.4064)
			(end -0.7874 -0.4064)
			(stroke
				(width 0.1524)
				(type default)
			)
			(layer "F.SilkS")
		)
		(fp_line
			(start 0.7874 0.4064)
			(end -0.7874 0.4064)
			(stroke
				(width 0.1524)
				(type default)
			)
			(layer "F.SilkS")
		)
		(fp_line
			(start -0.7874 -0.4064)
			(end 0.7874 -0.4064)
			(stroke
				(width 0.1524)
				(type default)
			)
			(layer "F.SilkS")
		)
		(fp_line
			(start 0.7874 -0.4064)
			(end 0.7874 0.4064)
			(stroke
				(width 0.1524)
				(type default)
			)
			(layer "F.SilkS")
		)
		(fp_line
			(start -0.67945 0.3048)
			(end -0.67945 -0.305054)
			(stroke
				(width 0.1)
				(type default)
			)
			(layer "F.Fab")
		)
		(fp_line
			(start -0.12065 0.3048)
			(end -0.67945 0.3048)
			(stroke
				(width 0.1)
				(type default)
			)
			(layer "F.Fab")
		)
		(fp_line
			(start 0.120396 0.3048)
			(end 0.120396 0.2794)
			(stroke
				(width 0.1)
				(type default)
			)
			(layer "F.Fab")
		)
		(fp_line
			(start 0.67945 0.3048)
			(end 0.120396 0.3048)
			(stroke
				(width 0.1)
				(type default)
			)
			(layer "F.Fab")
		)
		(fp_line
			(start -0.12065 0.2794)
			(end -0.12065 0.3048)
			(stroke
				(width 0.1)
				(type default)
			)
			(layer "F.Fab")
		)
		(fp_line
			(start 0.120396 0.2794)
			(end -0.12065 0.2794)
			(stroke
				(width 0.1)
				(type default)
			)
			(layer "F.Fab")
		)
		(fp_line
			(start -0.12065 -0.2794)
			(end 0.12065 -0.2794)
			(stroke
				(width 0.1)
				(type default)
			)
			(layer "F.Fab")
		)
		(fp_line
			(start 0.12065 -0.2794)
			(end 0.12065 -0.3048)
			(stroke
				(width 0.1)
				(type default)
			)
			(layer "F.Fab")
		)
		(fp_line
			(start 0.12065 -0.3048)
			(end 0.67945 -0.3048)
			(stroke
				(width 0.1)
				(type default)
			)
			(layer "F.Fab")
		)
		(fp_line
			(start 0.67945 -0.3048)
			(end 0.67945 0.3048)
			(stroke
				(width 0.1)
				(type default)
			)
			(layer "F.Fab")
		)
		(fp_line
			(start -0.67945 -0.305054)
			(end -0.12065 -0.305054)
			(stroke
				(width 0.1)
				(type default)
			)
			(layer "F.Fab")
		)
		(fp_line
			(start -0.12065 -0.305054)
			(end -0.12065 -0.2794)
			(stroke
				(width 0.1)
				(type default)
			)
			(layer "F.Fab")
		)
		(pad "1" smd circle
			(at -0.40005 0 270)
			(size 0 0)
			(layers "F.Cu" "F.Mask" "F.Paste")
			(net "SW_P5V_AUX_FLT")
		)
		(pad "2" smd circle
			(at 0.40005 0 270)
			(size 0 0)
			(layers "F.Cu" "F.Mask" "F.Paste")
			(net "GND")
		)
	)
	(footprint ""
		(layer "F.Cu")
		(at 177.9524 -94.338648 90)
		(property "Reference" "R4585"
			(at 0 0 90)
			(layer "F.SilkS")
			(hide yes)
			(effects
				(font
					(size 1.27 1.27)
				)
			)
		)
		(property "Value" ""
			(at 0 0 90)
			(layer "F.Fab")
			(effects
				(font
					(size 1.27 1.27)
				)
			)
		)
		(duplicate_pad_numbers_are_jumpers no)
		(fp_line
			(start 0.7874 -0.4064)
			(end 0.7874 0.4064)
			(stroke
				(width 0.1524)
				(type default)
			)
			(layer "F.SilkS")
		)
		(fp_line
			(start -0.7874 -0.4064)
			(end 0.7874 -0.4064)
			(stroke
				(width 0.1524)
				(type default)
			)
			(layer "F.SilkS")
		)
		(fp_line
			(start 0.7874 0.4064)
			(end -0.7874 0.4064)
			(stroke
				(width 0.1524)
				(type default)
			)
			(layer "F.SilkS")
		)
		(fp_line
			(start -0.7874 0.4064)
			(end -0.7874 -0.4064)
			(stroke
				(width 0.1524)
				(type default)
			)
			(layer "F.SilkS")
		)
		(fp_line
			(start -0.12065 -0.305054)
			(end -0.12065 -0.2794)
			(stroke
				(width 0.1)
				(type default)
			)
			(layer "F.Fab")
		)
		(fp_line
			(start -0.67945 -0.305054)
			(end -0.12065 -0.305054)
			(stroke
				(width 0.1)
				(type default)
			)
			(layer "F.Fab")
		)
		(fp_line
			(start 0.67945 -0.3048)
			(end 0.67945 0.3048)
			(stroke
				(width 0.1)
				(type default)
			)
			(layer "F.Fab")
		)
		(fp_line
			(start 0.12065 -0.3048)
			(end 0.67945 -0.3048)
			(stroke
				(width 0.1)
				(type default)
			)
			(layer "F.Fab")
		)
		(fp_line
			(start 0.12065 -0.2794)
			(end 0.12065 -0.3048)
			(stroke
				(width 0.1)
				(type default)
			)
			(layer "F.Fab")
		)
		(fp_line
			(start -0.12065 -0.2794)
			(end 0.12065 -0.2794)
			(stroke
				(width 0.1)
				(type default)
			)
			(layer "F.Fab")
		)
		(fp_line
			(start 0.120396 0.2794)
			(end -0.12065 0.2794)
			(stroke
				(width 0.1)
				(type default)
			)
			(layer "F.Fab")
		)
		(fp_line
			(start -0.12065 0.2794)
			(end -0.12065 0.3048)
			(stroke
				(width 0.1)
				(type default)
			)
			(layer "F.Fab")
		)
		(fp_line
			(start 0.67945 0.3048)
			(end 0.120396 0.3048)
			(stroke
				(width 0.1)
				(type default)
			)
			(layer "F.Fab")
		)
		(fp_line
			(start 0.120396 0.3048)
			(end 0.120396 0.2794)
			(stroke
				(width 0.1)
				(type default)
			)
			(layer "F.Fab")
		)
		(fp_line
			(start -0.12065 0.3048)
			(end -0.67945 0.3048)
			(stroke
				(width 0.1)
				(type default)
			)
			(layer "F.Fab")
		)
		(fp_line
			(start -0.67945 0.3048)
			(end -0.67945 -0.305054)
			(stroke
				(width 0.1)
				(type default)
			)
			(layer "F.Fab")
		)
		(pad "1" smd rect
			(at -0.40005 0 270)
			(size 0.4572 0.508)
			(layers "F.Cu" "F.Mask" "F.Paste")
			(net "FM_BOARD_BMC_SKU_ID0")
		)
		(pad "2" smd rect
			(at 0.40005 0 270)
			(size 0.4572 0.508)
			(layers "F.Cu" "F.Mask" "F.Paste")
			(net "GND")
		)
	)
	(footprint ""
		(layer "F.Cu")
		(at 193.93408 -351.551748 180)
		(property "Reference" "R625"
			(at 0 0 180)
			(layer "F.SilkS")
			(hide yes)
			(effects
				(font
					(size 1.27 1.27)
				)
			)
		)
		(property "Value" ""
			(at 0 0 180)
			(layer "F.Fab")
			(effects
				(font
					(size 1.27 1.27)
				)
			)
		)
		(duplicate_pad_numbers_are_jumpers no)
		(fp_line
			(start 0.7874 0.4064)
			(end -0.7874 0.4064)
			(stroke
				(width 0.1524)
				(type default)
			)
			(layer "F.SilkS")
		)
		(fp_line
			(start 0.7874 -0.4064)
			(end 0.7874 0.4064)
			(stroke
				(width 0.1524)
				(type default)
			)
			(layer "F.SilkS")
		)
		(fp_line
			(start -0.7874 0.4064)
			(end -0.7874 -0.4064)
			(stroke
				(width 0.1524)
				(type default)
			)
			(layer "F.SilkS")
		)
		(fp_line
			(start -0.7874 -0.4064)
			(end 0.7874 -0.4064)
			(stroke
				(width 0.1524)
				(type default)
			)
			(layer "F.SilkS")
		)
		(fp_line
			(start 0.67945 0.3048)
			(end 0.120396 0.3048)
			(stroke
				(width 0.1)
				(type default)
			)
			(layer "F.Fab")
		)
		(fp_line
			(start 0.67945 -0.3048)
			(end 0.67945 0.3048)
			(stroke
				(width 0.1)
				(type default)
			)
			(layer "F.Fab")
		)
		(fp_line
			(start 0.12065 -0.2794)
			(end 0.12065 -0.3048)
			(stroke
				(width 0.1)
				(type default)
			)
			(layer "F.Fab")
		)
		(fp_line
			(start 0.12065 -0.3048)
			(end 0.67945 -0.3048)
			(stroke
				(width 0.1)
				(type default)
			)
			(layer "F.Fab")
		)
		(fp_line
			(start 0.120396 0.3048)
			(end 0.120396 0.2794)
			(stroke
				(width 0.1)
				(type default)
			)
			(layer "F.Fab")
		)
		(fp_line
			(start 0.120396 0.2794)
			(end -0.12065 0.2794)
			(stroke
				(width 0.1)
				(type default)
			)
			(layer "F.Fab")
		)
		(fp_line
			(start -0.12065 0.3048)
			(end -0.67945 0.3048)
			(stroke
				(width 0.1)
				(type default)
			)
			(layer "F.Fab")
		)
		(fp_line
			(start -0.12065 0.2794)
			(end -0.12065 0.3048)
			(stroke
				(width 0.1)
				(type default)
			)
			(layer "F.Fab")
		)
		(fp_line
			(start -0.12065 -0.2794)
			(end 0.12065 -0.2794)
			(stroke
				(width 0.1)
				(type default)
			)
			(layer "F.Fab")
		)
		(fp_line
			(start -0.12065 -0.305054)
			(end -0.12065 -0.2794)
			(stroke
				(width 0.1)
				(type default)
			)
			(layer "F.Fab")
		)
		(fp_line
			(start -0.67945 0.3048)
			(end -0.67945 -0.305054)
			(stroke
				(width 0.1)
				(type default)
			)
			(layer "F.Fab")
		)
		(fp_line
			(start -0.67945 -0.305054)
			(end -0.12065 -0.305054)
			(stroke
				(width 0.1)
				(type default)
			)
			(layer "F.Fab")
		)
		(pad "1" smd circle
			(at -0.40005 0 180)
			(size 0 0)
			(layers "F.Cu" "F.Mask" "F.Paste")
			(net "P3V3_AUX")
		)
		(pad "2" smd circle
			(at 0.40005 0 180)
			(size 0 0)
			(layers "F.Cu" "F.Mask" "F.Paste")
			(net "PD_PIROM_CPU1_ADDR2")
		)
	)
	(footprint ""
		(layer "F.Cu")
		(at 325.193914 -25.102312)
		(property "Reference" "R1202"
			(at 0 0 0)
			(layer "F.SilkS")
			(hide yes)
			(effects
				(font
					(size 1.27 1.27)
				)
			)
		)
		(property "Value" ""
			(at 0 0 0)
			(layer "F.Fab")
			(effects
				(font
					(size 1.27 1.27)
				)
			)
		)
		(duplicate_pad_numbers_are_jumpers no)
		(fp_line
			(start -0.7874 -0.4064)
			(end 0.7874 -0.4064)
			(stroke
				(width 0.1524)
				(type default)
			)
			(layer "F.SilkS")
		)
		(fp_line
			(start -0.7874 0.4064)
			(end -0.7874 -0.4064)
			(stroke
				(width 0.1524)
				(type default)
			)
			(layer "F.SilkS")
		)
		(fp_line
			(start 0.7874 -0.4064)
			(end 0.7874 0.4064)
			(stroke
				(width 0.1524)
				(type default)
			)
			(layer "F.SilkS")
		)
		(fp_line
			(start 0.7874 0.4064)
			(end -0.7874 0.4064)
			(stroke
				(width 0.1524)
				(type default)
			)
			(layer "F.SilkS")
		)
		(fp_line
			(start -0.67945 -0.305054)
			(end -0.12065 -0.305054)
			(stroke
				(width 0.1)
				(type default)
			)
			(layer "F.Fab")
		)
		(fp_line
			(start -0.67945 0.3048)
			(end -0.67945 -0.305054)
			(stroke
				(width 0.1)
				(type default)
			)
			(layer "F.Fab")
		)
		(fp_line
			(start -0.12065 -0.305054)
			(end -0.12065 -0.2794)
			(stroke
				(width 0.1)
				(type default)
			)
			(layer "F.Fab")
		)
		(fp_line
			(start -0.12065 -0.2794)
			(end 0.12065 -0.2794)
			(stroke
				(width 0.1)
				(type default)
			)
			(layer "F.Fab")
		)
		(fp_line
			(start -0.12065 0.2794)
			(end -0.12065 0.3048)
			(stroke
				(width 0.1)
				(type default)
			)
			(layer "F.Fab")
		)
		(fp_line
			(start -0.12065 0.3048)
			(end -0.67945 0.3048)
			(stroke
				(width 0.1)
				(type default)
			)
			(layer "F.Fab")
		)
		(fp_line
			(start 0.120396 0.2794)
			(end -0.12065 0.2794)
			(stroke
				(width 0.1)
				(type default)
			)
			(layer "F.Fab")
		)
		(fp_line
			(start 0.120396 0.3048)
			(end 0.120396 0.2794)
			(stroke
				(width 0.1)
				(type default)
			)
			(layer "F.Fab")
		)
		(fp_line
			(start 0.12065 -0.3048)
			(end 0.67945 -0.3048)
			(stroke
				(width 0.1)
				(type default)
			)
			(layer "F.Fab")
		)
		(fp_line
			(start 0.12065 -0.2794)
			(end 0.12065 -0.3048)
			(stroke
				(width 0.1)
				(type default)
			)
			(layer "F.Fab")
		)
		(fp_line
			(start 0.67945 -0.3048)
			(end 0.67945 0.3048)
			(stroke
				(width 0.1)
				(type default)
			)
			(layer "F.Fab")
		)
		(fp_line
			(start 0.67945 0.3048)
			(end 0.120396 0.3048)
			(stroke
				(width 0.1)
				(type default)
			)
			(layer "F.Fab")
		)
		(pad "1" smd circle
			(at -0.40005 0)
			(size 0 0)
			(layers "F.Cu" "F.Mask" "F.Paste")
			(net "P3V3_RTC_AUX")
		)
		(pad "2" smd circle
			(at 0.40005 0)
			(size 0 0)
			(layers "F.Cu" "F.Mask" "F.Paste")
			(net "RST_SRTCRST_N")
		)
	)
	(footprint ""
		(layer "F.Cu")
		(at 123.96978 -113.121948 -90)
		(property "Reference" "U305"
			(at -2.09169 -3.21818 0)
			(unlocked yes)
			(layer "F.SilkS")
			(effects
				(font
					(size 0.7874 0.5842)
					(thickness 0.1524)
				)
				(justify left)
			)
		)
		(property "Value" ""
			(at 0 0 270)
			(layer "F.Fab")
			(effects
				(font
					(size 1.27 1.27)
				)
			)
		)
		(duplicate_pad_numbers_are_jumpers no)
		(fp_line
			(start -2.0066 2.5527)
			(end -2.0066 -2.5527)
			(stroke
				(width 0.1524)
				(type default)
			)
			(layer "F.SilkS")
		)
		(fp_line
			(start 2.0066 2.5527)
			(end -2.0066 2.5527)
			(stroke
				(width 0.1524)
				(type default)
			)
			(layer "F.SilkS")
		)
		(fp_line
			(start 0 -1.9812)
			(end 0.5715 -2.5527)
			(stroke
				(width 0.1524)
				(type default)
			)
			(layer "F.SilkS")
		)
		(fp_line
			(start -2.0066 -2.5527)
			(end -0.5715 -2.5527)
			(stroke
				(width 0.1524)
				(type default)
			)
			(layer "F.SilkS")
		)
		(fp_line
			(start -0.5715 -2.5527)
			(end 0 -1.9812)
			(stroke
				(width 0.1524)
				(type default)
			)
			(layer "F.SilkS")
		)
		(fp_line
			(start 0.5715 -2.5527)
			(end 2.0066 -2.5527)
			(stroke
				(width 0.1524)
				(type default)
			)
			(layer "F.SilkS")
		)
		(fp_line
			(start 2.0066 -2.5527)
			(end 2.0066 2.5527)
			(stroke
				(width 0.1524)
				(type default)
			)
			(layer "F.SilkS")
		)
		(fp_poly
			(pts
				(xy -4.36372 -2.233168) (xy -3.81 -1.905) (xy -4.36372 -1.608328)
			)
			(stroke
				(width 0)
				(type default)
			)
			(fill yes)
			(layer "F.SilkS")
		)
		(fp_line
			(start -2.249932 2.549906)
			(end -2.249932 -2.549906)
			(stroke
				(width 0.1)
				(type default)
			)
			(layer "F.Fab")
		)
		(fp_line
			(start 2.249932 2.549906)
			(end -2.249932 2.549906)
			(stroke
				(width 0.1)
				(type default)
			)
			(layer "F.Fab")
		)
		(fp_line
			(start -2.249932 -2.549906)
			(end 2.249932 -2.549906)
			(stroke
				(width 0.1)
				(type default)
			)
			(layer "F.Fab")
		)
		(fp_line
			(start 2.249932 -2.549906)
			(end 2.249932 2.549906)
			(stroke
				(width 0.1)
				(type default)
			)
			(layer "F.Fab")
		)
		(fp_poly
			(pts
				(xy -4.36372 -1.608328) (xy -4.36372 -2.233168) (xy -3.81 -1.905)
			)
			(stroke
				(width 0)
				(type default)
			)
			(fill yes)
			(layer "F.Fab")
		)
		(pad "1" smd rect
			(at -2.921 -1.949958 180)
			(size 0.3556 1.4986)
			(layers "F.Cu" "F.Mask" "F.Paste")
			(net "PD_GTL2014_BMC_JTAG_DIR_1")
		)
		(pad "2" smd rect
			(at -2.921 -1.299972 180)
			(size 0.3556 1.4986)
			(layers "F.Cu" "F.Mask" "F.Paste")
			(net "RST_CPU1_DRAM_GH_PLD_N")
		)
		(pad "3" smd rect
			(at -2.921 -0.649986 180)
			(size 0.3556 1.4986)
			(layers "F.Cu" "F.Mask" "F.Paste")
			(net "RST_CPU1_DRAM_EF_PLD_N")
		)
		(pad "4" smd rect
			(at -2.921 0 180)
			(size 0.3556 1.4986)
			(layers "F.Cu" "F.Mask" "F.Paste")
			(net "P0V62_CPU1_RST_DDR_VREF")
		)
		(pad "5" smd rect
			(at -2.921 0.649986 180)
			(size 0.3556 1.4986)
			(layers "F.Cu" "F.Mask" "F.Paste")
			(net "RST_CPU1_DRAM_CD_PLD_N")
		)
		(pad "6" smd rect
			(at -2.921 1.299972 180)
			(size 0.3556 1.4986)
			(layers "F.Cu" "F.Mask" "F.Paste")
			(net "RST_CPU1_DRAM_AB_PLD_N")
		)
		(pad "7" smd rect
			(at -2.921 1.949958 180)
			(size 0.3556 1.4986)
			(layers "F.Cu" "F.Mask" "F.Paste")
			(net "GND")
		)
		(pad "8" smd rect
			(at 2.921 1.949958 180)
			(size 0.3556 1.4986)
			(layers "F.Cu" "F.Mask" "F.Paste")
			(net "GND")
		)
		(pad "9" smd rect
			(at 2.921 1.299972 180)
			(size 0.3556 1.4986)
			(layers "F.Cu" "F.Mask" "F.Paste")
			(net "RST_CPU1_DRAM_AB_PLD_LVT3_R_N")
		)
		(pad "10" smd rect
			(at 2.921 0.649986 180)
			(size 0.3556 1.4986)
			(layers "F.Cu" "F.Mask" "F.Paste")
			(net "RST_CPU1_DRAM_CD_PLD_LVT3_R_N")
		)
		(pad "11" smd rect
			(at 2.921 0 180)
			(size 0.3556 1.4986)
			(layers "F.Cu" "F.Mask" "F.Paste")
			(net "GND")
		)
		(pad "12" smd rect
			(at 2.921 -0.649986 180)
			(size 0.3556 1.4986)
			(layers "F.Cu" "F.Mask" "F.Paste")
			(net "RST_CPU1_DRAM_EF_PLD_LVT3_R_N")
		)
		(pad "13" smd rect
			(at 2.921 -1.299972 180)
			(size 0.3556 1.4986)
			(layers "F.Cu" "F.Mask" "F.Paste")
			(net "RST_CPU1_DRAM_GH_PLD_LVT3_R_N")
		)
		(pad "14" smd rect
			(at 2.921 -1.949958 180)
			(size 0.3556 1.4986)
			(layers "F.Cu" "F.Mask" "F.Paste")
			(net "P3V3_AUX")
		)
	)
	(footprint ""
		(layer "F.Cu")
		(at 391.08888 -148.808948 -90)
		(property "Reference" "R1648"
			(at 0 0 270)
			(layer "F.SilkS")
			(hide yes)
			(effects
				(font
					(size 1.27 1.27)
				)
			)
		)
		(property "Value" ""
			(at 0 0 270)
			(layer "F.Fab")
			(effects
				(font
					(size 1.27 1.27)
				)
			)
		)
		(duplicate_pad_numbers_are_jumpers no)
		(fp_line
			(start -0.7874 0.4064)
			(end -0.7874 -0.4064)
			(stroke
				(width 0.1524)
				(type default)
			)
			(layer "F.SilkS")
		)
		(fp_line
			(start 0.7874 0.4064)
			(end -0.7874 0.4064)
			(stroke
				(width 0.1524)
				(type default)
			)
			(layer "F.SilkS")
		)
		(fp_line
			(start -0.7874 -0.4064)
			(end 0.7874 -0.4064)
			(stroke
				(width 0.1524)
				(type default)
			)
			(layer "F.SilkS")
		)
		(fp_line
			(start 0.7874 -0.4064)
			(end 0.7874 0.4064)
			(stroke
				(width 0.1524)
				(type default)
			)
			(layer "F.SilkS")
		)
		(fp_line
			(start -0.67945 0.3048)
			(end -0.67945 -0.305054)
			(stroke
				(width 0.1)
				(type default)
			)
			(layer "F.Fab")
		)
		(fp_line
			(start -0.12065 0.3048)
			(end -0.67945 0.3048)
			(stroke
				(width 0.1)
				(type default)
			)
			(layer "F.Fab")
		)
		(fp_line
			(start 0.120396 0.3048)
			(end 0.120396 0.2794)
			(stroke
				(width 0.1)
				(type default)
			)
			(layer "F.Fab")
		)
		(fp_line
			(start 0.67945 0.3048)
			(end 0.120396 0.3048)
			(stroke
				(width 0.1)
				(type default)
			)
			(layer "F.Fab")
		)
		(fp_line
			(start -0.12065 0.2794)
			(end -0.12065 0.3048)
			(stroke
				(width 0.1)
				(type default)
			)
			(layer "F.Fab")
		)
		(fp_line
			(start 0.120396 0.2794)
			(end -0.12065 0.2794)
			(stroke
				(width 0.1)
				(type default)
			)
			(layer "F.Fab")
		)
		(fp_line
			(start -0.12065 -0.2794)
			(end 0.12065 -0.2794)
			(stroke
				(width 0.1)
				(type default)
			)
			(layer "F.Fab")
		)
		(fp_line
			(start 0.12065 -0.2794)
			(end 0.12065 -0.3048)
			(stroke
				(width 0.1)
				(type default)
			)
			(layer "F.Fab")
		)
		(fp_line
			(start 0.12065 -0.3048)
			(end 0.67945 -0.3048)
			(stroke
				(width 0.1)
				(type default)
			)
			(layer "F.Fab")
		)
		(fp_line
			(start 0.67945 -0.3048)
			(end 0.67945 0.3048)
			(stroke
				(width 0.1)
				(type default)
			)
			(layer "F.Fab")
		)
		(fp_line
			(start -0.67945 -0.305054)
			(end -0.12065 -0.305054)
			(stroke
				(width 0.1)
				(type default)
			)
			(layer "F.Fab")
		)
		(fp_line
			(start -0.12065 -0.305054)
			(end -0.12065 -0.2794)
			(stroke
				(width 0.1)
				(type default)
			)
			(layer "F.Fab")
		)
		(pad "1" smd circle
			(at -0.40005 0 270)
			(size 0 0)
			(layers "F.Cu" "F.Mask" "F.Paste")
			(net "SMB_S3M_CPU0_3V3AUX_SDA")
		)
		(pad "2" smd circle
			(at 0.40005 0 270)
			(size 0 0)
			(layers "F.Cu" "F.Mask" "F.Paste")
			(net "SMB_S3M_CPU1_3V3AUX_SDA")
		)
	)
	(footprint ""
		(layer "F.Cu")
		(at 62.861698 -26.99004 90)
		(property "Reference" "PR3853"
			(at 0 0 90)
			(layer "F.SilkS")
			(hide yes)
			(effects
				(font
					(size 1.27 1.27)
				)
			)
		)
		(property "Value" ""
			(at 0 0 90)
			(layer "F.Fab")
			(effects
				(font
					(size 1.27 1.27)
				)
			)
		)
		(duplicate_pad_numbers_are_jumpers no)
		(fp_line
			(start 0.7874 -0.4064)
			(end 0.7874 0.4064)
			(stroke
				(width 0.1524)
				(type default)
			)
			(layer "F.SilkS")
		)
		(fp_line
			(start -0.7874 -0.4064)
			(end 0.7874 -0.4064)
			(stroke
				(width 0.1524)
				(type default)
			)
			(layer "F.SilkS")
		)
		(fp_line
			(start 0.7874 0.4064)
			(end -0.7874 0.4064)
			(stroke
				(width 0.1524)
				(type default)
			)
			(layer "F.SilkS")
		)
		(fp_line
			(start -0.7874 0.4064)
			(end -0.7874 -0.4064)
			(stroke
				(width 0.1524)
				(type default)
			)
			(layer "F.SilkS")
		)
		(fp_line
			(start -0.12065 -0.305054)
			(end -0.12065 -0.2794)
			(stroke
				(width 0.1)
				(type default)
			)
			(layer "F.Fab")
		)
		(fp_line
			(start -0.67945 -0.305054)
			(end -0.12065 -0.305054)
			(stroke
				(width 0.1)
				(type default)
			)
			(layer "F.Fab")
		)
		(fp_line
			(start 0.67945 -0.3048)
			(end 0.67945 0.3048)
			(stroke
				(width 0.1)
				(type default)
			)
			(layer "F.Fab")
		)
		(fp_line
			(start 0.12065 -0.3048)
			(end 0.67945 -0.3048)
			(stroke
				(width 0.1)
				(type default)
			)
			(layer "F.Fab")
		)
		(fp_line
			(start 0.12065 -0.2794)
			(end 0.12065 -0.3048)
			(stroke
				(width 0.1)
				(type default)
			)
			(layer "F.Fab")
		)
		(fp_line
			(start -0.12065 -0.2794)
			(end 0.12065 -0.2794)
			(stroke
				(width 0.1)
				(type default)
			)
			(layer "F.Fab")
		)
		(fp_line
			(start 0.120396 0.2794)
			(end -0.12065 0.2794)
			(stroke
				(width 0.1)
				(type default)
			)
			(layer "F.Fab")
		)
		(fp_line
			(start -0.12065 0.2794)
			(end -0.12065 0.3048)
			(stroke
				(width 0.1)
				(type default)
			)
			(layer "F.Fab")
		)
		(fp_line
			(start 0.67945 0.3048)
			(end 0.120396 0.3048)
			(stroke
				(width 0.1)
				(type default)
			)
			(layer "F.Fab")
		)
		(fp_line
			(start 0.120396 0.3048)
			(end 0.120396 0.2794)
			(stroke
				(width 0.1)
				(type default)
			)
			(layer "F.Fab")
		)
		(fp_line
			(start -0.12065 0.3048)
			(end -0.67945 0.3048)
			(stroke
				(width 0.1)
				(type default)
			)
			(layer "F.Fab")
		)
		(fp_line
			(start -0.67945 0.3048)
			(end -0.67945 -0.305054)
			(stroke
				(width 0.1)
				(type default)
			)
			(layer "F.Fab")
		)
		(pad "1" smd circle
			(at -0.40005 0 90)
			(size 0 0)
			(layers "F.Cu" "F.Mask" "F.Paste")
			(net "P12V_AUX")
		)
		(pad "2" smd circle
			(at 0.40005 0 90)
			(size 0 0)
			(layers "F.Cu" "F.Mask" "F.Paste")
			(net "P12V_OCP_OV_FB_2")
		)
	)
	(footprint ""
		(layer "F.Cu")
		(at 137.800334 -342.917018)
		(property "Reference" "PU23_P1_8"
			(at 0.53848 -6.47827 0)
			(unlocked yes)
			(layer "F.SilkS")
			(effects
				(font
					(size 0.7874 0.5842)
					(thickness 0.1524)
				)
				(justify left)
			)
		)
		(property "Value" ""
			(at 0 0 0)
			(layer "F.Fab")
			(effects
				(font
					(size 1.27 1.27)
				)
			)
		)
		(duplicate_pad_numbers_are_jumpers no)
		(fp_line
			(start -2.500122 -2.999994)
			(end -2.24409 -2.999994)
			(stroke
				(width 0.1524)
				(type default)
			)
			(layer "F.SilkS")
		)
		(fp_line
			(start -2.500122 -2.529078)
			(end -2.500122 -2.999994)
			(stroke
				(width 0.1524)
				(type default)
			)
			(layer "F.SilkS")
		)
		(fp_line
			(start -2.500122 0.6604)
			(end -2.500122 0.229108)
			(stroke
				(width 0.1524)
				(type default)
			)
			(layer "F.SilkS")
		)
		(fp_line
			(start -2.500122 2.999994)
			(end -2.500122 2.339594)
			(stroke
				(width 0.1524)
				(type default)
			)
			(layer "F.SilkS")
		)
		(fp_line
			(start -2.2987 2.999994)
			(end -2.500122 2.999994)
			(stroke
				(width 0.1524)
				(type default)
			)
			(layer "F.SilkS")
		)
		(fp_line
			(start 2.31394 -2.999994)
			(end 2.500122 -2.999994)
			(stroke
				(width 0.1524)
				(type default)
			)
			(layer "F.SilkS")
		)
		(fp_line
			(start 2.500122 -2.999994)
			(end 2.500122 -2.44348)
			(stroke
				(width 0.1524)
				(type default)
			)
			(layer "F.SilkS")
		)
		(fp_line
			(start 2.500122 2.339594)
			(end 2.500122 2.999994)
			(stroke
				(width 0.1524)
				(type default)
			)
			(layer "F.SilkS")
		)
		(fp_line
			(start 2.500122 2.999994)
			(end 2.2987 2.999994)
			(stroke
				(width 0.1524)
				(type default)
			)
			(layer "F.SilkS")
		)
		(fp_poly
			(pts
				(xy -2.234946 -3.650488) (xy -2.742946 -2.634488) (xy -3.250946 -3.650488)
			)
			(stroke
				(width 0)
				(type default)
			)
			(fill yes)
			(layer "F.SilkS")
		)
		(fp_line
			(start -2.500122 -2.999994)
			(end 2.500122 -2.999994)
			(stroke
				(width 0.1)
				(type default)
			)
			(layer "F.Fab")
		)
		(fp_line
			(start -2.500122 2.999994)
			(end -2.500122 -2.999994)
			(stroke
				(width 0.1)
				(type default)
			)
			(layer "F.Fab")
		)
		(fp_line
			(start 2.500122 -2.999994)
			(end 2.500122 2.999994)
			(stroke
				(width 0.1)
				(type default)
			)
			(layer "F.Fab")
		)
		(fp_line
			(start 2.500122 2.999994)
			(end -2.500122 2.999994)
			(stroke
				(width 0.1)
				(type default)
			)
			(layer "F.Fab")
		)
		(fp_poly
			(pts
				(xy -4.218432 -2.783078) (xy -4.218432 -1.767078) (xy -3.202432 -2.275078)
			)
			(stroke
				(width 0)
				(type default)
			)
			(fill yes)
			(layer "F.Fab")
		)
		(pad "1" smd rect
			(at -2.400046 -2.275078 90)
			(size 0.2286 0.6096)
			(layers "F.Cu" "F.Mask" "F.Paste")
			(net "PVCCIN_CPU1_VOS8")
		)
		(pad "2" smd rect
			(at -2.400046 -1.82499 90)
			(size 0.2286 0.6096)
			(layers "F.Cu" "F.Mask" "F.Paste")
			(net "GND")
		)
		(pad "3" smd rect
			(at -2.400046 -1.374902 90)
			(size 0.2286 0.6096)
			(layers "F.Cu" "F.Mask" "F.Paste")
			(net "PVCCIN_CPU1_VDD8")
		)
		(pad "4" smd rect
			(at -2.400046 -0.925068 90)
			(size 0.2286 0.6096)
			(layers "F.Cu" "F.Mask" "F.Paste")
			(net "PVCCIN_CPU1_PVCC")
		)
		(pad "5" smd rect
			(at -2.400046 -0.47498 90)
			(size 0.2286 0.6096)
			(layers "F.Cu" "F.Mask" "F.Paste")
			(net "GND")
		)
		(pad "6" smd rect
			(at -2.400046 -0.024892 90)
			(size 0.2286 0.6096)
			(layers "F.Cu" "F.Mask" "F.Paste")
			(net "Net_8541")
		)
		(pad "7_9-20_24" smd circle
			(at 0 1.150112 90)
			(size 0 0)
			(layers "F.Cu" "F.Mask" "F.Paste")
			(net "GND")
		)
		(pad "10_19" smd rect
			(at 0 2.899918 90)
			(size 0.6096 4.318)
			(layers "F.Cu" "F.Mask" "F.Paste")
			(net "SW_PVCCIN_CPU1_SW8")
		)
		(pad "25_29" smd rect
			(at 1.549908 -1.279906 270)
			(size 2.0574 2.3114)
			(layers "F.Cu" "F.Mask" "F.Paste")
			(net "SW_P12V_PVCCIN_CPU1_FLT")
		)
		(pad "30" smd rect
			(at 2.05994 -2.899918)
			(size 0.2286 0.6096)
			(layers "F.Cu" "F.Mask" "F.Paste")
			(net "SW_P12V_PVCCIN_CPU1_FLT")
		)
		(pad "31" smd rect
			(at 1.610106 -2.899918)
			(size 0.2286 0.6096)
			(layers "F.Cu" "F.Mask" "F.Paste")
			(net "Net_8542")
		)
		(pad "32" smd rect
			(at 1.160018 -2.899918)
			(size 0.2286 0.6096)
			(layers "F.Cu" "F.Mask" "F.Paste")
			(net "SW_PVCCIN_CPU1_BOOTR8")
		)
		(pad "33" smd rect
			(at 0.70993 -2.899918)
			(size 0.2286 0.6096)
			(layers "F.Cu" "F.Mask" "F.Paste")
			(net "SW_PVCCIN_CPU1_BOOT8")
		)
		(pad "34" smd rect
			(at 0.260096 -2.899918)
			(size 0.2286 0.6096)
			(layers "F.Cu" "F.Mask" "F.Paste")
			(net "PVCCIN_CPU1_PWM8")
		)
		(pad "35" smd rect
			(at -0.189992 -2.899918)
			(size 0.2286 0.6096)
			(layers "F.Cu" "F.Mask" "F.Paste")
			(net "PVCCIN_CPU1_VDD8")
		)
		(pad "36" smd rect
			(at -0.64008 -2.899918)
			(size 0.2286 0.6096)
			(layers "F.Cu" "F.Mask" "F.Paste")
			(net "PVCCIN_CPU1_ATSEN")
		)
		(pad "37" smd rect
			(at -1.089914 -2.899918)
			(size 0.2286 0.6096)
			(layers "F.Cu" "F.Mask" "F.Paste")
			(net "PVCCIN_CPU1_LSET8")
		)
		(pad "38" smd rect
			(at -1.540002 -2.899918)
			(size 0.2286 0.6096)
			(layers "F.Cu" "F.Mask" "F.Paste")
			(net "PVCCIN_CPU1_IMON8")
		)
		(pad "39" smd rect
			(at -1.99009 -2.899918)
			(size 0.2286 0.6096)
			(layers "F.Cu" "F.Mask" "F.Paste")
			(net "PVCCIN_CPU1_VREF")
		)
		(pad "40" smd rect
			(at -0.87503 -1.27508)
			(size 1.7526 1.9558)
			(layers "F.Cu" "F.Mask" "F.Paste")
			(net "GND")
		)
		(pad "41" smd rect
			(at -1.525016 0.249936 270)
			(size 0.3048 0.4572)
			(layers "F.Cu" "F.Mask" "F.Paste")
			(net "Net_8540")
		)
		(zone
			(layer "F.Cu")
			(hatch none 0.5)
			(connect_pads
				(clearance 0)
			)
			(min_thickness 0.25)
			(keepout
				(tracks not_allowed)
				(vias allowed)
				(pads allowed)
				(copperpour not_allowed)
				(footprints allowed)
			)
			(placement
				(enabled no)
				(sheetname "")
			)
			(fill
				(thermal_gap 0.5)
				(thermal_bridge_width 0.5)
				(island_removal_mode 0)
			)
			(polygon
				(pts
					(xy 135.300212 -339.917024) (xy 135.300212 -340.666324) (xy 140.300456 -340.666324) (xy 140.300456 -339.917024)
					(xy 140.010134 -339.917024) (xy 140.010134 -340.3727) (xy 135.590534 -340.3727) (xy 135.590534 -339.917024)
				)
			)
		)
		(zone
			(layer "F.Cu")
			(hatch none 0.5)
			(connect_pads
				(clearance 0)
			)
			(min_thickness 0.25)
			(keepout
				(tracks not_allowed)
				(vias allowed)
				(pads allowed)
				(copperpour not_allowed)
				(footprints allowed)
			)
			(placement
				(enabled no)
				(sheetname "")
			)
			(fill
				(thermal_gap 0.5)
				(thermal_bridge_width 0.5)
				(island_removal_mode 0)
			)
			(polygon
				(pts
					(xy 135.755888 -343.233248) (xy 135.998204 -343.233248) (xy 135.998204 -343.163398) (xy 136.78662 -343.163398)
					(xy 136.78662 -342.854788) (xy 136.849612 -342.854788) (xy 136.849612 -342.167718) (xy 135.300212 -342.167718)
					(xy 135.300212 -342.62441) (xy 135.995918 -342.62441) (xy 135.995918 -342.463882) (xy 136.554718 -342.463882)
					(xy 136.554718 -342.870282) (xy 135.995918 -342.870282) (xy 135.995918 -342.64981) (xy 135.300212 -342.64981)
					(xy 135.300212 -342.77681) (xy 135.755888 -342.77681)
				)
			)
		)
	)
	(footprint ""
		(layer "F.Cu")
		(at 95.095314 -419.722554 90)
		(property "Reference" "R3503"
			(at 0 0 90)
			(layer "F.SilkS")
			(hide yes)
			(effects
				(font
					(size 1.27 1.27)
				)
			)
		)
		(property "Value" ""
			(at 0 0 90)
			(layer "F.Fab")
			(effects
				(font
					(size 1.27 1.27)
				)
			)
		)
		(duplicate_pad_numbers_are_jumpers no)
		(fp_line
			(start 0.7874 -0.4064)
			(end 0.7874 0.4064)
			(stroke
				(width 0.1524)
				(type default)
			)
			(layer "F.SilkS")
		)
		(fp_line
			(start -0.7874 -0.4064)
			(end 0.7874 -0.4064)
			(stroke
				(width 0.1524)
				(type default)
			)
			(layer "F.SilkS")
		)
		(fp_line
			(start 0.7874 0.4064)
			(end -0.7874 0.4064)
			(stroke
				(width 0.1524)
				(type default)
			)
			(layer "F.SilkS")
		)
		(fp_line
			(start -0.7874 0.4064)
			(end -0.7874 -0.4064)
			(stroke
				(width 0.1524)
				(type default)
			)
			(layer "F.SilkS")
		)
		(fp_line
			(start -0.12065 -0.305054)
			(end -0.12065 -0.2794)
			(stroke
				(width 0.1)
				(type default)
			)
			(layer "F.Fab")
		)
		(fp_line
			(start -0.67945 -0.305054)
			(end -0.12065 -0.305054)
			(stroke
				(width 0.1)
				(type default)
			)
			(layer "F.Fab")
		)
		(fp_line
			(start 0.67945 -0.3048)
			(end 0.67945 0.3048)
			(stroke
				(width 0.1)
				(type default)
			)
			(layer "F.Fab")
		)
		(fp_line
			(start 0.12065 -0.3048)
			(end 0.67945 -0.3048)
			(stroke
				(width 0.1)
				(type default)
			)
			(layer "F.Fab")
		)
		(fp_line
			(start 0.12065 -0.2794)
			(end 0.12065 -0.3048)
			(stroke
				(width 0.1)
				(type default)
			)
			(layer "F.Fab")
		)
		(fp_line
			(start -0.12065 -0.2794)
			(end 0.12065 -0.2794)
			(stroke
				(width 0.1)
				(type default)
			)
			(layer "F.Fab")
		)
		(fp_line
			(start 0.120396 0.2794)
			(end -0.12065 0.2794)
			(stroke
				(width 0.1)
				(type default)
			)
			(layer "F.Fab")
		)
		(fp_line
			(start -0.12065 0.2794)
			(end -0.12065 0.3048)
			(stroke
				(width 0.1)
				(type default)
			)
			(layer "F.Fab")
		)
		(fp_line
			(start 0.67945 0.3048)
			(end 0.120396 0.3048)
			(stroke
				(width 0.1)
				(type default)
			)
			(layer "F.Fab")
		)
		(fp_line
			(start 0.120396 0.3048)
			(end 0.120396 0.2794)
			(stroke
				(width 0.1)
				(type default)
			)
			(layer "F.Fab")
		)
		(fp_line
			(start -0.12065 0.3048)
			(end -0.67945 0.3048)
			(stroke
				(width 0.1)
				(type default)
			)
			(layer "F.Fab")
		)
		(fp_line
			(start -0.67945 0.3048)
			(end -0.67945 -0.305054)
			(stroke
				(width 0.1)
				(type default)
			)
			(layer "F.Fab")
		)
		(pad "1" smd circle
			(at -0.40005 0 90)
			(size 0 0)
			(layers "F.Cu" "F.Mask" "F.Paste")
			(net "P3V3_AUX")
		)
		(pad "2" smd circle
			(at 0.40005 0 90)
			(size 0 0)
			(layers "F.Cu" "F.Mask" "F.Paste")
			(net "GPU_FPGA_EROT_FATALERR")
		)
	)
	(footprint ""
		(layer "F.Cu")
		(at 385.858004 -333.55153)
		(property "Reference" "PL7"
			(at 0.123444 6.322314 0)
			(unlocked yes)
			(layer "F.SilkS")
			(effects
				(font
					(size 0.7874 0.5842)
					(thickness 0.1524)
				)
				(justify left)
			)
		)
		(property "Value" ""
			(at 0 0 0)
			(layer "F.Fab")
			(effects
				(font
					(size 1.27 1.27)
				)
			)
		)
		(duplicate_pad_numbers_are_jumpers no)
		(fp_line
			(start -3.750056 -5.500116)
			(end -2.393442 -5.500116)
			(stroke
				(width 0.1524)
				(type default)
			)
			(layer "F.SilkS")
		)
		(fp_line
			(start -3.750056 5.500116)
			(end -3.750056 -5.500116)
			(stroke
				(width 0.1524)
				(type default)
			)
			(layer "F.SilkS")
		)
		(fp_line
			(start -2.393442 5.500116)
			(end -3.750056 5.500116)
			(stroke
				(width 0.1524)
				(type default)
			)
			(layer "F.SilkS")
		)
		(fp_line
			(start 2.393442 5.500116)
			(end 3.750056 5.500116)
			(stroke
				(width 0.1524)
				(type default)
			)
			(layer "F.SilkS")
		)
		(fp_line
			(start 3.750056 -5.500116)
			(end 2.393442 -5.500116)
			(stroke
				(width 0.1524)
				(type default)
			)
			(layer "F.SilkS")
		)
		(fp_line
			(start 3.750056 5.500116)
			(end 3.750056 -5.500116)
			(stroke
				(width 0.1524)
				(type default)
			)
			(layer "F.SilkS")
		)
		(fp_poly
			(pts
				(xy -4.8768 -5.720588) (xy -3.8608 -5.212588) (xy -4.8768 -4.704588)
			)
			(stroke
				(width 0)
				(type default)
			)
			(fill yes)
			(layer "F.SilkS")
		)
		(fp_line
			(start -3.750056 -5.500116)
			(end -3.750056 5.500116)
			(stroke
				(width 0.1)
				(type default)
			)
			(layer "F.Fab")
		)
		(fp_line
			(start -3.750056 5.500116)
			(end 3.750056 5.500116)
			(stroke
				(width 0.1)
				(type default)
			)
			(layer "F.Fab")
		)
		(fp_line
			(start 3.750056 -5.500116)
			(end -3.750056 -5.500116)
			(stroke
				(width 0.1)
				(type default)
			)
			(layer "F.Fab")
		)
		(fp_line
			(start 3.750056 5.500116)
			(end 3.750056 -5.500116)
			(stroke
				(width 0.1)
				(type default)
			)
			(layer "F.Fab")
		)
		(fp_poly
			(pts
				(xy -4.9276 -4.757928) (xy -4.9276 -3.741928) (xy -3.9116 -4.249928)
			)
			(stroke
				(width 0)
				(type default)
			)
			(fill yes)
			(layer "F.Fab")
		)
		(pad "1" smd rect
			(at 0 -4.249928 270)
			(size 2.413 4.5212)
			(layers "F.Cu" "F.Mask" "F.Paste")
			(net "SW_PVCCIN_CPU0_SW8")
		)
		(pad "2" smd rect
			(at 0 -1.175004 270)
			(size 1.3716 4.5212)
			(layers "F.Cu" "F.Mask" "F.Paste")
			(net "IND_P0_CPL8")
		)
		(pad "3" smd rect
			(at 0 1.175004 270)
			(size 1.3716 4.5212)
			(layers "F.Cu" "F.Mask" "F.Paste")
			(net "GND")
		)
		(pad "4" smd rect
			(at 0 4.249928 270)
			(size 2.413 4.5212)
			(layers "F.Cu" "F.Mask" "F.Paste")
			(net "PVCCIN_CPU0")
		)
	)
	(footprint ""
		(layer "F.Cu")
		(at 131.014216 -66.919602 90)
		(property "Reference" "R804"
			(at 0 0 90)
			(layer "F.SilkS")
			(hide yes)
			(effects
				(font
					(size 1.27 1.27)
				)
			)
		)
		(property "Value" ""
			(at 0 0 90)
			(layer "F.Fab")
			(effects
				(font
					(size 1.27 1.27)
				)
			)
		)
		(duplicate_pad_numbers_are_jumpers no)
		(fp_line
			(start 0.7874 -0.4064)
			(end 0.7874 0.4064)
			(stroke
				(width 0.1524)
				(type default)
			)
			(layer "F.SilkS")
		)
		(fp_line
			(start -0.7874 -0.4064)
			(end 0.7874 -0.4064)
			(stroke
				(width 0.1524)
				(type default)
			)
			(layer "F.SilkS")
		)
		(fp_line
			(start 0.7874 0.4064)
			(end -0.7874 0.4064)
			(stroke
				(width 0.1524)
				(type default)
			)
			(layer "F.SilkS")
		)
		(fp_line
			(start -0.7874 0.4064)
			(end -0.7874 -0.4064)
			(stroke
				(width 0.1524)
				(type default)
			)
			(layer "F.SilkS")
		)
		(fp_line
			(start -0.12065 -0.305054)
			(end -0.12065 -0.2794)
			(stroke
				(width 0.1)
				(type default)
			)
			(layer "F.Fab")
		)
		(fp_line
			(start -0.67945 -0.305054)
			(end -0.12065 -0.305054)
			(stroke
				(width 0.1)
				(type default)
			)
			(layer "F.Fab")
		)
		(fp_line
			(start 0.67945 -0.3048)
			(end 0.67945 0.3048)
			(stroke
				(width 0.1)
				(type default)
			)
			(layer "F.Fab")
		)
		(fp_line
			(start 0.12065 -0.3048)
			(end 0.67945 -0.3048)
			(stroke
				(width 0.1)
				(type default)
			)
			(layer "F.Fab")
		)
		(fp_line
			(start 0.12065 -0.2794)
			(end 0.12065 -0.3048)
			(stroke
				(width 0.1)
				(type default)
			)
			(layer "F.Fab")
		)
		(fp_line
			(start -0.12065 -0.2794)
			(end 0.12065 -0.2794)
			(stroke
				(width 0.1)
				(type default)
			)
			(layer "F.Fab")
		)
		(fp_line
			(start 0.120396 0.2794)
			(end -0.12065 0.2794)
			(stroke
				(width 0.1)
				(type default)
			)
			(layer "F.Fab")
		)
		(fp_line
			(start -0.12065 0.2794)
			(end -0.12065 0.3048)
			(stroke
				(width 0.1)
				(type default)
			)
			(layer "F.Fab")
		)
		(fp_line
			(start 0.67945 0.3048)
			(end 0.120396 0.3048)
			(stroke
				(width 0.1)
				(type default)
			)
			(layer "F.Fab")
		)
		(fp_line
			(start 0.120396 0.3048)
			(end 0.120396 0.2794)
			(stroke
				(width 0.1)
				(type default)
			)
			(layer "F.Fab")
		)
		(fp_line
			(start -0.12065 0.3048)
			(end -0.67945 0.3048)
			(stroke
				(width 0.1)
				(type default)
			)
			(layer "F.Fab")
		)
		(fp_line
			(start -0.67945 0.3048)
			(end -0.67945 -0.305054)
			(stroke
				(width 0.1)
				(type default)
			)
			(layer "F.Fab")
		)
		(pad "1" smd circle
			(at -0.40005 0 90)
			(size 0 0)
			(layers "F.Cu" "F.Mask" "F.Paste")
			(net "JTAG_PLD_TDO_R")
		)
		(pad "2" smd circle
			(at 0.40005 0 90)
			(size 0 0)
			(layers "F.Cu" "F.Mask" "F.Paste")
			(net "JTAG_BMC_PLD_TDO")
		)
	)
	(footprint ""
		(layer "F.Cu")
		(at 114.30508 -397.874998 90)
		(property "Reference" "R3032"
			(at 0 0 90)
			(layer "F.SilkS")
			(hide yes)
			(effects
				(font
					(size 1.27 1.27)
				)
			)
		)
		(property "Value" ""
			(at 0 0 90)
			(layer "F.Fab")
			(effects
				(font
					(size 1.27 1.27)
				)
			)
		)
		(duplicate_pad_numbers_are_jumpers no)
		(fp_line
			(start 0.7874 -0.4064)
			(end 0.7874 0.4064)
			(stroke
				(width 0.1524)
				(type default)
			)
			(layer "F.SilkS")
		)
		(fp_line
			(start -0.7874 -0.4064)
			(end 0.7874 -0.4064)
			(stroke
				(width 0.1524)
				(type default)
			)
			(layer "F.SilkS")
		)
		(fp_line
			(start 0.7874 0.4064)
			(end -0.7874 0.4064)
			(stroke
				(width 0.1524)
				(type default)
			)
			(layer "F.SilkS")
		)
		(fp_line
			(start -0.7874 0.4064)
			(end -0.7874 -0.4064)
			(stroke
				(width 0.1524)
				(type default)
			)
			(layer "F.SilkS")
		)
		(fp_line
			(start -0.12065 -0.305054)
			(end -0.12065 -0.2794)
			(stroke
				(width 0.1)
				(type default)
			)
			(layer "F.Fab")
		)
		(fp_line
			(start -0.67945 -0.305054)
			(end -0.12065 -0.305054)
			(stroke
				(width 0.1)
				(type default)
			)
			(layer "F.Fab")
		)
		(fp_line
			(start 0.67945 -0.3048)
			(end 0.67945 0.3048)
			(stroke
				(width 0.1)
				(type default)
			)
			(layer "F.Fab")
		)
		(fp_line
			(start 0.12065 -0.3048)
			(end 0.67945 -0.3048)
			(stroke
				(width 0.1)
				(type default)
			)
			(layer "F.Fab")
		)
		(fp_line
			(start 0.12065 -0.2794)
			(end 0.12065 -0.3048)
			(stroke
				(width 0.1)
				(type default)
			)
			(layer "F.Fab")
		)
		(fp_line
			(start -0.12065 -0.2794)
			(end 0.12065 -0.2794)
			(stroke
				(width 0.1)
				(type default)
			)
			(layer "F.Fab")
		)
		(fp_line
			(start 0.120396 0.2794)
			(end -0.12065 0.2794)
			(stroke
				(width 0.1)
				(type default)
			)
			(layer "F.Fab")
		)
		(fp_line
			(start -0.12065 0.2794)
			(end -0.12065 0.3048)
			(stroke
				(width 0.1)
				(type default)
			)
			(layer "F.Fab")
		)
		(fp_line
			(start 0.67945 0.3048)
			(end 0.120396 0.3048)
			(stroke
				(width 0.1)
				(type default)
			)
			(layer "F.Fab")
		)
		(fp_line
			(start 0.120396 0.3048)
			(end 0.120396 0.2794)
			(stroke
				(width 0.1)
				(type default)
			)
			(layer "F.Fab")
		)
		(fp_line
			(start -0.12065 0.3048)
			(end -0.67945 0.3048)
			(stroke
				(width 0.1)
				(type default)
			)
			(layer "F.Fab")
		)
		(fp_line
			(start -0.67945 0.3048)
			(end -0.67945 -0.305054)
			(stroke
				(width 0.1)
				(type default)
			)
			(layer "F.Fab")
		)
		(pad "1" smd circle
			(at -0.40005 0 90)
			(size 0 0)
			(layers "F.Cu" "F.Mask" "F.Paste")
			(net "FM_SMB_2_ALERT_GPU_N")
		)
		(pad "2" smd circle
			(at 0.40005 0 90)
			(size 0 0)
			(layers "F.Cu" "F.Mask" "F.Paste")
			(net "GND")
		)
	)
	(footprint ""
		(layer "F.Cu")
		(at 324.594728 -408.517344 -90)
		(property "Reference" "C915"
			(at 0 0 270)
			(layer "F.SilkS")
			(hide yes)
			(effects
				(font
					(size 1.27 1.27)
				)
			)
		)
		(property "Value" ""
			(at 0 0 270)
			(layer "F.Fab")
			(effects
				(font
					(size 1.27 1.27)
				)
			)
		)
		(duplicate_pad_numbers_are_jumpers no)
		(fp_line
			(start -0.299974 0.150114)
			(end -0.299974 -0.150114)
			(stroke
				(width 0.1)
				(type default)
			)
			(layer "F.Fab")
		)
		(fp_line
			(start 0.299974 0.150114)
			(end -0.299974 0.150114)
			(stroke
				(width 0.1)
				(type default)
			)
			(layer "F.Fab")
		)
		(fp_line
			(start -0.299974 -0.150114)
			(end 0.299974 -0.150114)
			(stroke
				(width 0.1)
				(type default)
			)
			(layer "F.Fab")
		)
		(fp_line
			(start 0.299974 -0.150114)
			(end 0.299974 0.150114)
			(stroke
				(width 0.1)
				(type default)
			)
			(layer "F.Fab")
		)
		(pad "1" smd rect
			(at -0.2667 0 270)
			(size 0.3048 0.381)
			(layers "F.Cu" "F.Mask" "F.Paste")
			(net "P5E_CPU0_PE0_TX_C_DP<9>")
		)
		(pad "2" smd rect
			(at 0.2667 0 270)
			(size 0.3048 0.381)
			(layers "F.Cu" "F.Mask" "F.Paste")
			(net "P5E_CPU0_PE0_TX_DP<9>")
		)
	)
	(footprint ""
		(layer "F.Cu")
		(at 54.242716 -114.99469)
		(property "Reference" "R3710"
			(at 0 0 0)
			(layer "F.SilkS")
			(hide yes)
			(effects
				(font
					(size 1.27 1.27)
				)
			)
		)
		(property "Value" ""
			(at 0 0 0)
			(layer "F.Fab")
			(effects
				(font
					(size 1.27 1.27)
				)
			)
		)
		(duplicate_pad_numbers_are_jumpers no)
		(fp_line
			(start -0.7874 -0.4064)
			(end 0.7874 -0.4064)
			(stroke
				(width 0.1524)
				(type default)
			)
			(layer "F.SilkS")
		)
		(fp_line
			(start -0.7874 0.4064)
			(end -0.7874 -0.4064)
			(stroke
				(width 0.1524)
				(type default)
			)
			(layer "F.SilkS")
		)
		(fp_line
			(start 0.7874 -0.4064)
			(end 0.7874 0.4064)
			(stroke
				(width 0.1524)
				(type default)
			)
			(layer "F.SilkS")
		)
		(fp_line
			(start 0.7874 0.4064)
			(end -0.7874 0.4064)
			(stroke
				(width 0.1524)
				(type default)
			)
			(layer "F.SilkS")
		)
		(fp_line
			(start -0.67945 -0.305054)
			(end -0.12065 -0.305054)
			(stroke
				(width 0.1)
				(type default)
			)
			(layer "F.Fab")
		)
		(fp_line
			(start -0.67945 0.3048)
			(end -0.67945 -0.305054)
			(stroke
				(width 0.1)
				(type default)
			)
			(layer "F.Fab")
		)
		(fp_line
			(start -0.12065 -0.305054)
			(end -0.12065 -0.2794)
			(stroke
				(width 0.1)
				(type default)
			)
			(layer "F.Fab")
		)
		(fp_line
			(start -0.12065 -0.2794)
			(end 0.12065 -0.2794)
			(stroke
				(width 0.1)
				(type default)
			)
			(layer "F.Fab")
		)
		(fp_line
			(start -0.12065 0.2794)
			(end -0.12065 0.3048)
			(stroke
				(width 0.1)
				(type default)
			)
			(layer "F.Fab")
		)
		(fp_line
			(start -0.12065 0.3048)
			(end -0.67945 0.3048)
			(stroke
				(width 0.1)
				(type default)
			)
			(layer "F.Fab")
		)
		(fp_line
			(start 0.120396 0.2794)
			(end -0.12065 0.2794)
			(stroke
				(width 0.1)
				(type default)
			)
			(layer "F.Fab")
		)
		(fp_line
			(start 0.120396 0.3048)
			(end 0.120396 0.2794)
			(stroke
				(width 0.1)
				(type default)
			)
			(layer "F.Fab")
		)
		(fp_line
			(start 0.12065 -0.3048)
			(end 0.67945 -0.3048)
			(stroke
				(width 0.1)
				(type default)
			)
			(layer "F.Fab")
		)
		(fp_line
			(start 0.12065 -0.2794)
			(end 0.12065 -0.3048)
			(stroke
				(width 0.1)
				(type default)
			)
			(layer "F.Fab")
		)
		(fp_line
			(start 0.67945 -0.3048)
			(end 0.67945 0.3048)
			(stroke
				(width 0.1)
				(type default)
			)
			(layer "F.Fab")
		)
		(fp_line
			(start 0.67945 0.3048)
			(end 0.120396 0.3048)
			(stroke
				(width 0.1)
				(type default)
			)
			(layer "F.Fab")
		)
		(pad "1" smd circle
			(at -0.40005 0)
			(size 0 0)
			(layers "F.Cu" "F.Mask" "F.Paste")
			(net "RST_SMB_SWITCH_N")
		)
		(pad "2" smd circle
			(at 0.40005 0)
			(size 0 0)
			(layers "F.Cu" "F.Mask" "F.Paste")
			(net "PU_RST_SMB_PCIE2_N")
		)
	)
	(footprint ""
		(layer "F.Cu")
		(at 316.900052 -68.449952)
		(property "Reference" "H38"
			(at -3.30454 -3.96621 0)
			(unlocked yes)
			(layer "F.SilkS")
			(effects
				(font
					(size 0.7874 0.5842)
					(thickness 0.1524)
				)
				(justify left)
			)
		)
		(property "Value" ""
			(at 0 0 0)
			(layer "F.Fab")
			(effects
				(font
					(size 1.27 1.27)
				)
			)
		)
		(duplicate_pad_numbers_are_jumpers no)
		(fp_circle
			(center 0 0)
			(end 2.3622 0)
			(stroke
				(width 0.1524)
				(type default)
			)
			(fill no)
			(layer "F.SilkS")
		)
		(fp_circle
			(center 0 0)
			(end 2.3622 0)
			(stroke
				(width 0.1524)
				(type default)
			)
			(fill no)
			(layer "B.SilkS")
		)
		(fp_circle
			(center 0 0)
			(end 2.3622 0)
			(stroke
				(width 0.1)
				(type default)
			)
			(fill no)
			(layer "B.Fab")
		)
		(fp_circle
			(center 0 0)
			(end 2.3622 0)
			(stroke
				(width 0.1)
				(type default)
			)
			(fill no)
			(layer "F.Fab")
		)
		(pad "" np_thru_hole circle
			(at 0 0)
			(size 3.0988 3.0988)
			(drill 3.0988)
			(layers "*.Cu" "*.Mask")
			(clearance 0.254)
			(thermal_gap 0.254)
		)
	)
	(footprint ""
		(layer "F.Cu")
		(at 154.23261 -57.436004)
		(property "Reference" "U98"
			(at -1.397 -2.13233 0)
			(unlocked yes)
			(layer "F.SilkS")
			(effects
				(font
					(size 0.7874 0.5842)
					(thickness 0.1524)
				)
				(justify left)
			)
		)
		(property "Value" ""
			(at 0 0 0)
			(layer "F.Fab")
			(effects
				(font
					(size 1.27 1.27)
				)
			)
		)
		(duplicate_pad_numbers_are_jumpers no)
		(fp_line
			(start -1.3208 -1.525016)
			(end -0.508 -1.525016)
			(stroke
				(width 0.1524)
				(type default)
			)
			(layer "F.SilkS")
		)
		(fp_line
			(start -1.3208 1.525016)
			(end -1.3208 -1.525016)
			(stroke
				(width 0.1524)
				(type default)
			)
			(layer "F.SilkS")
		)
		(fp_line
			(start -0.508 -1.525016)
			(end 0 -0.999998)
			(stroke
				(width 0.1524)
				(type default)
			)
			(layer "F.SilkS")
		)
		(fp_line
			(start 0 -0.999998)
			(end 0.508 -1.525016)
			(stroke
				(width 0.1524)
				(type default)
			)
			(layer "F.SilkS")
		)
		(fp_line
			(start 0.508 -1.525016)
			(end 1.3208 -1.525016)
			(stroke
				(width 0.1524)
				(type default)
			)
			(layer "F.SilkS")
		)
		(fp_line
			(start 1.3208 -1.525016)
			(end 1.3208 1.525016)
			(stroke
				(width 0.1524)
				(type default)
			)
			(layer "F.SilkS")
		)
		(fp_line
			(start 1.3208 1.525016)
			(end -1.3208 1.525016)
			(stroke
				(width 0.1524)
				(type default)
			)
			(layer "F.SilkS")
		)
		(fp_poly
			(pts
				(xy -3.937 -0.635) (xy -3.937 -1.397) (xy -3.175 -1.016)
			)
			(stroke
				(width 0)
				(type default)
			)
			(fill yes)
			(layer "F.SilkS")
		)
		(fp_line
			(start -3.037078 -1.20777)
			(end -1.524 -1.20777)
			(stroke
				(width 0.1)
				(type default)
			)
			(layer "F.Fab")
		)
		(fp_line
			(start -3.037078 1.203706)
			(end -3.037078 -1.20777)
			(stroke
				(width 0.1)
				(type default)
			)
			(layer "F.Fab")
		)
		(fp_line
			(start -1.5494 1.203706)
			(end -3.037078 1.203706)
			(stroke
				(width 0.1)
				(type default)
			)
			(layer "F.Fab")
		)
		(fp_line
			(start -1.5494 1.5494)
			(end -1.5494 1.203706)
			(stroke
				(width 0.1)
				(type default)
			)
			(layer "F.Fab")
		)
		(fp_line
			(start -1.524 -1.524)
			(end 1.524 -1.524)
			(stroke
				(width 0.1)
				(type default)
			)
			(layer "F.Fab")
		)
		(fp_line
			(start -1.524 -1.20777)
			(end -1.524 -1.524)
			(stroke
				(width 0.1)
				(type default)
			)
			(layer "F.Fab")
		)
		(fp_line
			(start 1.524 -1.524)
			(end 1.524 -1.20777)
			(stroke
				(width 0.1)
				(type default)
			)
			(layer "F.Fab")
		)
		(fp_line
			(start 1.524 -1.20777)
			(end 3.0353 -1.20777)
			(stroke
				(width 0.1)
				(type default)
			)
			(layer "F.Fab")
		)
		(fp_line
			(start 1.524 1.208786)
			(end 1.524 1.5494)
			(stroke
				(width 0.1)
				(type default)
			)
			(layer "F.Fab")
		)
		(fp_line
			(start 1.524 1.5494)
			(end -1.5494 1.5494)
			(stroke
				(width 0.1)
				(type default)
			)
			(layer "F.Fab")
		)
		(fp_line
			(start 3.0353 -1.20777)
			(end 3.0353 1.208786)
			(stroke
				(width 0.1)
				(type default)
			)
			(layer "F.Fab")
		)
		(fp_line
			(start 3.0353 1.208786)
			(end 1.524 1.208786)
			(stroke
				(width 0.1)
				(type default)
			)
			(layer "F.Fab")
		)
		(fp_poly
			(pts
				(xy -3.175 -1.016) (xy -3.937 -0.635) (xy -3.937 -1.397)
			)
			(stroke
				(width 0)
				(type default)
			)
			(fill yes)
			(layer "F.Fab")
		)
		(pad "1" smd rect
			(at -2.234946 -0.975106 270)
			(size 0.3556 1.4986)
			(layers "F.Cu" "F.Mask" "F.Paste")
			(net "GND")
		)
		(pad "2" smd rect
			(at -2.234946 -0.32512 270)
			(size 0.3556 1.4986)
			(layers "F.Cu" "F.Mask" "F.Paste")
			(net "P1V8_PCH_AUX")
		)
		(pad "3" smd rect
			(at -2.234946 0.32512 270)
			(size 0.3556 1.4986)
			(layers "F.Cu" "F.Mask" "F.Paste")
			(net "SMB_M2_P0_1V8AUX_SCL_R")
		)
		(pad "4" smd rect
			(at -2.234946 0.975106 270)
			(size 0.3556 1.4986)
			(layers "F.Cu" "F.Mask" "F.Paste")
			(net "SMB_M2_P0_1V8AUX_SDA_R")
		)
		(pad "5" smd rect
			(at 2.234946 0.975106 270)
			(size 0.3556 1.4986)
			(layers "F.Cu" "F.Mask" "F.Paste")
			(net "SMB_SENSOR_M2_P0_3V3AUX_SDA")
		)
		(pad "6" smd rect
			(at 2.234946 0.32512 270)
			(size 0.3556 1.4986)
			(layers "F.Cu" "F.Mask" "F.Paste")
			(net "SMB_SENSOR_M2_P0_3V3AUX_SCL")
		)
		(pad "7" smd rect
			(at 2.234946 -0.32512 270)
			(size 0.3556 1.4986)
			(layers "F.Cu" "F.Mask" "F.Paste")
			(net "SMB_PCIE_M2_0_EN")
		)
		(pad "8" smd rect
			(at 2.234946 -0.975106 270)
			(size 0.3556 1.4986)
			(layers "F.Cu" "F.Mask" "F.Paste")
			(net "SMB_PCIE_M2_0_EN")
		)
	)
	(footprint ""
		(layer "F.Cu")
		(at 104.349804 -244.032024 90)
		(property "Reference" "C252"
			(at 0 0 90)
			(layer "F.SilkS")
			(hide yes)
			(effects
				(font
					(size 1.27 1.27)
				)
			)
		)
		(property "Value" ""
			(at 0 0 90)
			(layer "F.Fab")
			(effects
				(font
					(size 1.27 1.27)
				)
			)
		)
		(duplicate_pad_numbers_are_jumpers no)
		(fp_line
			(start 0.7874 -0.4064)
			(end 0.7874 0.4064)
			(stroke
				(width 0.1524)
				(type default)
			)
			(layer "F.SilkS")
		)
		(fp_line
			(start -0.7874 -0.4064)
			(end 0.7874 -0.4064)
			(stroke
				(width 0.1524)
				(type default)
			)
			(layer "F.SilkS")
		)
		(fp_line
			(start 0.7874 0.4064)
			(end -0.7874 0.4064)
			(stroke
				(width 0.1524)
				(type default)
			)
			(layer "F.SilkS")
		)
		(fp_line
			(start -0.7874 0.4064)
			(end -0.7874 -0.4064)
			(stroke
				(width 0.1524)
				(type default)
			)
			(layer "F.SilkS")
		)
		(fp_line
			(start -0.12065 -0.305054)
			(end -0.12065 -0.2794)
			(stroke
				(width 0.1)
				(type default)
			)
			(layer "F.Fab")
		)
		(fp_line
			(start -0.67945 -0.305054)
			(end -0.12065 -0.305054)
			(stroke
				(width 0.1)
				(type default)
			)
			(layer "F.Fab")
		)
		(fp_line
			(start 0.67945 -0.3048)
			(end 0.67945 0.3048)
			(stroke
				(width 0.1)
				(type default)
			)
			(layer "F.Fab")
		)
		(fp_line
			(start 0.12065 -0.3048)
			(end 0.67945 -0.3048)
			(stroke
				(width 0.1)
				(type default)
			)
			(layer "F.Fab")
		)
		(fp_line
			(start 0.12065 -0.2794)
			(end 0.12065 -0.3048)
			(stroke
				(width 0.1)
				(type default)
			)
			(layer "F.Fab")
		)
		(fp_line
			(start -0.12065 -0.2794)
			(end 0.12065 -0.2794)
			(stroke
				(width 0.1)
				(type default)
			)
			(layer "F.Fab")
		)
		(fp_line
			(start 0.120396 0.2794)
			(end -0.12065 0.2794)
			(stroke
				(width 0.1)
				(type default)
			)
			(layer "F.Fab")
		)
		(fp_line
			(start -0.12065 0.2794)
			(end -0.12065 0.3048)
			(stroke
				(width 0.1)
				(type default)
			)
			(layer "F.Fab")
		)
		(fp_line
			(start 0.67945 0.3048)
			(end 0.120396 0.3048)
			(stroke
				(width 0.1)
				(type default)
			)
			(layer "F.Fab")
		)
		(fp_line
			(start 0.120396 0.3048)
			(end 0.120396 0.2794)
			(stroke
				(width 0.1)
				(type default)
			)
			(layer "F.Fab")
		)
		(fp_line
			(start -0.12065 0.3048)
			(end -0.67945 0.3048)
			(stroke
				(width 0.1)
				(type default)
			)
			(layer "F.Fab")
		)
		(fp_line
			(start -0.67945 0.3048)
			(end -0.67945 -0.305054)
			(stroke
				(width 0.1)
				(type default)
			)
			(layer "F.Fab")
		)
		(pad "1" smd circle
			(at -0.40005 0 90)
			(size 0 0)
			(layers "F.Cu" "F.Mask" "F.Paste")
			(net "PVCCIN_CPU1")
		)
		(pad "2" smd circle
			(at 0.40005 0 90)
			(size 0 0)
			(layers "F.Cu" "F.Mask" "F.Paste")
			(net "GND")
		)
	)
	(footprint ""
		(layer "F.Cu")
		(at 432.67884 -184.544208)
		(property "Reference" "PR3339"
			(at 0 0 0)
			(layer "F.SilkS")
			(hide yes)
			(effects
				(font
					(size 1.27 1.27)
				)
			)
		)
		(property "Value" ""
			(at 0 0 0)
			(layer "F.Fab")
			(effects
				(font
					(size 1.27 1.27)
				)
			)
		)
		(duplicate_pad_numbers_are_jumpers no)
		(fp_line
			(start -0.7874 -0.4064)
			(end 0.7874 -0.4064)
			(stroke
				(width 0.1524)
				(type default)
			)
			(layer "F.SilkS")
		)
		(fp_line
			(start -0.7874 0.4064)
			(end -0.7874 -0.4064)
			(stroke
				(width 0.1524)
				(type default)
			)
			(layer "F.SilkS")
		)
		(fp_line
			(start 0.7874 -0.4064)
			(end 0.7874 0.4064)
			(stroke
				(width 0.1524)
				(type default)
			)
			(layer "F.SilkS")
		)
		(fp_line
			(start 0.7874 0.4064)
			(end -0.7874 0.4064)
			(stroke
				(width 0.1524)
				(type default)
			)
			(layer "F.SilkS")
		)
		(fp_line
			(start -0.67945 -0.305054)
			(end -0.12065 -0.305054)
			(stroke
				(width 0.1)
				(type default)
			)
			(layer "F.Fab")
		)
		(fp_line
			(start -0.67945 0.3048)
			(end -0.67945 -0.305054)
			(stroke
				(width 0.1)
				(type default)
			)
			(layer "F.Fab")
		)
		(fp_line
			(start -0.12065 -0.305054)
			(end -0.12065 -0.2794)
			(stroke
				(width 0.1)
				(type default)
			)
			(layer "F.Fab")
		)
		(fp_line
			(start -0.12065 -0.2794)
			(end 0.12065 -0.2794)
			(stroke
				(width 0.1)
				(type default)
			)
			(layer "F.Fab")
		)
		(fp_line
			(start -0.12065 0.2794)
			(end -0.12065 0.3048)
			(stroke
				(width 0.1)
				(type default)
			)
			(layer "F.Fab")
		)
		(fp_line
			(start -0.12065 0.3048)
			(end -0.67945 0.3048)
			(stroke
				(width 0.1)
				(type default)
			)
			(layer "F.Fab")
		)
		(fp_line
			(start 0.120396 0.2794)
			(end -0.12065 0.2794)
			(stroke
				(width 0.1)
				(type default)
			)
			(layer "F.Fab")
		)
		(fp_line
			(start 0.120396 0.3048)
			(end 0.120396 0.2794)
			(stroke
				(width 0.1)
				(type default)
			)
			(layer "F.Fab")
		)
		(fp_line
			(start 0.12065 -0.3048)
			(end 0.67945 -0.3048)
			(stroke
				(width 0.1)
				(type default)
			)
			(layer "F.Fab")
		)
		(fp_line
			(start 0.12065 -0.2794)
			(end 0.12065 -0.3048)
			(stroke
				(width 0.1)
				(type default)
			)
			(layer "F.Fab")
		)
		(fp_line
			(start 0.67945 -0.3048)
			(end 0.67945 0.3048)
			(stroke
				(width 0.1)
				(type default)
			)
			(layer "F.Fab")
		)
		(fp_line
			(start 0.67945 0.3048)
			(end 0.120396 0.3048)
			(stroke
				(width 0.1)
				(type default)
			)
			(layer "F.Fab")
		)
		(pad "1" smd circle
			(at -0.40005 0)
			(size 0 0)
			(layers "F.Cu" "F.Mask" "F.Paste")
			(net "P3V3_AUX")
		)
		(pad "2" smd circle
			(at 0.40005 0)
			(size 0 0)
			(layers "F.Cu" "F.Mask" "F.Paste")
			(net "PVNN_MAIN_CPU0_VCC")
		)
	)
	(footprint ""
		(layer "F.Cu")
		(at 28.853638 -125.194314 -90)
		(property "Reference" "PC1193"
			(at 0 0 270)
			(layer "F.SilkS")
			(hide yes)
			(effects
				(font
					(size 1.27 1.27)
				)
			)
		)
		(property "Value" ""
			(at 0 0 270)
			(layer "F.Fab")
			(effects
				(font
					(size 1.27 1.27)
				)
			)
		)
		(duplicate_pad_numbers_are_jumpers no)
		(fp_line
			(start -0.7874 0.4064)
			(end -0.7874 -0.4064)
			(stroke
				(width 0.1524)
				(type default)
			)
			(layer "F.SilkS")
		)
		(fp_line
			(start 0.7874 0.4064)
			(end -0.7874 0.4064)
			(stroke
				(width 0.1524)
				(type default)
			)
			(layer "F.SilkS")
		)
		(fp_line
			(start -0.7874 -0.4064)
			(end 0.7874 -0.4064)
			(stroke
				(width 0.1524)
				(type default)
			)
			(layer "F.SilkS")
		)
		(fp_line
			(start 0.7874 -0.4064)
			(end 0.7874 0.4064)
			(stroke
				(width 0.1524)
				(type default)
			)
			(layer "F.SilkS")
		)
		(fp_line
			(start -0.67945 0.3048)
			(end -0.67945 -0.305054)
			(stroke
				(width 0.1)
				(type default)
			)
			(layer "F.Fab")
		)
		(fp_line
			(start -0.12065 0.3048)
			(end -0.67945 0.3048)
			(stroke
				(width 0.1)
				(type default)
			)
			(layer "F.Fab")
		)
		(fp_line
			(start 0.120396 0.3048)
			(end 0.120396 0.2794)
			(stroke
				(width 0.1)
				(type default)
			)
			(layer "F.Fab")
		)
		(fp_line
			(start 0.67945 0.3048)
			(end 0.120396 0.3048)
			(stroke
				(width 0.1)
				(type default)
			)
			(layer "F.Fab")
		)
		(fp_line
			(start -0.12065 0.2794)
			(end -0.12065 0.3048)
			(stroke
				(width 0.1)
				(type default)
			)
			(layer "F.Fab")
		)
		(fp_line
			(start 0.120396 0.2794)
			(end -0.12065 0.2794)
			(stroke
				(width 0.1)
				(type default)
			)
			(layer "F.Fab")
		)
		(fp_line
			(start -0.12065 -0.2794)
			(end 0.12065 -0.2794)
			(stroke
				(width 0.1)
				(type default)
			)
			(layer "F.Fab")
		)
		(fp_line
			(start 0.12065 -0.2794)
			(end 0.12065 -0.3048)
			(stroke
				(width 0.1)
				(type default)
			)
			(layer "F.Fab")
		)
		(fp_line
			(start 0.12065 -0.3048)
			(end 0.67945 -0.3048)
			(stroke
				(width 0.1)
				(type default)
			)
			(layer "F.Fab")
		)
		(fp_line
			(start 0.67945 -0.3048)
			(end 0.67945 0.3048)
			(stroke
				(width 0.1)
				(type default)
			)
			(layer "F.Fab")
		)
		(fp_line
			(start -0.67945 -0.305054)
			(end -0.12065 -0.305054)
			(stroke
				(width 0.1)
				(type default)
			)
			(layer "F.Fab")
		)
		(fp_line
			(start -0.12065 -0.305054)
			(end -0.12065 -0.2794)
			(stroke
				(width 0.1)
				(type default)
			)
			(layer "F.Fab")
		)
		(pad "1" smd circle
			(at -0.40005 0 270)
			(size 0 0)
			(layers "F.Cu" "F.Mask" "F.Paste")
			(net "PVCCINFAON_CPU1_VREF")
		)
		(pad "2" smd circle
			(at 0.40005 0 270)
			(size 0 0)
			(layers "F.Cu" "F.Mask" "F.Paste")
			(net "GND")
		)
	)
	(footprint ""
		(layer "F.Cu")
		(at 251.74956 -108.192824 90)
		(property "Reference" "R1011"
			(at 0 0 90)
			(layer "F.SilkS")
			(hide yes)
			(effects
				(font
					(size 1.27 1.27)
				)
			)
		)
		(property "Value" ""
			(at 0 0 90)
			(layer "F.Fab")
			(effects
				(font
					(size 1.27 1.27)
				)
			)
		)
		(duplicate_pad_numbers_are_jumpers no)
		(fp_line
			(start 0.7874 -0.4064)
			(end 0.7874 0.4064)
			(stroke
				(width 0.1524)
				(type default)
			)
			(layer "F.SilkS")
		)
		(fp_line
			(start -0.7874 -0.4064)
			(end 0.7874 -0.4064)
			(stroke
				(width 0.1524)
				(type default)
			)
			(layer "F.SilkS")
		)
		(fp_line
			(start 0.7874 0.4064)
			(end -0.7874 0.4064)
			(stroke
				(width 0.1524)
				(type default)
			)
			(layer "F.SilkS")
		)
		(fp_line
			(start -0.7874 0.4064)
			(end -0.7874 -0.4064)
			(stroke
				(width 0.1524)
				(type default)
			)
			(layer "F.SilkS")
		)
		(fp_line
			(start -0.12065 -0.305054)
			(end -0.12065 -0.2794)
			(stroke
				(width 0.1)
				(type default)
			)
			(layer "F.Fab")
		)
		(fp_line
			(start -0.67945 -0.305054)
			(end -0.12065 -0.305054)
			(stroke
				(width 0.1)
				(type default)
			)
			(layer "F.Fab")
		)
		(fp_line
			(start 0.67945 -0.3048)
			(end 0.67945 0.3048)
			(stroke
				(width 0.1)
				(type default)
			)
			(layer "F.Fab")
		)
		(fp_line
			(start 0.12065 -0.3048)
			(end 0.67945 -0.3048)
			(stroke
				(width 0.1)
				(type default)
			)
			(layer "F.Fab")
		)
		(fp_line
			(start 0.12065 -0.2794)
			(end 0.12065 -0.3048)
			(stroke
				(width 0.1)
				(type default)
			)
			(layer "F.Fab")
		)
		(fp_line
			(start -0.12065 -0.2794)
			(end 0.12065 -0.2794)
			(stroke
				(width 0.1)
				(type default)
			)
			(layer "F.Fab")
		)
		(fp_line
			(start 0.120396 0.2794)
			(end -0.12065 0.2794)
			(stroke
				(width 0.1)
				(type default)
			)
			(layer "F.Fab")
		)
		(fp_line
			(start -0.12065 0.2794)
			(end -0.12065 0.3048)
			(stroke
				(width 0.1)
				(type default)
			)
			(layer "F.Fab")
		)
		(fp_line
			(start 0.67945 0.3048)
			(end 0.120396 0.3048)
			(stroke
				(width 0.1)
				(type default)
			)
			(layer "F.Fab")
		)
		(fp_line
			(start 0.120396 0.3048)
			(end 0.120396 0.2794)
			(stroke
				(width 0.1)
				(type default)
			)
			(layer "F.Fab")
		)
		(fp_line
			(start -0.12065 0.3048)
			(end -0.67945 0.3048)
			(stroke
				(width 0.1)
				(type default)
			)
			(layer "F.Fab")
		)
		(fp_line
			(start -0.67945 0.3048)
			(end -0.67945 -0.305054)
			(stroke
				(width 0.1)
				(type default)
			)
			(layer "F.Fab")
		)
		(pad "1" smd circle
			(at -0.40005 0 90)
			(size 0 0)
			(layers "F.Cu" "F.Mask" "F.Paste")
			(net "CLK_25M_CK440_ISCLK_REF_DN")
		)
		(pad "2" smd circle
			(at 0.40005 0 90)
			(size 0 0)
			(layers "F.Cu" "F.Mask" "F.Paste")
			(net "CLK_25M_PCH_REF_NS_DN")
		)
	)
	(footprint ""
		(layer "F.Cu")
		(at 428.226474 -125.80366)
		(property "Reference" "PR357"
			(at 0 0 0)
			(layer "F.SilkS")
			(hide yes)
			(effects
				(font
					(size 1.27 1.27)
				)
			)
		)
		(property "Value" ""
			(at 0 0 0)
			(layer "F.Fab")
			(effects
				(font
					(size 1.27 1.27)
				)
			)
		)
		(duplicate_pad_numbers_are_jumpers no)
		(fp_line
			(start -0.7874 -0.4064)
			(end 0.7874 -0.4064)
			(stroke
				(width 0.1524)
				(type default)
			)
			(layer "F.SilkS")
		)
		(fp_line
			(start -0.7874 0.4064)
			(end -0.7874 -0.4064)
			(stroke
				(width 0.1524)
				(type default)
			)
			(layer "F.SilkS")
		)
		(fp_line
			(start 0.7874 -0.4064)
			(end 0.7874 0.4064)
			(stroke
				(width 0.1524)
				(type default)
			)
			(layer "F.SilkS")
		)
		(fp_line
			(start 0.7874 0.4064)
			(end -0.7874 0.4064)
			(stroke
				(width 0.1524)
				(type default)
			)
			(layer "F.SilkS")
		)
		(fp_line
			(start -0.67945 -0.305054)
			(end -0.12065 -0.305054)
			(stroke
				(width 0.1)
				(type default)
			)
			(layer "F.Fab")
		)
		(fp_line
			(start -0.67945 0.3048)
			(end -0.67945 -0.305054)
			(stroke
				(width 0.1)
				(type default)
			)
			(layer "F.Fab")
		)
		(fp_line
			(start -0.12065 -0.305054)
			(end -0.12065 -0.2794)
			(stroke
				(width 0.1)
				(type default)
			)
			(layer "F.Fab")
		)
		(fp_line
			(start -0.12065 -0.2794)
			(end 0.12065 -0.2794)
			(stroke
				(width 0.1)
				(type default)
			)
			(layer "F.Fab")
		)
		(fp_line
			(start -0.12065 0.2794)
			(end -0.12065 0.3048)
			(stroke
				(width 0.1)
				(type default)
			)
			(layer "F.Fab")
		)
		(fp_line
			(start -0.12065 0.3048)
			(end -0.67945 0.3048)
			(stroke
				(width 0.1)
				(type default)
			)
			(layer "F.Fab")
		)
		(fp_line
			(start 0.120396 0.2794)
			(end -0.12065 0.2794)
			(stroke
				(width 0.1)
				(type default)
			)
			(layer "F.Fab")
		)
		(fp_line
			(start 0.120396 0.3048)
			(end 0.120396 0.2794)
			(stroke
				(width 0.1)
				(type default)
			)
			(layer "F.Fab")
		)
		(fp_line
			(start 0.12065 -0.3048)
			(end 0.67945 -0.3048)
			(stroke
				(width 0.1)
				(type default)
			)
			(layer "F.Fab")
		)
		(fp_line
			(start 0.12065 -0.2794)
			(end 0.12065 -0.3048)
			(stroke
				(width 0.1)
				(type default)
			)
			(layer "F.Fab")
		)
		(fp_line
			(start 0.67945 -0.3048)
			(end 0.67945 0.3048)
			(stroke
				(width 0.1)
				(type default)
			)
			(layer "F.Fab")
		)
		(fp_line
			(start 0.67945 0.3048)
			(end 0.120396 0.3048)
			(stroke
				(width 0.1)
				(type default)
			)
			(layer "F.Fab")
		)
		(pad "1" smd circle
			(at -0.40005 0)
			(size 0 0)
			(layers "F.Cu" "F.Mask" "F.Paste")
			(net "PVCCD_HV_CPU0_VREF")
		)
		(pad "2" smd circle
			(at 0.40005 0)
			(size 0 0)
			(layers "F.Cu" "F.Mask" "F.Paste")
			(net "PVCCD_HV_CPU0_ADDR")
		)
	)
	(footprint ""
		(layer "F.Cu")
		(at 136.508998 -348.061026)
		(property "Reference" "PR285"
			(at 0 0 0)
			(layer "F.SilkS")
			(hide yes)
			(effects
				(font
					(size 1.27 1.27)
				)
			)
		)
		(property "Value" ""
			(at 0 0 0)
			(layer "F.Fab")
			(effects
				(font
					(size 1.27 1.27)
				)
			)
		)
		(duplicate_pad_numbers_are_jumpers no)
		(fp_line
			(start -0.7874 -0.4064)
			(end 0.7874 -0.4064)
			(stroke
				(width 0.1524)
				(type default)
			)
			(layer "F.SilkS")
		)
		(fp_line
			(start -0.7874 0.4064)
			(end -0.7874 -0.4064)
			(stroke
				(width 0.1524)
				(type default)
			)
			(layer "F.SilkS")
		)
		(fp_line
			(start 0.7874 -0.4064)
			(end 0.7874 0.4064)
			(stroke
				(width 0.1524)
				(type default)
			)
			(layer "F.SilkS")
		)
		(fp_line
			(start 0.7874 0.4064)
			(end -0.7874 0.4064)
			(stroke
				(width 0.1524)
				(type default)
			)
			(layer "F.SilkS")
		)
		(fp_line
			(start -0.67945 -0.305054)
			(end -0.12065 -0.305054)
			(stroke
				(width 0.1)
				(type default)
			)
			(layer "F.Fab")
		)
		(fp_line
			(start -0.67945 0.3048)
			(end -0.67945 -0.305054)
			(stroke
				(width 0.1)
				(type default)
			)
			(layer "F.Fab")
		)
		(fp_line
			(start -0.12065 -0.305054)
			(end -0.12065 -0.2794)
			(stroke
				(width 0.1)
				(type default)
			)
			(layer "F.Fab")
		)
		(fp_line
			(start -0.12065 -0.2794)
			(end 0.12065 -0.2794)
			(stroke
				(width 0.1)
				(type default)
			)
			(layer "F.Fab")
		)
		(fp_line
			(start -0.12065 0.2794)
			(end -0.12065 0.3048)
			(stroke
				(width 0.1)
				(type default)
			)
			(layer "F.Fab")
		)
		(fp_line
			(start -0.12065 0.3048)
			(end -0.67945 0.3048)
			(stroke
				(width 0.1)
				(type default)
			)
			(layer "F.Fab")
		)
		(fp_line
			(start 0.120396 0.2794)
			(end -0.12065 0.2794)
			(stroke
				(width 0.1)
				(type default)
			)
			(layer "F.Fab")
		)
		(fp_line
			(start 0.120396 0.3048)
			(end 0.120396 0.2794)
			(stroke
				(width 0.1)
				(type default)
			)
			(layer "F.Fab")
		)
		(fp_line
			(start 0.12065 -0.3048)
			(end 0.67945 -0.3048)
			(stroke
				(width 0.1)
				(type default)
			)
			(layer "F.Fab")
		)
		(fp_line
			(start 0.12065 -0.2794)
			(end 0.12065 -0.3048)
			(stroke
				(width 0.1)
				(type default)
			)
			(layer "F.Fab")
		)
		(fp_line
			(start 0.67945 -0.3048)
			(end 0.67945 0.3048)
			(stroke
				(width 0.1)
				(type default)
			)
			(layer "F.Fab")
		)
		(fp_line
			(start 0.67945 0.3048)
			(end 0.120396 0.3048)
			(stroke
				(width 0.1)
				(type default)
			)
			(layer "F.Fab")
		)
		(pad "1" smd circle
			(at -0.40005 0)
			(size 0 0)
			(layers "F.Cu" "F.Mask" "F.Paste")
			(net "PVCCIN_CPU1_LSET8")
		)
		(pad "2" smd circle
			(at 0.40005 0)
			(size 0 0)
			(layers "F.Cu" "F.Mask" "F.Paste")
			(net "GND")
		)
	)
	(footprint ""
		(layer "F.Cu")
		(at 160.83788 -115.026948)
		(property "Reference" "R3483"
			(at 0 0 0)
			(layer "F.SilkS")
			(hide yes)
			(effects
				(font
					(size 1.27 1.27)
				)
			)
		)
		(property "Value" ""
			(at 0 0 0)
			(layer "F.Fab")
			(effects
				(font
					(size 1.27 1.27)
				)
			)
		)
		(duplicate_pad_numbers_are_jumpers no)
		(fp_line
			(start -0.7874 -0.4064)
			(end 0.7874 -0.4064)
			(stroke
				(width 0.1524)
				(type default)
			)
			(layer "F.SilkS")
		)
		(fp_line
			(start -0.7874 0.4064)
			(end -0.7874 -0.4064)
			(stroke
				(width 0.1524)
				(type default)
			)
			(layer "F.SilkS")
		)
		(fp_line
			(start 0.7874 -0.4064)
			(end 0.7874 0.4064)
			(stroke
				(width 0.1524)
				(type default)
			)
			(layer "F.SilkS")
		)
		(fp_line
			(start 0.7874 0.4064)
			(end -0.7874 0.4064)
			(stroke
				(width 0.1524)
				(type default)
			)
			(layer "F.SilkS")
		)
		(fp_line
			(start -0.67945 -0.305054)
			(end -0.12065 -0.305054)
			(stroke
				(width 0.1)
				(type default)
			)
			(layer "F.Fab")
		)
		(fp_line
			(start -0.67945 0.3048)
			(end -0.67945 -0.305054)
			(stroke
				(width 0.1)
				(type default)
			)
			(layer "F.Fab")
		)
		(fp_line
			(start -0.12065 -0.305054)
			(end -0.12065 -0.2794)
			(stroke
				(width 0.1)
				(type default)
			)
			(layer "F.Fab")
		)
		(fp_line
			(start -0.12065 -0.2794)
			(end 0.12065 -0.2794)
			(stroke
				(width 0.1)
				(type default)
			)
			(layer "F.Fab")
		)
		(fp_line
			(start -0.12065 0.2794)
			(end -0.12065 0.3048)
			(stroke
				(width 0.1)
				(type default)
			)
			(layer "F.Fab")
		)
		(fp_line
			(start -0.12065 0.3048)
			(end -0.67945 0.3048)
			(stroke
				(width 0.1)
				(type default)
			)
			(layer "F.Fab")
		)
		(fp_line
			(start 0.120396 0.2794)
			(end -0.12065 0.2794)
			(stroke
				(width 0.1)
				(type default)
			)
			(layer "F.Fab")
		)
		(fp_line
			(start 0.120396 0.3048)
			(end 0.120396 0.2794)
			(stroke
				(width 0.1)
				(type default)
			)
			(layer "F.Fab")
		)
		(fp_line
			(start 0.12065 -0.3048)
			(end 0.67945 -0.3048)
			(stroke
				(width 0.1)
				(type default)
			)
			(layer "F.Fab")
		)
		(fp_line
			(start 0.12065 -0.2794)
			(end 0.12065 -0.3048)
			(stroke
				(width 0.1)
				(type default)
			)
			(layer "F.Fab")
		)
		(fp_line
			(start 0.67945 -0.3048)
			(end 0.67945 0.3048)
			(stroke
				(width 0.1)
				(type default)
			)
			(layer "F.Fab")
		)
		(fp_line
			(start 0.67945 0.3048)
			(end 0.120396 0.3048)
			(stroke
				(width 0.1)
				(type default)
			)
			(layer "F.Fab")
		)
		(pad "1" smd circle
			(at -0.40005 0)
			(size 0 0)
			(layers "F.Cu" "F.Mask" "F.Paste")
			(net "GPU_FPGA_EROT_RECOV_N")
		)
		(pad "2" smd circle
			(at 0.40005 0)
			(size 0 0)
			(layers "F.Cu" "F.Mask" "F.Paste")
			(net "GPU_FPGA_EROT_RECOV_R_N")
		)
	)
	(footprint ""
		(layer "F.Cu")
		(at 146.959828 -92.622878 -90)
		(property "Reference" "R4394"
			(at 0 0 270)
			(layer "F.SilkS")
			(hide yes)
			(effects
				(font
					(size 1.27 1.27)
				)
			)
		)
		(property "Value" ""
			(at 0 0 270)
			(layer "F.Fab")
			(effects
				(font
					(size 1.27 1.27)
				)
			)
		)
		(duplicate_pad_numbers_are_jumpers no)
		(fp_line
			(start -0.7874 0.4064)
			(end -0.7874 -0.4064)
			(stroke
				(width 0.1524)
				(type default)
			)
			(layer "F.SilkS")
		)
		(fp_line
			(start 0.7874 0.4064)
			(end -0.7874 0.4064)
			(stroke
				(width 0.1524)
				(type default)
			)
			(layer "F.SilkS")
		)
		(fp_line
			(start -0.7874 -0.4064)
			(end 0.7874 -0.4064)
			(stroke
				(width 0.1524)
				(type default)
			)
			(layer "F.SilkS")
		)
		(fp_line
			(start 0.7874 -0.4064)
			(end 0.7874 0.4064)
			(stroke
				(width 0.1524)
				(type default)
			)
			(layer "F.SilkS")
		)
		(fp_line
			(start -0.67945 0.3048)
			(end -0.67945 -0.305054)
			(stroke
				(width 0.1)
				(type default)
			)
			(layer "F.Fab")
		)
		(fp_line
			(start -0.12065 0.3048)
			(end -0.67945 0.3048)
			(stroke
				(width 0.1)
				(type default)
			)
			(layer "F.Fab")
		)
		(fp_line
			(start 0.120396 0.3048)
			(end 0.120396 0.2794)
			(stroke
				(width 0.1)
				(type default)
			)
			(layer "F.Fab")
		)
		(fp_line
			(start 0.67945 0.3048)
			(end 0.120396 0.3048)
			(stroke
				(width 0.1)
				(type default)
			)
			(layer "F.Fab")
		)
		(fp_line
			(start -0.12065 0.2794)
			(end -0.12065 0.3048)
			(stroke
				(width 0.1)
				(type default)
			)
			(layer "F.Fab")
		)
		(fp_line
			(start 0.120396 0.2794)
			(end -0.12065 0.2794)
			(stroke
				(width 0.1)
				(type default)
			)
			(layer "F.Fab")
		)
		(fp_line
			(start -0.12065 -0.2794)
			(end 0.12065 -0.2794)
			(stroke
				(width 0.1)
				(type default)
			)
			(layer "F.Fab")
		)
		(fp_line
			(start 0.12065 -0.2794)
			(end 0.12065 -0.3048)
			(stroke
				(width 0.1)
				(type default)
			)
			(layer "F.Fab")
		)
		(fp_line
			(start 0.12065 -0.3048)
			(end 0.67945 -0.3048)
			(stroke
				(width 0.1)
				(type default)
			)
			(layer "F.Fab")
		)
		(fp_line
			(start 0.67945 -0.3048)
			(end 0.67945 0.3048)
			(stroke
				(width 0.1)
				(type default)
			)
			(layer "F.Fab")
		)
		(fp_line
			(start -0.67945 -0.305054)
			(end -0.12065 -0.305054)
			(stroke
				(width 0.1)
				(type default)
			)
			(layer "F.Fab")
		)
		(fp_line
			(start -0.12065 -0.305054)
			(end -0.12065 -0.2794)
			(stroke
				(width 0.1)
				(type default)
			)
			(layer "F.Fab")
		)
		(pad "1" smd circle
			(at -0.40005 0 270)
			(size 0 0)
			(layers "F.Cu" "F.Mask" "F.Paste")
			(net "H_CPU_ERR2_LVC2_R_N")
		)
		(pad "2" smd circle
			(at 0.40005 0 270)
			(size 0 0)
			(layers "F.Cu" "F.Mask" "F.Paste")
			(net "H_CPU_ERR2_PCH_R_N")
		)
	)
	(footprint ""
		(layer "F.Cu")
		(at 12.784582 -410.802836 90)
		(property "Reference" "R2923"
			(at 0 0 90)
			(layer "F.SilkS")
			(hide yes)
			(effects
				(font
					(size 1.27 1.27)
				)
			)
		)
		(property "Value" ""
			(at 0 0 90)
			(layer "F.Fab")
			(effects
				(font
					(size 1.27 1.27)
				)
			)
		)
		(duplicate_pad_numbers_are_jumpers no)
		(fp_line
			(start 0.7874 -0.4064)
			(end 0.7874 0.4064)
			(stroke
				(width 0.1524)
				(type default)
			)
			(layer "F.SilkS")
		)
		(fp_line
			(start -0.7874 -0.4064)
			(end 0.7874 -0.4064)
			(stroke
				(width 0.1524)
				(type default)
			)
			(layer "F.SilkS")
		)
		(fp_line
			(start 0.7874 0.4064)
			(end -0.7874 0.4064)
			(stroke
				(width 0.1524)
				(type default)
			)
			(layer "F.SilkS")
		)
		(fp_line
			(start -0.7874 0.4064)
			(end -0.7874 -0.4064)
			(stroke
				(width 0.1524)
				(type default)
			)
			(layer "F.SilkS")
		)
		(fp_line
			(start -0.12065 -0.305054)
			(end -0.12065 -0.2794)
			(stroke
				(width 0.1)
				(type default)
			)
			(layer "F.Fab")
		)
		(fp_line
			(start -0.67945 -0.305054)
			(end -0.12065 -0.305054)
			(stroke
				(width 0.1)
				(type default)
			)
			(layer "F.Fab")
		)
		(fp_line
			(start 0.67945 -0.3048)
			(end 0.67945 0.3048)
			(stroke
				(width 0.1)
				(type default)
			)
			(layer "F.Fab")
		)
		(fp_line
			(start 0.12065 -0.3048)
			(end 0.67945 -0.3048)
			(stroke
				(width 0.1)
				(type default)
			)
			(layer "F.Fab")
		)
		(fp_line
			(start 0.12065 -0.2794)
			(end 0.12065 -0.3048)
			(stroke
				(width 0.1)
				(type default)
			)
			(layer "F.Fab")
		)
		(fp_line
			(start -0.12065 -0.2794)
			(end 0.12065 -0.2794)
			(stroke
				(width 0.1)
				(type default)
			)
			(layer "F.Fab")
		)
		(fp_line
			(start 0.120396 0.2794)
			(end -0.12065 0.2794)
			(stroke
				(width 0.1)
				(type default)
			)
			(layer "F.Fab")
		)
		(fp_line
			(start -0.12065 0.2794)
			(end -0.12065 0.3048)
			(stroke
				(width 0.1)
				(type default)
			)
			(layer "F.Fab")
		)
		(fp_line
			(start 0.67945 0.3048)
			(end 0.120396 0.3048)
			(stroke
				(width 0.1)
				(type default)
			)
			(layer "F.Fab")
		)
		(fp_line
			(start 0.120396 0.3048)
			(end 0.120396 0.2794)
			(stroke
				(width 0.1)
				(type default)
			)
			(layer "F.Fab")
		)
		(fp_line
			(start -0.12065 0.3048)
			(end -0.67945 0.3048)
			(stroke
				(width 0.1)
				(type default)
			)
			(layer "F.Fab")
		)
		(fp_line
			(start -0.67945 0.3048)
			(end -0.67945 -0.305054)
			(stroke
				(width 0.1)
				(type default)
			)
			(layer "F.Fab")
		)
		(pad "1" smd circle
			(at -0.40005 0 90)
			(size 0 0)
			(layers "F.Cu" "F.Mask" "F.Paste")
			(net "P3V3_AUX")
		)
		(pad "2" smd circle
			(at 0.40005 0 90)
			(size 0 0)
			(layers "F.Cu" "F.Mask" "F.Paste")
			(net "PU_U181_INT")
		)
	)
	(footprint ""
		(layer "F.Cu")
		(at 464.968336 -385.742434 90)
		(property "Reference" "PC1850"
			(at 0 0 90)
			(layer "F.SilkS")
			(hide yes)
			(effects
				(font
					(size 1.27 1.27)
				)
			)
		)
		(property "Value" ""
			(at 0 0 90)
			(layer "F.Fab")
			(effects
				(font
					(size 1.27 1.27)
				)
			)
		)
		(duplicate_pad_numbers_are_jumpers no)
		(fp_line
			(start 1.524 -0.762)
			(end 1.524 0.762)
			(stroke
				(width 0.1524)
				(type default)
			)
			(layer "F.SilkS")
		)
		(fp_line
			(start -1.524 -0.762)
			(end 1.524 -0.762)
			(stroke
				(width 0.1524)
				(type default)
			)
			(layer "F.SilkS")
		)
		(fp_line
			(start 1.524 0.762)
			(end -1.524 0.762)
			(stroke
				(width 0.1524)
				(type default)
			)
			(layer "F.SilkS")
		)
		(fp_line
			(start -1.524 0.762)
			(end -1.524 -0.762)
			(stroke
				(width 0.1524)
				(type default)
			)
			(layer "F.SilkS")
		)
		(fp_line
			(start 1.1049 -0.724916)
			(end -1.1049 -0.724916)
			(stroke
				(width 0.1)
				(type default)
			)
			(layer "F.Fab")
		)
		(fp_line
			(start -1.1049 -0.724916)
			(end -1.1049 0.724916)
			(stroke
				(width 0.1)
				(type default)
			)
			(layer "F.Fab")
		)
		(fp_line
			(start 1.1049 0.724916)
			(end 1.1049 -0.724916)
			(stroke
				(width 0.1)
				(type default)
			)
			(layer "F.Fab")
		)
		(fp_line
			(start -1.1049 0.724916)
			(end 1.1049 0.724916)
			(stroke
				(width 0.1)
				(type default)
			)
			(layer "F.Fab")
		)
		(pad "1" smd rect
			(at -0.889 0 270)
			(size 1.016 1.27)
			(layers "F.Cu" "F.Mask" "F.Paste")
			(net "SW_P5V_AUX_FLT")
		)
		(pad "2" smd rect
			(at 0.889 0 270)
			(size 1.016 1.27)
			(layers "F.Cu" "F.Mask" "F.Paste")
			(net "GND")
		)
	)
	(footprint ""
		(layer "F.Cu")
		(at 145.34388 -57.241948 180)
		(property "Reference" "R2411"
			(at 0 0 180)
			(layer "F.SilkS")
			(hide yes)
			(effects
				(font
					(size 1.27 1.27)
				)
			)
		)
		(property "Value" ""
			(at 0 0 180)
			(layer "F.Fab")
			(effects
				(font
					(size 1.27 1.27)
				)
			)
		)
		(duplicate_pad_numbers_are_jumpers no)
		(fp_line
			(start 0.7874 0.4064)
			(end -0.7874 0.4064)
			(stroke
				(width 0.1524)
				(type default)
			)
			(layer "F.SilkS")
		)
		(fp_line
			(start 0.7874 -0.4064)
			(end 0.7874 0.4064)
			(stroke
				(width 0.1524)
				(type default)
			)
			(layer "F.SilkS")
		)
		(fp_line
			(start -0.7874 0.4064)
			(end -0.7874 -0.4064)
			(stroke
				(width 0.1524)
				(type default)
			)
			(layer "F.SilkS")
		)
		(fp_line
			(start -0.7874 -0.4064)
			(end 0.7874 -0.4064)
			(stroke
				(width 0.1524)
				(type default)
			)
			(layer "F.SilkS")
		)
		(fp_line
			(start 0.67945 0.3048)
			(end 0.120396 0.3048)
			(stroke
				(width 0.1)
				(type default)
			)
			(layer "F.Fab")
		)
		(fp_line
			(start 0.67945 -0.3048)
			(end 0.67945 0.3048)
			(stroke
				(width 0.1)
				(type default)
			)
			(layer "F.Fab")
		)
		(fp_line
			(start 0.12065 -0.2794)
			(end 0.12065 -0.3048)
			(stroke
				(width 0.1)
				(type default)
			)
			(layer "F.Fab")
		)
		(fp_line
			(start 0.12065 -0.3048)
			(end 0.67945 -0.3048)
			(stroke
				(width 0.1)
				(type default)
			)
			(layer "F.Fab")
		)
		(fp_line
			(start 0.120396 0.3048)
			(end 0.120396 0.2794)
			(stroke
				(width 0.1)
				(type default)
			)
			(layer "F.Fab")
		)
		(fp_line
			(start 0.120396 0.2794)
			(end -0.12065 0.2794)
			(stroke
				(width 0.1)
				(type default)
			)
			(layer "F.Fab")
		)
		(fp_line
			(start -0.12065 0.3048)
			(end -0.67945 0.3048)
			(stroke
				(width 0.1)
				(type default)
			)
			(layer "F.Fab")
		)
		(fp_line
			(start -0.12065 0.2794)
			(end -0.12065 0.3048)
			(stroke
				(width 0.1)
				(type default)
			)
			(layer "F.Fab")
		)
		(fp_line
			(start -0.12065 -0.2794)
			(end 0.12065 -0.2794)
			(stroke
				(width 0.1)
				(type default)
			)
			(layer "F.Fab")
		)
		(fp_line
			(start -0.12065 -0.305054)
			(end -0.12065 -0.2794)
			(stroke
				(width 0.1)
				(type default)
			)
			(layer "F.Fab")
		)
		(fp_line
			(start -0.67945 0.3048)
			(end -0.67945 -0.305054)
			(stroke
				(width 0.1)
				(type default)
			)
			(layer "F.Fab")
		)
		(fp_line
			(start -0.67945 -0.305054)
			(end -0.12065 -0.305054)
			(stroke
				(width 0.1)
				(type default)
			)
			(layer "F.Fab")
		)
		(pad "1" smd circle
			(at -0.40005 0 180)
			(size 0 0)
			(layers "F.Cu" "F.Mask" "F.Paste")
			(net "SMB_M2_P0_1V8AUX_SCL_R")
		)
		(pad "2" smd circle
			(at 0.40005 0 180)
			(size 0 0)
			(layers "F.Cu" "F.Mask" "F.Paste")
			(net "SMB_M2_P0_1V8AUX_SCL")
		)
	)
	(footprint ""
		(layer "F.Cu")
		(at 421.92194 -109.271308 90)
		(property "Reference" "PC2162"
			(at 0 0 90)
			(layer "F.SilkS")
			(hide yes)
			(effects
				(font
					(size 1.27 1.27)
				)
			)
		)
		(property "Value" ""
			(at 0 0 90)
			(layer "F.Fab")
			(effects
				(font
					(size 1.27 1.27)
				)
			)
		)
		(duplicate_pad_numbers_are_jumpers no)
		(fp_line
			(start 0.7874 -0.4064)
			(end 0.7874 0.4064)
			(stroke
				(width 0.1524)
				(type default)
			)
			(layer "F.SilkS")
		)
		(fp_line
			(start -0.7874 -0.4064)
			(end 0.7874 -0.4064)
			(stroke
				(width 0.1524)
				(type default)
			)
			(layer "F.SilkS")
		)
		(fp_line
			(start 0.7874 0.4064)
			(end -0.7874 0.4064)
			(stroke
				(width 0.1524)
				(type default)
			)
			(layer "F.SilkS")
		)
		(fp_line
			(start -0.7874 0.4064)
			(end -0.7874 -0.4064)
			(stroke
				(width 0.1524)
				(type default)
			)
			(layer "F.SilkS")
		)
		(fp_line
			(start -0.12065 -0.305054)
			(end -0.12065 -0.2794)
			(stroke
				(width 0.1)
				(type default)
			)
			(layer "F.Fab")
		)
		(fp_line
			(start -0.67945 -0.305054)
			(end -0.12065 -0.305054)
			(stroke
				(width 0.1)
				(type default)
			)
			(layer "F.Fab")
		)
		(fp_line
			(start 0.67945 -0.3048)
			(end 0.67945 0.3048)
			(stroke
				(width 0.1)
				(type default)
			)
			(layer "F.Fab")
		)
		(fp_line
			(start 0.12065 -0.3048)
			(end 0.67945 -0.3048)
			(stroke
				(width 0.1)
				(type default)
			)
			(layer "F.Fab")
		)
		(fp_line
			(start 0.12065 -0.2794)
			(end 0.12065 -0.3048)
			(stroke
				(width 0.1)
				(type default)
			)
			(layer "F.Fab")
		)
		(fp_line
			(start -0.12065 -0.2794)
			(end 0.12065 -0.2794)
			(stroke
				(width 0.1)
				(type default)
			)
			(layer "F.Fab")
		)
		(fp_line
			(start 0.120396 0.2794)
			(end -0.12065 0.2794)
			(stroke
				(width 0.1)
				(type default)
			)
			(layer "F.Fab")
		)
		(fp_line
			(start -0.12065 0.2794)
			(end -0.12065 0.3048)
			(stroke
				(width 0.1)
				(type default)
			)
			(layer "F.Fab")
		)
		(fp_line
			(start 0.67945 0.3048)
			(end 0.120396 0.3048)
			(stroke
				(width 0.1)
				(type default)
			)
			(layer "F.Fab")
		)
		(fp_line
			(start 0.120396 0.3048)
			(end 0.120396 0.2794)
			(stroke
				(width 0.1)
				(type default)
			)
			(layer "F.Fab")
		)
		(fp_line
			(start -0.12065 0.3048)
			(end -0.67945 0.3048)
			(stroke
				(width 0.1)
				(type default)
			)
			(layer "F.Fab")
		)
		(fp_line
			(start -0.67945 0.3048)
			(end -0.67945 -0.305054)
			(stroke
				(width 0.1)
				(type default)
			)
			(layer "F.Fab")
		)
		(pad "1" smd circle
			(at -0.40005 0 90)
			(size 0 0)
			(layers "F.Cu" "F.Mask" "F.Paste")
			(net "P3V3_OCP_GATE_1")
		)
		(pad "2" smd circle
			(at 0.40005 0 90)
			(size 0 0)
			(layers "F.Cu" "F.Mask" "F.Paste")
			(net "GND")
		)
	)
	(footprint ""
		(layer "F.Cu")
		(at 376.271536 -105.483152 90)
		(property "Reference" "R1368"
			(at 0 0 90)
			(layer "F.SilkS")
			(hide yes)
			(effects
				(font
					(size 1.27 1.27)
				)
			)
		)
		(property "Value" ""
			(at 0 0 90)
			(layer "F.Fab")
			(effects
				(font
					(size 1.27 1.27)
				)
			)
		)
		(duplicate_pad_numbers_are_jumpers no)
		(fp_line
			(start 0.7874 -0.4064)
			(end 0.7874 0.4064)
			(stroke
				(width 0.1524)
				(type default)
			)
			(layer "F.SilkS")
		)
		(fp_line
			(start -0.7874 -0.4064)
			(end 0.7874 -0.4064)
			(stroke
				(width 0.1524)
				(type default)
			)
			(layer "F.SilkS")
		)
		(fp_line
			(start 0.7874 0.4064)
			(end -0.7874 0.4064)
			(stroke
				(width 0.1524)
				(type default)
			)
			(layer "F.SilkS")
		)
		(fp_line
			(start -0.7874 0.4064)
			(end -0.7874 -0.4064)
			(stroke
				(width 0.1524)
				(type default)
			)
			(layer "F.SilkS")
		)
		(fp_line
			(start -0.12065 -0.305054)
			(end -0.12065 -0.2794)
			(stroke
				(width 0.1)
				(type default)
			)
			(layer "F.Fab")
		)
		(fp_line
			(start -0.67945 -0.305054)
			(end -0.12065 -0.305054)
			(stroke
				(width 0.1)
				(type default)
			)
			(layer "F.Fab")
		)
		(fp_line
			(start 0.67945 -0.3048)
			(end 0.67945 0.3048)
			(stroke
				(width 0.1)
				(type default)
			)
			(layer "F.Fab")
		)
		(fp_line
			(start 0.12065 -0.3048)
			(end 0.67945 -0.3048)
			(stroke
				(width 0.1)
				(type default)
			)
			(layer "F.Fab")
		)
		(fp_line
			(start 0.12065 -0.2794)
			(end 0.12065 -0.3048)
			(stroke
				(width 0.1)
				(type default)
			)
			(layer "F.Fab")
		)
		(fp_line
			(start -0.12065 -0.2794)
			(end 0.12065 -0.2794)
			(stroke
				(width 0.1)
				(type default)
			)
			(layer "F.Fab")
		)
		(fp_line
			(start 0.120396 0.2794)
			(end -0.12065 0.2794)
			(stroke
				(width 0.1)
				(type default)
			)
			(layer "F.Fab")
		)
		(fp_line
			(start -0.12065 0.2794)
			(end -0.12065 0.3048)
			(stroke
				(width 0.1)
				(type default)
			)
			(layer "F.Fab")
		)
		(fp_line
			(start 0.67945 0.3048)
			(end 0.120396 0.3048)
			(stroke
				(width 0.1)
				(type default)
			)
			(layer "F.Fab")
		)
		(fp_line
			(start 0.120396 0.3048)
			(end 0.120396 0.2794)
			(stroke
				(width 0.1)
				(type default)
			)
			(layer "F.Fab")
		)
		(fp_line
			(start -0.12065 0.3048)
			(end -0.67945 0.3048)
			(stroke
				(width 0.1)
				(type default)
			)
			(layer "F.Fab")
		)
		(fp_line
			(start -0.67945 0.3048)
			(end -0.67945 -0.305054)
			(stroke
				(width 0.1)
				(type default)
			)
			(layer "F.Fab")
		)
		(pad "1" smd circle
			(at -0.40005 0 90)
			(size 0 0)
			(layers "F.Cu" "F.Mask" "F.Paste")
			(net "PD_JTAG_DBP_B2")
		)
		(pad "2" smd circle
			(at 0.40005 0 90)
			(size 0 0)
			(layers "F.Cu" "F.Mask" "F.Paste")
			(net "GND")
		)
	)
	(footprint ""
		(layer "F.Cu")
		(at 132.15874 -115.585748 180)
		(property "Reference" "C1818"
			(at 0 0 180)
			(layer "F.SilkS")
			(hide yes)
			(effects
				(font
					(size 1.27 1.27)
				)
			)
		)
		(property "Value" ""
			(at 0 0 180)
			(layer "F.Fab")
			(effects
				(font
					(size 1.27 1.27)
				)
			)
		)
		(duplicate_pad_numbers_are_jumpers no)
		(fp_line
			(start 0.7874 0.4064)
			(end -0.7874 0.4064)
			(stroke
				(width 0.1524)
				(type default)
			)
			(layer "F.SilkS")
		)
		(fp_line
			(start 0.7874 -0.4064)
			(end 0.7874 0.4064)
			(stroke
				(width 0.1524)
				(type default)
			)
			(layer "F.SilkS")
		)
		(fp_line
			(start -0.7874 0.4064)
			(end -0.7874 -0.4064)
			(stroke
				(width 0.1524)
				(type default)
			)
			(layer "F.SilkS")
		)
		(fp_line
			(start -0.7874 -0.4064)
			(end 0.7874 -0.4064)
			(stroke
				(width 0.1524)
				(type default)
			)
			(layer "F.SilkS")
		)
		(fp_line
			(start 0.67945 0.3048)
			(end 0.120396 0.3048)
			(stroke
				(width 0.1)
				(type default)
			)
			(layer "F.Fab")
		)
		(fp_line
			(start 0.67945 -0.3048)
			(end 0.67945 0.3048)
			(stroke
				(width 0.1)
				(type default)
			)
			(layer "F.Fab")
		)
		(fp_line
			(start 0.12065 -0.2794)
			(end 0.12065 -0.3048)
			(stroke
				(width 0.1)
				(type default)
			)
			(layer "F.Fab")
		)
		(fp_line
			(start 0.12065 -0.3048)
			(end 0.67945 -0.3048)
			(stroke
				(width 0.1)
				(type default)
			)
			(layer "F.Fab")
		)
		(fp_line
			(start 0.120396 0.3048)
			(end 0.120396 0.2794)
			(stroke
				(width 0.1)
				(type default)
			)
			(layer "F.Fab")
		)
		(fp_line
			(start 0.120396 0.2794)
			(end -0.12065 0.2794)
			(stroke
				(width 0.1)
				(type default)
			)
			(layer "F.Fab")
		)
		(fp_line
			(start -0.12065 0.3048)
			(end -0.67945 0.3048)
			(stroke
				(width 0.1)
				(type default)
			)
			(layer "F.Fab")
		)
		(fp_line
			(start -0.12065 0.2794)
			(end -0.12065 0.3048)
			(stroke
				(width 0.1)
				(type default)
			)
			(layer "F.Fab")
		)
		(fp_line
			(start -0.12065 -0.2794)
			(end 0.12065 -0.2794)
			(stroke
				(width 0.1)
				(type default)
			)
			(layer "F.Fab")
		)
		(fp_line
			(start -0.12065 -0.305054)
			(end -0.12065 -0.2794)
			(stroke
				(width 0.1)
				(type default)
			)
			(layer "F.Fab")
		)
		(fp_line
			(start -0.67945 0.3048)
			(end -0.67945 -0.305054)
			(stroke
				(width 0.1)
				(type default)
			)
			(layer "F.Fab")
		)
		(fp_line
			(start -0.67945 -0.305054)
			(end -0.12065 -0.305054)
			(stroke
				(width 0.1)
				(type default)
			)
			(layer "F.Fab")
		)
		(pad "1" smd circle
			(at -0.40005 0 180)
			(size 0 0)
			(layers "F.Cu" "F.Mask" "F.Paste")
			(net "P3V3_AUX")
		)
		(pad "2" smd circle
			(at 0.40005 0 180)
			(size 0 0)
			(layers "F.Cu" "F.Mask" "F.Paste")
			(net "GND")
		)
	)
	(footprint ""
		(layer "F.Cu")
		(at 32.272478 -16.099536 90)
		(property "Reference" "C819"
			(at 0 0 90)
			(layer "F.SilkS")
			(hide yes)
			(effects
				(font
					(size 1.27 1.27)
				)
			)
		)
		(property "Value" ""
			(at 0 0 90)
			(layer "F.Fab")
			(effects
				(font
					(size 1.27 1.27)
				)
			)
		)
		(duplicate_pad_numbers_are_jumpers no)
		(fp_line
			(start 0.299974 -0.150114)
			(end 0.299974 0.150114)
			(stroke
				(width 0.1)
				(type default)
			)
			(layer "F.Fab")
		)
		(fp_line
			(start -0.299974 -0.150114)
			(end 0.299974 -0.150114)
			(stroke
				(width 0.1)
				(type default)
			)
			(layer "F.Fab")
		)
		(fp_line
			(start 0.299974 0.150114)
			(end -0.299974 0.150114)
			(stroke
				(width 0.1)
				(type default)
			)
			(layer "F.Fab")
		)
		(fp_line
			(start -0.299974 0.150114)
			(end -0.299974 -0.150114)
			(stroke
				(width 0.1)
				(type default)
			)
			(layer "F.Fab")
		)
		(pad "1" smd rect
			(at -0.2667 0 90)
			(size 0.3048 0.381)
			(layers "F.Cu" "F.Mask" "F.Paste")
			(net "P5E_CPU1_PE1_TX_C_DP<9>")
		)
		(pad "2" smd rect
			(at 0.2667 0 90)
			(size 0.3048 0.381)
			(layers "F.Cu" "F.Mask" "F.Paste")
			(net "P5E_CPU1_PE1_TX_DP<9>")
		)
	)
	(footprint ""
		(layer "F.Cu")
		(at 163.014914 -402.371052 -90)
		(property "Reference" "C771"
			(at 0 0 270)
			(layer "F.SilkS")
			(hide yes)
			(effects
				(font
					(size 1.27 1.27)
				)
			)
		)
		(property "Value" ""
			(at 0 0 270)
			(layer "F.Fab")
			(effects
				(font
					(size 1.27 1.27)
				)
			)
		)
		(duplicate_pad_numbers_are_jumpers no)
		(fp_line
			(start -0.299974 0.150114)
			(end -0.299974 -0.150114)
			(stroke
				(width 0.1)
				(type default)
			)
			(layer "F.Fab")
		)
		(fp_line
			(start 0.299974 0.150114)
			(end -0.299974 0.150114)
			(stroke
				(width 0.1)
				(type default)
			)
			(layer "F.Fab")
		)
		(fp_line
			(start -0.299974 -0.150114)
			(end 0.299974 -0.150114)
			(stroke
				(width 0.1)
				(type default)
			)
			(layer "F.Fab")
		)
		(fp_line
			(start 0.299974 -0.150114)
			(end 0.299974 0.150114)
			(stroke
				(width 0.1)
				(type default)
			)
			(layer "F.Fab")
		)
		(pad "1" smd rect
			(at -0.2667 0 270)
			(size 0.3048 0.381)
			(layers "F.Cu" "F.Mask" "F.Paste")
			(net "P5E_CPU1_PE2_TX_C_DP<1>")
		)
		(pad "2" smd rect
			(at 0.2667 0 270)
			(size 0.3048 0.381)
			(layers "F.Cu" "F.Mask" "F.Paste")
			(net "P5E_CPU1_PE2_TX_DP<1>")
		)
	)
	(footprint ""
		(layer "F.Cu")
		(at 428.226474 -122.62866 180)
		(property "Reference" "PC624"
			(at 0 0 180)
			(layer "F.SilkS")
			(hide yes)
			(effects
				(font
					(size 1.27 1.27)
				)
			)
		)
		(property "Value" ""
			(at 0 0 180)
			(layer "F.Fab")
			(effects
				(font
					(size 1.27 1.27)
				)
			)
		)
		(duplicate_pad_numbers_are_jumpers no)
		(fp_line
			(start 0.7874 0.4064)
			(end -0.7874 0.4064)
			(stroke
				(width 0.1524)
				(type default)
			)
			(layer "F.SilkS")
		)
		(fp_line
			(start 0.7874 -0.4064)
			(end 0.7874 0.4064)
			(stroke
				(width 0.1524)
				(type default)
			)
			(layer "F.SilkS")
		)
		(fp_line
			(start -0.7874 0.4064)
			(end -0.7874 -0.4064)
			(stroke
				(width 0.1524)
				(type default)
			)
			(layer "F.SilkS")
		)
		(fp_line
			(start -0.7874 -0.4064)
			(end 0.7874 -0.4064)
			(stroke
				(width 0.1524)
				(type default)
			)
			(layer "F.SilkS")
		)
		(fp_line
			(start 0.67945 0.3048)
			(end 0.120396 0.3048)
			(stroke
				(width 0.1)
				(type default)
			)
			(layer "F.Fab")
		)
		(fp_line
			(start 0.67945 -0.3048)
			(end 0.67945 0.3048)
			(stroke
				(width 0.1)
				(type default)
			)
			(layer "F.Fab")
		)
		(fp_line
			(start 0.12065 -0.2794)
			(end 0.12065 -0.3048)
			(stroke
				(width 0.1)
				(type default)
			)
			(layer "F.Fab")
		)
		(fp_line
			(start 0.12065 -0.3048)
			(end 0.67945 -0.3048)
			(stroke
				(width 0.1)
				(type default)
			)
			(layer "F.Fab")
		)
		(fp_line
			(start 0.120396 0.3048)
			(end 0.120396 0.2794)
			(stroke
				(width 0.1)
				(type default)
			)
			(layer "F.Fab")
		)
		(fp_line
			(start 0.120396 0.2794)
			(end -0.12065 0.2794)
			(stroke
				(width 0.1)
				(type default)
			)
			(layer "F.Fab")
		)
		(fp_line
			(start -0.12065 0.3048)
			(end -0.67945 0.3048)
			(stroke
				(width 0.1)
				(type default)
			)
			(layer "F.Fab")
		)
		(fp_line
			(start -0.12065 0.2794)
			(end -0.12065 0.3048)
			(stroke
				(width 0.1)
				(type default)
			)
			(layer "F.Fab")
		)
		(fp_line
			(start -0.12065 -0.2794)
			(end 0.12065 -0.2794)
			(stroke
				(width 0.1)
				(type default)
			)
			(layer "F.Fab")
		)
		(fp_line
			(start -0.12065 -0.305054)
			(end -0.12065 -0.2794)
			(stroke
				(width 0.1)
				(type default)
			)
			(layer "F.Fab")
		)
		(fp_line
			(start -0.67945 0.3048)
			(end -0.67945 -0.305054)
			(stroke
				(width 0.1)
				(type default)
			)
			(layer "F.Fab")
		)
		(fp_line
			(start -0.67945 -0.305054)
			(end -0.12065 -0.305054)
			(stroke
				(width 0.1)
				(type default)
			)
			(layer "F.Fab")
		)
		(pad "1" smd circle
			(at -0.40005 0 180)
			(size 0 0)
			(layers "F.Cu" "F.Mask" "F.Paste")
			(net "PVCCD_HV_CPU0_ISENSE_P")
		)
		(pad "2" smd circle
			(at 0.40005 0 180)
			(size 0 0)
			(layers "F.Cu" "F.Mask" "F.Paste")
			(net "GND")
		)
	)
	(footprint ""
		(layer "F.Cu")
		(at 320.241422 -63.896748)
		(property "Reference" "R1249"
			(at 0 0 0)
			(layer "F.SilkS")
			(hide yes)
			(effects
				(font
					(size 1.27 1.27)
				)
			)
		)
		(property "Value" ""
			(at 0 0 0)
			(layer "F.Fab")
			(effects
				(font
					(size 1.27 1.27)
				)
			)
		)
		(duplicate_pad_numbers_are_jumpers no)
		(fp_line
			(start -0.7874 -0.4064)
			(end 0.7874 -0.4064)
			(stroke
				(width 0.1524)
				(type default)
			)
			(layer "F.SilkS")
		)
		(fp_line
			(start -0.7874 0.4064)
			(end -0.7874 -0.4064)
			(stroke
				(width 0.1524)
				(type default)
			)
			(layer "F.SilkS")
		)
		(fp_line
			(start 0.7874 -0.4064)
			(end 0.7874 0.4064)
			(stroke
				(width 0.1524)
				(type default)
			)
			(layer "F.SilkS")
		)
		(fp_line
			(start 0.7874 0.4064)
			(end -0.7874 0.4064)
			(stroke
				(width 0.1524)
				(type default)
			)
			(layer "F.SilkS")
		)
		(fp_line
			(start -0.67945 -0.305054)
			(end -0.12065 -0.305054)
			(stroke
				(width 0.1)
				(type default)
			)
			(layer "F.Fab")
		)
		(fp_line
			(start -0.67945 0.3048)
			(end -0.67945 -0.305054)
			(stroke
				(width 0.1)
				(type default)
			)
			(layer "F.Fab")
		)
		(fp_line
			(start -0.12065 -0.305054)
			(end -0.12065 -0.2794)
			(stroke
				(width 0.1)
				(type default)
			)
			(layer "F.Fab")
		)
		(fp_line
			(start -0.12065 -0.2794)
			(end 0.12065 -0.2794)
			(stroke
				(width 0.1)
				(type default)
			)
			(layer "F.Fab")
		)
		(fp_line
			(start -0.12065 0.2794)
			(end -0.12065 0.3048)
			(stroke
				(width 0.1)
				(type default)
			)
			(layer "F.Fab")
		)
		(fp_line
			(start -0.12065 0.3048)
			(end -0.67945 0.3048)
			(stroke
				(width 0.1)
				(type default)
			)
			(layer "F.Fab")
		)
		(fp_line
			(start 0.120396 0.2794)
			(end -0.12065 0.2794)
			(stroke
				(width 0.1)
				(type default)
			)
			(layer "F.Fab")
		)
		(fp_line
			(start 0.120396 0.3048)
			(end 0.120396 0.2794)
			(stroke
				(width 0.1)
				(type default)
			)
			(layer "F.Fab")
		)
		(fp_line
			(start 0.12065 -0.3048)
			(end 0.67945 -0.3048)
			(stroke
				(width 0.1)
				(type default)
			)
			(layer "F.Fab")
		)
		(fp_line
			(start 0.12065 -0.2794)
			(end 0.12065 -0.3048)
			(stroke
				(width 0.1)
				(type default)
			)
			(layer "F.Fab")
		)
		(fp_line
			(start 0.67945 -0.3048)
			(end 0.67945 0.3048)
			(stroke
				(width 0.1)
				(type default)
			)
			(layer "F.Fab")
		)
		(fp_line
			(start 0.67945 0.3048)
			(end 0.120396 0.3048)
			(stroke
				(width 0.1)
				(type default)
			)
			(layer "F.Fab")
		)
		(pad "1" smd circle
			(at -0.40005 0)
			(size 0 0)
			(layers "F.Cu" "F.Mask" "F.Paste")
			(net "FM_THERMTRIP_DLY_LVC1_N")
		)
		(pad "2" smd circle
			(at 0.40005 0)
			(size 0 0)
			(layers "F.Cu" "F.Mask" "F.Paste")
			(net "H_THERMTRIP_LVC1_N")
		)
	)
	(footprint ""
		(layer "F.Cu")
		(at 205.397608 -404.823422)
		(property "Reference" "PC2182"
			(at 0 0 0)
			(layer "F.SilkS")
			(hide yes)
			(effects
				(font
					(size 1.27 1.27)
				)
			)
		)
		(property "Value" ""
			(at 0 0 0)
			(layer "F.Fab")
			(effects
				(font
					(size 1.27 1.27)
				)
			)
		)
		(duplicate_pad_numbers_are_jumpers no)
		(fp_line
			(start -0.7874 -0.4064)
			(end 0.7874 -0.4064)
			(stroke
				(width 0.1524)
				(type default)
			)
			(layer "F.SilkS")
		)
		(fp_line
			(start -0.7874 0.4064)
			(end -0.7874 -0.4064)
			(stroke
				(width 0.1524)
				(type default)
			)
			(layer "F.SilkS")
		)
		(fp_line
			(start 0.7874 -0.4064)
			(end 0.7874 0.4064)
			(stroke
				(width 0.1524)
				(type default)
			)
			(layer "F.SilkS")
		)
		(fp_line
			(start 0.7874 0.4064)
			(end -0.7874 0.4064)
			(stroke
				(width 0.1524)
				(type default)
			)
			(layer "F.SilkS")
		)
		(fp_line
			(start -0.67945 -0.305054)
			(end -0.12065 -0.305054)
			(stroke
				(width 0.1)
				(type default)
			)
			(layer "F.Fab")
		)
		(fp_line
			(start -0.67945 0.3048)
			(end -0.67945 -0.305054)
			(stroke
				(width 0.1)
				(type default)
			)
			(layer "F.Fab")
		)
		(fp_line
			(start -0.12065 -0.305054)
			(end -0.12065 -0.2794)
			(stroke
				(width 0.1)
				(type default)
			)
			(layer "F.Fab")
		)
		(fp_line
			(start -0.12065 -0.2794)
			(end 0.12065 -0.2794)
			(stroke
				(width 0.1)
				(type default)
			)
			(layer "F.Fab")
		)
		(fp_line
			(start -0.12065 0.2794)
			(end -0.12065 0.3048)
			(stroke
				(width 0.1)
				(type default)
			)
			(layer "F.Fab")
		)
		(fp_line
			(start -0.12065 0.3048)
			(end -0.67945 0.3048)
			(stroke
				(width 0.1)
				(type default)
			)
			(layer "F.Fab")
		)
		(fp_line
			(start 0.120396 0.2794)
			(end -0.12065 0.2794)
			(stroke
				(width 0.1)
				(type default)
			)
			(layer "F.Fab")
		)
		(fp_line
			(start 0.120396 0.3048)
			(end 0.120396 0.2794)
			(stroke
				(width 0.1)
				(type default)
			)
			(layer "F.Fab")
		)
		(fp_line
			(start 0.12065 -0.3048)
			(end 0.67945 -0.3048)
			(stroke
				(width 0.1)
				(type default)
			)
			(layer "F.Fab")
		)
		(fp_line
			(start 0.12065 -0.2794)
			(end 0.12065 -0.3048)
			(stroke
				(width 0.1)
				(type default)
			)
			(layer "F.Fab")
		)
		(fp_line
			(start 0.67945 -0.3048)
			(end 0.67945 0.3048)
			(stroke
				(width 0.1)
				(type default)
			)
			(layer "F.Fab")
		)
		(fp_line
			(start 0.67945 0.3048)
			(end 0.120396 0.3048)
			(stroke
				(width 0.1)
				(type default)
			)
			(layer "F.Fab")
		)
		(pad "1" smd circle
			(at -0.40005 0)
			(size 0 0)
			(layers "F.Cu" "F.Mask" "F.Paste")
			(net "HSC_ON")
		)
		(pad "2" smd circle
			(at 0.40005 0)
			(size 0 0)
			(layers "F.Cu" "F.Mask" "F.Paste")
			(net "AGND_HSC")
		)
	)
	(footprint ""
		(layer "F.Cu")
		(at 462.143094 -38.684454 90)
		(property "Reference" "R4061"
			(at 0 0 90)
			(layer "F.SilkS")
			(hide yes)
			(effects
				(font
					(size 1.27 1.27)
				)
			)
		)
		(property "Value" ""
			(at 0 0 90)
			(layer "F.Fab")
			(effects
				(font
					(size 1.27 1.27)
				)
			)
		)
		(duplicate_pad_numbers_are_jumpers no)
		(fp_line
			(start 0.7874 -0.4064)
			(end 0.7874 0.4064)
			(stroke
				(width 0.1524)
				(type default)
			)
			(layer "F.SilkS")
		)
		(fp_line
			(start -0.7874 -0.4064)
			(end 0.7874 -0.4064)
			(stroke
				(width 0.1524)
				(type default)
			)
			(layer "F.SilkS")
		)
		(fp_line
			(start 0.7874 0.4064)
			(end -0.7874 0.4064)
			(stroke
				(width 0.1524)
				(type default)
			)
			(layer "F.SilkS")
		)
		(fp_line
			(start -0.7874 0.4064)
			(end -0.7874 -0.4064)
			(stroke
				(width 0.1524)
				(type default)
			)
			(layer "F.SilkS")
		)
		(fp_line
			(start -0.12065 -0.305054)
			(end -0.12065 -0.2794)
			(stroke
				(width 0.1)
				(type default)
			)
			(layer "F.Fab")
		)
		(fp_line
			(start -0.67945 -0.305054)
			(end -0.12065 -0.305054)
			(stroke
				(width 0.1)
				(type default)
			)
			(layer "F.Fab")
		)
		(fp_line
			(start 0.67945 -0.3048)
			(end 0.67945 0.3048)
			(stroke
				(width 0.1)
				(type default)
			)
			(layer "F.Fab")
		)
		(fp_line
			(start 0.12065 -0.3048)
			(end 0.67945 -0.3048)
			(stroke
				(width 0.1)
				(type default)
			)
			(layer "F.Fab")
		)
		(fp_line
			(start 0.12065 -0.2794)
			(end 0.12065 -0.3048)
			(stroke
				(width 0.1)
				(type default)
			)
			(layer "F.Fab")
		)
		(fp_line
			(start -0.12065 -0.2794)
			(end 0.12065 -0.2794)
			(stroke
				(width 0.1)
				(type default)
			)
			(layer "F.Fab")
		)
		(fp_line
			(start 0.120396 0.2794)
			(end -0.12065 0.2794)
			(stroke
				(width 0.1)
				(type default)
			)
			(layer "F.Fab")
		)
		(fp_line
			(start -0.12065 0.2794)
			(end -0.12065 0.3048)
			(stroke
				(width 0.1)
				(type default)
			)
			(layer "F.Fab")
		)
		(fp_line
			(start 0.67945 0.3048)
			(end 0.120396 0.3048)
			(stroke
				(width 0.1)
				(type default)
			)
			(layer "F.Fab")
		)
		(fp_line
			(start 0.120396 0.3048)
			(end 0.120396 0.2794)
			(stroke
				(width 0.1)
				(type default)
			)
			(layer "F.Fab")
		)
		(fp_line
			(start -0.12065 0.3048)
			(end -0.67945 0.3048)
			(stroke
				(width 0.1)
				(type default)
			)
			(layer "F.Fab")
		)
		(fp_line
			(start -0.67945 0.3048)
			(end -0.67945 -0.305054)
			(stroke
				(width 0.1)
				(type default)
			)
			(layer "F.Fab")
		)
		(pad "1" smd circle
			(at -0.40005 0 90)
			(size 0 0)
			(layers "F.Cu" "F.Mask" "F.Paste")
			(net "HP_LVC3_OCP_V3_1_EN")
		)
		(pad "2" smd circle
			(at 0.40005 0 90)
			(size 0 0)
			(layers "F.Cu" "F.Mask" "F.Paste")
			(net "P12V_OCP_EN_1_R")
		)
	)
	(footprint ""
		(layer "F.Cu")
		(at 160.83788 -108.295948)
		(property "Reference" "R3230"
			(at 0 0 0)
			(layer "F.SilkS")
			(hide yes)
			(effects
				(font
					(size 1.27 1.27)
				)
			)
		)
		(property "Value" ""
			(at 0 0 0)
			(layer "F.Fab")
			(effects
				(font
					(size 1.27 1.27)
				)
			)
		)
		(duplicate_pad_numbers_are_jumpers no)
		(fp_line
			(start -0.7874 -0.4064)
			(end 0.7874 -0.4064)
			(stroke
				(width 0.1524)
				(type default)
			)
			(layer "F.SilkS")
		)
		(fp_line
			(start -0.7874 0.4064)
			(end -0.7874 -0.4064)
			(stroke
				(width 0.1524)
				(type default)
			)
			(layer "F.SilkS")
		)
		(fp_line
			(start 0.7874 -0.4064)
			(end 0.7874 0.4064)
			(stroke
				(width 0.1524)
				(type default)
			)
			(layer "F.SilkS")
		)
		(fp_line
			(start 0.7874 0.4064)
			(end -0.7874 0.4064)
			(stroke
				(width 0.1524)
				(type default)
			)
			(layer "F.SilkS")
		)
		(fp_line
			(start -0.67945 -0.305054)
			(end -0.12065 -0.305054)
			(stroke
				(width 0.1)
				(type default)
			)
			(layer "F.Fab")
		)
		(fp_line
			(start -0.67945 0.3048)
			(end -0.67945 -0.305054)
			(stroke
				(width 0.1)
				(type default)
			)
			(layer "F.Fab")
		)
		(fp_line
			(start -0.12065 -0.305054)
			(end -0.12065 -0.2794)
			(stroke
				(width 0.1)
				(type default)
			)
			(layer "F.Fab")
		)
		(fp_line
			(start -0.12065 -0.2794)
			(end 0.12065 -0.2794)
			(stroke
				(width 0.1)
				(type default)
			)
			(layer "F.Fab")
		)
		(fp_line
			(start -0.12065 0.2794)
			(end -0.12065 0.3048)
			(stroke
				(width 0.1)
				(type default)
			)
			(layer "F.Fab")
		)
		(fp_line
			(start -0.12065 0.3048)
			(end -0.67945 0.3048)
			(stroke
				(width 0.1)
				(type default)
			)
			(layer "F.Fab")
		)
		(fp_line
			(start 0.120396 0.2794)
			(end -0.12065 0.2794)
			(stroke
				(width 0.1)
				(type default)
			)
			(layer "F.Fab")
		)
		(fp_line
			(start 0.120396 0.3048)
			(end 0.120396 0.2794)
			(stroke
				(width 0.1)
				(type default)
			)
			(layer "F.Fab")
		)
		(fp_line
			(start 0.12065 -0.3048)
			(end 0.67945 -0.3048)
			(stroke
				(width 0.1)
				(type default)
			)
			(layer "F.Fab")
		)
		(fp_line
			(start 0.12065 -0.2794)
			(end 0.12065 -0.3048)
			(stroke
				(width 0.1)
				(type default)
			)
			(layer "F.Fab")
		)
		(fp_line
			(start 0.67945 -0.3048)
			(end 0.67945 0.3048)
			(stroke
				(width 0.1)
				(type default)
			)
			(layer "F.Fab")
		)
		(fp_line
			(start 0.67945 0.3048)
			(end 0.120396 0.3048)
			(stroke
				(width 0.1)
				(type default)
			)
			(layer "F.Fab")
		)
		(pad "1" smd circle
			(at -0.40005 0)
			(size 0 0)
			(layers "F.Cu" "F.Mask" "F.Paste")
			(net "FM_OCP_V3_2_PWR_GOOD")
		)
		(pad "2" smd circle
			(at 0.40005 0)
			(size 0 0)
			(layers "F.Cu" "F.Mask" "F.Paste")
			(net "FM_OCP_V3_2_PWR_GOOD_R")
		)
	)
	(footprint ""
		(layer "F.Cu")
		(at 97.992438 -354.88499 -90)
		(property "Reference" "PC1656"
			(at 0 0 270)
			(layer "F.SilkS")
			(hide yes)
			(effects
				(font
					(size 1.27 1.27)
				)
			)
		)
		(property "Value" ""
			(at 0 0 270)
			(layer "F.Fab")
			(effects
				(font
					(size 1.27 1.27)
				)
			)
		)
		(duplicate_pad_numbers_are_jumpers no)
		(fp_line
			(start -0.7874 0.4064)
			(end -0.7874 -0.4064)
			(stroke
				(width 0.1524)
				(type default)
			)
			(layer "F.SilkS")
		)
		(fp_line
			(start 0.7874 0.4064)
			(end -0.7874 0.4064)
			(stroke
				(width 0.1524)
				(type default)
			)
			(layer "F.SilkS")
		)
		(fp_line
			(start -0.7874 -0.4064)
			(end 0.7874 -0.4064)
			(stroke
				(width 0.1524)
				(type default)
			)
			(layer "F.SilkS")
		)
		(fp_line
			(start 0.7874 -0.4064)
			(end 0.7874 0.4064)
			(stroke
				(width 0.1524)
				(type default)
			)
			(layer "F.SilkS")
		)
		(fp_line
			(start -0.67945 0.3048)
			(end -0.67945 -0.305054)
			(stroke
				(width 0.1)
				(type default)
			)
			(layer "F.Fab")
		)
		(fp_line
			(start -0.12065 0.3048)
			(end -0.67945 0.3048)
			(stroke
				(width 0.1)
				(type default)
			)
			(layer "F.Fab")
		)
		(fp_line
			(start 0.120396 0.3048)
			(end 0.120396 0.2794)
			(stroke
				(width 0.1)
				(type default)
			)
			(layer "F.Fab")
		)
		(fp_line
			(start 0.67945 0.3048)
			(end 0.120396 0.3048)
			(stroke
				(width 0.1)
				(type default)
			)
			(layer "F.Fab")
		)
		(fp_line
			(start -0.12065 0.2794)
			(end -0.12065 0.3048)
			(stroke
				(width 0.1)
				(type default)
			)
			(layer "F.Fab")
		)
		(fp_line
			(start 0.120396 0.2794)
			(end -0.12065 0.2794)
			(stroke
				(width 0.1)
				(type default)
			)
			(layer "F.Fab")
		)
		(fp_line
			(start -0.12065 -0.2794)
			(end 0.12065 -0.2794)
			(stroke
				(width 0.1)
				(type default)
			)
			(layer "F.Fab")
		)
		(fp_line
			(start 0.12065 -0.2794)
			(end 0.12065 -0.3048)
			(stroke
				(width 0.1)
				(type default)
			)
			(layer "F.Fab")
		)
		(fp_line
			(start 0.12065 -0.3048)
			(end 0.67945 -0.3048)
			(stroke
				(width 0.1)
				(type default)
			)
			(layer "F.Fab")
		)
		(fp_line
			(start 0.67945 -0.3048)
			(end 0.67945 0.3048)
			(stroke
				(width 0.1)
				(type default)
			)
			(layer "F.Fab")
		)
		(fp_line
			(start -0.67945 -0.305054)
			(end -0.12065 -0.305054)
			(stroke
				(width 0.1)
				(type default)
			)
			(layer "F.Fab")
		)
		(fp_line
			(start -0.12065 -0.305054)
			(end -0.12065 -0.2794)
			(stroke
				(width 0.1)
				(type default)
			)
			(layer "F.Fab")
		)
		(pad "1" smd circle
			(at -0.40005 0 270)
			(size 0 0)
			(layers "F.Cu" "F.Mask" "F.Paste")
			(net "P12V_AUX")
		)
		(pad "2" smd circle
			(at 0.40005 0 270)
			(size 0 0)
			(layers "F.Cu" "F.Mask" "F.Paste")
			(net "GND")
		)
	)
	(footprint ""
		(layer "F.Cu")
		(at 30.748732 -403.695408 180)
		(property "Reference" "R3320"
			(at 0 0 180)
			(layer "F.SilkS")
			(hide yes)
			(effects
				(font
					(size 1.27 1.27)
				)
			)
		)
		(property "Value" ""
			(at 0 0 180)
			(layer "F.Fab")
			(effects
				(font
					(size 1.27 1.27)
				)
			)
		)
		(duplicate_pad_numbers_are_jumpers no)
		(fp_line
			(start 0.7874 0.4064)
			(end -0.7874 0.4064)
			(stroke
				(width 0.1524)
				(type default)
			)
			(layer "F.SilkS")
		)
		(fp_line
			(start 0.7874 -0.4064)
			(end 0.7874 0.4064)
			(stroke
				(width 0.1524)
				(type default)
			)
			(layer "F.SilkS")
		)
		(fp_line
			(start -0.7874 0.4064)
			(end -0.7874 -0.4064)
			(stroke
				(width 0.1524)
				(type default)
			)
			(layer "F.SilkS")
		)
		(fp_line
			(start -0.7874 -0.4064)
			(end 0.7874 -0.4064)
			(stroke
				(width 0.1524)
				(type default)
			)
			(layer "F.SilkS")
		)
		(fp_line
			(start 0.67945 0.3048)
			(end 0.120396 0.3048)
			(stroke
				(width 0.1)
				(type default)
			)
			(layer "F.Fab")
		)
		(fp_line
			(start 0.67945 -0.3048)
			(end 0.67945 0.3048)
			(stroke
				(width 0.1)
				(type default)
			)
			(layer "F.Fab")
		)
		(fp_line
			(start 0.12065 -0.2794)
			(end 0.12065 -0.3048)
			(stroke
				(width 0.1)
				(type default)
			)
			(layer "F.Fab")
		)
		(fp_line
			(start 0.12065 -0.3048)
			(end 0.67945 -0.3048)
			(stroke
				(width 0.1)
				(type default)
			)
			(layer "F.Fab")
		)
		(fp_line
			(start 0.120396 0.3048)
			(end 0.120396 0.2794)
			(stroke
				(width 0.1)
				(type default)
			)
			(layer "F.Fab")
		)
		(fp_line
			(start 0.120396 0.2794)
			(end -0.12065 0.2794)
			(stroke
				(width 0.1)
				(type default)
			)
			(layer "F.Fab")
		)
		(fp_line
			(start -0.12065 0.3048)
			(end -0.67945 0.3048)
			(stroke
				(width 0.1)
				(type default)
			)
			(layer "F.Fab")
		)
		(fp_line
			(start -0.12065 0.2794)
			(end -0.12065 0.3048)
			(stroke
				(width 0.1)
				(type default)
			)
			(layer "F.Fab")
		)
		(fp_line
			(start -0.12065 -0.2794)
			(end 0.12065 -0.2794)
			(stroke
				(width 0.1)
				(type default)
			)
			(layer "F.Fab")
		)
		(fp_line
			(start -0.12065 -0.305054)
			(end -0.12065 -0.2794)
			(stroke
				(width 0.1)
				(type default)
			)
			(layer "F.Fab")
		)
		(fp_line
			(start -0.67945 0.3048)
			(end -0.67945 -0.305054)
			(stroke
				(width 0.1)
				(type default)
			)
			(layer "F.Fab")
		)
		(fp_line
			(start -0.67945 -0.305054)
			(end -0.12065 -0.305054)
			(stroke
				(width 0.1)
				(type default)
			)
			(layer "F.Fab")
		)
		(pad "1" smd circle
			(at -0.40005 0 180)
			(size 0 0)
			(layers "F.Cu" "F.Mask" "F.Paste")
			(net "P3V3_AUX")
		)
		(pad "2" smd circle
			(at 0.40005 0 180)
			(size 0 0)
			(layers "F.Cu" "F.Mask" "F.Paste")
			(net "GPU_FPGA_READY_N")
		)
	)
	(footprint ""
		(layer "F.Cu")
		(at 179.352448 -405.303482 180)
		(property "Reference" "PC2192"
			(at 0 0 180)
			(layer "F.SilkS")
			(hide yes)
			(effects
				(font
					(size 1.27 1.27)
				)
			)
		)
		(property "Value" ""
			(at 0 0 180)
			(layer "F.Fab")
			(effects
				(font
					(size 1.27 1.27)
				)
			)
		)
		(duplicate_pad_numbers_are_jumpers no)
		(fp_line
			(start 0.7874 0.4064)
			(end -0.7874 0.4064)
			(stroke
				(width 0.1524)
				(type default)
			)
			(layer "F.SilkS")
		)
		(fp_line
			(start 0.7874 -0.4064)
			(end 0.7874 0.4064)
			(stroke
				(width 0.1524)
				(type default)
			)
			(layer "F.SilkS")
		)
		(fp_line
			(start -0.7874 0.4064)
			(end -0.7874 -0.4064)
			(stroke
				(width 0.1524)
				(type default)
			)
			(layer "F.SilkS")
		)
		(fp_line
			(start -0.7874 -0.4064)
			(end 0.7874 -0.4064)
			(stroke
				(width 0.1524)
				(type default)
			)
			(layer "F.SilkS")
		)
		(fp_line
			(start 0.67945 0.3048)
			(end 0.120396 0.3048)
			(stroke
				(width 0.1)
				(type default)
			)
			(layer "F.Fab")
		)
		(fp_line
			(start 0.67945 -0.3048)
			(end 0.67945 0.3048)
			(stroke
				(width 0.1)
				(type default)
			)
			(layer "F.Fab")
		)
		(fp_line
			(start 0.12065 -0.2794)
			(end 0.12065 -0.3048)
			(stroke
				(width 0.1)
				(type default)
			)
			(layer "F.Fab")
		)
		(fp_line
			(start 0.12065 -0.3048)
			(end 0.67945 -0.3048)
			(stroke
				(width 0.1)
				(type default)
			)
			(layer "F.Fab")
		)
		(fp_line
			(start 0.120396 0.3048)
			(end 0.120396 0.2794)
			(stroke
				(width 0.1)
				(type default)
			)
			(layer "F.Fab")
		)
		(fp_line
			(start 0.120396 0.2794)
			(end -0.12065 0.2794)
			(stroke
				(width 0.1)
				(type default)
			)
			(layer "F.Fab")
		)
		(fp_line
			(start -0.12065 0.3048)
			(end -0.67945 0.3048)
			(stroke
				(width 0.1)
				(type default)
			)
			(layer "F.Fab")
		)
		(fp_line
			(start -0.12065 0.2794)
			(end -0.12065 0.3048)
			(stroke
				(width 0.1)
				(type default)
			)
			(layer "F.Fab")
		)
		(fp_line
			(start -0.12065 -0.2794)
			(end 0.12065 -0.2794)
			(stroke
				(width 0.1)
				(type default)
			)
			(layer "F.Fab")
		)
		(fp_line
			(start -0.12065 -0.305054)
			(end -0.12065 -0.2794)
			(stroke
				(width 0.1)
				(type default)
			)
			(layer "F.Fab")
		)
		(fp_line
			(start -0.67945 0.3048)
			(end -0.67945 -0.305054)
			(stroke
				(width 0.1)
				(type default)
			)
			(layer "F.Fab")
		)
		(fp_line
			(start -0.67945 -0.305054)
			(end -0.12065 -0.305054)
			(stroke
				(width 0.1)
				(type default)
			)
			(layer "F.Fab")
		)
		(pad "1" smd circle
			(at -0.40005 0 180)
			(size 0 0)
			(layers "F.Cu" "F.Mask" "F.Paste")
			(net "HSC_VTEMP")
		)
		(pad "2" smd circle
			(at 0.40005 0 180)
			(size 0 0)
			(layers "F.Cu" "F.Mask" "F.Paste")
			(net "AGND_HSC")
		)
	)
	(footprint ""
		(layer "F.Cu")
		(at 300.54042 -424.00601 90)
		(property "Reference" "Q132"
			(at -7.76986 7.383272 90)
			(unlocked yes)
			(layer "F.SilkS")
			(effects
				(font
					(size 0.7874 0.5842)
					(thickness 0.1524)
				)
				(justify left)
			)
		)
		(property "Value" ""
			(at 0 0 90)
			(layer "F.Fab")
			(effects
				(font
					(size 1.27 1.27)
				)
			)
		)
		(duplicate_pad_numbers_are_jumpers no)
		(fp_line
			(start 1.332738 -1.100074)
			(end 1.332738 1.100074)
			(stroke
				(width 0.1524)
				(type default)
			)
			(layer "F.SilkS")
		)
		(fp_line
			(start 0.4826 -1.100074)
			(end 1.332738 -1.100074)
			(stroke
				(width 0.1524)
				(type default)
			)
			(layer "F.SilkS")
		)
		(fp_line
			(start -0.4826 -1.100074)
			(end 0 -0.541274)
			(stroke
				(width 0.1524)
				(type default)
			)
			(layer "F.SilkS")
		)
		(fp_line
			(start -1.332738 -1.100074)
			(end -0.4826 -1.100074)
			(stroke
				(width 0.1524)
				(type default)
			)
			(layer "F.SilkS")
		)
		(fp_line
			(start 0 -0.541274)
			(end 0.4826 -1.100074)
			(stroke
				(width 0.1524)
				(type default)
			)
			(layer "F.SilkS")
		)
		(fp_line
			(start 1.332738 1.100074)
			(end -1.332738 1.100074)
			(stroke
				(width 0.1524)
				(type default)
			)
			(layer "F.SilkS")
		)
		(fp_line
			(start -1.332738 1.100074)
			(end -1.332738 -1.100074)
			(stroke
				(width 0.1524)
				(type default)
			)
			(layer "F.SilkS")
		)
		(fp_poly
			(pts
				(xy -2.37998 -1.432814) (xy -1.677924 -1.081786) (xy -2.37998 -0.730758)
			)
			(stroke
				(width 0)
				(type default)
			)
			(fill yes)
			(layer "F.SilkS")
		)
		(fp_line
			(start 0.674878 -1.100074)
			(end 0.674878 1.100074)
			(stroke
				(width 0.1)
				(type default)
			)
			(layer "F.Fab")
		)
		(fp_line
			(start -0.674878 -1.100074)
			(end 0.674878 -1.100074)
			(stroke
				(width 0.1)
				(type default)
			)
			(layer "F.Fab")
		)
		(fp_line
			(start 0.674878 1.100074)
			(end -0.674878 1.100074)
			(stroke
				(width 0.1)
				(type default)
			)
			(layer "F.Fab")
		)
		(fp_line
			(start -0.674878 1.100074)
			(end -0.674878 -1.100074)
			(stroke
				(width 0.1)
				(type default)
			)
			(layer "F.Fab")
		)
		(fp_poly
			(pts
				(xy -2.2352 -0.298958) (xy -2.2352 -1.001014) (xy -1.533144 -0.649986)
			)
			(stroke
				(width 0)
				(type default)
			)
			(fill yes)
			(layer "F.Fab")
		)
		(pad "1" smd rect
			(at -0.94996 -0.649986 180)
			(size 0.4318 0.508)
			(layers "F.Cu" "F.Mask" "F.Paste")
			(net "GND")
		)
		(pad "2" smd rect
			(at -0.94996 0 180)
			(size 0.4318 0.508)
			(layers "F.Cu" "F.Mask" "F.Paste")
			(net "PRSNT_CABLE_GPU_B3_N")
		)
		(pad "3" smd rect
			(at -0.94996 0.649986 180)
			(size 0.4318 0.508)
			(layers "F.Cu" "F.Mask" "F.Paste")
			(net "PRSNT_CABLE_GPU_B3_ISO_N")
		)
		(pad "4" smd rect
			(at 0.94996 0.649986 180)
			(size 0.4318 0.508)
			(layers "F.Cu" "F.Mask" "F.Paste")
			(net "GND")
		)
		(pad "5" smd rect
			(at 0.94996 0 180)
			(size 0.4318 0.508)
			(layers "F.Cu" "F.Mask" "F.Paste")
			(net "PRSNT_CABLE_GPU_B3")
		)
		(pad "6" smd rect
			(at 0.94996 -0.649986 180)
			(size 0.4318 0.508)
			(layers "F.Cu" "F.Mask" "F.Paste")
			(net "PRSNT_CABLE_GPU_B3")
		)
	)
	(footprint ""
		(layer "F.Cu")
		(at 56.950102 -336.006186 180)
		(property "Reference" "PR560"
			(at 0 0 180)
			(layer "F.SilkS")
			(hide yes)
			(effects
				(font
					(size 1.27 1.27)
				)
			)
		)
		(property "Value" ""
			(at 0 0 180)
			(layer "F.Fab")
			(effects
				(font
					(size 1.27 1.27)
				)
			)
		)
		(duplicate_pad_numbers_are_jumpers no)
		(fp_line
			(start 0.7874 0.4064)
			(end -0.7874 0.4064)
			(stroke
				(width 0.1524)
				(type default)
			)
			(layer "F.SilkS")
		)
		(fp_line
			(start 0.7874 -0.4064)
			(end 0.7874 0.4064)
			(stroke
				(width 0.1524)
				(type default)
			)
			(layer "F.SilkS")
		)
		(fp_line
			(start -0.7874 0.4064)
			(end -0.7874 -0.4064)
			(stroke
				(width 0.1524)
				(type default)
			)
			(layer "F.SilkS")
		)
		(fp_line
			(start -0.7874 -0.4064)
			(end 0.7874 -0.4064)
			(stroke
				(width 0.1524)
				(type default)
			)
			(layer "F.SilkS")
		)
		(fp_line
			(start 0.67945 0.3048)
			(end 0.120396 0.3048)
			(stroke
				(width 0.1)
				(type default)
			)
			(layer "F.Fab")
		)
		(fp_line
			(start 0.67945 -0.3048)
			(end 0.67945 0.3048)
			(stroke
				(width 0.1)
				(type default)
			)
			(layer "F.Fab")
		)
		(fp_line
			(start 0.12065 -0.2794)
			(end 0.12065 -0.3048)
			(stroke
				(width 0.1)
				(type default)
			)
			(layer "F.Fab")
		)
		(fp_line
			(start 0.12065 -0.3048)
			(end 0.67945 -0.3048)
			(stroke
				(width 0.1)
				(type default)
			)
			(layer "F.Fab")
		)
		(fp_line
			(start 0.120396 0.3048)
			(end 0.120396 0.2794)
			(stroke
				(width 0.1)
				(type default)
			)
			(layer "F.Fab")
		)
		(fp_line
			(start 0.120396 0.2794)
			(end -0.12065 0.2794)
			(stroke
				(width 0.1)
				(type default)
			)
			(layer "F.Fab")
		)
		(fp_line
			(start -0.12065 0.3048)
			(end -0.67945 0.3048)
			(stroke
				(width 0.1)
				(type default)
			)
			(layer "F.Fab")
		)
		(fp_line
			(start -0.12065 0.2794)
			(end -0.12065 0.3048)
			(stroke
				(width 0.1)
				(type default)
			)
			(layer "F.Fab")
		)
		(fp_line
			(start -0.12065 -0.2794)
			(end 0.12065 -0.2794)
			(stroke
				(width 0.1)
				(type default)
			)
			(layer "F.Fab")
		)
		(fp_line
			(start -0.12065 -0.305054)
			(end -0.12065 -0.2794)
			(stroke
				(width 0.1)
				(type default)
			)
			(layer "F.Fab")
		)
		(fp_line
			(start -0.67945 0.3048)
			(end -0.67945 -0.305054)
			(stroke
				(width 0.1)
				(type default)
			)
			(layer "F.Fab")
		)
		(fp_line
			(start -0.67945 -0.305054)
			(end -0.12065 -0.305054)
			(stroke
				(width 0.1)
				(type default)
			)
			(layer "F.Fab")
		)
		(pad "1" smd circle
			(at -0.40005 0 180)
			(size 0 0)
			(layers "F.Cu" "F.Mask" "F.Paste")
			(net "VSENSE_PVCCFA_EHV_FIVRA_CPU1_DN")
		)
		(pad "2" smd circle
			(at 0.40005 0 180)
			(size 0 0)
			(layers "F.Cu" "F.Mask" "F.Paste")
			(net "GND")
		)
	)
	(footprint ""
		(layer "F.Cu")
		(at 209.74558 -130.830828)
		(property "Reference" "R1688"
			(at 0 0 0)
			(layer "F.SilkS")
			(hide yes)
			(effects
				(font
					(size 1.27 1.27)
				)
			)
		)
		(property "Value" ""
			(at 0 0 0)
			(layer "F.Fab")
			(effects
				(font
					(size 1.27 1.27)
				)
			)
		)
		(duplicate_pad_numbers_are_jumpers no)
		(fp_line
			(start -0.7874 -0.4064)
			(end 0.7874 -0.4064)
			(stroke
				(width 0.1524)
				(type default)
			)
			(layer "F.SilkS")
		)
		(fp_line
			(start -0.7874 0.4064)
			(end -0.7874 -0.4064)
			(stroke
				(width 0.1524)
				(type default)
			)
			(layer "F.SilkS")
		)
		(fp_line
			(start 0.7874 -0.4064)
			(end 0.7874 0.4064)
			(stroke
				(width 0.1524)
				(type default)
			)
			(layer "F.SilkS")
		)
		(fp_line
			(start 0.7874 0.4064)
			(end -0.7874 0.4064)
			(stroke
				(width 0.1524)
				(type default)
			)
			(layer "F.SilkS")
		)
		(fp_line
			(start -0.67945 -0.305054)
			(end -0.12065 -0.305054)
			(stroke
				(width 0.1)
				(type default)
			)
			(layer "F.Fab")
		)
		(fp_line
			(start -0.67945 0.3048)
			(end -0.67945 -0.305054)
			(stroke
				(width 0.1)
				(type default)
			)
			(layer "F.Fab")
		)
		(fp_line
			(start -0.12065 -0.305054)
			(end -0.12065 -0.2794)
			(stroke
				(width 0.1)
				(type default)
			)
			(layer "F.Fab")
		)
		(fp_line
			(start -0.12065 -0.2794)
			(end 0.12065 -0.2794)
			(stroke
				(width 0.1)
				(type default)
			)
			(layer "F.Fab")
		)
		(fp_line
			(start -0.12065 0.2794)
			(end -0.12065 0.3048)
			(stroke
				(width 0.1)
				(type default)
			)
			(layer "F.Fab")
		)
		(fp_line
			(start -0.12065 0.3048)
			(end -0.67945 0.3048)
			(stroke
				(width 0.1)
				(type default)
			)
			(layer "F.Fab")
		)
		(fp_line
			(start 0.120396 0.2794)
			(end -0.12065 0.2794)
			(stroke
				(width 0.1)
				(type default)
			)
			(layer "F.Fab")
		)
		(fp_line
			(start 0.120396 0.3048)
			(end 0.120396 0.2794)
			(stroke
				(width 0.1)
				(type default)
			)
			(layer "F.Fab")
		)
		(fp_line
			(start 0.12065 -0.3048)
			(end 0.67945 -0.3048)
			(stroke
				(width 0.1)
				(type default)
			)
			(layer "F.Fab")
		)
		(fp_line
			(start 0.12065 -0.2794)
			(end 0.12065 -0.3048)
			(stroke
				(width 0.1)
				(type default)
			)
			(layer "F.Fab")
		)
		(fp_line
			(start 0.67945 -0.3048)
			(end 0.67945 0.3048)
			(stroke
				(width 0.1)
				(type default)
			)
			(layer "F.Fab")
		)
		(fp_line
			(start 0.67945 0.3048)
			(end 0.120396 0.3048)
			(stroke
				(width 0.1)
				(type default)
			)
			(layer "F.Fab")
		)
		(pad "1" smd circle
			(at -0.40005 0)
			(size 0 0)
			(layers "F.Cu" "F.Mask" "F.Paste")
			(net "P12V_AUX")
		)
		(pad "2" smd circle
			(at 0.40005 0)
			(size 0 0)
			(layers "F.Cu" "F.Mask" "F.Paste")
			(net "FM_COMP_P3V3_AUX_VIN")
		)
	)
	(footprint ""
		(layer "F.Cu")
		(at 370.4082 -92.954348 90)
		(property "Reference" "R779"
			(at 0 0 90)
			(layer "F.SilkS")
			(hide yes)
			(effects
				(font
					(size 1.27 1.27)
				)
			)
		)
		(property "Value" ""
			(at 0 0 90)
			(layer "F.Fab")
			(effects
				(font
					(size 1.27 1.27)
				)
			)
		)
		(duplicate_pad_numbers_are_jumpers no)
		(fp_line
			(start 0.7874 -0.4064)
			(end 0.7874 0.4064)
			(stroke
				(width 0.1524)
				(type default)
			)
			(layer "F.SilkS")
		)
		(fp_line
			(start -0.7874 -0.4064)
			(end 0.7874 -0.4064)
			(stroke
				(width 0.1524)
				(type default)
			)
			(layer "F.SilkS")
		)
		(fp_line
			(start 0.7874 0.4064)
			(end -0.7874 0.4064)
			(stroke
				(width 0.1524)
				(type default)
			)
			(layer "F.SilkS")
		)
		(fp_line
			(start -0.7874 0.4064)
			(end -0.7874 -0.4064)
			(stroke
				(width 0.1524)
				(type default)
			)
			(layer "F.SilkS")
		)
		(fp_line
			(start -0.12065 -0.305054)
			(end -0.12065 -0.2794)
			(stroke
				(width 0.1)
				(type default)
			)
			(layer "F.Fab")
		)
		(fp_line
			(start -0.67945 -0.305054)
			(end -0.12065 -0.305054)
			(stroke
				(width 0.1)
				(type default)
			)
			(layer "F.Fab")
		)
		(fp_line
			(start 0.67945 -0.3048)
			(end 0.67945 0.3048)
			(stroke
				(width 0.1)
				(type default)
			)
			(layer "F.Fab")
		)
		(fp_line
			(start 0.12065 -0.3048)
			(end 0.67945 -0.3048)
			(stroke
				(width 0.1)
				(type default)
			)
			(layer "F.Fab")
		)
		(fp_line
			(start 0.12065 -0.2794)
			(end 0.12065 -0.3048)
			(stroke
				(width 0.1)
				(type default)
			)
			(layer "F.Fab")
		)
		(fp_line
			(start -0.12065 -0.2794)
			(end 0.12065 -0.2794)
			(stroke
				(width 0.1)
				(type default)
			)
			(layer "F.Fab")
		)
		(fp_line
			(start 0.120396 0.2794)
			(end -0.12065 0.2794)
			(stroke
				(width 0.1)
				(type default)
			)
			(layer "F.Fab")
		)
		(fp_line
			(start -0.12065 0.2794)
			(end -0.12065 0.3048)
			(stroke
				(width 0.1)
				(type default)
			)
			(layer "F.Fab")
		)
		(fp_line
			(start 0.67945 0.3048)
			(end 0.120396 0.3048)
			(stroke
				(width 0.1)
				(type default)
			)
			(layer "F.Fab")
		)
		(fp_line
			(start 0.120396 0.3048)
			(end 0.120396 0.2794)
			(stroke
				(width 0.1)
				(type default)
			)
			(layer "F.Fab")
		)
		(fp_line
			(start -0.12065 0.3048)
			(end -0.67945 0.3048)
			(stroke
				(width 0.1)
				(type default)
			)
			(layer "F.Fab")
		)
		(fp_line
			(start -0.67945 0.3048)
			(end -0.67945 -0.305054)
			(stroke
				(width 0.1)
				(type default)
			)
			(layer "F.Fab")
		)
		(pad "1" smd circle
			(at -0.40005 0 90)
			(size 0 0)
			(layers "F.Cu" "F.Mask" "F.Paste")
			(net "PVNN_TERM_CPU0")
		)
		(pad "2" smd circle
			(at 0.40005 0 90)
			(size 0 0)
			(layers "F.Cu" "F.Mask" "F.Paste")
			(net "FM_CPU_FBRK_DEBUG_N")
		)
	)
	(footprint ""
		(layer "F.Cu")
		(at 196.67982 -80.617568)
		(property "Reference" "D6"
			(at -1.397 -1.24333 0)
			(unlocked yes)
			(layer "F.SilkS")
			(effects
				(font
					(size 0.7874 0.5842)
					(thickness 0.1524)
				)
				(justify left)
			)
		)
		(property "Value" ""
			(at 0 0 0)
			(layer "F.Fab")
			(effects
				(font
					(size 1.27 1.27)
				)
			)
		)
		(duplicate_pad_numbers_are_jumpers no)
		(fp_line
			(start -1.3208 -0.5588)
			(end 1.3208 -0.5588)
			(stroke
				(width 0.1524)
				(type default)
			)
			(layer "F.SilkS")
		)
		(fp_line
			(start -1.3208 0.5588)
			(end -1.3208 -0.5588)
			(stroke
				(width 0.1524)
				(type default)
			)
			(layer "F.SilkS")
		)
		(fp_line
			(start 1.3208 -0.5588)
			(end 1.3208 0.5588)
			(stroke
				(width 0.1524)
				(type default)
			)
			(layer "F.SilkS")
		)
		(fp_line
			(start 1.3208 0.5588)
			(end -1.3208 0.5588)
			(stroke
				(width 0.1524)
				(type default)
			)
			(layer "F.SilkS")
		)
		(fp_line
			(start 1.4732 -0.5588)
			(end 1.4732 0.5588)
			(stroke
				(width 0.1524)
				(type default)
			)
			(layer "F.SilkS")
		)
		(fp_line
			(start 1.6256 0.5588)
			(end 1.6256 -0.5588)
			(stroke
				(width 0.1524)
				(type default)
			)
			(layer "F.SilkS")
		)
		(fp_line
			(start 1.778 -0.5588)
			(end 1.3208 -0.5588)
			(stroke
				(width 0.1524)
				(type default)
			)
			(layer "F.SilkS")
		)
		(fp_line
			(start 1.778 -0.5588)
			(end 1.778 0.5588)
			(stroke
				(width 0.1524)
				(type default)
			)
			(layer "F.SilkS")
		)
		(fp_line
			(start 1.778 0.5588)
			(end 1.3208 0.5588)
			(stroke
				(width 0.1524)
				(type default)
			)
			(layer "F.SilkS")
		)
		(fp_line
			(start -0.899922 -0.40005)
			(end 0.899922 -0.40005)
			(stroke
				(width 0.1)
				(type default)
			)
			(layer "F.Fab")
		)
		(fp_line
			(start -0.899922 0.40005)
			(end -0.899922 -0.40005)
			(stroke
				(width 0.1)
				(type default)
			)
			(layer "F.Fab")
		)
		(fp_line
			(start 0.899922 -0.40005)
			(end 0.899922 0.40005)
			(stroke
				(width 0.1)
				(type default)
			)
			(layer "F.Fab")
		)
		(fp_line
			(start 0.899922 0.40005)
			(end -0.899922 0.40005)
			(stroke
				(width 0.1)
				(type default)
			)
			(layer "F.Fab")
		)
		(fp_text user "+"
			(at -2.8956 -1.23825 0)
			(unlocked yes)
			(layer "F.SilkS")
			(effects
				(font
					(size 1.905 1.4224)
					(thickness 0.1524)
				)
				(justify left)
			)
		)
		(fp_text user "-"
			(at 1.651 -0.22225 0)
			(unlocked yes)
			(layer "F.SilkS")
			(effects
				(font
					(size 1.905 1.4224)
					(thickness 0.1524)
				)
				(justify left)
			)
		)
		(fp_text user "+"
			(at -2.6162 -0.22225 0)
			(unlocked yes)
			(layer "F.Fab")
			(effects
				(font
					(size 1.905 1.4224)
					(thickness 0.1524)
				)
				(justify left)
			)
		)
		(fp_text user "-"
			(at 1.651 -0.22225 0)
			(unlocked yes)
			(layer "F.Fab")
			(effects
				(font
					(size 1.905 1.4224)
					(thickness 0.1524)
				)
				(justify left)
			)
		)
		(pad "A" smd rect
			(at -0.750062 0)
			(size 0.8128 0.8128)
			(layers "F.Cu" "F.Mask" "F.Paste")
			(net "LED_CPU_RMCA_CATERR")
		)
		(pad "C" smd rect
			(at 0.750062 0)
			(size 0.8128 0.8128)
			(layers "F.Cu" "F.Mask" "F.Paste")
			(net "GND")
		)
	)
	(footprint ""
		(layer "F.Cu")
		(at 393.75461 -402.371052 -90)
		(property "Reference" "C948"
			(at 0 0 270)
			(layer "F.SilkS")
			(hide yes)
			(effects
				(font
					(size 1.27 1.27)
				)
			)
		)
		(property "Value" ""
			(at 0 0 270)
			(layer "F.Fab")
			(effects
				(font
					(size 1.27 1.27)
				)
			)
		)
		(duplicate_pad_numbers_are_jumpers no)
		(fp_line
			(start -0.299974 0.150114)
			(end -0.299974 -0.150114)
			(stroke
				(width 0.1)
				(type default)
			)
			(layer "F.Fab")
		)
		(fp_line
			(start 0.299974 0.150114)
			(end -0.299974 0.150114)
			(stroke
				(width 0.1)
				(type default)
			)
			(layer "F.Fab")
		)
		(fp_line
			(start -0.299974 -0.150114)
			(end 0.299974 -0.150114)
			(stroke
				(width 0.1)
				(type default)
			)
			(layer "F.Fab")
		)
		(fp_line
			(start 0.299974 -0.150114)
			(end 0.299974 0.150114)
			(stroke
				(width 0.1)
				(type default)
			)
			(layer "F.Fab")
		)
		(pad "1" smd rect
			(at -0.2667 0 270)
			(size 0.3048 0.381)
			(layers "F.Cu" "F.Mask" "F.Paste")
			(net "P5E_CPU0_PE2_TX_C_DN<8>")
		)
		(pad "2" smd rect
			(at 0.2667 0 270)
			(size 0.3048 0.381)
			(layers "F.Cu" "F.Mask" "F.Paste")
			(net "P5E_CPU0_PE2_TX_DN<8>")
		)
	)
	(footprint ""
		(layer "F.Cu")
		(at 113.44656 -28.567634 90)
		(property "Reference" "U218"
			(at -0.191516 -5.00888 0)
			(unlocked yes)
			(layer "F.SilkS")
			(effects
				(font
					(size 0.7874 0.5842)
					(thickness 0.1524)
				)
				(justify left)
			)
		)
		(property "Value" ""
			(at 0 0 90)
			(layer "F.Fab")
			(effects
				(font
					(size 1.27 1.27)
				)
			)
		)
		(duplicate_pad_numbers_are_jumpers no)
		(fp_line
			(start 1.733296 -1.549908)
			(end 0.660908 -1.549908)
			(stroke
				(width 0.1524)
				(type default)
			)
			(layer "F.SilkS")
		)
		(fp_line
			(start 0.660908 -1.549908)
			(end 0 -0.889)
			(stroke
				(width 0.1524)
				(type default)
			)
			(layer "F.SilkS")
		)
		(fp_line
			(start -0.660908 -1.549908)
			(end -1.733296 -1.549908)
			(stroke
				(width 0.1524)
				(type default)
			)
			(layer "F.SilkS")
		)
		(fp_line
			(start -1.733296 -1.549908)
			(end -1.733296 1.549908)
			(stroke
				(width 0.1524)
				(type default)
			)
			(layer "F.SilkS")
		)
		(fp_line
			(start 0 -0.889)
			(end -0.660908 -1.549908)
			(stroke
				(width 0.1524)
				(type default)
			)
			(layer "F.SilkS")
		)
		(fp_line
			(start 1.733296 1.549908)
			(end 1.733296 -1.549908)
			(stroke
				(width 0.1524)
				(type default)
			)
			(layer "F.SilkS")
		)
		(fp_line
			(start -1.733296 1.549908)
			(end 1.733296 1.549908)
			(stroke
				(width 0.1524)
				(type default)
			)
			(layer "F.SilkS")
		)
		(fp_poly
			(pts
				(xy -0.982726 -2.387854) (xy -1.236726 -1.879854) (xy -1.490726 -2.387854)
			)
			(stroke
				(width 0)
				(type default)
			)
			(fill yes)
			(layer "F.SilkS")
		)
		(fp_line
			(start 0.849884 -1.549908)
			(end -0.849884 -1.549908)
			(stroke
				(width 0.1)
				(type default)
			)
			(layer "F.Fab")
		)
		(fp_line
			(start -0.849884 -1.549908)
			(end -0.849884 1.549908)
			(stroke
				(width 0.1)
				(type default)
			)
			(layer "F.Fab")
		)
		(fp_line
			(start 0.849884 1.549908)
			(end 0.849884 -1.549908)
			(stroke
				(width 0.1)
				(type default)
			)
			(layer "F.Fab")
		)
		(fp_line
			(start -0.849884 1.549908)
			(end 0.849884 1.549908)
			(stroke
				(width 0.1)
				(type default)
			)
			(layer "F.Fab")
		)
		(fp_poly
			(pts
				(xy -2.4384 -1.20396) (xy -2.4384 -0.69596) (xy -1.9304 -0.94996)
			)
			(stroke
				(width 0)
				(type default)
			)
			(fill yes)
			(layer "F.Fab")
		)
		(pad "1" smd rect
			(at -1.199896 -0.94996)
			(size 0.5588 0.8128)
			(layers "F.Cu" "F.Mask" "F.Paste")
			(net "NC_U218_NC1")
		)
		(pad "2" smd rect
			(at -1.199896 0)
			(size 0.5588 0.8128)
			(layers "F.Cu" "F.Mask" "F.Paste")
			(net "FM_SYS_THROTTLE_R_N")
		)
		(pad "3" smd rect
			(at -1.199896 0.94996)
			(size 0.5588 0.8128)
			(layers "F.Cu" "F.Mask" "F.Paste")
			(net "GND")
		)
		(pad "4" smd rect
			(at 1.199896 0.94996)
			(size 0.5588 0.8128)
			(layers "F.Cu" "F.Mask" "F.Paste")
			(net "OCP_V3_2_PWRBRK_BUFF_N")
		)
		(pad "5" smd rect
			(at 1.199896 -0.94996)
			(size 0.5588 0.8128)
			(layers "F.Cu" "F.Mask" "F.Paste")
			(net "P3V3_AUX")
		)
	)
	(footprint ""
		(layer "F.Cu")
		(at 314.490608 -408.517344 -90)
		(property "Reference" "C908"
			(at 0 0 270)
			(layer "F.SilkS")
			(hide yes)
			(effects
				(font
					(size 1.27 1.27)
				)
			)
		)
		(property "Value" ""
			(at 0 0 270)
			(layer "F.Fab")
			(effects
				(font
					(size 1.27 1.27)
				)
			)
		)
		(duplicate_pad_numbers_are_jumpers no)
		(fp_line
			(start -0.299974 0.150114)
			(end -0.299974 -0.150114)
			(stroke
				(width 0.1)
				(type default)
			)
			(layer "F.Fab")
		)
		(fp_line
			(start 0.299974 0.150114)
			(end -0.299974 0.150114)
			(stroke
				(width 0.1)
				(type default)
			)
			(layer "F.Fab")
		)
		(fp_line
			(start -0.299974 -0.150114)
			(end 0.299974 -0.150114)
			(stroke
				(width 0.1)
				(type default)
			)
			(layer "F.Fab")
		)
		(fp_line
			(start 0.299974 -0.150114)
			(end 0.299974 0.150114)
			(stroke
				(width 0.1)
				(type default)
			)
			(layer "F.Fab")
		)
		(pad "1" smd rect
			(at -0.2667 0 270)
			(size 0.3048 0.381)
			(layers "F.Cu" "F.Mask" "F.Paste")
			(net "P5E_CPU0_PE0_TX_C_DN<12>")
		)
		(pad "2" smd rect
			(at 0.2667 0 270)
			(size 0.3048 0.381)
			(layers "F.Cu" "F.Mask" "F.Paste")
			(net "P5E_CPU0_PE0_TX_DN<12>")
		)
	)
	(footprint ""
		(layer "F.Cu")
		(at 161.21888 -133.695948 180)
		(property "Reference" "R2486"
			(at 0 0 180)
			(layer "F.SilkS")
			(hide yes)
			(effects
				(font
					(size 1.27 1.27)
				)
			)
		)
		(property "Value" ""
			(at 0 0 180)
			(layer "F.Fab")
			(effects
				(font
					(size 1.27 1.27)
				)
			)
		)
		(duplicate_pad_numbers_are_jumpers no)
		(fp_line
			(start 0.7874 0.4064)
			(end -0.7874 0.4064)
			(stroke
				(width 0.1524)
				(type default)
			)
			(layer "F.SilkS")
		)
		(fp_line
			(start 0.7874 -0.4064)
			(end 0.7874 0.4064)
			(stroke
				(width 0.1524)
				(type default)
			)
			(layer "F.SilkS")
		)
		(fp_line
			(start -0.7874 0.4064)
			(end -0.7874 -0.4064)
			(stroke
				(width 0.1524)
				(type default)
			)
			(layer "F.SilkS")
		)
		(fp_line
			(start -0.7874 -0.4064)
			(end 0.7874 -0.4064)
			(stroke
				(width 0.1524)
				(type default)
			)
			(layer "F.SilkS")
		)
		(fp_line
			(start 0.67945 0.3048)
			(end 0.120396 0.3048)
			(stroke
				(width 0.1)
				(type default)
			)
			(layer "F.Fab")
		)
		(fp_line
			(start 0.67945 -0.3048)
			(end 0.67945 0.3048)
			(stroke
				(width 0.1)
				(type default)
			)
			(layer "F.Fab")
		)
		(fp_line
			(start 0.12065 -0.2794)
			(end 0.12065 -0.3048)
			(stroke
				(width 0.1)
				(type default)
			)
			(layer "F.Fab")
		)
		(fp_line
			(start 0.12065 -0.3048)
			(end 0.67945 -0.3048)
			(stroke
				(width 0.1)
				(type default)
			)
			(layer "F.Fab")
		)
		(fp_line
			(start 0.120396 0.3048)
			(end 0.120396 0.2794)
			(stroke
				(width 0.1)
				(type default)
			)
			(layer "F.Fab")
		)
		(fp_line
			(start 0.120396 0.2794)
			(end -0.12065 0.2794)
			(stroke
				(width 0.1)
				(type default)
			)
			(layer "F.Fab")
		)
		(fp_line
			(start -0.12065 0.3048)
			(end -0.67945 0.3048)
			(stroke
				(width 0.1)
				(type default)
			)
			(layer "F.Fab")
		)
		(fp_line
			(start -0.12065 0.2794)
			(end -0.12065 0.3048)
			(stroke
				(width 0.1)
				(type default)
			)
			(layer "F.Fab")
		)
		(fp_line
			(start -0.12065 -0.2794)
			(end 0.12065 -0.2794)
			(stroke
				(width 0.1)
				(type default)
			)
			(layer "F.Fab")
		)
		(fp_line
			(start -0.12065 -0.305054)
			(end -0.12065 -0.2794)
			(stroke
				(width 0.1)
				(type default)
			)
			(layer "F.Fab")
		)
		(fp_line
			(start -0.67945 0.3048)
			(end -0.67945 -0.305054)
			(stroke
				(width 0.1)
				(type default)
			)
			(layer "F.Fab")
		)
		(fp_line
			(start -0.67945 -0.305054)
			(end -0.12065 -0.305054)
			(stroke
				(width 0.1)
				(type default)
			)
			(layer "F.Fab")
		)
		(pad "1" smd circle
			(at -0.40005 0 180)
			(size 0 0)
			(layers "F.Cu" "F.Mask" "F.Paste")
			(net "P3V3_AUX")
		)
		(pad "2" smd circle
			(at 0.40005 0 180)
			(size 0 0)
			(layers "F.Cu" "F.Mask" "F.Paste")
			(net "PWRGD_P3V3_AUX_R2")
		)
	)
	(footprint ""
		(layer "F.Cu")
		(at 170.23588 -435.955948)
		(property "Reference" "R3392"
			(at 0 0 0)
			(layer "F.SilkS")
			(hide yes)
			(effects
				(font
					(size 1.27 1.27)
				)
			)
		)
		(property "Value" ""
			(at 0 0 0)
			(layer "F.Fab")
			(effects
				(font
					(size 1.27 1.27)
				)
			)
		)
		(duplicate_pad_numbers_are_jumpers no)
		(fp_line
			(start -0.7874 -0.4064)
			(end 0.7874 -0.4064)
			(stroke
				(width 0.1524)
				(type default)
			)
			(layer "F.SilkS")
		)
		(fp_line
			(start -0.7874 0.4064)
			(end -0.7874 -0.4064)
			(stroke
				(width 0.1524)
				(type default)
			)
			(layer "F.SilkS")
		)
		(fp_line
			(start 0.7874 -0.4064)
			(end 0.7874 0.4064)
			(stroke
				(width 0.1524)
				(type default)
			)
			(layer "F.SilkS")
		)
		(fp_line
			(start 0.7874 0.4064)
			(end -0.7874 0.4064)
			(stroke
				(width 0.1524)
				(type default)
			)
			(layer "F.SilkS")
		)
		(fp_line
			(start -0.67945 -0.305054)
			(end -0.12065 -0.305054)
			(stroke
				(width 0.1)
				(type default)
			)
			(layer "F.Fab")
		)
		(fp_line
			(start -0.67945 0.3048)
			(end -0.67945 -0.305054)
			(stroke
				(width 0.1)
				(type default)
			)
			(layer "F.Fab")
		)
		(fp_line
			(start -0.12065 -0.305054)
			(end -0.12065 -0.2794)
			(stroke
				(width 0.1)
				(type default)
			)
			(layer "F.Fab")
		)
		(fp_line
			(start -0.12065 -0.2794)
			(end 0.12065 -0.2794)
			(stroke
				(width 0.1)
				(type default)
			)
			(layer "F.Fab")
		)
		(fp_line
			(start -0.12065 0.2794)
			(end -0.12065 0.3048)
			(stroke
				(width 0.1)
				(type default)
			)
			(layer "F.Fab")
		)
		(fp_line
			(start -0.12065 0.3048)
			(end -0.67945 0.3048)
			(stroke
				(width 0.1)
				(type default)
			)
			(layer "F.Fab")
		)
		(fp_line
			(start 0.120396 0.2794)
			(end -0.12065 0.2794)
			(stroke
				(width 0.1)
				(type default)
			)
			(layer "F.Fab")
		)
		(fp_line
			(start 0.120396 0.3048)
			(end 0.120396 0.2794)
			(stroke
				(width 0.1)
				(type default)
			)
			(layer "F.Fab")
		)
		(fp_line
			(start 0.12065 -0.3048)
			(end 0.67945 -0.3048)
			(stroke
				(width 0.1)
				(type default)
			)
			(layer "F.Fab")
		)
		(fp_line
			(start 0.12065 -0.2794)
			(end 0.12065 -0.3048)
			(stroke
				(width 0.1)
				(type default)
			)
			(layer "F.Fab")
		)
		(fp_line
			(start 0.67945 -0.3048)
			(end 0.67945 0.3048)
			(stroke
				(width 0.1)
				(type default)
			)
			(layer "F.Fab")
		)
		(fp_line
			(start 0.67945 0.3048)
			(end 0.120396 0.3048)
			(stroke
				(width 0.1)
				(type default)
			)
			(layer "F.Fab")
		)
		(pad "1" smd circle
			(at -0.40005 0)
			(size 0 0)
			(layers "F.Cu" "F.Mask" "F.Paste")
			(net "GPU_BASE_STBY_EN_BUF_R")
		)
		(pad "2" smd circle
			(at 0.40005 0)
			(size 0 0)
			(layers "F.Cu" "F.Mask" "F.Paste")
			(net "GPU_BASE_STBY_EN_BUF")
		)
	)
	(footprint ""
		(layer "F.Cu")
		(at 448.672458 -92.493592 180)
		(property "Reference" "R3616"
			(at 0 0 180)
			(layer "F.SilkS")
			(hide yes)
			(effects
				(font
					(size 1.27 1.27)
				)
			)
		)
		(property "Value" ""
			(at 0 0 180)
			(layer "F.Fab")
			(effects
				(font
					(size 1.27 1.27)
				)
			)
		)
		(duplicate_pad_numbers_are_jumpers no)
		(fp_line
			(start 0.7874 0.4064)
			(end -0.7874 0.4064)
			(stroke
				(width 0.1524)
				(type default)
			)
			(layer "F.SilkS")
		)
		(fp_line
			(start 0.7874 -0.4064)
			(end 0.7874 0.4064)
			(stroke
				(width 0.1524)
				(type default)
			)
			(layer "F.SilkS")
		)
		(fp_line
			(start -0.7874 0.4064)
			(end -0.7874 -0.4064)
			(stroke
				(width 0.1524)
				(type default)
			)
			(layer "F.SilkS")
		)
		(fp_line
			(start -0.7874 -0.4064)
			(end 0.7874 -0.4064)
			(stroke
				(width 0.1524)
				(type default)
			)
			(layer "F.SilkS")
		)
		(fp_line
			(start 0.67945 0.3048)
			(end 0.120396 0.3048)
			(stroke
				(width 0.1)
				(type default)
			)
			(layer "F.Fab")
		)
		(fp_line
			(start 0.67945 -0.3048)
			(end 0.67945 0.3048)
			(stroke
				(width 0.1)
				(type default)
			)
			(layer "F.Fab")
		)
		(fp_line
			(start 0.12065 -0.2794)
			(end 0.12065 -0.3048)
			(stroke
				(width 0.1)
				(type default)
			)
			(layer "F.Fab")
		)
		(fp_line
			(start 0.12065 -0.3048)
			(end 0.67945 -0.3048)
			(stroke
				(width 0.1)
				(type default)
			)
			(layer "F.Fab")
		)
		(fp_line
			(start 0.120396 0.3048)
			(end 0.120396 0.2794)
			(stroke
				(width 0.1)
				(type default)
			)
			(layer "F.Fab")
		)
		(fp_line
			(start 0.120396 0.2794)
			(end -0.12065 0.2794)
			(stroke
				(width 0.1)
				(type default)
			)
			(layer "F.Fab")
		)
		(fp_line
			(start -0.12065 0.3048)
			(end -0.67945 0.3048)
			(stroke
				(width 0.1)
				(type default)
			)
			(layer "F.Fab")
		)
		(fp_line
			(start -0.12065 0.2794)
			(end -0.12065 0.3048)
			(stroke
				(width 0.1)
				(type default)
			)
			(layer "F.Fab")
		)
		(fp_line
			(start -0.12065 -0.2794)
			(end 0.12065 -0.2794)
			(stroke
				(width 0.1)
				(type default)
			)
			(layer "F.Fab")
		)
		(fp_line
			(start -0.12065 -0.305054)
			(end -0.12065 -0.2794)
			(stroke
				(width 0.1)
				(type default)
			)
			(layer "F.Fab")
		)
		(fp_line
			(start -0.67945 0.3048)
			(end -0.67945 -0.305054)
			(stroke
				(width 0.1)
				(type default)
			)
			(layer "F.Fab")
		)
		(fp_line
			(start -0.67945 -0.305054)
			(end -0.12065 -0.305054)
			(stroke
				(width 0.1)
				(type default)
			)
			(layer "F.Fab")
		)
		(pad "1" smd circle
			(at -0.40005 0 180)
			(size 0 0)
			(layers "F.Cu" "F.Mask" "F.Paste")
			(net "GND")
		)
		(pad "2" smd circle
			(at 0.40005 0 180)
			(size 0 0)
			(layers "F.Cu" "F.Mask" "F.Paste")
			(net "INA230_1_A1")
		)
	)
	(footprint ""
		(layer "F.Cu")
		(at 104.34193 -241.97691 -90)
		(property "Reference" "C247"
			(at 0 0 270)
			(layer "F.SilkS")
			(hide yes)
			(effects
				(font
					(size 1.27 1.27)
				)
			)
		)
		(property "Value" ""
			(at 0 0 270)
			(layer "F.Fab")
			(effects
				(font
					(size 1.27 1.27)
				)
			)
		)
		(duplicate_pad_numbers_are_jumpers no)
		(fp_line
			(start -0.7874 0.4064)
			(end -0.7874 -0.4064)
			(stroke
				(width 0.1524)
				(type default)
			)
			(layer "F.SilkS")
		)
		(fp_line
			(start 0.7874 0.4064)
			(end -0.7874 0.4064)
			(stroke
				(width 0.1524)
				(type default)
			)
			(layer "F.SilkS")
		)
		(fp_line
			(start -0.7874 -0.4064)
			(end 0.7874 -0.4064)
			(stroke
				(width 0.1524)
				(type default)
			)
			(layer "F.SilkS")
		)
		(fp_line
			(start 0.7874 -0.4064)
			(end 0.7874 0.4064)
			(stroke
				(width 0.1524)
				(type default)
			)
			(layer "F.SilkS")
		)
		(fp_line
			(start -0.67945 0.3048)
			(end -0.67945 -0.305054)
			(stroke
				(width 0.1)
				(type default)
			)
			(layer "F.Fab")
		)
		(fp_line
			(start -0.12065 0.3048)
			(end -0.67945 0.3048)
			(stroke
				(width 0.1)
				(type default)
			)
			(layer "F.Fab")
		)
		(fp_line
			(start 0.120396 0.3048)
			(end 0.120396 0.2794)
			(stroke
				(width 0.1)
				(type default)
			)
			(layer "F.Fab")
		)
		(fp_line
			(start 0.67945 0.3048)
			(end 0.120396 0.3048)
			(stroke
				(width 0.1)
				(type default)
			)
			(layer "F.Fab")
		)
		(fp_line
			(start -0.12065 0.2794)
			(end -0.12065 0.3048)
			(stroke
				(width 0.1)
				(type default)
			)
			(layer "F.Fab")
		)
		(fp_line
			(start 0.120396 0.2794)
			(end -0.12065 0.2794)
			(stroke
				(width 0.1)
				(type default)
			)
			(layer "F.Fab")
		)
		(fp_line
			(start -0.12065 -0.2794)
			(end 0.12065 -0.2794)
			(stroke
				(width 0.1)
				(type default)
			)
			(layer "F.Fab")
		)
		(fp_line
			(start 0.12065 -0.2794)
			(end 0.12065 -0.3048)
			(stroke
				(width 0.1)
				(type default)
			)
			(layer "F.Fab")
		)
		(fp_line
			(start 0.12065 -0.3048)
			(end 0.67945 -0.3048)
			(stroke
				(width 0.1)
				(type default)
			)
			(layer "F.Fab")
		)
		(fp_line
			(start 0.67945 -0.3048)
			(end 0.67945 0.3048)
			(stroke
				(width 0.1)
				(type default)
			)
			(layer "F.Fab")
		)
		(fp_line
			(start -0.67945 -0.305054)
			(end -0.12065 -0.305054)
			(stroke
				(width 0.1)
				(type default)
			)
			(layer "F.Fab")
		)
		(fp_line
			(start -0.12065 -0.305054)
			(end -0.12065 -0.2794)
			(stroke
				(width 0.1)
				(type default)
			)
			(layer "F.Fab")
		)
		(pad "1" smd circle
			(at -0.40005 0 270)
			(size 0 0)
			(layers "F.Cu" "F.Mask" "F.Paste")
			(net "PVCCIN_CPU1")
		)
		(pad "2" smd circle
			(at 0.40005 0 270)
			(size 0 0)
			(layers "F.Cu" "F.Mask" "F.Paste")
			(net "GND")
		)
	)
	(footprint ""
		(layer "F.Cu")
		(at 208.49336 -120.1166 180)
		(property "Reference" "R4718"
			(at 0 0 180)
			(layer "F.SilkS")
			(hide yes)
			(effects
				(font
					(size 1.27 1.27)
				)
			)
		)
		(property "Value" ""
			(at 0 0 180)
			(layer "F.Fab")
			(effects
				(font
					(size 1.27 1.27)
				)
			)
		)
		(duplicate_pad_numbers_are_jumpers no)
		(fp_line
			(start 0.7874 0.4064)
			(end -0.7874 0.4064)
			(stroke
				(width 0.1524)
				(type default)
			)
			(layer "F.SilkS")
		)
		(fp_line
			(start 0.7874 -0.4064)
			(end 0.7874 0.4064)
			(stroke
				(width 0.1524)
				(type default)
			)
			(layer "F.SilkS")
		)
		(fp_line
			(start -0.7874 0.4064)
			(end -0.7874 -0.4064)
			(stroke
				(width 0.1524)
				(type default)
			)
			(layer "F.SilkS")
		)
		(fp_line
			(start -0.7874 -0.4064)
			(end 0.7874 -0.4064)
			(stroke
				(width 0.1524)
				(type default)
			)
			(layer "F.SilkS")
		)
		(fp_line
			(start 0.67945 0.3048)
			(end 0.120396 0.3048)
			(stroke
				(width 0.1)
				(type default)
			)
			(layer "F.Fab")
		)
		(fp_line
			(start 0.67945 -0.3048)
			(end 0.67945 0.3048)
			(stroke
				(width 0.1)
				(type default)
			)
			(layer "F.Fab")
		)
		(fp_line
			(start 0.12065 -0.2794)
			(end 0.12065 -0.3048)
			(stroke
				(width 0.1)
				(type default)
			)
			(layer "F.Fab")
		)
		(fp_line
			(start 0.12065 -0.3048)
			(end 0.67945 -0.3048)
			(stroke
				(width 0.1)
				(type default)
			)
			(layer "F.Fab")
		)
		(fp_line
			(start 0.120396 0.3048)
			(end 0.120396 0.2794)
			(stroke
				(width 0.1)
				(type default)
			)
			(layer "F.Fab")
		)
		(fp_line
			(start 0.120396 0.2794)
			(end -0.12065 0.2794)
			(stroke
				(width 0.1)
				(type default)
			)
			(layer "F.Fab")
		)
		(fp_line
			(start -0.12065 0.3048)
			(end -0.67945 0.3048)
			(stroke
				(width 0.1)
				(type default)
			)
			(layer "F.Fab")
		)
		(fp_line
			(start -0.12065 0.2794)
			(end -0.12065 0.3048)
			(stroke
				(width 0.1)
				(type default)
			)
			(layer "F.Fab")
		)
		(fp_line
			(start -0.12065 -0.2794)
			(end 0.12065 -0.2794)
			(stroke
				(width 0.1)
				(type default)
			)
			(layer "F.Fab")
		)
		(fp_line
			(start -0.12065 -0.305054)
			(end -0.12065 -0.2794)
			(stroke
				(width 0.1)
				(type default)
			)
			(layer "F.Fab")
		)
		(fp_line
			(start -0.67945 0.3048)
			(end -0.67945 -0.305054)
			(stroke
				(width 0.1)
				(type default)
			)
			(layer "F.Fab")
		)
		(fp_line
			(start -0.67945 -0.305054)
			(end -0.12065 -0.305054)
			(stroke
				(width 0.1)
				(type default)
			)
			(layer "F.Fab")
		)
		(pad "1" smd circle
			(at -0.40005 0 180)
			(size 0 0)
			(layers "F.Cu" "F.Mask" "F.Paste")
			(net "FM_AC_PWR_BTN_PLD_ISO_R_N")
		)
		(pad "2" smd circle
			(at 0.40005 0 180)
			(size 0 0)
			(layers "F.Cu" "F.Mask" "F.Paste")
			(net "FM_AC_PWR_BTN_PLD_ISO_N")
		)
	)
	(footprint ""
		(layer "F.Cu")
		(at 257.85953 -56.495442)
		(property "Reference" "R3955"
			(at 0 0 0)
			(layer "F.SilkS")
			(hide yes)
			(effects
				(font
					(size 1.27 1.27)
				)
			)
		)
		(property "Value" ""
			(at 0 0 0)
			(layer "F.Fab")
			(effects
				(font
					(size 1.27 1.27)
				)
			)
		)
		(duplicate_pad_numbers_are_jumpers no)
		(fp_line
			(start -0.7874 -0.4064)
			(end 0.7874 -0.4064)
			(stroke
				(width 0.1524)
				(type default)
			)
			(layer "F.SilkS")
		)
		(fp_line
			(start -0.7874 0.4064)
			(end -0.7874 -0.4064)
			(stroke
				(width 0.1524)
				(type default)
			)
			(layer "F.SilkS")
		)
		(fp_line
			(start 0.7874 -0.4064)
			(end 0.7874 0.4064)
			(stroke
				(width 0.1524)
				(type default)
			)
			(layer "F.SilkS")
		)
		(fp_line
			(start 0.7874 0.4064)
			(end -0.7874 0.4064)
			(stroke
				(width 0.1524)
				(type default)
			)
			(layer "F.SilkS")
		)
		(fp_line
			(start -0.67945 -0.305054)
			(end -0.12065 -0.305054)
			(stroke
				(width 0.1)
				(type default)
			)
			(layer "F.Fab")
		)
		(fp_line
			(start -0.67945 0.3048)
			(end -0.67945 -0.305054)
			(stroke
				(width 0.1)
				(type default)
			)
			(layer "F.Fab")
		)
		(fp_line
			(start -0.12065 -0.305054)
			(end -0.12065 -0.2794)
			(stroke
				(width 0.1)
				(type default)
			)
			(layer "F.Fab")
		)
		(fp_line
			(start -0.12065 -0.2794)
			(end 0.12065 -0.2794)
			(stroke
				(width 0.1)
				(type default)
			)
			(layer "F.Fab")
		)
		(fp_line
			(start -0.12065 0.2794)
			(end -0.12065 0.3048)
			(stroke
				(width 0.1)
				(type default)
			)
			(layer "F.Fab")
		)
		(fp_line
			(start -0.12065 0.3048)
			(end -0.67945 0.3048)
			(stroke
				(width 0.1)
				(type default)
			)
			(layer "F.Fab")
		)
		(fp_line
			(start 0.120396 0.2794)
			(end -0.12065 0.2794)
			(stroke
				(width 0.1)
				(type default)
			)
			(layer "F.Fab")
		)
		(fp_line
			(start 0.120396 0.3048)
			(end 0.120396 0.2794)
			(stroke
				(width 0.1)
				(type default)
			)
			(layer "F.Fab")
		)
		(fp_line
			(start 0.12065 -0.3048)
			(end 0.67945 -0.3048)
			(stroke
				(width 0.1)
				(type default)
			)
			(layer "F.Fab")
		)
		(fp_line
			(start 0.12065 -0.2794)
			(end 0.12065 -0.3048)
			(stroke
				(width 0.1)
				(type default)
			)
			(layer "F.Fab")
		)
		(fp_line
			(start 0.67945 -0.3048)
			(end 0.67945 0.3048)
			(stroke
				(width 0.1)
				(type default)
			)
			(layer "F.Fab")
		)
		(fp_line
			(start 0.67945 0.3048)
			(end 0.120396 0.3048)
			(stroke
				(width 0.1)
				(type default)
			)
			(layer "F.Fab")
		)
		(pad "1" smd circle
			(at -0.40005 0)
			(size 0 0)
			(layers "F.Cu" "F.Mask" "F.Paste")
			(net "P12V_E1S_IMON_0")
		)
		(pad "2" smd circle
			(at 0.40005 0)
			(size 0 0)
			(layers "F.Cu" "F.Mask" "F.Paste")
			(net "P12V_E1S_0_ISENSE_MPS_MAM")
		)
	)
	(footprint ""
		(layer "F.Cu")
		(at 120.36044 -428.107348)
		(property "Reference" "R3507"
			(at 0 0 0)
			(layer "F.SilkS")
			(hide yes)
			(effects
				(font
					(size 1.27 1.27)
				)
			)
		)
		(property "Value" ""
			(at 0 0 0)
			(layer "F.Fab")
			(effects
				(font
					(size 1.27 1.27)
				)
			)
		)
		(duplicate_pad_numbers_are_jumpers no)
		(fp_line
			(start -0.7874 -0.4064)
			(end 0.7874 -0.4064)
			(stroke
				(width 0.1524)
				(type default)
			)
			(layer "F.SilkS")
		)
		(fp_line
			(start -0.7874 0.4064)
			(end -0.7874 -0.4064)
			(stroke
				(width 0.1524)
				(type default)
			)
			(layer "F.SilkS")
		)
		(fp_line
			(start 0.7874 -0.4064)
			(end 0.7874 0.4064)
			(stroke
				(width 0.1524)
				(type default)
			)
			(layer "F.SilkS")
		)
		(fp_line
			(start 0.7874 0.4064)
			(end -0.7874 0.4064)
			(stroke
				(width 0.1524)
				(type default)
			)
			(layer "F.SilkS")
		)
		(fp_line
			(start -0.67945 -0.305054)
			(end -0.12065 -0.305054)
			(stroke
				(width 0.1)
				(type default)
			)
			(layer "F.Fab")
		)
		(fp_line
			(start -0.67945 0.3048)
			(end -0.67945 -0.305054)
			(stroke
				(width 0.1)
				(type default)
			)
			(layer "F.Fab")
		)
		(fp_line
			(start -0.12065 -0.305054)
			(end -0.12065 -0.2794)
			(stroke
				(width 0.1)
				(type default)
			)
			(layer "F.Fab")
		)
		(fp_line
			(start -0.12065 -0.2794)
			(end 0.12065 -0.2794)
			(stroke
				(width 0.1)
				(type default)
			)
			(layer "F.Fab")
		)
		(fp_line
			(start -0.12065 0.2794)
			(end -0.12065 0.3048)
			(stroke
				(width 0.1)
				(type default)
			)
			(layer "F.Fab")
		)
		(fp_line
			(start -0.12065 0.3048)
			(end -0.67945 0.3048)
			(stroke
				(width 0.1)
				(type default)
			)
			(layer "F.Fab")
		)
		(fp_line
			(start 0.120396 0.2794)
			(end -0.12065 0.2794)
			(stroke
				(width 0.1)
				(type default)
			)
			(layer "F.Fab")
		)
		(fp_line
			(start 0.120396 0.3048)
			(end 0.120396 0.2794)
			(stroke
				(width 0.1)
				(type default)
			)
			(layer "F.Fab")
		)
		(fp_line
			(start 0.12065 -0.3048)
			(end 0.67945 -0.3048)
			(stroke
				(width 0.1)
				(type default)
			)
			(layer "F.Fab")
		)
		(fp_line
			(start 0.12065 -0.2794)
			(end 0.12065 -0.3048)
			(stroke
				(width 0.1)
				(type default)
			)
			(layer "F.Fab")
		)
		(fp_line
			(start 0.67945 -0.3048)
			(end 0.67945 0.3048)
			(stroke
				(width 0.1)
				(type default)
			)
			(layer "F.Fab")
		)
		(fp_line
			(start 0.67945 0.3048)
			(end 0.120396 0.3048)
			(stroke
				(width 0.1)
				(type default)
			)
			(layer "F.Fab")
		)
		(pad "1" smd circle
			(at -0.40005 0)
			(size 0 0)
			(layers "F.Cu" "F.Mask" "F.Paste")
			(net "GPU_FPGA_RST_R_N")
		)
		(pad "2" smd circle
			(at 0.40005 0)
			(size 0 0)
			(layers "F.Cu" "F.Mask" "F.Paste")
			(net "GND")
		)
	)
	(footprint ""
		(layer "F.Cu")
		(at 85.626194 -99.477322 180)
		(property "Reference" "Q99"
			(at 2.758948 0.66802 0)
			(unlocked yes)
			(layer "F.SilkS")
			(effects
				(font
					(size 0.7874 0.5842)
					(thickness 0.1524)
				)
			)
		)
		(property "Value" ""
			(at 0 0 180)
			(layer "F.Fab")
			(effects
				(font
					(size 1.27 1.27)
				)
			)
		)
		(duplicate_pad_numbers_are_jumpers no)
		(fp_line
			(start 1.376172 1.199896)
			(end -1.376172 1.199896)
			(stroke
				(width 0.1524)
				(type default)
			)
			(layer "F.SilkS")
		)
		(fp_line
			(start 1.376172 -1.199896)
			(end 1.376172 1.199896)
			(stroke
				(width 0.1524)
				(type default)
			)
			(layer "F.SilkS")
		)
		(fp_line
			(start 0.508 -1.199896)
			(end 1.376172 -1.199896)
			(stroke
				(width 0.1524)
				(type default)
			)
			(layer "F.SilkS")
		)
		(fp_line
			(start 0 -0.762)
			(end 0.508 -1.199896)
			(stroke
				(width 0.1524)
				(type default)
			)
			(layer "F.SilkS")
		)
		(fp_line
			(start -0.508 -1.199896)
			(end 0 -0.762)
			(stroke
				(width 0.1524)
				(type default)
			)
			(layer "F.SilkS")
		)
		(fp_line
			(start -1.376172 1.199896)
			(end -1.376172 -1.199896)
			(stroke
				(width 0.1524)
				(type default)
			)
			(layer "F.SilkS")
		)
		(fp_line
			(start -1.376172 -1.199896)
			(end -0.508 -1.199896)
			(stroke
				(width 0.1524)
				(type default)
			)
			(layer "F.SilkS")
		)
		(fp_poly
			(pts
				(xy -1.96596 -0.82042) (xy -2.72796 -0.43942) (xy -2.72796 -1.20142)
			)
			(stroke
				(width 0)
				(type default)
			)
			(fill yes)
			(layer "F.SilkS")
		)
		(fp_line
			(start 0.674878 1.100074)
			(end -0.674878 1.100074)
			(stroke
				(width 0.1)
				(type default)
			)
			(layer "F.Fab")
		)
		(fp_line
			(start 0.674878 -1.100074)
			(end 0.674878 1.100074)
			(stroke
				(width 0.1)
				(type default)
			)
			(layer "F.Fab")
		)
		(fp_line
			(start -0.674878 1.100074)
			(end -0.674878 -1.100074)
			(stroke
				(width 0.1)
				(type default)
			)
			(layer "F.Fab")
		)
		(fp_line
			(start -0.674878 -1.100074)
			(end 0.674878 -1.100074)
			(stroke
				(width 0.1)
				(type default)
			)
			(layer "F.Fab")
		)
		(fp_poly
			(pts
				(xy -1.4605 -0.7493) (xy -2.2225 -1.1303) (xy -2.2225 -0.3683)
			)
			(stroke
				(width 0)
				(type default)
			)
			(fill yes)
			(layer "F.Fab")
		)
		(pad "1" smd rect
			(at -0.899922 -0.750062 90)
			(size 0.6096 0.6096)
			(layers "F.Cu" "F.Mask" "F.Paste")
			(net "GND")
		)
		(pad "2" smd rect
			(at -0.899922 0 90)
			(size 0.4064 0.6096)
			(layers "F.Cu" "F.Mask" "F.Paste")
			(net "RST_PLD_CPU1_DRAM_CD_N")
		)
		(pad "3" smd rect
			(at -0.899922 0.750062 90)
			(size 0.6096 0.6096)
			(layers "F.Cu" "F.Mask" "F.Paste")
			(net "Net_1464")
		)
		(pad "4" smd rect
			(at 0.899922 0.750062 90)
			(size 0.6096 0.6096)
			(layers "F.Cu" "F.Mask" "F.Paste")
			(net "Net_1466")
		)
		(pad "5" smd rect
			(at 0.899922 0 90)
			(size 0.4064 0.6096)
			(layers "F.Cu" "F.Mask" "F.Paste")
			(net "Net_1465")
		)
		(pad "6" smd rect
			(at 0.899922 -0.750062 90)
			(size 0.6096 0.6096)
			(layers "F.Cu" "F.Mask" "F.Paste")
			(net "LED_RST_PLD_CPU1_DRAM_CD_N_D")
		)
	)
	(footprint ""
		(layer "F.Cu")
		(at 256.889504 -43.504612 180)
		(property "Reference" "PC2207"
			(at 0 0 180)
			(layer "F.SilkS")
			(hide yes)
			(effects
				(font
					(size 1.27 1.27)
				)
			)
		)
		(property "Value" ""
			(at 0 0 180)
			(layer "F.Fab")
			(effects
				(font
					(size 1.27 1.27)
				)
			)
		)
		(duplicate_pad_numbers_are_jumpers no)
		(fp_line
			(start 0.7874 0.4064)
			(end -0.7874 0.4064)
			(stroke
				(width 0.1524)
				(type default)
			)
			(layer "F.SilkS")
		)
		(fp_line
			(start 0.7874 -0.4064)
			(end 0.7874 0.4064)
			(stroke
				(width 0.1524)
				(type default)
			)
			(layer "F.SilkS")
		)
		(fp_line
			(start -0.7874 0.4064)
			(end -0.7874 -0.4064)
			(stroke
				(width 0.1524)
				(type default)
			)
			(layer "F.SilkS")
		)
		(fp_line
			(start -0.7874 -0.4064)
			(end 0.7874 -0.4064)
			(stroke
				(width 0.1524)
				(type default)
			)
			(layer "F.SilkS")
		)
		(fp_line
			(start 0.67945 0.3048)
			(end 0.120396 0.3048)
			(stroke
				(width 0.1)
				(type default)
			)
			(layer "F.Fab")
		)
		(fp_line
			(start 0.67945 -0.3048)
			(end 0.67945 0.3048)
			(stroke
				(width 0.1)
				(type default)
			)
			(layer "F.Fab")
		)
		(fp_line
			(start 0.12065 -0.2794)
			(end 0.12065 -0.3048)
			(stroke
				(width 0.1)
				(type default)
			)
			(layer "F.Fab")
		)
		(fp_line
			(start 0.12065 -0.3048)
			(end 0.67945 -0.3048)
			(stroke
				(width 0.1)
				(type default)
			)
			(layer "F.Fab")
		)
		(fp_line
			(start 0.120396 0.3048)
			(end 0.120396 0.2794)
			(stroke
				(width 0.1)
				(type default)
			)
			(layer "F.Fab")
		)
		(fp_line
			(start 0.120396 0.2794)
			(end -0.12065 0.2794)
			(stroke
				(width 0.1)
				(type default)
			)
			(layer "F.Fab")
		)
		(fp_line
			(start -0.12065 0.3048)
			(end -0.67945 0.3048)
			(stroke
				(width 0.1)
				(type default)
			)
			(layer "F.Fab")
		)
		(fp_line
			(start -0.12065 0.2794)
			(end -0.12065 0.3048)
			(stroke
				(width 0.1)
				(type default)
			)
			(layer "F.Fab")
		)
		(fp_line
			(start -0.12065 -0.2794)
			(end 0.12065 -0.2794)
			(stroke
				(width 0.1)
				(type default)
			)
			(layer "F.Fab")
		)
		(fp_line
			(start -0.12065 -0.305054)
			(end -0.12065 -0.2794)
			(stroke
				(width 0.1)
				(type default)
			)
			(layer "F.Fab")
		)
		(fp_line
			(start -0.67945 0.3048)
			(end -0.67945 -0.305054)
			(stroke
				(width 0.1)
				(type default)
			)
			(layer "F.Fab")
		)
		(fp_line
			(start -0.67945 -0.305054)
			(end -0.12065 -0.305054)
			(stroke
				(width 0.1)
				(type default)
			)
			(layer "F.Fab")
		)
		(pad "1" smd circle
			(at -0.40005 0 180)
			(size 0 0)
			(layers "F.Cu" "F.Mask" "F.Paste")
			(net "P12V_AUX")
		)
		(pad "2" smd circle
			(at 0.40005 0 180)
			(size 0 0)
			(layers "F.Cu" "F.Mask" "F.Paste")
			(net "GND")
		)
	)
	(footprint ""
		(layer "F.Cu")
		(at 361.953556 -338.180172 90)
		(property "Reference" "PR1769"
			(at 0 0 90)
			(layer "F.SilkS")
			(hide yes)
			(effects
				(font
					(size 1.27 1.27)
				)
			)
		)
		(property "Value" ""
			(at 0 0 90)
			(layer "F.Fab")
			(effects
				(font
					(size 1.27 1.27)
				)
			)
		)
		(duplicate_pad_numbers_are_jumpers no)
		(fp_line
			(start 0.7874 -0.4064)
			(end 0.7874 0.4064)
			(stroke
				(width 0.1524)
				(type default)
			)
			(layer "F.SilkS")
		)
		(fp_line
			(start -0.7874 -0.4064)
			(end 0.7874 -0.4064)
			(stroke
				(width 0.1524)
				(type default)
			)
			(layer "F.SilkS")
		)
		(fp_line
			(start 0.7874 0.4064)
			(end -0.7874 0.4064)
			(stroke
				(width 0.1524)
				(type default)
			)
			(layer "F.SilkS")
		)
		(fp_line
			(start -0.7874 0.4064)
			(end -0.7874 -0.4064)
			(stroke
				(width 0.1524)
				(type default)
			)
			(layer "F.SilkS")
		)
		(fp_line
			(start -0.12065 -0.305054)
			(end -0.12065 -0.2794)
			(stroke
				(width 0.1)
				(type default)
			)
			(layer "F.Fab")
		)
		(fp_line
			(start -0.67945 -0.305054)
			(end -0.12065 -0.305054)
			(stroke
				(width 0.1)
				(type default)
			)
			(layer "F.Fab")
		)
		(fp_line
			(start 0.67945 -0.3048)
			(end 0.67945 0.3048)
			(stroke
				(width 0.1)
				(type default)
			)
			(layer "F.Fab")
		)
		(fp_line
			(start 0.12065 -0.3048)
			(end 0.67945 -0.3048)
			(stroke
				(width 0.1)
				(type default)
			)
			(layer "F.Fab")
		)
		(fp_line
			(start 0.12065 -0.2794)
			(end 0.12065 -0.3048)
			(stroke
				(width 0.1)
				(type default)
			)
			(layer "F.Fab")
		)
		(fp_line
			(start -0.12065 -0.2794)
			(end 0.12065 -0.2794)
			(stroke
				(width 0.1)
				(type default)
			)
			(layer "F.Fab")
		)
		(fp_line
			(start 0.120396 0.2794)
			(end -0.12065 0.2794)
			(stroke
				(width 0.1)
				(type default)
			)
			(layer "F.Fab")
		)
		(fp_line
			(start -0.12065 0.2794)
			(end -0.12065 0.3048)
			(stroke
				(width 0.1)
				(type default)
			)
			(layer "F.Fab")
		)
		(fp_line
			(start 0.67945 0.3048)
			(end 0.120396 0.3048)
			(stroke
				(width 0.1)
				(type default)
			)
			(layer "F.Fab")
		)
		(fp_line
			(start 0.120396 0.3048)
			(end 0.120396 0.2794)
			(stroke
				(width 0.1)
				(type default)
			)
			(layer "F.Fab")
		)
		(fp_line
			(start -0.12065 0.3048)
			(end -0.67945 0.3048)
			(stroke
				(width 0.1)
				(type default)
			)
			(layer "F.Fab")
		)
		(fp_line
			(start -0.67945 0.3048)
			(end -0.67945 -0.305054)
			(stroke
				(width 0.1)
				(type default)
			)
			(layer "F.Fab")
		)
		(pad "1" smd circle
			(at -0.40005 0 90)
			(size 0 0)
			(layers "F.Cu" "F.Mask" "F.Paste")
			(net "SW_PVCCIN_CPU0_BOOT3")
		)
		(pad "2" smd circle
			(at 0.40005 0 90)
			(size 0 0)
			(layers "F.Cu" "F.Mask" "F.Paste")
			(net "SW_PVCCIN_CPU0_BOOT3_R")
		)
	)
	(footprint ""
		(layer "F.Cu")
		(at 299.02023 -52.368196 180)
		(property "Reference" "R2978"
			(at 0 0 180)
			(layer "F.SilkS")
			(hide yes)
			(effects
				(font
					(size 1.27 1.27)
				)
			)
		)
		(property "Value" ""
			(at 0 0 180)
			(layer "F.Fab")
			(effects
				(font
					(size 1.27 1.27)
				)
			)
		)
		(duplicate_pad_numbers_are_jumpers no)
		(fp_line
			(start 0.7874 0.4064)
			(end -0.7874 0.4064)
			(stroke
				(width 0.1524)
				(type default)
			)
			(layer "F.SilkS")
		)
		(fp_line
			(start 0.7874 -0.4064)
			(end 0.7874 0.4064)
			(stroke
				(width 0.1524)
				(type default)
			)
			(layer "F.SilkS")
		)
		(fp_line
			(start -0.7874 0.4064)
			(end -0.7874 -0.4064)
			(stroke
				(width 0.1524)
				(type default)
			)
			(layer "F.SilkS")
		)
		(fp_line
			(start -0.7874 -0.4064)
			(end 0.7874 -0.4064)
			(stroke
				(width 0.1524)
				(type default)
			)
			(layer "F.SilkS")
		)
		(fp_line
			(start 0.67945 0.3048)
			(end 0.120396 0.3048)
			(stroke
				(width 0.1)
				(type default)
			)
			(layer "F.Fab")
		)
		(fp_line
			(start 0.67945 -0.3048)
			(end 0.67945 0.3048)
			(stroke
				(width 0.1)
				(type default)
			)
			(layer "F.Fab")
		)
		(fp_line
			(start 0.12065 -0.2794)
			(end 0.12065 -0.3048)
			(stroke
				(width 0.1)
				(type default)
			)
			(layer "F.Fab")
		)
		(fp_line
			(start 0.12065 -0.3048)
			(end 0.67945 -0.3048)
			(stroke
				(width 0.1)
				(type default)
			)
			(layer "F.Fab")
		)
		(fp_line
			(start 0.120396 0.3048)
			(end 0.120396 0.2794)
			(stroke
				(width 0.1)
				(type default)
			)
			(layer "F.Fab")
		)
		(fp_line
			(start 0.120396 0.2794)
			(end -0.12065 0.2794)
			(stroke
				(width 0.1)
				(type default)
			)
			(layer "F.Fab")
		)
		(fp_line
			(start -0.12065 0.3048)
			(end -0.67945 0.3048)
			(stroke
				(width 0.1)
				(type default)
			)
			(layer "F.Fab")
		)
		(fp_line
			(start -0.12065 0.2794)
			(end -0.12065 0.3048)
			(stroke
				(width 0.1)
				(type default)
			)
			(layer "F.Fab")
		)
		(fp_line
			(start -0.12065 -0.2794)
			(end 0.12065 -0.2794)
			(stroke
				(width 0.1)
				(type default)
			)
			(layer "F.Fab")
		)
		(fp_line
			(start -0.12065 -0.305054)
			(end -0.12065 -0.2794)
			(stroke
				(width 0.1)
				(type default)
			)
			(layer "F.Fab")
		)
		(fp_line
			(start -0.67945 0.3048)
			(end -0.67945 -0.305054)
			(stroke
				(width 0.1)
				(type default)
			)
			(layer "F.Fab")
		)
		(fp_line
			(start -0.67945 -0.305054)
			(end -0.12065 -0.305054)
			(stroke
				(width 0.1)
				(type default)
			)
			(layer "F.Fab")
		)
		(pad "1" smd circle
			(at -0.40005 0 180)
			(size 0 0)
			(layers "F.Cu" "F.Mask" "F.Paste")
			(net "FAB_REV_ID0")
		)
		(pad "2" smd circle
			(at 0.40005 0 180)
			(size 0 0)
			(layers "F.Cu" "F.Mask" "F.Paste")
			(net "GND")
		)
	)
	(footprint ""
		(layer "F.Cu")
		(at 13.6398 -425.7548 90)
		(property "Reference" "R2696"
			(at 0 0 90)
			(layer "F.SilkS")
			(hide yes)
			(effects
				(font
					(size 1.27 1.27)
				)
			)
		)
		(property "Value" ""
			(at 0 0 90)
			(layer "F.Fab")
			(effects
				(font
					(size 1.27 1.27)
				)
			)
		)
		(duplicate_pad_numbers_are_jumpers no)
		(fp_line
			(start 0.7874 -0.4064)
			(end 0.7874 0.4064)
			(stroke
				(width 0.1524)
				(type default)
			)
			(layer "F.SilkS")
		)
		(fp_line
			(start -0.7874 -0.4064)
			(end 0.7874 -0.4064)
			(stroke
				(width 0.1524)
				(type default)
			)
			(layer "F.SilkS")
		)
		(fp_line
			(start 0.7874 0.4064)
			(end -0.7874 0.4064)
			(stroke
				(width 0.1524)
				(type default)
			)
			(layer "F.SilkS")
		)
		(fp_line
			(start -0.7874 0.4064)
			(end -0.7874 -0.4064)
			(stroke
				(width 0.1524)
				(type default)
			)
			(layer "F.SilkS")
		)
		(fp_line
			(start -0.12065 -0.305054)
			(end -0.12065 -0.2794)
			(stroke
				(width 0.1)
				(type default)
			)
			(layer "F.Fab")
		)
		(fp_line
			(start -0.67945 -0.305054)
			(end -0.12065 -0.305054)
			(stroke
				(width 0.1)
				(type default)
			)
			(layer "F.Fab")
		)
		(fp_line
			(start 0.67945 -0.3048)
			(end 0.67945 0.3048)
			(stroke
				(width 0.1)
				(type default)
			)
			(layer "F.Fab")
		)
		(fp_line
			(start 0.12065 -0.3048)
			(end 0.67945 -0.3048)
			(stroke
				(width 0.1)
				(type default)
			)
			(layer "F.Fab")
		)
		(fp_line
			(start 0.12065 -0.2794)
			(end 0.12065 -0.3048)
			(stroke
				(width 0.1)
				(type default)
			)
			(layer "F.Fab")
		)
		(fp_line
			(start -0.12065 -0.2794)
			(end 0.12065 -0.2794)
			(stroke
				(width 0.1)
				(type default)
			)
			(layer "F.Fab")
		)
		(fp_line
			(start 0.120396 0.2794)
			(end -0.12065 0.2794)
			(stroke
				(width 0.1)
				(type default)
			)
			(layer "F.Fab")
		)
		(fp_line
			(start -0.12065 0.2794)
			(end -0.12065 0.3048)
			(stroke
				(width 0.1)
				(type default)
			)
			(layer "F.Fab")
		)
		(fp_line
			(start 0.67945 0.3048)
			(end 0.120396 0.3048)
			(stroke
				(width 0.1)
				(type default)
			)
			(layer "F.Fab")
		)
		(fp_line
			(start 0.120396 0.3048)
			(end 0.120396 0.2794)
			(stroke
				(width 0.1)
				(type default)
			)
			(layer "F.Fab")
		)
		(fp_line
			(start -0.12065 0.3048)
			(end -0.67945 0.3048)
			(stroke
				(width 0.1)
				(type default)
			)
			(layer "F.Fab")
		)
		(fp_line
			(start -0.67945 0.3048)
			(end -0.67945 -0.305054)
			(stroke
				(width 0.1)
				(type default)
			)
			(layer "F.Fab")
		)
		(pad "1" smd circle
			(at -0.40005 0 90)
			(size 0 0)
			(layers "F.Cu" "F.Mask" "F.Paste")
			(net "TCA9539_0_ADD0")
		)
		(pad "2" smd circle
			(at 0.40005 0 90)
			(size 0 0)
			(layers "F.Cu" "F.Mask" "F.Paste")
			(net "GND")
		)
	)
	(footprint ""
		(layer "F.Cu")
		(at 332.68666 -16.2052 -90)
		(property "Reference" "R2132"
			(at 0 0 270)
			(layer "F.SilkS")
			(hide yes)
			(effects
				(font
					(size 1.27 1.27)
				)
			)
		)
		(property "Value" ""
			(at 0 0 270)
			(layer "F.Fab")
			(effects
				(font
					(size 1.27 1.27)
				)
			)
		)
		(duplicate_pad_numbers_are_jumpers no)
		(fp_line
			(start -0.7874 0.4064)
			(end -0.7874 -0.4064)
			(stroke
				(width 0.1524)
				(type default)
			)
			(layer "F.SilkS")
		)
		(fp_line
			(start 0.7874 0.4064)
			(end -0.7874 0.4064)
			(stroke
				(width 0.1524)
				(type default)
			)
			(layer "F.SilkS")
		)
		(fp_line
			(start -0.7874 -0.4064)
			(end 0.7874 -0.4064)
			(stroke
				(width 0.1524)
				(type default)
			)
			(layer "F.SilkS")
		)
		(fp_line
			(start 0.7874 -0.4064)
			(end 0.7874 0.4064)
			(stroke
				(width 0.1524)
				(type default)
			)
			(layer "F.SilkS")
		)
		(fp_line
			(start -0.67945 0.3048)
			(end -0.67945 -0.305054)
			(stroke
				(width 0.1)
				(type default)
			)
			(layer "F.Fab")
		)
		(fp_line
			(start -0.12065 0.3048)
			(end -0.67945 0.3048)
			(stroke
				(width 0.1)
				(type default)
			)
			(layer "F.Fab")
		)
		(fp_line
			(start 0.120396 0.3048)
			(end 0.120396 0.2794)
			(stroke
				(width 0.1)
				(type default)
			)
			(layer "F.Fab")
		)
		(fp_line
			(start 0.67945 0.3048)
			(end 0.120396 0.3048)
			(stroke
				(width 0.1)
				(type default)
			)
			(layer "F.Fab")
		)
		(fp_line
			(start -0.12065 0.2794)
			(end -0.12065 0.3048)
			(stroke
				(width 0.1)
				(type default)
			)
			(layer "F.Fab")
		)
		(fp_line
			(start 0.120396 0.2794)
			(end -0.12065 0.2794)
			(stroke
				(width 0.1)
				(type default)
			)
			(layer "F.Fab")
		)
		(fp_line
			(start -0.12065 -0.2794)
			(end 0.12065 -0.2794)
			(stroke
				(width 0.1)
				(type default)
			)
			(layer "F.Fab")
		)
		(fp_line
			(start 0.12065 -0.2794)
			(end 0.12065 -0.3048)
			(stroke
				(width 0.1)
				(type default)
			)
			(layer "F.Fab")
		)
		(fp_line
			(start 0.12065 -0.3048)
			(end 0.67945 -0.3048)
			(stroke
				(width 0.1)
				(type default)
			)
			(layer "F.Fab")
		)
		(fp_line
			(start 0.67945 -0.3048)
			(end 0.67945 0.3048)
			(stroke
				(width 0.1)
				(type default)
			)
			(layer "F.Fab")
		)
		(fp_line
			(start -0.67945 -0.305054)
			(end -0.12065 -0.305054)
			(stroke
				(width 0.1)
				(type default)
			)
			(layer "F.Fab")
		)
		(fp_line
			(start -0.12065 -0.305054)
			(end -0.12065 -0.2794)
			(stroke
				(width 0.1)
				(type default)
			)
			(layer "F.Fab")
		)
		(pad "1" smd circle
			(at -0.40005 0 270)
			(size 0 0)
			(layers "F.Cu" "F.Mask" "F.Paste")
			(net "JTAG_TRC_PCH_PTI<6>")
		)
		(pad "2" smd circle
			(at 0.40005 0 270)
			(size 0 0)
			(layers "F.Cu" "F.Mask" "F.Paste")
			(net "FM_ESPI_PLD_R1_EN")
		)
	)
	(footprint ""
		(layer "F.Cu")
		(at 304.53965 -60.094368)
		(property "Reference" "R2253"
			(at 0 0 0)
			(layer "F.SilkS")
			(hide yes)
			(effects
				(font
					(size 1.27 1.27)
				)
			)
		)
		(property "Value" ""
			(at 0 0 0)
			(layer "F.Fab")
			(effects
				(font
					(size 1.27 1.27)
				)
			)
		)
		(duplicate_pad_numbers_are_jumpers no)
		(fp_line
			(start -0.7874 -0.4064)
			(end 0.7874 -0.4064)
			(stroke
				(width 0.1524)
				(type default)
			)
			(layer "F.SilkS")
		)
		(fp_line
			(start -0.7874 0.4064)
			(end -0.7874 -0.4064)
			(stroke
				(width 0.1524)
				(type default)
			)
			(layer "F.SilkS")
		)
		(fp_line
			(start 0.7874 -0.4064)
			(end 0.7874 0.4064)
			(stroke
				(width 0.1524)
				(type default)
			)
			(layer "F.SilkS")
		)
		(fp_line
			(start 0.7874 0.4064)
			(end -0.7874 0.4064)
			(stroke
				(width 0.1524)
				(type default)
			)
			(layer "F.SilkS")
		)
		(fp_line
			(start -0.67945 -0.305054)
			(end -0.12065 -0.305054)
			(stroke
				(width 0.1)
				(type default)
			)
			(layer "F.Fab")
		)
		(fp_line
			(start -0.67945 0.3048)
			(end -0.67945 -0.305054)
			(stroke
				(width 0.1)
				(type default)
			)
			(layer "F.Fab")
		)
		(fp_line
			(start -0.12065 -0.305054)
			(end -0.12065 -0.2794)
			(stroke
				(width 0.1)
				(type default)
			)
			(layer "F.Fab")
		)
		(fp_line
			(start -0.12065 -0.2794)
			(end 0.12065 -0.2794)
			(stroke
				(width 0.1)
				(type default)
			)
			(layer "F.Fab")
		)
		(fp_line
			(start -0.12065 0.2794)
			(end -0.12065 0.3048)
			(stroke
				(width 0.1)
				(type default)
			)
			(layer "F.Fab")
		)
		(fp_line
			(start -0.12065 0.3048)
			(end -0.67945 0.3048)
			(stroke
				(width 0.1)
				(type default)
			)
			(layer "F.Fab")
		)
		(fp_line
			(start 0.120396 0.2794)
			(end -0.12065 0.2794)
			(stroke
				(width 0.1)
				(type default)
			)
			(layer "F.Fab")
		)
		(fp_line
			(start 0.120396 0.3048)
			(end 0.120396 0.2794)
			(stroke
				(width 0.1)
				(type default)
			)
			(layer "F.Fab")
		)
		(fp_line
			(start 0.12065 -0.3048)
			(end 0.67945 -0.3048)
			(stroke
				(width 0.1)
				(type default)
			)
			(layer "F.Fab")
		)
		(fp_line
			(start 0.12065 -0.2794)
			(end 0.12065 -0.3048)
			(stroke
				(width 0.1)
				(type default)
			)
			(layer "F.Fab")
		)
		(fp_line
			(start 0.67945 -0.3048)
			(end 0.67945 0.3048)
			(stroke
				(width 0.1)
				(type default)
			)
			(layer "F.Fab")
		)
		(fp_line
			(start 0.67945 0.3048)
			(end 0.120396 0.3048)
			(stroke
				(width 0.1)
				(type default)
			)
			(layer "F.Fab")
		)
		(pad "1" smd circle
			(at -0.40005 0)
			(size 0 0)
			(layers "F.Cu" "F.Mask" "F.Paste")
			(net "P3V3_AUX")
		)
		(pad "2" smd circle
			(at 0.40005 0)
			(size 0 0)
			(layers "F.Cu" "F.Mask" "F.Paste")
			(net "PECI_MUX_SEL_R")
		)
	)
	(footprint ""
		(layer "F.Cu")
		(at 264.126726 -129.439924 180)
		(property "Reference" "C2338"
			(at 0 0 180)
			(layer "F.SilkS")
			(hide yes)
			(effects
				(font
					(size 1.27 1.27)
				)
			)
		)
		(property "Value" ""
			(at 0 0 180)
			(layer "F.Fab")
			(effects
				(font
					(size 1.27 1.27)
				)
			)
		)
		(duplicate_pad_numbers_are_jumpers no)
		(fp_line
			(start 0.7874 0.4064)
			(end -0.7874 0.4064)
			(stroke
				(width 0.1524)
				(type default)
			)
			(layer "F.SilkS")
		)
		(fp_line
			(start 0.7874 -0.4064)
			(end 0.7874 0.4064)
			(stroke
				(width 0.1524)
				(type default)
			)
			(layer "F.SilkS")
		)
		(fp_line
			(start -0.7874 0.4064)
			(end -0.7874 -0.4064)
			(stroke
				(width 0.1524)
				(type default)
			)
			(layer "F.SilkS")
		)
		(fp_line
			(start -0.7874 -0.4064)
			(end 0.7874 -0.4064)
			(stroke
				(width 0.1524)
				(type default)
			)
			(layer "F.SilkS")
		)
		(fp_line
			(start 0.67945 0.3048)
			(end 0.120396 0.3048)
			(stroke
				(width 0.1)
				(type default)
			)
			(layer "F.Fab")
		)
		(fp_line
			(start 0.67945 -0.3048)
			(end 0.67945 0.3048)
			(stroke
				(width 0.1)
				(type default)
			)
			(layer "F.Fab")
		)
		(fp_line
			(start 0.12065 -0.2794)
			(end 0.12065 -0.3048)
			(stroke
				(width 0.1)
				(type default)
			)
			(layer "F.Fab")
		)
		(fp_line
			(start 0.12065 -0.3048)
			(end 0.67945 -0.3048)
			(stroke
				(width 0.1)
				(type default)
			)
			(layer "F.Fab")
		)
		(fp_line
			(start 0.120396 0.3048)
			(end 0.120396 0.2794)
			(stroke
				(width 0.1)
				(type default)
			)
			(layer "F.Fab")
		)
		(fp_line
			(start 0.120396 0.2794)
			(end -0.12065 0.2794)
			(stroke
				(width 0.1)
				(type default)
			)
			(layer "F.Fab")
		)
		(fp_line
			(start -0.12065 0.3048)
			(end -0.67945 0.3048)
			(stroke
				(width 0.1)
				(type default)
			)
			(layer "F.Fab")
		)
		(fp_line
			(start -0.12065 0.2794)
			(end -0.12065 0.3048)
			(stroke
				(width 0.1)
				(type default)
			)
			(layer "F.Fab")
		)
		(fp_line
			(start -0.12065 -0.2794)
			(end 0.12065 -0.2794)
			(stroke
				(width 0.1)
				(type default)
			)
			(layer "F.Fab")
		)
		(fp_line
			(start -0.12065 -0.305054)
			(end -0.12065 -0.2794)
			(stroke
				(width 0.1)
				(type default)
			)
			(layer "F.Fab")
		)
		(fp_line
			(start -0.67945 0.3048)
			(end -0.67945 -0.305054)
			(stroke
				(width 0.1)
				(type default)
			)
			(layer "F.Fab")
		)
		(fp_line
			(start -0.67945 -0.305054)
			(end -0.12065 -0.305054)
			(stroke
				(width 0.1)
				(type default)
			)
			(layer "F.Fab")
		)
		(pad "1" smd circle
			(at -0.40005 0 180)
			(size 0 0)
			(layers "F.Cu" "F.Mask" "F.Paste")
			(net "P3V3")
		)
		(pad "2" smd circle
			(at 0.40005 0 180)
			(size 0 0)
			(layers "F.Cu" "F.Mask" "F.Paste")
			(net "GND")
		)
	)
	(footprint ""
		(layer "F.Cu")
		(at 111.13008 -119.846598 -90)
		(property "Reference" "R851"
			(at 0 0 270)
			(layer "F.SilkS")
			(hide yes)
			(effects
				(font
					(size 1.27 1.27)
				)
			)
		)
		(property "Value" ""
			(at 0 0 270)
			(layer "F.Fab")
			(effects
				(font
					(size 1.27 1.27)
				)
			)
		)
		(duplicate_pad_numbers_are_jumpers no)
		(fp_line
			(start -0.7874 0.4064)
			(end -0.7874 -0.4064)
			(stroke
				(width 0.1524)
				(type default)
			)
			(layer "F.SilkS")
		)
		(fp_line
			(start 0.7874 0.4064)
			(end -0.7874 0.4064)
			(stroke
				(width 0.1524)
				(type default)
			)
			(layer "F.SilkS")
		)
		(fp_line
			(start -0.7874 -0.4064)
			(end 0.7874 -0.4064)
			(stroke
				(width 0.1524)
				(type default)
			)
			(layer "F.SilkS")
		)
		(fp_line
			(start 0.7874 -0.4064)
			(end 0.7874 0.4064)
			(stroke
				(width 0.1524)
				(type default)
			)
			(layer "F.SilkS")
		)
		(fp_line
			(start -0.67945 0.3048)
			(end -0.67945 -0.305054)
			(stroke
				(width 0.1)
				(type default)
			)
			(layer "F.Fab")
		)
		(fp_line
			(start -0.12065 0.3048)
			(end -0.67945 0.3048)
			(stroke
				(width 0.1)
				(type default)
			)
			(layer "F.Fab")
		)
		(fp_line
			(start 0.120396 0.3048)
			(end 0.120396 0.2794)
			(stroke
				(width 0.1)
				(type default)
			)
			(layer "F.Fab")
		)
		(fp_line
			(start 0.67945 0.3048)
			(end 0.120396 0.3048)
			(stroke
				(width 0.1)
				(type default)
			)
			(layer "F.Fab")
		)
		(fp_line
			(start -0.12065 0.2794)
			(end -0.12065 0.3048)
			(stroke
				(width 0.1)
				(type default)
			)
			(layer "F.Fab")
		)
		(fp_line
			(start 0.120396 0.2794)
			(end -0.12065 0.2794)
			(stroke
				(width 0.1)
				(type default)
			)
			(layer "F.Fab")
		)
		(fp_line
			(start -0.12065 -0.2794)
			(end 0.12065 -0.2794)
			(stroke
				(width 0.1)
				(type default)
			)
			(layer "F.Fab")
		)
		(fp_line
			(start 0.12065 -0.2794)
			(end 0.12065 -0.3048)
			(stroke
				(width 0.1)
				(type default)
			)
			(layer "F.Fab")
		)
		(fp_line
			(start 0.12065 -0.3048)
			(end 0.67945 -0.3048)
			(stroke
				(width 0.1)
				(type default)
			)
			(layer "F.Fab")
		)
		(fp_line
			(start 0.67945 -0.3048)
			(end 0.67945 0.3048)
			(stroke
				(width 0.1)
				(type default)
			)
			(layer "F.Fab")
		)
		(fp_line
			(start -0.67945 -0.305054)
			(end -0.12065 -0.305054)
			(stroke
				(width 0.1)
				(type default)
			)
			(layer "F.Fab")
		)
		(fp_line
			(start -0.12065 -0.305054)
			(end -0.12065 -0.2794)
			(stroke
				(width 0.1)
				(type default)
			)
			(layer "F.Fab")
		)
		(pad "1" smd circle
			(at -0.40005 0 270)
			(size 0 0)
			(layers "F.Cu" "F.Mask" "F.Paste")
			(net "RST_CPU0_DRAM_AB_N")
		)
		(pad "2" smd circle
			(at 0.40005 0 270)
			(size 0 0)
			(layers "F.Cu" "F.Mask" "F.Paste")
			(net "RST_CPU0_DRAM_AB_PLD_N")
		)
	)
	(footprint ""
		(layer "F.Cu")
		(at 133.02488 -92.674948 -90)
		(property "Reference" "R4402"
			(at 0 0 270)
			(layer "F.SilkS")
			(hide yes)
			(effects
				(font
					(size 1.27 1.27)
				)
			)
		)
		(property "Value" ""
			(at 0 0 270)
			(layer "F.Fab")
			(effects
				(font
					(size 1.27 1.27)
				)
			)
		)
		(duplicate_pad_numbers_are_jumpers no)
		(fp_line
			(start -0.7874 0.4064)
			(end -0.7874 -0.4064)
			(stroke
				(width 0.1524)
				(type default)
			)
			(layer "F.SilkS")
		)
		(fp_line
			(start 0.7874 0.4064)
			(end -0.7874 0.4064)
			(stroke
				(width 0.1524)
				(type default)
			)
			(layer "F.SilkS")
		)
		(fp_line
			(start -0.7874 -0.4064)
			(end 0.7874 -0.4064)
			(stroke
				(width 0.1524)
				(type default)
			)
			(layer "F.SilkS")
		)
		(fp_line
			(start 0.7874 -0.4064)
			(end 0.7874 0.4064)
			(stroke
				(width 0.1524)
				(type default)
			)
			(layer "F.SilkS")
		)
		(fp_line
			(start -0.67945 0.3048)
			(end -0.67945 -0.305054)
			(stroke
				(width 0.1)
				(type default)
			)
			(layer "F.Fab")
		)
		(fp_line
			(start -0.12065 0.3048)
			(end -0.67945 0.3048)
			(stroke
				(width 0.1)
				(type default)
			)
			(layer "F.Fab")
		)
		(fp_line
			(start 0.120396 0.3048)
			(end 0.120396 0.2794)
			(stroke
				(width 0.1)
				(type default)
			)
			(layer "F.Fab")
		)
		(fp_line
			(start 0.67945 0.3048)
			(end 0.120396 0.3048)
			(stroke
				(width 0.1)
				(type default)
			)
			(layer "F.Fab")
		)
		(fp_line
			(start -0.12065 0.2794)
			(end -0.12065 0.3048)
			(stroke
				(width 0.1)
				(type default)
			)
			(layer "F.Fab")
		)
		(fp_line
			(start 0.120396 0.2794)
			(end -0.12065 0.2794)
			(stroke
				(width 0.1)
				(type default)
			)
			(layer "F.Fab")
		)
		(fp_line
			(start -0.12065 -0.2794)
			(end 0.12065 -0.2794)
			(stroke
				(width 0.1)
				(type default)
			)
			(layer "F.Fab")
		)
		(fp_line
			(start 0.12065 -0.2794)
			(end 0.12065 -0.3048)
			(stroke
				(width 0.1)
				(type default)
			)
			(layer "F.Fab")
		)
		(fp_line
			(start 0.12065 -0.3048)
			(end 0.67945 -0.3048)
			(stroke
				(width 0.1)
				(type default)
			)
			(layer "F.Fab")
		)
		(fp_line
			(start 0.67945 -0.3048)
			(end 0.67945 0.3048)
			(stroke
				(width 0.1)
				(type default)
			)
			(layer "F.Fab")
		)
		(fp_line
			(start -0.67945 -0.305054)
			(end -0.12065 -0.305054)
			(stroke
				(width 0.1)
				(type default)
			)
			(layer "F.Fab")
		)
		(fp_line
			(start -0.12065 -0.305054)
			(end -0.12065 -0.2794)
			(stroke
				(width 0.1)
				(type default)
			)
			(layer "F.Fab")
		)
		(pad "1" smd circle
			(at -0.40005 0 270)
			(size 0 0)
			(layers "F.Cu" "F.Mask" "F.Paste")
			(net "PVNN_TERM_CPU1")
		)
		(pad "2" smd circle
			(at 0.40005 0 270)
			(size 0 0)
			(layers "F.Cu" "F.Mask" "F.Paste")
			(net "H_CPU1_MEMHOT_OUT_LVC1_R_N")
		)
	)
	(footprint ""
		(layer "F.Cu")
		(at 183.515 -93.91015 90)
		(property "Reference" "R4765"
			(at 0 0 90)
			(layer "F.SilkS")
			(hide yes)
			(effects
				(font
					(size 1.27 1.27)
				)
			)
		)
		(property "Value" ""
			(at 0 0 90)
			(layer "F.Fab")
			(effects
				(font
					(size 1.27 1.27)
				)
			)
		)
		(duplicate_pad_numbers_are_jumpers no)
		(fp_line
			(start 0.7874 -0.4064)
			(end 0.7874 0.4064)
			(stroke
				(width 0.1524)
				(type default)
			)
			(layer "F.SilkS")
		)
		(fp_line
			(start -0.7874 -0.4064)
			(end 0.7874 -0.4064)
			(stroke
				(width 0.1524)
				(type default)
			)
			(layer "F.SilkS")
		)
		(fp_line
			(start 0.7874 0.4064)
			(end -0.7874 0.4064)
			(stroke
				(width 0.1524)
				(type default)
			)
			(layer "F.SilkS")
		)
		(fp_line
			(start -0.7874 0.4064)
			(end -0.7874 -0.4064)
			(stroke
				(width 0.1524)
				(type default)
			)
			(layer "F.SilkS")
		)
		(fp_line
			(start -0.12065 -0.305054)
			(end -0.12065 -0.2794)
			(stroke
				(width 0.1)
				(type default)
			)
			(layer "F.Fab")
		)
		(fp_line
			(start -0.67945 -0.305054)
			(end -0.12065 -0.305054)
			(stroke
				(width 0.1)
				(type default)
			)
			(layer "F.Fab")
		)
		(fp_line
			(start 0.67945 -0.3048)
			(end 0.67945 0.3048)
			(stroke
				(width 0.1)
				(type default)
			)
			(layer "F.Fab")
		)
		(fp_line
			(start 0.12065 -0.3048)
			(end 0.67945 -0.3048)
			(stroke
				(width 0.1)
				(type default)
			)
			(layer "F.Fab")
		)
		(fp_line
			(start 0.12065 -0.2794)
			(end 0.12065 -0.3048)
			(stroke
				(width 0.1)
				(type default)
			)
			(layer "F.Fab")
		)
		(fp_line
			(start -0.12065 -0.2794)
			(end 0.12065 -0.2794)
			(stroke
				(width 0.1)
				(type default)
			)
			(layer "F.Fab")
		)
		(fp_line
			(start 0.120396 0.2794)
			(end -0.12065 0.2794)
			(stroke
				(width 0.1)
				(type default)
			)
			(layer "F.Fab")
		)
		(fp_line
			(start -0.12065 0.2794)
			(end -0.12065 0.3048)
			(stroke
				(width 0.1)
				(type default)
			)
			(layer "F.Fab")
		)
		(fp_line
			(start 0.67945 0.3048)
			(end 0.120396 0.3048)
			(stroke
				(width 0.1)
				(type default)
			)
			(layer "F.Fab")
		)
		(fp_line
			(start 0.120396 0.3048)
			(end 0.120396 0.2794)
			(stroke
				(width 0.1)
				(type default)
			)
			(layer "F.Fab")
		)
		(fp_line
			(start -0.12065 0.3048)
			(end -0.67945 0.3048)
			(stroke
				(width 0.1)
				(type default)
			)
			(layer "F.Fab")
		)
		(fp_line
			(start -0.67945 0.3048)
			(end -0.67945 -0.305054)
			(stroke
				(width 0.1)
				(type default)
			)
			(layer "F.Fab")
		)
		(pad "1" smd circle
			(at -0.40005 0 90)
			(size 0 0)
			(layers "F.Cu" "F.Mask" "F.Paste")
			(net "HP_LVC3_E1S_0_HSC_PWRGD")
		)
		(pad "2" smd circle
			(at 0.40005 0 90)
			(size 0 0)
			(layers "F.Cu" "F.Mask" "F.Paste")
			(net "HP_LVC3_E1S_0_HSC_PWRGD_PLD")
		)
	)
	(footprint ""
		(layer "F.Cu")
		(at 424.204892 -386.298948)
		(property "Reference" "R2837"
			(at 0 0 0)
			(layer "F.SilkS")
			(hide yes)
			(effects
				(font
					(size 1.27 1.27)
				)
			)
		)
		(property "Value" ""
			(at 0 0 0)
			(layer "F.Fab")
			(effects
				(font
					(size 1.27 1.27)
				)
			)
		)
		(duplicate_pad_numbers_are_jumpers no)
		(fp_line
			(start -0.7874 -0.4064)
			(end 0.7874 -0.4064)
			(stroke
				(width 0.1524)
				(type default)
			)
			(layer "F.SilkS")
		)
		(fp_line
			(start -0.7874 0.4064)
			(end -0.7874 -0.4064)
			(stroke
				(width 0.1524)
				(type default)
			)
			(layer "F.SilkS")
		)
		(fp_line
			(start 0.7874 -0.4064)
			(end 0.7874 0.4064)
			(stroke
				(width 0.1524)
				(type default)
			)
			(layer "F.SilkS")
		)
		(fp_line
			(start 0.7874 0.4064)
			(end -0.7874 0.4064)
			(stroke
				(width 0.1524)
				(type default)
			)
			(layer "F.SilkS")
		)
		(fp_line
			(start -0.67945 -0.305054)
			(end -0.12065 -0.305054)
			(stroke
				(width 0.1)
				(type default)
			)
			(layer "F.Fab")
		)
		(fp_line
			(start -0.67945 0.3048)
			(end -0.67945 -0.305054)
			(stroke
				(width 0.1)
				(type default)
			)
			(layer "F.Fab")
		)
		(fp_line
			(start -0.12065 -0.305054)
			(end -0.12065 -0.2794)
			(stroke
				(width 0.1)
				(type default)
			)
			(layer "F.Fab")
		)
		(fp_line
			(start -0.12065 -0.2794)
			(end 0.12065 -0.2794)
			(stroke
				(width 0.1)
				(type default)
			)
			(layer "F.Fab")
		)
		(fp_line
			(start -0.12065 0.2794)
			(end -0.12065 0.3048)
			(stroke
				(width 0.1)
				(type default)
			)
			(layer "F.Fab")
		)
		(fp_line
			(start -0.12065 0.3048)
			(end -0.67945 0.3048)
			(stroke
				(width 0.1)
				(type default)
			)
			(layer "F.Fab")
		)
		(fp_line
			(start 0.120396 0.2794)
			(end -0.12065 0.2794)
			(stroke
				(width 0.1)
				(type default)
			)
			(layer "F.Fab")
		)
		(fp_line
			(start 0.120396 0.3048)
			(end 0.120396 0.2794)
			(stroke
				(width 0.1)
				(type default)
			)
			(layer "F.Fab")
		)
		(fp_line
			(start 0.12065 -0.3048)
			(end 0.67945 -0.3048)
			(stroke
				(width 0.1)
				(type default)
			)
			(layer "F.Fab")
		)
		(fp_line
			(start 0.12065 -0.2794)
			(end 0.12065 -0.3048)
			(stroke
				(width 0.1)
				(type default)
			)
			(layer "F.Fab")
		)
		(fp_line
			(start 0.67945 -0.3048)
			(end 0.67945 0.3048)
			(stroke
				(width 0.1)
				(type default)
			)
			(layer "F.Fab")
		)
		(fp_line
			(start 0.67945 0.3048)
			(end 0.120396 0.3048)
			(stroke
				(width 0.1)
				(type default)
			)
			(layer "F.Fab")
		)
		(pad "1" smd circle
			(at -0.40005 0)
			(size 0 0)
			(layers "F.Cu" "F.Mask" "F.Paste")
			(net "P3V3_AUX")
		)
		(pad "2" smd circle
			(at 0.40005 0)
			(size 0 0)
			(layers "F.Cu" "F.Mask" "F.Paste")
			(net "FM_SWB_PWRGD")
		)
	)
	(footprint ""
		(layer "F.Cu")
		(at 178.13782 -353.36353 -90)
		(property "Reference" "PC1244_P1_3"
			(at 0 0 270)
			(layer "F.SilkS")
			(hide yes)
			(effects
				(font
					(size 1.27 1.27)
				)
			)
		)
		(property "Value" ""
			(at 0 0 270)
			(layer "F.Fab")
			(effects
				(font
					(size 1.27 1.27)
				)
			)
		)
		(duplicate_pad_numbers_are_jumpers no)
		(fp_line
			(start -0.7874 0.4064)
			(end -0.7874 -0.4064)
			(stroke
				(width 0.1524)
				(type default)
			)
			(layer "F.SilkS")
		)
		(fp_line
			(start 0.7874 0.4064)
			(end -0.7874 0.4064)
			(stroke
				(width 0.1524)
				(type default)
			)
			(layer "F.SilkS")
		)
		(fp_line
			(start -0.7874 -0.4064)
			(end 0.7874 -0.4064)
			(stroke
				(width 0.1524)
				(type default)
			)
			(layer "F.SilkS")
		)
		(fp_line
			(start 0.7874 -0.4064)
			(end 0.7874 0.4064)
			(stroke
				(width 0.1524)
				(type default)
			)
			(layer "F.SilkS")
		)
		(fp_line
			(start -0.67945 0.3048)
			(end -0.67945 -0.305054)
			(stroke
				(width 0.1)
				(type default)
			)
			(layer "F.Fab")
		)
		(fp_line
			(start -0.12065 0.3048)
			(end -0.67945 0.3048)
			(stroke
				(width 0.1)
				(type default)
			)
			(layer "F.Fab")
		)
		(fp_line
			(start 0.120396 0.3048)
			(end 0.120396 0.2794)
			(stroke
				(width 0.1)
				(type default)
			)
			(layer "F.Fab")
		)
		(fp_line
			(start 0.67945 0.3048)
			(end 0.120396 0.3048)
			(stroke
				(width 0.1)
				(type default)
			)
			(layer "F.Fab")
		)
		(fp_line
			(start -0.12065 0.2794)
			(end -0.12065 0.3048)
			(stroke
				(width 0.1)
				(type default)
			)
			(layer "F.Fab")
		)
		(fp_line
			(start 0.120396 0.2794)
			(end -0.12065 0.2794)
			(stroke
				(width 0.1)
				(type default)
			)
			(layer "F.Fab")
		)
		(fp_line
			(start -0.12065 -0.2794)
			(end 0.12065 -0.2794)
			(stroke
				(width 0.1)
				(type default)
			)
			(layer "F.Fab")
		)
		(fp_line
			(start 0.12065 -0.2794)
			(end 0.12065 -0.3048)
			(stroke
				(width 0.1)
				(type default)
			)
			(layer "F.Fab")
		)
		(fp_line
			(start 0.12065 -0.3048)
			(end 0.67945 -0.3048)
			(stroke
				(width 0.1)
				(type default)
			)
			(layer "F.Fab")
		)
		(fp_line
			(start 0.67945 -0.3048)
			(end 0.67945 0.3048)
			(stroke
				(width 0.1)
				(type default)
			)
			(layer "F.Fab")
		)
		(fp_line
			(start -0.67945 -0.305054)
			(end -0.12065 -0.305054)
			(stroke
				(width 0.1)
				(type default)
			)
			(layer "F.Fab")
		)
		(fp_line
			(start -0.12065 -0.305054)
			(end -0.12065 -0.2794)
			(stroke
				(width 0.1)
				(type default)
			)
			(layer "F.Fab")
		)
		(pad "1" smd circle
			(at -0.40005 0 270)
			(size 0 0)
			(layers "F.Cu" "F.Mask" "F.Paste")
			(net "PVCCFA_EHV_FIVRA_CPU1_PVCC1")
		)
		(pad "2" smd circle
			(at 0.40005 0 270)
			(size 0 0)
			(layers "F.Cu" "F.Mask" "F.Paste")
			(net "GND")
		)
	)
	(footprint ""
		(layer "F.Cu")
		(at 201.00036 -111.724948 180)
		(property "Reference" "R4148"
			(at 0 0 180)
			(layer "F.SilkS")
			(hide yes)
			(effects
				(font
					(size 1.27 1.27)
				)
			)
		)
		(property "Value" ""
			(at 0 0 180)
			(layer "F.Fab")
			(effects
				(font
					(size 1.27 1.27)
				)
			)
		)
		(duplicate_pad_numbers_are_jumpers no)
		(fp_line
			(start 0.7874 0.4064)
			(end -0.7874 0.4064)
			(stroke
				(width 0.1524)
				(type default)
			)
			(layer "F.SilkS")
		)
		(fp_line
			(start 0.7874 -0.4064)
			(end 0.7874 0.4064)
			(stroke
				(width 0.1524)
				(type default)
			)
			(layer "F.SilkS")
		)
		(fp_line
			(start -0.7874 0.4064)
			(end -0.7874 -0.4064)
			(stroke
				(width 0.1524)
				(type default)
			)
			(layer "F.SilkS")
		)
		(fp_line
			(start -0.7874 -0.4064)
			(end 0.7874 -0.4064)
			(stroke
				(width 0.1524)
				(type default)
			)
			(layer "F.SilkS")
		)
		(fp_line
			(start 0.67945 0.3048)
			(end 0.120396 0.3048)
			(stroke
				(width 0.1)
				(type default)
			)
			(layer "F.Fab")
		)
		(fp_line
			(start 0.67945 -0.3048)
			(end 0.67945 0.3048)
			(stroke
				(width 0.1)
				(type default)
			)
			(layer "F.Fab")
		)
		(fp_line
			(start 0.12065 -0.2794)
			(end 0.12065 -0.3048)
			(stroke
				(width 0.1)
				(type default)
			)
			(layer "F.Fab")
		)
		(fp_line
			(start 0.12065 -0.3048)
			(end 0.67945 -0.3048)
			(stroke
				(width 0.1)
				(type default)
			)
			(layer "F.Fab")
		)
		(fp_line
			(start 0.120396 0.3048)
			(end 0.120396 0.2794)
			(stroke
				(width 0.1)
				(type default)
			)
			(layer "F.Fab")
		)
		(fp_line
			(start 0.120396 0.2794)
			(end -0.12065 0.2794)
			(stroke
				(width 0.1)
				(type default)
			)
			(layer "F.Fab")
		)
		(fp_line
			(start -0.12065 0.3048)
			(end -0.67945 0.3048)
			(stroke
				(width 0.1)
				(type default)
			)
			(layer "F.Fab")
		)
		(fp_line
			(start -0.12065 0.2794)
			(end -0.12065 0.3048)
			(stroke
				(width 0.1)
				(type default)
			)
			(layer "F.Fab")
		)
		(fp_line
			(start -0.12065 -0.2794)
			(end 0.12065 -0.2794)
			(stroke
				(width 0.1)
				(type default)
			)
			(layer "F.Fab")
		)
		(fp_line
			(start -0.12065 -0.305054)
			(end -0.12065 -0.2794)
			(stroke
				(width 0.1)
				(type default)
			)
			(layer "F.Fab")
		)
		(fp_line
			(start -0.67945 0.3048)
			(end -0.67945 -0.305054)
			(stroke
				(width 0.1)
				(type default)
			)
			(layer "F.Fab")
		)
		(fp_line
			(start -0.67945 -0.305054)
			(end -0.12065 -0.305054)
			(stroke
				(width 0.1)
				(type default)
			)
			(layer "F.Fab")
		)
		(pad "1" smd circle
			(at -0.40005 0 180)
			(size 0 0)
			(layers "F.Cu" "F.Mask" "F.Paste")
			(net "GPU_3V3IO_RSVD5_FFU_ISO")
		)
		(pad "2" smd circle
			(at 0.40005 0 180)
			(size 0 0)
			(layers "F.Cu" "F.Mask" "F.Paste")
			(net "GPU_3V3IO_RSVD5_FFU_ISO_R")
		)
	)
	(footprint ""
		(layer "F.Cu")
		(at 28.190698 -137.97661 90)
		(property "Reference" "PR4246"
			(at 0 0 90)
			(layer "F.SilkS")
			(hide yes)
			(effects
				(font
					(size 1.27 1.27)
				)
			)
		)
		(property "Value" ""
			(at 0 0 90)
			(layer "F.Fab")
			(effects
				(font
					(size 1.27 1.27)
				)
			)
		)
		(duplicate_pad_numbers_are_jumpers no)
		(fp_line
			(start 0.7874 -0.4064)
			(end 0.7874 0.4064)
			(stroke
				(width 0.1524)
				(type default)
			)
			(layer "F.SilkS")
		)
		(fp_line
			(start -0.7874 -0.4064)
			(end 0.7874 -0.4064)
			(stroke
				(width 0.1524)
				(type default)
			)
			(layer "F.SilkS")
		)
		(fp_line
			(start 0.7874 0.4064)
			(end -0.7874 0.4064)
			(stroke
				(width 0.1524)
				(type default)
			)
			(layer "F.SilkS")
		)
		(fp_line
			(start -0.7874 0.4064)
			(end -0.7874 -0.4064)
			(stroke
				(width 0.1524)
				(type default)
			)
			(layer "F.SilkS")
		)
		(fp_line
			(start -0.12065 -0.305054)
			(end -0.12065 -0.2794)
			(stroke
				(width 0.1)
				(type default)
			)
			(layer "F.Fab")
		)
		(fp_line
			(start -0.67945 -0.305054)
			(end -0.12065 -0.305054)
			(stroke
				(width 0.1)
				(type default)
			)
			(layer "F.Fab")
		)
		(fp_line
			(start 0.67945 -0.3048)
			(end 0.67945 0.3048)
			(stroke
				(width 0.1)
				(type default)
			)
			(layer "F.Fab")
		)
		(fp_line
			(start 0.12065 -0.3048)
			(end 0.67945 -0.3048)
			(stroke
				(width 0.1)
				(type default)
			)
			(layer "F.Fab")
		)
		(fp_line
			(start 0.12065 -0.2794)
			(end 0.12065 -0.3048)
			(stroke
				(width 0.1)
				(type default)
			)
			(layer "F.Fab")
		)
		(fp_line
			(start -0.12065 -0.2794)
			(end 0.12065 -0.2794)
			(stroke
				(width 0.1)
				(type default)
			)
			(layer "F.Fab")
		)
		(fp_line
			(start 0.120396 0.2794)
			(end -0.12065 0.2794)
			(stroke
				(width 0.1)
				(type default)
			)
			(layer "F.Fab")
		)
		(fp_line
			(start -0.12065 0.2794)
			(end -0.12065 0.3048)
			(stroke
				(width 0.1)
				(type default)
			)
			(layer "F.Fab")
		)
		(fp_line
			(start 0.67945 0.3048)
			(end 0.120396 0.3048)
			(stroke
				(width 0.1)
				(type default)
			)
			(layer "F.Fab")
		)
		(fp_line
			(start 0.120396 0.3048)
			(end 0.120396 0.2794)
			(stroke
				(width 0.1)
				(type default)
			)
			(layer "F.Fab")
		)
		(fp_line
			(start -0.12065 0.3048)
			(end -0.67945 0.3048)
			(stroke
				(width 0.1)
				(type default)
			)
			(layer "F.Fab")
		)
		(fp_line
			(start -0.67945 0.3048)
			(end -0.67945 -0.305054)
			(stroke
				(width 0.1)
				(type default)
			)
			(layer "F.Fab")
		)
		(pad "1" smd circle
			(at -0.40005 0 90)
			(size 0 0)
			(layers "F.Cu" "F.Mask" "F.Paste")
			(net "NC_PVCCINFAON_CPU1_ACSP7")
		)
		(pad "2" smd circle
			(at 0.40005 0 90)
			(size 0 0)
			(layers "F.Cu" "F.Mask" "F.Paste")
			(net "GND")
		)
	)
	(footprint ""
		(layer "F.Cu")
		(at 170.23588 -440.019948)
		(property "Reference" "R3454"
			(at 0 0 0)
			(layer "F.SilkS")
			(hide yes)
			(effects
				(font
					(size 1.27 1.27)
				)
			)
		)
		(property "Value" ""
			(at 0 0 0)
			(layer "F.Fab")
			(effects
				(font
					(size 1.27 1.27)
				)
			)
		)
		(duplicate_pad_numbers_are_jumpers no)
		(fp_line
			(start -0.7874 -0.4064)
			(end 0.7874 -0.4064)
			(stroke
				(width 0.1524)
				(type default)
			)
			(layer "F.SilkS")
		)
		(fp_line
			(start -0.7874 0.4064)
			(end -0.7874 -0.4064)
			(stroke
				(width 0.1524)
				(type default)
			)
			(layer "F.SilkS")
		)
		(fp_line
			(start 0.7874 -0.4064)
			(end 0.7874 0.4064)
			(stroke
				(width 0.1524)
				(type default)
			)
			(layer "F.SilkS")
		)
		(fp_line
			(start 0.7874 0.4064)
			(end -0.7874 0.4064)
			(stroke
				(width 0.1524)
				(type default)
			)
			(layer "F.SilkS")
		)
		(fp_line
			(start -0.67945 -0.305054)
			(end -0.12065 -0.305054)
			(stroke
				(width 0.1)
				(type default)
			)
			(layer "F.Fab")
		)
		(fp_line
			(start -0.67945 0.3048)
			(end -0.67945 -0.305054)
			(stroke
				(width 0.1)
				(type default)
			)
			(layer "F.Fab")
		)
		(fp_line
			(start -0.12065 -0.305054)
			(end -0.12065 -0.2794)
			(stroke
				(width 0.1)
				(type default)
			)
			(layer "F.Fab")
		)
		(fp_line
			(start -0.12065 -0.2794)
			(end 0.12065 -0.2794)
			(stroke
				(width 0.1)
				(type default)
			)
			(layer "F.Fab")
		)
		(fp_line
			(start -0.12065 0.2794)
			(end -0.12065 0.3048)
			(stroke
				(width 0.1)
				(type default)
			)
			(layer "F.Fab")
		)
		(fp_line
			(start -0.12065 0.3048)
			(end -0.67945 0.3048)
			(stroke
				(width 0.1)
				(type default)
			)
			(layer "F.Fab")
		)
		(fp_line
			(start 0.120396 0.2794)
			(end -0.12065 0.2794)
			(stroke
				(width 0.1)
				(type default)
			)
			(layer "F.Fab")
		)
		(fp_line
			(start 0.120396 0.3048)
			(end 0.120396 0.2794)
			(stroke
				(width 0.1)
				(type default)
			)
			(layer "F.Fab")
		)
		(fp_line
			(start 0.12065 -0.3048)
			(end 0.67945 -0.3048)
			(stroke
				(width 0.1)
				(type default)
			)
			(layer "F.Fab")
		)
		(fp_line
			(start 0.12065 -0.2794)
			(end 0.12065 -0.3048)
			(stroke
				(width 0.1)
				(type default)
			)
			(layer "F.Fab")
		)
		(fp_line
			(start 0.67945 -0.3048)
			(end 0.67945 0.3048)
			(stroke
				(width 0.1)
				(type default)
			)
			(layer "F.Fab")
		)
		(fp_line
			(start 0.67945 0.3048)
			(end 0.120396 0.3048)
			(stroke
				(width 0.1)
				(type default)
			)
			(layer "F.Fab")
		)
		(pad "1" smd circle
			(at -0.40005 0)
			(size 0 0)
			(layers "F.Cu" "F.Mask" "F.Paste")
			(net "GPU_FPGA_BOOT_EN_BUF_R")
		)
		(pad "2" smd circle
			(at 0.40005 0)
			(size 0 0)
			(layers "F.Cu" "F.Mask" "F.Paste")
			(net "GND")
		)
	)
	(footprint ""
		(layer "F.Cu")
		(at 92.40647 -337.214718 -90)
		(property "Reference" "PC507_P1_6"
			(at 0 0 270)
			(layer "F.SilkS")
			(hide yes)
			(effects
				(font
					(size 1.27 1.27)
				)
			)
		)
		(property "Value" ""
			(at 0 0 270)
			(layer "F.Fab")
			(effects
				(font
					(size 1.27 1.27)
				)
			)
		)
		(duplicate_pad_numbers_are_jumpers no)
		(fp_line
			(start -0.7874 0.4064)
			(end -0.7874 -0.4064)
			(stroke
				(width 0.1524)
				(type default)
			)
			(layer "F.SilkS")
		)
		(fp_line
			(start 0.7874 0.4064)
			(end -0.7874 0.4064)
			(stroke
				(width 0.1524)
				(type default)
			)
			(layer "F.SilkS")
		)
		(fp_line
			(start -0.7874 -0.4064)
			(end 0.7874 -0.4064)
			(stroke
				(width 0.1524)
				(type default)
			)
			(layer "F.SilkS")
		)
		(fp_line
			(start 0.7874 -0.4064)
			(end 0.7874 0.4064)
			(stroke
				(width 0.1524)
				(type default)
			)
			(layer "F.SilkS")
		)
		(fp_line
			(start -0.67945 0.3048)
			(end -0.67945 -0.305054)
			(stroke
				(width 0.1)
				(type default)
			)
			(layer "F.Fab")
		)
		(fp_line
			(start -0.12065 0.3048)
			(end -0.67945 0.3048)
			(stroke
				(width 0.1)
				(type default)
			)
			(layer "F.Fab")
		)
		(fp_line
			(start 0.120396 0.3048)
			(end 0.120396 0.2794)
			(stroke
				(width 0.1)
				(type default)
			)
			(layer "F.Fab")
		)
		(fp_line
			(start 0.67945 0.3048)
			(end 0.120396 0.3048)
			(stroke
				(width 0.1)
				(type default)
			)
			(layer "F.Fab")
		)
		(fp_line
			(start -0.12065 0.2794)
			(end -0.12065 0.3048)
			(stroke
				(width 0.1)
				(type default)
			)
			(layer "F.Fab")
		)
		(fp_line
			(start 0.120396 0.2794)
			(end -0.12065 0.2794)
			(stroke
				(width 0.1)
				(type default)
			)
			(layer "F.Fab")
		)
		(fp_line
			(start -0.12065 -0.2794)
			(end 0.12065 -0.2794)
			(stroke
				(width 0.1)
				(type default)
			)
			(layer "F.Fab")
		)
		(fp_line
			(start 0.12065 -0.2794)
			(end 0.12065 -0.3048)
			(stroke
				(width 0.1)
				(type default)
			)
			(layer "F.Fab")
		)
		(fp_line
			(start 0.12065 -0.3048)
			(end 0.67945 -0.3048)
			(stroke
				(width 0.1)
				(type default)
			)
			(layer "F.Fab")
		)
		(fp_line
			(start 0.67945 -0.3048)
			(end 0.67945 0.3048)
			(stroke
				(width 0.1)
				(type default)
			)
			(layer "F.Fab")
		)
		(fp_line
			(start -0.67945 -0.305054)
			(end -0.12065 -0.305054)
			(stroke
				(width 0.1)
				(type default)
			)
			(layer "F.Fab")
		)
		(fp_line
			(start -0.12065 -0.305054)
			(end -0.12065 -0.2794)
			(stroke
				(width 0.1)
				(type default)
			)
			(layer "F.Fab")
		)
		(pad "1" smd circle
			(at -0.40005 0 270)
			(size 0 0)
			(layers "F.Cu" "F.Mask" "F.Paste")
			(net "SW_P12V_PVCCIN_CPU1_FLT")
		)
		(pad "2" smd circle
			(at 0.40005 0 270)
			(size 0 0)
			(layers "F.Cu" "F.Mask" "F.Paste")
			(net "GND")
		)
	)
	(footprint ""
		(layer "F.Cu")
		(at 118.542816 -244.032024 90)
		(property "Reference" "C224"
			(at 0 0 90)
			(layer "F.SilkS")
			(hide yes)
			(effects
				(font
					(size 1.27 1.27)
				)
			)
		)
		(property "Value" ""
			(at 0 0 90)
			(layer "F.Fab")
			(effects
				(font
					(size 1.27 1.27)
				)
			)
		)
		(duplicate_pad_numbers_are_jumpers no)
		(fp_line
			(start 0.7874 -0.4064)
			(end 0.7874 0.4064)
			(stroke
				(width 0.1524)
				(type default)
			)
			(layer "F.SilkS")
		)
		(fp_line
			(start -0.7874 -0.4064)
			(end 0.7874 -0.4064)
			(stroke
				(width 0.1524)
				(type default)
			)
			(layer "F.SilkS")
		)
		(fp_line
			(start 0.7874 0.4064)
			(end -0.7874 0.4064)
			(stroke
				(width 0.1524)
				(type default)
			)
			(layer "F.SilkS")
		)
		(fp_line
			(start -0.7874 0.4064)
			(end -0.7874 -0.4064)
			(stroke
				(width 0.1524)
				(type default)
			)
			(layer "F.SilkS")
		)
		(fp_line
			(start -0.12065 -0.305054)
			(end -0.12065 -0.2794)
			(stroke
				(width 0.1)
				(type default)
			)
			(layer "F.Fab")
		)
		(fp_line
			(start -0.67945 -0.305054)
			(end -0.12065 -0.305054)
			(stroke
				(width 0.1)
				(type default)
			)
			(layer "F.Fab")
		)
		(fp_line
			(start 0.67945 -0.3048)
			(end 0.67945 0.3048)
			(stroke
				(width 0.1)
				(type default)
			)
			(layer "F.Fab")
		)
		(fp_line
			(start 0.12065 -0.3048)
			(end 0.67945 -0.3048)
			(stroke
				(width 0.1)
				(type default)
			)
			(layer "F.Fab")
		)
		(fp_line
			(start 0.12065 -0.2794)
			(end 0.12065 -0.3048)
			(stroke
				(width 0.1)
				(type default)
			)
			(layer "F.Fab")
		)
		(fp_line
			(start -0.12065 -0.2794)
			(end 0.12065 -0.2794)
			(stroke
				(width 0.1)
				(type default)
			)
			(layer "F.Fab")
		)
		(fp_line
			(start 0.120396 0.2794)
			(end -0.12065 0.2794)
			(stroke
				(width 0.1)
				(type default)
			)
			(layer "F.Fab")
		)
		(fp_line
			(start -0.12065 0.2794)
			(end -0.12065 0.3048)
			(stroke
				(width 0.1)
				(type default)
			)
			(layer "F.Fab")
		)
		(fp_line
			(start 0.67945 0.3048)
			(end 0.120396 0.3048)
			(stroke
				(width 0.1)
				(type default)
			)
			(layer "F.Fab")
		)
		(fp_line
			(start 0.120396 0.3048)
			(end 0.120396 0.2794)
			(stroke
				(width 0.1)
				(type default)
			)
			(layer "F.Fab")
		)
		(fp_line
			(start -0.12065 0.3048)
			(end -0.67945 0.3048)
			(stroke
				(width 0.1)
				(type default)
			)
			(layer "F.Fab")
		)
		(fp_line
			(start -0.67945 0.3048)
			(end -0.67945 -0.305054)
			(stroke
				(width 0.1)
				(type default)
			)
			(layer "F.Fab")
		)
		(pad "1" smd circle
			(at -0.40005 0 90)
			(size 0 0)
			(layers "F.Cu" "F.Mask" "F.Paste")
			(net "PVCCIN_CPU1")
		)
		(pad "2" smd circle
			(at 0.40005 0 90)
			(size 0 0)
			(layers "F.Cu" "F.Mask" "F.Paste")
			(net "GND")
		)
	)
	(footprint ""
		(layer "F.Cu")
		(at 112.492282 -406.439116 180)
		(property "Reference" "C1979"
			(at 0 0 180)
			(layer "F.SilkS")
			(hide yes)
			(effects
				(font
					(size 1.27 1.27)
				)
			)
		)
		(property "Value" ""
			(at 0 0 180)
			(layer "F.Fab")
			(effects
				(font
					(size 1.27 1.27)
				)
			)
		)
		(duplicate_pad_numbers_are_jumpers no)
		(fp_line
			(start 0.7874 0.4064)
			(end -0.7874 0.4064)
			(stroke
				(width 0.1524)
				(type default)
			)
			(layer "F.SilkS")
		)
		(fp_line
			(start 0.7874 -0.4064)
			(end 0.7874 0.4064)
			(stroke
				(width 0.1524)
				(type default)
			)
			(layer "F.SilkS")
		)
		(fp_line
			(start -0.7874 0.4064)
			(end -0.7874 -0.4064)
			(stroke
				(width 0.1524)
				(type default)
			)
			(layer "F.SilkS")
		)
		(fp_line
			(start -0.7874 -0.4064)
			(end 0.7874 -0.4064)
			(stroke
				(width 0.1524)
				(type default)
			)
			(layer "F.SilkS")
		)
		(fp_line
			(start 0.67945 0.3048)
			(end 0.120396 0.3048)
			(stroke
				(width 0.1)
				(type default)
			)
			(layer "F.Fab")
		)
		(fp_line
			(start 0.67945 -0.3048)
			(end 0.67945 0.3048)
			(stroke
				(width 0.1)
				(type default)
			)
			(layer "F.Fab")
		)
		(fp_line
			(start 0.12065 -0.2794)
			(end 0.12065 -0.3048)
			(stroke
				(width 0.1)
				(type default)
			)
			(layer "F.Fab")
		)
		(fp_line
			(start 0.12065 -0.3048)
			(end 0.67945 -0.3048)
			(stroke
				(width 0.1)
				(type default)
			)
			(layer "F.Fab")
		)
		(fp_line
			(start 0.120396 0.3048)
			(end 0.120396 0.2794)
			(stroke
				(width 0.1)
				(type default)
			)
			(layer "F.Fab")
		)
		(fp_line
			(start 0.120396 0.2794)
			(end -0.12065 0.2794)
			(stroke
				(width 0.1)
				(type default)
			)
			(layer "F.Fab")
		)
		(fp_line
			(start -0.12065 0.3048)
			(end -0.67945 0.3048)
			(stroke
				(width 0.1)
				(type default)
			)
			(layer "F.Fab")
		)
		(fp_line
			(start -0.12065 0.2794)
			(end -0.12065 0.3048)
			(stroke
				(width 0.1)
				(type default)
			)
			(layer "F.Fab")
		)
		(fp_line
			(start -0.12065 -0.2794)
			(end 0.12065 -0.2794)
			(stroke
				(width 0.1)
				(type default)
			)
			(layer "F.Fab")
		)
		(fp_line
			(start -0.12065 -0.305054)
			(end -0.12065 -0.2794)
			(stroke
				(width 0.1)
				(type default)
			)
			(layer "F.Fab")
		)
		(fp_line
			(start -0.67945 0.3048)
			(end -0.67945 -0.305054)
			(stroke
				(width 0.1)
				(type default)
			)
			(layer "F.Fab")
		)
		(fp_line
			(start -0.67945 -0.305054)
			(end -0.12065 -0.305054)
			(stroke
				(width 0.1)
				(type default)
			)
			(layer "F.Fab")
		)
		(pad "1" smd circle
			(at -0.40005 0 180)
			(size 0 0)
			(layers "F.Cu" "F.Mask" "F.Paste")
			(net "P3V3_AUX")
		)
		(pad "2" smd circle
			(at 0.40005 0 180)
			(size 0 0)
			(layers "F.Cu" "F.Mask" "F.Paste")
			(net "GND")
		)
	)
	(footprint ""
		(layer "F.Cu")
		(at 325.95312 -347.541342 -90)
		(property "Reference" "PC1345"
			(at 0 0 270)
			(layer "F.SilkS")
			(hide yes)
			(effects
				(font
					(size 1.27 1.27)
				)
			)
		)
		(property "Value" ""
			(at 0 0 270)
			(layer "F.Fab")
			(effects
				(font
					(size 1.27 1.27)
				)
			)
		)
		(duplicate_pad_numbers_are_jumpers no)
		(fp_line
			(start -0.7874 0.4064)
			(end -0.7874 -0.4064)
			(stroke
				(width 0.1524)
				(type default)
			)
			(layer "F.SilkS")
		)
		(fp_line
			(start 0.7874 0.4064)
			(end -0.7874 0.4064)
			(stroke
				(width 0.1524)
				(type default)
			)
			(layer "F.SilkS")
		)
		(fp_line
			(start -0.7874 -0.4064)
			(end 0.7874 -0.4064)
			(stroke
				(width 0.1524)
				(type default)
			)
			(layer "F.SilkS")
		)
		(fp_line
			(start 0.7874 -0.4064)
			(end 0.7874 0.4064)
			(stroke
				(width 0.1524)
				(type default)
			)
			(layer "F.SilkS")
		)
		(fp_line
			(start -0.67945 0.3048)
			(end -0.67945 -0.305054)
			(stroke
				(width 0.1)
				(type default)
			)
			(layer "F.Fab")
		)
		(fp_line
			(start -0.12065 0.3048)
			(end -0.67945 0.3048)
			(stroke
				(width 0.1)
				(type default)
			)
			(layer "F.Fab")
		)
		(fp_line
			(start 0.120396 0.3048)
			(end 0.120396 0.2794)
			(stroke
				(width 0.1)
				(type default)
			)
			(layer "F.Fab")
		)
		(fp_line
			(start 0.67945 0.3048)
			(end 0.120396 0.3048)
			(stroke
				(width 0.1)
				(type default)
			)
			(layer "F.Fab")
		)
		(fp_line
			(start -0.12065 0.2794)
			(end -0.12065 0.3048)
			(stroke
				(width 0.1)
				(type default)
			)
			(layer "F.Fab")
		)
		(fp_line
			(start 0.120396 0.2794)
			(end -0.12065 0.2794)
			(stroke
				(width 0.1)
				(type default)
			)
			(layer "F.Fab")
		)
		(fp_line
			(start -0.12065 -0.2794)
			(end 0.12065 -0.2794)
			(stroke
				(width 0.1)
				(type default)
			)
			(layer "F.Fab")
		)
		(fp_line
			(start 0.12065 -0.2794)
			(end 0.12065 -0.3048)
			(stroke
				(width 0.1)
				(type default)
			)
			(layer "F.Fab")
		)
		(fp_line
			(start 0.12065 -0.3048)
			(end 0.67945 -0.3048)
			(stroke
				(width 0.1)
				(type default)
			)
			(layer "F.Fab")
		)
		(fp_line
			(start 0.67945 -0.3048)
			(end 0.67945 0.3048)
			(stroke
				(width 0.1)
				(type default)
			)
			(layer "F.Fab")
		)
		(fp_line
			(start -0.67945 -0.305054)
			(end -0.12065 -0.305054)
			(stroke
				(width 0.1)
				(type default)
			)
			(layer "F.Fab")
		)
		(fp_line
			(start -0.12065 -0.305054)
			(end -0.12065 -0.2794)
			(stroke
				(width 0.1)
				(type default)
			)
			(layer "F.Fab")
		)
		(pad "1" smd circle
			(at -0.40005 0 270)
			(size 0 0)
			(layers "F.Cu" "F.Mask" "F.Paste")
			(net "GND")
		)
		(pad "2" smd circle
			(at 0.40005 0 270)
			(size 0 0)
			(layers "F.Cu" "F.Mask" "F.Paste")
			(net "PVCCIN_CPU0_VREF")
		)
	)
	(footprint ""
		(layer "F.Cu")
		(at 394.18641 -408.517344 -90)
		(property "Reference" "C884"
			(at 0 0 270)
			(layer "F.SilkS")
			(hide yes)
			(effects
				(font
					(size 1.27 1.27)
				)
			)
		)
		(property "Value" ""
			(at 0 0 270)
			(layer "F.Fab")
			(effects
				(font
					(size 1.27 1.27)
				)
			)
		)
		(duplicate_pad_numbers_are_jumpers no)
		(fp_line
			(start -0.299974 0.150114)
			(end -0.299974 -0.150114)
			(stroke
				(width 0.1)
				(type default)
			)
			(layer "F.Fab")
		)
		(fp_line
			(start 0.299974 0.150114)
			(end -0.299974 0.150114)
			(stroke
				(width 0.1)
				(type default)
			)
			(layer "F.Fab")
		)
		(fp_line
			(start -0.299974 -0.150114)
			(end 0.299974 -0.150114)
			(stroke
				(width 0.1)
				(type default)
			)
			(layer "F.Fab")
		)
		(fp_line
			(start 0.299974 -0.150114)
			(end 0.299974 0.150114)
			(stroke
				(width 0.1)
				(type default)
			)
			(layer "F.Fab")
		)
		(pad "1" smd rect
			(at -0.2667 0 270)
			(size 0.3048 0.381)
			(layers "F.Cu" "F.Mask" "F.Paste")
			(net "P5E_CPU0_PE3_TX_C_DN<8>")
		)
		(pad "2" smd rect
			(at 0.2667 0 270)
			(size 0.3048 0.381)
			(layers "F.Cu" "F.Mask" "F.Paste")
			(net "P5E_CPU0_PE3_TX_DN<8>")
		)
	)
	(footprint ""
		(layer "F.Cu")
		(at 381.750824 -368.140742)
		(property "Reference" "PC1258"
			(at 0 0 0)
			(layer "F.SilkS")
			(hide yes)
			(effects
				(font
					(size 1.27 1.27)
				)
			)
		)
		(property "Value" ""
			(at 0 0 0)
			(layer "F.Fab")
			(effects
				(font
					(size 1.27 1.27)
				)
			)
		)
		(duplicate_pad_numbers_are_jumpers no)
		(fp_line
			(start -3.400044 1.249934)
			(end 3.400044 1.249934)
			(stroke
				(width 0.1524)
				(type default)
			)
			(layer "F.SilkS")
		)
		(fp_circle
			(center 0 1.249934)
			(end 3.400044 1.249934)
			(stroke
				(width 0.1524)
				(type default)
			)
			(fill no)
			(layer "F.SilkS")
		)
		(fp_poly
			(pts
				(arc
					(start 3.400044 1.249934)
					(mid 0 4.649978)
					(end -3.400044 1.249934)
				)
			)
			(stroke
				(width 0)
				(type default)
			)
			(fill yes)
			(layer "F.SilkS")
		)
		(fp_circle
			(center 0 1.249934)
			(end 3.400044 1.249934)
			(stroke
				(width 0.1)
				(type default)
			)
			(fill no)
			(layer "F.Fab")
		)
		(pad "1" thru_hole rect
			(at 0 0)
			(size 1.524 1.524)
			(drill 1.016)
			(layers "*.Cu" "*.Mask")
			(remove_unused_layers no)
			(net "PVPP_HBM_CPU0")
			(clearance 0)
			(padstack
				(mode front_inner_back)
				(layer "Inner"
					(shape circle)
					(size 1.524 1.524)
					(clearance 0)
				)
				(layer "B.Cu"
					(shape rect)
					(size 1.524 1.524)
					(clearance 0)
				)
			)
		)
		(pad "2" thru_hole circle
			(at 0 2.500122)
			(size 1.524 1.524)
			(drill 1.016)
			(layers "*.Cu" "*.Mask")
			(remove_unused_layers no)
			(net "GND")
			(clearance 0)
		)
	)
	(footprint ""
		(layer "F.Cu")
		(at 406.124664 -367.576862 180)
		(property "Reference" "R333"
			(at 0 0 180)
			(layer "F.SilkS")
			(hide yes)
			(effects
				(font
					(size 1.27 1.27)
				)
			)
		)
		(property "Value" ""
			(at 0 0 180)
			(layer "F.Fab")
			(effects
				(font
					(size 1.27 1.27)
				)
			)
		)
		(duplicate_pad_numbers_are_jumpers no)
		(fp_line
			(start 0.7874 0.4064)
			(end -0.7874 0.4064)
			(stroke
				(width 0.1524)
				(type default)
			)
			(layer "F.SilkS")
		)
		(fp_line
			(start 0.7874 -0.4064)
			(end 0.7874 0.4064)
			(stroke
				(width 0.1524)
				(type default)
			)
			(layer "F.SilkS")
		)
		(fp_line
			(start -0.7874 0.4064)
			(end -0.7874 -0.4064)
			(stroke
				(width 0.1524)
				(type default)
			)
			(layer "F.SilkS")
		)
		(fp_line
			(start -0.7874 -0.4064)
			(end 0.7874 -0.4064)
			(stroke
				(width 0.1524)
				(type default)
			)
			(layer "F.SilkS")
		)
		(fp_line
			(start 0.67945 0.3048)
			(end 0.120396 0.3048)
			(stroke
				(width 0.1)
				(type default)
			)
			(layer "F.Fab")
		)
		(fp_line
			(start 0.67945 -0.3048)
			(end 0.67945 0.3048)
			(stroke
				(width 0.1)
				(type default)
			)
			(layer "F.Fab")
		)
		(fp_line
			(start 0.12065 -0.2794)
			(end 0.12065 -0.3048)
			(stroke
				(width 0.1)
				(type default)
			)
			(layer "F.Fab")
		)
		(fp_line
			(start 0.12065 -0.3048)
			(end 0.67945 -0.3048)
			(stroke
				(width 0.1)
				(type default)
			)
			(layer "F.Fab")
		)
		(fp_line
			(start 0.120396 0.3048)
			(end 0.120396 0.2794)
			(stroke
				(width 0.1)
				(type default)
			)
			(layer "F.Fab")
		)
		(fp_line
			(start 0.120396 0.2794)
			(end -0.12065 0.2794)
			(stroke
				(width 0.1)
				(type default)
			)
			(layer "F.Fab")
		)
		(fp_line
			(start -0.12065 0.3048)
			(end -0.67945 0.3048)
			(stroke
				(width 0.1)
				(type default)
			)
			(layer "F.Fab")
		)
		(fp_line
			(start -0.12065 0.2794)
			(end -0.12065 0.3048)
			(stroke
				(width 0.1)
				(type default)
			)
			(layer "F.Fab")
		)
		(fp_line
			(start -0.12065 -0.2794)
			(end 0.12065 -0.2794)
			(stroke
				(width 0.1)
				(type default)
			)
			(layer "F.Fab")
		)
		(fp_line
			(start -0.12065 -0.305054)
			(end -0.12065 -0.2794)
			(stroke
				(width 0.1)
				(type default)
			)
			(layer "F.Fab")
		)
		(fp_line
			(start -0.67945 0.3048)
			(end -0.67945 -0.305054)
			(stroke
				(width 0.1)
				(type default)
			)
			(layer "F.Fab")
		)
		(fp_line
			(start -0.67945 -0.305054)
			(end -0.12065 -0.305054)
			(stroke
				(width 0.1)
				(type default)
			)
			(layer "F.Fab")
		)
		(pad "1" smd circle
			(at -0.40005 0 180)
			(size 0 0)
			(layers "F.Cu" "F.Mask" "F.Paste")
			(net "P3V3_AUX")
		)
		(pad "2" smd circle
			(at 0.40005 0 180)
			(size 0 0)
			(layers "F.Cu" "F.Mask" "F.Paste")
			(net "PD_PIROM_CPU0_ADDR1")
		)
	)
	(footprint ""
		(layer "F.Cu")
		(at 43.350942 -358.38003 -90)
		(property "Reference" "PC1198"
			(at 0 0 270)
			(layer "F.SilkS")
			(hide yes)
			(effects
				(font
					(size 1.27 1.27)
				)
			)
		)
		(property "Value" ""
			(at 0 0 270)
			(layer "F.Fab")
			(effects
				(font
					(size 1.27 1.27)
				)
			)
		)
		(duplicate_pad_numbers_are_jumpers no)
		(fp_line
			(start -0.7874 0.4064)
			(end -0.7874 -0.4064)
			(stroke
				(width 0.1524)
				(type default)
			)
			(layer "F.SilkS")
		)
		(fp_line
			(start 0.7874 0.4064)
			(end -0.7874 0.4064)
			(stroke
				(width 0.1524)
				(type default)
			)
			(layer "F.SilkS")
		)
		(fp_line
			(start -0.7874 -0.4064)
			(end 0.7874 -0.4064)
			(stroke
				(width 0.1524)
				(type default)
			)
			(layer "F.SilkS")
		)
		(fp_line
			(start 0.7874 -0.4064)
			(end 0.7874 0.4064)
			(stroke
				(width 0.1524)
				(type default)
			)
			(layer "F.SilkS")
		)
		(fp_line
			(start -0.67945 0.3048)
			(end -0.67945 -0.305054)
			(stroke
				(width 0.1)
				(type default)
			)
			(layer "F.Fab")
		)
		(fp_line
			(start -0.12065 0.3048)
			(end -0.67945 0.3048)
			(stroke
				(width 0.1)
				(type default)
			)
			(layer "F.Fab")
		)
		(fp_line
			(start 0.120396 0.3048)
			(end 0.120396 0.2794)
			(stroke
				(width 0.1)
				(type default)
			)
			(layer "F.Fab")
		)
		(fp_line
			(start 0.67945 0.3048)
			(end 0.120396 0.3048)
			(stroke
				(width 0.1)
				(type default)
			)
			(layer "F.Fab")
		)
		(fp_line
			(start -0.12065 0.2794)
			(end -0.12065 0.3048)
			(stroke
				(width 0.1)
				(type default)
			)
			(layer "F.Fab")
		)
		(fp_line
			(start 0.120396 0.2794)
			(end -0.12065 0.2794)
			(stroke
				(width 0.1)
				(type default)
			)
			(layer "F.Fab")
		)
		(fp_line
			(start -0.12065 -0.2794)
			(end 0.12065 -0.2794)
			(stroke
				(width 0.1)
				(type default)
			)
			(layer "F.Fab")
		)
		(fp_line
			(start 0.12065 -0.2794)
			(end 0.12065 -0.3048)
			(stroke
				(width 0.1)
				(type default)
			)
			(layer "F.Fab")
		)
		(fp_line
			(start 0.12065 -0.3048)
			(end 0.67945 -0.3048)
			(stroke
				(width 0.1)
				(type default)
			)
			(layer "F.Fab")
		)
		(fp_line
			(start 0.67945 -0.3048)
			(end 0.67945 0.3048)
			(stroke
				(width 0.1)
				(type default)
			)
			(layer "F.Fab")
		)
		(fp_line
			(start -0.67945 -0.305054)
			(end -0.12065 -0.305054)
			(stroke
				(width 0.1)
				(type default)
			)
			(layer "F.Fab")
		)
		(fp_line
			(start -0.12065 -0.305054)
			(end -0.12065 -0.2794)
			(stroke
				(width 0.1)
				(type default)
			)
			(layer "F.Fab")
		)
		(pad "1" smd circle
			(at -0.40005 0 270)
			(size 0 0)
			(layers "F.Cu" "F.Mask" "F.Paste")
			(net "SW_PVCCFA_EHV_FIVRA_CPU1_BOOT4_")
		)
		(pad "2" smd circle
			(at 0.40005 0 270)
			(size 0 0)
			(layers "F.Cu" "F.Mask" "F.Paste")
			(net "SW_PVCCFA_EHV_FIVRA_CPU1_BOOTR4")
		)
	)
	(footprint ""
		(layer "F.Cu")
		(at 424.204892 -392.648948)
		(property "Reference" "R2832"
			(at 0 0 0)
			(layer "F.SilkS")
			(hide yes)
			(effects
				(font
					(size 1.27 1.27)
				)
			)
		)
		(property "Value" ""
			(at 0 0 0)
			(layer "F.Fab")
			(effects
				(font
					(size 1.27 1.27)
				)
			)
		)
		(duplicate_pad_numbers_are_jumpers no)
		(fp_line
			(start -0.7874 -0.4064)
			(end 0.7874 -0.4064)
			(stroke
				(width 0.1524)
				(type default)
			)
			(layer "F.SilkS")
		)
		(fp_line
			(start -0.7874 0.4064)
			(end -0.7874 -0.4064)
			(stroke
				(width 0.1524)
				(type default)
			)
			(layer "F.SilkS")
		)
		(fp_line
			(start 0.7874 -0.4064)
			(end 0.7874 0.4064)
			(stroke
				(width 0.1524)
				(type default)
			)
			(layer "F.SilkS")
		)
		(fp_line
			(start 0.7874 0.4064)
			(end -0.7874 0.4064)
			(stroke
				(width 0.1524)
				(type default)
			)
			(layer "F.SilkS")
		)
		(fp_line
			(start -0.67945 -0.305054)
			(end -0.12065 -0.305054)
			(stroke
				(width 0.1)
				(type default)
			)
			(layer "F.Fab")
		)
		(fp_line
			(start -0.67945 0.3048)
			(end -0.67945 -0.305054)
			(stroke
				(width 0.1)
				(type default)
			)
			(layer "F.Fab")
		)
		(fp_line
			(start -0.12065 -0.305054)
			(end -0.12065 -0.2794)
			(stroke
				(width 0.1)
				(type default)
			)
			(layer "F.Fab")
		)
		(fp_line
			(start -0.12065 -0.2794)
			(end 0.12065 -0.2794)
			(stroke
				(width 0.1)
				(type default)
			)
			(layer "F.Fab")
		)
		(fp_line
			(start -0.12065 0.2794)
			(end -0.12065 0.3048)
			(stroke
				(width 0.1)
				(type default)
			)
			(layer "F.Fab")
		)
		(fp_line
			(start -0.12065 0.3048)
			(end -0.67945 0.3048)
			(stroke
				(width 0.1)
				(type default)
			)
			(layer "F.Fab")
		)
		(fp_line
			(start 0.120396 0.2794)
			(end -0.12065 0.2794)
			(stroke
				(width 0.1)
				(type default)
			)
			(layer "F.Fab")
		)
		(fp_line
			(start 0.120396 0.3048)
			(end 0.120396 0.2794)
			(stroke
				(width 0.1)
				(type default)
			)
			(layer "F.Fab")
		)
		(fp_line
			(start 0.12065 -0.3048)
			(end 0.67945 -0.3048)
			(stroke
				(width 0.1)
				(type default)
			)
			(layer "F.Fab")
		)
		(fp_line
			(start 0.12065 -0.2794)
			(end 0.12065 -0.3048)
			(stroke
				(width 0.1)
				(type default)
			)
			(layer "F.Fab")
		)
		(fp_line
			(start 0.67945 -0.3048)
			(end 0.67945 0.3048)
			(stroke
				(width 0.1)
				(type default)
			)
			(layer "F.Fab")
		)
		(fp_line
			(start 0.67945 0.3048)
			(end 0.120396 0.3048)
			(stroke
				(width 0.1)
				(type default)
			)
			(layer "F.Fab")
		)
		(pad "1" smd circle
			(at -0.40005 0)
			(size 0 0)
			(layers "F.Cu" "F.Mask" "F.Paste")
			(net "P3V3_AUX")
		)
		(pad "2" smd circle
			(at 0.40005 0)
			(size 0 0)
			(layers "F.Cu" "F.Mask" "F.Paste")
			(net "FM_SWB_BIC_READY_N")
		)
	)
	(footprint ""
		(layer "F.Cu")
		(at 116.21008 -106.238548 -90)
		(property "Reference" "R4045"
			(at 0 0 270)
			(layer "F.SilkS")
			(hide yes)
			(effects
				(font
					(size 1.27 1.27)
				)
			)
		)
		(property "Value" ""
			(at 0 0 270)
			(layer "F.Fab")
			(effects
				(font
					(size 1.27 1.27)
				)
			)
		)
		(duplicate_pad_numbers_are_jumpers no)
		(fp_line
			(start -0.7874 0.4064)
			(end -0.7874 -0.4064)
			(stroke
				(width 0.1524)
				(type default)
			)
			(layer "F.SilkS")
		)
		(fp_line
			(start 0.7874 0.4064)
			(end -0.7874 0.4064)
			(stroke
				(width 0.1524)
				(type default)
			)
			(layer "F.SilkS")
		)
		(fp_line
			(start -0.7874 -0.4064)
			(end 0.7874 -0.4064)
			(stroke
				(width 0.1524)
				(type default)
			)
			(layer "F.SilkS")
		)
		(fp_line
			(start 0.7874 -0.4064)
			(end 0.7874 0.4064)
			(stroke
				(width 0.1524)
				(type default)
			)
			(layer "F.SilkS")
		)
		(fp_line
			(start -0.67945 0.3048)
			(end -0.67945 -0.305054)
			(stroke
				(width 0.1)
				(type default)
			)
			(layer "F.Fab")
		)
		(fp_line
			(start -0.12065 0.3048)
			(end -0.67945 0.3048)
			(stroke
				(width 0.1)
				(type default)
			)
			(layer "F.Fab")
		)
		(fp_line
			(start 0.120396 0.3048)
			(end 0.120396 0.2794)
			(stroke
				(width 0.1)
				(type default)
			)
			(layer "F.Fab")
		)
		(fp_line
			(start 0.67945 0.3048)
			(end 0.120396 0.3048)
			(stroke
				(width 0.1)
				(type default)
			)
			(layer "F.Fab")
		)
		(fp_line
			(start -0.12065 0.2794)
			(end -0.12065 0.3048)
			(stroke
				(width 0.1)
				(type default)
			)
			(layer "F.Fab")
		)
		(fp_line
			(start 0.120396 0.2794)
			(end -0.12065 0.2794)
			(stroke
				(width 0.1)
				(type default)
			)
			(layer "F.Fab")
		)
		(fp_line
			(start -0.12065 -0.2794)
			(end 0.12065 -0.2794)
			(stroke
				(width 0.1)
				(type default)
			)
			(layer "F.Fab")
		)
		(fp_line
			(start 0.12065 -0.2794)
			(end 0.12065 -0.3048)
			(stroke
				(width 0.1)
				(type default)
			)
			(layer "F.Fab")
		)
		(fp_line
			(start 0.12065 -0.3048)
			(end 0.67945 -0.3048)
			(stroke
				(width 0.1)
				(type default)
			)
			(layer "F.Fab")
		)
		(fp_line
			(start 0.67945 -0.3048)
			(end 0.67945 0.3048)
			(stroke
				(width 0.1)
				(type default)
			)
			(layer "F.Fab")
		)
		(fp_line
			(start -0.67945 -0.305054)
			(end -0.12065 -0.305054)
			(stroke
				(width 0.1)
				(type default)
			)
			(layer "F.Fab")
		)
		(fp_line
			(start -0.12065 -0.305054)
			(end -0.12065 -0.2794)
			(stroke
				(width 0.1)
				(type default)
			)
			(layer "F.Fab")
		)
		(pad "1" smd circle
			(at -0.40005 0 270)
			(size 0 0)
			(layers "F.Cu" "F.Mask" "F.Paste")
			(net "RST_CPU0_DRAM_GH_PLD_LVT3_R_N")
		)
		(pad "2" smd circle
			(at 0.40005 0 270)
			(size 0 0)
			(layers "F.Cu" "F.Mask" "F.Paste")
			(net "RST_CPU0_DRAM_GH_PLD_LVT3_N")
		)
	)
	(footprint ""
		(layer "F.Cu")
		(at 279.0317 -424.69562)
		(property "Reference" "R4805"
			(at 0 0 0)
			(layer "F.SilkS")
			(hide yes)
			(effects
				(font
					(size 1.27 1.27)
				)
			)
		)
		(property "Value" ""
			(at 0 0 0)
			(layer "F.Fab")
			(effects
				(font
					(size 1.27 1.27)
				)
			)
		)
		(duplicate_pad_numbers_are_jumpers no)
		(fp_line
			(start -0.7874 -0.4064)
			(end 0.7874 -0.4064)
			(stroke
				(width 0.1524)
				(type default)
			)
			(layer "F.SilkS")
		)
		(fp_line
			(start -0.7874 0.4064)
			(end -0.7874 -0.4064)
			(stroke
				(width 0.1524)
				(type default)
			)
			(layer "F.SilkS")
		)
		(fp_line
			(start 0.7874 -0.4064)
			(end 0.7874 0.4064)
			(stroke
				(width 0.1524)
				(type default)
			)
			(layer "F.SilkS")
		)
		(fp_line
			(start 0.7874 0.4064)
			(end -0.7874 0.4064)
			(stroke
				(width 0.1524)
				(type default)
			)
			(layer "F.SilkS")
		)
		(fp_line
			(start -0.67945 -0.305054)
			(end -0.12065 -0.305054)
			(stroke
				(width 0.1)
				(type default)
			)
			(layer "F.Fab")
		)
		(fp_line
			(start -0.67945 0.3048)
			(end -0.67945 -0.305054)
			(stroke
				(width 0.1)
				(type default)
			)
			(layer "F.Fab")
		)
		(fp_line
			(start -0.12065 -0.305054)
			(end -0.12065 -0.2794)
			(stroke
				(width 0.1)
				(type default)
			)
			(layer "F.Fab")
		)
		(fp_line
			(start -0.12065 -0.2794)
			(end 0.12065 -0.2794)
			(stroke
				(width 0.1)
				(type default)
			)
			(layer "F.Fab")
		)
		(fp_line
			(start -0.12065 0.2794)
			(end -0.12065 0.3048)
			(stroke
				(width 0.1)
				(type default)
			)
			(layer "F.Fab")
		)
		(fp_line
			(start -0.12065 0.3048)
			(end -0.67945 0.3048)
			(stroke
				(width 0.1)
				(type default)
			)
			(layer "F.Fab")
		)
		(fp_line
			(start 0.120396 0.2794)
			(end -0.12065 0.2794)
			(stroke
				(width 0.1)
				(type default)
			)
			(layer "F.Fab")
		)
		(fp_line
			(start 0.120396 0.3048)
			(end 0.120396 0.2794)
			(stroke
				(width 0.1)
				(type default)
			)
			(layer "F.Fab")
		)
		(fp_line
			(start 0.12065 -0.3048)
			(end 0.67945 -0.3048)
			(stroke
				(width 0.1)
				(type default)
			)
			(layer "F.Fab")
		)
		(fp_line
			(start 0.12065 -0.2794)
			(end 0.12065 -0.3048)
			(stroke
				(width 0.1)
				(type default)
			)
			(layer "F.Fab")
		)
		(fp_line
			(start 0.67945 -0.3048)
			(end 0.67945 0.3048)
			(stroke
				(width 0.1)
				(type default)
			)
			(layer "F.Fab")
		)
		(fp_line
			(start 0.67945 0.3048)
			(end 0.120396 0.3048)
			(stroke
				(width 0.1)
				(type default)
			)
			(layer "F.Fab")
		)
		(pad "1" smd circle
			(at -0.40005 0)
			(size 0 0)
			(layers "F.Cu" "F.Mask" "F.Paste")
			(net "P3V3_AUX")
		)
		(pad "2" smd circle
			(at 0.40005 0)
			(size 0 0)
			(layers "F.Cu" "F.Mask" "F.Paste")
			(net "U369_VDD")
		)
	)
	(footprint ""
		(layer "F.Cu")
		(at 79.933038 -408.517344 -90)
		(property "Reference" "C688"
			(at 0 0 270)
			(layer "F.SilkS")
			(hide yes)
			(effects
				(font
					(size 1.27 1.27)
				)
			)
		)
		(property "Value" ""
			(at 0 0 270)
			(layer "F.Fab")
			(effects
				(font
					(size 1.27 1.27)
				)
			)
		)
		(duplicate_pad_numbers_are_jumpers no)
		(fp_line
			(start -0.299974 0.150114)
			(end -0.299974 -0.150114)
			(stroke
				(width 0.1)
				(type default)
			)
			(layer "F.Fab")
		)
		(fp_line
			(start 0.299974 0.150114)
			(end -0.299974 0.150114)
			(stroke
				(width 0.1)
				(type default)
			)
			(layer "F.Fab")
		)
		(fp_line
			(start -0.299974 -0.150114)
			(end 0.299974 -0.150114)
			(stroke
				(width 0.1)
				(type default)
			)
			(layer "F.Fab")
		)
		(fp_line
			(start 0.299974 -0.150114)
			(end 0.299974 0.150114)
			(stroke
				(width 0.1)
				(type default)
			)
			(layer "F.Fab")
		)
		(pad "1" smd rect
			(at -0.2667 0 270)
			(size 0.3048 0.381)
			(layers "F.Cu" "F.Mask" "F.Paste")
			(net "P5E_CPU1_PE4_TX_C_DN<10>")
		)
		(pad "2" smd rect
			(at 0.2667 0 270)
			(size 0.3048 0.381)
			(layers "F.Cu" "F.Mask" "F.Paste")
			(net "P5E_CPU1_PE4_TX_DN<10>")
		)
	)
	(footprint ""
		(layer "F.Cu")
		(at 82.996278 -408.517344 -90)
		(property "Reference" "C687"
			(at 0 0 270)
			(layer "F.SilkS")
			(hide yes)
			(effects
				(font
					(size 1.27 1.27)
				)
			)
		)
		(property "Value" ""
			(at 0 0 270)
			(layer "F.Fab")
			(effects
				(font
					(size 1.27 1.27)
				)
			)
		)
		(duplicate_pad_numbers_are_jumpers no)
		(fp_line
			(start -0.299974 0.150114)
			(end -0.299974 -0.150114)
			(stroke
				(width 0.1)
				(type default)
			)
			(layer "F.Fab")
		)
		(fp_line
			(start 0.299974 0.150114)
			(end -0.299974 0.150114)
			(stroke
				(width 0.1)
				(type default)
			)
			(layer "F.Fab")
		)
		(fp_line
			(start -0.299974 -0.150114)
			(end 0.299974 -0.150114)
			(stroke
				(width 0.1)
				(type default)
			)
			(layer "F.Fab")
		)
		(fp_line
			(start 0.299974 -0.150114)
			(end 0.299974 0.150114)
			(stroke
				(width 0.1)
				(type default)
			)
			(layer "F.Fab")
		)
		(pad "1" smd rect
			(at -0.2667 0 270)
			(size 0.3048 0.381)
			(layers "F.Cu" "F.Mask" "F.Paste")
			(net "P5E_CPU1_PE4_TX_C_DP<11>")
		)
		(pad "2" smd rect
			(at 0.2667 0 270)
			(size 0.3048 0.381)
			(layers "F.Cu" "F.Mask" "F.Paste")
			(net "P5E_CPU1_PE4_TX_DP<11>")
		)
	)
	(footprint ""
		(layer "F.Cu")
		(at 230.248206 -246.693436 180)
		(property "Reference" "R3338"
			(at 0 0 180)
			(layer "F.SilkS")
			(hide yes)
			(effects
				(font
					(size 1.27 1.27)
				)
			)
		)
		(property "Value" ""
			(at 0 0 180)
			(layer "F.Fab")
			(effects
				(font
					(size 1.27 1.27)
				)
			)
		)
		(duplicate_pad_numbers_are_jumpers no)
		(fp_line
			(start 0.7874 0.4064)
			(end -0.7874 0.4064)
			(stroke
				(width 0.1524)
				(type default)
			)
			(layer "F.SilkS")
		)
		(fp_line
			(start 0.7874 -0.4064)
			(end 0.7874 0.4064)
			(stroke
				(width 0.1524)
				(type default)
			)
			(layer "F.SilkS")
		)
		(fp_line
			(start -0.7874 0.4064)
			(end -0.7874 -0.4064)
			(stroke
				(width 0.1524)
				(type default)
			)
			(layer "F.SilkS")
		)
		(fp_line
			(start -0.7874 -0.4064)
			(end 0.7874 -0.4064)
			(stroke
				(width 0.1524)
				(type default)
			)
			(layer "F.SilkS")
		)
		(fp_line
			(start 0.67945 0.3048)
			(end 0.120396 0.3048)
			(stroke
				(width 0.1)
				(type default)
			)
			(layer "F.Fab")
		)
		(fp_line
			(start 0.67945 -0.3048)
			(end 0.67945 0.3048)
			(stroke
				(width 0.1)
				(type default)
			)
			(layer "F.Fab")
		)
		(fp_line
			(start 0.12065 -0.2794)
			(end 0.12065 -0.3048)
			(stroke
				(width 0.1)
				(type default)
			)
			(layer "F.Fab")
		)
		(fp_line
			(start 0.12065 -0.3048)
			(end 0.67945 -0.3048)
			(stroke
				(width 0.1)
				(type default)
			)
			(layer "F.Fab")
		)
		(fp_line
			(start 0.120396 0.3048)
			(end 0.120396 0.2794)
			(stroke
				(width 0.1)
				(type default)
			)
			(layer "F.Fab")
		)
		(fp_line
			(start 0.120396 0.2794)
			(end -0.12065 0.2794)
			(stroke
				(width 0.1)
				(type default)
			)
			(layer "F.Fab")
		)
		(fp_line
			(start -0.12065 0.3048)
			(end -0.67945 0.3048)
			(stroke
				(width 0.1)
				(type default)
			)
			(layer "F.Fab")
		)
		(fp_line
			(start -0.12065 0.2794)
			(end -0.12065 0.3048)
			(stroke
				(width 0.1)
				(type default)
			)
			(layer "F.Fab")
		)
		(fp_line
			(start -0.12065 -0.2794)
			(end 0.12065 -0.2794)
			(stroke
				(width 0.1)
				(type default)
			)
			(layer "F.Fab")
		)
		(fp_line
			(start -0.12065 -0.305054)
			(end -0.12065 -0.2794)
			(stroke
				(width 0.1)
				(type default)
			)
			(layer "F.Fab")
		)
		(fp_line
			(start -0.67945 0.3048)
			(end -0.67945 -0.305054)
			(stroke
				(width 0.1)
				(type default)
			)
			(layer "F.Fab")
		)
		(fp_line
			(start -0.67945 -0.305054)
			(end -0.12065 -0.305054)
			(stroke
				(width 0.1)
				(type default)
			)
			(layer "F.Fab")
		)
		(pad "1" smd circle
			(at -0.40005 0 180)
			(size 0 0)
			(layers "F.Cu" "F.Mask" "F.Paste")
			(net "CLK_100M_GPU_FPGA_DN_R")
		)
		(pad "2" smd circle
			(at 0.40005 0 180)
			(size 0 0)
			(layers "F.Cu" "F.Mask" "F.Paste")
			(net "CLK_100M_GPU_FPGA_DN")
		)
	)
	(footprint ""
		(layer "F.Cu")
		(at 391.12317 -408.517344 -90)
		(property "Reference" "C882"
			(at 0 0 270)
			(layer "F.SilkS")
			(hide yes)
			(effects
				(font
					(size 1.27 1.27)
				)
			)
		)
		(property "Value" ""
			(at 0 0 270)
			(layer "F.Fab")
			(effects
				(font
					(size 1.27 1.27)
				)
			)
		)
		(duplicate_pad_numbers_are_jumpers no)
		(fp_line
			(start -0.299974 0.150114)
			(end -0.299974 -0.150114)
			(stroke
				(width 0.1)
				(type default)
			)
			(layer "F.Fab")
		)
		(fp_line
			(start 0.299974 0.150114)
			(end -0.299974 0.150114)
			(stroke
				(width 0.1)
				(type default)
			)
			(layer "F.Fab")
		)
		(fp_line
			(start -0.299974 -0.150114)
			(end 0.299974 -0.150114)
			(stroke
				(width 0.1)
				(type default)
			)
			(layer "F.Fab")
		)
		(fp_line
			(start 0.299974 -0.150114)
			(end 0.299974 0.150114)
			(stroke
				(width 0.1)
				(type default)
			)
			(layer "F.Fab")
		)
		(pad "1" smd rect
			(at -0.2667 0 270)
			(size 0.3048 0.381)
			(layers "F.Cu" "F.Mask" "F.Paste")
			(net "P5E_CPU0_PE3_TX_C_DN<9>")
		)
		(pad "2" smd rect
			(at 0.2667 0 270)
			(size 0.3048 0.381)
			(layers "F.Cu" "F.Mask" "F.Paste")
			(net "P5E_CPU0_PE3_TX_DN<9>")
		)
	)
	(footprint ""
		(layer "F.Cu")
		(at 105.39222 -296.05478 180)
		(property "Reference" "C250"
			(at 0 0 180)
			(layer "F.SilkS")
			(hide yes)
			(effects
				(font
					(size 1.27 1.27)
				)
			)
		)
		(property "Value" ""
			(at 0 0 180)
			(layer "F.Fab")
			(effects
				(font
					(size 1.27 1.27)
				)
			)
		)
		(duplicate_pad_numbers_are_jumpers no)
		(fp_line
			(start 1.524 0.762)
			(end -1.524 0.762)
			(stroke
				(width 0.1524)
				(type default)
			)
			(layer "F.SilkS")
		)
		(fp_line
			(start 1.524 -0.762)
			(end 1.524 0.762)
			(stroke
				(width 0.1524)
				(type default)
			)
			(layer "F.SilkS")
		)
		(fp_line
			(start -1.524 0.762)
			(end -1.524 -0.762)
			(stroke
				(width 0.1524)
				(type default)
			)
			(layer "F.SilkS")
		)
		(fp_line
			(start -1.524 -0.762)
			(end 1.524 -0.762)
			(stroke
				(width 0.1524)
				(type default)
			)
			(layer "F.SilkS")
		)
		(fp_line
			(start 1.1049 0.724916)
			(end 1.1049 -0.724916)
			(stroke
				(width 0.1)
				(type default)
			)
			(layer "F.Fab")
		)
		(fp_line
			(start 1.1049 -0.724916)
			(end -1.1049 -0.724916)
			(stroke
				(width 0.1)
				(type default)
			)
			(layer "F.Fab")
		)
		(fp_line
			(start -1.1049 0.724916)
			(end 1.1049 0.724916)
			(stroke
				(width 0.1)
				(type default)
			)
			(layer "F.Fab")
		)
		(fp_line
			(start -1.1049 -0.724916)
			(end -1.1049 0.724916)
			(stroke
				(width 0.1)
				(type default)
			)
			(layer "F.Fab")
		)
		(pad "1" smd rect
			(at -0.889 0)
			(size 1.016 1.27)
			(layers "F.Cu" "F.Mask" "F.Paste")
			(net "PVCCIN_CPU1")
		)
		(pad "2" smd rect
			(at 0.889 0)
			(size 1.016 1.27)
			(layers "F.Cu" "F.Mask" "F.Paste")
			(net "GND")
		)
	)
	(footprint ""
		(layer "F.Cu")
		(at 16.35506 -335.871312)
		(property "Reference" "U103"
			(at -5.4864 -3.969258 0)
			(unlocked yes)
			(layer "F.SilkS")
			(effects
				(font
					(size 0.7874 0.5842)
					(thickness 0.1524)
				)
				(justify left)
			)
		)
		(property "Value" ""
			(at 0 0 0)
			(layer "F.Fab")
			(effects
				(font
					(size 1.27 1.27)
				)
			)
		)
		(duplicate_pad_numbers_are_jumpers no)
		(fp_line
			(start -1.99263 -1.525016)
			(end -1.99263 1.525016)
			(stroke
				(width 0.1524)
				(type default)
			)
			(layer "F.SilkS")
		)
		(fp_line
			(start -1.99263 1.525016)
			(end 1.99263 1.525016)
			(stroke
				(width 0.1524)
				(type default)
			)
			(layer "F.SilkS")
		)
		(fp_line
			(start 1.99263 -1.525016)
			(end -1.99263 -1.525016)
			(stroke
				(width 0.1524)
				(type default)
			)
			(layer "F.SilkS")
		)
		(fp_line
			(start 1.99263 1.525016)
			(end 1.99263 -1.525016)
			(stroke
				(width 0.1524)
				(type default)
			)
			(layer "F.SilkS")
		)
		(fp_poly
			(pts
				(xy -4.286504 -1.43764) (xy -3.270504 -0.92964) (xy -4.286504 -0.42164)
			)
			(stroke
				(width 0)
				(type default)
			)
			(fill yes)
			(layer "F.SilkS")
		)
		(fp_line
			(start -0.87503 -1.525016)
			(end -0.87503 1.525016)
			(stroke
				(width 0.1)
				(type default)
			)
			(layer "F.Fab")
		)
		(fp_line
			(start -0.87503 1.525016)
			(end 0.87503 1.525016)
			(stroke
				(width 0.1)
				(type default)
			)
			(layer "F.Fab")
		)
		(fp_line
			(start 0.87503 -1.525016)
			(end -0.87503 -1.525016)
			(stroke
				(width 0.1)
				(type default)
			)
			(layer "F.Fab")
		)
		(fp_line
			(start 0.87503 1.525016)
			(end 0.87503 -1.525016)
			(stroke
				(width 0.1)
				(type default)
			)
			(layer "F.Fab")
		)
		(fp_poly
			(pts
				(xy -3.2004 -1.45796) (xy -3.2004 -0.44196) (xy -2.1844 -0.94996)
			)
			(stroke
				(width 0)
				(type default)
			)
			(fill yes)
			(layer "F.Fab")
		)
		(pad "1" smd circle
			(at -1.299972 -0.94996 270)
			(size 0 0)
			(layers "F.Cu" "F.Mask" "F.Paste")
			(net "GND")
		)
		(pad "2" smd circle
			(at -1.299972 0 270)
			(size 0 0)
			(layers "F.Cu" "F.Mask" "F.Paste")
			(net "GND")
		)
		(pad "3" smd circle
			(at -1.299972 0.94996 270)
			(size 0 0)
			(layers "F.Cu" "F.Mask" "F.Paste")
			(net "PVCCD_HV_CPU1_NVDIMM_ISENSE")
		)
		(pad "4" smd circle
			(at 1.299972 0.94996 270)
			(size 0 0)
			(layers "F.Cu" "F.Mask" "F.Paste")
			(net "P12V_AUX_CPU1_DIMM_ISEN_N")
		)
		(pad "5" smd circle
			(at 1.299972 -0.94996 270)
			(size 0 0)
			(layers "F.Cu" "F.Mask" "F.Paste")
			(net "P12V_AUX_CPU1_DIMM_ISEN_P")
		)
	)
	(footprint ""
		(layer "F.Cu")
		(at 93.582998 -47.049944 90)
		(property "Reference" "H74"
			(at -4.312666 -0.46101 0)
			(unlocked yes)
			(layer "F.SilkS")
			(effects
				(font
					(size 0.7874 0.5842)
					(thickness 0.1524)
				)
			)
		)
		(property "Value" ""
			(at 0 0 90)
			(layer "F.Fab")
			(effects
				(font
					(size 1.27 1.27)
				)
			)
		)
		(duplicate_pad_numbers_are_jumpers no)
		(pad "" np_thru_hole circle
			(at 0 0 90)
			(size 0 0)
			(drill oval 3.2004 4.8006)
			(layers "*.Cu" "*.Mask")
			(clearance -1.2192)
			(thermal_gap 0.381)
			(padstack
				(mode front_inner_back)
				(layer "Inner"
					(shape oval)
					(size 3.2004 4.8006)
					(clearance 0.381)
				)
				(layer "B.Cu"
					(shape circle)
					(size 0 0)
					(clearance -1.2192)
				)
			)
		)
		(zone
			(layers "F.Cu" "B.Cu" "In1.Cu" "In2.Cu" "In3.Cu" "In4.Cu" "In5.Cu" "In6.Cu"
				"In7.Cu" "In8.Cu" "In9.Cu" "In10.Cu" "In11.Cu" "In12.Cu" "In13.Cu" "In14.Cu"
				"In15.Cu" "In16.Cu"
			)
			(hatch none 0.5)
			(connect_pads
				(clearance 0)
			)
			(min_thickness 0.25)
			(keepout
				(tracks not_allowed)
				(vias allowed)
				(pads allowed)
				(copperpour not_allowed)
				(footprints allowed)
			)
			(placement
				(enabled no)
				(sheetname "")
			)
			(fill
				(thermal_gap 0.5)
				(thermal_bridge_width 0.5)
				(island_removal_mode 0)
			)
			(polygon
				(pts
					(arc
						(start 94.383098 -49.158144)
						(mid 96.491298 -47.049944)
						(end 94.383098 -44.941744)
					)
					(arc
						(start 92.782898 -44.941744)
						(mid 90.674698 -47.049944)
						(end 92.782898 -49.158144)
					)
				)
			)
		)
		(zone
			(layers "F.Cu" "B.Cu" "In1.Cu" "In2.Cu" "In3.Cu" "In4.Cu" "In5.Cu" "In6.Cu"
				"In7.Cu" "In8.Cu" "In9.Cu" "In10.Cu" "In11.Cu" "In12.Cu" "In13.Cu" "In14.Cu"
				"In15.Cu" "In16.Cu"
			)
			(hatch none 0.5)
			(connect_pads
				(clearance 0)
			)
			(min_thickness 0.25)
			(keepout
				(tracks not_allowed)
				(vias allowed)
				(pads allowed)
				(copperpour not_allowed)
				(footprints allowed)
			)
			(placement
				(enabled no)
				(sheetname "")
			)
			(fill
				(thermal_gap 0.5)
				(thermal_bridge_width 0.5)
				(island_removal_mode 0)
			)
			(polygon
				(pts
					(arc
						(start 94.383098 -50.050192)
						(mid 97.383346 -47.049944)
						(end 94.383098 -44.049696)
					)
					(arc
						(start 92.782898 -44.049696)
						(mid 89.78265 -47.049944)
						(end 92.782898 -50.050192)
					)
				)
			)
		)
	)
	(footprint ""
		(layer "F.Cu")
		(at 103.384096 -70.78599)
		(property "Reference" "D85"
			(at -51.698906 50.178462 90)
			(unlocked yes)
			(layer "F.SilkS")
			(effects
				(font
					(size 0.635 0.4064)
					(thickness 0.1524)
				)
				(justify left)
			)
		)
		(property "Value" ""
			(at 0 0 0)
			(layer "F.Fab")
			(effects
				(font
					(size 1.27 1.27)
				)
			)
		)
		(duplicate_pad_numbers_are_jumpers no)
		(fp_line
			(start -0.90678 0.4826)
			(end -0.90678 -0.4699)
			(stroke
				(width 0.1524)
				(type default)
			)
			(layer "F.SilkS")
		)
		(fp_line
			(start -0.89408 -0.4826)
			(end 0.90678 -0.4826)
			(stroke
				(width 0.1524)
				(type default)
			)
			(layer "F.SilkS")
		)
		(fp_line
			(start -0.79248 -0.4826)
			(end 1.03378 -0.4826)
			(stroke
				(width 0.1524)
				(type default)
			)
			(layer "F.SilkS")
		)
		(fp_line
			(start -0.64008 -0.4826)
			(end 1.16078 -0.4826)
			(stroke
				(width 0.1524)
				(type default)
			)
			(layer "F.SilkS")
		)
		(fp_line
			(start 0.90678 -0.4826)
			(end 0.90678 0.4826)
			(stroke
				(width 0.1524)
				(type default)
			)
			(layer "F.SilkS")
		)
		(fp_line
			(start 0.90678 0.4826)
			(end -0.90678 0.4826)
			(stroke
				(width 0.1524)
				(type default)
			)
			(layer "F.SilkS")
		)
		(fp_line
			(start 1.03378 -0.4826)
			(end 1.03378 0.4826)
			(stroke
				(width 0.1524)
				(type default)
			)
			(layer "F.SilkS")
		)
		(fp_line
			(start 1.03378 0.4826)
			(end -0.79248 0.4826)
			(stroke
				(width 0.1524)
				(type default)
			)
			(layer "F.SilkS")
		)
		(fp_line
			(start 1.16078 -0.4826)
			(end 1.16078 0.4826)
			(stroke
				(width 0.1524)
				(type default)
			)
			(layer "F.SilkS")
		)
		(fp_line
			(start 1.16078 0.4826)
			(end -0.64008 0.4826)
			(stroke
				(width 0.1524)
				(type default)
			)
			(layer "F.SilkS")
		)
		(fp_line
			(start -0.499872 -0.249936)
			(end 0.499872 -0.249936)
			(stroke
				(width 0.1)
				(type default)
			)
			(layer "F.Fab")
		)
		(fp_line
			(start -0.499872 0.249936)
			(end -0.499872 -0.249936)
			(stroke
				(width 0.1)
				(type default)
			)
			(layer "F.Fab")
		)
		(fp_line
			(start 0.499872 -0.249936)
			(end 0.499872 0.249936)
			(stroke
				(width 0.1)
				(type default)
			)
			(layer "F.Fab")
		)
		(fp_line
			(start 0.499872 0.249936)
			(end -0.499872 0.249936)
			(stroke
				(width 0.1)
				(type default)
			)
			(layer "F.Fab")
		)
		(pad "A" smd rect
			(at -0.47498 0)
			(size 0.6096 0.7112)
			(layers "F.Cu" "F.Mask" "F.Paste")
			(net "LED_PWRGD_PVNN_MAIN_CPU1")
		)
		(pad "C" smd rect
			(at 0.47498 0)
			(size 0.6096 0.7112)
			(layers "F.Cu" "F.Mask" "F.Paste")
			(net "LED_PWRGD_PVNN_MAIN_CPU1_D")
		)
	)
	(footprint ""
		(layer "F.Cu")
		(at 329.855068 -353.52482)
		(property "Reference" "H45"
			(at -3.64744 -5.138928 0)
			(unlocked yes)
			(layer "F.SilkS")
			(effects
				(font
					(size 0.7874 0.5842)
					(thickness 0.1524)
				)
				(justify left)
			)
		)
		(property "Value" ""
			(at 0 0 0)
			(layer "F.Fab")
			(effects
				(font
					(size 1.27 1.27)
				)
			)
		)
		(duplicate_pad_numbers_are_jumpers no)
		(pad "1" thru_hole circle
			(at 0 0)
			(size 8.001 8.001)
			(drill 3.2004)
			(layers "*.Cu" "*.Mask")
			(remove_unused_layers no)
			(net "GND")
			(clearance -2.1463)
			(padstack
				(mode front_inner_back)
				(layer "Inner"
					(shape circle)
					(size 5.0038 5.0038)
					(clearance -0.6477)
				)
				(layer "B.Cu"
					(shape circle)
					(size 8.001 8.001)
					(clearance -2.1463)
				)
			)
		)
	)
	(footprint ""
		(layer "F.Cu")
		(at 444.627 -76.164948 90)
		(property "Reference" "PC8"
			(at 0 0 90)
			(layer "F.SilkS")
			(hide yes)
			(effects
				(font
					(size 1.27 1.27)
				)
			)
		)
		(property "Value" ""
			(at 0 0 90)
			(layer "F.Fab")
			(effects
				(font
					(size 1.27 1.27)
				)
			)
		)
		(duplicate_pad_numbers_are_jumpers no)
		(fp_line
			(start 1.2954 -0.5842)
			(end 1.2954 0.5842)
			(stroke
				(width 0.1524)
				(type default)
			)
			(layer "F.SilkS")
		)
		(fp_line
			(start 0 -0.5842)
			(end 0 0.5842)
			(stroke
				(width 0.1524)
				(type default)
			)
			(layer "F.SilkS")
		)
		(fp_line
			(start -1.2954 -0.5842)
			(end 1.2954 -0.5842)
			(stroke
				(width 0.1524)
				(type default)
			)
			(layer "F.SilkS")
		)
		(fp_line
			(start 1.2954 0.5842)
			(end -1.2954 0.5842)
			(stroke
				(width 0.1524)
				(type default)
			)
			(layer "F.SilkS")
		)
		(fp_line
			(start -1.2954 0.5842)
			(end -1.2954 -0.5842)
			(stroke
				(width 0.1524)
				(type default)
			)
			(layer "F.SilkS")
		)
		(fp_line
			(start 0.8636 -0.4572)
			(end 0.8636 -0.4064)
			(stroke
				(width 0.1)
				(type default)
			)
			(layer "F.Fab")
		)
		(fp_line
			(start -0.8636 -0.4572)
			(end 0.8636 -0.4572)
			(stroke
				(width 0.1)
				(type default)
			)
			(layer "F.Fab")
		)
		(fp_line
			(start 1.1938 -0.4064)
			(end 1.1938 0.4064)
			(stroke
				(width 0.1)
				(type default)
			)
			(layer "F.Fab")
		)
		(fp_line
			(start 0.8636 -0.4064)
			(end 1.1938 -0.4064)
			(stroke
				(width 0.1)
				(type default)
			)
			(layer "F.Fab")
		)
		(fp_line
			(start -0.8636 -0.4064)
			(end -0.8636 -0.4572)
			(stroke
				(width 0.1)
				(type default)
			)
			(layer "F.Fab")
		)
		(fp_line
			(start -1.1938 -0.4064)
			(end -0.8636 -0.4064)
			(stroke
				(width 0.1)
				(type default)
			)
			(layer "F.Fab")
		)
		(fp_line
			(start 1.1938 0.4064)
			(end 0.8636 0.4064)
			(stroke
				(width 0.1)
				(type default)
			)
			(layer "F.Fab")
		)
		(fp_line
			(start 0.8636 0.4064)
			(end 0.8636 0.4572)
			(stroke
				(width 0.1)
				(type default)
			)
			(layer "F.Fab")
		)
		(fp_line
			(start -0.8636 0.4064)
			(end -1.1938 0.4064)
			(stroke
				(width 0.1)
				(type default)
			)
			(layer "F.Fab")
		)
		(fp_line
			(start -1.1938 0.4064)
			(end -1.1938 -0.4064)
			(stroke
				(width 0.1)
				(type default)
			)
			(layer "F.Fab")
		)
		(fp_line
			(start 0.8636 0.4572)
			(end -0.8636 0.4572)
			(stroke
				(width 0.1)
				(type default)
			)
			(layer "F.Fab")
		)
		(fp_line
			(start -0.8636 0.4572)
			(end -0.8636 0.4064)
			(stroke
				(width 0.1)
				(type default)
			)
			(layer "F.Fab")
		)
		(pad "1" smd rect
			(at -0.7366 0)
			(size 0.7112 0.8128)
			(layers "F.Cu" "F.Mask" "F.Paste")
			(net "P12V_AUX")
		)
		(pad "2" smd rect
			(at 0.7366 0)
			(size 0.7112 0.8128)
			(layers "F.Cu" "F.Mask" "F.Paste")
			(net "GND")
		)
	)
	(footprint ""
		(layer "F.Cu")
		(at 380.538736 -92.887292 90)
		(property "Reference" "R1831"
			(at 0 0 90)
			(layer "F.SilkS")
			(hide yes)
			(effects
				(font
					(size 1.27 1.27)
				)
			)
		)
		(property "Value" ""
			(at 0 0 90)
			(layer "F.Fab")
			(effects
				(font
					(size 1.27 1.27)
				)
			)
		)
		(duplicate_pad_numbers_are_jumpers no)
		(fp_line
			(start 0.7874 -0.4064)
			(end 0.7874 0.4064)
			(stroke
				(width 0.1524)
				(type default)
			)
			(layer "F.SilkS")
		)
		(fp_line
			(start -0.7874 -0.4064)
			(end 0.7874 -0.4064)
			(stroke
				(width 0.1524)
				(type default)
			)
			(layer "F.SilkS")
		)
		(fp_line
			(start 0.7874 0.4064)
			(end -0.7874 0.4064)
			(stroke
				(width 0.1524)
				(type default)
			)
			(layer "F.SilkS")
		)
		(fp_line
			(start -0.7874 0.4064)
			(end -0.7874 -0.4064)
			(stroke
				(width 0.1524)
				(type default)
			)
			(layer "F.SilkS")
		)
		(fp_line
			(start -0.12065 -0.305054)
			(end -0.12065 -0.2794)
			(stroke
				(width 0.1)
				(type default)
			)
			(layer "F.Fab")
		)
		(fp_line
			(start -0.67945 -0.305054)
			(end -0.12065 -0.305054)
			(stroke
				(width 0.1)
				(type default)
			)
			(layer "F.Fab")
		)
		(fp_line
			(start 0.67945 -0.3048)
			(end 0.67945 0.3048)
			(stroke
				(width 0.1)
				(type default)
			)
			(layer "F.Fab")
		)
		(fp_line
			(start 0.12065 -0.3048)
			(end 0.67945 -0.3048)
			(stroke
				(width 0.1)
				(type default)
			)
			(layer "F.Fab")
		)
		(fp_line
			(start 0.12065 -0.2794)
			(end 0.12065 -0.3048)
			(stroke
				(width 0.1)
				(type default)
			)
			(layer "F.Fab")
		)
		(fp_line
			(start -0.12065 -0.2794)
			(end 0.12065 -0.2794)
			(stroke
				(width 0.1)
				(type default)
			)
			(layer "F.Fab")
		)
		(fp_line
			(start 0.120396 0.2794)
			(end -0.12065 0.2794)
			(stroke
				(width 0.1)
				(type default)
			)
			(layer "F.Fab")
		)
		(fp_line
			(start -0.12065 0.2794)
			(end -0.12065 0.3048)
			(stroke
				(width 0.1)
				(type default)
			)
			(layer "F.Fab")
		)
		(fp_line
			(start 0.67945 0.3048)
			(end 0.120396 0.3048)
			(stroke
				(width 0.1)
				(type default)
			)
			(layer "F.Fab")
		)
		(fp_line
			(start 0.120396 0.3048)
			(end 0.120396 0.2794)
			(stroke
				(width 0.1)
				(type default)
			)
			(layer "F.Fab")
		)
		(fp_line
			(start -0.12065 0.3048)
			(end -0.67945 0.3048)
			(stroke
				(width 0.1)
				(type default)
			)
			(layer "F.Fab")
		)
		(fp_line
			(start -0.67945 0.3048)
			(end -0.67945 -0.305054)
			(stroke
				(width 0.1)
				(type default)
			)
			(layer "F.Fab")
		)
		(pad "1" smd circle
			(at -0.40005 0 90)
			(size 0 0)
			(layers "F.Cu" "F.Mask" "F.Paste")
			(net "JTAG_DBP_BMC_PRDY_N")
		)
		(pad "2" smd circle
			(at 0.40005 0 90)
			(size 0 0)
			(layers "F.Cu" "F.Mask" "F.Paste")
			(net "JTAG_DBP_BMC_PRDY_R_N")
		)
	)
	(footprint ""
		(layer "F.Cu")
		(at 317.553848 -408.517344 -90)
		(property "Reference" "C910"
			(at 0 0 270)
			(layer "F.SilkS")
			(hide yes)
			(effects
				(font
					(size 1.27 1.27)
				)
			)
		)
		(property "Value" ""
			(at 0 0 270)
			(layer "F.Fab")
			(effects
				(font
					(size 1.27 1.27)
				)
			)
		)
		(duplicate_pad_numbers_are_jumpers no)
		(fp_line
			(start -0.299974 0.150114)
			(end -0.299974 -0.150114)
			(stroke
				(width 0.1)
				(type default)
			)
			(layer "F.Fab")
		)
		(fp_line
			(start 0.299974 0.150114)
			(end -0.299974 0.150114)
			(stroke
				(width 0.1)
				(type default)
			)
			(layer "F.Fab")
		)
		(fp_line
			(start -0.299974 -0.150114)
			(end 0.299974 -0.150114)
			(stroke
				(width 0.1)
				(type default)
			)
			(layer "F.Fab")
		)
		(fp_line
			(start 0.299974 -0.150114)
			(end 0.299974 0.150114)
			(stroke
				(width 0.1)
				(type default)
			)
			(layer "F.Fab")
		)
		(pad "1" smd rect
			(at -0.2667 0 270)
			(size 0.3048 0.381)
			(layers "F.Cu" "F.Mask" "F.Paste")
			(net "P5E_CPU0_PE0_TX_C_DN<11>")
		)
		(pad "2" smd rect
			(at 0.2667 0 270)
			(size 0.3048 0.381)
			(layers "F.Cu" "F.Mask" "F.Paste")
			(net "P5E_CPU0_PE0_TX_DN<11>")
		)
	)
	(footprint ""
		(layer "F.Cu")
		(at 160.28035 -43.832526 90)
		(property "Reference" "R4472"
			(at 0 0 90)
			(layer "F.SilkS")
			(hide yes)
			(effects
				(font
					(size 1.27 1.27)
				)
			)
		)
		(property "Value" ""
			(at 0 0 90)
			(layer "F.Fab")
			(effects
				(font
					(size 1.27 1.27)
				)
			)
		)
		(duplicate_pad_numbers_are_jumpers no)
		(fp_line
			(start 0.7874 -0.4064)
			(end 0.7874 0.4064)
			(stroke
				(width 0.1524)
				(type default)
			)
			(layer "F.SilkS")
		)
		(fp_line
			(start 0.7874 0.4064)
			(end -0.7874 0.4064)
			(stroke
				(width 0.1524)
				(type default)
			)
			(layer "F.SilkS")
		)
		(fp_line
			(start -0.12065 -0.305054)
			(end -0.12065 -0.2794)
			(stroke
				(width 0.1)
				(type default)
			)
			(layer "F.Fab")
		)
		(fp_line
			(start -0.67945 -0.305054)
			(end -0.12065 -0.305054)
			(stroke
				(width 0.1)
				(type default)
			)
			(layer "F.Fab")
		)
		(fp_line
			(start 0.67945 -0.3048)
			(end 0.67945 0.3048)
			(stroke
				(width 0.1)
				(type default)
			)
			(layer "F.Fab")
		)
		(fp_line
			(start 0.12065 -0.3048)
			(end 0.67945 -0.3048)
			(stroke
				(width 0.1)
				(type default)
			)
			(layer "F.Fab")
		)
		(fp_line
			(start 0.12065 -0.2794)
			(end 0.12065 -0.3048)
			(stroke
				(width 0.1)
				(type default)
			)
			(layer "F.Fab")
		)
		(fp_line
			(start -0.12065 -0.2794)
			(end 0.12065 -0.2794)
			(stroke
				(width 0.1)
				(type default)
			)
			(layer "F.Fab")
		)
		(fp_line
			(start 0.120396 0.2794)
			(end -0.12065 0.2794)
			(stroke
				(width 0.1)
				(type default)
			)
			(layer "F.Fab")
		)
		(fp_line
			(start -0.12065 0.2794)
			(end -0.12065 0.3048)
			(stroke
				(width 0.1)
				(type default)
			)
			(layer "F.Fab")
		)
		(fp_line
			(start 0.67945 0.3048)
			(end 0.120396 0.3048)
			(stroke
				(width 0.1)
				(type default)
			)
			(layer "F.Fab")
		)
		(fp_line
			(start 0.120396 0.3048)
			(end 0.120396 0.2794)
			(stroke
				(width 0.1)
				(type default)
			)
			(layer "F.Fab")
		)
		(fp_line
			(start -0.12065 0.3048)
			(end -0.67945 0.3048)
			(stroke
				(width 0.1)
				(type default)
			)
			(layer "F.Fab")
		)
		(fp_line
			(start -0.67945 0.3048)
			(end -0.67945 -0.305054)
			(stroke
				(width 0.1)
				(type default)
			)
			(layer "F.Fab")
		)
		(pad "1" smd rect
			(at -0.40005 0 270)
			(size 0.4572 0.508)
			(layers "F.Cu" "F.Mask" "F.Paste")
			(net "USB2_PCH_0_R_DN")
		)
		(pad "2" smd rect
			(at 0.40005 0 270)
			(size 0.4572 0.508)
			(layers "F.Cu" "F.Mask" "F.Paste")
			(net "USB2_0_DN")
		)
	)
	(footprint ""
		(layer "F.Cu")
		(at 148.1963 -48.283368)
		(property "Reference" "R4090"
			(at 0 0 0)
			(layer "F.SilkS")
			(hide yes)
			(effects
				(font
					(size 1.27 1.27)
				)
			)
		)
		(property "Value" ""
			(at 0 0 0)
			(layer "F.Fab")
			(effects
				(font
					(size 1.27 1.27)
				)
			)
		)
		(duplicate_pad_numbers_are_jumpers no)
		(fp_line
			(start -0.7874 -0.4064)
			(end 0.7874 -0.4064)
			(stroke
				(width 0.1524)
				(type default)
			)
			(layer "F.SilkS")
		)
		(fp_line
			(start -0.7874 0.4064)
			(end -0.7874 -0.4064)
			(stroke
				(width 0.1524)
				(type default)
			)
			(layer "F.SilkS")
		)
		(fp_line
			(start 0.7874 -0.4064)
			(end 0.7874 0.4064)
			(stroke
				(width 0.1524)
				(type default)
			)
			(layer "F.SilkS")
		)
		(fp_line
			(start 0.7874 0.4064)
			(end -0.7874 0.4064)
			(stroke
				(width 0.1524)
				(type default)
			)
			(layer "F.SilkS")
		)
		(fp_line
			(start -0.67945 -0.305054)
			(end -0.12065 -0.305054)
			(stroke
				(width 0.1)
				(type default)
			)
			(layer "F.Fab")
		)
		(fp_line
			(start -0.67945 0.3048)
			(end -0.67945 -0.305054)
			(stroke
				(width 0.1)
				(type default)
			)
			(layer "F.Fab")
		)
		(fp_line
			(start -0.12065 -0.305054)
			(end -0.12065 -0.2794)
			(stroke
				(width 0.1)
				(type default)
			)
			(layer "F.Fab")
		)
		(fp_line
			(start -0.12065 -0.2794)
			(end 0.12065 -0.2794)
			(stroke
				(width 0.1)
				(type default)
			)
			(layer "F.Fab")
		)
		(fp_line
			(start -0.12065 0.2794)
			(end -0.12065 0.3048)
			(stroke
				(width 0.1)
				(type default)
			)
			(layer "F.Fab")
		)
		(fp_line
			(start -0.12065 0.3048)
			(end -0.67945 0.3048)
			(stroke
				(width 0.1)
				(type default)
			)
			(layer "F.Fab")
		)
		(fp_line
			(start 0.120396 0.2794)
			(end -0.12065 0.2794)
			(stroke
				(width 0.1)
				(type default)
			)
			(layer "F.Fab")
		)
		(fp_line
			(start 0.120396 0.3048)
			(end 0.120396 0.2794)
			(stroke
				(width 0.1)
				(type default)
			)
			(layer "F.Fab")
		)
		(fp_line
			(start 0.12065 -0.3048)
			(end 0.67945 -0.3048)
			(stroke
				(width 0.1)
				(type default)
			)
			(layer "F.Fab")
		)
		(fp_line
			(start 0.12065 -0.2794)
			(end 0.12065 -0.3048)
			(stroke
				(width 0.1)
				(type default)
			)
			(layer "F.Fab")
		)
		(fp_line
			(start 0.67945 -0.3048)
			(end 0.67945 0.3048)
			(stroke
				(width 0.1)
				(type default)
			)
			(layer "F.Fab")
		)
		(fp_line
			(start 0.67945 0.3048)
			(end 0.120396 0.3048)
			(stroke
				(width 0.1)
				(type default)
			)
			(layer "F.Fab")
		)
		(pad "1" smd circle
			(at -0.40005 0)
			(size 0 0)
			(layers "F.Cu" "F.Mask" "F.Paste")
			(net "P3V3_AUX")
		)
		(pad "2" smd circle
			(at 0.40005 0)
			(size 0 0)
			(layers "F.Cu" "F.Mask" "F.Paste")
			(net "M2_0_P3V3_ADC_ALERT_R")
		)
	)
	(footprint ""
		(layer "F.Cu")
		(at 411.201108 -362.296964)
		(property "Reference" "PR632"
			(at 0 0 0)
			(layer "F.SilkS")
			(hide yes)
			(effects
				(font
					(size 1.27 1.27)
				)
			)
		)
		(property "Value" ""
			(at 0 0 0)
			(layer "F.Fab")
			(effects
				(font
					(size 1.27 1.27)
				)
			)
		)
		(duplicate_pad_numbers_are_jumpers no)
		(fp_line
			(start -0.7874 -0.4064)
			(end 0.7874 -0.4064)
			(stroke
				(width 0.1524)
				(type default)
			)
			(layer "F.SilkS")
		)
		(fp_line
			(start -0.7874 0.4064)
			(end -0.7874 -0.4064)
			(stroke
				(width 0.1524)
				(type default)
			)
			(layer "F.SilkS")
		)
		(fp_line
			(start 0.7874 -0.4064)
			(end 0.7874 0.4064)
			(stroke
				(width 0.1524)
				(type default)
			)
			(layer "F.SilkS")
		)
		(fp_line
			(start 0.7874 0.4064)
			(end -0.7874 0.4064)
			(stroke
				(width 0.1524)
				(type default)
			)
			(layer "F.SilkS")
		)
		(fp_line
			(start -0.67945 -0.305054)
			(end -0.12065 -0.305054)
			(stroke
				(width 0.1)
				(type default)
			)
			(layer "F.Fab")
		)
		(fp_line
			(start -0.67945 0.3048)
			(end -0.67945 -0.305054)
			(stroke
				(width 0.1)
				(type default)
			)
			(layer "F.Fab")
		)
		(fp_line
			(start -0.12065 -0.305054)
			(end -0.12065 -0.2794)
			(stroke
				(width 0.1)
				(type default)
			)
			(layer "F.Fab")
		)
		(fp_line
			(start -0.12065 -0.2794)
			(end 0.12065 -0.2794)
			(stroke
				(width 0.1)
				(type default)
			)
			(layer "F.Fab")
		)
		(fp_line
			(start -0.12065 0.2794)
			(end -0.12065 0.3048)
			(stroke
				(width 0.1)
				(type default)
			)
			(layer "F.Fab")
		)
		(fp_line
			(start -0.12065 0.3048)
			(end -0.67945 0.3048)
			(stroke
				(width 0.1)
				(type default)
			)
			(layer "F.Fab")
		)
		(fp_line
			(start 0.120396 0.2794)
			(end -0.12065 0.2794)
			(stroke
				(width 0.1)
				(type default)
			)
			(layer "F.Fab")
		)
		(fp_line
			(start 0.120396 0.3048)
			(end 0.120396 0.2794)
			(stroke
				(width 0.1)
				(type default)
			)
			(layer "F.Fab")
		)
		(fp_line
			(start 0.12065 -0.3048)
			(end 0.67945 -0.3048)
			(stroke
				(width 0.1)
				(type default)
			)
			(layer "F.Fab")
		)
		(fp_line
			(start 0.12065 -0.2794)
			(end 0.12065 -0.3048)
			(stroke
				(width 0.1)
				(type default)
			)
			(layer "F.Fab")
		)
		(fp_line
			(start 0.67945 -0.3048)
			(end 0.67945 0.3048)
			(stroke
				(width 0.1)
				(type default)
			)
			(layer "F.Fab")
		)
		(fp_line
			(start 0.67945 0.3048)
			(end 0.120396 0.3048)
			(stroke
				(width 0.1)
				(type default)
			)
			(layer "F.Fab")
		)
		(pad "1" smd circle
			(at -0.40005 0)
			(size 0 0)
			(layers "F.Cu" "F.Mask" "F.Paste")
			(net "P3V3")
		)
		(pad "2" smd circle
			(at 0.40005 0)
			(size 0 0)
			(layers "F.Cu" "F.Mask" "F.Paste")
			(net "PVCCFA_EHV_FIVRA_CPU0_PVCC1")
		)
	)
	(footprint ""
		(layer "F.Cu")
		(at 252.961648 -55.177182)
		(property "Reference" "PR3953"
			(at 0 0 0)
			(layer "F.SilkS")
			(hide yes)
			(effects
				(font
					(size 1.27 1.27)
				)
			)
		)
		(property "Value" ""
			(at 0 0 0)
			(layer "F.Fab")
			(effects
				(font
					(size 1.27 1.27)
				)
			)
		)
		(duplicate_pad_numbers_are_jumpers no)
		(fp_line
			(start -0.7874 -0.4064)
			(end 0.7874 -0.4064)
			(stroke
				(width 0.1524)
				(type default)
			)
			(layer "F.SilkS")
		)
		(fp_line
			(start -0.7874 0.4064)
			(end -0.7874 -0.4064)
			(stroke
				(width 0.1524)
				(type default)
			)
			(layer "F.SilkS")
		)
		(fp_line
			(start 0.7874 -0.4064)
			(end 0.7874 0.4064)
			(stroke
				(width 0.1524)
				(type default)
			)
			(layer "F.SilkS")
		)
		(fp_line
			(start 0.7874 0.4064)
			(end -0.7874 0.4064)
			(stroke
				(width 0.1524)
				(type default)
			)
			(layer "F.SilkS")
		)
		(fp_line
			(start -0.67945 -0.305054)
			(end -0.12065 -0.305054)
			(stroke
				(width 0.1)
				(type default)
			)
			(layer "F.Fab")
		)
		(fp_line
			(start -0.67945 0.3048)
			(end -0.67945 -0.305054)
			(stroke
				(width 0.1)
				(type default)
			)
			(layer "F.Fab")
		)
		(fp_line
			(start -0.12065 -0.305054)
			(end -0.12065 -0.2794)
			(stroke
				(width 0.1)
				(type default)
			)
			(layer "F.Fab")
		)
		(fp_line
			(start -0.12065 -0.2794)
			(end 0.12065 -0.2794)
			(stroke
				(width 0.1)
				(type default)
			)
			(layer "F.Fab")
		)
		(fp_line
			(start -0.12065 0.2794)
			(end -0.12065 0.3048)
			(stroke
				(width 0.1)
				(type default)
			)
			(layer "F.Fab")
		)
		(fp_line
			(start -0.12065 0.3048)
			(end -0.67945 0.3048)
			(stroke
				(width 0.1)
				(type default)
			)
			(layer "F.Fab")
		)
		(fp_line
			(start 0.120396 0.2794)
			(end -0.12065 0.2794)
			(stroke
				(width 0.1)
				(type default)
			)
			(layer "F.Fab")
		)
		(fp_line
			(start 0.120396 0.3048)
			(end 0.120396 0.2794)
			(stroke
				(width 0.1)
				(type default)
			)
			(layer "F.Fab")
		)
		(fp_line
			(start 0.12065 -0.3048)
			(end 0.67945 -0.3048)
			(stroke
				(width 0.1)
				(type default)
			)
			(layer "F.Fab")
		)
		(fp_line
			(start 0.12065 -0.2794)
			(end 0.12065 -0.3048)
			(stroke
				(width 0.1)
				(type default)
			)
			(layer "F.Fab")
		)
		(fp_line
			(start 0.67945 -0.3048)
			(end 0.67945 0.3048)
			(stroke
				(width 0.1)
				(type default)
			)
			(layer "F.Fab")
		)
		(fp_line
			(start 0.67945 0.3048)
			(end 0.120396 0.3048)
			(stroke
				(width 0.1)
				(type default)
			)
			(layer "F.Fab")
		)
		(pad "1" smd circle
			(at -0.40005 0)
			(size 0 0)
			(layers "F.Cu" "F.Mask" "F.Paste")
			(net "P12V_AUX")
		)
		(pad "2" smd circle
			(at 0.40005 0)
			(size 0 0)
			(layers "F.Cu" "F.Mask" "F.Paste")
			(net "P12V_E1S_OV_FB_0")
		)
	)
	(footprint ""
		(layer "F.Cu")
		(at 212.4202 -107.4166 90)
		(property "Reference" "R4776"
			(at 0 0 90)
			(layer "F.SilkS")
			(hide yes)
			(effects
				(font
					(size 1.27 1.27)
				)
			)
		)
		(property "Value" ""
			(at 0 0 90)
			(layer "F.Fab")
			(effects
				(font
					(size 1.27 1.27)
				)
			)
		)
		(duplicate_pad_numbers_are_jumpers no)
		(fp_line
			(start 0.7874 -0.4064)
			(end 0.7874 0.4064)
			(stroke
				(width 0.1524)
				(type default)
			)
			(layer "F.SilkS")
		)
		(fp_line
			(start -0.7874 -0.4064)
			(end 0.7874 -0.4064)
			(stroke
				(width 0.1524)
				(type default)
			)
			(layer "F.SilkS")
		)
		(fp_line
			(start 0.7874 0.4064)
			(end -0.7874 0.4064)
			(stroke
				(width 0.1524)
				(type default)
			)
			(layer "F.SilkS")
		)
		(fp_line
			(start -0.7874 0.4064)
			(end -0.7874 -0.4064)
			(stroke
				(width 0.1524)
				(type default)
			)
			(layer "F.SilkS")
		)
		(fp_line
			(start -0.12065 -0.305054)
			(end -0.12065 -0.2794)
			(stroke
				(width 0.1)
				(type default)
			)
			(layer "F.Fab")
		)
		(fp_line
			(start -0.67945 -0.305054)
			(end -0.12065 -0.305054)
			(stroke
				(width 0.1)
				(type default)
			)
			(layer "F.Fab")
		)
		(fp_line
			(start 0.67945 -0.3048)
			(end 0.67945 0.3048)
			(stroke
				(width 0.1)
				(type default)
			)
			(layer "F.Fab")
		)
		(fp_line
			(start 0.12065 -0.3048)
			(end 0.67945 -0.3048)
			(stroke
				(width 0.1)
				(type default)
			)
			(layer "F.Fab")
		)
		(fp_line
			(start 0.12065 -0.2794)
			(end 0.12065 -0.3048)
			(stroke
				(width 0.1)
				(type default)
			)
			(layer "F.Fab")
		)
		(fp_line
			(start -0.12065 -0.2794)
			(end 0.12065 -0.2794)
			(stroke
				(width 0.1)
				(type default)
			)
			(layer "F.Fab")
		)
		(fp_line
			(start 0.120396 0.2794)
			(end -0.12065 0.2794)
			(stroke
				(width 0.1)
				(type default)
			)
			(layer "F.Fab")
		)
		(fp_line
			(start -0.12065 0.2794)
			(end -0.12065 0.3048)
			(stroke
				(width 0.1)
				(type default)
			)
			(layer "F.Fab")
		)
		(fp_line
			(start 0.67945 0.3048)
			(end 0.120396 0.3048)
			(stroke
				(width 0.1)
				(type default)
			)
			(layer "F.Fab")
		)
		(fp_line
			(start 0.120396 0.3048)
			(end 0.120396 0.2794)
			(stroke
				(width 0.1)
				(type default)
			)
			(layer "F.Fab")
		)
		(fp_line
			(start -0.12065 0.3048)
			(end -0.67945 0.3048)
			(stroke
				(width 0.1)
				(type default)
			)
			(layer "F.Fab")
		)
		(fp_line
			(start -0.67945 0.3048)
			(end -0.67945 -0.305054)
			(stroke
				(width 0.1)
				(type default)
			)
			(layer "F.Fab")
		)
		(pad "1" smd circle
			(at -0.40005 0 90)
			(size 0 0)
			(layers "F.Cu" "F.Mask" "F.Paste")
			(net "P12V_AUX")
		)
		(pad "2" smd circle
			(at 0.40005 0 90)
			(size 0 0)
			(layers "F.Cu" "F.Mask" "F.Paste")
			(net "P12V_AUX_UV_TRIGGER")
		)
	)
	(footprint ""
		(layer "F.Cu")
		(at 32.353758 -138.03757 90)
		(property "Reference" "PR4242"
			(at 0 0 90)
			(layer "F.SilkS")
			(hide yes)
			(effects
				(font
					(size 1.27 1.27)
				)
			)
		)
		(property "Value" ""
			(at 0 0 90)
			(layer "F.Fab")
			(effects
				(font
					(size 1.27 1.27)
				)
			)
		)
		(duplicate_pad_numbers_are_jumpers no)
		(fp_line
			(start 0.7874 -0.4064)
			(end 0.7874 0.4064)
			(stroke
				(width 0.1524)
				(type default)
			)
			(layer "F.SilkS")
		)
		(fp_line
			(start -0.7874 -0.4064)
			(end 0.7874 -0.4064)
			(stroke
				(width 0.1524)
				(type default)
			)
			(layer "F.SilkS")
		)
		(fp_line
			(start 0.7874 0.4064)
			(end -0.7874 0.4064)
			(stroke
				(width 0.1524)
				(type default)
			)
			(layer "F.SilkS")
		)
		(fp_line
			(start -0.7874 0.4064)
			(end -0.7874 -0.4064)
			(stroke
				(width 0.1524)
				(type default)
			)
			(layer "F.SilkS")
		)
		(fp_line
			(start -0.12065 -0.305054)
			(end -0.12065 -0.2794)
			(stroke
				(width 0.1)
				(type default)
			)
			(layer "F.Fab")
		)
		(fp_line
			(start -0.67945 -0.305054)
			(end -0.12065 -0.305054)
			(stroke
				(width 0.1)
				(type default)
			)
			(layer "F.Fab")
		)
		(fp_line
			(start 0.67945 -0.3048)
			(end 0.67945 0.3048)
			(stroke
				(width 0.1)
				(type default)
			)
			(layer "F.Fab")
		)
		(fp_line
			(start 0.12065 -0.3048)
			(end 0.67945 -0.3048)
			(stroke
				(width 0.1)
				(type default)
			)
			(layer "F.Fab")
		)
		(fp_line
			(start 0.12065 -0.2794)
			(end 0.12065 -0.3048)
			(stroke
				(width 0.1)
				(type default)
			)
			(layer "F.Fab")
		)
		(fp_line
			(start -0.12065 -0.2794)
			(end 0.12065 -0.2794)
			(stroke
				(width 0.1)
				(type default)
			)
			(layer "F.Fab")
		)
		(fp_line
			(start 0.120396 0.2794)
			(end -0.12065 0.2794)
			(stroke
				(width 0.1)
				(type default)
			)
			(layer "F.Fab")
		)
		(fp_line
			(start -0.12065 0.2794)
			(end -0.12065 0.3048)
			(stroke
				(width 0.1)
				(type default)
			)
			(layer "F.Fab")
		)
		(fp_line
			(start 0.67945 0.3048)
			(end 0.120396 0.3048)
			(stroke
				(width 0.1)
				(type default)
			)
			(layer "F.Fab")
		)
		(fp_line
			(start 0.120396 0.3048)
			(end 0.120396 0.2794)
			(stroke
				(width 0.1)
				(type default)
			)
			(layer "F.Fab")
		)
		(fp_line
			(start -0.12065 0.3048)
			(end -0.67945 0.3048)
			(stroke
				(width 0.1)
				(type default)
			)
			(layer "F.Fab")
		)
		(fp_line
			(start -0.67945 0.3048)
			(end -0.67945 -0.305054)
			(stroke
				(width 0.1)
				(type default)
			)
			(layer "F.Fab")
		)
		(pad "1" smd circle
			(at -0.40005 0 90)
			(size 0 0)
			(layers "F.Cu" "F.Mask" "F.Paste")
			(net "NC_PVCCINFAON_CPU1_ACSP3")
		)
		(pad "2" smd circle
			(at 0.40005 0 90)
			(size 0 0)
			(layers "F.Cu" "F.Mask" "F.Paste")
			(net "GND")
		)
	)
	(footprint ""
		(layer "F.Cu")
		(at 257.176524 -108.154216 90)
		(property "Reference" "R553"
			(at 0 0 90)
			(layer "F.SilkS")
			(hide yes)
			(effects
				(font
					(size 1.27 1.27)
				)
			)
		)
		(property "Value" ""
			(at 0 0 90)
			(layer "F.Fab")
			(effects
				(font
					(size 1.27 1.27)
				)
			)
		)
		(duplicate_pad_numbers_are_jumpers no)
		(fp_line
			(start 0.7874 -0.4064)
			(end 0.7874 0.4064)
			(stroke
				(width 0.1524)
				(type default)
			)
			(layer "F.SilkS")
		)
		(fp_line
			(start -0.7874 -0.4064)
			(end 0.7874 -0.4064)
			(stroke
				(width 0.1524)
				(type default)
			)
			(layer "F.SilkS")
		)
		(fp_line
			(start 0.7874 0.4064)
			(end -0.7874 0.4064)
			(stroke
				(width 0.1524)
				(type default)
			)
			(layer "F.SilkS")
		)
		(fp_line
			(start -0.7874 0.4064)
			(end -0.7874 -0.4064)
			(stroke
				(width 0.1524)
				(type default)
			)
			(layer "F.SilkS")
		)
		(fp_line
			(start -0.12065 -0.305054)
			(end -0.12065 -0.2794)
			(stroke
				(width 0.1)
				(type default)
			)
			(layer "F.Fab")
		)
		(fp_line
			(start -0.67945 -0.305054)
			(end -0.12065 -0.305054)
			(stroke
				(width 0.1)
				(type default)
			)
			(layer "F.Fab")
		)
		(fp_line
			(start 0.67945 -0.3048)
			(end 0.67945 0.3048)
			(stroke
				(width 0.1)
				(type default)
			)
			(layer "F.Fab")
		)
		(fp_line
			(start 0.12065 -0.3048)
			(end 0.67945 -0.3048)
			(stroke
				(width 0.1)
				(type default)
			)
			(layer "F.Fab")
		)
		(fp_line
			(start 0.12065 -0.2794)
			(end 0.12065 -0.3048)
			(stroke
				(width 0.1)
				(type default)
			)
			(layer "F.Fab")
		)
		(fp_line
			(start -0.12065 -0.2794)
			(end 0.12065 -0.2794)
			(stroke
				(width 0.1)
				(type default)
			)
			(layer "F.Fab")
		)
		(fp_line
			(start 0.120396 0.2794)
			(end -0.12065 0.2794)
			(stroke
				(width 0.1)
				(type default)
			)
			(layer "F.Fab")
		)
		(fp_line
			(start -0.12065 0.2794)
			(end -0.12065 0.3048)
			(stroke
				(width 0.1)
				(type default)
			)
			(layer "F.Fab")
		)
		(fp_line
			(start 0.67945 0.3048)
			(end 0.120396 0.3048)
			(stroke
				(width 0.1)
				(type default)
			)
			(layer "F.Fab")
		)
		(fp_line
			(start 0.120396 0.3048)
			(end 0.120396 0.2794)
			(stroke
				(width 0.1)
				(type default)
			)
			(layer "F.Fab")
		)
		(fp_line
			(start -0.12065 0.3048)
			(end -0.67945 0.3048)
			(stroke
				(width 0.1)
				(type default)
			)
			(layer "F.Fab")
		)
		(fp_line
			(start -0.67945 0.3048)
			(end -0.67945 -0.305054)
			(stroke
				(width 0.1)
				(type default)
			)
			(layer "F.Fab")
		)
		(pad "1" smd circle
			(at -0.40005 0 90)
			(size 0 0)
			(layers "F.Cu" "F.Mask" "F.Paste")
			(net "CLK_100M_CK440_PCH_EXTCLK_R_DP")
		)
		(pad "2" smd circle
			(at 0.40005 0 90)
			(size 0 0)
			(layers "F.Cu" "F.Mask" "F.Paste")
			(net "CLK_100M_CK440_PCH_EXTCLK_DP")
		)
	)
	(footprint ""
		(layer "F.Cu")
		(at 190.41364 -68.407788 180)
		(property "Reference" "PC2197"
			(at 0 0 180)
			(layer "F.SilkS")
			(hide yes)
			(effects
				(font
					(size 1.27 1.27)
				)
			)
		)
		(property "Value" ""
			(at 0 0 180)
			(layer "F.Fab")
			(effects
				(font
					(size 1.27 1.27)
				)
			)
		)
		(duplicate_pad_numbers_are_jumpers no)
		(fp_line
			(start 0.7874 0.4064)
			(end -0.7874 0.4064)
			(stroke
				(width 0.1524)
				(type default)
			)
			(layer "F.SilkS")
		)
		(fp_line
			(start 0.7874 -0.4064)
			(end 0.7874 0.4064)
			(stroke
				(width 0.1524)
				(type default)
			)
			(layer "F.SilkS")
		)
		(fp_line
			(start -0.7874 0.4064)
			(end -0.7874 -0.4064)
			(stroke
				(width 0.1524)
				(type default)
			)
			(layer "F.SilkS")
		)
		(fp_line
			(start -0.7874 -0.4064)
			(end 0.7874 -0.4064)
			(stroke
				(width 0.1524)
				(type default)
			)
			(layer "F.SilkS")
		)
		(fp_line
			(start 0.67945 0.3048)
			(end 0.120396 0.3048)
			(stroke
				(width 0.1)
				(type default)
			)
			(layer "F.Fab")
		)
		(fp_line
			(start 0.67945 -0.3048)
			(end 0.67945 0.3048)
			(stroke
				(width 0.1)
				(type default)
			)
			(layer "F.Fab")
		)
		(fp_line
			(start 0.12065 -0.2794)
			(end 0.12065 -0.3048)
			(stroke
				(width 0.1)
				(type default)
			)
			(layer "F.Fab")
		)
		(fp_line
			(start 0.12065 -0.3048)
			(end 0.67945 -0.3048)
			(stroke
				(width 0.1)
				(type default)
			)
			(layer "F.Fab")
		)
		(fp_line
			(start 0.120396 0.3048)
			(end 0.120396 0.2794)
			(stroke
				(width 0.1)
				(type default)
			)
			(layer "F.Fab")
		)
		(fp_line
			(start 0.120396 0.2794)
			(end -0.12065 0.2794)
			(stroke
				(width 0.1)
				(type default)
			)
			(layer "F.Fab")
		)
		(fp_line
			(start -0.12065 0.3048)
			(end -0.67945 0.3048)
			(stroke
				(width 0.1)
				(type default)
			)
			(layer "F.Fab")
		)
		(fp_line
			(start -0.12065 0.2794)
			(end -0.12065 0.3048)
			(stroke
				(width 0.1)
				(type default)
			)
			(layer "F.Fab")
		)
		(fp_line
			(start -0.12065 -0.2794)
			(end 0.12065 -0.2794)
			(stroke
				(width 0.1)
				(type default)
			)
			(layer "F.Fab")
		)
		(fp_line
			(start -0.12065 -0.305054)
			(end -0.12065 -0.2794)
			(stroke
				(width 0.1)
				(type default)
			)
			(layer "F.Fab")
		)
		(fp_line
			(start -0.67945 0.3048)
			(end -0.67945 -0.305054)
			(stroke
				(width 0.1)
				(type default)
			)
			(layer "F.Fab")
		)
		(fp_line
			(start -0.67945 -0.305054)
			(end -0.12065 -0.305054)
			(stroke
				(width 0.1)
				(type default)
			)
			(layer "F.Fab")
		)
		(pad "1" smd circle
			(at -0.40005 0 180)
			(size 0 0)
			(layers "F.Cu" "F.Mask" "F.Paste")
			(net "P3V3_E1S_MODE_0")
		)
		(pad "2" smd circle
			(at 0.40005 0 180)
			(size 0 0)
			(layers "F.Cu" "F.Mask" "F.Paste")
			(net "GND")
		)
	)
	(footprint ""
		(layer "F.Cu")
		(at 110.181136 -70.79361)
		(property "Reference" "D84"
			(at -54.939946 50.186082 90)
			(unlocked yes)
			(layer "F.SilkS")
			(effects
				(font
					(size 0.635 0.4064)
					(thickness 0.1524)
				)
				(justify left)
			)
		)
		(property "Value" ""
			(at 0 0 0)
			(layer "F.Fab")
			(effects
				(font
					(size 1.27 1.27)
				)
			)
		)
		(duplicate_pad_numbers_are_jumpers no)
		(fp_line
			(start -0.90678 0.4826)
			(end -0.90678 -0.4699)
			(stroke
				(width 0.1524)
				(type default)
			)
			(layer "F.SilkS")
		)
		(fp_line
			(start -0.89408 -0.4826)
			(end 0.90678 -0.4826)
			(stroke
				(width 0.1524)
				(type default)
			)
			(layer "F.SilkS")
		)
		(fp_line
			(start -0.79248 -0.4826)
			(end 1.03378 -0.4826)
			(stroke
				(width 0.1524)
				(type default)
			)
			(layer "F.SilkS")
		)
		(fp_line
			(start -0.64008 -0.4826)
			(end 1.16078 -0.4826)
			(stroke
				(width 0.1524)
				(type default)
			)
			(layer "F.SilkS")
		)
		(fp_line
			(start 0.90678 -0.4826)
			(end 0.90678 0.4826)
			(stroke
				(width 0.1524)
				(type default)
			)
			(layer "F.SilkS")
		)
		(fp_line
			(start 0.90678 0.4826)
			(end -0.90678 0.4826)
			(stroke
				(width 0.1524)
				(type default)
			)
			(layer "F.SilkS")
		)
		(fp_line
			(start 1.03378 -0.4826)
			(end 1.03378 0.4826)
			(stroke
				(width 0.1524)
				(type default)
			)
			(layer "F.SilkS")
		)
		(fp_line
			(start 1.03378 0.4826)
			(end -0.79248 0.4826)
			(stroke
				(width 0.1524)
				(type default)
			)
			(layer "F.SilkS")
		)
		(fp_line
			(start 1.16078 -0.4826)
			(end 1.16078 0.4826)
			(stroke
				(width 0.1524)
				(type default)
			)
			(layer "F.SilkS")
		)
		(fp_line
			(start 1.16078 0.4826)
			(end -0.64008 0.4826)
			(stroke
				(width 0.1524)
				(type default)
			)
			(layer "F.SilkS")
		)
		(fp_line
			(start -0.499872 -0.249936)
			(end 0.499872 -0.249936)
			(stroke
				(width 0.1)
				(type default)
			)
			(layer "F.Fab")
		)
		(fp_line
			(start -0.499872 0.249936)
			(end -0.499872 -0.249936)
			(stroke
				(width 0.1)
				(type default)
			)
			(layer "F.Fab")
		)
		(fp_line
			(start 0.499872 -0.249936)
			(end 0.499872 0.249936)
			(stroke
				(width 0.1)
				(type default)
			)
			(layer "F.Fab")
		)
		(fp_line
			(start 0.499872 0.249936)
			(end -0.499872 0.249936)
			(stroke
				(width 0.1)
				(type default)
			)
			(layer "F.Fab")
		)
		(pad "A" smd rect
			(at -0.47498 0)
			(size 0.6096 0.7112)
			(layers "F.Cu" "F.Mask" "F.Paste")
			(net "LED_PWRGD_PVCCINFAON_CPU1")
		)
		(pad "C" smd rect
			(at 0.47498 0)
			(size 0.6096 0.7112)
			(layers "F.Cu" "F.Mask" "F.Paste")
			(net "LED_PWRGD_PVCCINFAON_CPU1_D")
		)
	)
	(footprint ""
		(layer "F.Cu")
		(at 133.20903 -337.214718 -90)
		(property "Reference" "PC508_P1_5"
			(at 0 0 270)
			(layer "F.SilkS")
			(hide yes)
			(effects
				(font
					(size 1.27 1.27)
				)
			)
		)
		(property "Value" ""
			(at 0 0 270)
			(layer "F.Fab")
			(effects
				(font
					(size 1.27 1.27)
				)
			)
		)
		(duplicate_pad_numbers_are_jumpers no)
		(fp_line
			(start -0.7874 0.4064)
			(end -0.7874 -0.4064)
			(stroke
				(width 0.1524)
				(type default)
			)
			(layer "F.SilkS")
		)
		(fp_line
			(start 0.7874 0.4064)
			(end -0.7874 0.4064)
			(stroke
				(width 0.1524)
				(type default)
			)
			(layer "F.SilkS")
		)
		(fp_line
			(start -0.7874 -0.4064)
			(end 0.7874 -0.4064)
			(stroke
				(width 0.1524)
				(type default)
			)
			(layer "F.SilkS")
		)
		(fp_line
			(start 0.7874 -0.4064)
			(end 0.7874 0.4064)
			(stroke
				(width 0.1524)
				(type default)
			)
			(layer "F.SilkS")
		)
		(fp_line
			(start -0.67945 0.3048)
			(end -0.67945 -0.305054)
			(stroke
				(width 0.1)
				(type default)
			)
			(layer "F.Fab")
		)
		(fp_line
			(start -0.12065 0.3048)
			(end -0.67945 0.3048)
			(stroke
				(width 0.1)
				(type default)
			)
			(layer "F.Fab")
		)
		(fp_line
			(start 0.120396 0.3048)
			(end 0.120396 0.2794)
			(stroke
				(width 0.1)
				(type default)
			)
			(layer "F.Fab")
		)
		(fp_line
			(start 0.67945 0.3048)
			(end 0.120396 0.3048)
			(stroke
				(width 0.1)
				(type default)
			)
			(layer "F.Fab")
		)
		(fp_line
			(start -0.12065 0.2794)
			(end -0.12065 0.3048)
			(stroke
				(width 0.1)
				(type default)
			)
			(layer "F.Fab")
		)
		(fp_line
			(start 0.120396 0.2794)
			(end -0.12065 0.2794)
			(stroke
				(width 0.1)
				(type default)
			)
			(layer "F.Fab")
		)
		(fp_line
			(start -0.12065 -0.2794)
			(end 0.12065 -0.2794)
			(stroke
				(width 0.1)
				(type default)
			)
			(layer "F.Fab")
		)
		(fp_line
			(start 0.12065 -0.2794)
			(end 0.12065 -0.3048)
			(stroke
				(width 0.1)
				(type default)
			)
			(layer "F.Fab")
		)
		(fp_line
			(start 0.12065 -0.3048)
			(end 0.67945 -0.3048)
			(stroke
				(width 0.1)
				(type default)
			)
			(layer "F.Fab")
		)
		(fp_line
			(start 0.67945 -0.3048)
			(end 0.67945 0.3048)
			(stroke
				(width 0.1)
				(type default)
			)
			(layer "F.Fab")
		)
		(fp_line
			(start -0.67945 -0.305054)
			(end -0.12065 -0.305054)
			(stroke
				(width 0.1)
				(type default)
			)
			(layer "F.Fab")
		)
		(fp_line
			(start -0.12065 -0.305054)
			(end -0.12065 -0.2794)
			(stroke
				(width 0.1)
				(type default)
			)
			(layer "F.Fab")
		)
		(pad "1" smd circle
			(at -0.40005 0 270)
			(size 0 0)
			(layers "F.Cu" "F.Mask" "F.Paste")
			(net "SW_P12V_PVCCIN_CPU1_FLT")
		)
		(pad "2" smd circle
			(at 0.40005 0 270)
			(size 0 0)
			(layers "F.Cu" "F.Mask" "F.Paste")
			(net "GND")
		)
	)
	(footprint ""
		(layer "F.Cu")
		(at 111.24946 -418.027358 90)
		(property "Reference" "R2660"
			(at 0 0 90)
			(layer "F.SilkS")
			(hide yes)
			(effects
				(font
					(size 1.27 1.27)
				)
			)
		)
		(property "Value" ""
			(at 0 0 90)
			(layer "F.Fab")
			(effects
				(font
					(size 1.27 1.27)
				)
			)
		)
		(duplicate_pad_numbers_are_jumpers no)
		(fp_line
			(start 0.7874 -0.4064)
			(end 0.7874 0.03556)
			(stroke
				(width 0.1524)
				(type default)
			)
			(layer "F.SilkS")
		)
		(fp_line
			(start -0.7874 -0.4064)
			(end 0.7874 -0.4064)
			(stroke
				(width 0.1524)
				(type default)
			)
			(layer "F.SilkS")
		)
		(fp_line
			(start -0.7874 -0.0127)
			(end -0.7874 -0.4064)
			(stroke
				(width 0.1524)
				(type default)
			)
			(layer "F.SilkS")
		)
		(fp_line
			(start 0.35941 0.4064)
			(end -0.39751 0.4064)
			(stroke
				(width 0.1524)
				(type default)
			)
			(layer "F.SilkS")
		)
		(fp_line
			(start -0.12065 -0.305054)
			(end -0.12065 -0.2794)
			(stroke
				(width 0.1)
				(type default)
			)
			(layer "F.Fab")
		)
		(fp_line
			(start -0.67945 -0.305054)
			(end -0.12065 -0.305054)
			(stroke
				(width 0.1)
				(type default)
			)
			(layer "F.Fab")
		)
		(fp_line
			(start 0.67945 -0.3048)
			(end 0.67945 0.3048)
			(stroke
				(width 0.1)
				(type default)
			)
			(layer "F.Fab")
		)
		(fp_line
			(start 0.12065 -0.3048)
			(end 0.67945 -0.3048)
			(stroke
				(width 0.1)
				(type default)
			)
			(layer "F.Fab")
		)
		(fp_line
			(start 0.12065 -0.2794)
			(end 0.12065 -0.3048)
			(stroke
				(width 0.1)
				(type default)
			)
			(layer "F.Fab")
		)
		(fp_line
			(start -0.12065 -0.2794)
			(end 0.12065 -0.2794)
			(stroke
				(width 0.1)
				(type default)
			)
			(layer "F.Fab")
		)
		(fp_line
			(start 0.120396 0.2794)
			(end -0.12065 0.2794)
			(stroke
				(width 0.1)
				(type default)
			)
			(layer "F.Fab")
		)
		(fp_line
			(start -0.12065 0.2794)
			(end -0.12065 0.3048)
			(stroke
				(width 0.1)
				(type default)
			)
			(layer "F.Fab")
		)
		(fp_line
			(start 0.67945 0.3048)
			(end 0.120396 0.3048)
			(stroke
				(width 0.1)
				(type default)
			)
			(layer "F.Fab")
		)
		(fp_line
			(start 0.120396 0.3048)
			(end 0.120396 0.2794)
			(stroke
				(width 0.1)
				(type default)
			)
			(layer "F.Fab")
		)
		(fp_line
			(start -0.12065 0.3048)
			(end -0.67945 0.3048)
			(stroke
				(width 0.1)
				(type default)
			)
			(layer "F.Fab")
		)
		(fp_line
			(start -0.67945 0.3048)
			(end -0.67945 -0.305054)
			(stroke
				(width 0.1)
				(type default)
			)
			(layer "F.Fab")
		)
		(pad "1" smd circle
			(at -0.40005 0 90)
			(size 0 0)
			(layers "F.Cu" "F.Mask" "F.Paste")
			(net "CLK_100M_SWB_R_DN")
		)
		(pad "2" smd circle
			(at 0.40005 0 90)
			(size 0 0)
			(layers "F.Cu" "F.Mask" "F.Paste")
			(net "CLK_100M_SWB_DN")
		)
	)
	(footprint ""
		(layer "F.Cu")
		(at 148.98243 -79.139034)
		(property "Reference" "R3130"
			(at 0 0 0)
			(layer "F.SilkS")
			(hide yes)
			(effects
				(font
					(size 1.27 1.27)
				)
			)
		)
		(property "Value" ""
			(at 0 0 0)
			(layer "F.Fab")
			(effects
				(font
					(size 1.27 1.27)
				)
			)
		)
		(duplicate_pad_numbers_are_jumpers no)
		(fp_line
			(start -0.7874 -0.4064)
			(end 0.7874 -0.4064)
			(stroke
				(width 0.1524)
				(type default)
			)
			(layer "F.SilkS")
		)
		(fp_line
			(start -0.7874 0.4064)
			(end -0.7874 -0.4064)
			(stroke
				(width 0.1524)
				(type default)
			)
			(layer "F.SilkS")
		)
		(fp_line
			(start 0.7874 -0.4064)
			(end 0.7874 0.4064)
			(stroke
				(width 0.1524)
				(type default)
			)
			(layer "F.SilkS")
		)
		(fp_line
			(start 0.7874 0.4064)
			(end -0.7874 0.4064)
			(stroke
				(width 0.1524)
				(type default)
			)
			(layer "F.SilkS")
		)
		(fp_line
			(start -0.67945 -0.305054)
			(end -0.12065 -0.305054)
			(stroke
				(width 0.1)
				(type default)
			)
			(layer "F.Fab")
		)
		(fp_line
			(start -0.67945 0.3048)
			(end -0.67945 -0.305054)
			(stroke
				(width 0.1)
				(type default)
			)
			(layer "F.Fab")
		)
		(fp_line
			(start -0.12065 -0.305054)
			(end -0.12065 -0.2794)
			(stroke
				(width 0.1)
				(type default)
			)
			(layer "F.Fab")
		)
		(fp_line
			(start -0.12065 -0.2794)
			(end 0.12065 -0.2794)
			(stroke
				(width 0.1)
				(type default)
			)
			(layer "F.Fab")
		)
		(fp_line
			(start -0.12065 0.2794)
			(end -0.12065 0.3048)
			(stroke
				(width 0.1)
				(type default)
			)
			(layer "F.Fab")
		)
		(fp_line
			(start -0.12065 0.3048)
			(end -0.67945 0.3048)
			(stroke
				(width 0.1)
				(type default)
			)
			(layer "F.Fab")
		)
		(fp_line
			(start 0.120396 0.2794)
			(end -0.12065 0.2794)
			(stroke
				(width 0.1)
				(type default)
			)
			(layer "F.Fab")
		)
		(fp_line
			(start 0.120396 0.3048)
			(end 0.120396 0.2794)
			(stroke
				(width 0.1)
				(type default)
			)
			(layer "F.Fab")
		)
		(fp_line
			(start 0.12065 -0.3048)
			(end 0.67945 -0.3048)
			(stroke
				(width 0.1)
				(type default)
			)
			(layer "F.Fab")
		)
		(fp_line
			(start 0.12065 -0.2794)
			(end 0.12065 -0.3048)
			(stroke
				(width 0.1)
				(type default)
			)
			(layer "F.Fab")
		)
		(fp_line
			(start 0.67945 -0.3048)
			(end 0.67945 0.3048)
			(stroke
				(width 0.1)
				(type default)
			)
			(layer "F.Fab")
		)
		(fp_line
			(start 0.67945 0.3048)
			(end 0.120396 0.3048)
			(stroke
				(width 0.1)
				(type default)
			)
			(layer "F.Fab")
		)
		(pad "1" smd circle
			(at -0.40005 0)
			(size 0 0)
			(layers "F.Cu" "F.Mask" "F.Paste")
			(net "P3V3_AUX")
		)
		(pad "2" smd circle
			(at 0.40005 0)
			(size 0 0)
			(layers "F.Cu" "F.Mask" "F.Paste")
			(net "PCA9543_S3M_INT2_N")
		)
	)
	(footprint ""
		(layer "F.Cu")
		(at 148.613114 -402.371052 -90)
		(property "Reference" "C760"
			(at 0 0 270)
			(layer "F.SilkS")
			(hide yes)
			(effects
				(font
					(size 1.27 1.27)
				)
			)
		)
		(property "Value" ""
			(at 0 0 270)
			(layer "F.Fab")
			(effects
				(font
					(size 1.27 1.27)
				)
			)
		)
		(duplicate_pad_numbers_are_jumpers no)
		(fp_line
			(start -0.299974 0.150114)
			(end -0.299974 -0.150114)
			(stroke
				(width 0.1)
				(type default)
			)
			(layer "F.Fab")
		)
		(fp_line
			(start 0.299974 0.150114)
			(end -0.299974 0.150114)
			(stroke
				(width 0.1)
				(type default)
			)
			(layer "F.Fab")
		)
		(fp_line
			(start -0.299974 -0.150114)
			(end 0.299974 -0.150114)
			(stroke
				(width 0.1)
				(type default)
			)
			(layer "F.Fab")
		)
		(fp_line
			(start 0.299974 -0.150114)
			(end 0.299974 0.150114)
			(stroke
				(width 0.1)
				(type default)
			)
			(layer "F.Fab")
		)
		(pad "1" smd rect
			(at -0.2667 0 270)
			(size 0.3048 0.381)
			(layers "F.Cu" "F.Mask" "F.Paste")
			(net "P5E_CPU1_PE2_TX_C_DN<6>")
		)
		(pad "2" smd rect
			(at 0.2667 0 270)
			(size 0.3048 0.381)
			(layers "F.Cu" "F.Mask" "F.Paste")
			(net "P5E_CPU1_PE2_TX_DN<6>")
		)
	)
	(footprint ""
		(layer "F.Cu")
		(at 390.42594 -343.018872 -90)
		(property "Reference" "PC230_P0_8"
			(at 0 0 270)
			(layer "F.SilkS")
			(hide yes)
			(effects
				(font
					(size 1.27 1.27)
				)
			)
		)
		(property "Value" ""
			(at 0 0 270)
			(layer "F.Fab")
			(effects
				(font
					(size 1.27 1.27)
				)
			)
		)
		(duplicate_pad_numbers_are_jumpers no)
		(fp_line
			(start -0.7874 0.4064)
			(end -0.7874 -0.4064)
			(stroke
				(width 0.1524)
				(type default)
			)
			(layer "F.SilkS")
		)
		(fp_line
			(start 0.7874 0.4064)
			(end -0.7874 0.4064)
			(stroke
				(width 0.1524)
				(type default)
			)
			(layer "F.SilkS")
		)
		(fp_line
			(start -0.7874 -0.4064)
			(end 0.7874 -0.4064)
			(stroke
				(width 0.1524)
				(type default)
			)
			(layer "F.SilkS")
		)
		(fp_line
			(start 0.7874 -0.4064)
			(end 0.7874 0.4064)
			(stroke
				(width 0.1524)
				(type default)
			)
			(layer "F.SilkS")
		)
		(fp_line
			(start -0.67945 0.3048)
			(end -0.67945 -0.305054)
			(stroke
				(width 0.1)
				(type default)
			)
			(layer "F.Fab")
		)
		(fp_line
			(start -0.12065 0.3048)
			(end -0.67945 0.3048)
			(stroke
				(width 0.1)
				(type default)
			)
			(layer "F.Fab")
		)
		(fp_line
			(start 0.120396 0.3048)
			(end 0.120396 0.2794)
			(stroke
				(width 0.1)
				(type default)
			)
			(layer "F.Fab")
		)
		(fp_line
			(start 0.67945 0.3048)
			(end 0.120396 0.3048)
			(stroke
				(width 0.1)
				(type default)
			)
			(layer "F.Fab")
		)
		(fp_line
			(start -0.12065 0.2794)
			(end -0.12065 0.3048)
			(stroke
				(width 0.1)
				(type default)
			)
			(layer "F.Fab")
		)
		(fp_line
			(start 0.120396 0.2794)
			(end -0.12065 0.2794)
			(stroke
				(width 0.1)
				(type default)
			)
			(layer "F.Fab")
		)
		(fp_line
			(start -0.12065 -0.2794)
			(end 0.12065 -0.2794)
			(stroke
				(width 0.1)
				(type default)
			)
			(layer "F.Fab")
		)
		(fp_line
			(start 0.12065 -0.2794)
			(end 0.12065 -0.3048)
			(stroke
				(width 0.1)
				(type default)
			)
			(layer "F.Fab")
		)
		(fp_line
			(start 0.12065 -0.3048)
			(end 0.67945 -0.3048)
			(stroke
				(width 0.1)
				(type default)
			)
			(layer "F.Fab")
		)
		(fp_line
			(start 0.67945 -0.3048)
			(end 0.67945 0.3048)
			(stroke
				(width 0.1)
				(type default)
			)
			(layer "F.Fab")
		)
		(fp_line
			(start -0.67945 -0.305054)
			(end -0.12065 -0.305054)
			(stroke
				(width 0.1)
				(type default)
			)
			(layer "F.Fab")
		)
		(fp_line
			(start -0.12065 -0.305054)
			(end -0.12065 -0.2794)
			(stroke
				(width 0.1)
				(type default)
			)
			(layer "F.Fab")
		)
		(pad "1" smd circle
			(at -0.40005 0 270)
			(size 0 0)
			(layers "F.Cu" "F.Mask" "F.Paste")
			(net "SW_P12V_PVCCIN_CPU0_FLT")
		)
		(pad "2" smd circle
			(at 0.40005 0 270)
			(size 0 0)
			(layers "F.Cu" "F.Mask" "F.Paste")
			(net "GND")
		)
	)
	(footprint ""
		(layer "F.Cu")
		(at 276.80666 -424.424602 180)
		(property "Reference" "R4671"
			(at 0 0 180)
			(layer "F.SilkS")
			(hide yes)
			(effects
				(font
					(size 1.27 1.27)
				)
			)
		)
		(property "Value" ""
			(at 0 0 180)
			(layer "F.Fab")
			(effects
				(font
					(size 1.27 1.27)
				)
			)
		)
		(duplicate_pad_numbers_are_jumpers no)
		(fp_line
			(start 0.7874 0.4064)
			(end -0.7874 0.4064)
			(stroke
				(width 0.1524)
				(type default)
			)
			(layer "F.SilkS")
		)
		(fp_line
			(start 0.7874 -0.4064)
			(end 0.7874 0.4064)
			(stroke
				(width 0.1524)
				(type default)
			)
			(layer "F.SilkS")
		)
		(fp_line
			(start -0.7874 0.4064)
			(end -0.7874 -0.4064)
			(stroke
				(width 0.1524)
				(type default)
			)
			(layer "F.SilkS")
		)
		(fp_line
			(start -0.7874 -0.4064)
			(end 0.7874 -0.4064)
			(stroke
				(width 0.1524)
				(type default)
			)
			(layer "F.SilkS")
		)
		(fp_line
			(start 0.67945 0.3048)
			(end 0.120396 0.3048)
			(stroke
				(width 0.1)
				(type default)
			)
			(layer "F.Fab")
		)
		(fp_line
			(start 0.67945 -0.3048)
			(end 0.67945 0.3048)
			(stroke
				(width 0.1)
				(type default)
			)
			(layer "F.Fab")
		)
		(fp_line
			(start 0.12065 -0.2794)
			(end 0.12065 -0.3048)
			(stroke
				(width 0.1)
				(type default)
			)
			(layer "F.Fab")
		)
		(fp_line
			(start 0.12065 -0.3048)
			(end 0.67945 -0.3048)
			(stroke
				(width 0.1)
				(type default)
			)
			(layer "F.Fab")
		)
		(fp_line
			(start 0.120396 0.3048)
			(end 0.120396 0.2794)
			(stroke
				(width 0.1)
				(type default)
			)
			(layer "F.Fab")
		)
		(fp_line
			(start 0.120396 0.2794)
			(end -0.12065 0.2794)
			(stroke
				(width 0.1)
				(type default)
			)
			(layer "F.Fab")
		)
		(fp_line
			(start -0.12065 0.3048)
			(end -0.67945 0.3048)
			(stroke
				(width 0.1)
				(type default)
			)
			(layer "F.Fab")
		)
		(fp_line
			(start -0.12065 0.2794)
			(end -0.12065 0.3048)
			(stroke
				(width 0.1)
				(type default)
			)
			(layer "F.Fab")
		)
		(fp_line
			(start -0.12065 -0.2794)
			(end 0.12065 -0.2794)
			(stroke
				(width 0.1)
				(type default)
			)
			(layer "F.Fab")
		)
		(fp_line
			(start -0.12065 -0.305054)
			(end -0.12065 -0.2794)
			(stroke
				(width 0.1)
				(type default)
			)
			(layer "F.Fab")
		)
		(fp_line
			(start -0.67945 0.3048)
			(end -0.67945 -0.305054)
			(stroke
				(width 0.1)
				(type default)
			)
			(layer "F.Fab")
		)
		(fp_line
			(start -0.67945 -0.305054)
			(end -0.12065 -0.305054)
			(stroke
				(width 0.1)
				(type default)
			)
			(layer "F.Fab")
		)
		(pad "1" smd circle
			(at -0.40005 0 180)
			(size 0 0)
			(layers "F.Cu" "F.Mask" "F.Paste")
			(net "P3V3_AUX")
		)
		(pad "2" smd circle
			(at 0.40005 0 180)
			(size 0 0)
			(layers "F.Cu" "F.Mask" "F.Paste")
			(net "HSC_D_OC")
		)
	)
	(footprint ""
		(layer "F.Cu")
		(at 426.73016 -143.675608 90)
		(property "Reference" "PR4221"
			(at 0 0 90)
			(layer "F.SilkS")
			(hide yes)
			(effects
				(font
					(size 1.27 1.27)
				)
			)
		)
		(property "Value" ""
			(at 0 0 90)
			(layer "F.Fab")
			(effects
				(font
					(size 1.27 1.27)
				)
			)
		)
		(duplicate_pad_numbers_are_jumpers no)
		(fp_line
			(start 0.7874 -0.4064)
			(end 0.7874 0.4064)
			(stroke
				(width 0.1524)
				(type default)
			)
			(layer "F.SilkS")
		)
		(fp_line
			(start -0.7874 -0.4064)
			(end 0.7874 -0.4064)
			(stroke
				(width 0.1524)
				(type default)
			)
			(layer "F.SilkS")
		)
		(fp_line
			(start 0.7874 0.4064)
			(end -0.7874 0.4064)
			(stroke
				(width 0.1524)
				(type default)
			)
			(layer "F.SilkS")
		)
		(fp_line
			(start -0.7874 0.4064)
			(end -0.7874 -0.4064)
			(stroke
				(width 0.1524)
				(type default)
			)
			(layer "F.SilkS")
		)
		(fp_line
			(start -0.12065 -0.305054)
			(end -0.12065 -0.2794)
			(stroke
				(width 0.1)
				(type default)
			)
			(layer "F.Fab")
		)
		(fp_line
			(start -0.67945 -0.305054)
			(end -0.12065 -0.305054)
			(stroke
				(width 0.1)
				(type default)
			)
			(layer "F.Fab")
		)
		(fp_line
			(start 0.67945 -0.3048)
			(end 0.67945 0.3048)
			(stroke
				(width 0.1)
				(type default)
			)
			(layer "F.Fab")
		)
		(fp_line
			(start 0.12065 -0.3048)
			(end 0.67945 -0.3048)
			(stroke
				(width 0.1)
				(type default)
			)
			(layer "F.Fab")
		)
		(fp_line
			(start 0.12065 -0.2794)
			(end 0.12065 -0.3048)
			(stroke
				(width 0.1)
				(type default)
			)
			(layer "F.Fab")
		)
		(fp_line
			(start -0.12065 -0.2794)
			(end 0.12065 -0.2794)
			(stroke
				(width 0.1)
				(type default)
			)
			(layer "F.Fab")
		)
		(fp_line
			(start 0.120396 0.2794)
			(end -0.12065 0.2794)
			(stroke
				(width 0.1)
				(type default)
			)
			(layer "F.Fab")
		)
		(fp_line
			(start -0.12065 0.2794)
			(end -0.12065 0.3048)
			(stroke
				(width 0.1)
				(type default)
			)
			(layer "F.Fab")
		)
		(fp_line
			(start 0.67945 0.3048)
			(end 0.120396 0.3048)
			(stroke
				(width 0.1)
				(type default)
			)
			(layer "F.Fab")
		)
		(fp_line
			(start 0.120396 0.3048)
			(end 0.120396 0.2794)
			(stroke
				(width 0.1)
				(type default)
			)
			(layer "F.Fab")
		)
		(fp_line
			(start -0.12065 0.3048)
			(end -0.67945 0.3048)
			(stroke
				(width 0.1)
				(type default)
			)
			(layer "F.Fab")
		)
		(fp_line
			(start -0.67945 0.3048)
			(end -0.67945 -0.305054)
			(stroke
				(width 0.1)
				(type default)
			)
			(layer "F.Fab")
		)
		(pad "1" smd circle
			(at -0.40005 0 90)
			(size 0 0)
			(layers "F.Cu" "F.Mask" "F.Paste")
			(net "NC_PVCCINFAON_CPU0_ACSP3")
		)
		(pad "2" smd circle
			(at 0.40005 0 90)
			(size 0 0)
			(layers "F.Cu" "F.Mask" "F.Paste")
			(net "GND")
		)
	)
	(footprint ""
		(layer "F.Cu")
		(at 163.50488 -436.463948)
		(property "Reference" "R3451"
			(at 0 0 0)
			(layer "F.SilkS")
			(hide yes)
			(effects
				(font
					(size 1.27 1.27)
				)
			)
		)
		(property "Value" ""
			(at 0 0 0)
			(layer "F.Fab")
			(effects
				(font
					(size 1.27 1.27)
				)
			)
		)
		(duplicate_pad_numbers_are_jumpers no)
		(fp_line
			(start -0.7874 -0.4064)
			(end 0.7874 -0.4064)
			(stroke
				(width 0.1524)
				(type default)
			)
			(layer "F.SilkS")
		)
		(fp_line
			(start -0.7874 0.4064)
			(end -0.7874 -0.4064)
			(stroke
				(width 0.1524)
				(type default)
			)
			(layer "F.SilkS")
		)
		(fp_line
			(start 0.7874 -0.4064)
			(end 0.7874 0.4064)
			(stroke
				(width 0.1524)
				(type default)
			)
			(layer "F.SilkS")
		)
		(fp_line
			(start 0.7874 0.4064)
			(end -0.7874 0.4064)
			(stroke
				(width 0.1524)
				(type default)
			)
			(layer "F.SilkS")
		)
		(fp_line
			(start -0.67945 -0.305054)
			(end -0.12065 -0.305054)
			(stroke
				(width 0.1)
				(type default)
			)
			(layer "F.Fab")
		)
		(fp_line
			(start -0.67945 0.3048)
			(end -0.67945 -0.305054)
			(stroke
				(width 0.1)
				(type default)
			)
			(layer "F.Fab")
		)
		(fp_line
			(start -0.12065 -0.305054)
			(end -0.12065 -0.2794)
			(stroke
				(width 0.1)
				(type default)
			)
			(layer "F.Fab")
		)
		(fp_line
			(start -0.12065 -0.2794)
			(end 0.12065 -0.2794)
			(stroke
				(width 0.1)
				(type default)
			)
			(layer "F.Fab")
		)
		(fp_line
			(start -0.12065 0.2794)
			(end -0.12065 0.3048)
			(stroke
				(width 0.1)
				(type default)
			)
			(layer "F.Fab")
		)
		(fp_line
			(start -0.12065 0.3048)
			(end -0.67945 0.3048)
			(stroke
				(width 0.1)
				(type default)
			)
			(layer "F.Fab")
		)
		(fp_line
			(start 0.120396 0.2794)
			(end -0.12065 0.2794)
			(stroke
				(width 0.1)
				(type default)
			)
			(layer "F.Fab")
		)
		(fp_line
			(start 0.120396 0.3048)
			(end 0.120396 0.2794)
			(stroke
				(width 0.1)
				(type default)
			)
			(layer "F.Fab")
		)
		(fp_line
			(start 0.12065 -0.3048)
			(end 0.67945 -0.3048)
			(stroke
				(width 0.1)
				(type default)
			)
			(layer "F.Fab")
		)
		(fp_line
			(start 0.12065 -0.2794)
			(end 0.12065 -0.3048)
			(stroke
				(width 0.1)
				(type default)
			)
			(layer "F.Fab")
		)
		(fp_line
			(start 0.67945 -0.3048)
			(end 0.67945 0.3048)
			(stroke
				(width 0.1)
				(type default)
			)
			(layer "F.Fab")
		)
		(fp_line
			(start 0.67945 0.3048)
			(end 0.120396 0.3048)
			(stroke
				(width 0.1)
				(type default)
			)
			(layer "F.Fab")
		)
		(pad "1" smd circle
			(at -0.40005 0)
			(size 0 0)
			(layers "F.Cu" "F.Mask" "F.Paste")
			(net "P3V3_AUX")
		)
		(pad "2" smd circle
			(at 0.40005 0)
			(size 0 0)
			(layers "F.Cu" "F.Mask" "F.Paste")
			(net "GPU_BASE_STBY_EN")
		)
	)
	(footprint ""
		(layer "F.Cu")
		(at 309.522622 -30.343348 180)
		(property "Reference" "R1450"
			(at 0 0 180)
			(layer "F.SilkS")
			(hide yes)
			(effects
				(font
					(size 1.27 1.27)
				)
			)
		)
		(property "Value" ""
			(at 0 0 180)
			(layer "F.Fab")
			(effects
				(font
					(size 1.27 1.27)
				)
			)
		)
		(duplicate_pad_numbers_are_jumpers no)
		(fp_line
			(start 0.7874 0.4064)
			(end -0.7874 0.4064)
			(stroke
				(width 0.1524)
				(type default)
			)
			(layer "F.SilkS")
		)
		(fp_line
			(start 0.7874 -0.4064)
			(end 0.7874 0.4064)
			(stroke
				(width 0.1524)
				(type default)
			)
			(layer "F.SilkS")
		)
		(fp_line
			(start -0.7874 0.4064)
			(end -0.7874 -0.4064)
			(stroke
				(width 0.1524)
				(type default)
			)
			(layer "F.SilkS")
		)
		(fp_line
			(start -0.7874 -0.4064)
			(end 0.7874 -0.4064)
			(stroke
				(width 0.1524)
				(type default)
			)
			(layer "F.SilkS")
		)
		(fp_line
			(start 0.67945 0.3048)
			(end 0.120396 0.3048)
			(stroke
				(width 0.1)
				(type default)
			)
			(layer "F.Fab")
		)
		(fp_line
			(start 0.67945 -0.3048)
			(end 0.67945 0.3048)
			(stroke
				(width 0.1)
				(type default)
			)
			(layer "F.Fab")
		)
		(fp_line
			(start 0.12065 -0.2794)
			(end 0.12065 -0.3048)
			(stroke
				(width 0.1)
				(type default)
			)
			(layer "F.Fab")
		)
		(fp_line
			(start 0.12065 -0.3048)
			(end 0.67945 -0.3048)
			(stroke
				(width 0.1)
				(type default)
			)
			(layer "F.Fab")
		)
		(fp_line
			(start 0.120396 0.3048)
			(end 0.120396 0.2794)
			(stroke
				(width 0.1)
				(type default)
			)
			(layer "F.Fab")
		)
		(fp_line
			(start 0.120396 0.2794)
			(end -0.12065 0.2794)
			(stroke
				(width 0.1)
				(type default)
			)
			(layer "F.Fab")
		)
		(fp_line
			(start -0.12065 0.3048)
			(end -0.67945 0.3048)
			(stroke
				(width 0.1)
				(type default)
			)
			(layer "F.Fab")
		)
		(fp_line
			(start -0.12065 0.2794)
			(end -0.12065 0.3048)
			(stroke
				(width 0.1)
				(type default)
			)
			(layer "F.Fab")
		)
		(fp_line
			(start -0.12065 -0.2794)
			(end 0.12065 -0.2794)
			(stroke
				(width 0.1)
				(type default)
			)
			(layer "F.Fab")
		)
		(fp_line
			(start -0.12065 -0.305054)
			(end -0.12065 -0.2794)
			(stroke
				(width 0.1)
				(type default)
			)
			(layer "F.Fab")
		)
		(fp_line
			(start -0.67945 0.3048)
			(end -0.67945 -0.305054)
			(stroke
				(width 0.1)
				(type default)
			)
			(layer "F.Fab")
		)
		(fp_line
			(start -0.67945 -0.305054)
			(end -0.12065 -0.305054)
			(stroke
				(width 0.1)
				(type default)
			)
			(layer "F.Fab")
		)
		(pad "1" smd circle
			(at -0.40005 0 180)
			(size 0 0)
			(layers "F.Cu" "F.Mask" "F.Paste")
			(net "P3V3_AUX")
		)
		(pad "2" smd circle
			(at 0.40005 0 180)
			(size 0 0)
			(layers "F.Cu" "F.Mask" "F.Paste")
			(net "FM_THROTTLE_N")
		)
	)
	(footprint ""
		(layer "F.Cu")
		(at 94.045278 -102.509574 180)
		(property "Reference" "Q105"
			(at 3.089656 0.763016 0)
			(unlocked yes)
			(layer "F.SilkS")
			(effects
				(font
					(size 0.7874 0.5842)
					(thickness 0.1524)
				)
			)
		)
		(property "Value" ""
			(at 0 0 180)
			(layer "F.Fab")
			(effects
				(font
					(size 1.27 1.27)
				)
			)
		)
		(duplicate_pad_numbers_are_jumpers no)
		(fp_line
			(start 1.376172 1.199896)
			(end -1.376172 1.199896)
			(stroke
				(width 0.1524)
				(type default)
			)
			(layer "F.SilkS")
		)
		(fp_line
			(start 1.376172 -1.199896)
			(end 1.376172 1.199896)
			(stroke
				(width 0.1524)
				(type default)
			)
			(layer "F.SilkS")
		)
		(fp_line
			(start 0.508 -1.199896)
			(end 1.376172 -1.199896)
			(stroke
				(width 0.1524)
				(type default)
			)
			(layer "F.SilkS")
		)
		(fp_line
			(start 0 -0.762)
			(end 0.508 -1.199896)
			(stroke
				(width 0.1524)
				(type default)
			)
			(layer "F.SilkS")
		)
		(fp_line
			(start -0.508 -1.199896)
			(end 0 -0.762)
			(stroke
				(width 0.1524)
				(type default)
			)
			(layer "F.SilkS")
		)
		(fp_line
			(start -1.376172 1.199896)
			(end -1.376172 -1.199896)
			(stroke
				(width 0.1524)
				(type default)
			)
			(layer "F.SilkS")
		)
		(fp_line
			(start -1.376172 -1.199896)
			(end -0.508 -1.199896)
			(stroke
				(width 0.1524)
				(type default)
			)
			(layer "F.SilkS")
		)
		(fp_poly
			(pts
				(xy -1.4605 -0.7493) (xy -2.2225 -0.3683) (xy -2.2225 -1.1303)
			)
			(stroke
				(width 0)
				(type default)
			)
			(fill yes)
			(layer "F.SilkS")
		)
		(fp_line
			(start 0.674878 1.100074)
			(end -0.674878 1.100074)
			(stroke
				(width 0.1)
				(type default)
			)
			(layer "F.Fab")
		)
		(fp_line
			(start 0.674878 -1.100074)
			(end 0.674878 1.100074)
			(stroke
				(width 0.1)
				(type default)
			)
			(layer "F.Fab")
		)
		(fp_line
			(start -0.674878 1.100074)
			(end -0.674878 -1.100074)
			(stroke
				(width 0.1)
				(type default)
			)
			(layer "F.Fab")
		)
		(fp_line
			(start -0.674878 -1.100074)
			(end 0.674878 -1.100074)
			(stroke
				(width 0.1)
				(type default)
			)
			(layer "F.Fab")
		)
		(fp_poly
			(pts
				(xy -1.4605 -0.7493) (xy -2.2225 -1.1303) (xy -2.2225 -0.3683)
			)
			(stroke
				(width 0)
				(type default)
			)
			(fill yes)
			(layer "F.Fab")
		)
		(pad "1" smd rect
			(at -0.899922 -0.750062 90)
			(size 0.6096 0.6096)
			(layers "F.Cu" "F.Mask" "F.Paste")
			(net "GND")
		)
		(pad "2" smd rect
			(at -0.899922 0 90)
			(size 0.4064 0.6096)
			(layers "F.Cu" "F.Mask" "F.Paste")
			(net "RST_PLD_CPU1_DRAM_AB_N")
		)
		(pad "3" smd rect
			(at -0.899922 0.750062 90)
			(size 0.6096 0.6096)
			(layers "F.Cu" "F.Mask" "F.Paste")
			(net "Net_1467")
		)
		(pad "4" smd rect
			(at 0.899922 0.750062 90)
			(size 0.6096 0.6096)
			(layers "F.Cu" "F.Mask" "F.Paste")
			(net "Net_1469")
		)
		(pad "5" smd rect
			(at 0.899922 0 90)
			(size 0.4064 0.6096)
			(layers "F.Cu" "F.Mask" "F.Paste")
			(net "Net_1468")
		)
		(pad "6" smd rect
			(at 0.899922 -0.750062 90)
			(size 0.6096 0.6096)
			(layers "F.Cu" "F.Mask" "F.Paste")
			(net "LED_RST_PLD_CPU1_DRAM_AB_N_D")
		)
	)
	(footprint ""
		(layer "F.Cu")
		(at 56.349138 -362.656882)
		(property "Reference" "PC1678"
			(at 0 0 0)
			(layer "F.SilkS")
			(hide yes)
			(effects
				(font
					(size 1.27 1.27)
				)
			)
		)
		(property "Value" ""
			(at 0 0 0)
			(layer "F.Fab")
			(effects
				(font
					(size 1.27 1.27)
				)
			)
		)
		(duplicate_pad_numbers_are_jumpers no)
		(fp_line
			(start -1.524 -0.762)
			(end 1.524 -0.762)
			(stroke
				(width 0.1524)
				(type default)
			)
			(layer "F.SilkS")
		)
		(fp_line
			(start -1.524 0.762)
			(end -1.524 -0.762)
			(stroke
				(width 0.1524)
				(type default)
			)
			(layer "F.SilkS")
		)
		(fp_line
			(start 1.524 -0.762)
			(end 1.524 0.762)
			(stroke
				(width 0.1524)
				(type default)
			)
			(layer "F.SilkS")
		)
		(fp_line
			(start 1.524 0.762)
			(end -1.524 0.762)
			(stroke
				(width 0.1524)
				(type default)
			)
			(layer "F.SilkS")
		)
		(fp_line
			(start -1.1049 -0.724916)
			(end -1.1049 0.724916)
			(stroke
				(width 0.1)
				(type default)
			)
			(layer "F.Fab")
		)
		(fp_line
			(start -1.1049 0.724916)
			(end 1.1049 0.724916)
			(stroke
				(width 0.1)
				(type default)
			)
			(layer "F.Fab")
		)
		(fp_line
			(start 1.1049 -0.724916)
			(end -1.1049 -0.724916)
			(stroke
				(width 0.1)
				(type default)
			)
			(layer "F.Fab")
		)
		(fp_line
			(start 1.1049 0.724916)
			(end 1.1049 -0.724916)
			(stroke
				(width 0.1)
				(type default)
			)
			(layer "F.Fab")
		)
		(pad "1" smd rect
			(at -0.889 0 180)
			(size 1.016 1.27)
			(layers "F.Cu" "F.Mask" "F.Paste")
			(net "SW_P12V_PVCCFA_EHV_FIVRA_CPU1_L")
		)
		(pad "2" smd rect
			(at 0.889 0 180)
			(size 1.016 1.27)
			(layers "F.Cu" "F.Mask" "F.Paste")
			(net "GND")
		)
	)
	(footprint ""
		(layer "F.Cu")
		(at 167.899842 -160.50006)
		(property "Reference" "H86"
			(at -5.718302 -4.55549 0)
			(unlocked yes)
			(layer "F.SilkS")
			(effects
				(font
					(size 0.7874 0.5842)
					(thickness 0.1524)
				)
				(justify left)
			)
		)
		(property "Value" ""
			(at 0 0 0)
			(layer "F.Fab")
			(effects
				(font
					(size 1.27 1.27)
				)
			)
		)
		(duplicate_pad_numbers_are_jumpers no)
		(pad "1" thru_hole circle
			(at 0 0)
			(size 10.0076 10.0076)
			(drill 5.6134)
			(layers "*.Cu" "*.Mask")
			(remove_unused_layers no)
			(net "GND")
			(clearance -1.9431)
		)
	)
	(footprint ""
		(layer "F.Cu")
		(at 199.4916 -93.98 -90)
		(property "Reference" "U337"
			(at -2.159 0.701548 90)
			(unlocked yes)
			(layer "F.SilkS")
			(effects
				(font
					(size 0.7874 0.5842)
					(thickness 0.1524)
				)
				(justify left)
			)
		)
		(property "Value" ""
			(at 0 0 270)
			(layer "F.Fab")
			(effects
				(font
					(size 1.27 1.27)
				)
			)
		)
		(duplicate_pad_numbers_are_jumpers no)
		(fp_line
			(start -1.868424 1.519936)
			(end 1.868424 1.519936)
			(stroke
				(width 0.1524)
				(type default)
			)
			(layer "F.SilkS")
		)
		(fp_line
			(start 1.868424 1.519936)
			(end 1.868424 -1.519936)
			(stroke
				(width 0.1524)
				(type default)
			)
			(layer "F.SilkS")
		)
		(fp_line
			(start -1.868424 -1.519936)
			(end -1.868424 1.519936)
			(stroke
				(width 0.1524)
				(type default)
			)
			(layer "F.SilkS")
		)
		(fp_line
			(start 1.868424 -1.519936)
			(end -1.868424 -1.519936)
			(stroke
				(width 0.1524)
				(type default)
			)
			(layer "F.SilkS")
		)
		(fp_line
			(start -0.700024 1.519936)
			(end 0.700024 1.519936)
			(stroke
				(width 0.1)
				(type default)
			)
			(layer "F.Fab")
		)
		(fp_line
			(start 0.700024 1.519936)
			(end 0.700024 -1.519936)
			(stroke
				(width 0.1)
				(type default)
			)
			(layer "F.Fab")
		)
		(fp_line
			(start -0.700024 -1.519936)
			(end -0.700024 1.519936)
			(stroke
				(width 0.1)
				(type default)
			)
			(layer "F.Fab")
		)
		(fp_line
			(start 0.700024 -1.519936)
			(end -0.700024 -1.519936)
			(stroke
				(width 0.1)
				(type default)
			)
			(layer "F.Fab")
		)
		(pad "1" smd rect
			(at -1.18491 -0.94996 180)
			(size 0.6096 1.0668)
			(layers "F.Cu" "F.Mask" "F.Paste")
			(net "UV_ADR_P2V5_COMP")
		)
		(pad "2" smd rect
			(at -1.18491 0.94996 180)
			(size 0.6096 1.0668)
			(layers "F.Cu" "F.Mask" "F.Paste")
			(net "GND")
		)
		(pad "3" smd rect
			(at 1.18491 0 180)
			(size 0.6096 1.0668)
			(layers "F.Cu" "F.Mask" "F.Paste")
			(net "Net_8628")
		)
	)
	(footprint ""
		(layer "F.Cu")
		(at 27.598878 -16.099536 90)
		(property "Reference" "C814"
			(at 0 0 90)
			(layer "F.SilkS")
			(hide yes)
			(effects
				(font
					(size 1.27 1.27)
				)
			)
		)
		(property "Value" ""
			(at 0 0 90)
			(layer "F.Fab")
			(effects
				(font
					(size 1.27 1.27)
				)
			)
		)
		(duplicate_pad_numbers_are_jumpers no)
		(fp_line
			(start 0.299974 -0.150114)
			(end 0.299974 0.150114)
			(stroke
				(width 0.1)
				(type default)
			)
			(layer "F.Fab")
		)
		(fp_line
			(start -0.299974 -0.150114)
			(end 0.299974 -0.150114)
			(stroke
				(width 0.1)
				(type default)
			)
			(layer "F.Fab")
		)
		(fp_line
			(start 0.299974 0.150114)
			(end -0.299974 0.150114)
			(stroke
				(width 0.1)
				(type default)
			)
			(layer "F.Fab")
		)
		(fp_line
			(start -0.299974 0.150114)
			(end -0.299974 -0.150114)
			(stroke
				(width 0.1)
				(type default)
			)
			(layer "F.Fab")
		)
		(pad "1" smd rect
			(at -0.2667 0 90)
			(size 0.3048 0.381)
			(layers "F.Cu" "F.Mask" "F.Paste")
			(net "P5E_CPU1_PE1_TX_C_DN<11>")
		)
		(pad "2" smd rect
			(at 0.2667 0 90)
			(size 0.3048 0.381)
			(layers "F.Cu" "F.Mask" "F.Paste")
			(net "P5E_CPU1_PE1_TX_DN<11>")
		)
	)
	(footprint ""
		(layer "F.Cu")
		(at 315.405008 -408.517344 -90)
		(property "Reference" "C909"
			(at 0 0 270)
			(layer "F.SilkS")
			(hide yes)
			(effects
				(font
					(size 1.27 1.27)
				)
			)
		)
		(property "Value" ""
			(at 0 0 270)
			(layer "F.Fab")
			(effects
				(font
					(size 1.27 1.27)
				)
			)
		)
		(duplicate_pad_numbers_are_jumpers no)
		(fp_line
			(start -0.299974 0.150114)
			(end -0.299974 -0.150114)
			(stroke
				(width 0.1)
				(type default)
			)
			(layer "F.Fab")
		)
		(fp_line
			(start 0.299974 0.150114)
			(end -0.299974 0.150114)
			(stroke
				(width 0.1)
				(type default)
			)
			(layer "F.Fab")
		)
		(fp_line
			(start -0.299974 -0.150114)
			(end 0.299974 -0.150114)
			(stroke
				(width 0.1)
				(type default)
			)
			(layer "F.Fab")
		)
		(fp_line
			(start 0.299974 -0.150114)
			(end 0.299974 0.150114)
			(stroke
				(width 0.1)
				(type default)
			)
			(layer "F.Fab")
		)
		(pad "1" smd rect
			(at -0.2667 0 270)
			(size 0.3048 0.381)
			(layers "F.Cu" "F.Mask" "F.Paste")
			(net "P5E_CPU0_PE0_TX_C_DP<12>")
		)
		(pad "2" smd rect
			(at 0.2667 0 270)
			(size 0.3048 0.381)
			(layers "F.Cu" "F.Mask" "F.Paste")
			(net "P5E_CPU0_PE0_TX_DP<12>")
		)
	)
	(footprint ""
		(layer "F.Cu")
		(at 300.094904 -41.987724 -90)
		(property "Reference" "R1342"
			(at 0 0 270)
			(layer "F.SilkS")
			(hide yes)
			(effects
				(font
					(size 1.27 1.27)
				)
			)
		)
		(property "Value" ""
			(at 0 0 270)
			(layer "F.Fab")
			(effects
				(font
					(size 1.27 1.27)
				)
			)
		)
		(duplicate_pad_numbers_are_jumpers no)
		(fp_line
			(start -0.7874 0.4064)
			(end -0.7874 -0.4064)
			(stroke
				(width 0.1524)
				(type default)
			)
			(layer "F.SilkS")
		)
		(fp_line
			(start 0.7874 0.4064)
			(end -0.7874 0.4064)
			(stroke
				(width 0.1524)
				(type default)
			)
			(layer "F.SilkS")
		)
		(fp_line
			(start -0.7874 -0.4064)
			(end 0.7874 -0.4064)
			(stroke
				(width 0.1524)
				(type default)
			)
			(layer "F.SilkS")
		)
		(fp_line
			(start 0.7874 -0.4064)
			(end 0.7874 0.4064)
			(stroke
				(width 0.1524)
				(type default)
			)
			(layer "F.SilkS")
		)
		(fp_line
			(start -0.67945 0.3048)
			(end -0.67945 -0.305054)
			(stroke
				(width 0.1)
				(type default)
			)
			(layer "F.Fab")
		)
		(fp_line
			(start -0.12065 0.3048)
			(end -0.67945 0.3048)
			(stroke
				(width 0.1)
				(type default)
			)
			(layer "F.Fab")
		)
		(fp_line
			(start 0.120396 0.3048)
			(end 0.120396 0.2794)
			(stroke
				(width 0.1)
				(type default)
			)
			(layer "F.Fab")
		)
		(fp_line
			(start 0.67945 0.3048)
			(end 0.120396 0.3048)
			(stroke
				(width 0.1)
				(type default)
			)
			(layer "F.Fab")
		)
		(fp_line
			(start -0.12065 0.2794)
			(end -0.12065 0.3048)
			(stroke
				(width 0.1)
				(type default)
			)
			(layer "F.Fab")
		)
		(fp_line
			(start 0.120396 0.2794)
			(end -0.12065 0.2794)
			(stroke
				(width 0.1)
				(type default)
			)
			(layer "F.Fab")
		)
		(fp_line
			(start -0.12065 -0.2794)
			(end 0.12065 -0.2794)
			(stroke
				(width 0.1)
				(type default)
			)
			(layer "F.Fab")
		)
		(fp_line
			(start 0.12065 -0.2794)
			(end 0.12065 -0.3048)
			(stroke
				(width 0.1)
				(type default)
			)
			(layer "F.Fab")
		)
		(fp_line
			(start 0.12065 -0.3048)
			(end 0.67945 -0.3048)
			(stroke
				(width 0.1)
				(type default)
			)
			(layer "F.Fab")
		)
		(fp_line
			(start 0.67945 -0.3048)
			(end 0.67945 0.3048)
			(stroke
				(width 0.1)
				(type default)
			)
			(layer "F.Fab")
		)
		(fp_line
			(start -0.67945 -0.305054)
			(end -0.12065 -0.305054)
			(stroke
				(width 0.1)
				(type default)
			)
			(layer "F.Fab")
		)
		(fp_line
			(start -0.12065 -0.305054)
			(end -0.12065 -0.2794)
			(stroke
				(width 0.1)
				(type default)
			)
			(layer "F.Fab")
		)
		(pad "1" smd circle
			(at -0.40005 0 270)
			(size 0 0)
			(layers "F.Cu" "F.Mask" "F.Paste")
			(net "P1V05_PCH_AUX")
		)
		(pad "2" smd circle
			(at 0.40005 0 270)
			(size 0 0)
			(layers "F.Cu" "F.Mask" "F.Paste")
			(net "FM_ME_RCVR_N")
		)
	)
	(footprint ""
		(layer "F.Cu")
		(at 182.42788 -99.659948 -90)
		(property "Reference" "R1415"
			(at 0 0 270)
			(layer "F.SilkS")
			(hide yes)
			(effects
				(font
					(size 1.27 1.27)
				)
			)
		)
		(property "Value" ""
			(at 0 0 270)
			(layer "F.Fab")
			(effects
				(font
					(size 1.27 1.27)
				)
			)
		)
		(duplicate_pad_numbers_are_jumpers no)
		(fp_line
			(start -0.7874 0.4064)
			(end -0.7874 -0.4064)
			(stroke
				(width 0.1524)
				(type default)
			)
			(layer "F.SilkS")
		)
		(fp_line
			(start 0.7874 0.4064)
			(end -0.7874 0.4064)
			(stroke
				(width 0.1524)
				(type default)
			)
			(layer "F.SilkS")
		)
		(fp_line
			(start -0.7874 -0.4064)
			(end 0.7874 -0.4064)
			(stroke
				(width 0.1524)
				(type default)
			)
			(layer "F.SilkS")
		)
		(fp_line
			(start 0.7874 -0.4064)
			(end 0.7874 0.4064)
			(stroke
				(width 0.1524)
				(type default)
			)
			(layer "F.SilkS")
		)
		(fp_line
			(start -0.67945 0.3048)
			(end -0.67945 -0.305054)
			(stroke
				(width 0.1)
				(type default)
			)
			(layer "F.Fab")
		)
		(fp_line
			(start -0.12065 0.3048)
			(end -0.67945 0.3048)
			(stroke
				(width 0.1)
				(type default)
			)
			(layer "F.Fab")
		)
		(fp_line
			(start 0.120396 0.3048)
			(end 0.120396 0.2794)
			(stroke
				(width 0.1)
				(type default)
			)
			(layer "F.Fab")
		)
		(fp_line
			(start 0.67945 0.3048)
			(end 0.120396 0.3048)
			(stroke
				(width 0.1)
				(type default)
			)
			(layer "F.Fab")
		)
		(fp_line
			(start -0.12065 0.2794)
			(end -0.12065 0.3048)
			(stroke
				(width 0.1)
				(type default)
			)
			(layer "F.Fab")
		)
		(fp_line
			(start 0.120396 0.2794)
			(end -0.12065 0.2794)
			(stroke
				(width 0.1)
				(type default)
			)
			(layer "F.Fab")
		)
		(fp_line
			(start -0.12065 -0.2794)
			(end 0.12065 -0.2794)
			(stroke
				(width 0.1)
				(type default)
			)
			(layer "F.Fab")
		)
		(fp_line
			(start 0.12065 -0.2794)
			(end 0.12065 -0.3048)
			(stroke
				(width 0.1)
				(type default)
			)
			(layer "F.Fab")
		)
		(fp_line
			(start 0.12065 -0.3048)
			(end 0.67945 -0.3048)
			(stroke
				(width 0.1)
				(type default)
			)
			(layer "F.Fab")
		)
		(fp_line
			(start 0.67945 -0.3048)
			(end 0.67945 0.3048)
			(stroke
				(width 0.1)
				(type default)
			)
			(layer "F.Fab")
		)
		(fp_line
			(start -0.67945 -0.305054)
			(end -0.12065 -0.305054)
			(stroke
				(width 0.1)
				(type default)
			)
			(layer "F.Fab")
		)
		(fp_line
			(start -0.12065 -0.305054)
			(end -0.12065 -0.2794)
			(stroke
				(width 0.1)
				(type default)
			)
			(layer "F.Fab")
		)
		(pad "1" smd circle
			(at -0.40005 0 270)
			(size 0 0)
			(layers "F.Cu" "F.Mask" "F.Paste")
			(net "RST_CPU0_LVC1_R_N")
		)
		(pad "2" smd circle
			(at 0.40005 0 270)
			(size 0 0)
			(layers "F.Cu" "F.Mask" "F.Paste")
			(net "GND")
		)
	)
	(footprint ""
		(layer "F.Cu")
		(at 406.124664 -359.579926 180)
		(property "Reference" "R1232"
			(at 0 0 180)
			(layer "F.SilkS")
			(hide yes)
			(effects
				(font
					(size 1.27 1.27)
				)
			)
		)
		(property "Value" ""
			(at 0 0 180)
			(layer "F.Fab")
			(effects
				(font
					(size 1.27 1.27)
				)
			)
		)
		(duplicate_pad_numbers_are_jumpers no)
		(fp_line
			(start 0.7874 0.4064)
			(end -0.7874 0.4064)
			(stroke
				(width 0.1524)
				(type default)
			)
			(layer "F.SilkS")
		)
		(fp_line
			(start 0.7874 -0.4064)
			(end 0.7874 0.4064)
			(stroke
				(width 0.1524)
				(type default)
			)
			(layer "F.SilkS")
		)
		(fp_line
			(start -0.7874 0.4064)
			(end -0.7874 -0.4064)
			(stroke
				(width 0.1524)
				(type default)
			)
			(layer "F.SilkS")
		)
		(fp_line
			(start -0.7874 -0.4064)
			(end 0.7874 -0.4064)
			(stroke
				(width 0.1524)
				(type default)
			)
			(layer "F.SilkS")
		)
		(fp_line
			(start 0.67945 0.3048)
			(end 0.120396 0.3048)
			(stroke
				(width 0.1)
				(type default)
			)
			(layer "F.Fab")
		)
		(fp_line
			(start 0.67945 -0.3048)
			(end 0.67945 0.3048)
			(stroke
				(width 0.1)
				(type default)
			)
			(layer "F.Fab")
		)
		(fp_line
			(start 0.12065 -0.2794)
			(end 0.12065 -0.3048)
			(stroke
				(width 0.1)
				(type default)
			)
			(layer "F.Fab")
		)
		(fp_line
			(start 0.12065 -0.3048)
			(end 0.67945 -0.3048)
			(stroke
				(width 0.1)
				(type default)
			)
			(layer "F.Fab")
		)
		(fp_line
			(start 0.120396 0.3048)
			(end 0.120396 0.2794)
			(stroke
				(width 0.1)
				(type default)
			)
			(layer "F.Fab")
		)
		(fp_line
			(start 0.120396 0.2794)
			(end -0.12065 0.2794)
			(stroke
				(width 0.1)
				(type default)
			)
			(layer "F.Fab")
		)
		(fp_line
			(start -0.12065 0.3048)
			(end -0.67945 0.3048)
			(stroke
				(width 0.1)
				(type default)
			)
			(layer "F.Fab")
		)
		(fp_line
			(start -0.12065 0.2794)
			(end -0.12065 0.3048)
			(stroke
				(width 0.1)
				(type default)
			)
			(layer "F.Fab")
		)
		(fp_line
			(start -0.12065 -0.2794)
			(end 0.12065 -0.2794)
			(stroke
				(width 0.1)
				(type default)
			)
			(layer "F.Fab")
		)
		(fp_line
			(start -0.12065 -0.305054)
			(end -0.12065 -0.2794)
			(stroke
				(width 0.1)
				(type default)
			)
			(layer "F.Fab")
		)
		(fp_line
			(start -0.67945 0.3048)
			(end -0.67945 -0.305054)
			(stroke
				(width 0.1)
				(type default)
			)
			(layer "F.Fab")
		)
		(fp_line
			(start -0.67945 -0.305054)
			(end -0.12065 -0.305054)
			(stroke
				(width 0.1)
				(type default)
			)
			(layer "F.Fab")
		)
		(pad "1" smd circle
			(at -0.40005 0 180)
			(size 0 0)
			(layers "F.Cu" "F.Mask" "F.Paste")
			(net "PVNN_TERM_CPU0")
		)
		(pad "2" smd circle
			(at 0.40005 0 180)
			(size 0 0)
			(layers "F.Cu" "F.Mask" "F.Paste")
			(net "PUD_XTAL_CPU0_MODE0")
		)
	)
	(footprint ""
		(layer "F.Cu")
		(at 261.436612 -130.600704 180)
		(property "Reference" "R4496"
			(at 0 0 180)
			(layer "F.SilkS")
			(hide yes)
			(effects
				(font
					(size 1.27 1.27)
				)
			)
		)
		(property "Value" ""
			(at 0 0 180)
			(layer "F.Fab")
			(effects
				(font
					(size 1.27 1.27)
				)
			)
		)
		(duplicate_pad_numbers_are_jumpers no)
		(fp_line
			(start 0.7874 0.4064)
			(end -0.7874 0.4064)
			(stroke
				(width 0.1524)
				(type default)
			)
			(layer "F.SilkS")
		)
		(fp_line
			(start 0.7874 -0.4064)
			(end 0.7874 0.4064)
			(stroke
				(width 0.1524)
				(type default)
			)
			(layer "F.SilkS")
		)
		(fp_line
			(start -0.7874 0.4064)
			(end -0.7874 -0.4064)
			(stroke
				(width 0.1524)
				(type default)
			)
			(layer "F.SilkS")
		)
		(fp_line
			(start -0.7874 -0.4064)
			(end 0.7874 -0.4064)
			(stroke
				(width 0.1524)
				(type default)
			)
			(layer "F.SilkS")
		)
		(fp_line
			(start 0.67945 0.3048)
			(end 0.120396 0.3048)
			(stroke
				(width 0.1)
				(type default)
			)
			(layer "F.Fab")
		)
		(fp_line
			(start 0.67945 -0.3048)
			(end 0.67945 0.3048)
			(stroke
				(width 0.1)
				(type default)
			)
			(layer "F.Fab")
		)
		(fp_line
			(start 0.12065 -0.2794)
			(end 0.12065 -0.3048)
			(stroke
				(width 0.1)
				(type default)
			)
			(layer "F.Fab")
		)
		(fp_line
			(start 0.12065 -0.3048)
			(end 0.67945 -0.3048)
			(stroke
				(width 0.1)
				(type default)
			)
			(layer "F.Fab")
		)
		(fp_line
			(start 0.120396 0.3048)
			(end 0.120396 0.2794)
			(stroke
				(width 0.1)
				(type default)
			)
			(layer "F.Fab")
		)
		(fp_line
			(start 0.120396 0.2794)
			(end -0.12065 0.2794)
			(stroke
				(width 0.1)
				(type default)
			)
			(layer "F.Fab")
		)
		(fp_line
			(start -0.12065 0.3048)
			(end -0.67945 0.3048)
			(stroke
				(width 0.1)
				(type default)
			)
			(layer "F.Fab")
		)
		(fp_line
			(start -0.12065 0.2794)
			(end -0.12065 0.3048)
			(stroke
				(width 0.1)
				(type default)
			)
			(layer "F.Fab")
		)
		(fp_line
			(start -0.12065 -0.2794)
			(end 0.12065 -0.2794)
			(stroke
				(width 0.1)
				(type default)
			)
			(layer "F.Fab")
		)
		(fp_line
			(start -0.12065 -0.305054)
			(end -0.12065 -0.2794)
			(stroke
				(width 0.1)
				(type default)
			)
			(layer "F.Fab")
		)
		(fp_line
			(start -0.67945 0.3048)
			(end -0.67945 -0.305054)
			(stroke
				(width 0.1)
				(type default)
			)
			(layer "F.Fab")
		)
		(fp_line
			(start -0.67945 -0.305054)
			(end -0.12065 -0.305054)
			(stroke
				(width 0.1)
				(type default)
			)
			(layer "F.Fab")
		)
		(pad "1" smd circle
			(at -0.40005 0 180)
			(size 0 0)
			(layers "F.Cu" "F.Mask" "F.Paste")
			(net "SMB_HOST_CLK_BUF_ISO_3V3AUX_SCL")
		)
		(pad "2" smd circle
			(at 0.40005 0 180)
			(size 0 0)
			(layers "F.Cu" "F.Mask" "F.Paste")
			(net "SMB_HOST_DB2000_3V3AUX_SCL")
		)
	)
	(footprint ""
		(layer "F.Cu")
		(at 28.081732 -403.695408)
		(property "Reference" "Q96"
			(at 1.97358 1.620012 0)
			(unlocked yes)
			(layer "F.SilkS")
			(effects
				(font
					(size 0.7874 0.5842)
					(thickness 0.1524)
				)
				(justify left)
			)
		)
		(property "Value" ""
			(at 0 0 0)
			(layer "F.Fab")
			(effects
				(font
					(size 1.27 1.27)
				)
			)
		)
		(duplicate_pad_numbers_are_jumpers no)
		(fp_line
			(start -1.332738 -1.100074)
			(end -0.4826 -1.100074)
			(stroke
				(width 0.1524)
				(type default)
			)
			(layer "F.SilkS")
		)
		(fp_line
			(start -1.332738 1.100074)
			(end -1.332738 -1.100074)
			(stroke
				(width 0.1524)
				(type default)
			)
			(layer "F.SilkS")
		)
		(fp_line
			(start -0.4826 -1.100074)
			(end 0 -0.541274)
			(stroke
				(width 0.1524)
				(type default)
			)
			(layer "F.SilkS")
		)
		(fp_line
			(start 0 -0.541274)
			(end 0.4826 -1.100074)
			(stroke
				(width 0.1524)
				(type default)
			)
			(layer "F.SilkS")
		)
		(fp_line
			(start 0.4826 -1.100074)
			(end 1.332738 -1.100074)
			(stroke
				(width 0.1524)
				(type default)
			)
			(layer "F.SilkS")
		)
		(fp_line
			(start 1.332738 -1.100074)
			(end 1.332738 1.100074)
			(stroke
				(width 0.1524)
				(type default)
			)
			(layer "F.SilkS")
		)
		(fp_line
			(start 1.332738 1.100074)
			(end -1.332738 1.100074)
			(stroke
				(width 0.1524)
				(type default)
			)
			(layer "F.SilkS")
		)
		(fp_poly
			(pts
				(xy -1.848612 -1.41478) (xy -1.600454 -0.670306) (xy -2.344928 -0.918464)
			)
			(stroke
				(width 0)
				(type default)
			)
			(fill yes)
			(layer "F.SilkS")
		)
		(fp_line
			(start -0.674878 -1.100074)
			(end 0.674878 -1.100074)
			(stroke
				(width 0.1)
				(type default)
			)
			(layer "F.Fab")
		)
		(fp_line
			(start -0.674878 1.100074)
			(end -0.674878 -1.100074)
			(stroke
				(width 0.1)
				(type default)
			)
			(layer "F.Fab")
		)
		(fp_line
			(start 0.674878 -1.100074)
			(end 0.674878 1.100074)
			(stroke
				(width 0.1)
				(type default)
			)
			(layer "F.Fab")
		)
		(fp_line
			(start 0.674878 1.100074)
			(end -0.674878 1.100074)
			(stroke
				(width 0.1)
				(type default)
			)
			(layer "F.Fab")
		)
		(fp_poly
			(pts
				(xy -2.2352 -0.298958) (xy -2.2352 -1.001014) (xy -1.533144 -0.649986)
			)
			(stroke
				(width 0)
				(type default)
			)
			(fill yes)
			(layer "F.Fab")
		)
		(pad "1" smd rect
			(at -0.94996 -0.649986 90)
			(size 0.4318 0.508)
			(layers "F.Cu" "F.Mask" "F.Paste")
			(net "GND")
		)
		(pad "2" smd rect
			(at -0.94996 0 90)
			(size 0.4318 0.508)
			(layers "F.Cu" "F.Mask" "F.Paste")
			(net "GPU_FPGA_READY")
		)
		(pad "3" smd rect
			(at -0.94996 0.649986 90)
			(size 0.4318 0.508)
			(layers "F.Cu" "F.Mask" "F.Paste")
			(net "GPU_FPGA_READY_ISO")
		)
		(pad "4" smd rect
			(at 0.94996 0.649986 90)
			(size 0.4318 0.508)
			(layers "F.Cu" "F.Mask" "F.Paste")
			(net "GND")
		)
		(pad "5" smd rect
			(at 0.94996 0 90)
			(size 0.4318 0.508)
			(layers "F.Cu" "F.Mask" "F.Paste")
			(net "GPU_FPGA_READY_N")
		)
		(pad "6" smd rect
			(at 0.94996 -0.649986 90)
			(size 0.4318 0.508)
			(layers "F.Cu" "F.Mask" "F.Paste")
			(net "GPU_FPGA_READY_N")
		)
	)
	(footprint ""
		(layer "F.Cu")
		(at 189.28588 -130.266948 -90)
		(property "Reference" "R286"
			(at 0 0 270)
			(layer "F.SilkS")
			(hide yes)
			(effects
				(font
					(size 1.27 1.27)
				)
			)
		)
		(property "Value" ""
			(at 0 0 270)
			(layer "F.Fab")
			(effects
				(font
					(size 1.27 1.27)
				)
			)
		)
		(duplicate_pad_numbers_are_jumpers no)
		(fp_line
			(start -0.7874 0.4064)
			(end -0.7874 -0.4064)
			(stroke
				(width 0.1524)
				(type default)
			)
			(layer "F.SilkS")
		)
		(fp_line
			(start 0.7874 0.4064)
			(end -0.7874 0.4064)
			(stroke
				(width 0.1524)
				(type default)
			)
			(layer "F.SilkS")
		)
		(fp_line
			(start -0.7874 -0.4064)
			(end 0.7874 -0.4064)
			(stroke
				(width 0.1524)
				(type default)
			)
			(layer "F.SilkS")
		)
		(fp_line
			(start 0.7874 -0.4064)
			(end 0.7874 0.4064)
			(stroke
				(width 0.1524)
				(type default)
			)
			(layer "F.SilkS")
		)
		(fp_line
			(start -0.67945 0.3048)
			(end -0.67945 -0.305054)
			(stroke
				(width 0.1)
				(type default)
			)
			(layer "F.Fab")
		)
		(fp_line
			(start -0.12065 0.3048)
			(end -0.67945 0.3048)
			(stroke
				(width 0.1)
				(type default)
			)
			(layer "F.Fab")
		)
		(fp_line
			(start 0.120396 0.3048)
			(end 0.120396 0.2794)
			(stroke
				(width 0.1)
				(type default)
			)
			(layer "F.Fab")
		)
		(fp_line
			(start 0.67945 0.3048)
			(end 0.120396 0.3048)
			(stroke
				(width 0.1)
				(type default)
			)
			(layer "F.Fab")
		)
		(fp_line
			(start -0.12065 0.2794)
			(end -0.12065 0.3048)
			(stroke
				(width 0.1)
				(type default)
			)
			(layer "F.Fab")
		)
		(fp_line
			(start 0.120396 0.2794)
			(end -0.12065 0.2794)
			(stroke
				(width 0.1)
				(type default)
			)
			(layer "F.Fab")
		)
		(fp_line
			(start -0.12065 -0.2794)
			(end 0.12065 -0.2794)
			(stroke
				(width 0.1)
				(type default)
			)
			(layer "F.Fab")
		)
		(fp_line
			(start 0.12065 -0.2794)
			(end 0.12065 -0.3048)
			(stroke
				(width 0.1)
				(type default)
			)
			(layer "F.Fab")
		)
		(fp_line
			(start 0.12065 -0.3048)
			(end 0.67945 -0.3048)
			(stroke
				(width 0.1)
				(type default)
			)
			(layer "F.Fab")
		)
		(fp_line
			(start 0.67945 -0.3048)
			(end 0.67945 0.3048)
			(stroke
				(width 0.1)
				(type default)
			)
			(layer "F.Fab")
		)
		(fp_line
			(start -0.67945 -0.305054)
			(end -0.12065 -0.305054)
			(stroke
				(width 0.1)
				(type default)
			)
			(layer "F.Fab")
		)
		(fp_line
			(start -0.12065 -0.305054)
			(end -0.12065 -0.2794)
			(stroke
				(width 0.1)
				(type default)
			)
			(layer "F.Fab")
		)
		(pad "1" smd circle
			(at -0.40005 0 270)
			(size 0 0)
			(layers "F.Cu" "F.Mask" "F.Paste")
			(net "P3V3_AUX")
		)
		(pad "2" smd circle
			(at 0.40005 0 270)
			(size 0 0)
			(layers "F.Cu" "F.Mask" "F.Paste")
			(net "FM_CPU0_PROC_ID0")
		)
	)
	(footprint ""
		(layer "F.Cu")
		(at 58.490358 -408.517344 -90)
		(property "Reference" "C702"
			(at 0 0 270)
			(layer "F.SilkS")
			(hide yes)
			(effects
				(font
					(size 1.27 1.27)
				)
			)
		)
		(property "Value" ""
			(at 0 0 270)
			(layer "F.Fab")
			(effects
				(font
					(size 1.27 1.27)
				)
			)
		)
		(duplicate_pad_numbers_are_jumpers no)
		(fp_line
			(start -0.299974 0.150114)
			(end -0.299974 -0.150114)
			(stroke
				(width 0.1)
				(type default)
			)
			(layer "F.Fab")
		)
		(fp_line
			(start 0.299974 0.150114)
			(end -0.299974 0.150114)
			(stroke
				(width 0.1)
				(type default)
			)
			(layer "F.Fab")
		)
		(fp_line
			(start -0.299974 -0.150114)
			(end 0.299974 -0.150114)
			(stroke
				(width 0.1)
				(type default)
			)
			(layer "F.Fab")
		)
		(fp_line
			(start 0.299974 -0.150114)
			(end 0.299974 0.150114)
			(stroke
				(width 0.1)
				(type default)
			)
			(layer "F.Fab")
		)
		(pad "1" smd rect
			(at -0.2667 0 270)
			(size 0.3048 0.381)
			(layers "F.Cu" "F.Mask" "F.Paste")
			(net "P5E_CPU1_PE4_TX_C_DN<3>")
		)
		(pad "2" smd rect
			(at 0.2667 0 270)
			(size 0.3048 0.381)
			(layers "F.Cu" "F.Mask" "F.Paste")
			(net "P5E_CPU1_PE4_TX_DN<3>")
		)
	)
	(footprint ""
		(layer "F.Cu")
		(at 437.242966 -122.648726 180)
		(property "Reference" "PR370"
			(at 0 0 180)
			(layer "F.SilkS")
			(hide yes)
			(effects
				(font
					(size 1.27 1.27)
				)
			)
		)
		(property "Value" ""
			(at 0 0 180)
			(layer "F.Fab")
			(effects
				(font
					(size 1.27 1.27)
				)
			)
		)
		(duplicate_pad_numbers_are_jumpers no)
		(fp_line
			(start 0.7874 0.4064)
			(end -0.7874 0.4064)
			(stroke
				(width 0.1524)
				(type default)
			)
			(layer "F.SilkS")
		)
		(fp_line
			(start 0.7874 -0.4064)
			(end 0.7874 0.4064)
			(stroke
				(width 0.1524)
				(type default)
			)
			(layer "F.SilkS")
		)
		(fp_line
			(start -0.7874 0.4064)
			(end -0.7874 -0.4064)
			(stroke
				(width 0.1524)
				(type default)
			)
			(layer "F.SilkS")
		)
		(fp_line
			(start -0.7874 -0.4064)
			(end 0.7874 -0.4064)
			(stroke
				(width 0.1524)
				(type default)
			)
			(layer "F.SilkS")
		)
		(fp_line
			(start 0.67945 0.3048)
			(end 0.120396 0.3048)
			(stroke
				(width 0.1)
				(type default)
			)
			(layer "F.Fab")
		)
		(fp_line
			(start 0.67945 -0.3048)
			(end 0.67945 0.3048)
			(stroke
				(width 0.1)
				(type default)
			)
			(layer "F.Fab")
		)
		(fp_line
			(start 0.12065 -0.2794)
			(end 0.12065 -0.3048)
			(stroke
				(width 0.1)
				(type default)
			)
			(layer "F.Fab")
		)
		(fp_line
			(start 0.12065 -0.3048)
			(end 0.67945 -0.3048)
			(stroke
				(width 0.1)
				(type default)
			)
			(layer "F.Fab")
		)
		(fp_line
			(start 0.120396 0.3048)
			(end 0.120396 0.2794)
			(stroke
				(width 0.1)
				(type default)
			)
			(layer "F.Fab")
		)
		(fp_line
			(start 0.120396 0.2794)
			(end -0.12065 0.2794)
			(stroke
				(width 0.1)
				(type default)
			)
			(layer "F.Fab")
		)
		(fp_line
			(start -0.12065 0.3048)
			(end -0.67945 0.3048)
			(stroke
				(width 0.1)
				(type default)
			)
			(layer "F.Fab")
		)
		(fp_line
			(start -0.12065 0.2794)
			(end -0.12065 0.3048)
			(stroke
				(width 0.1)
				(type default)
			)
			(layer "F.Fab")
		)
		(fp_line
			(start -0.12065 -0.2794)
			(end 0.12065 -0.2794)
			(stroke
				(width 0.1)
				(type default)
			)
			(layer "F.Fab")
		)
		(fp_line
			(start -0.12065 -0.305054)
			(end -0.12065 -0.2794)
			(stroke
				(width 0.1)
				(type default)
			)
			(layer "F.Fab")
		)
		(fp_line
			(start -0.67945 0.3048)
			(end -0.67945 -0.305054)
			(stroke
				(width 0.1)
				(type default)
			)
			(layer "F.Fab")
		)
		(fp_line
			(start -0.67945 -0.305054)
			(end -0.12065 -0.305054)
			(stroke
				(width 0.1)
				(type default)
			)
			(layer "F.Fab")
		)
		(pad "1" smd circle
			(at -0.40005 0 180)
			(size 0 0)
			(layers "F.Cu" "F.Mask" "F.Paste")
			(net "P3V3_AUX")
		)
		(pad "2" smd circle
			(at 0.40005 0 180)
			(size 0 0)
			(layers "F.Cu" "F.Mask" "F.Paste")
			(net "PVCCD_HV_CPU0_PIN_ALT")
		)
	)
	(footprint ""
		(layer "F.Cu")
		(at 234.300014 -50.55997 180)
		(property "Reference" "J90"
			(at -0.596646 16.126968 0)
			(unlocked yes)
			(layer "F.SilkS")
			(effects
				(font
					(size 0.7874 0.5842)
					(thickness 0.1524)
				)
			)
		)
		(property "Value" ""
			(at 0 0 180)
			(layer "F.Fab")
			(effects
				(font
					(size 1.27 1.27)
				)
			)
		)
		(duplicate_pad_numbers_are_jumpers no)
		(fp_line
			(start 3.150108 12.115038)
			(end 1.529334 12.115038)
			(stroke
				(width 0.1524)
				(type default)
			)
			(layer "F.SilkS")
		)
		(fp_line
			(start 3.074924 12.014962)
			(end 1.632204 12.014962)
			(stroke
				(width 0.1524)
				(type default)
			)
			(layer "F.SilkS")
		)
		(fp_line
			(start 1.632204 -12.014962)
			(end 3.074924 -12.014962)
			(stroke
				(width 0.1524)
				(type default)
			)
			(layer "F.SilkS")
		)
		(fp_line
			(start 1.529334 -12.115038)
			(end 3.150108 -12.115038)
			(stroke
				(width 0.1524)
				(type default)
			)
			(layer "F.SilkS")
		)
		(fp_line
			(start -1.529334 12.115038)
			(end -3.150108 12.115038)
			(stroke
				(width 0.1524)
				(type default)
			)
			(layer "F.SilkS")
		)
		(fp_line
			(start -1.632204 12.014962)
			(end -3.074924 12.014962)
			(stroke
				(width 0.1524)
				(type default)
			)
			(layer "F.SilkS")
		)
		(fp_line
			(start -3.074924 -12.014962)
			(end -1.632204 -12.014962)
			(stroke
				(width 0.1524)
				(type default)
			)
			(layer "F.SilkS")
		)
		(fp_line
			(start -3.150108 -12.115038)
			(end -1.529334 -12.115038)
			(stroke
				(width 0.1524)
				(type default)
			)
			(layer "F.SilkS")
		)
		(fp_poly
			(pts
				(xy 3.901948 -10.042906) (xy 4.747006 -9.197848) (xy 3.479546 -8.775192)
			)
			(stroke
				(width 0)
				(type default)
			)
			(fill yes)
			(layer "F.SilkS")
		)
		(fp_line
			(start 3.074924 12.014962)
			(end -3.074924 12.014962)
			(stroke
				(width 0.1)
				(type default)
			)
			(layer "F.Fab")
		)
		(fp_line
			(start 3.074924 -12.014962)
			(end 3.074924 12.014962)
			(stroke
				(width 0.1)
				(type default)
			)
			(layer "F.Fab")
		)
		(fp_line
			(start -3.074924 12.014962)
			(end -3.074924 -12.014962)
			(stroke
				(width 0.1)
				(type default)
			)
			(layer "F.Fab")
		)
		(fp_line
			(start -3.074924 -12.014962)
			(end 3.074924 -12.014962)
			(stroke
				(width 0.1)
				(type default)
			)
			(layer "F.Fab")
		)
		(fp_poly
			(pts
				(xy 3.348736 -7.994904) (xy 4.543806 -8.592566) (xy 4.543806 -7.397496)
			)
			(stroke
				(width 0)
				(type default)
			)
			(fill yes)
			(layer "F.Fab")
		)
		(pad "" np_thru_hole circle
			(at -1.75006 -9.815068 90)
			(size 1.1176 1.1176)
			(drill 1.1176)
			(layers "*.Cu" "*.Mask")
			(clearance 0.381)
			(thermal_gap 0.381)
		)
		(pad "" np_thru_hole circle
			(at 0 9.815068 90)
			(size 1.1176 1.1176)
			(drill 1.1176)
			(layers "*.Cu" "*.Mask")
			(clearance 0.381)
			(thermal_gap 0.381)
		)
		(pad "A1" smd rect
			(at 2.29997 -7.994904 90)
			(size 0.381 1.27)
			(layers "F.Cu" "F.Mask" "F.Paste")
			(net "GND")
		)
		(pad "A2" smd rect
			(at 2.29997 -7.394956 90)
			(size 0.381 1.27)
			(layers "F.Cu" "F.Mask" "F.Paste")
			(net "GND")
		)
		(pad "A3" smd rect
			(at 2.29997 -6.795008 90)
			(size 0.381 1.27)
			(layers "F.Cu" "F.Mask" "F.Paste")
			(net "GND")
		)
		(pad "A4" smd rect
			(at 2.29997 -6.19506 90)
			(size 0.381 1.27)
			(layers "F.Cu" "F.Mask" "F.Paste")
			(net "GND")
		)
		(pad "A5" smd rect
			(at 2.29997 -5.595112 90)
			(size 0.381 1.27)
			(layers "F.Cu" "F.Mask" "F.Paste")
			(net "GND")
		)
		(pad "A6" smd rect
			(at 2.29997 -4.99491 90)
			(size 0.381 1.27)
			(layers "F.Cu" "F.Mask" "F.Paste")
			(net "GND")
		)
		(pad "A7" smd rect
			(at 2.29997 -4.394962 90)
			(size 0.381 1.27)
			(layers "F.Cu" "F.Mask" "F.Paste")
			(net "SMB_E1S_3V3AUX_ISO_SCL")
		)
		(pad "A8" smd rect
			(at 2.29997 -3.795014 90)
			(size 0.381 1.27)
			(layers "F.Cu" "F.Mask" "F.Paste")
			(net "SMB_E1S_3V3AUX_ISO_SDA")
		)
		(pad "A9" smd rect
			(at 2.29997 -3.195066 90)
			(size 0.381 1.27)
			(layers "F.Cu" "F.Mask" "F.Paste")
			(net "RST_SMB_E1S_0_N")
		)
		(pad "A10" smd rect
			(at 2.29997 -2.595118 90)
			(size 0.381 1.27)
			(layers "F.Cu" "F.Mask" "F.Paste")
			(net "E1S_0_LED_ACT_N")
		)
		(pad "A11" smd rect
			(at 2.29997 -1.994916 90)
			(size 0.381 1.27)
			(layers "F.Cu" "F.Mask" "F.Paste")
			(net "E1S_0_PERST1_CLKREQ_N")
		)
		(pad "A12" smd rect
			(at 2.29997 -1.394968 90)
			(size 0.381 1.27)
			(layers "F.Cu" "F.Mask" "F.Paste")
			(net "E1S_0_PRSNT_N")
		)
		(pad "A13" smd rect
			(at 2.29997 -0.79502 90)
			(size 0.381 1.27)
			(layers "F.Cu" "F.Mask" "F.Paste")
			(net "GND")
		)
		(pad "A14" smd rect
			(at 2.29997 -0.195072 90)
			(size 0.381 1.27)
			(layers "F.Cu" "F.Mask" "F.Paste")
			(net "TP_CLK_100M_E1S_0_DN")
		)
		(pad "A15" smd rect
			(at 2.29997 0.404876 90)
			(size 0.381 1.27)
			(layers "F.Cu" "F.Mask" "F.Paste")
			(net "TP_CLK_100M_E1S_0_DP")
		)
		(pad "A16" smd rect
			(at 2.29997 1.005078 90)
			(size 0.381 1.27)
			(layers "F.Cu" "F.Mask" "F.Paste")
			(net "GND")
		)
		(pad "A17" smd rect
			(at 2.29997 1.605026 90)
			(size 0.381 1.27)
			(layers "F.Cu" "F.Mask" "F.Paste")
			(net "P3E_PCH_E1S_RX_DP<0>")
		)
		(pad "A18" smd rect
			(at 2.29997 2.204974 90)
			(size 0.381 1.27)
			(layers "F.Cu" "F.Mask" "F.Paste")
			(net "P3E_PCH_E1S_RX_DN<0>")
		)
		(pad "A19" smd rect
			(at 2.29997 2.804922 90)
			(size 0.381 1.27)
			(layers "F.Cu" "F.Mask" "F.Paste")
			(net "GND")
		)
		(pad "A20" smd rect
			(at 2.29997 3.405124 90)
			(size 0.381 1.27)
			(layers "F.Cu" "F.Mask" "F.Paste")
			(net "P3E_PCH_E1S_RX_DN<1>")
		)
		(pad "A21" smd rect
			(at 2.29997 4.005072 90)
			(size 0.381 1.27)
			(layers "F.Cu" "F.Mask" "F.Paste")
			(net "P3E_PCH_E1S_RX_DP<1>")
		)
		(pad "A22" smd rect
			(at 2.29997 4.60502 90)
			(size 0.381 1.27)
			(layers "F.Cu" "F.Mask" "F.Paste")
			(net "GND")
		)
		(pad "A23" smd rect
			(at 2.29997 5.204968 90)
			(size 0.381 1.27)
			(layers "F.Cu" "F.Mask" "F.Paste")
			(net "P3E_PCH_E1S_RX_DN<2>")
		)
		(pad "A24" smd rect
			(at 2.29997 5.804916 90)
			(size 0.381 1.27)
			(layers "F.Cu" "F.Mask" "F.Paste")
			(net "P3E_PCH_E1S_RX_DP<2>")
		)
		(pad "A25" smd rect
			(at 2.29997 6.405118 90)
			(size 0.381 1.27)
			(layers "F.Cu" "F.Mask" "F.Paste")
			(net "GND")
		)
		(pad "A26" smd rect
			(at 2.29997 7.005066 90)
			(size 0.381 1.27)
			(layers "F.Cu" "F.Mask" "F.Paste")
			(net "P3E_PCH_E1S_RX_DN<3>")
		)
		(pad "A27" smd rect
			(at 2.29997 7.605014 90)
			(size 0.381 1.27)
			(layers "F.Cu" "F.Mask" "F.Paste")
			(net "P3E_PCH_E1S_RX_DP<3>")
		)
		(pad "A28" smd rect
			(at 2.29997 8.204962 90)
			(size 0.381 1.27)
			(layers "F.Cu" "F.Mask" "F.Paste")
			(net "GND")
		)
		(pad "B1" smd rect
			(at -2.29997 -7.994904 90)
			(size 0.381 1.27)
			(layers "F.Cu" "F.Mask" "F.Paste")
			(net "P12V_E1S_0")
		)
		(pad "B2" smd rect
			(at -2.29997 -7.394956 90)
			(size 0.381 1.27)
			(layers "F.Cu" "F.Mask" "F.Paste")
			(net "P12V_E1S_0")
		)
		(pad "B3" smd rect
			(at -2.29997 -6.795008 90)
			(size 0.381 1.27)
			(layers "F.Cu" "F.Mask" "F.Paste")
			(net "P12V_E1S_0")
		)
		(pad "B4" smd rect
			(at -2.29997 -6.19506 90)
			(size 0.381 1.27)
			(layers "F.Cu" "F.Mask" "F.Paste")
			(net "P12V_E1S_0")
		)
		(pad "B5" smd rect
			(at -2.29997 -5.595112 90)
			(size 0.381 1.27)
			(layers "F.Cu" "F.Mask" "F.Paste")
			(net "P12V_E1S_0")
		)
		(pad "B6" smd rect
			(at -2.29997 -4.99491 90)
			(size 0.381 1.27)
			(layers "F.Cu" "F.Mask" "F.Paste")
			(net "P12V_E1S_0")
		)
		(pad "B7" smd rect
			(at -2.29997 -4.394962 90)
			(size 0.381 1.27)
			(layers "F.Cu" "F.Mask" "F.Paste")
			(net "TP_E1S_0_MFG")
		)
		(pad "B8" smd rect
			(at -2.29997 -3.795014 90)
			(size 0.381 1.27)
			(layers "F.Cu" "F.Mask" "F.Paste")
			(net "TP_E1S_0_RFU")
		)
		(pad "B9" smd rect
			(at -2.29997 -3.195066 90)
			(size 0.381 1.27)
			(layers "F.Cu" "F.Mask" "F.Paste")
			(net "PU_E1S_0_DUALPORT_EN_N")
		)
		(pad "B10" smd rect
			(at -2.29997 -2.595118 90)
			(size 0.381 1.27)
			(layers "F.Cu" "F.Mask" "F.Paste")
			(net "RST_PCIE_PCH_E1S_PERST_N")
		)
		(pad "B11" smd rect
			(at -2.29997 -1.994916 90)
			(size 0.381 1.27)
			(layers "F.Cu" "F.Mask" "F.Paste")
			(net "P3V3_E1S_0")
		)
		(pad "B12" smd rect
			(at -2.29997 -1.394968 90)
			(size 0.381 1.27)
			(layers "F.Cu" "F.Mask" "F.Paste")
			(net "E1S_0_PWRDIS")
		)
		(pad "B13" smd rect
			(at -2.29997 -0.79502 90)
			(size 0.381 1.27)
			(layers "F.Cu" "F.Mask" "F.Paste")
			(net "GND")
		)
		(pad "B14" smd rect
			(at -2.29997 -0.195072 90)
			(size 0.381 1.27)
			(layers "F.Cu" "F.Mask" "F.Paste")
			(net "CLK_100M_E1S_0_DN")
		)
		(pad "B15" smd rect
			(at -2.29997 0.404876 90)
			(size 0.381 1.27)
			(layers "F.Cu" "F.Mask" "F.Paste")
			(net "CLK_100M_E1S_0_DP")
		)
		(pad "B16" smd rect
			(at -2.29997 1.005078 90)
			(size 0.381 1.27)
			(layers "F.Cu" "F.Mask" "F.Paste")
			(net "GND")
		)
		(pad "B17" smd rect
			(at -2.29997 1.605026 90)
			(size 0.381 1.27)
			(layers "F.Cu" "F.Mask" "F.Paste")
			(net "P3E_PCH_E1S_TX_C_DP<0>")
		)
		(pad "B18" smd rect
			(at -2.29997 2.204974 90)
			(size 0.381 1.27)
			(layers "F.Cu" "F.Mask" "F.Paste")
			(net "P3E_PCH_E1S_TX_C_DN<0>")
		)
		(pad "B19" smd rect
			(at -2.29997 2.804922 90)
			(size 0.381 1.27)
			(layers "F.Cu" "F.Mask" "F.Paste")
			(net "GND")
		)
		(pad "B20" smd rect
			(at -2.29997 3.405124 90)
			(size 0.381 1.27)
			(layers "F.Cu" "F.Mask" "F.Paste")
			(net "P3E_PCH_E1S_TX_C_DP<1>")
		)
		(pad "B21" smd rect
			(at -2.29997 4.005072 90)
			(size 0.381 1.27)
			(layers "F.Cu" "F.Mask" "F.Paste")
			(net "P3E_PCH_E1S_TX_C_DN<1>")
		)
		(pad "B22" smd rect
			(at -2.29997 4.60502 90)
			(size 0.381 1.27)
			(layers "F.Cu" "F.Mask" "F.Paste")
			(net "GND")
		)
		(pad "B23" smd rect
			(at -2.29997 5.204968 90)
			(size 0.381 1.27)
			(layers "F.Cu" "F.Mask" "F.Paste")
			(net "P3E_PCH_E1S_TX_C_DN<2>")
		)
		(pad "B24" smd rect
			(at -2.29997 5.804916 90)
			(size 0.381 1.27)
			(layers "F.Cu" "F.Mask" "F.Paste")
			(net "P3E_PCH_E1S_TX_C_DP<2>")
		)
		(pad "B25" smd rect
			(at -2.29997 6.405118 90)
			(size 0.381 1.27)
			(layers "F.Cu" "F.Mask" "F.Paste")
			(net "GND")
		)
		(pad "B26" smd rect
			(at -2.29997 7.005066 90)
			(size 0.381 1.27)
			(layers "F.Cu" "F.Mask" "F.Paste")
			(net "P3E_PCH_E1S_TX_C_DN<3>")
		)
		(pad "B27" smd rect
			(at -2.29997 7.605014 90)
			(size 0.381 1.27)
			(layers "F.Cu" "F.Mask" "F.Paste")
			(net "P3E_PCH_E1S_TX_C_DP<3>")
		)
		(pad "B28" smd rect
			(at -2.29997 8.204962 90)
			(size 0.381 1.27)
			(layers "F.Cu" "F.Mask" "F.Paste")
			(net "GND")
		)
		(pad "G1" thru_hole oval
			(at 0 -11.364976 90)
			(size 1.6256 3.4798)
			(drill oval 1.1176 2.4638)
			(layers "*.Cu" "*.Mask")
			(remove_unused_layers no)
			(net "GND")
			(clearance 0.127)
			(thermal_gap 0.127)
		)
		(pad "G2" thru_hole oval
			(at 0 11.364976 90)
			(size 1.6256 3.4798)
			(drill oval 1.1176 2.4638)
			(layers "*.Cu" "*.Mask")
			(remove_unused_layers no)
			(net "GND")
			(clearance 0.127)
			(thermal_gap 0.127)
		)
		(zone
			(layer "F.Cu")
			(hatch none 0.5)
			(connect_pads
				(clearance 0)
			)
			(min_thickness 0.25)
			(keepout
				(tracks not_allowed)
				(vias allowed)
				(pads allowed)
				(copperpour not_allowed)
				(footprints allowed)
			)
			(placement
				(enabled no)
				(sheetname "")
			)
			(fill
				(thermal_gap 0.5)
				(thermal_bridge_width 0.5)
				(island_removal_mode 0)
			)
			(polygon
				(pts
					(xy 235.679996 -62.62497) (xy 232.929938 -62.62497) (xy 232.929938 -59.675014) (xy 235.679996 -59.675014)
				)
			)
		)
		(zone
			(layer "F.Cu")
			(hatch none 0.5)
			(connect_pads
				(clearance 0)
			)
			(min_thickness 0.25)
			(keepout
				(tracks not_allowed)
				(vias allowed)
				(pads allowed)
				(copperpour not_allowed)
				(footprints allowed)
			)
			(placement
				(enabled no)
				(sheetname "")
			)
			(fill
				(thermal_gap 0.5)
				(thermal_bridge_width 0.5)
				(island_removal_mode 0)
			)
			(polygon
				(pts
					(xy 236.750098 -41.444926) (xy 232.920032 -41.444926) (xy 232.920032 -38.49497) (xy 236.750098 -38.49497)
				)
			)
		)
		(zone
			(layers "F.Cu" "B.Cu" "In1.Cu" "In2.Cu" "In3.Cu" "In4.Cu" "In5.Cu" "In6.Cu"
				"In7.Cu" "In8.Cu" "In9.Cu" "In10.Cu" "In11.Cu" "In12.Cu" "In13.Cu" "In14.Cu"
				"In15.Cu" "In16.Cu"
			)
			(hatch none 0.5)
			(connect_pads
				(clearance 0)
			)
			(min_thickness 0.25)
			(keepout
				(tracks not_allowed)
				(vias allowed)
				(pads allowed)
				(copperpour not_allowed)
				(footprints allowed)
			)
			(placement
				(enabled no)
				(sheetname "")
			)
			(fill
				(thermal_gap 0.5)
				(thermal_bridge_width 0.5)
				(island_removal_mode 0)
			)
			(polygon
				(pts
					(arc
						(start 235.265214 -60.375038)
						(mid 233.334814 -60.375038)
						(end 235.265214 -60.375038)
					)
				)
			)
		)
		(zone
			(layers "F.Cu" "B.Cu" "In1.Cu" "In2.Cu" "In3.Cu" "In4.Cu" "In5.Cu" "In6.Cu"
				"In7.Cu" "In8.Cu" "In9.Cu" "In10.Cu" "In11.Cu" "In12.Cu" "In13.Cu" "In14.Cu"
				"In15.Cu" "In16.Cu"
			)
			(hatch none 0.5)
			(connect_pads
				(clearance 0)
			)
			(min_thickness 0.25)
			(keepout
				(tracks not_allowed)
				(vias allowed)
				(pads allowed)
				(copperpour not_allowed)
				(footprints allowed)
			)
			(placement
				(enabled no)
				(sheetname "")
			)
			(fill
				(thermal_gap 0.5)
				(thermal_bridge_width 0.5)
				(island_removal_mode 0)
			)
			(polygon
				(pts
					(arc
						(start 237.015274 -40.744902)
						(mid 235.084874 -40.744902)
						(end 237.015274 -40.744902)
					)
				)
			)
		)
	)
	(footprint ""
		(layer "F.Cu")
		(at 122.05208 -106.238548 -90)
		(property "Reference" "R4046"
			(at 0 0 270)
			(layer "F.SilkS")
			(hide yes)
			(effects
				(font
					(size 1.27 1.27)
				)
			)
		)
		(property "Value" ""
			(at 0 0 270)
			(layer "F.Fab")
			(effects
				(font
					(size 1.27 1.27)
				)
			)
		)
		(duplicate_pad_numbers_are_jumpers no)
		(fp_line
			(start -0.7874 0.4064)
			(end -0.7874 -0.4064)
			(stroke
				(width 0.1524)
				(type default)
			)
			(layer "F.SilkS")
		)
		(fp_line
			(start 0.7874 0.4064)
			(end -0.7874 0.4064)
			(stroke
				(width 0.1524)
				(type default)
			)
			(layer "F.SilkS")
		)
		(fp_line
			(start -0.7874 -0.4064)
			(end 0.7874 -0.4064)
			(stroke
				(width 0.1524)
				(type default)
			)
			(layer "F.SilkS")
		)
		(fp_line
			(start 0.7874 -0.4064)
			(end 0.7874 0.4064)
			(stroke
				(width 0.1524)
				(type default)
			)
			(layer "F.SilkS")
		)
		(fp_line
			(start -0.67945 0.3048)
			(end -0.67945 -0.305054)
			(stroke
				(width 0.1)
				(type default)
			)
			(layer "F.Fab")
		)
		(fp_line
			(start -0.12065 0.3048)
			(end -0.67945 0.3048)
			(stroke
				(width 0.1)
				(type default)
			)
			(layer "F.Fab")
		)
		(fp_line
			(start 0.120396 0.3048)
			(end 0.120396 0.2794)
			(stroke
				(width 0.1)
				(type default)
			)
			(layer "F.Fab")
		)
		(fp_line
			(start 0.67945 0.3048)
			(end 0.120396 0.3048)
			(stroke
				(width 0.1)
				(type default)
			)
			(layer "F.Fab")
		)
		(fp_line
			(start -0.12065 0.2794)
			(end -0.12065 0.3048)
			(stroke
				(width 0.1)
				(type default)
			)
			(layer "F.Fab")
		)
		(fp_line
			(start 0.120396 0.2794)
			(end -0.12065 0.2794)
			(stroke
				(width 0.1)
				(type default)
			)
			(layer "F.Fab")
		)
		(fp_line
			(start -0.12065 -0.2794)
			(end 0.12065 -0.2794)
			(stroke
				(width 0.1)
				(type default)
			)
			(layer "F.Fab")
		)
		(fp_line
			(start 0.12065 -0.2794)
			(end 0.12065 -0.3048)
			(stroke
				(width 0.1)
				(type default)
			)
			(layer "F.Fab")
		)
		(fp_line
			(start 0.12065 -0.3048)
			(end 0.67945 -0.3048)
			(stroke
				(width 0.1)
				(type default)
			)
			(layer "F.Fab")
		)
		(fp_line
			(start 0.67945 -0.3048)
			(end 0.67945 0.3048)
			(stroke
				(width 0.1)
				(type default)
			)
			(layer "F.Fab")
		)
		(fp_line
			(start -0.67945 -0.305054)
			(end -0.12065 -0.305054)
			(stroke
				(width 0.1)
				(type default)
			)
			(layer "F.Fab")
		)
		(fp_line
			(start -0.12065 -0.305054)
			(end -0.12065 -0.2794)
			(stroke
				(width 0.1)
				(type default)
			)
			(layer "F.Fab")
		)
		(pad "1" smd circle
			(at -0.40005 0 270)
			(size 0 0)
			(layers "F.Cu" "F.Mask" "F.Paste")
			(net "RST_CPU1_DRAM_AB_PLD_LVT3_R_N")
		)
		(pad "2" smd circle
			(at 0.40005 0 270)
			(size 0 0)
			(layers "F.Cu" "F.Mask" "F.Paste")
			(net "RST_CPU1_DRAM_AB_PLD_LVT3_N")
		)
	)
	(footprint ""
		(layer "F.Cu")
		(at 118.849902 -407.335228 180)
		(property "Reference" "R2830"
			(at 0 0 180)
			(layer "F.SilkS")
			(hide yes)
			(effects
				(font
					(size 1.27 1.27)
				)
			)
		)
		(property "Value" ""
			(at 0 0 180)
			(layer "F.Fab")
			(effects
				(font
					(size 1.27 1.27)
				)
			)
		)
		(duplicate_pad_numbers_are_jumpers no)
		(fp_line
			(start 0.7874 0.4064)
			(end -0.7874 0.4064)
			(stroke
				(width 0.1524)
				(type default)
			)
			(layer "F.SilkS")
		)
		(fp_line
			(start 0.7874 -0.4064)
			(end 0.7874 0.4064)
			(stroke
				(width 0.1524)
				(type default)
			)
			(layer "F.SilkS")
		)
		(fp_line
			(start -0.7874 0.4064)
			(end -0.7874 -0.4064)
			(stroke
				(width 0.1524)
				(type default)
			)
			(layer "F.SilkS")
		)
		(fp_line
			(start -0.7874 -0.4064)
			(end 0.7874 -0.4064)
			(stroke
				(width 0.1524)
				(type default)
			)
			(layer "F.SilkS")
		)
		(fp_line
			(start 0.67945 0.3048)
			(end 0.120396 0.3048)
			(stroke
				(width 0.1)
				(type default)
			)
			(layer "F.Fab")
		)
		(fp_line
			(start 0.67945 -0.3048)
			(end 0.67945 0.3048)
			(stroke
				(width 0.1)
				(type default)
			)
			(layer "F.Fab")
		)
		(fp_line
			(start 0.12065 -0.2794)
			(end 0.12065 -0.3048)
			(stroke
				(width 0.1)
				(type default)
			)
			(layer "F.Fab")
		)
		(fp_line
			(start 0.12065 -0.3048)
			(end 0.67945 -0.3048)
			(stroke
				(width 0.1)
				(type default)
			)
			(layer "F.Fab")
		)
		(fp_line
			(start 0.120396 0.3048)
			(end 0.120396 0.2794)
			(stroke
				(width 0.1)
				(type default)
			)
			(layer "F.Fab")
		)
		(fp_line
			(start 0.120396 0.2794)
			(end -0.12065 0.2794)
			(stroke
				(width 0.1)
				(type default)
			)
			(layer "F.Fab")
		)
		(fp_line
			(start -0.12065 0.3048)
			(end -0.67945 0.3048)
			(stroke
				(width 0.1)
				(type default)
			)
			(layer "F.Fab")
		)
		(fp_line
			(start -0.12065 0.2794)
			(end -0.12065 0.3048)
			(stroke
				(width 0.1)
				(type default)
			)
			(layer "F.Fab")
		)
		(fp_line
			(start -0.12065 -0.2794)
			(end 0.12065 -0.2794)
			(stroke
				(width 0.1)
				(type default)
			)
			(layer "F.Fab")
		)
		(fp_line
			(start -0.12065 -0.305054)
			(end -0.12065 -0.2794)
			(stroke
				(width 0.1)
				(type default)
			)
			(layer "F.Fab")
		)
		(fp_line
			(start -0.67945 0.3048)
			(end -0.67945 -0.305054)
			(stroke
				(width 0.1)
				(type default)
			)
			(layer "F.Fab")
		)
		(fp_line
			(start -0.67945 -0.305054)
			(end -0.12065 -0.305054)
			(stroke
				(width 0.1)
				(type default)
			)
			(layer "F.Fab")
		)
		(pad "1" smd circle
			(at -0.40005 0 180)
			(size 0 0)
			(layers "F.Cu" "F.Mask" "F.Paste")
			(net "P3V3_AUX")
		)
		(pad "2" smd circle
			(at 0.40005 0 180)
			(size 0 0)
			(layers "F.Cu" "F.Mask" "F.Paste")
			(net "BIC_MONITER")
		)
	)
	(footprint ""
		(layer "F.Cu")
		(at 29.977334 -169.000678 90)
		(property "Reference" "PC392"
			(at 0 0 90)
			(layer "F.SilkS")
			(hide yes)
			(effects
				(font
					(size 1.27 1.27)
				)
			)
		)
		(property "Value" ""
			(at 0 0 90)
			(layer "F.Fab")
			(effects
				(font
					(size 1.27 1.27)
				)
			)
		)
		(duplicate_pad_numbers_are_jumpers no)
		(fp_line
			(start 0.7874 -0.4064)
			(end 0.7874 0.4064)
			(stroke
				(width 0.1524)
				(type default)
			)
			(layer "F.SilkS")
		)
		(fp_line
			(start -0.7874 -0.4064)
			(end 0.7874 -0.4064)
			(stroke
				(width 0.1524)
				(type default)
			)
			(layer "F.SilkS")
		)
		(fp_line
			(start 0.7874 0.4064)
			(end -0.7874 0.4064)
			(stroke
				(width 0.1524)
				(type default)
			)
			(layer "F.SilkS")
		)
		(fp_line
			(start -0.7874 0.4064)
			(end -0.7874 -0.4064)
			(stroke
				(width 0.1524)
				(type default)
			)
			(layer "F.SilkS")
		)
		(fp_line
			(start -0.12065 -0.305054)
			(end -0.12065 -0.2794)
			(stroke
				(width 0.1)
				(type default)
			)
			(layer "F.Fab")
		)
		(fp_line
			(start -0.67945 -0.305054)
			(end -0.12065 -0.305054)
			(stroke
				(width 0.1)
				(type default)
			)
			(layer "F.Fab")
		)
		(fp_line
			(start 0.67945 -0.3048)
			(end 0.67945 0.3048)
			(stroke
				(width 0.1)
				(type default)
			)
			(layer "F.Fab")
		)
		(fp_line
			(start 0.12065 -0.3048)
			(end 0.67945 -0.3048)
			(stroke
				(width 0.1)
				(type default)
			)
			(layer "F.Fab")
		)
		(fp_line
			(start 0.12065 -0.2794)
			(end 0.12065 -0.3048)
			(stroke
				(width 0.1)
				(type default)
			)
			(layer "F.Fab")
		)
		(fp_line
			(start -0.12065 -0.2794)
			(end 0.12065 -0.2794)
			(stroke
				(width 0.1)
				(type default)
			)
			(layer "F.Fab")
		)
		(fp_line
			(start 0.120396 0.2794)
			(end -0.12065 0.2794)
			(stroke
				(width 0.1)
				(type default)
			)
			(layer "F.Fab")
		)
		(fp_line
			(start -0.12065 0.2794)
			(end -0.12065 0.3048)
			(stroke
				(width 0.1)
				(type default)
			)
			(layer "F.Fab")
		)
		(fp_line
			(start 0.67945 0.3048)
			(end 0.120396 0.3048)
			(stroke
				(width 0.1)
				(type default)
			)
			(layer "F.Fab")
		)
		(fp_line
			(start 0.120396 0.3048)
			(end 0.120396 0.2794)
			(stroke
				(width 0.1)
				(type default)
			)
			(layer "F.Fab")
		)
		(fp_line
			(start -0.12065 0.3048)
			(end -0.67945 0.3048)
			(stroke
				(width 0.1)
				(type default)
			)
			(layer "F.Fab")
		)
		(fp_line
			(start -0.67945 0.3048)
			(end -0.67945 -0.305054)
			(stroke
				(width 0.1)
				(type default)
			)
			(layer "F.Fab")
		)
		(pad "1" smd circle
			(at -0.40005 0 90)
			(size 0 0)
			(layers "F.Cu" "F.Mask" "F.Paste")
			(net "PVCCD_HV_CPU1_VREF")
		)
		(pad "2" smd circle
			(at 0.40005 0 90)
			(size 0 0)
			(layers "F.Cu" "F.Mask" "F.Paste")
			(net "GND")
		)
	)
	(footprint ""
		(layer "F.Cu")
		(at 214.61349 -23.304754 90)
		(property "Reference" "R1138"
			(at 0 0 90)
			(layer "F.SilkS")
			(hide yes)
			(effects
				(font
					(size 1.27 1.27)
				)
			)
		)
		(property "Value" ""
			(at 0 0 90)
			(layer "F.Fab")
			(effects
				(font
					(size 1.27 1.27)
				)
			)
		)
		(duplicate_pad_numbers_are_jumpers no)
		(fp_line
			(start 0.7874 -0.4064)
			(end 0.7874 0.4064)
			(stroke
				(width 0.1524)
				(type default)
			)
			(layer "F.SilkS")
		)
		(fp_line
			(start -0.7874 -0.4064)
			(end 0.7874 -0.4064)
			(stroke
				(width 0.1524)
				(type default)
			)
			(layer "F.SilkS")
		)
		(fp_line
			(start 0.7874 0.4064)
			(end -0.7874 0.4064)
			(stroke
				(width 0.1524)
				(type default)
			)
			(layer "F.SilkS")
		)
		(fp_line
			(start -0.7874 0.4064)
			(end -0.7874 -0.4064)
			(stroke
				(width 0.1524)
				(type default)
			)
			(layer "F.SilkS")
		)
		(fp_line
			(start -0.12065 -0.305054)
			(end -0.12065 -0.2794)
			(stroke
				(width 0.1)
				(type default)
			)
			(layer "F.Fab")
		)
		(fp_line
			(start -0.67945 -0.305054)
			(end -0.12065 -0.305054)
			(stroke
				(width 0.1)
				(type default)
			)
			(layer "F.Fab")
		)
		(fp_line
			(start 0.67945 -0.3048)
			(end 0.67945 0.3048)
			(stroke
				(width 0.1)
				(type default)
			)
			(layer "F.Fab")
		)
		(fp_line
			(start 0.12065 -0.3048)
			(end 0.67945 -0.3048)
			(stroke
				(width 0.1)
				(type default)
			)
			(layer "F.Fab")
		)
		(fp_line
			(start 0.12065 -0.2794)
			(end 0.12065 -0.3048)
			(stroke
				(width 0.1)
				(type default)
			)
			(layer "F.Fab")
		)
		(fp_line
			(start -0.12065 -0.2794)
			(end 0.12065 -0.2794)
			(stroke
				(width 0.1)
				(type default)
			)
			(layer "F.Fab")
		)
		(fp_line
			(start 0.120396 0.2794)
			(end -0.12065 0.2794)
			(stroke
				(width 0.1)
				(type default)
			)
			(layer "F.Fab")
		)
		(fp_line
			(start -0.12065 0.2794)
			(end -0.12065 0.3048)
			(stroke
				(width 0.1)
				(type default)
			)
			(layer "F.Fab")
		)
		(fp_line
			(start 0.67945 0.3048)
			(end 0.120396 0.3048)
			(stroke
				(width 0.1)
				(type default)
			)
			(layer "F.Fab")
		)
		(fp_line
			(start 0.120396 0.3048)
			(end 0.120396 0.2794)
			(stroke
				(width 0.1)
				(type default)
			)
			(layer "F.Fab")
		)
		(fp_line
			(start -0.12065 0.3048)
			(end -0.67945 0.3048)
			(stroke
				(width 0.1)
				(type default)
			)
			(layer "F.Fab")
		)
		(fp_line
			(start -0.67945 0.3048)
			(end -0.67945 -0.305054)
			(stroke
				(width 0.1)
				(type default)
			)
			(layer "F.Fab")
		)
		(pad "1" smd circle
			(at -0.40005 0 90)
			(size 0 0)
			(layers "F.Cu" "F.Mask" "F.Paste")
			(net "P3V3_AUX")
		)
		(pad "2" smd circle
			(at 0.40005 0 90)
			(size 0 0)
			(layers "F.Cu" "F.Mask" "F.Paste")
			(net "CLK_50M_EN")
		)
	)
	(footprint ""
		(layer "F.Cu")
		(at 71.79056 -56.159908 -90)
		(property "Reference" "PC2173"
			(at 0 0 270)
			(layer "F.SilkS")
			(hide yes)
			(effects
				(font
					(size 1.27 1.27)
				)
			)
		)
		(property "Value" ""
			(at 0 0 270)
			(layer "F.Fab")
			(effects
				(font
					(size 1.27 1.27)
				)
			)
		)
		(duplicate_pad_numbers_are_jumpers no)
		(fp_line
			(start -1.524 0.762)
			(end -1.524 -0.762)
			(stroke
				(width 0.1524)
				(type default)
			)
			(layer "F.SilkS")
		)
		(fp_line
			(start 1.524 0.762)
			(end -1.524 0.762)
			(stroke
				(width 0.1524)
				(type default)
			)
			(layer "F.SilkS")
		)
		(fp_line
			(start -1.524 -0.762)
			(end 1.524 -0.762)
			(stroke
				(width 0.1524)
				(type default)
			)
			(layer "F.SilkS")
		)
		(fp_line
			(start 1.524 -0.762)
			(end 1.524 0.762)
			(stroke
				(width 0.1524)
				(type default)
			)
			(layer "F.SilkS")
		)
		(fp_line
			(start -1.1049 0.724916)
			(end 1.1049 0.724916)
			(stroke
				(width 0.1)
				(type default)
			)
			(layer "F.Fab")
		)
		(fp_line
			(start 1.1049 0.724916)
			(end 1.1049 -0.724916)
			(stroke
				(width 0.1)
				(type default)
			)
			(layer "F.Fab")
		)
		(fp_line
			(start -1.1049 -0.724916)
			(end -1.1049 0.724916)
			(stroke
				(width 0.1)
				(type default)
			)
			(layer "F.Fab")
		)
		(fp_line
			(start 1.1049 -0.724916)
			(end -1.1049 -0.724916)
			(stroke
				(width 0.1)
				(type default)
			)
			(layer "F.Fab")
		)
		(pad "1" smd rect
			(at -0.889 0 90)
			(size 1.016 1.27)
			(layers "F.Cu" "F.Mask" "F.Paste")
			(net "P3V3_OCP_V3_2_R")
		)
		(pad "2" smd rect
			(at 0.889 0 90)
			(size 1.016 1.27)
			(layers "F.Cu" "F.Mask" "F.Paste")
			(net "GND")
		)
	)
	(footprint ""
		(layer "F.Cu")
		(at 22.809454 -114.431826 180)
		(property "Reference" "R3690"
			(at 0 0 180)
			(layer "F.SilkS")
			(hide yes)
			(effects
				(font
					(size 1.27 1.27)
				)
			)
		)
		(property "Value" ""
			(at 0 0 180)
			(layer "F.Fab")
			(effects
				(font
					(size 1.27 1.27)
				)
			)
		)
		(duplicate_pad_numbers_are_jumpers no)
		(fp_line
			(start 0.7874 0.4064)
			(end -0.7874 0.4064)
			(stroke
				(width 0.1524)
				(type default)
			)
			(layer "F.SilkS")
		)
		(fp_line
			(start 0.7874 -0.4064)
			(end 0.7874 0.4064)
			(stroke
				(width 0.1524)
				(type default)
			)
			(layer "F.SilkS")
		)
		(fp_line
			(start -0.7874 0.4064)
			(end -0.7874 -0.4064)
			(stroke
				(width 0.1524)
				(type default)
			)
			(layer "F.SilkS")
		)
		(fp_line
			(start -0.7874 -0.4064)
			(end 0.7874 -0.4064)
			(stroke
				(width 0.1524)
				(type default)
			)
			(layer "F.SilkS")
		)
		(fp_line
			(start 0.67945 0.3048)
			(end 0.120396 0.3048)
			(stroke
				(width 0.1)
				(type default)
			)
			(layer "F.Fab")
		)
		(fp_line
			(start 0.67945 -0.3048)
			(end 0.67945 0.3048)
			(stroke
				(width 0.1)
				(type default)
			)
			(layer "F.Fab")
		)
		(fp_line
			(start 0.12065 -0.2794)
			(end 0.12065 -0.3048)
			(stroke
				(width 0.1)
				(type default)
			)
			(layer "F.Fab")
		)
		(fp_line
			(start 0.12065 -0.3048)
			(end 0.67945 -0.3048)
			(stroke
				(width 0.1)
				(type default)
			)
			(layer "F.Fab")
		)
		(fp_line
			(start 0.120396 0.3048)
			(end 0.120396 0.2794)
			(stroke
				(width 0.1)
				(type default)
			)
			(layer "F.Fab")
		)
		(fp_line
			(start 0.120396 0.2794)
			(end -0.12065 0.2794)
			(stroke
				(width 0.1)
				(type default)
			)
			(layer "F.Fab")
		)
		(fp_line
			(start -0.12065 0.3048)
			(end -0.67945 0.3048)
			(stroke
				(width 0.1)
				(type default)
			)
			(layer "F.Fab")
		)
		(fp_line
			(start -0.12065 0.2794)
			(end -0.12065 0.3048)
			(stroke
				(width 0.1)
				(type default)
			)
			(layer "F.Fab")
		)
		(fp_line
			(start -0.12065 -0.2794)
			(end 0.12065 -0.2794)
			(stroke
				(width 0.1)
				(type default)
			)
			(layer "F.Fab")
		)
		(fp_line
			(start -0.12065 -0.305054)
			(end -0.12065 -0.2794)
			(stroke
				(width 0.1)
				(type default)
			)
			(layer "F.Fab")
		)
		(fp_line
			(start -0.67945 0.3048)
			(end -0.67945 -0.305054)
			(stroke
				(width 0.1)
				(type default)
			)
			(layer "F.Fab")
		)
		(fp_line
			(start -0.67945 -0.305054)
			(end -0.12065 -0.305054)
			(stroke
				(width 0.1)
				(type default)
			)
			(layer "F.Fab")
		)
		(pad "1" smd circle
			(at -0.40005 0 180)
			(size 0 0)
			(layers "F.Cu" "F.Mask" "F.Paste")
			(net "ADC128_VREF")
		)
		(pad "2" smd circle
			(at 0.40005 0 180)
			(size 0 0)
			(layers "F.Cu" "F.Mask" "F.Paste")
			(net "GND")
		)
	)
	(footprint ""
		(layer "F.Cu")
		(at 463.562954 -93.396054)
		(property "Reference" "R3232"
			(at 0 0 0)
			(layer "F.SilkS")
			(hide yes)
			(effects
				(font
					(size 1.27 1.27)
				)
			)
		)
		(property "Value" ""
			(at 0 0 0)
			(layer "F.Fab")
			(effects
				(font
					(size 1.27 1.27)
				)
			)
		)
		(duplicate_pad_numbers_are_jumpers no)
		(fp_line
			(start -0.7874 -0.4064)
			(end 0.7874 -0.4064)
			(stroke
				(width 0.1524)
				(type default)
			)
			(layer "F.SilkS")
		)
		(fp_line
			(start -0.7874 0.4064)
			(end -0.7874 -0.4064)
			(stroke
				(width 0.1524)
				(type default)
			)
			(layer "F.SilkS")
		)
		(fp_line
			(start 0.7874 -0.4064)
			(end 0.7874 0.4064)
			(stroke
				(width 0.1524)
				(type default)
			)
			(layer "F.SilkS")
		)
		(fp_line
			(start 0.7874 0.4064)
			(end -0.7874 0.4064)
			(stroke
				(width 0.1524)
				(type default)
			)
			(layer "F.SilkS")
		)
		(fp_line
			(start -0.67945 -0.305054)
			(end -0.12065 -0.305054)
			(stroke
				(width 0.1)
				(type default)
			)
			(layer "F.Fab")
		)
		(fp_line
			(start -0.67945 0.3048)
			(end -0.67945 -0.305054)
			(stroke
				(width 0.1)
				(type default)
			)
			(layer "F.Fab")
		)
		(fp_line
			(start -0.12065 -0.305054)
			(end -0.12065 -0.2794)
			(stroke
				(width 0.1)
				(type default)
			)
			(layer "F.Fab")
		)
		(fp_line
			(start -0.12065 -0.2794)
			(end 0.12065 -0.2794)
			(stroke
				(width 0.1)
				(type default)
			)
			(layer "F.Fab")
		)
		(fp_line
			(start -0.12065 0.2794)
			(end -0.12065 0.3048)
			(stroke
				(width 0.1)
				(type default)
			)
			(layer "F.Fab")
		)
		(fp_line
			(start -0.12065 0.3048)
			(end -0.67945 0.3048)
			(stroke
				(width 0.1)
				(type default)
			)
			(layer "F.Fab")
		)
		(fp_line
			(start 0.120396 0.2794)
			(end -0.12065 0.2794)
			(stroke
				(width 0.1)
				(type default)
			)
			(layer "F.Fab")
		)
		(fp_line
			(start 0.120396 0.3048)
			(end 0.120396 0.2794)
			(stroke
				(width 0.1)
				(type default)
			)
			(layer "F.Fab")
		)
		(fp_line
			(start 0.12065 -0.3048)
			(end 0.67945 -0.3048)
			(stroke
				(width 0.1)
				(type default)
			)
			(layer "F.Fab")
		)
		(fp_line
			(start 0.12065 -0.2794)
			(end 0.12065 -0.3048)
			(stroke
				(width 0.1)
				(type default)
			)
			(layer "F.Fab")
		)
		(fp_line
			(start 0.67945 -0.3048)
			(end 0.67945 0.3048)
			(stroke
				(width 0.1)
				(type default)
			)
			(layer "F.Fab")
		)
		(fp_line
			(start 0.67945 0.3048)
			(end 0.120396 0.3048)
			(stroke
				(width 0.1)
				(type default)
			)
			(layer "F.Fab")
		)
		(pad "1" smd circle
			(at -0.40005 0)
			(size 0 0)
			(layers "F.Cu" "F.Mask" "F.Paste")
			(net "RST_HP_OCP_SFF_R_N")
		)
		(pad "2" smd circle
			(at 0.40005 0)
			(size 0 0)
			(layers "F.Cu" "F.Mask" "F.Paste")
			(net "GND")
		)
	)
	(footprint ""
		(layer "F.Cu")
		(at 255.493012 -76.222098 90)
		(property "Reference" "PC1215"
			(at 0 0 90)
			(layer "F.SilkS")
			(hide yes)
			(effects
				(font
					(size 1.27 1.27)
				)
			)
		)
		(property "Value" ""
			(at 0 0 90)
			(layer "F.Fab")
			(effects
				(font
					(size 1.27 1.27)
				)
			)
		)
		(duplicate_pad_numbers_are_jumpers no)
		(fp_line
			(start 2.750058 -2.750058)
			(end -1.988058 -2.750058)
			(stroke
				(width 0.1524)
				(type default)
			)
			(layer "F.SilkS")
		)
		(fp_line
			(start -1.988058 -2.750058)
			(end -2.750058 -1.988058)
			(stroke
				(width 0.1524)
				(type default)
			)
			(layer "F.SilkS")
		)
		(fp_line
			(start -2.750058 -1.988058)
			(end -2.750058 -0.9398)
			(stroke
				(width 0.1524)
				(type default)
			)
			(layer "F.SilkS")
		)
		(fp_line
			(start 2.750058 -0.9398)
			(end 2.750058 -2.750058)
			(stroke
				(width 0.1524)
				(type default)
			)
			(layer "F.SilkS")
		)
		(fp_line
			(start -2.750058 0.9398)
			(end -2.750058 1.988058)
			(stroke
				(width 0.1524)
				(type default)
			)
			(layer "F.SilkS")
		)
		(fp_line
			(start -2.750058 1.988058)
			(end -1.988058 2.750058)
			(stroke
				(width 0.1524)
				(type default)
			)
			(layer "F.SilkS")
		)
		(fp_line
			(start 2.750058 2.750058)
			(end 2.750058 0.9398)
			(stroke
				(width 0.1524)
				(type default)
			)
			(layer "F.SilkS")
		)
		(fp_line
			(start -1.988058 2.750058)
			(end 2.750058 2.750058)
			(stroke
				(width 0.1524)
				(type default)
			)
			(layer "F.SilkS")
		)
		(fp_line
			(start 2.750058 -2.750058)
			(end -2.750058 -2.750058)
			(stroke
				(width 0.1)
				(type default)
			)
			(layer "F.Fab")
		)
		(fp_line
			(start -2.750058 -2.750058)
			(end -2.750058 2.750058)
			(stroke
				(width 0.1)
				(type default)
			)
			(layer "F.Fab")
		)
		(fp_line
			(start 2.750058 2.750058)
			(end 2.750058 -2.750058)
			(stroke
				(width 0.1)
				(type default)
			)
			(layer "F.Fab")
		)
		(fp_line
			(start -2.750058 2.750058)
			(end 2.750058 2.750058)
			(stroke
				(width 0.1)
				(type default)
			)
			(layer "F.Fab")
		)
		(pad "1" smd rect
			(at -2.199894 0 180)
			(size 1.6002 3.0226)
			(layers "F.Cu" "F.Mask" "F.Paste")
			(net "SW_P12V_AUX_P1V05_PCH_AUX_FLT")
		)
		(pad "2" smd rect
			(at 2.199894 0 180)
			(size 1.6002 3.0226)
			(layers "F.Cu" "F.Mask" "F.Paste")
			(net "GND")
		)
	)
	(footprint ""
		(layer "F.Cu")
		(at 76.869798 -408.517344 -90)
		(property "Reference" "C690"
			(at 0 0 270)
			(layer "F.SilkS")
			(hide yes)
			(effects
				(font
					(size 1.27 1.27)
				)
			)
		)
		(property "Value" ""
			(at 0 0 270)
			(layer "F.Fab")
			(effects
				(font
					(size 1.27 1.27)
				)
			)
		)
		(duplicate_pad_numbers_are_jumpers no)
		(fp_line
			(start -0.299974 0.150114)
			(end -0.299974 -0.150114)
			(stroke
				(width 0.1)
				(type default)
			)
			(layer "F.Fab")
		)
		(fp_line
			(start 0.299974 0.150114)
			(end -0.299974 0.150114)
			(stroke
				(width 0.1)
				(type default)
			)
			(layer "F.Fab")
		)
		(fp_line
			(start -0.299974 -0.150114)
			(end 0.299974 -0.150114)
			(stroke
				(width 0.1)
				(type default)
			)
			(layer "F.Fab")
		)
		(fp_line
			(start 0.299974 -0.150114)
			(end 0.299974 0.150114)
			(stroke
				(width 0.1)
				(type default)
			)
			(layer "F.Fab")
		)
		(pad "1" smd rect
			(at -0.2667 0 270)
			(size 0.3048 0.381)
			(layers "F.Cu" "F.Mask" "F.Paste")
			(net "P5E_CPU1_PE4_TX_C_DN<9>")
		)
		(pad "2" smd rect
			(at 0.2667 0 270)
			(size 0.3048 0.381)
			(layers "F.Cu" "F.Mask" "F.Paste")
			(net "P5E_CPU1_PE4_TX_DN<9>")
		)
	)
	(footprint ""
		(layer "F.Cu")
		(at 426.630084 -44.619926)
		(property "Reference" "J104"
			(at 1.19126 -2.926588 0)
			(unlocked yes)
			(layer "F.SilkS")
			(effects
				(font
					(size 0.7874 0.5842)
					(thickness 0.1524)
				)
				(justify left)
			)
		)
		(property "Value" ""
			(at 0 0 0)
			(layer "F.Fab")
			(effects
				(font
					(size 1.27 1.27)
				)
			)
		)
		(duplicate_pad_numbers_are_jumpers no)
		(fp_line
			(start -1.230122 -1.27)
			(end -1.230122 16.51)
			(stroke
				(width 0.1524)
				(type default)
			)
			(layer "F.SilkS")
		)
		(fp_line
			(start -1.230122 16.51)
			(end 3.770122 16.51)
			(stroke
				(width 0.1524)
				(type default)
			)
			(layer "F.SilkS")
		)
		(fp_line
			(start 3.770122 -1.27)
			(end -1.230122 -1.27)
			(stroke
				(width 0.1524)
				(type default)
			)
			(layer "F.SilkS")
		)
		(fp_line
			(start 3.770122 16.51)
			(end 3.770122 -1.27)
			(stroke
				(width 0.1524)
				(type default)
			)
			(layer "F.SilkS")
		)
		(fp_poly
			(pts
				(xy 0.45974 -2.63144) (xy -0.04826 -1.61544) (xy -0.55626 -2.63144)
			)
			(stroke
				(width 0)
				(type default)
			)
			(fill yes)
			(layer "F.SilkS")
		)
		(fp_line
			(start -1.230122 -1.27)
			(end -1.230122 16.51)
			(stroke
				(width 0.1)
				(type default)
			)
			(layer "F.Fab")
		)
		(fp_line
			(start -1.230122 16.51)
			(end 3.770122 16.51)
			(stroke
				(width 0.1)
				(type default)
			)
			(layer "F.Fab")
		)
		(fp_line
			(start 3.770122 -1.27)
			(end -1.230122 -1.27)
			(stroke
				(width 0.1)
				(type default)
			)
			(layer "F.Fab")
		)
		(fp_line
			(start 3.770122 16.51)
			(end 3.770122 -1.27)
			(stroke
				(width 0.1)
				(type default)
			)
			(layer "F.Fab")
		)
		(fp_poly
			(pts
				(xy 0.508 -2.5146) (xy -0.508 -2.5146) (xy 0 -1.4986)
			)
			(stroke
				(width 0)
				(type default)
			)
			(fill yes)
			(layer "F.Fab")
		)
		(fp_text user "13"
			(at -0.684022 17.95145 0)
			(unlocked yes)
			(layer "F.SilkS")
			(effects
				(font
					(size 0.7874 0.5842)
					(thickness 0.1524)
				)
				(justify left)
			)
		)
		(fp_text user "14"
			(at 1.855978 17.95145 0)
			(unlocked yes)
			(layer "F.SilkS")
			(effects
				(font
					(size 0.7874 0.5842)
					(thickness 0.1524)
				)
				(justify left)
			)
		)
		(fp_text user "2"
			(at 4.372356 -1.470152 0)
			(unlocked yes)
			(layer "F.SilkS")
			(effects
				(font
					(size 0.7874 0.5842)
					(thickness 0.1524)
				)
				(justify left)
			)
		)
		(fp_text user "1"
			(at 0.026416 -2.300732 0)
			(unlocked yes)
			(layer "B.SilkS")
			(effects
				(font
					(size 0.7874 0.5842)
					(thickness 0.1524)
				)
				(justify left mirror)
			)
		)
		(fp_text user "13"
			(at 0.524256 17.173448 0)
			(unlocked yes)
			(layer "B.SilkS")
			(effects
				(font
					(size 0.7874 0.5842)
					(thickness 0.1524)
				)
				(justify left mirror)
			)
		)
		(fp_text user "2"
			(at 3.356356 -1.955292 0)
			(unlocked yes)
			(layer "B.SilkS")
			(effects
				(font
					(size 0.7874 0.5842)
					(thickness 0.1524)
				)
				(justify left mirror)
			)
		)
		(fp_text user "14"
			(at 4.273296 17.249648 0)
			(unlocked yes)
			(layer "B.SilkS")
			(effects
				(font
					(size 0.7874 0.5842)
					(thickness 0.1524)
				)
				(justify left mirror)
			)
		)
		(fp_text user "1"
			(at 0.091948 -0.9779 270)
			(unlocked yes)
			(layer "B.Fab")
			(effects
				(font
					(size 0.7874 0.5842)
					(thickness 0.1524)
				)
				(justify left mirror)
			)
		)
		(fp_text user "13"
			(at 0.091948 17.7038 270)
			(unlocked yes)
			(layer "B.Fab")
			(effects
				(font
					(size 0.7874 0.5842)
					(thickness 0.1524)
				)
				(justify left mirror)
			)
		)
		(fp_text user "2"
			(at 2.631948 -0.9779 270)
			(unlocked yes)
			(layer "B.Fab")
			(effects
				(font
					(size 0.7874 0.5842)
					(thickness 0.1524)
				)
				(justify left mirror)
			)
		)
		(fp_text user "14"
			(at 2.631948 17.7038 270)
			(unlocked yes)
			(layer "B.Fab")
			(effects
				(font
					(size 0.7874 0.5842)
					(thickness 0.1524)
				)
				(justify left mirror)
			)
		)
		(fp_text user "13"
			(at 0.091948 16.5862 270)
			(unlocked yes)
			(layer "F.Fab")
			(effects
				(font
					(size 0.7874 0.5842)
					(thickness 0.1524)
				)
				(justify left)
			)
		)
		(fp_text user "2"
			(at 2.631948 -2.0701 270)
			(unlocked yes)
			(layer "F.Fab")
			(effects
				(font
					(size 0.7874 0.5842)
					(thickness 0.1524)
				)
				(justify left)
			)
		)
		(fp_text user "14"
			(at 2.631948 16.5862 270)
			(unlocked yes)
			(layer "F.Fab")
			(effects
				(font
					(size 0.7874 0.5842)
					(thickness 0.1524)
				)
				(justify left)
			)
		)
		(pad "1" thru_hole rect
			(at 0 0 270)
			(size 1.5494 1.5494)
			(drill 1.0414)
			(layers "*.Cu" "*.Mask")
			(remove_unused_layers no)
			(net "PU_ESPI_ENABLE_STRAP")
			(clearance 0)
			(padstack
				(mode front_inner_back)
				(layer "Inner"
					(shape circle)
					(size 1.5494 1.5494)
					(clearance 0)
				)
				(layer "B.Cu"
					(shape rect)
					(size 1.5494 1.5494)
					(clearance 0)
				)
			)
		)
		(pad "2" thru_hole circle
			(at 2.54 0 270)
			(size 1.5494 1.5494)
			(drill 1.0414)
			(layers "*.Cu" "*.Mask")
			(remove_unused_layers no)
			(net "JTAG_TRC_PCH_PTI<6>")
			(clearance 0)
		)
		(pad "3" thru_hole circle
			(at 0 2.54 270)
			(size 1.5494 1.5494)
			(drill 1.0414)
			(layers "*.Cu" "*.Mask")
			(remove_unused_layers no)
			(net "PU_BIOS_RCVR_BOOT")
			(clearance 0)
		)
		(pad "4" thru_hole circle
			(at 2.54 2.54 270)
			(size 1.5494 1.5494)
			(drill 1.0414)
			(layers "*.Cu" "*.Mask")
			(remove_unused_layers no)
			(net "FM_PCH_BIOS_RCVR_MODE")
			(clearance 0)
		)
		(pad "5" thru_hole circle
			(at 0 5.08 270)
			(size 1.5494 1.5494)
			(drill 1.0414)
			(layers "*.Cu" "*.Mask")
			(remove_unused_layers no)
			(net "PU_SWAP_OVERRIDE_N")
			(clearance 0)
		)
		(pad "6" thru_hole circle
			(at 2.54 5.08 270)
			(size 1.5494 1.5494)
			(drill 1.0414)
			(layers "*.Cu" "*.Mask")
			(remove_unused_layers no)
			(net "FM_ADR_COMPLETE")
			(clearance 0)
		)
		(pad "7" thru_hole circle
			(at 0 7.62 270)
			(size 1.5494 1.5494)
			(drill 1.0414)
			(layers "*.Cu" "*.Mask")
			(remove_unused_layers no)
			(net "PD_BIOS_IMAGE_SWAP_N")
			(clearance 0)
		)
		(pad "8" thru_hole circle
			(at 2.54 7.62 270)
			(size 1.5494 1.5494)
			(drill 1.0414)
			(layers "*.Cu" "*.Mask")
			(remove_unused_layers no)
			(net "FM_BIOS_IMAGE_SWAP_N")
			(clearance 0)
		)
		(pad "9" thru_hole circle
			(at 0 10.16 270)
			(size 1.5494 1.5494)
			(drill 1.0414)
			(layers "*.Cu" "*.Mask")
			(remove_unused_layers no)
			(net "PU_FLASH_SECURITY_STRAP")
			(clearance 0)
		)
		(pad "10" thru_hole circle
			(at 2.54 10.16 270)
			(size 1.5494 1.5494)
			(drill 1.0414)
			(layers "*.Cu" "*.Mask")
			(remove_unused_layers no)
			(net "FM_FLASH_SECURITY_STRAP")
			(clearance 0)
		)
		(pad "11" thru_hole circle
			(at 0 12.7 270)
			(size 1.5494 1.5494)
			(drill 1.0414)
			(layers "*.Cu" "*.Mask")
			(remove_unused_layers no)
			(net "PD_ME_RCVR_N")
			(clearance 0)
		)
		(pad "12" thru_hole circle
			(at 2.54 12.7 270)
			(size 1.5494 1.5494)
			(drill 1.0414)
			(layers "*.Cu" "*.Mask")
			(remove_unused_layers no)
			(net "FM_ME_RCVR_N")
			(clearance 0)
		)
		(pad "13" thru_hole circle
			(at 0 15.24 270)
			(size 1.5494 1.5494)
			(drill 1.0414)
			(layers "*.Cu" "*.Mask")
			(remove_unused_layers no)
			(net "PD_PASSWORD_CLEAR")
			(clearance 0)
		)
		(pad "14" thru_hole circle
			(at 2.54 15.24 270)
			(size 1.5494 1.5494)
			(drill 1.0414)
			(layers "*.Cu" "*.Mask")
			(remove_unused_layers no)
			(net "FM_PASSWORD_CLEAR_N")
			(clearance 0)
		)
	)
	(footprint ""
		(layer "F.Cu")
		(at 355.219 -390.439148 180)
		(property "Reference" "R4570"
			(at 0 0 180)
			(layer "F.SilkS")
			(hide yes)
			(effects
				(font
					(size 1.27 1.27)
				)
			)
		)
		(property "Value" ""
			(at 0 0 180)
			(layer "F.Fab")
			(effects
				(font
					(size 1.27 1.27)
				)
			)
		)
		(duplicate_pad_numbers_are_jumpers no)
		(fp_line
			(start 0.7874 0.4064)
			(end -0.7874 0.4064)
			(stroke
				(width 0.1524)
				(type default)
			)
			(layer "F.SilkS")
		)
		(fp_line
			(start 0.7874 -0.4064)
			(end 0.7874 0.4064)
			(stroke
				(width 0.1524)
				(type default)
			)
			(layer "F.SilkS")
		)
		(fp_line
			(start -0.7874 0.4064)
			(end -0.7874 -0.4064)
			(stroke
				(width 0.1524)
				(type default)
			)
			(layer "F.SilkS")
		)
		(fp_line
			(start -0.7874 -0.4064)
			(end 0.7874 -0.4064)
			(stroke
				(width 0.1524)
				(type default)
			)
			(layer "F.SilkS")
		)
		(fp_line
			(start 0.67945 0.3048)
			(end 0.120396 0.3048)
			(stroke
				(width 0.1)
				(type default)
			)
			(layer "F.Fab")
		)
		(fp_line
			(start 0.67945 -0.3048)
			(end 0.67945 0.3048)
			(stroke
				(width 0.1)
				(type default)
			)
			(layer "F.Fab")
		)
		(fp_line
			(start 0.12065 -0.2794)
			(end 0.12065 -0.3048)
			(stroke
				(width 0.1)
				(type default)
			)
			(layer "F.Fab")
		)
		(fp_line
			(start 0.12065 -0.3048)
			(end 0.67945 -0.3048)
			(stroke
				(width 0.1)
				(type default)
			)
			(layer "F.Fab")
		)
		(fp_line
			(start 0.120396 0.3048)
			(end 0.120396 0.2794)
			(stroke
				(width 0.1)
				(type default)
			)
			(layer "F.Fab")
		)
		(fp_line
			(start 0.120396 0.2794)
			(end -0.12065 0.2794)
			(stroke
				(width 0.1)
				(type default)
			)
			(layer "F.Fab")
		)
		(fp_line
			(start -0.12065 0.3048)
			(end -0.67945 0.3048)
			(stroke
				(width 0.1)
				(type default)
			)
			(layer "F.Fab")
		)
		(fp_line
			(start -0.12065 0.2794)
			(end -0.12065 0.3048)
			(stroke
				(width 0.1)
				(type default)
			)
			(layer "F.Fab")
		)
		(fp_line
			(start -0.12065 -0.2794)
			(end 0.12065 -0.2794)
			(stroke
				(width 0.1)
				(type default)
			)
			(layer "F.Fab")
		)
		(fp_line
			(start -0.12065 -0.305054)
			(end -0.12065 -0.2794)
			(stroke
				(width 0.1)
				(type default)
			)
			(layer "F.Fab")
		)
		(fp_line
			(start -0.67945 0.3048)
			(end -0.67945 -0.305054)
			(stroke
				(width 0.1)
				(type default)
			)
			(layer "F.Fab")
		)
		(fp_line
			(start -0.67945 -0.305054)
			(end -0.12065 -0.305054)
			(stroke
				(width 0.1)
				(type default)
			)
			(layer "F.Fab")
		)
		(pad "1" smd circle
			(at -0.40005 0 180)
			(size 0 0)
			(layers "F.Cu" "F.Mask" "F.Paste")
			(net "GPU_3V3IO_RSVD3")
		)
		(pad "2" smd circle
			(at 0.40005 0 180)
			(size 0 0)
			(layers "F.Cu" "F.Mask" "F.Paste")
			(net "GPU_3V3IO_RSVD3_ISO")
		)
	)
	(footprint ""
		(layer "F.Cu")
		(at 300.21022 -419.02761 -90)
		(property "Reference" "R4122"
			(at 0 0 270)
			(layer "F.SilkS")
			(hide yes)
			(effects
				(font
					(size 1.27 1.27)
				)
			)
		)
		(property "Value" ""
			(at 0 0 270)
			(layer "F.Fab")
			(effects
				(font
					(size 1.27 1.27)
				)
			)
		)
		(duplicate_pad_numbers_are_jumpers no)
		(fp_line
			(start -0.7874 0.4064)
			(end -0.7874 -0.4064)
			(stroke
				(width 0.1524)
				(type default)
			)
			(layer "F.SilkS")
		)
		(fp_line
			(start 0.7874 0.4064)
			(end -0.7874 0.4064)
			(stroke
				(width 0.1524)
				(type default)
			)
			(layer "F.SilkS")
		)
		(fp_line
			(start -0.7874 -0.4064)
			(end 0.7874 -0.4064)
			(stroke
				(width 0.1524)
				(type default)
			)
			(layer "F.SilkS")
		)
		(fp_line
			(start 0.7874 -0.4064)
			(end 0.7874 0.4064)
			(stroke
				(width 0.1524)
				(type default)
			)
			(layer "F.SilkS")
		)
		(fp_line
			(start -0.67945 0.3048)
			(end -0.67945 -0.305054)
			(stroke
				(width 0.1)
				(type default)
			)
			(layer "F.Fab")
		)
		(fp_line
			(start -0.12065 0.3048)
			(end -0.67945 0.3048)
			(stroke
				(width 0.1)
				(type default)
			)
			(layer "F.Fab")
		)
		(fp_line
			(start 0.120396 0.3048)
			(end 0.120396 0.2794)
			(stroke
				(width 0.1)
				(type default)
			)
			(layer "F.Fab")
		)
		(fp_line
			(start 0.67945 0.3048)
			(end 0.120396 0.3048)
			(stroke
				(width 0.1)
				(type default)
			)
			(layer "F.Fab")
		)
		(fp_line
			(start -0.12065 0.2794)
			(end -0.12065 0.3048)
			(stroke
				(width 0.1)
				(type default)
			)
			(layer "F.Fab")
		)
		(fp_line
			(start 0.120396 0.2794)
			(end -0.12065 0.2794)
			(stroke
				(width 0.1)
				(type default)
			)
			(layer "F.Fab")
		)
		(fp_line
			(start -0.12065 -0.2794)
			(end 0.12065 -0.2794)
			(stroke
				(width 0.1)
				(type default)
			)
			(layer "F.Fab")
		)
		(fp_line
			(start 0.12065 -0.2794)
			(end 0.12065 -0.3048)
			(stroke
				(width 0.1)
				(type default)
			)
			(layer "F.Fab")
		)
		(fp_line
			(start 0.12065 -0.3048)
			(end 0.67945 -0.3048)
			(stroke
				(width 0.1)
				(type default)
			)
			(layer "F.Fab")
		)
		(fp_line
			(start 0.67945 -0.3048)
			(end 0.67945 0.3048)
			(stroke
				(width 0.1)
				(type default)
			)
			(layer "F.Fab")
		)
		(fp_line
			(start -0.67945 -0.305054)
			(end -0.12065 -0.305054)
			(stroke
				(width 0.1)
				(type default)
			)
			(layer "F.Fab")
		)
		(fp_line
			(start -0.12065 -0.305054)
			(end -0.12065 -0.2794)
			(stroke
				(width 0.1)
				(type default)
			)
			(layer "F.Fab")
		)
		(pad "1" smd circle
			(at -0.40005 0 270)
			(size 0 0)
			(layers "F.Cu" "F.Mask" "F.Paste")
			(net "PRSNT_CABLE_GPU_B3_N")
		)
		(pad "2" smd circle
			(at 0.40005 0 270)
			(size 0 0)
			(layers "F.Cu" "F.Mask" "F.Paste")
			(net "GND")
		)
	)
	(footprint ""
		(layer "F.Cu")
		(at 407.91257 -157.691328)
		(property "Reference" "PC641"
			(at 0 0 0)
			(layer "F.SilkS")
			(hide yes)
			(effects
				(font
					(size 1.27 1.27)
				)
			)
		)
		(property "Value" ""
			(at 0 0 0)
			(layer "F.Fab")
			(effects
				(font
					(size 1.27 1.27)
				)
			)
		)
		(duplicate_pad_numbers_are_jumpers no)
		(fp_line
			(start -1.524 -0.762)
			(end 1.524 -0.762)
			(stroke
				(width 0.1524)
				(type default)
			)
			(layer "F.SilkS")
		)
		(fp_line
			(start -1.524 0.762)
			(end -1.524 -0.762)
			(stroke
				(width 0.1524)
				(type default)
			)
			(layer "F.SilkS")
		)
		(fp_line
			(start 1.524 -0.762)
			(end 1.524 0.762)
			(stroke
				(width 0.1524)
				(type default)
			)
			(layer "F.SilkS")
		)
		(fp_line
			(start 1.524 0.762)
			(end -1.524 0.762)
			(stroke
				(width 0.1524)
				(type default)
			)
			(layer "F.SilkS")
		)
		(fp_line
			(start -1.1049 -0.724916)
			(end -1.1049 0.724916)
			(stroke
				(width 0.1)
				(type default)
			)
			(layer "F.Fab")
		)
		(fp_line
			(start -1.1049 0.724916)
			(end 1.1049 0.724916)
			(stroke
				(width 0.1)
				(type default)
			)
			(layer "F.Fab")
		)
		(fp_line
			(start 1.1049 -0.724916)
			(end -1.1049 -0.724916)
			(stroke
				(width 0.1)
				(type default)
			)
			(layer "F.Fab")
		)
		(fp_line
			(start 1.1049 0.724916)
			(end 1.1049 -0.724916)
			(stroke
				(width 0.1)
				(type default)
			)
			(layer "F.Fab")
		)
		(pad "1" smd rect
			(at -0.889 0 180)
			(size 1.016 1.27)
			(layers "F.Cu" "F.Mask" "F.Paste")
			(net "PVCCD_HV_CPU0")
		)
		(pad "2" smd rect
			(at 0.889 0 180)
			(size 1.016 1.27)
			(layers "F.Cu" "F.Mask" "F.Paste")
			(net "GND")
		)
	)
	(footprint ""
		(layer "F.Cu")
		(at 411.35681 -29.478986 -90)
		(property "Reference" "R1333"
			(at 0 0 270)
			(layer "F.SilkS")
			(hide yes)
			(effects
				(font
					(size 1.27 1.27)
				)
			)
		)
		(property "Value" ""
			(at 0 0 270)
			(layer "F.Fab")
			(effects
				(font
					(size 1.27 1.27)
				)
			)
		)
		(duplicate_pad_numbers_are_jumpers no)
		(fp_line
			(start -0.7874 0.4064)
			(end -0.7874 -0.4064)
			(stroke
				(width 0.1524)
				(type default)
			)
			(layer "F.SilkS")
		)
		(fp_line
			(start 0.7874 0.4064)
			(end -0.7874 0.4064)
			(stroke
				(width 0.1524)
				(type default)
			)
			(layer "F.SilkS")
		)
		(fp_line
			(start -0.7874 -0.4064)
			(end 0.7874 -0.4064)
			(stroke
				(width 0.1524)
				(type default)
			)
			(layer "F.SilkS")
		)
		(fp_line
			(start 0.7874 -0.4064)
			(end 0.7874 0.4064)
			(stroke
				(width 0.1524)
				(type default)
			)
			(layer "F.SilkS")
		)
		(fp_line
			(start -0.67945 0.3048)
			(end -0.67945 -0.305054)
			(stroke
				(width 0.1)
				(type default)
			)
			(layer "F.Fab")
		)
		(fp_line
			(start -0.12065 0.3048)
			(end -0.67945 0.3048)
			(stroke
				(width 0.1)
				(type default)
			)
			(layer "F.Fab")
		)
		(fp_line
			(start 0.120396 0.3048)
			(end 0.120396 0.2794)
			(stroke
				(width 0.1)
				(type default)
			)
			(layer "F.Fab")
		)
		(fp_line
			(start 0.67945 0.3048)
			(end 0.120396 0.3048)
			(stroke
				(width 0.1)
				(type default)
			)
			(layer "F.Fab")
		)
		(fp_line
			(start -0.12065 0.2794)
			(end -0.12065 0.3048)
			(stroke
				(width 0.1)
				(type default)
			)
			(layer "F.Fab")
		)
		(fp_line
			(start 0.120396 0.2794)
			(end -0.12065 0.2794)
			(stroke
				(width 0.1)
				(type default)
			)
			(layer "F.Fab")
		)
		(fp_line
			(start -0.12065 -0.2794)
			(end 0.12065 -0.2794)
			(stroke
				(width 0.1)
				(type default)
			)
			(layer "F.Fab")
		)
		(fp_line
			(start 0.12065 -0.2794)
			(end 0.12065 -0.3048)
			(stroke
				(width 0.1)
				(type default)
			)
			(layer "F.Fab")
		)
		(fp_line
			(start 0.12065 -0.3048)
			(end 0.67945 -0.3048)
			(stroke
				(width 0.1)
				(type default)
			)
			(layer "F.Fab")
		)
		(fp_line
			(start 0.67945 -0.3048)
			(end 0.67945 0.3048)
			(stroke
				(width 0.1)
				(type default)
			)
			(layer "F.Fab")
		)
		(fp_line
			(start -0.67945 -0.305054)
			(end -0.12065 -0.305054)
			(stroke
				(width 0.1)
				(type default)
			)
			(layer "F.Fab")
		)
		(fp_line
			(start -0.12065 -0.305054)
			(end -0.12065 -0.2794)
			(stroke
				(width 0.1)
				(type default)
			)
			(layer "F.Fab")
		)
		(pad "1" smd circle
			(at -0.40005 0 270)
			(size 0 0)
			(layers "F.Cu" "F.Mask" "F.Paste")
			(net "GND")
		)
		(pad "2" smd circle
			(at 0.40005 0 270)
			(size 0 0)
			(layers "F.Cu" "F.Mask" "F.Paste")
			(net "PD_RST_RTCRST_N")
		)
	)
	(footprint ""
		(layer "F.Cu")
		(at 164.64788 -117.566948)
		(property "Reference" "R1753"
			(at 0 0 0)
			(layer "F.SilkS")
			(hide yes)
			(effects
				(font
					(size 1.27 1.27)
				)
			)
		)
		(property "Value" ""
			(at 0 0 0)
			(layer "F.Fab")
			(effects
				(font
					(size 1.27 1.27)
				)
			)
		)
		(duplicate_pad_numbers_are_jumpers no)
		(fp_line
			(start -0.7874 -0.4064)
			(end 0.7874 -0.4064)
			(stroke
				(width 0.1524)
				(type default)
			)
			(layer "F.SilkS")
		)
		(fp_line
			(start -0.7874 0.4064)
			(end -0.7874 -0.4064)
			(stroke
				(width 0.1524)
				(type default)
			)
			(layer "F.SilkS")
		)
		(fp_line
			(start 0.7874 -0.4064)
			(end 0.7874 0.4064)
			(stroke
				(width 0.1524)
				(type default)
			)
			(layer "F.SilkS")
		)
		(fp_line
			(start 0.7874 0.4064)
			(end -0.7874 0.4064)
			(stroke
				(width 0.1524)
				(type default)
			)
			(layer "F.SilkS")
		)
		(fp_line
			(start -0.67945 -0.305054)
			(end -0.12065 -0.305054)
			(stroke
				(width 0.1)
				(type default)
			)
			(layer "F.Fab")
		)
		(fp_line
			(start -0.67945 0.3048)
			(end -0.67945 -0.305054)
			(stroke
				(width 0.1)
				(type default)
			)
			(layer "F.Fab")
		)
		(fp_line
			(start -0.12065 -0.305054)
			(end -0.12065 -0.2794)
			(stroke
				(width 0.1)
				(type default)
			)
			(layer "F.Fab")
		)
		(fp_line
			(start -0.12065 -0.2794)
			(end 0.12065 -0.2794)
			(stroke
				(width 0.1)
				(type default)
			)
			(layer "F.Fab")
		)
		(fp_line
			(start -0.12065 0.2794)
			(end -0.12065 0.3048)
			(stroke
				(width 0.1)
				(type default)
			)
			(layer "F.Fab")
		)
		(fp_line
			(start -0.12065 0.3048)
			(end -0.67945 0.3048)
			(stroke
				(width 0.1)
				(type default)
			)
			(layer "F.Fab")
		)
		(fp_line
			(start 0.120396 0.2794)
			(end -0.12065 0.2794)
			(stroke
				(width 0.1)
				(type default)
			)
			(layer "F.Fab")
		)
		(fp_line
			(start 0.120396 0.3048)
			(end 0.120396 0.2794)
			(stroke
				(width 0.1)
				(type default)
			)
			(layer "F.Fab")
		)
		(fp_line
			(start 0.12065 -0.3048)
			(end 0.67945 -0.3048)
			(stroke
				(width 0.1)
				(type default)
			)
			(layer "F.Fab")
		)
		(fp_line
			(start 0.12065 -0.2794)
			(end 0.12065 -0.3048)
			(stroke
				(width 0.1)
				(type default)
			)
			(layer "F.Fab")
		)
		(fp_line
			(start 0.67945 -0.3048)
			(end 0.67945 0.3048)
			(stroke
				(width 0.1)
				(type default)
			)
			(layer "F.Fab")
		)
		(fp_line
			(start 0.67945 0.3048)
			(end 0.120396 0.3048)
			(stroke
				(width 0.1)
				(type default)
			)
			(layer "F.Fab")
		)
		(pad "1" smd circle
			(at -0.40005 0)
			(size 0 0)
			(layers "F.Cu" "F.Mask" "F.Paste")
			(net "SGPIO_DI_0")
		)
		(pad "2" smd circle
			(at 0.40005 0)
			(size 0 0)
			(layers "F.Cu" "F.Mask" "F.Paste")
			(net "SGPIO_DEBUG_PLD_DIN")
		)
	)
	(footprint ""
		(layer "F.Cu")
		(at 27.628596 -397.406876)
		(property "Reference" "R3279"
			(at 0 0 0)
			(layer "F.SilkS")
			(hide yes)
			(effects
				(font
					(size 1.27 1.27)
				)
			)
		)
		(property "Value" ""
			(at 0 0 0)
			(layer "F.Fab")
			(effects
				(font
					(size 1.27 1.27)
				)
			)
		)
		(duplicate_pad_numbers_are_jumpers no)
		(fp_line
			(start -0.7874 -0.4064)
			(end 0.7874 -0.4064)
			(stroke
				(width 0.1524)
				(type default)
			)
			(layer "F.SilkS")
		)
		(fp_line
			(start -0.7874 0.4064)
			(end -0.7874 -0.4064)
			(stroke
				(width 0.1524)
				(type default)
			)
			(layer "F.SilkS")
		)
		(fp_line
			(start 0.7874 -0.4064)
			(end 0.7874 0.4064)
			(stroke
				(width 0.1524)
				(type default)
			)
			(layer "F.SilkS")
		)
		(fp_line
			(start 0.7874 0.4064)
			(end -0.7874 0.4064)
			(stroke
				(width 0.1524)
				(type default)
			)
			(layer "F.SilkS")
		)
		(fp_line
			(start -0.67945 -0.305054)
			(end -0.12065 -0.305054)
			(stroke
				(width 0.1)
				(type default)
			)
			(layer "F.Fab")
		)
		(fp_line
			(start -0.67945 0.3048)
			(end -0.67945 -0.305054)
			(stroke
				(width 0.1)
				(type default)
			)
			(layer "F.Fab")
		)
		(fp_line
			(start -0.12065 -0.305054)
			(end -0.12065 -0.2794)
			(stroke
				(width 0.1)
				(type default)
			)
			(layer "F.Fab")
		)
		(fp_line
			(start -0.12065 -0.2794)
			(end 0.12065 -0.2794)
			(stroke
				(width 0.1)
				(type default)
			)
			(layer "F.Fab")
		)
		(fp_line
			(start -0.12065 0.2794)
			(end -0.12065 0.3048)
			(stroke
				(width 0.1)
				(type default)
			)
			(layer "F.Fab")
		)
		(fp_line
			(start -0.12065 0.3048)
			(end -0.67945 0.3048)
			(stroke
				(width 0.1)
				(type default)
			)
			(layer "F.Fab")
		)
		(fp_line
			(start 0.120396 0.2794)
			(end -0.12065 0.2794)
			(stroke
				(width 0.1)
				(type default)
			)
			(layer "F.Fab")
		)
		(fp_line
			(start 0.120396 0.3048)
			(end 0.120396 0.2794)
			(stroke
				(width 0.1)
				(type default)
			)
			(layer "F.Fab")
		)
		(fp_line
			(start 0.12065 -0.3048)
			(end 0.67945 -0.3048)
			(stroke
				(width 0.1)
				(type default)
			)
			(layer "F.Fab")
		)
		(fp_line
			(start 0.12065 -0.2794)
			(end 0.12065 -0.3048)
			(stroke
				(width 0.1)
				(type default)
			)
			(layer "F.Fab")
		)
		(fp_line
			(start 0.67945 -0.3048)
			(end 0.67945 0.3048)
			(stroke
				(width 0.1)
				(type default)
			)
			(layer "F.Fab")
		)
		(fp_line
			(start 0.67945 0.3048)
			(end 0.120396 0.3048)
			(stroke
				(width 0.1)
				(type default)
			)
			(layer "F.Fab")
		)
		(pad "1" smd circle
			(at -0.40005 0)
			(size 0 0)
			(layers "F.Cu" "F.Mask" "F.Paste")
			(net "FM_P2E_EQB1")
		)
		(pad "2" smd circle
			(at 0.40005 0)
			(size 0 0)
			(layers "F.Cu" "F.Mask" "F.Paste")
			(net "GND")
		)
	)
	(footprint ""
		(layer "F.Cu")
		(at 398.96669 -402.371052 -90)
		(property "Reference" "C953"
			(at 0 0 270)
			(layer "F.SilkS")
			(hide yes)
			(effects
				(font
					(size 1.27 1.27)
				)
			)
		)
		(property "Value" ""
			(at 0 0 270)
			(layer "F.Fab")
			(effects
				(font
					(size 1.27 1.27)
				)
			)
		)
		(duplicate_pad_numbers_are_jumpers no)
		(fp_line
			(start -0.299974 0.150114)
			(end -0.299974 -0.150114)
			(stroke
				(width 0.1)
				(type default)
			)
			(layer "F.Fab")
		)
		(fp_line
			(start 0.299974 0.150114)
			(end -0.299974 0.150114)
			(stroke
				(width 0.1)
				(type default)
			)
			(layer "F.Fab")
		)
		(fp_line
			(start -0.299974 -0.150114)
			(end 0.299974 -0.150114)
			(stroke
				(width 0.1)
				(type default)
			)
			(layer "F.Fab")
		)
		(fp_line
			(start 0.299974 -0.150114)
			(end 0.299974 0.150114)
			(stroke
				(width 0.1)
				(type default)
			)
			(layer "F.Fab")
		)
		(pad "1" smd rect
			(at -0.2667 0 270)
			(size 0.3048 0.381)
			(layers "F.Cu" "F.Mask" "F.Paste")
			(net "P5E_CPU0_PE2_TX_C_DP<6>")
		)
		(pad "2" smd rect
			(at 0.2667 0 270)
			(size 0.3048 0.381)
			(layers "F.Cu" "F.Mask" "F.Paste")
			(net "P5E_CPU0_PE2_TX_DP<6>")
		)
	)
	(footprint ""
		(layer "F.Cu")
		(at 51.593496 -109.53877)
		(property "Reference" "R3728"
			(at 0 0 0)
			(layer "F.SilkS")
			(hide yes)
			(effects
				(font
					(size 1.27 1.27)
				)
			)
		)
		(property "Value" ""
			(at 0 0 0)
			(layer "F.Fab")
			(effects
				(font
					(size 1.27 1.27)
				)
			)
		)
		(duplicate_pad_numbers_are_jumpers no)
		(fp_line
			(start -0.7874 -0.4064)
			(end 0.7874 -0.4064)
			(stroke
				(width 0.1524)
				(type default)
			)
			(layer "F.SilkS")
		)
		(fp_line
			(start -0.7874 0.4064)
			(end -0.7874 -0.4064)
			(stroke
				(width 0.1524)
				(type default)
			)
			(layer "F.SilkS")
		)
		(fp_line
			(start 0.7874 -0.4064)
			(end 0.7874 0.4064)
			(stroke
				(width 0.1524)
				(type default)
			)
			(layer "F.SilkS")
		)
		(fp_line
			(start 0.7874 0.4064)
			(end -0.7874 0.4064)
			(stroke
				(width 0.1524)
				(type default)
			)
			(layer "F.SilkS")
		)
		(fp_line
			(start -0.67945 -0.305054)
			(end -0.12065 -0.305054)
			(stroke
				(width 0.1)
				(type default)
			)
			(layer "F.Fab")
		)
		(fp_line
			(start -0.67945 0.3048)
			(end -0.67945 -0.305054)
			(stroke
				(width 0.1)
				(type default)
			)
			(layer "F.Fab")
		)
		(fp_line
			(start -0.12065 -0.305054)
			(end -0.12065 -0.2794)
			(stroke
				(width 0.1)
				(type default)
			)
			(layer "F.Fab")
		)
		(fp_line
			(start -0.12065 -0.2794)
			(end 0.12065 -0.2794)
			(stroke
				(width 0.1)
				(type default)
			)
			(layer "F.Fab")
		)
		(fp_line
			(start -0.12065 0.2794)
			(end -0.12065 0.3048)
			(stroke
				(width 0.1)
				(type default)
			)
			(layer "F.Fab")
		)
		(fp_line
			(start -0.12065 0.3048)
			(end -0.67945 0.3048)
			(stroke
				(width 0.1)
				(type default)
			)
			(layer "F.Fab")
		)
		(fp_line
			(start 0.120396 0.2794)
			(end -0.12065 0.2794)
			(stroke
				(width 0.1)
				(type default)
			)
			(layer "F.Fab")
		)
		(fp_line
			(start 0.120396 0.3048)
			(end 0.120396 0.2794)
			(stroke
				(width 0.1)
				(type default)
			)
			(layer "F.Fab")
		)
		(fp_line
			(start 0.12065 -0.3048)
			(end 0.67945 -0.3048)
			(stroke
				(width 0.1)
				(type default)
			)
			(layer "F.Fab")
		)
		(fp_line
			(start 0.12065 -0.2794)
			(end 0.12065 -0.3048)
			(stroke
				(width 0.1)
				(type default)
			)
			(layer "F.Fab")
		)
		(fp_line
			(start 0.67945 -0.3048)
			(end 0.67945 0.3048)
			(stroke
				(width 0.1)
				(type default)
			)
			(layer "F.Fab")
		)
		(fp_line
			(start 0.67945 0.3048)
			(end 0.120396 0.3048)
			(stroke
				(width 0.1)
				(type default)
			)
			(layer "F.Fab")
		)
		(pad "1" smd circle
			(at -0.40005 0)
			(size 0 0)
			(layers "F.Cu" "F.Mask" "F.Paste")
			(net "P3V3_AUX")
		)
		(pad "2" smd circle
			(at 0.40005 0)
			(size 0 0)
			(layers "F.Cu" "F.Mask" "F.Paste")
			(net "SMB_LM75_1_3V3AUX_SDA")
		)
	)
	(footprint ""
		(layer "F.Cu")
		(at 237.401608 -401.673822)
		(property "Reference" "PR3994"
			(at 0 0 0)
			(layer "F.SilkS")
			(hide yes)
			(effects
				(font
					(size 1.27 1.27)
				)
			)
		)
		(property "Value" ""
			(at 0 0 0)
			(layer "F.Fab")
			(effects
				(font
					(size 1.27 1.27)
				)
			)
		)
		(duplicate_pad_numbers_are_jumpers no)
		(fp_line
			(start -0.7874 -0.4064)
			(end 0.7874 -0.4064)
			(stroke
				(width 0.1524)
				(type default)
			)
			(layer "F.SilkS")
		)
		(fp_line
			(start -0.7874 0.4064)
			(end -0.7874 -0.4064)
			(stroke
				(width 0.1524)
				(type default)
			)
			(layer "F.SilkS")
		)
		(fp_line
			(start 0.7874 -0.4064)
			(end 0.7874 0.4064)
			(stroke
				(width 0.1524)
				(type default)
			)
			(layer "F.SilkS")
		)
		(fp_line
			(start 0.7874 0.4064)
			(end -0.7874 0.4064)
			(stroke
				(width 0.1524)
				(type default)
			)
			(layer "F.SilkS")
		)
		(fp_line
			(start -0.67945 -0.305054)
			(end -0.12065 -0.305054)
			(stroke
				(width 0.1)
				(type default)
			)
			(layer "F.Fab")
		)
		(fp_line
			(start -0.67945 0.3048)
			(end -0.67945 -0.305054)
			(stroke
				(width 0.1)
				(type default)
			)
			(layer "F.Fab")
		)
		(fp_line
			(start -0.12065 -0.305054)
			(end -0.12065 -0.2794)
			(stroke
				(width 0.1)
				(type default)
			)
			(layer "F.Fab")
		)
		(fp_line
			(start -0.12065 -0.2794)
			(end 0.12065 -0.2794)
			(stroke
				(width 0.1)
				(type default)
			)
			(layer "F.Fab")
		)
		(fp_line
			(start -0.12065 0.2794)
			(end -0.12065 0.3048)
			(stroke
				(width 0.1)
				(type default)
			)
			(layer "F.Fab")
		)
		(fp_line
			(start -0.12065 0.3048)
			(end -0.67945 0.3048)
			(stroke
				(width 0.1)
				(type default)
			)
			(layer "F.Fab")
		)
		(fp_line
			(start 0.120396 0.2794)
			(end -0.12065 0.2794)
			(stroke
				(width 0.1)
				(type default)
			)
			(layer "F.Fab")
		)
		(fp_line
			(start 0.120396 0.3048)
			(end 0.120396 0.2794)
			(stroke
				(width 0.1)
				(type default)
			)
			(layer "F.Fab")
		)
		(fp_line
			(start 0.12065 -0.3048)
			(end 0.67945 -0.3048)
			(stroke
				(width 0.1)
				(type default)
			)
			(layer "F.Fab")
		)
		(fp_line
			(start 0.12065 -0.2794)
			(end 0.12065 -0.3048)
			(stroke
				(width 0.1)
				(type default)
			)
			(layer "F.Fab")
		)
		(fp_line
			(start 0.67945 -0.3048)
			(end 0.67945 0.3048)
			(stroke
				(width 0.1)
				(type default)
			)
			(layer "F.Fab")
		)
		(fp_line
			(start 0.67945 0.3048)
			(end 0.120396 0.3048)
			(stroke
				(width 0.1)
				(type default)
			)
			(layer "F.Fab")
		)
		(pad "1" smd circle
			(at -0.40005 0)
			(size 0 0)
			(layers "F.Cu" "F.Mask" "F.Paste")
			(net "HSC_D_OC_4")
		)
		(pad "2" smd circle
			(at 0.40005 0)
			(size 0 0)
			(layers "F.Cu" "F.Mask" "F.Paste")
			(net "HSC_D_OC_R")
		)
	)
	(footprint ""
		(layer "F.Cu")
		(at 99.62388 -81.585308)
		(property "Reference" "Q83"
			(at 0.37592 -1.93675 0)
			(unlocked yes)
			(layer "F.SilkS")
			(effects
				(font
					(size 0.635 0.4064)
					(thickness 0.1524)
				)
			)
		)
		(property "Value" ""
			(at 0 0 0)
			(layer "F.Fab")
			(effects
				(font
					(size 1.27 1.27)
				)
			)
		)
		(duplicate_pad_numbers_are_jumpers no)
		(fp_line
			(start -1.332738 -1.100074)
			(end -0.4826 -1.100074)
			(stroke
				(width 0.1524)
				(type default)
			)
			(layer "F.SilkS")
		)
		(fp_line
			(start -1.332738 1.100074)
			(end -1.332738 -1.100074)
			(stroke
				(width 0.1524)
				(type default)
			)
			(layer "F.SilkS")
		)
		(fp_line
			(start -0.4826 -1.100074)
			(end 0 -0.541274)
			(stroke
				(width 0.1524)
				(type default)
			)
			(layer "F.SilkS")
		)
		(fp_line
			(start 0 -0.541274)
			(end 0.4826 -1.100074)
			(stroke
				(width 0.1524)
				(type default)
			)
			(layer "F.SilkS")
		)
		(fp_line
			(start 0.4826 -1.100074)
			(end 1.332738 -1.100074)
			(stroke
				(width 0.1524)
				(type default)
			)
			(layer "F.SilkS")
		)
		(fp_line
			(start 1.332738 -1.100074)
			(end 1.332738 1.100074)
			(stroke
				(width 0.1524)
				(type default)
			)
			(layer "F.SilkS")
		)
		(fp_line
			(start 1.332738 1.100074)
			(end -1.332738 1.100074)
			(stroke
				(width 0.1524)
				(type default)
			)
			(layer "F.SilkS")
		)
		(fp_poly
			(pts
				(xy -2.1082 -1.763014) (xy -1.406144 -1.411986) (xy -2.1082 -1.060958)
			)
			(stroke
				(width 0)
				(type default)
			)
			(fill yes)
			(layer "F.SilkS")
		)
		(fp_line
			(start -0.674878 -1.100074)
			(end 0.674878 -1.100074)
			(stroke
				(width 0.1)
				(type default)
			)
			(layer "F.Fab")
		)
		(fp_line
			(start -0.674878 1.100074)
			(end -0.674878 -1.100074)
			(stroke
				(width 0.1)
				(type default)
			)
			(layer "F.Fab")
		)
		(fp_line
			(start 0.674878 -1.100074)
			(end 0.674878 1.100074)
			(stroke
				(width 0.1)
				(type default)
			)
			(layer "F.Fab")
		)
		(fp_line
			(start 0.674878 1.100074)
			(end -0.674878 1.100074)
			(stroke
				(width 0.1)
				(type default)
			)
			(layer "F.Fab")
		)
		(fp_poly
			(pts
				(xy -2.2352 -0.298958) (xy -2.2352 -1.001014) (xy -1.533144 -0.649986)
			)
			(stroke
				(width 0)
				(type default)
			)
			(fill yes)
			(layer "F.Fab")
		)
		(pad "1" smd rect
			(at -0.94996 -0.649986 90)
			(size 0.4318 0.508)
			(layers "F.Cu" "F.Mask" "F.Paste")
			(net "GND")
		)
		(pad "2" smd rect
			(at -0.94996 0 90)
			(size 0.4318 0.508)
			(layers "F.Cu" "F.Mask" "F.Paste")
			(net "PWRGD_PVCCIN_CPU0")
		)
		(pad "3" smd rect
			(at -0.94996 0.649986 90)
			(size 0.4318 0.508)
			(layers "F.Cu" "F.Mask" "F.Paste")
			(net "LED_PWRGD_PVCCIN_CPU1_D")
		)
		(pad "4" smd rect
			(at 0.94996 0.649986 90)
			(size 0.4318 0.508)
			(layers "F.Cu" "F.Mask" "F.Paste")
			(net "GND")
		)
		(pad "5" smd rect
			(at 0.94996 0 90)
			(size 0.4318 0.508)
			(layers "F.Cu" "F.Mask" "F.Paste")
			(net "PWRGD_PVCCIN_CPU1")
		)
		(pad "6" smd rect
			(at 0.94996 -0.649986 90)
			(size 0.4318 0.508)
			(layers "F.Cu" "F.Mask" "F.Paste")
			(net "LED_PWRGD_PVCCIN_CPU0_D")
		)
	)
	(footprint ""
		(layer "F.Cu")
		(at 193.893186 -438.17413 90)
		(property "Reference" "R2941"
			(at 0 0 90)
			(layer "F.SilkS")
			(hide yes)
			(effects
				(font
					(size 1.27 1.27)
				)
			)
		)
		(property "Value" ""
			(at 0 0 90)
			(layer "F.Fab")
			(effects
				(font
					(size 1.27 1.27)
				)
			)
		)
		(duplicate_pad_numbers_are_jumpers no)
		(fp_line
			(start 0.7874 -0.4064)
			(end 0.7874 0.4064)
			(stroke
				(width 0.1524)
				(type default)
			)
			(layer "F.SilkS")
		)
		(fp_line
			(start -0.7874 -0.4064)
			(end 0.7874 -0.4064)
			(stroke
				(width 0.1524)
				(type default)
			)
			(layer "F.SilkS")
		)
		(fp_line
			(start 0.7874 0.4064)
			(end -0.7874 0.4064)
			(stroke
				(width 0.1524)
				(type default)
			)
			(layer "F.SilkS")
		)
		(fp_line
			(start -0.7874 0.4064)
			(end -0.7874 -0.4064)
			(stroke
				(width 0.1524)
				(type default)
			)
			(layer "F.SilkS")
		)
		(fp_line
			(start -0.12065 -0.305054)
			(end -0.12065 -0.2794)
			(stroke
				(width 0.1)
				(type default)
			)
			(layer "F.Fab")
		)
		(fp_line
			(start -0.67945 -0.305054)
			(end -0.12065 -0.305054)
			(stroke
				(width 0.1)
				(type default)
			)
			(layer "F.Fab")
		)
		(fp_line
			(start 0.67945 -0.3048)
			(end 0.67945 0.3048)
			(stroke
				(width 0.1)
				(type default)
			)
			(layer "F.Fab")
		)
		(fp_line
			(start 0.12065 -0.3048)
			(end 0.67945 -0.3048)
			(stroke
				(width 0.1)
				(type default)
			)
			(layer "F.Fab")
		)
		(fp_line
			(start 0.12065 -0.2794)
			(end 0.12065 -0.3048)
			(stroke
				(width 0.1)
				(type default)
			)
			(layer "F.Fab")
		)
		(fp_line
			(start -0.12065 -0.2794)
			(end 0.12065 -0.2794)
			(stroke
				(width 0.1)
				(type default)
			)
			(layer "F.Fab")
		)
		(fp_line
			(start 0.120396 0.2794)
			(end -0.12065 0.2794)
			(stroke
				(width 0.1)
				(type default)
			)
			(layer "F.Fab")
		)
		(fp_line
			(start -0.12065 0.2794)
			(end -0.12065 0.3048)
			(stroke
				(width 0.1)
				(type default)
			)
			(layer "F.Fab")
		)
		(fp_line
			(start 0.67945 0.3048)
			(end 0.120396 0.3048)
			(stroke
				(width 0.1)
				(type default)
			)
			(layer "F.Fab")
		)
		(fp_line
			(start 0.120396 0.3048)
			(end 0.120396 0.2794)
			(stroke
				(width 0.1)
				(type default)
			)
			(layer "F.Fab")
		)
		(fp_line
			(start -0.12065 0.3048)
			(end -0.67945 0.3048)
			(stroke
				(width 0.1)
				(type default)
			)
			(layer "F.Fab")
		)
		(fp_line
			(start -0.67945 0.3048)
			(end -0.67945 -0.305054)
			(stroke
				(width 0.1)
				(type default)
			)
			(layer "F.Fab")
		)
		(pad "1" smd circle
			(at -0.40005 0 90)
			(size 0 0)
			(layers "F.Cu" "F.Mask" "F.Paste")
			(net "FM_GPU_HSC_EN")
		)
		(pad "2" smd circle
			(at 0.40005 0 90)
			(size 0 0)
			(layers "F.Cu" "F.Mask" "F.Paste")
			(net "GND")
		)
	)
	(footprint ""
		(layer "F.Cu")
		(at 100.94849 -92.87256)
		(property "Reference" "Q78"
			(at 1.61544 -0.762508 0)
			(unlocked yes)
			(layer "F.SilkS")
			(effects
				(font
					(size 0.7874 0.5842)
					(thickness 0.1524)
				)
				(justify left)
			)
		)
		(property "Value" ""
			(at 0 0 0)
			(layer "F.Fab")
			(effects
				(font
					(size 1.27 1.27)
				)
			)
		)
		(duplicate_pad_numbers_are_jumpers no)
		(fp_line
			(start -1.332738 -1.100074)
			(end -0.4826 -1.100074)
			(stroke
				(width 0.1524)
				(type default)
			)
			(layer "F.SilkS")
		)
		(fp_line
			(start -1.332738 1.100074)
			(end -1.332738 -1.100074)
			(stroke
				(width 0.1524)
				(type default)
			)
			(layer "F.SilkS")
		)
		(fp_line
			(start -0.4826 -1.100074)
			(end 0 -0.541274)
			(stroke
				(width 0.1524)
				(type default)
			)
			(layer "F.SilkS")
		)
		(fp_line
			(start 0 -0.541274)
			(end 0.4826 -1.100074)
			(stroke
				(width 0.1524)
				(type default)
			)
			(layer "F.SilkS")
		)
		(fp_line
			(start 0.4826 -1.100074)
			(end 1.332738 -1.100074)
			(stroke
				(width 0.1524)
				(type default)
			)
			(layer "F.SilkS")
		)
		(fp_line
			(start 1.332738 -1.100074)
			(end 1.332738 1.100074)
			(stroke
				(width 0.1524)
				(type default)
			)
			(layer "F.SilkS")
		)
		(fp_line
			(start 1.332738 1.100074)
			(end -1.332738 1.100074)
			(stroke
				(width 0.1524)
				(type default)
			)
			(layer "F.SilkS")
		)
		(fp_poly
			(pts
				(xy -1.809242 -1.854962) (xy -1.561084 -1.110488) (xy -2.305812 -1.358646)
			)
			(stroke
				(width 0)
				(type default)
			)
			(fill yes)
			(layer "F.SilkS")
		)
		(fp_line
			(start -0.674878 -1.100074)
			(end 0.674878 -1.100074)
			(stroke
				(width 0.1)
				(type default)
			)
			(layer "F.Fab")
		)
		(fp_line
			(start -0.674878 1.100074)
			(end -0.674878 -1.100074)
			(stroke
				(width 0.1)
				(type default)
			)
			(layer "F.Fab")
		)
		(fp_line
			(start 0.674878 -1.100074)
			(end 0.674878 1.100074)
			(stroke
				(width 0.1)
				(type default)
			)
			(layer "F.Fab")
		)
		(fp_line
			(start 0.674878 1.100074)
			(end -0.674878 1.100074)
			(stroke
				(width 0.1)
				(type default)
			)
			(layer "F.Fab")
		)
		(fp_poly
			(pts
				(xy -2.2352 -0.298958) (xy -2.2352 -1.001014) (xy -1.533144 -0.649986)
			)
			(stroke
				(width 0)
				(type default)
			)
			(fill yes)
			(layer "F.Fab")
		)
		(pad "1" smd rect
			(at -0.94996 -0.649986 90)
			(size 0.4318 0.508)
			(layers "F.Cu" "F.Mask" "F.Paste")
			(net "GND")
		)
		(pad "2" smd rect
			(at -0.94996 0 90)
			(size 0.4318 0.508)
			(layers "F.Cu" "F.Mask" "F.Paste")
			(net "FM_PCH_SLP_S3_N")
		)
		(pad "3" smd rect
			(at -0.94996 0.649986 90)
			(size 0.4318 0.508)
			(layers "F.Cu" "F.Mask" "F.Paste")
			(net "LED_PWRGD_PS_PWROK_PLD_D")
		)
		(pad "4" smd rect
			(at 0.94996 0.649986 90)
			(size 0.4318 0.508)
			(layers "F.Cu" "F.Mask" "F.Paste")
			(net "GND")
		)
		(pad "5" smd rect
			(at 0.94996 0 90)
			(size 0.4318 0.508)
			(layers "F.Cu" "F.Mask" "F.Paste")
			(net "PWRGD_PS_PWROK_PLD")
		)
		(pad "6" smd rect
			(at 0.94996 -0.649986 90)
			(size 0.4318 0.508)
			(layers "F.Cu" "F.Mask" "F.Paste")
			(net "LED_FM_PCH_SLP_S3_N_D")
		)
	)
	(footprint ""
		(layer "F.Cu")
		(at 197.41388 -102.415848)
		(property "Reference" "R1843"
			(at 0 0 0)
			(layer "F.SilkS")
			(hide yes)
			(effects
				(font
					(size 1.27 1.27)
				)
			)
		)
		(property "Value" ""
			(at 0 0 0)
			(layer "F.Fab")
			(effects
				(font
					(size 1.27 1.27)
				)
			)
		)
		(duplicate_pad_numbers_are_jumpers no)
		(fp_line
			(start -0.7874 -0.4064)
			(end 0.7874 -0.4064)
			(stroke
				(width 0.1524)
				(type default)
			)
			(layer "F.SilkS")
		)
		(fp_line
			(start -0.7874 0.4064)
			(end -0.7874 -0.4064)
			(stroke
				(width 0.1524)
				(type default)
			)
			(layer "F.SilkS")
		)
		(fp_line
			(start 0.7874 -0.4064)
			(end 0.7874 0.4064)
			(stroke
				(width 0.1524)
				(type default)
			)
			(layer "F.SilkS")
		)
		(fp_line
			(start 0.7874 0.4064)
			(end -0.7874 0.4064)
			(stroke
				(width 0.1524)
				(type default)
			)
			(layer "F.SilkS")
		)
		(fp_line
			(start -0.67945 -0.305054)
			(end -0.12065 -0.305054)
			(stroke
				(width 0.1)
				(type default)
			)
			(layer "F.Fab")
		)
		(fp_line
			(start -0.67945 0.3048)
			(end -0.67945 -0.305054)
			(stroke
				(width 0.1)
				(type default)
			)
			(layer "F.Fab")
		)
		(fp_line
			(start -0.12065 -0.305054)
			(end -0.12065 -0.2794)
			(stroke
				(width 0.1)
				(type default)
			)
			(layer "F.Fab")
		)
		(fp_line
			(start -0.12065 -0.2794)
			(end 0.12065 -0.2794)
			(stroke
				(width 0.1)
				(type default)
			)
			(layer "F.Fab")
		)
		(fp_line
			(start -0.12065 0.2794)
			(end -0.12065 0.3048)
			(stroke
				(width 0.1)
				(type default)
			)
			(layer "F.Fab")
		)
		(fp_line
			(start -0.12065 0.3048)
			(end -0.67945 0.3048)
			(stroke
				(width 0.1)
				(type default)
			)
			(layer "F.Fab")
		)
		(fp_line
			(start 0.120396 0.2794)
			(end -0.12065 0.2794)
			(stroke
				(width 0.1)
				(type default)
			)
			(layer "F.Fab")
		)
		(fp_line
			(start 0.120396 0.3048)
			(end 0.120396 0.2794)
			(stroke
				(width 0.1)
				(type default)
			)
			(layer "F.Fab")
		)
		(fp_line
			(start 0.12065 -0.3048)
			(end 0.67945 -0.3048)
			(stroke
				(width 0.1)
				(type default)
			)
			(layer "F.Fab")
		)
		(fp_line
			(start 0.12065 -0.2794)
			(end 0.12065 -0.3048)
			(stroke
				(width 0.1)
				(type default)
			)
			(layer "F.Fab")
		)
		(fp_line
			(start 0.67945 -0.3048)
			(end 0.67945 0.3048)
			(stroke
				(width 0.1)
				(type default)
			)
			(layer "F.Fab")
		)
		(fp_line
			(start 0.67945 0.3048)
			(end 0.120396 0.3048)
			(stroke
				(width 0.1)
				(type default)
			)
			(layer "F.Fab")
		)
		(pad "1" smd circle
			(at -0.40005 0)
			(size 0 0)
			(layers "F.Cu" "F.Mask" "F.Paste")
			(net "RST_PFR_OVR_RTC_R")
		)
		(pad "2" smd circle
			(at 0.40005 0)
			(size 0 0)
			(layers "F.Cu" "F.Mask" "F.Paste")
			(net "RST_PFR_OVR_RTC")
		)
	)
	(footprint ""
		(layer "F.Cu")
		(at 109.14888 -53.304948)
		(property "Reference" "R1349"
			(at 0 0 0)
			(layer "F.SilkS")
			(hide yes)
			(effects
				(font
					(size 1.27 1.27)
				)
			)
		)
		(property "Value" ""
			(at 0 0 0)
			(layer "F.Fab")
			(effects
				(font
					(size 1.27 1.27)
				)
			)
		)
		(duplicate_pad_numbers_are_jumpers no)
		(fp_line
			(start -0.7874 -0.4064)
			(end 0.7874 -0.4064)
			(stroke
				(width 0.1524)
				(type default)
			)
			(layer "F.SilkS")
		)
		(fp_line
			(start -0.7874 0.4064)
			(end -0.7874 -0.4064)
			(stroke
				(width 0.1524)
				(type default)
			)
			(layer "F.SilkS")
		)
		(fp_line
			(start 0.7874 -0.4064)
			(end 0.7874 0.4064)
			(stroke
				(width 0.1524)
				(type default)
			)
			(layer "F.SilkS")
		)
		(fp_line
			(start 0.7874 0.4064)
			(end -0.7874 0.4064)
			(stroke
				(width 0.1524)
				(type default)
			)
			(layer "F.SilkS")
		)
		(fp_line
			(start -0.67945 -0.305054)
			(end -0.12065 -0.305054)
			(stroke
				(width 0.1)
				(type default)
			)
			(layer "F.Fab")
		)
		(fp_line
			(start -0.67945 0.3048)
			(end -0.67945 -0.305054)
			(stroke
				(width 0.1)
				(type default)
			)
			(layer "F.Fab")
		)
		(fp_line
			(start -0.12065 -0.305054)
			(end -0.12065 -0.2794)
			(stroke
				(width 0.1)
				(type default)
			)
			(layer "F.Fab")
		)
		(fp_line
			(start -0.12065 -0.2794)
			(end 0.12065 -0.2794)
			(stroke
				(width 0.1)
				(type default)
			)
			(layer "F.Fab")
		)
		(fp_line
			(start -0.12065 0.2794)
			(end -0.12065 0.3048)
			(stroke
				(width 0.1)
				(type default)
			)
			(layer "F.Fab")
		)
		(fp_line
			(start -0.12065 0.3048)
			(end -0.67945 0.3048)
			(stroke
				(width 0.1)
				(type default)
			)
			(layer "F.Fab")
		)
		(fp_line
			(start 0.120396 0.2794)
			(end -0.12065 0.2794)
			(stroke
				(width 0.1)
				(type default)
			)
			(layer "F.Fab")
		)
		(fp_line
			(start 0.120396 0.3048)
			(end 0.120396 0.2794)
			(stroke
				(width 0.1)
				(type default)
			)
			(layer "F.Fab")
		)
		(fp_line
			(start 0.12065 -0.3048)
			(end 0.67945 -0.3048)
			(stroke
				(width 0.1)
				(type default)
			)
			(layer "F.Fab")
		)
		(fp_line
			(start 0.12065 -0.2794)
			(end 0.12065 -0.3048)
			(stroke
				(width 0.1)
				(type default)
			)
			(layer "F.Fab")
		)
		(fp_line
			(start 0.67945 -0.3048)
			(end 0.67945 0.3048)
			(stroke
				(width 0.1)
				(type default)
			)
			(layer "F.Fab")
		)
		(fp_line
			(start 0.67945 0.3048)
			(end 0.120396 0.3048)
			(stroke
				(width 0.1)
				(type default)
			)
			(layer "F.Fab")
		)
		(pad "1" smd circle
			(at -0.40005 0)
			(size 0 0)
			(layers "F.Cu" "F.Mask" "F.Paste")
			(net "JTAG_DBP_TCK_PCH_R")
		)
		(pad "2" smd circle
			(at 0.40005 0)
			(size 0 0)
			(layers "F.Cu" "F.Mask" "F.Paste")
			(net "JTAG_DBP_TCK_PCH")
		)
	)
	(footprint ""
		(layer "F.Cu")
		(at 171.50588 -126.964948 90)
		(property "Reference" "R1411"
			(at 0 0 90)
			(layer "F.SilkS")
			(hide yes)
			(effects
				(font
					(size 1.27 1.27)
				)
			)
		)
		(property "Value" ""
			(at 0 0 90)
			(layer "F.Fab")
			(effects
				(font
					(size 1.27 1.27)
				)
			)
		)
		(duplicate_pad_numbers_are_jumpers no)
		(fp_line
			(start 0.7874 -0.4064)
			(end 0.7874 0.4064)
			(stroke
				(width 0.1524)
				(type default)
			)
			(layer "F.SilkS")
		)
		(fp_line
			(start -0.7874 -0.4064)
			(end 0.7874 -0.4064)
			(stroke
				(width 0.1524)
				(type default)
			)
			(layer "F.SilkS")
		)
		(fp_line
			(start 0.7874 0.4064)
			(end -0.7874 0.4064)
			(stroke
				(width 0.1524)
				(type default)
			)
			(layer "F.SilkS")
		)
		(fp_line
			(start -0.7874 0.4064)
			(end -0.7874 -0.4064)
			(stroke
				(width 0.1524)
				(type default)
			)
			(layer "F.SilkS")
		)
		(fp_line
			(start -0.12065 -0.305054)
			(end -0.12065 -0.2794)
			(stroke
				(width 0.1)
				(type default)
			)
			(layer "F.Fab")
		)
		(fp_line
			(start -0.67945 -0.305054)
			(end -0.12065 -0.305054)
			(stroke
				(width 0.1)
				(type default)
			)
			(layer "F.Fab")
		)
		(fp_line
			(start 0.67945 -0.3048)
			(end 0.67945 0.3048)
			(stroke
				(width 0.1)
				(type default)
			)
			(layer "F.Fab")
		)
		(fp_line
			(start 0.12065 -0.3048)
			(end 0.67945 -0.3048)
			(stroke
				(width 0.1)
				(type default)
			)
			(layer "F.Fab")
		)
		(fp_line
			(start 0.12065 -0.2794)
			(end 0.12065 -0.3048)
			(stroke
				(width 0.1)
				(type default)
			)
			(layer "F.Fab")
		)
		(fp_line
			(start -0.12065 -0.2794)
			(end 0.12065 -0.2794)
			(stroke
				(width 0.1)
				(type default)
			)
			(layer "F.Fab")
		)
		(fp_line
			(start 0.120396 0.2794)
			(end -0.12065 0.2794)
			(stroke
				(width 0.1)
				(type default)
			)
			(layer "F.Fab")
		)
		(fp_line
			(start -0.12065 0.2794)
			(end -0.12065 0.3048)
			(stroke
				(width 0.1)
				(type default)
			)
			(layer "F.Fab")
		)
		(fp_line
			(start 0.67945 0.3048)
			(end 0.120396 0.3048)
			(stroke
				(width 0.1)
				(type default)
			)
			(layer "F.Fab")
		)
		(fp_line
			(start 0.120396 0.3048)
			(end 0.120396 0.2794)
			(stroke
				(width 0.1)
				(type default)
			)
			(layer "F.Fab")
		)
		(fp_line
			(start -0.12065 0.3048)
			(end -0.67945 0.3048)
			(stroke
				(width 0.1)
				(type default)
			)
			(layer "F.Fab")
		)
		(fp_line
			(start -0.67945 0.3048)
			(end -0.67945 -0.305054)
			(stroke
				(width 0.1)
				(type default)
			)
			(layer "F.Fab")
		)
		(pad "1" smd circle
			(at -0.40005 0 90)
			(size 0 0)
			(layers "F.Cu" "F.Mask" "F.Paste")
			(net "FM_PVCCFA_EHV_FIVRA_CPU0_R_EN")
		)
		(pad "2" smd circle
			(at 0.40005 0 90)
			(size 0 0)
			(layers "F.Cu" "F.Mask" "F.Paste")
			(net "GND")
		)
	)
	(footprint ""
		(layer "F.Cu")
		(at 443.717172 -32.173418 90)
		(property "Reference" "PC2153"
			(at 0 0 90)
			(layer "F.SilkS")
			(hide yes)
			(effects
				(font
					(size 1.27 1.27)
				)
			)
		)
		(property "Value" ""
			(at 0 0 90)
			(layer "F.Fab")
			(effects
				(font
					(size 1.27 1.27)
				)
			)
		)
		(duplicate_pad_numbers_are_jumpers no)
		(fp_line
			(start 0.7874 -0.4064)
			(end 0.7874 0.4064)
			(stroke
				(width 0.1524)
				(type default)
			)
			(layer "F.SilkS")
		)
		(fp_line
			(start -0.7874 -0.4064)
			(end 0.7874 -0.4064)
			(stroke
				(width 0.1524)
				(type default)
			)
			(layer "F.SilkS")
		)
		(fp_line
			(start 0.7874 0.4064)
			(end -0.7874 0.4064)
			(stroke
				(width 0.1524)
				(type default)
			)
			(layer "F.SilkS")
		)
		(fp_line
			(start -0.7874 0.4064)
			(end -0.7874 -0.4064)
			(stroke
				(width 0.1524)
				(type default)
			)
			(layer "F.SilkS")
		)
		(fp_line
			(start -0.12065 -0.305054)
			(end -0.12065 -0.2794)
			(stroke
				(width 0.1)
				(type default)
			)
			(layer "F.Fab")
		)
		(fp_line
			(start -0.67945 -0.305054)
			(end -0.12065 -0.305054)
			(stroke
				(width 0.1)
				(type default)
			)
			(layer "F.Fab")
		)
		(fp_line
			(start 0.67945 -0.3048)
			(end 0.67945 0.3048)
			(stroke
				(width 0.1)
				(type default)
			)
			(layer "F.Fab")
		)
		(fp_line
			(start 0.12065 -0.3048)
			(end 0.67945 -0.3048)
			(stroke
				(width 0.1)
				(type default)
			)
			(layer "F.Fab")
		)
		(fp_line
			(start 0.12065 -0.2794)
			(end 0.12065 -0.3048)
			(stroke
				(width 0.1)
				(type default)
			)
			(layer "F.Fab")
		)
		(fp_line
			(start -0.12065 -0.2794)
			(end 0.12065 -0.2794)
			(stroke
				(width 0.1)
				(type default)
			)
			(layer "F.Fab")
		)
		(fp_line
			(start 0.120396 0.2794)
			(end -0.12065 0.2794)
			(stroke
				(width 0.1)
				(type default)
			)
			(layer "F.Fab")
		)
		(fp_line
			(start -0.12065 0.2794)
			(end -0.12065 0.3048)
			(stroke
				(width 0.1)
				(type default)
			)
			(layer "F.Fab")
		)
		(fp_line
			(start 0.67945 0.3048)
			(end 0.120396 0.3048)
			(stroke
				(width 0.1)
				(type default)
			)
			(layer "F.Fab")
		)
		(fp_line
			(start 0.120396 0.3048)
			(end 0.120396 0.2794)
			(stroke
				(width 0.1)
				(type default)
			)
			(layer "F.Fab")
		)
		(fp_line
			(start -0.12065 0.3048)
			(end -0.67945 0.3048)
			(stroke
				(width 0.1)
				(type default)
			)
			(layer "F.Fab")
		)
		(fp_line
			(start -0.67945 0.3048)
			(end -0.67945 -0.305054)
			(stroke
				(width 0.1)
				(type default)
			)
			(layer "F.Fab")
		)
		(pad "1" smd circle
			(at -0.40005 0 90)
			(size 0 0)
			(layers "F.Cu" "F.Mask" "F.Paste")
			(net "P12V_OCP_TIMER_1")
		)
		(pad "2" smd circle
			(at 0.40005 0 90)
			(size 0 0)
			(layers "F.Cu" "F.Mask" "F.Paste")
			(net "GND")
		)
	)
	(footprint ""
		(layer "F.Cu")
		(at 308.66334 -435.71541 90)
		(property "Reference" "Q131"
			(at 4.467098 -1.20269 0)
			(unlocked yes)
			(layer "F.SilkS")
			(effects
				(font
					(size 0.7874 0.5842)
					(thickness 0.1524)
				)
				(justify left)
			)
		)
		(property "Value" ""
			(at 0 0 90)
			(layer "F.Fab")
			(effects
				(font
					(size 1.27 1.27)
				)
			)
		)
		(duplicate_pad_numbers_are_jumpers no)
		(fp_line
			(start 1.332738 -1.100074)
			(end 1.332738 1.100074)
			(stroke
				(width 0.1524)
				(type default)
			)
			(layer "F.SilkS")
		)
		(fp_line
			(start 0.4826 -1.100074)
			(end 1.332738 -1.100074)
			(stroke
				(width 0.1524)
				(type default)
			)
			(layer "F.SilkS")
		)
		(fp_line
			(start -0.4826 -1.100074)
			(end 0 -0.541274)
			(stroke
				(width 0.1524)
				(type default)
			)
			(layer "F.SilkS")
		)
		(fp_line
			(start -1.332738 -1.100074)
			(end -0.4826 -1.100074)
			(stroke
				(width 0.1524)
				(type default)
			)
			(layer "F.SilkS")
		)
		(fp_line
			(start 0 -0.541274)
			(end 0.4826 -1.100074)
			(stroke
				(width 0.1524)
				(type default)
			)
			(layer "F.SilkS")
		)
		(fp_line
			(start 1.332738 1.100074)
			(end -1.332738 1.100074)
			(stroke
				(width 0.1524)
				(type default)
			)
			(layer "F.SilkS")
		)
		(fp_line
			(start -1.332738 1.100074)
			(end -1.332738 -1.100074)
			(stroke
				(width 0.1524)
				(type default)
			)
			(layer "F.SilkS")
		)
		(fp_poly
			(pts
				(xy -2.43586 -1.303274) (xy -1.733804 -0.952246) (xy -2.43586 -0.601218)
			)
			(stroke
				(width 0)
				(type default)
			)
			(fill yes)
			(layer "F.SilkS")
		)
		(fp_line
			(start 0.674878 -1.100074)
			(end 0.674878 1.100074)
			(stroke
				(width 0.1)
				(type default)
			)
			(layer "F.Fab")
		)
		(fp_line
			(start -0.674878 -1.100074)
			(end 0.674878 -1.100074)
			(stroke
				(width 0.1)
				(type default)
			)
			(layer "F.Fab")
		)
		(fp_line
			(start 0.674878 1.100074)
			(end -0.674878 1.100074)
			(stroke
				(width 0.1)
				(type default)
			)
			(layer "F.Fab")
		)
		(fp_line
			(start -0.674878 1.100074)
			(end -0.674878 -1.100074)
			(stroke
				(width 0.1)
				(type default)
			)
			(layer "F.Fab")
		)
		(fp_poly
			(pts
				(xy -2.2352 -0.298958) (xy -2.2352 -1.001014) (xy -1.533144 -0.649986)
			)
			(stroke
				(width 0)
				(type default)
			)
			(fill yes)
			(layer "F.Fab")
		)
		(pad "1" smd rect
			(at -0.94996 -0.649986 180)
			(size 0.4318 0.508)
			(layers "F.Cu" "F.Mask" "F.Paste")
			(net "GND")
		)
		(pad "2" smd rect
			(at -0.94996 0 180)
			(size 0.4318 0.508)
			(layers "F.Cu" "F.Mask" "F.Paste")
			(net "GPU_3V3IO_RSVD1_FFU")
		)
		(pad "3" smd rect
			(at -0.94996 0.649986 180)
			(size 0.4318 0.508)
			(layers "F.Cu" "F.Mask" "F.Paste")
			(net "GPU_3V3IO_RSVD1_FFU_ISO")
		)
		(pad "4" smd rect
			(at 0.94996 0.649986 180)
			(size 0.4318 0.508)
			(layers "F.Cu" "F.Mask" "F.Paste")
			(net "GND")
		)
		(pad "5" smd rect
			(at 0.94996 0 180)
			(size 0.4318 0.508)
			(layers "F.Cu" "F.Mask" "F.Paste")
			(net "GPU_3V3IO_RSVD1_FFU_N")
		)
		(pad "6" smd rect
			(at 0.94996 -0.649986 180)
			(size 0.4318 0.508)
			(layers "F.Cu" "F.Mask" "F.Paste")
			(net "GPU_3V3IO_RSVD1_FFU_N")
		)
	)
	(footprint ""
		(layer "F.Cu")
		(at 157.430978 -46.741588)
		(property "Reference" "R4487"
			(at 0 0 0)
			(layer "F.SilkS")
			(hide yes)
			(effects
				(font
					(size 1.27 1.27)
				)
			)
		)
		(property "Value" ""
			(at 0 0 0)
			(layer "F.Fab")
			(effects
				(font
					(size 1.27 1.27)
				)
			)
		)
		(duplicate_pad_numbers_are_jumpers no)
		(fp_line
			(start -0.009398 -0.4064)
			(end 0.7874 -0.4064)
			(stroke
				(width 0.1524)
				(type default)
			)
			(layer "F.SilkS")
		)
		(fp_line
			(start 0.7874 -0.4064)
			(end 0.7874 0.4064)
			(stroke
				(width 0.1524)
				(type default)
			)
			(layer "F.SilkS")
		)
		(fp_line
			(start 0.7874 0.4064)
			(end 0.041402 0.4064)
			(stroke
				(width 0.1524)
				(type default)
			)
			(layer "F.SilkS")
		)
		(fp_line
			(start -0.67945 -0.305054)
			(end -0.12065 -0.305054)
			(stroke
				(width 0.1)
				(type default)
			)
			(layer "F.Fab")
		)
		(fp_line
			(start -0.67945 0.3048)
			(end -0.67945 -0.305054)
			(stroke
				(width 0.1)
				(type default)
			)
			(layer "F.Fab")
		)
		(fp_line
			(start -0.12065 -0.305054)
			(end -0.12065 -0.2794)
			(stroke
				(width 0.1)
				(type default)
			)
			(layer "F.Fab")
		)
		(fp_line
			(start -0.12065 -0.2794)
			(end 0.12065 -0.2794)
			(stroke
				(width 0.1)
				(type default)
			)
			(layer "F.Fab")
		)
		(fp_line
			(start -0.12065 0.2794)
			(end -0.12065 0.3048)
			(stroke
				(width 0.1)
				(type default)
			)
			(layer "F.Fab")
		)
		(fp_line
			(start -0.12065 0.3048)
			(end -0.67945 0.3048)
			(stroke
				(width 0.1)
				(type default)
			)
			(layer "F.Fab")
		)
		(fp_line
			(start 0.120396 0.2794)
			(end -0.12065 0.2794)
			(stroke
				(width 0.1)
				(type default)
			)
			(layer "F.Fab")
		)
		(fp_line
			(start 0.120396 0.3048)
			(end 0.120396 0.2794)
			(stroke
				(width 0.1)
				(type default)
			)
			(layer "F.Fab")
		)
		(fp_line
			(start 0.12065 -0.3048)
			(end 0.67945 -0.3048)
			(stroke
				(width 0.1)
				(type default)
			)
			(layer "F.Fab")
		)
		(fp_line
			(start 0.12065 -0.2794)
			(end 0.12065 -0.3048)
			(stroke
				(width 0.1)
				(type default)
			)
			(layer "F.Fab")
		)
		(fp_line
			(start 0.67945 -0.3048)
			(end 0.67945 0.3048)
			(stroke
				(width 0.1)
				(type default)
			)
			(layer "F.Fab")
		)
		(fp_line
			(start 0.67945 0.3048)
			(end 0.120396 0.3048)
			(stroke
				(width 0.1)
				(type default)
			)
			(layer "F.Fab")
		)
		(pad "1" smd circle
			(at -0.40005 0)
			(size 0 0)
			(layers "F.Cu" "F.Mask" "F.Paste")
			(net "USB2_HOST_PCH_0_DN")
		)
		(pad "2" smd circle
			(at 0.40005 0)
			(size 0 0)
			(layers "F.Cu" "F.Mask" "F.Paste")
			(net "GND")
		)
	)
	(footprint ""
		(layer "F.Cu")
		(at 150.93188 -109.819948 -90)
		(property "Reference" "C1841"
			(at 0 0 270)
			(layer "F.SilkS")
			(hide yes)
			(effects
				(font
					(size 1.27 1.27)
				)
			)
		)
		(property "Value" ""
			(at 0 0 270)
			(layer "F.Fab")
			(effects
				(font
					(size 1.27 1.27)
				)
			)
		)
		(duplicate_pad_numbers_are_jumpers no)
		(fp_line
			(start -0.7874 0.4064)
			(end -0.7874 -0.4064)
			(stroke
				(width 0.1524)
				(type default)
			)
			(layer "F.SilkS")
		)
		(fp_line
			(start 0.7874 0.4064)
			(end -0.7874 0.4064)
			(stroke
				(width 0.1524)
				(type default)
			)
			(layer "F.SilkS")
		)
		(fp_line
			(start -0.7874 -0.4064)
			(end 0.7874 -0.4064)
			(stroke
				(width 0.1524)
				(type default)
			)
			(layer "F.SilkS")
		)
		(fp_line
			(start 0.7874 -0.4064)
			(end 0.7874 0.4064)
			(stroke
				(width 0.1524)
				(type default)
			)
			(layer "F.SilkS")
		)
		(fp_line
			(start -0.67945 0.3048)
			(end -0.67945 -0.305054)
			(stroke
				(width 0.1)
				(type default)
			)
			(layer "F.Fab")
		)
		(fp_line
			(start -0.12065 0.3048)
			(end -0.67945 0.3048)
			(stroke
				(width 0.1)
				(type default)
			)
			(layer "F.Fab")
		)
		(fp_line
			(start 0.120396 0.3048)
			(end 0.120396 0.2794)
			(stroke
				(width 0.1)
				(type default)
			)
			(layer "F.Fab")
		)
		(fp_line
			(start 0.67945 0.3048)
			(end 0.120396 0.3048)
			(stroke
				(width 0.1)
				(type default)
			)
			(layer "F.Fab")
		)
		(fp_line
			(start -0.12065 0.2794)
			(end -0.12065 0.3048)
			(stroke
				(width 0.1)
				(type default)
			)
			(layer "F.Fab")
		)
		(fp_line
			(start 0.120396 0.2794)
			(end -0.12065 0.2794)
			(stroke
				(width 0.1)
				(type default)
			)
			(layer "F.Fab")
		)
		(fp_line
			(start -0.12065 -0.2794)
			(end 0.12065 -0.2794)
			(stroke
				(width 0.1)
				(type default)
			)
			(layer "F.Fab")
		)
		(fp_line
			(start 0.12065 -0.2794)
			(end 0.12065 -0.3048)
			(stroke
				(width 0.1)
				(type default)
			)
			(layer "F.Fab")
		)
		(fp_line
			(start 0.12065 -0.3048)
			(end 0.67945 -0.3048)
			(stroke
				(width 0.1)
				(type default)
			)
			(layer "F.Fab")
		)
		(fp_line
			(start 0.67945 -0.3048)
			(end 0.67945 0.3048)
			(stroke
				(width 0.1)
				(type default)
			)
			(layer "F.Fab")
		)
		(fp_line
			(start -0.67945 -0.305054)
			(end -0.12065 -0.305054)
			(stroke
				(width 0.1)
				(type default)
			)
			(layer "F.Fab")
		)
		(fp_line
			(start -0.12065 -0.305054)
			(end -0.12065 -0.2794)
			(stroke
				(width 0.1)
				(type default)
			)
			(layer "F.Fab")
		)
		(pad "1" smd circle
			(at -0.40005 0 270)
			(size 0 0)
			(layers "F.Cu" "F.Mask" "F.Paste")
			(net "P3V3_AUX")
		)
		(pad "2" smd circle
			(at 0.40005 0 270)
			(size 0 0)
			(layers "F.Cu" "F.Mask" "F.Paste")
			(net "GND")
		)
	)
	(footprint ""
		(layer "F.Cu")
		(at 390.992106 -78.863698 180)
		(property "Reference" "PC1651"
			(at 0 0 180)
			(layer "F.SilkS")
			(hide yes)
			(effects
				(font
					(size 1.27 1.27)
				)
			)
		)
		(property "Value" ""
			(at 0 0 180)
			(layer "F.Fab")
			(effects
				(font
					(size 1.27 1.27)
				)
			)
		)
		(duplicate_pad_numbers_are_jumpers no)
		(fp_line
			(start 0.7874 0.4064)
			(end -0.7874 0.4064)
			(stroke
				(width 0.1524)
				(type default)
			)
			(layer "F.SilkS")
		)
		(fp_line
			(start 0.7874 -0.4064)
			(end 0.7874 0.4064)
			(stroke
				(width 0.1524)
				(type default)
			)
			(layer "F.SilkS")
		)
		(fp_line
			(start -0.7874 0.4064)
			(end -0.7874 -0.4064)
			(stroke
				(width 0.1524)
				(type default)
			)
			(layer "F.SilkS")
		)
		(fp_line
			(start -0.7874 -0.4064)
			(end 0.7874 -0.4064)
			(stroke
				(width 0.1524)
				(type default)
			)
			(layer "F.SilkS")
		)
		(fp_line
			(start 0.67945 0.3048)
			(end 0.120396 0.3048)
			(stroke
				(width 0.1)
				(type default)
			)
			(layer "F.Fab")
		)
		(fp_line
			(start 0.67945 -0.3048)
			(end 0.67945 0.3048)
			(stroke
				(width 0.1)
				(type default)
			)
			(layer "F.Fab")
		)
		(fp_line
			(start 0.12065 -0.2794)
			(end 0.12065 -0.3048)
			(stroke
				(width 0.1)
				(type default)
			)
			(layer "F.Fab")
		)
		(fp_line
			(start 0.12065 -0.3048)
			(end 0.67945 -0.3048)
			(stroke
				(width 0.1)
				(type default)
			)
			(layer "F.Fab")
		)
		(fp_line
			(start 0.120396 0.3048)
			(end 0.120396 0.2794)
			(stroke
				(width 0.1)
				(type default)
			)
			(layer "F.Fab")
		)
		(fp_line
			(start 0.120396 0.2794)
			(end -0.12065 0.2794)
			(stroke
				(width 0.1)
				(type default)
			)
			(layer "F.Fab")
		)
		(fp_line
			(start -0.12065 0.3048)
			(end -0.67945 0.3048)
			(stroke
				(width 0.1)
				(type default)
			)
			(layer "F.Fab")
		)
		(fp_line
			(start -0.12065 0.2794)
			(end -0.12065 0.3048)
			(stroke
				(width 0.1)
				(type default)
			)
			(layer "F.Fab")
		)
		(fp_line
			(start -0.12065 -0.2794)
			(end 0.12065 -0.2794)
			(stroke
				(width 0.1)
				(type default)
			)
			(layer "F.Fab")
		)
		(fp_line
			(start -0.12065 -0.305054)
			(end -0.12065 -0.2794)
			(stroke
				(width 0.1)
				(type default)
			)
			(layer "F.Fab")
		)
		(fp_line
			(start -0.67945 0.3048)
			(end -0.67945 -0.305054)
			(stroke
				(width 0.1)
				(type default)
			)
			(layer "F.Fab")
		)
		(fp_line
			(start -0.67945 -0.305054)
			(end -0.12065 -0.305054)
			(stroke
				(width 0.1)
				(type default)
			)
			(layer "F.Fab")
		)
		(pad "1" smd circle
			(at -0.40005 0 180)
			(size 0 0)
			(layers "F.Cu" "F.Mask" "F.Paste")
			(net "P12V_AUX")
		)
		(pad "2" smd circle
			(at 0.40005 0 180)
			(size 0 0)
			(layers "F.Cu" "F.Mask" "F.Paste")
			(net "GND")
		)
	)
	(footprint ""
		(layer "F.Cu")
		(at 228.31044 -365.940848)
		(property "Reference" "ME21"
			(at 0 0 0)
			(layer "F.SilkS")
			(hide yes)
			(effects
				(font
					(size 1.27 1.27)
				)
			)
		)
		(property "Value" ""
			(at 0 0 0)
			(layer "F.Fab")
			(effects
				(font
					(size 1.27 1.27)
				)
			)
		)
		(duplicate_pad_numbers_are_jumpers no)
	)
	(footprint ""
		(layer "F.Cu")
		(at 392.03757 -408.517344 -90)
		(property "Reference" "C883"
			(at 0 0 270)
			(layer "F.SilkS")
			(hide yes)
			(effects
				(font
					(size 1.27 1.27)
				)
			)
		)
		(property "Value" ""
			(at 0 0 270)
			(layer "F.Fab")
			(effects
				(font
					(size 1.27 1.27)
				)
			)
		)
		(duplicate_pad_numbers_are_jumpers no)
		(fp_line
			(start -0.299974 0.150114)
			(end -0.299974 -0.150114)
			(stroke
				(width 0.1)
				(type default)
			)
			(layer "F.Fab")
		)
		(fp_line
			(start 0.299974 0.150114)
			(end -0.299974 0.150114)
			(stroke
				(width 0.1)
				(type default)
			)
			(layer "F.Fab")
		)
		(fp_line
			(start -0.299974 -0.150114)
			(end 0.299974 -0.150114)
			(stroke
				(width 0.1)
				(type default)
			)
			(layer "F.Fab")
		)
		(fp_line
			(start 0.299974 -0.150114)
			(end 0.299974 0.150114)
			(stroke
				(width 0.1)
				(type default)
			)
			(layer "F.Fab")
		)
		(pad "1" smd rect
			(at -0.2667 0 270)
			(size 0.3048 0.381)
			(layers "F.Cu" "F.Mask" "F.Paste")
			(net "P5E_CPU0_PE3_TX_C_DP<9>")
		)
		(pad "2" smd rect
			(at 0.2667 0 270)
			(size 0.3048 0.381)
			(layers "F.Cu" "F.Mask" "F.Paste")
			(net "P5E_CPU0_PE3_TX_DP<9>")
		)
	)
	(footprint ""
		(layer "F.Cu")
		(at 137.91819 -333.55153)
		(property "Reference" "PL24"
			(at -0.359156 7.018274 0)
			(unlocked yes)
			(layer "F.SilkS")
			(effects
				(font
					(size 0.7874 0.5842)
					(thickness 0.1524)
				)
				(justify left)
			)
		)
		(property "Value" ""
			(at 0 0 0)
			(layer "F.Fab")
			(effects
				(font
					(size 1.27 1.27)
				)
			)
		)
		(duplicate_pad_numbers_are_jumpers no)
		(fp_line
			(start -3.750056 -5.500116)
			(end -2.393442 -5.500116)
			(stroke
				(width 0.1524)
				(type default)
			)
			(layer "F.SilkS")
		)
		(fp_line
			(start -3.750056 5.500116)
			(end -3.750056 -5.500116)
			(stroke
				(width 0.1524)
				(type default)
			)
			(layer "F.SilkS")
		)
		(fp_line
			(start -2.393442 5.500116)
			(end -3.750056 5.500116)
			(stroke
				(width 0.1524)
				(type default)
			)
			(layer "F.SilkS")
		)
		(fp_line
			(start 2.393442 5.500116)
			(end 3.750056 5.500116)
			(stroke
				(width 0.1524)
				(type default)
			)
			(layer "F.SilkS")
		)
		(fp_line
			(start 3.750056 -5.500116)
			(end 2.393442 -5.500116)
			(stroke
				(width 0.1524)
				(type default)
			)
			(layer "F.SilkS")
		)
		(fp_line
			(start 3.750056 5.500116)
			(end 3.750056 -5.500116)
			(stroke
				(width 0.1524)
				(type default)
			)
			(layer "F.SilkS")
		)
		(fp_poly
			(pts
				(xy -5.02666 -5.700268) (xy -4.01066 -5.192268) (xy -5.02666 -4.684268)
			)
			(stroke
				(width 0)
				(type default)
			)
			(fill yes)
			(layer "F.SilkS")
		)
		(fp_line
			(start -3.750056 -5.500116)
			(end -3.750056 5.500116)
			(stroke
				(width 0.1)
				(type default)
			)
			(layer "F.Fab")
		)
		(fp_line
			(start -3.750056 5.500116)
			(end 3.750056 5.500116)
			(stroke
				(width 0.1)
				(type default)
			)
			(layer "F.Fab")
		)
		(fp_line
			(start 3.750056 -5.500116)
			(end -3.750056 -5.500116)
			(stroke
				(width 0.1)
				(type default)
			)
			(layer "F.Fab")
		)
		(fp_line
			(start 3.750056 5.500116)
			(end 3.750056 -5.500116)
			(stroke
				(width 0.1)
				(type default)
			)
			(layer "F.Fab")
		)
		(fp_poly
			(pts
				(xy -4.9276 -4.757928) (xy -4.9276 -3.741928) (xy -3.9116 -4.249928)
			)
			(stroke
				(width 0)
				(type default)
			)
			(fill yes)
			(layer "F.Fab")
		)
		(pad "1" smd rect
			(at 0 -4.249928 270)
			(size 2.413 4.5212)
			(layers "F.Cu" "F.Mask" "F.Paste")
			(net "SW_PVCCIN_CPU1_SW8")
		)
		(pad "2" smd rect
			(at 0 -1.175004 270)
			(size 1.3716 4.5212)
			(layers "F.Cu" "F.Mask" "F.Paste")
			(net "IND_P1_CPL8")
		)
		(pad "3" smd rect
			(at 0 1.175004 270)
			(size 1.3716 4.5212)
			(layers "F.Cu" "F.Mask" "F.Paste")
			(net "IND_P1_CPL5")
		)
		(pad "4" smd rect
			(at 0 4.249928 270)
			(size 2.413 4.5212)
			(layers "F.Cu" "F.Mask" "F.Paste")
			(net "PVCCIN_CPU1")
		)
	)
	(footprint ""
		(layer "F.Cu")
		(at 465.821014 -116.616734)
		(property "Reference" "R1128"
			(at 0 0 0)
			(layer "F.SilkS")
			(hide yes)
			(effects
				(font
					(size 1.27 1.27)
				)
			)
		)
		(property "Value" ""
			(at 0 0 0)
			(layer "F.Fab")
			(effects
				(font
					(size 1.27 1.27)
				)
			)
		)
		(duplicate_pad_numbers_are_jumpers no)
		(fp_line
			(start -0.7874 -0.4064)
			(end 0.7874 -0.4064)
			(stroke
				(width 0.1524)
				(type default)
			)
			(layer "F.SilkS")
		)
		(fp_line
			(start -0.7874 0.4064)
			(end -0.7874 -0.4064)
			(stroke
				(width 0.1524)
				(type default)
			)
			(layer "F.SilkS")
		)
		(fp_line
			(start 0.7874 -0.4064)
			(end 0.7874 0.4064)
			(stroke
				(width 0.1524)
				(type default)
			)
			(layer "F.SilkS")
		)
		(fp_line
			(start 0.7874 0.4064)
			(end -0.7874 0.4064)
			(stroke
				(width 0.1524)
				(type default)
			)
			(layer "F.SilkS")
		)
		(fp_line
			(start -0.67945 -0.305054)
			(end -0.12065 -0.305054)
			(stroke
				(width 0.1)
				(type default)
			)
			(layer "F.Fab")
		)
		(fp_line
			(start -0.67945 0.3048)
			(end -0.67945 -0.305054)
			(stroke
				(width 0.1)
				(type default)
			)
			(layer "F.Fab")
		)
		(fp_line
			(start -0.12065 -0.305054)
			(end -0.12065 -0.2794)
			(stroke
				(width 0.1)
				(type default)
			)
			(layer "F.Fab")
		)
		(fp_line
			(start -0.12065 -0.2794)
			(end 0.12065 -0.2794)
			(stroke
				(width 0.1)
				(type default)
			)
			(layer "F.Fab")
		)
		(fp_line
			(start -0.12065 0.2794)
			(end -0.12065 0.3048)
			(stroke
				(width 0.1)
				(type default)
			)
			(layer "F.Fab")
		)
		(fp_line
			(start -0.12065 0.3048)
			(end -0.67945 0.3048)
			(stroke
				(width 0.1)
				(type default)
			)
			(layer "F.Fab")
		)
		(fp_line
			(start 0.120396 0.2794)
			(end -0.12065 0.2794)
			(stroke
				(width 0.1)
				(type default)
			)
			(layer "F.Fab")
		)
		(fp_line
			(start 0.120396 0.3048)
			(end 0.120396 0.2794)
			(stroke
				(width 0.1)
				(type default)
			)
			(layer "F.Fab")
		)
		(fp_line
			(start 0.12065 -0.3048)
			(end 0.67945 -0.3048)
			(stroke
				(width 0.1)
				(type default)
			)
			(layer "F.Fab")
		)
		(fp_line
			(start 0.12065 -0.2794)
			(end 0.12065 -0.3048)
			(stroke
				(width 0.1)
				(type default)
			)
			(layer "F.Fab")
		)
		(fp_line
			(start 0.67945 -0.3048)
			(end 0.67945 0.3048)
			(stroke
				(width 0.1)
				(type default)
			)
			(layer "F.Fab")
		)
		(fp_line
			(start 0.67945 0.3048)
			(end 0.120396 0.3048)
			(stroke
				(width 0.1)
				(type default)
			)
			(layer "F.Fab")
		)
		(pad "1" smd circle
			(at -0.40005 0)
			(size 0 0)
			(layers "F.Cu" "F.Mask" "F.Paste")
			(net "PD_SMB_OCP1_HP_ADD0")
		)
		(pad "2" smd circle
			(at 0.40005 0)
			(size 0 0)
			(layers "F.Cu" "F.Mask" "F.Paste")
			(net "GND")
		)
	)
	(footprint ""
		(layer "F.Cu")
		(at 133.53288 -100.167948 90)
		(property "Reference" "R206"
			(at 0 0 90)
			(layer "F.SilkS")
			(hide yes)
			(effects
				(font
					(size 1.27 1.27)
				)
			)
		)
		(property "Value" ""
			(at 0 0 90)
			(layer "F.Fab")
			(effects
				(font
					(size 1.27 1.27)
				)
			)
		)
		(duplicate_pad_numbers_are_jumpers no)
		(fp_line
			(start 0.7874 -0.4064)
			(end 0.7874 0.4064)
			(stroke
				(width 0.1524)
				(type default)
			)
			(layer "F.SilkS")
		)
		(fp_line
			(start -0.7874 -0.4064)
			(end 0.7874 -0.4064)
			(stroke
				(width 0.1524)
				(type default)
			)
			(layer "F.SilkS")
		)
		(fp_line
			(start 0.7874 0.4064)
			(end -0.7874 0.4064)
			(stroke
				(width 0.1524)
				(type default)
			)
			(layer "F.SilkS")
		)
		(fp_line
			(start -0.7874 0.4064)
			(end -0.7874 -0.4064)
			(stroke
				(width 0.1524)
				(type default)
			)
			(layer "F.SilkS")
		)
		(fp_line
			(start -0.12065 -0.305054)
			(end -0.12065 -0.2794)
			(stroke
				(width 0.1)
				(type default)
			)
			(layer "F.Fab")
		)
		(fp_line
			(start -0.67945 -0.305054)
			(end -0.12065 -0.305054)
			(stroke
				(width 0.1)
				(type default)
			)
			(layer "F.Fab")
		)
		(fp_line
			(start 0.67945 -0.3048)
			(end 0.67945 0.3048)
			(stroke
				(width 0.1)
				(type default)
			)
			(layer "F.Fab")
		)
		(fp_line
			(start 0.12065 -0.3048)
			(end 0.67945 -0.3048)
			(stroke
				(width 0.1)
				(type default)
			)
			(layer "F.Fab")
		)
		(fp_line
			(start 0.12065 -0.2794)
			(end 0.12065 -0.3048)
			(stroke
				(width 0.1)
				(type default)
			)
			(layer "F.Fab")
		)
		(fp_line
			(start -0.12065 -0.2794)
			(end 0.12065 -0.2794)
			(stroke
				(width 0.1)
				(type default)
			)
			(layer "F.Fab")
		)
		(fp_line
			(start 0.120396 0.2794)
			(end -0.12065 0.2794)
			(stroke
				(width 0.1)
				(type default)
			)
			(layer "F.Fab")
		)
		(fp_line
			(start -0.12065 0.2794)
			(end -0.12065 0.3048)
			(stroke
				(width 0.1)
				(type default)
			)
			(layer "F.Fab")
		)
		(fp_line
			(start 0.67945 0.3048)
			(end 0.120396 0.3048)
			(stroke
				(width 0.1)
				(type default)
			)
			(layer "F.Fab")
		)
		(fp_line
			(start 0.120396 0.3048)
			(end 0.120396 0.2794)
			(stroke
				(width 0.1)
				(type default)
			)
			(layer "F.Fab")
		)
		(fp_line
			(start -0.12065 0.3048)
			(end -0.67945 0.3048)
			(stroke
				(width 0.1)
				(type default)
			)
			(layer "F.Fab")
		)
		(fp_line
			(start -0.67945 0.3048)
			(end -0.67945 -0.305054)
			(stroke
				(width 0.1)
				(type default)
			)
			(layer "F.Fab")
		)
		(pad "1" smd circle
			(at -0.40005 0 90)
			(size 0 0)
			(layers "F.Cu" "F.Mask" "F.Paste")
			(net "H_CPU1_MEMTRIP_LVC1_R_N")
		)
		(pad "2" smd circle
			(at 0.40005 0 90)
			(size 0 0)
			(layers "F.Cu" "F.Mask" "F.Paste")
			(net "H_CPU1_MEMTRIP_OUT_VT_R_N")
		)
	)
	(footprint ""
		(layer "F.Cu")
		(at 109.580934 -393.14374 180)
		(property "Reference" "R3459"
			(at 0 0 180)
			(layer "F.SilkS")
			(hide yes)
			(effects
				(font
					(size 1.27 1.27)
				)
			)
		)
		(property "Value" ""
			(at 0 0 180)
			(layer "F.Fab")
			(effects
				(font
					(size 1.27 1.27)
				)
			)
		)
		(duplicate_pad_numbers_are_jumpers no)
		(fp_line
			(start 0.7874 0.4064)
			(end -0.7874 0.4064)
			(stroke
				(width 0.1524)
				(type default)
			)
			(layer "F.SilkS")
		)
		(fp_line
			(start 0.7874 -0.4064)
			(end 0.7874 0.4064)
			(stroke
				(width 0.1524)
				(type default)
			)
			(layer "F.SilkS")
		)
		(fp_line
			(start -0.7874 0.4064)
			(end -0.7874 -0.4064)
			(stroke
				(width 0.1524)
				(type default)
			)
			(layer "F.SilkS")
		)
		(fp_line
			(start -0.7874 -0.4064)
			(end 0.7874 -0.4064)
			(stroke
				(width 0.1524)
				(type default)
			)
			(layer "F.SilkS")
		)
		(fp_line
			(start 0.67945 0.3048)
			(end 0.120396 0.3048)
			(stroke
				(width 0.1)
				(type default)
			)
			(layer "F.Fab")
		)
		(fp_line
			(start 0.67945 -0.3048)
			(end 0.67945 0.3048)
			(stroke
				(width 0.1)
				(type default)
			)
			(layer "F.Fab")
		)
		(fp_line
			(start 0.12065 -0.2794)
			(end 0.12065 -0.3048)
			(stroke
				(width 0.1)
				(type default)
			)
			(layer "F.Fab")
		)
		(fp_line
			(start 0.12065 -0.3048)
			(end 0.67945 -0.3048)
			(stroke
				(width 0.1)
				(type default)
			)
			(layer "F.Fab")
		)
		(fp_line
			(start 0.120396 0.3048)
			(end 0.120396 0.2794)
			(stroke
				(width 0.1)
				(type default)
			)
			(layer "F.Fab")
		)
		(fp_line
			(start 0.120396 0.2794)
			(end -0.12065 0.2794)
			(stroke
				(width 0.1)
				(type default)
			)
			(layer "F.Fab")
		)
		(fp_line
			(start -0.12065 0.3048)
			(end -0.67945 0.3048)
			(stroke
				(width 0.1)
				(type default)
			)
			(layer "F.Fab")
		)
		(fp_line
			(start -0.12065 0.2794)
			(end -0.12065 0.3048)
			(stroke
				(width 0.1)
				(type default)
			)
			(layer "F.Fab")
		)
		(fp_line
			(start -0.12065 -0.2794)
			(end 0.12065 -0.2794)
			(stroke
				(width 0.1)
				(type default)
			)
			(layer "F.Fab")
		)
		(fp_line
			(start -0.12065 -0.305054)
			(end -0.12065 -0.2794)
			(stroke
				(width 0.1)
				(type default)
			)
			(layer "F.Fab")
		)
		(fp_line
			(start -0.67945 0.3048)
			(end -0.67945 -0.305054)
			(stroke
				(width 0.1)
				(type default)
			)
			(layer "F.Fab")
		)
		(fp_line
			(start -0.67945 -0.305054)
			(end -0.12065 -0.305054)
			(stroke
				(width 0.1)
				(type default)
			)
			(layer "F.Fab")
		)
		(pad "1" smd circle
			(at -0.40005 0 180)
			(size 0 0)
			(layers "F.Cu" "F.Mask" "F.Paste")
			(net "P3V3_AUX")
		)
		(pad "2" smd circle
			(at 0.40005 0 180)
			(size 0 0)
			(layers "F.Cu" "F.Mask" "F.Paste")
			(net "GPU_NVS_PWR_BRAKE_N")
		)
	)
	(footprint ""
		(layer "F.Cu")
		(at 288.580068 -395.046454 180)
		(property "Reference" "PC1789"
			(at 0 0 180)
			(layer "F.SilkS")
			(hide yes)
			(effects
				(font
					(size 1.27 1.27)
				)
			)
		)
		(property "Value" ""
			(at 0 0 180)
			(layer "F.Fab")
			(effects
				(font
					(size 1.27 1.27)
				)
			)
		)
		(duplicate_pad_numbers_are_jumpers no)
		(fp_line
			(start 0.7874 0.4064)
			(end -0.7874 0.4064)
			(stroke
				(width 0.1524)
				(type default)
			)
			(layer "F.SilkS")
		)
		(fp_line
			(start 0.7874 -0.4064)
			(end 0.7874 0.4064)
			(stroke
				(width 0.1524)
				(type default)
			)
			(layer "F.SilkS")
		)
		(fp_line
			(start -0.7874 0.4064)
			(end -0.7874 -0.4064)
			(stroke
				(width 0.1524)
				(type default)
			)
			(layer "F.SilkS")
		)
		(fp_line
			(start -0.7874 -0.4064)
			(end 0.7874 -0.4064)
			(stroke
				(width 0.1524)
				(type default)
			)
			(layer "F.SilkS")
		)
		(fp_line
			(start 0.67945 0.3048)
			(end 0.120396 0.3048)
			(stroke
				(width 0.1)
				(type default)
			)
			(layer "F.Fab")
		)
		(fp_line
			(start 0.67945 -0.3048)
			(end 0.67945 0.3048)
			(stroke
				(width 0.1)
				(type default)
			)
			(layer "F.Fab")
		)
		(fp_line
			(start 0.12065 -0.2794)
			(end 0.12065 -0.3048)
			(stroke
				(width 0.1)
				(type default)
			)
			(layer "F.Fab")
		)
		(fp_line
			(start 0.12065 -0.3048)
			(end 0.67945 -0.3048)
			(stroke
				(width 0.1)
				(type default)
			)
			(layer "F.Fab")
		)
		(fp_line
			(start 0.120396 0.3048)
			(end 0.120396 0.2794)
			(stroke
				(width 0.1)
				(type default)
			)
			(layer "F.Fab")
		)
		(fp_line
			(start 0.120396 0.2794)
			(end -0.12065 0.2794)
			(stroke
				(width 0.1)
				(type default)
			)
			(layer "F.Fab")
		)
		(fp_line
			(start -0.12065 0.3048)
			(end -0.67945 0.3048)
			(stroke
				(width 0.1)
				(type default)
			)
			(layer "F.Fab")
		)
		(fp_line
			(start -0.12065 0.2794)
			(end -0.12065 0.3048)
			(stroke
				(width 0.1)
				(type default)
			)
			(layer "F.Fab")
		)
		(fp_line
			(start -0.12065 -0.2794)
			(end 0.12065 -0.2794)
			(stroke
				(width 0.1)
				(type default)
			)
			(layer "F.Fab")
		)
		(fp_line
			(start -0.12065 -0.305054)
			(end -0.12065 -0.2794)
			(stroke
				(width 0.1)
				(type default)
			)
			(layer "F.Fab")
		)
		(fp_line
			(start -0.67945 0.3048)
			(end -0.67945 -0.305054)
			(stroke
				(width 0.1)
				(type default)
			)
			(layer "F.Fab")
		)
		(fp_line
			(start -0.67945 -0.305054)
			(end -0.12065 -0.305054)
			(stroke
				(width 0.1)
				(type default)
			)
			(layer "F.Fab")
		)
		(pad "1" smd circle
			(at -0.40005 0 180)
			(size 0 0)
			(layers "F.Cu" "F.Mask" "F.Paste")
			(net "P12V_AUX")
		)
		(pad "2" smd circle
			(at 0.40005 0 180)
			(size 0 0)
			(layers "F.Cu" "F.Mask" "F.Paste")
			(net "GND")
		)
	)
	(footprint ""
		(layer "F.Cu")
		(at 108.006388 -102.943152)
		(property "Reference" "Q77"
			(at -1.803908 -3.540506 0)
			(unlocked yes)
			(layer "F.SilkS")
			(effects
				(font
					(size 0.7874 0.5842)
					(thickness 0.1524)
				)
				(justify left)
			)
		)
		(property "Value" ""
			(at 0 0 0)
			(layer "F.Fab")
			(effects
				(font
					(size 1.27 1.27)
				)
			)
		)
		(duplicate_pad_numbers_are_jumpers no)
		(fp_line
			(start -1.332738 -1.100074)
			(end -0.4826 -1.100074)
			(stroke
				(width 0.1524)
				(type default)
			)
			(layer "F.SilkS")
		)
		(fp_line
			(start -1.332738 1.100074)
			(end -1.332738 -1.100074)
			(stroke
				(width 0.1524)
				(type default)
			)
			(layer "F.SilkS")
		)
		(fp_line
			(start -0.4826 -1.100074)
			(end 0 -0.541274)
			(stroke
				(width 0.1524)
				(type default)
			)
			(layer "F.SilkS")
		)
		(fp_line
			(start 0 -0.541274)
			(end 0.4826 -1.100074)
			(stroke
				(width 0.1524)
				(type default)
			)
			(layer "F.SilkS")
		)
		(fp_line
			(start 0.4826 -1.100074)
			(end 1.332738 -1.100074)
			(stroke
				(width 0.1524)
				(type default)
			)
			(layer "F.SilkS")
		)
		(fp_line
			(start 1.332738 -1.100074)
			(end 1.332738 1.100074)
			(stroke
				(width 0.1524)
				(type default)
			)
			(layer "F.SilkS")
		)
		(fp_line
			(start 1.332738 1.100074)
			(end -1.332738 1.100074)
			(stroke
				(width 0.1524)
				(type default)
			)
			(layer "F.SilkS")
		)
		(fp_poly
			(pts
				(xy -0.60325 -2.019808) (xy -0.954278 -1.317752) (xy -1.305306 -2.019808)
			)
			(stroke
				(width 0)
				(type default)
			)
			(fill yes)
			(layer "F.SilkS")
		)
		(fp_line
			(start -0.674878 -1.100074)
			(end 0.674878 -1.100074)
			(stroke
				(width 0.1)
				(type default)
			)
			(layer "F.Fab")
		)
		(fp_line
			(start -0.674878 1.100074)
			(end -0.674878 -1.100074)
			(stroke
				(width 0.1)
				(type default)
			)
			(layer "F.Fab")
		)
		(fp_line
			(start 0.674878 -1.100074)
			(end 0.674878 1.100074)
			(stroke
				(width 0.1)
				(type default)
			)
			(layer "F.Fab")
		)
		(fp_line
			(start 0.674878 1.100074)
			(end -0.674878 1.100074)
			(stroke
				(width 0.1)
				(type default)
			)
			(layer "F.Fab")
		)
		(fp_poly
			(pts
				(xy -2.2352 -0.298958) (xy -2.2352 -1.001014) (xy -1.533144 -0.649986)
			)
			(stroke
				(width 0)
				(type default)
			)
			(fill yes)
			(layer "F.Fab")
		)
		(pad "1" smd rect
			(at -0.94996 -0.649986 90)
			(size 0.4318 0.508)
			(layers "F.Cu" "F.Mask" "F.Paste")
			(net "GND")
		)
		(pad "2" smd rect
			(at -0.94996 0 90)
			(size 0.4318 0.508)
			(layers "F.Cu" "F.Mask" "F.Paste")
			(net "RST_RSMRST_PLD_R_N")
		)
		(pad "3" smd rect
			(at -0.94996 0.649986 90)
			(size 0.4318 0.508)
			(layers "F.Cu" "F.Mask" "F.Paste")
			(net "LED_FM_PCH_SLP_S4_N_D")
		)
		(pad "4" smd rect
			(at 0.94996 0.649986 90)
			(size 0.4318 0.508)
			(layers "F.Cu" "F.Mask" "F.Paste")
			(net "GND")
		)
		(pad "5" smd rect
			(at 0.94996 0 90)
			(size 0.4318 0.508)
			(layers "F.Cu" "F.Mask" "F.Paste")
			(net "FM_PCH_SLP_S4_N")
		)
		(pad "6" smd rect
			(at 0.94996 -0.649986 90)
			(size 0.4318 0.508)
			(layers "F.Cu" "F.Mask" "F.Paste")
			(net "LED_RST_RSMRST_PLD_R_N_D")
		)
	)
	(footprint ""
		(layer "F.Cu")
		(at 131.50088 -100.167948 -90)
		(property "Reference" "R4413"
			(at 0 0 270)
			(layer "F.SilkS")
			(hide yes)
			(effects
				(font
					(size 1.27 1.27)
				)
			)
		)
		(property "Value" ""
			(at 0 0 270)
			(layer "F.Fab")
			(effects
				(font
					(size 1.27 1.27)
				)
			)
		)
		(duplicate_pad_numbers_are_jumpers no)
		(fp_line
			(start -0.7874 0.4064)
			(end -0.7874 -0.4064)
			(stroke
				(width 0.1524)
				(type default)
			)
			(layer "F.SilkS")
		)
		(fp_line
			(start 0.7874 0.4064)
			(end -0.7874 0.4064)
			(stroke
				(width 0.1524)
				(type default)
			)
			(layer "F.SilkS")
		)
		(fp_line
			(start -0.7874 -0.4064)
			(end 0.7874 -0.4064)
			(stroke
				(width 0.1524)
				(type default)
			)
			(layer "F.SilkS")
		)
		(fp_line
			(start 0.7874 -0.4064)
			(end 0.7874 0.4064)
			(stroke
				(width 0.1524)
				(type default)
			)
			(layer "F.SilkS")
		)
		(fp_line
			(start -0.67945 0.3048)
			(end -0.67945 -0.305054)
			(stroke
				(width 0.1)
				(type default)
			)
			(layer "F.Fab")
		)
		(fp_line
			(start -0.12065 0.3048)
			(end -0.67945 0.3048)
			(stroke
				(width 0.1)
				(type default)
			)
			(layer "F.Fab")
		)
		(fp_line
			(start 0.120396 0.3048)
			(end 0.120396 0.2794)
			(stroke
				(width 0.1)
				(type default)
			)
			(layer "F.Fab")
		)
		(fp_line
			(start 0.67945 0.3048)
			(end 0.120396 0.3048)
			(stroke
				(width 0.1)
				(type default)
			)
			(layer "F.Fab")
		)
		(fp_line
			(start -0.12065 0.2794)
			(end -0.12065 0.3048)
			(stroke
				(width 0.1)
				(type default)
			)
			(layer "F.Fab")
		)
		(fp_line
			(start 0.120396 0.2794)
			(end -0.12065 0.2794)
			(stroke
				(width 0.1)
				(type default)
			)
			(layer "F.Fab")
		)
		(fp_line
			(start -0.12065 -0.2794)
			(end 0.12065 -0.2794)
			(stroke
				(width 0.1)
				(type default)
			)
			(layer "F.Fab")
		)
		(fp_line
			(start 0.12065 -0.2794)
			(end 0.12065 -0.3048)
			(stroke
				(width 0.1)
				(type default)
			)
			(layer "F.Fab")
		)
		(fp_line
			(start 0.12065 -0.3048)
			(end 0.67945 -0.3048)
			(stroke
				(width 0.1)
				(type default)
			)
			(layer "F.Fab")
		)
		(fp_line
			(start 0.67945 -0.3048)
			(end 0.67945 0.3048)
			(stroke
				(width 0.1)
				(type default)
			)
			(layer "F.Fab")
		)
		(fp_line
			(start -0.67945 -0.305054)
			(end -0.12065 -0.305054)
			(stroke
				(width 0.1)
				(type default)
			)
			(layer "F.Fab")
		)
		(fp_line
			(start -0.12065 -0.305054)
			(end -0.12065 -0.2794)
			(stroke
				(width 0.1)
				(type default)
			)
			(layer "F.Fab")
		)
		(pad "1" smd circle
			(at -0.40005 0 270)
			(size 0 0)
			(layers "F.Cu" "F.Mask" "F.Paste")
			(net "H_CPU0_MEMTRIP_VT_N")
		)
		(pad "2" smd circle
			(at 0.40005 0 270)
			(size 0 0)
			(layers "F.Cu" "F.Mask" "F.Paste")
			(net "H_CPU0_MEMTRIP_LVC1_N")
		)
	)
	(footprint ""
		(layer "F.Cu")
		(at 437.242966 -120.614186)
		(property "Reference" "C626"
			(at 0 0 0)
			(layer "F.SilkS")
			(hide yes)
			(effects
				(font
					(size 1.27 1.27)
				)
			)
		)
		(property "Value" ""
			(at 0 0 0)
			(layer "F.Fab")
			(effects
				(font
					(size 1.27 1.27)
				)
			)
		)
		(duplicate_pad_numbers_are_jumpers no)
		(fp_line
			(start -0.7874 -0.4064)
			(end 0.7874 -0.4064)
			(stroke
				(width 0.1524)
				(type default)
			)
			(layer "F.SilkS")
		)
		(fp_line
			(start -0.7874 0.4064)
			(end -0.7874 -0.4064)
			(stroke
				(width 0.1524)
				(type default)
			)
			(layer "F.SilkS")
		)
		(fp_line
			(start 0.7874 -0.4064)
			(end 0.7874 0.4064)
			(stroke
				(width 0.1524)
				(type default)
			)
			(layer "F.SilkS")
		)
		(fp_line
			(start 0.7874 0.4064)
			(end -0.7874 0.4064)
			(stroke
				(width 0.1524)
				(type default)
			)
			(layer "F.SilkS")
		)
		(fp_line
			(start -0.67945 -0.305054)
			(end -0.12065 -0.305054)
			(stroke
				(width 0.1)
				(type default)
			)
			(layer "F.Fab")
		)
		(fp_line
			(start -0.67945 0.3048)
			(end -0.67945 -0.305054)
			(stroke
				(width 0.1)
				(type default)
			)
			(layer "F.Fab")
		)
		(fp_line
			(start -0.12065 -0.305054)
			(end -0.12065 -0.2794)
			(stroke
				(width 0.1)
				(type default)
			)
			(layer "F.Fab")
		)
		(fp_line
			(start -0.12065 -0.2794)
			(end 0.12065 -0.2794)
			(stroke
				(width 0.1)
				(type default)
			)
			(layer "F.Fab")
		)
		(fp_line
			(start -0.12065 0.2794)
			(end -0.12065 0.3048)
			(stroke
				(width 0.1)
				(type default)
			)
			(layer "F.Fab")
		)
		(fp_line
			(start -0.12065 0.3048)
			(end -0.67945 0.3048)
			(stroke
				(width 0.1)
				(type default)
			)
			(layer "F.Fab")
		)
		(fp_line
			(start 0.120396 0.2794)
			(end -0.12065 0.2794)
			(stroke
				(width 0.1)
				(type default)
			)
			(layer "F.Fab")
		)
		(fp_line
			(start 0.120396 0.3048)
			(end 0.120396 0.2794)
			(stroke
				(width 0.1)
				(type default)
			)
			(layer "F.Fab")
		)
		(fp_line
			(start 0.12065 -0.3048)
			(end 0.67945 -0.3048)
			(stroke
				(width 0.1)
				(type default)
			)
			(layer "F.Fab")
		)
		(fp_line
			(start 0.12065 -0.2794)
			(end 0.12065 -0.3048)
			(stroke
				(width 0.1)
				(type default)
			)
			(layer "F.Fab")
		)
		(fp_line
			(start 0.67945 -0.3048)
			(end 0.67945 0.3048)
			(stroke
				(width 0.1)
				(type default)
			)
			(layer "F.Fab")
		)
		(fp_line
			(start 0.67945 0.3048)
			(end 0.120396 0.3048)
			(stroke
				(width 0.1)
				(type default)
			)
			(layer "F.Fab")
		)
		(pad "1" smd circle
			(at -0.40005 0)
			(size 0 0)
			(layers "F.Cu" "F.Mask" "F.Paste")
			(net "PWRGD_PVCCD_HV_CPU0_R")
		)
		(pad "2" smd circle
			(at 0.40005 0)
			(size 0 0)
			(layers "F.Cu" "F.Mask" "F.Paste")
			(net "GND")
		)
	)
	(footprint ""
		(layer "F.Cu")
		(at 308.79288 -53.050948 90)
		(property "Reference" "R143"
			(at 0 0 90)
			(layer "F.SilkS")
			(hide yes)
			(effects
				(font
					(size 1.27 1.27)
				)
			)
		)
		(property "Value" ""
			(at 0 0 90)
			(layer "F.Fab")
			(effects
				(font
					(size 1.27 1.27)
				)
			)
		)
		(duplicate_pad_numbers_are_jumpers no)
		(fp_line
			(start 0.7874 -0.4064)
			(end 0.7874 0.4064)
			(stroke
				(width 0.1524)
				(type default)
			)
			(layer "F.SilkS")
		)
		(fp_line
			(start -0.7874 -0.4064)
			(end 0.7874 -0.4064)
			(stroke
				(width 0.1524)
				(type default)
			)
			(layer "F.SilkS")
		)
		(fp_line
			(start 0.7874 0.4064)
			(end -0.7874 0.4064)
			(stroke
				(width 0.1524)
				(type default)
			)
			(layer "F.SilkS")
		)
		(fp_line
			(start -0.7874 0.4064)
			(end -0.7874 -0.4064)
			(stroke
				(width 0.1524)
				(type default)
			)
			(layer "F.SilkS")
		)
		(fp_line
			(start -0.12065 -0.305054)
			(end -0.12065 -0.2794)
			(stroke
				(width 0.1)
				(type default)
			)
			(layer "F.Fab")
		)
		(fp_line
			(start -0.67945 -0.305054)
			(end -0.12065 -0.305054)
			(stroke
				(width 0.1)
				(type default)
			)
			(layer "F.Fab")
		)
		(fp_line
			(start 0.67945 -0.3048)
			(end 0.67945 0.3048)
			(stroke
				(width 0.1)
				(type default)
			)
			(layer "F.Fab")
		)
		(fp_line
			(start 0.12065 -0.3048)
			(end 0.67945 -0.3048)
			(stroke
				(width 0.1)
				(type default)
			)
			(layer "F.Fab")
		)
		(fp_line
			(start 0.12065 -0.2794)
			(end 0.12065 -0.3048)
			(stroke
				(width 0.1)
				(type default)
			)
			(layer "F.Fab")
		)
		(fp_line
			(start -0.12065 -0.2794)
			(end 0.12065 -0.2794)
			(stroke
				(width 0.1)
				(type default)
			)
			(layer "F.Fab")
		)
		(fp_line
			(start 0.120396 0.2794)
			(end -0.12065 0.2794)
			(stroke
				(width 0.1)
				(type default)
			)
			(layer "F.Fab")
		)
		(fp_line
			(start -0.12065 0.2794)
			(end -0.12065 0.3048)
			(stroke
				(width 0.1)
				(type default)
			)
			(layer "F.Fab")
		)
		(fp_line
			(start 0.67945 0.3048)
			(end 0.120396 0.3048)
			(stroke
				(width 0.1)
				(type default)
			)
			(layer "F.Fab")
		)
		(fp_line
			(start 0.120396 0.3048)
			(end 0.120396 0.2794)
			(stroke
				(width 0.1)
				(type default)
			)
			(layer "F.Fab")
		)
		(fp_line
			(start -0.12065 0.3048)
			(end -0.67945 0.3048)
			(stroke
				(width 0.1)
				(type default)
			)
			(layer "F.Fab")
		)
		(fp_line
			(start -0.67945 0.3048)
			(end -0.67945 -0.305054)
			(stroke
				(width 0.1)
				(type default)
			)
			(layer "F.Fab")
		)
		(pad "1" smd circle
			(at -0.40005 0 90)
			(size 0 0)
			(layers "F.Cu" "F.Mask" "F.Paste")
			(net "PECI_PCH")
		)
		(pad "2" smd circle
			(at 0.40005 0 90)
			(size 0 0)
			(layers "F.Cu" "F.Mask" "F.Paste")
			(net "PECI_PCH_R")
		)
	)
	(footprint ""
		(layer "F.Cu")
		(at 438.87771 -43.960288 180)
		(property "Reference" "R3241"
			(at 0 0 180)
			(layer "F.SilkS")
			(hide yes)
			(effects
				(font
					(size 1.27 1.27)
				)
			)
		)
		(property "Value" ""
			(at 0 0 180)
			(layer "F.Fab")
			(effects
				(font
					(size 1.27 1.27)
				)
			)
		)
		(duplicate_pad_numbers_are_jumpers no)
		(fp_line
			(start 0.7874 0.4064)
			(end -0.7874 0.4064)
			(stroke
				(width 0.1524)
				(type default)
			)
			(layer "F.SilkS")
		)
		(fp_line
			(start 0.7874 -0.4064)
			(end 0.7874 0.4064)
			(stroke
				(width 0.1524)
				(type default)
			)
			(layer "F.SilkS")
		)
		(fp_line
			(start -0.7874 0.4064)
			(end -0.7874 -0.4064)
			(stroke
				(width 0.1524)
				(type default)
			)
			(layer "F.SilkS")
		)
		(fp_line
			(start -0.7874 -0.4064)
			(end 0.7874 -0.4064)
			(stroke
				(width 0.1524)
				(type default)
			)
			(layer "F.SilkS")
		)
		(fp_line
			(start 0.67945 0.3048)
			(end 0.120396 0.3048)
			(stroke
				(width 0.1)
				(type default)
			)
			(layer "F.Fab")
		)
		(fp_line
			(start 0.67945 -0.3048)
			(end 0.67945 0.3048)
			(stroke
				(width 0.1)
				(type default)
			)
			(layer "F.Fab")
		)
		(fp_line
			(start 0.12065 -0.2794)
			(end 0.12065 -0.3048)
			(stroke
				(width 0.1)
				(type default)
			)
			(layer "F.Fab")
		)
		(fp_line
			(start 0.12065 -0.3048)
			(end 0.67945 -0.3048)
			(stroke
				(width 0.1)
				(type default)
			)
			(layer "F.Fab")
		)
		(fp_line
			(start 0.120396 0.3048)
			(end 0.120396 0.2794)
			(stroke
				(width 0.1)
				(type default)
			)
			(layer "F.Fab")
		)
		(fp_line
			(start 0.120396 0.2794)
			(end -0.12065 0.2794)
			(stroke
				(width 0.1)
				(type default)
			)
			(layer "F.Fab")
		)
		(fp_line
			(start -0.12065 0.3048)
			(end -0.67945 0.3048)
			(stroke
				(width 0.1)
				(type default)
			)
			(layer "F.Fab")
		)
		(fp_line
			(start -0.12065 0.2794)
			(end -0.12065 0.3048)
			(stroke
				(width 0.1)
				(type default)
			)
			(layer "F.Fab")
		)
		(fp_line
			(start -0.12065 -0.2794)
			(end 0.12065 -0.2794)
			(stroke
				(width 0.1)
				(type default)
			)
			(layer "F.Fab")
		)
		(fp_line
			(start -0.12065 -0.305054)
			(end -0.12065 -0.2794)
			(stroke
				(width 0.1)
				(type default)
			)
			(layer "F.Fab")
		)
		(fp_line
			(start -0.67945 0.3048)
			(end -0.67945 -0.305054)
			(stroke
				(width 0.1)
				(type default)
			)
			(layer "F.Fab")
		)
		(fp_line
			(start -0.67945 -0.305054)
			(end -0.12065 -0.305054)
			(stroke
				(width 0.1)
				(type default)
			)
			(layer "F.Fab")
		)
		(pad "1" smd circle
			(at -0.40005 0 180)
			(size 0 0)
			(layers "F.Cu" "F.Mask" "F.Paste")
			(net "SMB_OCP_SFF_3V3AUX_SDA")
		)
		(pad "2" smd circle
			(at 0.40005 0 180)
			(size 0 0)
			(layers "F.Cu" "F.Mask" "F.Paste")
			(net "P3V3_AUX")
		)
	)
	(footprint ""
		(layer "F.Cu")
		(at 117.526816 -256.6543 -90)
		(property "Reference" "C285"
			(at 0 0 270)
			(layer "F.SilkS")
			(hide yes)
			(effects
				(font
					(size 1.27 1.27)
				)
			)
		)
		(property "Value" ""
			(at 0 0 270)
			(layer "F.Fab")
			(effects
				(font
					(size 1.27 1.27)
				)
			)
		)
		(duplicate_pad_numbers_are_jumpers no)
		(fp_line
			(start -0.7874 0.4064)
			(end -0.7874 -0.4064)
			(stroke
				(width 0.1524)
				(type default)
			)
			(layer "F.SilkS")
		)
		(fp_line
			(start 0.7874 0.4064)
			(end -0.7874 0.4064)
			(stroke
				(width 0.1524)
				(type default)
			)
			(layer "F.SilkS")
		)
		(fp_line
			(start -0.7874 -0.4064)
			(end 0.7874 -0.4064)
			(stroke
				(width 0.1524)
				(type default)
			)
			(layer "F.SilkS")
		)
		(fp_line
			(start 0.7874 -0.4064)
			(end 0.7874 0.4064)
			(stroke
				(width 0.1524)
				(type default)
			)
			(layer "F.SilkS")
		)
		(fp_line
			(start -0.67945 0.3048)
			(end -0.67945 -0.305054)
			(stroke
				(width 0.1)
				(type default)
			)
			(layer "F.Fab")
		)
		(fp_line
			(start -0.12065 0.3048)
			(end -0.67945 0.3048)
			(stroke
				(width 0.1)
				(type default)
			)
			(layer "F.Fab")
		)
		(fp_line
			(start 0.120396 0.3048)
			(end 0.120396 0.2794)
			(stroke
				(width 0.1)
				(type default)
			)
			(layer "F.Fab")
		)
		(fp_line
			(start 0.67945 0.3048)
			(end 0.120396 0.3048)
			(stroke
				(width 0.1)
				(type default)
			)
			(layer "F.Fab")
		)
		(fp_line
			(start -0.12065 0.2794)
			(end -0.12065 0.3048)
			(stroke
				(width 0.1)
				(type default)
			)
			(layer "F.Fab")
		)
		(fp_line
			(start 0.120396 0.2794)
			(end -0.12065 0.2794)
			(stroke
				(width 0.1)
				(type default)
			)
			(layer "F.Fab")
		)
		(fp_line
			(start -0.12065 -0.2794)
			(end 0.12065 -0.2794)
			(stroke
				(width 0.1)
				(type default)
			)
			(layer "F.Fab")
		)
		(fp_line
			(start 0.12065 -0.2794)
			(end 0.12065 -0.3048)
			(stroke
				(width 0.1)
				(type default)
			)
			(layer "F.Fab")
		)
		(fp_line
			(start 0.12065 -0.3048)
			(end 0.67945 -0.3048)
			(stroke
				(width 0.1)
				(type default)
			)
			(layer "F.Fab")
		)
		(fp_line
			(start 0.67945 -0.3048)
			(end 0.67945 0.3048)
			(stroke
				(width 0.1)
				(type default)
			)
			(layer "F.Fab")
		)
		(fp_line
			(start -0.67945 -0.305054)
			(end -0.12065 -0.305054)
			(stroke
				(width 0.1)
				(type default)
			)
			(layer "F.Fab")
		)
		(fp_line
			(start -0.12065 -0.305054)
			(end -0.12065 -0.2794)
			(stroke
				(width 0.1)
				(type default)
			)
			(layer "F.Fab")
		)
		(pad "1" smd circle
			(at -0.40005 0 270)
			(size 0 0)
			(layers "F.Cu" "F.Mask" "F.Paste")
			(net "PVCCIN_CPU1")
		)
		(pad "2" smd circle
			(at 0.40005 0 270)
			(size 0 0)
			(layers "F.Cu" "F.Mask" "F.Paste")
			(net "GND")
		)
	)
	(footprint ""
		(layer "F.Cu")
		(at 382.84785 -408.517344 -90)
		(property "Reference" "C877"
			(at 0 0 270)
			(layer "F.SilkS")
			(hide yes)
			(effects
				(font
					(size 1.27 1.27)
				)
			)
		)
		(property "Value" ""
			(at 0 0 270)
			(layer "F.Fab")
			(effects
				(font
					(size 1.27 1.27)
				)
			)
		)
		(duplicate_pad_numbers_are_jumpers no)
		(fp_line
			(start -0.299974 0.150114)
			(end -0.299974 -0.150114)
			(stroke
				(width 0.1)
				(type default)
			)
			(layer "F.Fab")
		)
		(fp_line
			(start 0.299974 0.150114)
			(end -0.299974 0.150114)
			(stroke
				(width 0.1)
				(type default)
			)
			(layer "F.Fab")
		)
		(fp_line
			(start -0.299974 -0.150114)
			(end 0.299974 -0.150114)
			(stroke
				(width 0.1)
				(type default)
			)
			(layer "F.Fab")
		)
		(fp_line
			(start 0.299974 -0.150114)
			(end 0.299974 0.150114)
			(stroke
				(width 0.1)
				(type default)
			)
			(layer "F.Fab")
		)
		(pad "1" smd rect
			(at -0.2667 0 270)
			(size 0.3048 0.381)
			(layers "F.Cu" "F.Mask" "F.Paste")
			(net "P5E_CPU0_PE3_TX_C_DP<12>")
		)
		(pad "2" smd rect
			(at 0.2667 0 270)
			(size 0.3048 0.381)
			(layers "F.Cu" "F.Mask" "F.Paste")
			(net "P5E_CPU0_PE3_TX_DP<12>")
		)
	)
	(footprint ""
		(layer "F.Cu")
		(at 89.535 -32.070548)
		(property "Reference" "U321"
			(at -2.2606 -2.352548 0)
			(unlocked yes)
			(layer "F.SilkS")
			(effects
				(font
					(size 0.7874 0.5842)
					(thickness 0.1524)
				)
				(justify left)
			)
		)
		(property "Value" ""
			(at 0 0 0)
			(layer "F.Fab")
			(effects
				(font
					(size 1.27 1.27)
				)
			)
		)
		(duplicate_pad_numbers_are_jumpers no)
		(fp_line
			(start -2.032 -1.549908)
			(end 2.032 -1.549908)
			(stroke
				(width 0.1524)
				(type default)
			)
			(layer "F.SilkS")
		)
		(fp_line
			(start -2.032 1.549908)
			(end -2.032 -1.549908)
			(stroke
				(width 0.1524)
				(type default)
			)
			(layer "F.SilkS")
		)
		(fp_line
			(start 2.032 -1.549908)
			(end 2.032 1.549908)
			(stroke
				(width 0.1524)
				(type default)
			)
			(layer "F.SilkS")
		)
		(fp_line
			(start 2.032 1.549908)
			(end -2.032 1.549908)
			(stroke
				(width 0.1524)
				(type default)
			)
			(layer "F.SilkS")
		)
		(fp_poly
			(pts
				(xy -2.9464 -1.2192) (xy -2.9464 -0.7112) (xy -2.1844 -0.9652)
			)
			(stroke
				(width 0)
				(type default)
			)
			(fill yes)
			(layer "F.SilkS")
		)
		(fp_line
			(start -0.849884 -1.549908)
			(end -0.849884 1.549908)
			(stroke
				(width 0.1)
				(type default)
			)
			(layer "F.Fab")
		)
		(fp_line
			(start -0.849884 1.549908)
			(end 0.849884 1.549908)
			(stroke
				(width 0.1)
				(type default)
			)
			(layer "F.Fab")
		)
		(fp_line
			(start 0.849884 -1.549908)
			(end -0.849884 -1.549908)
			(stroke
				(width 0.1)
				(type default)
			)
			(layer "F.Fab")
		)
		(fp_line
			(start 0.849884 1.549908)
			(end 0.849884 -1.549908)
			(stroke
				(width 0.1)
				(type default)
			)
			(layer "F.Fab")
		)
		(fp_poly
			(pts
				(xy -2.9464 -1.2192) (xy -2.9464 -0.7112) (xy -2.1844 -0.9652)
			)
			(stroke
				(width 0)
				(type default)
			)
			(fill yes)
			(layer "F.Fab")
		)
		(pad "1" smd rect
			(at -1.225042 -0.94996 270)
			(size 0.4572 1.3208)
			(layers "F.Cu" "F.Mask" "F.Paste")
			(net "CLK_50M_NCSI_OCP_V3_2")
		)
		(pad "2" smd rect
			(at -1.225042 0 270)
			(size 0.4572 1.3208)
			(layers "F.Cu" "F.Mask" "F.Paste")
			(net "CLK_50M_NCSI_OCP_V3_2_ISO_R")
		)
		(pad "3" smd rect
			(at -1.225042 0.94996 270)
			(size 0.4572 1.3208)
			(layers "F.Cu" "F.Mask" "F.Paste")
			(net "GND")
		)
		(pad "4" smd rect
			(at 1.225042 0.94996 270)
			(size 0.4572 1.3208)
			(layers "F.Cu" "F.Mask" "F.Paste")
			(net "FB_BMC_ISOLATE1")
		)
		(pad "5" smd rect
			(at 1.225042 -0.94996 270)
			(size 0.4572 1.3208)
			(layers "F.Cu" "F.Mask" "F.Paste")
			(net "P3V3_AUX")
		)
	)
	(footprint ""
		(layer "F.Cu")
		(at 389.636 -31.841948 180)
		(property "Reference" "R4614"
			(at 0 0 180)
			(layer "F.SilkS")
			(hide yes)
			(effects
				(font
					(size 1.27 1.27)
				)
			)
		)
		(property "Value" ""
			(at 0 0 180)
			(layer "F.Fab")
			(effects
				(font
					(size 1.27 1.27)
				)
			)
		)
		(duplicate_pad_numbers_are_jumpers no)
		(fp_line
			(start 0.7874 0.4064)
			(end -0.7874 0.4064)
			(stroke
				(width 0.1524)
				(type default)
			)
			(layer "F.SilkS")
		)
		(fp_line
			(start 0.7874 -0.4064)
			(end 0.7874 0.4064)
			(stroke
				(width 0.1524)
				(type default)
			)
			(layer "F.SilkS")
		)
		(fp_line
			(start -0.7874 0.4064)
			(end -0.7874 -0.4064)
			(stroke
				(width 0.1524)
				(type default)
			)
			(layer "F.SilkS")
		)
		(fp_line
			(start -0.7874 -0.4064)
			(end 0.7874 -0.4064)
			(stroke
				(width 0.1524)
				(type default)
			)
			(layer "F.SilkS")
		)
		(fp_line
			(start 0.67945 0.3048)
			(end 0.120396 0.3048)
			(stroke
				(width 0.1)
				(type default)
			)
			(layer "F.Fab")
		)
		(fp_line
			(start 0.67945 -0.3048)
			(end 0.67945 0.3048)
			(stroke
				(width 0.1)
				(type default)
			)
			(layer "F.Fab")
		)
		(fp_line
			(start 0.12065 -0.2794)
			(end 0.12065 -0.3048)
			(stroke
				(width 0.1)
				(type default)
			)
			(layer "F.Fab")
		)
		(fp_line
			(start 0.12065 -0.3048)
			(end 0.67945 -0.3048)
			(stroke
				(width 0.1)
				(type default)
			)
			(layer "F.Fab")
		)
		(fp_line
			(start 0.120396 0.3048)
			(end 0.120396 0.2794)
			(stroke
				(width 0.1)
				(type default)
			)
			(layer "F.Fab")
		)
		(fp_line
			(start 0.120396 0.2794)
			(end -0.12065 0.2794)
			(stroke
				(width 0.1)
				(type default)
			)
			(layer "F.Fab")
		)
		(fp_line
			(start -0.12065 0.3048)
			(end -0.67945 0.3048)
			(stroke
				(width 0.1)
				(type default)
			)
			(layer "F.Fab")
		)
		(fp_line
			(start -0.12065 0.2794)
			(end -0.12065 0.3048)
			(stroke
				(width 0.1)
				(type default)
			)
			(layer "F.Fab")
		)
		(fp_line
			(start -0.12065 -0.2794)
			(end 0.12065 -0.2794)
			(stroke
				(width 0.1)
				(type default)
			)
			(layer "F.Fab")
		)
		(fp_line
			(start -0.12065 -0.305054)
			(end -0.12065 -0.2794)
			(stroke
				(width 0.1)
				(type default)
			)
			(layer "F.Fab")
		)
		(fp_line
			(start -0.67945 0.3048)
			(end -0.67945 -0.305054)
			(stroke
				(width 0.1)
				(type default)
			)
			(layer "F.Fab")
		)
		(fp_line
			(start -0.67945 -0.305054)
			(end -0.12065 -0.305054)
			(stroke
				(width 0.1)
				(type default)
			)
			(layer "F.Fab")
		)
		(pad "1" smd circle
			(at -0.40005 0 180)
			(size 0 0)
			(layers "F.Cu" "F.Mask" "F.Paste")
			(net "HP_OCP_V3_1_RST")
		)
		(pad "2" smd circle
			(at 0.40005 0 180)
			(size 0 0)
			(layers "F.Cu" "F.Mask" "F.Paste")
			(net "HP_OCP_V3_1_RST_R")
		)
	)
	(footprint ""
		(layer "F.Cu")
		(at 102.844346 -358.452674 180)
		(property "Reference" "C2447"
			(at 0 0 180)
			(layer "F.SilkS")
			(hide yes)
			(effects
				(font
					(size 1.27 1.27)
				)
			)
		)
		(property "Value" ""
			(at 0 0 180)
			(layer "F.Fab")
			(effects
				(font
					(size 1.27 1.27)
				)
			)
		)
		(duplicate_pad_numbers_are_jumpers no)
		(fp_line
			(start 0.7874 0.4064)
			(end -0.7874 0.4064)
			(stroke
				(width 0.1524)
				(type default)
			)
			(layer "F.SilkS")
		)
		(fp_line
			(start 0.7874 -0.4064)
			(end 0.7874 0.4064)
			(stroke
				(width 0.1524)
				(type default)
			)
			(layer "F.SilkS")
		)
		(fp_line
			(start -0.7874 0.4064)
			(end -0.7874 -0.4064)
			(stroke
				(width 0.1524)
				(type default)
			)
			(layer "F.SilkS")
		)
		(fp_line
			(start -0.7874 -0.4064)
			(end 0.7874 -0.4064)
			(stroke
				(width 0.1524)
				(type default)
			)
			(layer "F.SilkS")
		)
		(fp_line
			(start 0.67945 0.3048)
			(end 0.120396 0.3048)
			(stroke
				(width 0.1)
				(type default)
			)
			(layer "F.Fab")
		)
		(fp_line
			(start 0.67945 -0.3048)
			(end 0.67945 0.3048)
			(stroke
				(width 0.1)
				(type default)
			)
			(layer "F.Fab")
		)
		(fp_line
			(start 0.12065 -0.2794)
			(end 0.12065 -0.3048)
			(stroke
				(width 0.1)
				(type default)
			)
			(layer "F.Fab")
		)
		(fp_line
			(start 0.12065 -0.3048)
			(end 0.67945 -0.3048)
			(stroke
				(width 0.1)
				(type default)
			)
			(layer "F.Fab")
		)
		(fp_line
			(start 0.120396 0.3048)
			(end 0.120396 0.2794)
			(stroke
				(width 0.1)
				(type default)
			)
			(layer "F.Fab")
		)
		(fp_line
			(start 0.120396 0.2794)
			(end -0.12065 0.2794)
			(stroke
				(width 0.1)
				(type default)
			)
			(layer "F.Fab")
		)
		(fp_line
			(start -0.12065 0.3048)
			(end -0.67945 0.3048)
			(stroke
				(width 0.1)
				(type default)
			)
			(layer "F.Fab")
		)
		(fp_line
			(start -0.12065 0.2794)
			(end -0.12065 0.3048)
			(stroke
				(width 0.1)
				(type default)
			)
			(layer "F.Fab")
		)
		(fp_line
			(start -0.12065 -0.2794)
			(end 0.12065 -0.2794)
			(stroke
				(width 0.1)
				(type default)
			)
			(layer "F.Fab")
		)
		(fp_line
			(start -0.12065 -0.305054)
			(end -0.12065 -0.2794)
			(stroke
				(width 0.1)
				(type default)
			)
			(layer "F.Fab")
		)
		(fp_line
			(start -0.67945 0.3048)
			(end -0.67945 -0.305054)
			(stroke
				(width 0.1)
				(type default)
			)
			(layer "F.Fab")
		)
		(fp_line
			(start -0.67945 -0.305054)
			(end -0.12065 -0.305054)
			(stroke
				(width 0.1)
				(type default)
			)
			(layer "F.Fab")
		)
		(pad "1" smd circle
			(at -0.40005 0 180)
			(size 0 0)
			(layers "F.Cu" "F.Mask" "F.Paste")
			(net "PWRGD_PVCCFA_EHV_FIVRA_CPU1_R")
		)
		(pad "2" smd circle
			(at 0.40005 0 180)
			(size 0 0)
			(layers "F.Cu" "F.Mask" "F.Paste")
			(net "GND")
		)
	)
	(footprint ""
		(layer "F.Cu")
		(at 360.444542 -389.19277)
		(property "Reference" "R4169"
			(at 0 0 0)
			(layer "F.SilkS")
			(hide yes)
			(effects
				(font
					(size 1.27 1.27)
				)
			)
		)
		(property "Value" ""
			(at 0 0 0)
			(layer "F.Fab")
			(effects
				(font
					(size 1.27 1.27)
				)
			)
		)
		(duplicate_pad_numbers_are_jumpers no)
		(fp_line
			(start -0.7874 -0.4064)
			(end 0.7874 -0.4064)
			(stroke
				(width 0.1524)
				(type default)
			)
			(layer "F.SilkS")
		)
		(fp_line
			(start -0.7874 0.4064)
			(end -0.7874 -0.4064)
			(stroke
				(width 0.1524)
				(type default)
			)
			(layer "F.SilkS")
		)
		(fp_line
			(start 0.7874 -0.4064)
			(end 0.7874 0.4064)
			(stroke
				(width 0.1524)
				(type default)
			)
			(layer "F.SilkS")
		)
		(fp_line
			(start 0.7874 0.4064)
			(end -0.7874 0.4064)
			(stroke
				(width 0.1524)
				(type default)
			)
			(layer "F.SilkS")
		)
		(fp_line
			(start -0.67945 -0.305054)
			(end -0.12065 -0.305054)
			(stroke
				(width 0.1)
				(type default)
			)
			(layer "F.Fab")
		)
		(fp_line
			(start -0.67945 0.3048)
			(end -0.67945 -0.305054)
			(stroke
				(width 0.1)
				(type default)
			)
			(layer "F.Fab")
		)
		(fp_line
			(start -0.12065 -0.305054)
			(end -0.12065 -0.2794)
			(stroke
				(width 0.1)
				(type default)
			)
			(layer "F.Fab")
		)
		(fp_line
			(start -0.12065 -0.2794)
			(end 0.12065 -0.2794)
			(stroke
				(width 0.1)
				(type default)
			)
			(layer "F.Fab")
		)
		(fp_line
			(start -0.12065 0.2794)
			(end -0.12065 0.3048)
			(stroke
				(width 0.1)
				(type default)
			)
			(layer "F.Fab")
		)
		(fp_line
			(start -0.12065 0.3048)
			(end -0.67945 0.3048)
			(stroke
				(width 0.1)
				(type default)
			)
			(layer "F.Fab")
		)
		(fp_line
			(start 0.120396 0.2794)
			(end -0.12065 0.2794)
			(stroke
				(width 0.1)
				(type default)
			)
			(layer "F.Fab")
		)
		(fp_line
			(start 0.120396 0.3048)
			(end 0.120396 0.2794)
			(stroke
				(width 0.1)
				(type default)
			)
			(layer "F.Fab")
		)
		(fp_line
			(start 0.12065 -0.3048)
			(end 0.67945 -0.3048)
			(stroke
				(width 0.1)
				(type default)
			)
			(layer "F.Fab")
		)
		(fp_line
			(start 0.12065 -0.2794)
			(end 0.12065 -0.3048)
			(stroke
				(width 0.1)
				(type default)
			)
			(layer "F.Fab")
		)
		(fp_line
			(start 0.67945 -0.3048)
			(end 0.67945 0.3048)
			(stroke
				(width 0.1)
				(type default)
			)
			(layer "F.Fab")
		)
		(fp_line
			(start 0.67945 0.3048)
			(end 0.120396 0.3048)
			(stroke
				(width 0.1)
				(type default)
			)
			(layer "F.Fab")
		)
		(pad "1" smd circle
			(at -0.40005 0)
			(size 0 0)
			(layers "F.Cu" "F.Mask" "F.Paste")
			(net "P3V3_AUX")
		)
		(pad "2" smd circle
			(at 0.40005 0)
			(size 0 0)
			(layers "F.Cu" "F.Mask" "F.Paste")
			(net "GPU_3V3IO_RSVD3_ISO")
		)
	)
	(footprint ""
		(layer "F.Cu")
		(at 390.015984 -16.088614 90)
		(property "Reference" "C839"
			(at 0 0 90)
			(layer "F.SilkS")
			(hide yes)
			(effects
				(font
					(size 1.27 1.27)
				)
			)
		)
		(property "Value" ""
			(at 0 0 90)
			(layer "F.Fab")
			(effects
				(font
					(size 1.27 1.27)
				)
			)
		)
		(duplicate_pad_numbers_are_jumpers no)
		(fp_line
			(start 0.299974 -0.150114)
			(end 0.299974 0.150114)
			(stroke
				(width 0.1)
				(type default)
			)
			(layer "F.Fab")
		)
		(fp_line
			(start -0.299974 -0.150114)
			(end 0.299974 -0.150114)
			(stroke
				(width 0.1)
				(type default)
			)
			(layer "F.Fab")
		)
		(fp_line
			(start 0.299974 0.150114)
			(end -0.299974 0.150114)
			(stroke
				(width 0.1)
				(type default)
			)
			(layer "F.Fab")
		)
		(fp_line
			(start -0.299974 0.150114)
			(end -0.299974 -0.150114)
			(stroke
				(width 0.1)
				(type default)
			)
			(layer "F.Fab")
		)
		(pad "1" smd rect
			(at -0.2667 0 90)
			(size 0.3048 0.381)
			(layers "F.Cu" "F.Mask" "F.Paste")
			(net "P5E_CPU0_PE1_TX_C_DP<15>")
		)
		(pad "2" smd rect
			(at 0.2667 0 90)
			(size 0.3048 0.381)
			(layers "F.Cu" "F.Mask" "F.Paste")
			(net "P5E_CPU0_PE1_TX_DP<15>")
		)
	)
	(footprint ""
		(layer "F.Cu")
		(at 251.16409 -48.121062 -90)
		(property "Reference" "PC2206"
			(at 0 0 270)
			(layer "F.SilkS")
			(hide yes)
			(effects
				(font
					(size 1.27 1.27)
				)
			)
		)
		(property "Value" ""
			(at 0 0 270)
			(layer "F.Fab")
			(effects
				(font
					(size 1.27 1.27)
				)
			)
		)
		(duplicate_pad_numbers_are_jumpers no)
		(fp_line
			(start -0.7874 0.4064)
			(end -0.7874 -0.4064)
			(stroke
				(width 0.1524)
				(type default)
			)
			(layer "F.SilkS")
		)
		(fp_line
			(start 0.7874 0.4064)
			(end -0.7874 0.4064)
			(stroke
				(width 0.1524)
				(type default)
			)
			(layer "F.SilkS")
		)
		(fp_line
			(start -0.7874 -0.4064)
			(end 0.7874 -0.4064)
			(stroke
				(width 0.1524)
				(type default)
			)
			(layer "F.SilkS")
		)
		(fp_line
			(start 0.7874 -0.4064)
			(end 0.7874 0.4064)
			(stroke
				(width 0.1524)
				(type default)
			)
			(layer "F.SilkS")
		)
		(fp_line
			(start -0.67945 0.3048)
			(end -0.67945 -0.305054)
			(stroke
				(width 0.1)
				(type default)
			)
			(layer "F.Fab")
		)
		(fp_line
			(start -0.12065 0.3048)
			(end -0.67945 0.3048)
			(stroke
				(width 0.1)
				(type default)
			)
			(layer "F.Fab")
		)
		(fp_line
			(start 0.120396 0.3048)
			(end 0.120396 0.2794)
			(stroke
				(width 0.1)
				(type default)
			)
			(layer "F.Fab")
		)
		(fp_line
			(start 0.67945 0.3048)
			(end 0.120396 0.3048)
			(stroke
				(width 0.1)
				(type default)
			)
			(layer "F.Fab")
		)
		(fp_line
			(start -0.12065 0.2794)
			(end -0.12065 0.3048)
			(stroke
				(width 0.1)
				(type default)
			)
			(layer "F.Fab")
		)
		(fp_line
			(start 0.120396 0.2794)
			(end -0.12065 0.2794)
			(stroke
				(width 0.1)
				(type default)
			)
			(layer "F.Fab")
		)
		(fp_line
			(start -0.12065 -0.2794)
			(end 0.12065 -0.2794)
			(stroke
				(width 0.1)
				(type default)
			)
			(layer "F.Fab")
		)
		(fp_line
			(start 0.12065 -0.2794)
			(end 0.12065 -0.3048)
			(stroke
				(width 0.1)
				(type default)
			)
			(layer "F.Fab")
		)
		(fp_line
			(start 0.12065 -0.3048)
			(end 0.67945 -0.3048)
			(stroke
				(width 0.1)
				(type default)
			)
			(layer "F.Fab")
		)
		(fp_line
			(start 0.67945 -0.3048)
			(end 0.67945 0.3048)
			(stroke
				(width 0.1)
				(type default)
			)
			(layer "F.Fab")
		)
		(fp_line
			(start -0.67945 -0.305054)
			(end -0.12065 -0.305054)
			(stroke
				(width 0.1)
				(type default)
			)
			(layer "F.Fab")
		)
		(fp_line
			(start -0.12065 -0.305054)
			(end -0.12065 -0.2794)
			(stroke
				(width 0.1)
				(type default)
			)
			(layer "F.Fab")
		)
		(pad "1" smd circle
			(at -0.40005 0 270)
			(size 0 0)
			(layers "F.Cu" "F.Mask" "F.Paste")
			(net "P12V_E1S_0")
		)
		(pad "2" smd circle
			(at 0.40005 0 270)
			(size 0 0)
			(layers "F.Cu" "F.Mask" "F.Paste")
			(net "GND")
		)
	)
	(footprint ""
		(layer "F.Cu")
		(at 456.927204 -70.255384 -90)
		(property "Reference" "PC2342"
			(at 0 0 270)
			(layer "F.SilkS")
			(hide yes)
			(effects
				(font
					(size 1.27 1.27)
				)
			)
		)
		(property "Value" ""
			(at 0 0 270)
			(layer "F.Fab")
			(effects
				(font
					(size 1.27 1.27)
				)
			)
		)
		(duplicate_pad_numbers_are_jumpers no)
		(fp_line
			(start -1.524 0.762)
			(end -1.524 -0.762)
			(stroke
				(width 0.1524)
				(type default)
			)
			(layer "F.SilkS")
		)
		(fp_line
			(start 1.524 0.762)
			(end -1.524 0.762)
			(stroke
				(width 0.1524)
				(type default)
			)
			(layer "F.SilkS")
		)
		(fp_line
			(start -1.524 -0.762)
			(end 1.524 -0.762)
			(stroke
				(width 0.1524)
				(type default)
			)
			(layer "F.SilkS")
		)
		(fp_line
			(start 1.524 -0.762)
			(end 1.524 0.762)
			(stroke
				(width 0.1524)
				(type default)
			)
			(layer "F.SilkS")
		)
		(fp_line
			(start -1.1049 0.724916)
			(end 1.1049 0.724916)
			(stroke
				(width 0.1)
				(type default)
			)
			(layer "F.Fab")
		)
		(fp_line
			(start 1.1049 0.724916)
			(end 1.1049 -0.724916)
			(stroke
				(width 0.1)
				(type default)
			)
			(layer "F.Fab")
		)
		(fp_line
			(start -1.1049 -0.724916)
			(end -1.1049 0.724916)
			(stroke
				(width 0.1)
				(type default)
			)
			(layer "F.Fab")
		)
		(fp_line
			(start 1.1049 -0.724916)
			(end -1.1049 -0.724916)
			(stroke
				(width 0.1)
				(type default)
			)
			(layer "F.Fab")
		)
		(pad "1" smd rect
			(at -0.889 0 90)
			(size 1.016 1.27)
			(layers "F.Cu" "F.Mask" "F.Paste")
			(net "SW_P3V3_AUX_FLT")
		)
		(pad "2" smd rect
			(at 0.889 0 90)
			(size 1.016 1.27)
			(layers "F.Cu" "F.Mask" "F.Paste")
			(net "GND")
		)
	)
	(footprint ""
		(layer "F.Cu")
		(at 382.168908 -75.376278 90)
		(property "Reference" "PC1235"
			(at 0 0 90)
			(layer "F.SilkS")
			(hide yes)
			(effects
				(font
					(size 1.27 1.27)
				)
			)
		)
		(property "Value" ""
			(at 0 0 90)
			(layer "F.Fab")
			(effects
				(font
					(size 1.27 1.27)
				)
			)
		)
		(duplicate_pad_numbers_are_jumpers no)
		(fp_line
			(start 0.7874 -0.4064)
			(end 0.7874 0.4064)
			(stroke
				(width 0.1524)
				(type default)
			)
			(layer "F.SilkS")
		)
		(fp_line
			(start -0.7874 -0.4064)
			(end 0.7874 -0.4064)
			(stroke
				(width 0.1524)
				(type default)
			)
			(layer "F.SilkS")
		)
		(fp_line
			(start 0.7874 0.4064)
			(end -0.7874 0.4064)
			(stroke
				(width 0.1524)
				(type default)
			)
			(layer "F.SilkS")
		)
		(fp_line
			(start -0.7874 0.4064)
			(end -0.7874 -0.4064)
			(stroke
				(width 0.1524)
				(type default)
			)
			(layer "F.SilkS")
		)
		(fp_line
			(start -0.12065 -0.305054)
			(end -0.12065 -0.2794)
			(stroke
				(width 0.1)
				(type default)
			)
			(layer "F.Fab")
		)
		(fp_line
			(start -0.67945 -0.305054)
			(end -0.12065 -0.305054)
			(stroke
				(width 0.1)
				(type default)
			)
			(layer "F.Fab")
		)
		(fp_line
			(start 0.67945 -0.3048)
			(end 0.67945 0.3048)
			(stroke
				(width 0.1)
				(type default)
			)
			(layer "F.Fab")
		)
		(fp_line
			(start 0.12065 -0.3048)
			(end 0.67945 -0.3048)
			(stroke
				(width 0.1)
				(type default)
			)
			(layer "F.Fab")
		)
		(fp_line
			(start 0.12065 -0.2794)
			(end 0.12065 -0.3048)
			(stroke
				(width 0.1)
				(type default)
			)
			(layer "F.Fab")
		)
		(fp_line
			(start -0.12065 -0.2794)
			(end 0.12065 -0.2794)
			(stroke
				(width 0.1)
				(type default)
			)
			(layer "F.Fab")
		)
		(fp_line
			(start 0.120396 0.2794)
			(end -0.12065 0.2794)
			(stroke
				(width 0.1)
				(type default)
			)
			(layer "F.Fab")
		)
		(fp_line
			(start -0.12065 0.2794)
			(end -0.12065 0.3048)
			(stroke
				(width 0.1)
				(type default)
			)
			(layer "F.Fab")
		)
		(fp_line
			(start 0.67945 0.3048)
			(end 0.120396 0.3048)
			(stroke
				(width 0.1)
				(type default)
			)
			(layer "F.Fab")
		)
		(fp_line
			(start 0.120396 0.3048)
			(end 0.120396 0.2794)
			(stroke
				(width 0.1)
				(type default)
			)
			(layer "F.Fab")
		)
		(fp_line
			(start -0.12065 0.3048)
			(end -0.67945 0.3048)
			(stroke
				(width 0.1)
				(type default)
			)
			(layer "F.Fab")
		)
		(fp_line
			(start -0.67945 0.3048)
			(end -0.67945 -0.305054)
			(stroke
				(width 0.1)
				(type default)
			)
			(layer "F.Fab")
		)
		(pad "1" smd circle
			(at -0.40005 0 90)
			(size 0 0)
			(layers "F.Cu" "F.Mask" "F.Paste")
			(net "SW_P1V8_PCH_AUX_BST")
		)
		(pad "2" smd circle
			(at 0.40005 0 90)
			(size 0 0)
			(layers "F.Cu" "F.Mask" "F.Paste")
			(net "SW_P1V8_PCH_AUX_SW")
		)
	)
	(footprint ""
		(layer "F.Cu")
		(at 194.346322 -79.057246)
		(property "Reference" "C640"
			(at 0 0 0)
			(layer "F.SilkS")
			(hide yes)
			(effects
				(font
					(size 1.27 1.27)
				)
			)
		)
		(property "Value" ""
			(at 0 0 0)
			(layer "F.Fab")
			(effects
				(font
					(size 1.27 1.27)
				)
			)
		)
		(duplicate_pad_numbers_are_jumpers no)
		(fp_line
			(start -0.7874 -0.4064)
			(end 0.7874 -0.4064)
			(stroke
				(width 0.1524)
				(type default)
			)
			(layer "F.SilkS")
		)
		(fp_line
			(start -0.7874 0.4064)
			(end -0.7874 -0.4064)
			(stroke
				(width 0.1524)
				(type default)
			)
			(layer "F.SilkS")
		)
		(fp_line
			(start 0.7874 -0.4064)
			(end 0.7874 0.4064)
			(stroke
				(width 0.1524)
				(type default)
			)
			(layer "F.SilkS")
		)
		(fp_line
			(start 0.7874 0.4064)
			(end -0.7874 0.4064)
			(stroke
				(width 0.1524)
				(type default)
			)
			(layer "F.SilkS")
		)
		(fp_line
			(start -0.67945 -0.305054)
			(end -0.12065 -0.305054)
			(stroke
				(width 0.1)
				(type default)
			)
			(layer "F.Fab")
		)
		(fp_line
			(start -0.67945 0.3048)
			(end -0.67945 -0.305054)
			(stroke
				(width 0.1)
				(type default)
			)
			(layer "F.Fab")
		)
		(fp_line
			(start -0.12065 -0.305054)
			(end -0.12065 -0.2794)
			(stroke
				(width 0.1)
				(type default)
			)
			(layer "F.Fab")
		)
		(fp_line
			(start -0.12065 -0.2794)
			(end 0.12065 -0.2794)
			(stroke
				(width 0.1)
				(type default)
			)
			(layer "F.Fab")
		)
		(fp_line
			(start -0.12065 0.2794)
			(end -0.12065 0.3048)
			(stroke
				(width 0.1)
				(type default)
			)
			(layer "F.Fab")
		)
		(fp_line
			(start -0.12065 0.3048)
			(end -0.67945 0.3048)
			(stroke
				(width 0.1)
				(type default)
			)
			(layer "F.Fab")
		)
		(fp_line
			(start 0.120396 0.2794)
			(end -0.12065 0.2794)
			(stroke
				(width 0.1)
				(type default)
			)
			(layer "F.Fab")
		)
		(fp_line
			(start 0.120396 0.3048)
			(end 0.120396 0.2794)
			(stroke
				(width 0.1)
				(type default)
			)
			(layer "F.Fab")
		)
		(fp_line
			(start 0.12065 -0.3048)
			(end 0.67945 -0.3048)
			(stroke
				(width 0.1)
				(type default)
			)
			(layer "F.Fab")
		)
		(fp_line
			(start 0.12065 -0.2794)
			(end 0.12065 -0.3048)
			(stroke
				(width 0.1)
				(type default)
			)
			(layer "F.Fab")
		)
		(fp_line
			(start 0.67945 -0.3048)
			(end 0.67945 0.3048)
			(stroke
				(width 0.1)
				(type default)
			)
			(layer "F.Fab")
		)
		(fp_line
			(start 0.67945 0.3048)
			(end 0.120396 0.3048)
			(stroke
				(width 0.1)
				(type default)
			)
			(layer "F.Fab")
		)
		(pad "1" smd circle
			(at -0.40005 0)
			(size 0 0)
			(layers "F.Cu" "F.Mask" "F.Paste")
			(net "P3V3_AUX")
		)
		(pad "2" smd circle
			(at 0.40005 0)
			(size 0 0)
			(layers "F.Cu" "F.Mask" "F.Paste")
			(net "GND")
		)
	)
	(footprint ""
		(layer "F.Cu")
		(at 310.937148 -258.091686)
		(property "Reference" "J2"
			(at -3.683 -81.702148 0)
			(unlocked yes)
			(layer "F.SilkS")
			(effects
				(font
					(size 0.7874 0.5842)
					(thickness 0.1524)
				)
				(justify left)
			)
		)
		(property "Value" ""
			(at 0 0 0)
			(layer "F.Fab")
			(effects
				(font
					(size 1.27 1.27)
				)
			)
		)
		(duplicate_pad_numbers_are_jumpers no)
		(fp_line
			(start -3.24993 -81.000092)
			(end -3.24993 81.000092)
			(stroke
				(width 0.1524)
				(type default)
			)
			(layer "F.SilkS")
		)
		(fp_line
			(start -3.24993 81.000092)
			(end 3.24993 81.000092)
			(stroke
				(width 0.1524)
				(type default)
			)
			(layer "F.SilkS")
		)
		(fp_line
			(start 3.24993 -81.000092)
			(end -3.24993 -81.000092)
			(stroke
				(width 0.1524)
				(type default)
			)
			(layer "F.SilkS")
		)
		(fp_line
			(start 3.24993 -72.00011)
			(end -3.24993 -72.00011)
			(stroke
				(width 0.1524)
				(type default)
			)
			(layer "F.SilkS")
		)
		(fp_line
			(start 3.24993 72.00011)
			(end -3.24993 72.00011)
			(stroke
				(width 0.1524)
				(type default)
			)
			(layer "F.SilkS")
		)
		(fp_line
			(start 3.24993 81.000092)
			(end 3.24993 -81.000092)
			(stroke
				(width 0.1524)
				(type default)
			)
			(layer "F.SilkS")
		)
		(fp_poly
			(pts
				(xy -4.253484 -63.815722) (xy -3.356356 -63.367158) (xy -4.253484 -62.918594)
			)
			(stroke
				(width 0)
				(type default)
			)
			(fill yes)
			(layer "F.SilkS")
		)
		(fp_line
			(start -3.24993 -81.000092)
			(end -3.24993 81.000092)
			(stroke
				(width 0.1)
				(type default)
			)
			(layer "F.Fab")
		)
		(fp_line
			(start -3.24993 81.000092)
			(end 3.24993 81.000092)
			(stroke
				(width 0.1)
				(type default)
			)
			(layer "F.Fab")
		)
		(fp_line
			(start 3.24993 -81.000092)
			(end -3.24993 -81.000092)
			(stroke
				(width 0.1)
				(type default)
			)
			(layer "F.Fab")
		)
		(fp_line
			(start 3.24993 -72.00011)
			(end -3.24993 -72.00011)
			(stroke
				(width 0.1)
				(type default)
			)
			(layer "F.Fab")
		)
		(fp_line
			(start 3.24993 -71.000112)
			(end -3.24993 -71.000112)
			(stroke
				(width 0.1)
				(type default)
			)
			(layer "F.Fab")
		)
		(fp_line
			(start 3.24993 71.000112)
			(end -3.24993 71.000112)
			(stroke
				(width 0.1)
				(type default)
			)
			(layer "F.Fab")
		)
		(fp_line
			(start 3.24993 72.00011)
			(end -3.24993 72.00011)
			(stroke
				(width 0.1)
				(type default)
			)
			(layer "F.Fab")
		)
		(fp_line
			(start 3.24993 81.000092)
			(end 3.24993 -81.000092)
			(stroke
				(width 0.1)
				(type default)
			)
			(layer "F.Fab")
		)
		(fp_poly
			(pts
				(xy -4.445 -63.832994) (xy -4.445 -62.816994) (xy -3.429 -63.324994)
			)
			(stroke
				(width 0)
				(type default)
			)
			(fill yes)
			(layer "F.Fab")
		)
		(pad "1" smd rect
			(at -2.050034 -63.324994 270)
			(size 0.519938 1.4986)
			(layers "F.Cu" "F.Mask" "F.Paste")
			(net "P12V_S3_AUX_CPU0_NVDIMM")
		)
		(pad "2" smd rect
			(at -2.050034 -62.47511 270)
			(size 0.519938 1.4986)
			(layers "F.Cu" "F.Mask" "F.Paste")
			(net "TP_CHA_CPU0_DIMM2_FRU_0")
		)
		(pad "3" smd rect
			(at -2.050034 -61.624972 270)
			(size 0.519938 1.4986)
			(layers "F.Cu" "F.Mask" "F.Paste")
			(net "P3V3_AUX")
		)
		(pad "4" smd rect
			(at -2.050034 -60.775088 270)
			(size 0.519938 1.4986)
			(layers "F.Cu" "F.Mask" "F.Paste")
			(net "I3C_SPD_DDRABCD_CPU0_LVC1_SCL_1")
		)
		(pad "5" smd rect
			(at -2.050034 -59.92495 270)
			(size 0.519938 1.4986)
			(layers "F.Cu" "F.Mask" "F.Paste")
			(net "I3C_SPD_DDRABCD_CPU0_LVC1_SDA")
		)
		(pad "6" smd rect
			(at -2.050034 -59.075066 270)
			(size 0.519938 1.4986)
			(layers "F.Cu" "F.Mask" "F.Paste")
			(net "GND")
		)
		(pad "7" smd rect
			(at -2.050034 -58.224928 270)
			(size 0.519938 1.4986)
			(layers "F.Cu" "F.Mask" "F.Paste")
			(net "M_A_CPU0_SA_DQ<0>")
		)
		(pad "8" smd rect
			(at -2.050034 -57.375044 270)
			(size 0.519938 1.4986)
			(layers "F.Cu" "F.Mask" "F.Paste")
			(net "GND")
		)
		(pad "9" smd rect
			(at -2.050034 -56.524906 270)
			(size 0.519938 1.4986)
			(layers "F.Cu" "F.Mask" "F.Paste")
			(net "M_A_CPU0_SA_DQ<1>")
		)
		(pad "10" smd rect
			(at -2.050034 -55.675022 270)
			(size 0.519938 1.4986)
			(layers "F.Cu" "F.Mask" "F.Paste")
			(net "GND")
		)
		(pad "11" smd rect
			(at -2.050034 -54.824884 270)
			(size 0.519938 1.4986)
			(layers "F.Cu" "F.Mask" "F.Paste")
			(net "M_A_CPU0_SA_DQS_DP<0>")
		)
		(pad "12" smd rect
			(at -2.050034 -53.975 270)
			(size 0.519938 1.4986)
			(layers "F.Cu" "F.Mask" "F.Paste")
			(net "M_A_CPU0_SA_DQS_DN<0>")
		)
		(pad "13" smd rect
			(at -2.050034 -53.125116 270)
			(size 0.519938 1.4986)
			(layers "F.Cu" "F.Mask" "F.Paste")
			(net "GND")
		)
		(pad "14" smd rect
			(at -2.050034 -52.274978 270)
			(size 0.519938 1.4986)
			(layers "F.Cu" "F.Mask" "F.Paste")
			(net "M_A_CPU0_SA_DQ<4>")
		)
		(pad "15" smd rect
			(at -2.050034 -51.425094 270)
			(size 0.519938 1.4986)
			(layers "F.Cu" "F.Mask" "F.Paste")
			(net "GND")
		)
		(pad "16" smd rect
			(at -2.050034 -50.574956 270)
			(size 0.519938 1.4986)
			(layers "F.Cu" "F.Mask" "F.Paste")
			(net "M_A_CPU0_SA_DQ<5>")
		)
		(pad "17" smd rect
			(at -2.050034 -49.725072 270)
			(size 0.519938 1.4986)
			(layers "F.Cu" "F.Mask" "F.Paste")
			(net "GND")
		)
		(pad "18" smd rect
			(at -2.050034 -48.874934 270)
			(size 0.519938 1.4986)
			(layers "F.Cu" "F.Mask" "F.Paste")
			(net "M_A_CPU0_SA_DQ<8>")
		)
		(pad "19" smd rect
			(at -2.050034 -48.02505 270)
			(size 0.519938 1.4986)
			(layers "F.Cu" "F.Mask" "F.Paste")
			(net "GND")
		)
		(pad "20" smd rect
			(at -2.050034 -47.174912 270)
			(size 0.519938 1.4986)
			(layers "F.Cu" "F.Mask" "F.Paste")
			(net "M_A_CPU0_SA_DQ<9>")
		)
		(pad "21" smd rect
			(at -2.050034 -46.325028 270)
			(size 0.519938 1.4986)
			(layers "F.Cu" "F.Mask" "F.Paste")
			(net "GND")
		)
		(pad "22" smd rect
			(at -2.050034 -45.47489 270)
			(size 0.519938 1.4986)
			(layers "F.Cu" "F.Mask" "F.Paste")
			(net "M_A_CPU0_SA_DQS_DP<1>")
		)
		(pad "23" smd rect
			(at -2.050034 -44.625006 270)
			(size 0.519938 1.4986)
			(layers "F.Cu" "F.Mask" "F.Paste")
			(net "M_A_CPU0_SA_DQS_DN<1>")
		)
		(pad "24" smd rect
			(at -2.050034 -43.775122 270)
			(size 0.519938 1.4986)
			(layers "F.Cu" "F.Mask" "F.Paste")
			(net "GND")
		)
		(pad "25" smd rect
			(at -2.050034 -42.924984 270)
			(size 0.519938 1.4986)
			(layers "F.Cu" "F.Mask" "F.Paste")
			(net "M_A_CPU0_SA_DQ<12>")
		)
		(pad "26" smd rect
			(at -2.050034 -42.0751 270)
			(size 0.519938 1.4986)
			(layers "F.Cu" "F.Mask" "F.Paste")
			(net "GND")
		)
		(pad "27" smd rect
			(at -2.050034 -41.224962 270)
			(size 0.519938 1.4986)
			(layers "F.Cu" "F.Mask" "F.Paste")
			(net "M_A_CPU0_SA_DQ<13>")
		)
		(pad "28" smd rect
			(at -2.050034 -40.375078 270)
			(size 0.519938 1.4986)
			(layers "F.Cu" "F.Mask" "F.Paste")
			(net "GND")
		)
		(pad "29" smd rect
			(at -2.050034 -39.52494 270)
			(size 0.519938 1.4986)
			(layers "F.Cu" "F.Mask" "F.Paste")
			(net "M_A_CPU0_SA_DQ<16>")
		)
		(pad "30" smd rect
			(at -2.050034 -38.675056 270)
			(size 0.519938 1.4986)
			(layers "F.Cu" "F.Mask" "F.Paste")
			(net "GND")
		)
		(pad "31" smd rect
			(at -2.050034 -37.824918 270)
			(size 0.519938 1.4986)
			(layers "F.Cu" "F.Mask" "F.Paste")
			(net "M_A_CPU0_SA_DQ<17>")
		)
		(pad "32" smd rect
			(at -2.050034 -36.975034 270)
			(size 0.519938 1.4986)
			(layers "F.Cu" "F.Mask" "F.Paste")
			(net "GND")
		)
		(pad "33" smd rect
			(at -2.050034 -36.124896 270)
			(size 0.519938 1.4986)
			(layers "F.Cu" "F.Mask" "F.Paste")
			(net "M_A_CPU0_SA_DQS_DP<2>")
		)
		(pad "34" smd rect
			(at -2.050034 -35.275012 270)
			(size 0.519938 1.4986)
			(layers "F.Cu" "F.Mask" "F.Paste")
			(net "M_A_CPU0_SA_DQS_DN<2>")
		)
		(pad "35" smd rect
			(at -2.050034 -34.425128 270)
			(size 0.519938 1.4986)
			(layers "F.Cu" "F.Mask" "F.Paste")
			(net "GND")
		)
		(pad "36" smd rect
			(at -2.050034 -33.57499 270)
			(size 0.519938 1.4986)
			(layers "F.Cu" "F.Mask" "F.Paste")
			(net "M_A_CPU0_SA_DQ<20>")
		)
		(pad "37" smd rect
			(at -2.050034 -32.725106 270)
			(size 0.519938 1.4986)
			(layers "F.Cu" "F.Mask" "F.Paste")
			(net "GND")
		)
		(pad "38" smd rect
			(at -2.050034 -31.874968 270)
			(size 0.519938 1.4986)
			(layers "F.Cu" "F.Mask" "F.Paste")
			(net "M_A_CPU0_SA_DQ<21>")
		)
		(pad "39" smd rect
			(at -2.050034 -31.025084 270)
			(size 0.519938 1.4986)
			(layers "F.Cu" "F.Mask" "F.Paste")
			(net "GND")
		)
		(pad "40" smd rect
			(at -2.050034 -30.174946 270)
			(size 0.519938 1.4986)
			(layers "F.Cu" "F.Mask" "F.Paste")
			(net "M_A_CPU0_SA_DQ<24>")
		)
		(pad "41" smd rect
			(at -2.050034 -29.325062 270)
			(size 0.519938 1.4986)
			(layers "F.Cu" "F.Mask" "F.Paste")
			(net "GND")
		)
		(pad "42" smd rect
			(at -2.050034 -28.474924 270)
			(size 0.519938 1.4986)
			(layers "F.Cu" "F.Mask" "F.Paste")
			(net "M_A_CPU0_SA_DQ<25>")
		)
		(pad "43" smd rect
			(at -2.050034 -27.62504 270)
			(size 0.519938 1.4986)
			(layers "F.Cu" "F.Mask" "F.Paste")
			(net "GND")
		)
		(pad "44" smd rect
			(at -2.050034 -26.774902 270)
			(size 0.519938 1.4986)
			(layers "F.Cu" "F.Mask" "F.Paste")
			(net "M_A_CPU0_SA_DQS_DP<3>")
		)
		(pad "45" smd rect
			(at -2.050034 -25.925018 270)
			(size 0.519938 1.4986)
			(layers "F.Cu" "F.Mask" "F.Paste")
			(net "M_A_CPU0_SA_DQS_DN<3>")
		)
		(pad "46" smd rect
			(at -2.050034 -25.07488 270)
			(size 0.519938 1.4986)
			(layers "F.Cu" "F.Mask" "F.Paste")
			(net "GND")
		)
		(pad "47" smd rect
			(at -2.050034 -24.224996 270)
			(size 0.519938 1.4986)
			(layers "F.Cu" "F.Mask" "F.Paste")
			(net "M_A_CPU0_SA_DQ<28>")
		)
		(pad "48" smd rect
			(at -2.050034 -23.375112 270)
			(size 0.519938 1.4986)
			(layers "F.Cu" "F.Mask" "F.Paste")
			(net "GND")
		)
		(pad "49" smd rect
			(at -2.050034 -22.524974 270)
			(size 0.519938 1.4986)
			(layers "F.Cu" "F.Mask" "F.Paste")
			(net "M_A_CPU0_SA_DQ<29>")
		)
		(pad "50" smd rect
			(at -2.050034 -21.67509 270)
			(size 0.519938 1.4986)
			(layers "F.Cu" "F.Mask" "F.Paste")
			(net "GND")
		)
		(pad "51" smd rect
			(at -2.050034 -20.824952 270)
			(size 0.519938 1.4986)
			(layers "F.Cu" "F.Mask" "F.Paste")
			(net "M_A_CPU0_SA_CB<0>")
		)
		(pad "52" smd rect
			(at -2.050034 -19.975068 270)
			(size 0.519938 1.4986)
			(layers "F.Cu" "F.Mask" "F.Paste")
			(net "GND")
		)
		(pad "53" smd rect
			(at -2.050034 -19.12493 270)
			(size 0.519938 1.4986)
			(layers "F.Cu" "F.Mask" "F.Paste")
			(net "M_A_CPU0_SA_CB<1>")
		)
		(pad "54" smd rect
			(at -2.050034 -18.275046 270)
			(size 0.519938 1.4986)
			(layers "F.Cu" "F.Mask" "F.Paste")
			(net "GND")
		)
		(pad "55" smd rect
			(at -2.050034 -17.424908 270)
			(size 0.519938 1.4986)
			(layers "F.Cu" "F.Mask" "F.Paste")
			(net "M_A_CPU0_SA_DQS_DP<4>")
		)
		(pad "56" smd rect
			(at -2.050034 -16.575024 270)
			(size 0.519938 1.4986)
			(layers "F.Cu" "F.Mask" "F.Paste")
			(net "M_A_CPU0_SA_DQS_DN<4>")
		)
		(pad "57" smd rect
			(at -2.050034 -15.724886 270)
			(size 0.519938 1.4986)
			(layers "F.Cu" "F.Mask" "F.Paste")
			(net "GND")
		)
		(pad "58" smd rect
			(at -2.050034 -14.875002 270)
			(size 0.519938 1.4986)
			(layers "F.Cu" "F.Mask" "F.Paste")
			(net "M_A_CPU0_SA_CB<4>")
		)
		(pad "59" smd rect
			(at -2.050034 -14.025118 270)
			(size 0.519938 1.4986)
			(layers "F.Cu" "F.Mask" "F.Paste")
			(net "GND")
		)
		(pad "60" smd rect
			(at -2.050034 -13.17498 270)
			(size 0.519938 1.4986)
			(layers "F.Cu" "F.Mask" "F.Paste")
			(net "M_A_CPU0_SA_CB<5>")
		)
		(pad "61" smd rect
			(at -2.050034 -12.325096 270)
			(size 0.519938 1.4986)
			(layers "F.Cu" "F.Mask" "F.Paste")
			(net "GND")
		)
		(pad "62" smd rect
			(at -2.050034 -11.474958 270)
			(size 0.519938 1.4986)
			(layers "F.Cu" "F.Mask" "F.Paste")
			(net "M_A_CPU0_ALERT_N")
		)
		(pad "63" smd rect
			(at -2.050034 -10.625074 270)
			(size 0.519938 1.4986)
			(layers "F.Cu" "F.Mask" "F.Paste")
			(net "GND")
		)
		(pad "64" smd rect
			(at -2.050034 -9.774936 270)
			(size 0.519938 1.4986)
			(layers "F.Cu" "F.Mask" "F.Paste")
			(net "M_A_CPU0_SA_CS_N<2>")
		)
		(pad "65" smd rect
			(at -2.050034 -8.925052 270)
			(size 0.519938 1.4986)
			(layers "F.Cu" "F.Mask" "F.Paste")
			(net "GND")
		)
		(pad "66" smd rect
			(at -2.050034 -8.074914 270)
			(size 0.519938 1.4986)
			(layers "F.Cu" "F.Mask" "F.Paste")
			(net "M_A_CPU0_SA_CA<0>")
		)
		(pad "67" smd rect
			(at -2.050034 -7.22503 270)
			(size 0.519938 1.4986)
			(layers "F.Cu" "F.Mask" "F.Paste")
			(net "GND")
		)
		(pad "68" smd rect
			(at -2.050034 -6.374892 270)
			(size 0.519938 1.4986)
			(layers "F.Cu" "F.Mask" "F.Paste")
			(net "M_A_CPU0_SA_CA<2>")
		)
		(pad "69" smd rect
			(at -2.050034 -5.525008 270)
			(size 0.519938 1.4986)
			(layers "F.Cu" "F.Mask" "F.Paste")
			(net "GND")
		)
		(pad "70" smd rect
			(at -2.050034 -4.675124 270)
			(size 0.519938 1.4986)
			(layers "F.Cu" "F.Mask" "F.Paste")
			(net "M_A_CPU0_SA_CA<4>")
		)
		(pad "71" smd rect
			(at -2.050034 -3.824986 270)
			(size 0.519938 1.4986)
			(layers "F.Cu" "F.Mask" "F.Paste")
			(net "GND")
		)
		(pad "72" smd rect
			(at -2.050034 -2.975102 270)
			(size 0.519938 1.4986)
			(layers "F.Cu" "F.Mask" "F.Paste")
			(net "M_A_CPU0_SA_CA<6>")
		)
		(pad "73" smd rect
			(at -2.050034 -2.124964 270)
			(size 0.519938 1.4986)
			(layers "F.Cu" "F.Mask" "F.Paste")
			(net "GND")
		)
		(pad "74" smd rect
			(at -2.050034 -1.27508 270)
			(size 0.519938 1.4986)
			(layers "F.Cu" "F.Mask" "F.Paste")
			(net "M_A_CPU0_SA_PAR")
		)
		(pad "75" smd rect
			(at -2.050034 -0.424942 270)
			(size 0.519938 1.4986)
			(layers "F.Cu" "F.Mask" "F.Paste")
			(net "GND")
		)
		(pad "76" smd rect
			(at -2.050034 5.525008 270)
			(size 0.519938 1.4986)
			(layers "F.Cu" "F.Mask" "F.Paste")
			(net "M_A_CPU0_SB_CA<0>")
		)
		(pad "77" smd rect
			(at -2.050034 6.374892 270)
			(size 0.519938 1.4986)
			(layers "F.Cu" "F.Mask" "F.Paste")
			(net "GND")
		)
		(pad "78" smd rect
			(at -2.050034 7.22503 270)
			(size 0.519938 1.4986)
			(layers "F.Cu" "F.Mask" "F.Paste")
			(net "M_A_CPU0_SB_CA<2>")
		)
		(pad "79" smd rect
			(at -2.050034 8.074914 270)
			(size 0.519938 1.4986)
			(layers "F.Cu" "F.Mask" "F.Paste")
			(net "GND")
		)
		(pad "80" smd rect
			(at -2.050034 8.925052 270)
			(size 0.519938 1.4986)
			(layers "F.Cu" "F.Mask" "F.Paste")
			(net "M_A_CPU0_SB_CA<4>")
		)
		(pad "81" smd rect
			(at -2.050034 9.774936 270)
			(size 0.519938 1.4986)
			(layers "F.Cu" "F.Mask" "F.Paste")
			(net "GND")
		)
		(pad "82" smd rect
			(at -2.050034 10.625074 270)
			(size 0.519938 1.4986)
			(layers "F.Cu" "F.Mask" "F.Paste")
			(net "M_A_CPU0_SB_CA<6>")
		)
		(pad "83" smd rect
			(at -2.050034 11.474958 270)
			(size 0.519938 1.4986)
			(layers "F.Cu" "F.Mask" "F.Paste")
			(net "GND")
		)
		(pad "84" smd rect
			(at -2.050034 12.325096 270)
			(size 0.519938 1.4986)
			(layers "F.Cu" "F.Mask" "F.Paste")
			(net "M_A_CPU0_SB_CS_N<2>")
		)
		(pad "85" smd rect
			(at -2.050034 13.17498 270)
			(size 0.519938 1.4986)
			(layers "F.Cu" "F.Mask" "F.Paste")
			(net "GND")
		)
		(pad "86" smd rect
			(at -2.050034 14.025118 270)
			(size 0.519938 1.4986)
			(layers "F.Cu" "F.Mask" "F.Paste")
			(net "M_A_CPU0_SA_RSP<1>")
		)
		(pad "87" smd rect
			(at -2.050034 14.875002 270)
			(size 0.519938 1.4986)
			(layers "F.Cu" "F.Mask" "F.Paste")
			(net "M_A_CPU0_SB_RSP<1>")
		)
		(pad "88" smd rect
			(at -2.050034 15.724886 270)
			(size 0.519938 1.4986)
			(layers "F.Cu" "F.Mask" "F.Paste")
			(net "GND")
		)
		(pad "89" smd rect
			(at -2.050034 16.575024 270)
			(size 0.519938 1.4986)
			(layers "F.Cu" "F.Mask" "F.Paste")
			(net "M_A_CPU0_SB_CB<4>")
		)
		(pad "90" smd rect
			(at -2.050034 17.424908 270)
			(size 0.519938 1.4986)
			(layers "F.Cu" "F.Mask" "F.Paste")
			(net "GND")
		)
		(pad "91" smd rect
			(at -2.050034 18.275046 270)
			(size 0.519938 1.4986)
			(layers "F.Cu" "F.Mask" "F.Paste")
			(net "M_A_CPU0_SB_CB<5>")
		)
		(pad "92" smd rect
			(at -2.050034 19.12493 270)
			(size 0.519938 1.4986)
			(layers "F.Cu" "F.Mask" "F.Paste")
			(net "GND")
		)
		(pad "93" smd rect
			(at -2.050034 19.975068 270)
			(size 0.519938 1.4986)
			(layers "F.Cu" "F.Mask" "F.Paste")
			(net "M_A_CPU0_SB_DQS_DP<9>")
		)
		(pad "94" smd rect
			(at -2.050034 20.824952 270)
			(size 0.519938 1.4986)
			(layers "F.Cu" "F.Mask" "F.Paste")
			(net "M_A_CPU0_SB_DQS_DN<9>")
		)
		(pad "95" smd rect
			(at -2.050034 21.67509 270)
			(size 0.519938 1.4986)
			(layers "F.Cu" "F.Mask" "F.Paste")
			(net "GND")
		)
		(pad "96" smd rect
			(at -2.050034 22.524974 270)
			(size 0.519938 1.4986)
			(layers "F.Cu" "F.Mask" "F.Paste")
			(net "M_A_CPU0_SB_CB<0>")
		)
		(pad "97" smd rect
			(at -2.050034 23.375112 270)
			(size 0.519938 1.4986)
			(layers "F.Cu" "F.Mask" "F.Paste")
			(net "GND")
		)
		(pad "98" smd rect
			(at -2.050034 24.224996 270)
			(size 0.519938 1.4986)
			(layers "F.Cu" "F.Mask" "F.Paste")
			(net "M_A_CPU0_SB_CB<1>")
		)
		(pad "99" smd rect
			(at -2.050034 25.07488 270)
			(size 0.519938 1.4986)
			(layers "F.Cu" "F.Mask" "F.Paste")
			(net "GND")
		)
		(pad "100" smd rect
			(at -2.050034 25.925018 270)
			(size 0.519938 1.4986)
			(layers "F.Cu" "F.Mask" "F.Paste")
			(net "M_A_CPU0_SB_DQ<0>")
		)
		(pad "101" smd rect
			(at -2.050034 26.774902 270)
			(size 0.519938 1.4986)
			(layers "F.Cu" "F.Mask" "F.Paste")
			(net "GND")
		)
		(pad "102" smd rect
			(at -2.050034 27.62504 270)
			(size 0.519938 1.4986)
			(layers "F.Cu" "F.Mask" "F.Paste")
			(net "M_A_CPU0_SB_DQ<1>")
		)
		(pad "103" smd rect
			(at -2.050034 28.474924 270)
			(size 0.519938 1.4986)
			(layers "F.Cu" "F.Mask" "F.Paste")
			(net "GND")
		)
		(pad "104" smd rect
			(at -2.050034 29.325062 270)
			(size 0.519938 1.4986)
			(layers "F.Cu" "F.Mask" "F.Paste")
			(net "M_A_CPU0_SB_DQS_DP<0>")
		)
		(pad "105" smd rect
			(at -2.050034 30.174946 270)
			(size 0.519938 1.4986)
			(layers "F.Cu" "F.Mask" "F.Paste")
			(net "M_A_CPU0_SB_DQS_DN<0>")
		)
		(pad "106" smd rect
			(at -2.050034 31.025084 270)
			(size 0.519938 1.4986)
			(layers "F.Cu" "F.Mask" "F.Paste")
			(net "GND")
		)
		(pad "107" smd rect
			(at -2.050034 31.874968 270)
			(size 0.519938 1.4986)
			(layers "F.Cu" "F.Mask" "F.Paste")
			(net "M_A_CPU0_SB_DQ<4>")
		)
		(pad "108" smd rect
			(at -2.050034 32.725106 270)
			(size 0.519938 1.4986)
			(layers "F.Cu" "F.Mask" "F.Paste")
			(net "GND")
		)
		(pad "109" smd rect
			(at -2.050034 33.57499 270)
			(size 0.519938 1.4986)
			(layers "F.Cu" "F.Mask" "F.Paste")
			(net "M_A_CPU0_SB_DQ<5>")
		)
		(pad "110" smd rect
			(at -2.050034 34.425128 270)
			(size 0.519938 1.4986)
			(layers "F.Cu" "F.Mask" "F.Paste")
			(net "GND")
		)
		(pad "111" smd rect
			(at -2.050034 35.275012 270)
			(size 0.519938 1.4986)
			(layers "F.Cu" "F.Mask" "F.Paste")
			(net "M_A_CPU0_SB_DQ<8>")
		)
		(pad "112" smd rect
			(at -2.050034 36.124896 270)
			(size 0.519938 1.4986)
			(layers "F.Cu" "F.Mask" "F.Paste")
			(net "GND")
		)
		(pad "113" smd rect
			(at -2.050034 36.975034 270)
			(size 0.519938 1.4986)
			(layers "F.Cu" "F.Mask" "F.Paste")
			(net "M_A_CPU0_SB_DQ<9>")
		)
		(pad "114" smd rect
			(at -2.050034 37.824918 270)
			(size 0.519938 1.4986)
			(layers "F.Cu" "F.Mask" "F.Paste")
			(net "GND")
		)
		(pad "115" smd rect
			(at -2.050034 38.675056 270)
			(size 0.519938 1.4986)
			(layers "F.Cu" "F.Mask" "F.Paste")
			(net "M_A_CPU0_SB_DQS_DP<1>")
		)
		(pad "116" smd rect
			(at -2.050034 39.52494 270)
			(size 0.519938 1.4986)
			(layers "F.Cu" "F.Mask" "F.Paste")
			(net "M_A_CPU0_SB_DQS_DN<1>")
		)
		(pad "117" smd rect
			(at -2.050034 40.375078 270)
			(size 0.519938 1.4986)
			(layers "F.Cu" "F.Mask" "F.Paste")
			(net "GND")
		)
		(pad "118" smd rect
			(at -2.050034 41.224962 270)
			(size 0.519938 1.4986)
			(layers "F.Cu" "F.Mask" "F.Paste")
			(net "M_A_CPU0_SB_DQ<12>")
		)
		(pad "119" smd rect
			(at -2.050034 42.0751 270)
			(size 0.519938 1.4986)
			(layers "F.Cu" "F.Mask" "F.Paste")
			(net "GND")
		)
		(pad "120" smd rect
			(at -2.050034 42.924984 270)
			(size 0.519938 1.4986)
			(layers "F.Cu" "F.Mask" "F.Paste")
			(net "M_A_CPU0_SB_DQ<13>")
		)
		(pad "121" smd rect
			(at -2.050034 43.775122 270)
			(size 0.519938 1.4986)
			(layers "F.Cu" "F.Mask" "F.Paste")
			(net "GND")
		)
		(pad "122" smd rect
			(at -2.050034 44.625006 270)
			(size 0.519938 1.4986)
			(layers "F.Cu" "F.Mask" "F.Paste")
			(net "M_A_CPU0_SB_DQ<16>")
		)
		(pad "123" smd rect
			(at -2.050034 45.47489 270)
			(size 0.519938 1.4986)
			(layers "F.Cu" "F.Mask" "F.Paste")
			(net "GND")
		)
		(pad "124" smd rect
			(at -2.050034 46.325028 270)
			(size 0.519938 1.4986)
			(layers "F.Cu" "F.Mask" "F.Paste")
			(net "M_A_CPU0_SB_DQ<17>")
		)
		(pad "125" smd rect
			(at -2.050034 47.174912 270)
			(size 0.519938 1.4986)
			(layers "F.Cu" "F.Mask" "F.Paste")
			(net "GND")
		)
		(pad "126" smd rect
			(at -2.050034 48.02505 270)
			(size 0.519938 1.4986)
			(layers "F.Cu" "F.Mask" "F.Paste")
			(net "M_A_CPU0_SB_DQS_DP<2>")
		)
		(pad "127" smd rect
			(at -2.050034 48.874934 270)
			(size 0.519938 1.4986)
			(layers "F.Cu" "F.Mask" "F.Paste")
			(net "M_A_CPU0_SB_DQS_DN<2>")
		)
		(pad "128" smd rect
			(at -2.050034 49.725072 270)
			(size 0.519938 1.4986)
			(layers "F.Cu" "F.Mask" "F.Paste")
			(net "GND")
		)
		(pad "129" smd rect
			(at -2.050034 50.574956 270)
			(size 0.519938 1.4986)
			(layers "F.Cu" "F.Mask" "F.Paste")
			(net "M_A_CPU0_SB_DQ<20>")
		)
		(pad "130" smd rect
			(at -2.050034 51.425094 270)
			(size 0.519938 1.4986)
			(layers "F.Cu" "F.Mask" "F.Paste")
			(net "GND")
		)
		(pad "131" smd rect
			(at -2.050034 52.274978 270)
			(size 0.519938 1.4986)
			(layers "F.Cu" "F.Mask" "F.Paste")
			(net "M_A_CPU0_SB_DQ<21>")
		)
		(pad "132" smd rect
			(at -2.050034 53.125116 270)
			(size 0.519938 1.4986)
			(layers "F.Cu" "F.Mask" "F.Paste")
			(net "GND")
		)
		(pad "133" smd rect
			(at -2.050034 53.975 270)
			(size 0.519938 1.4986)
			(layers "F.Cu" "F.Mask" "F.Paste")
			(net "M_A_CPU0_SB_DQ<24>")
		)
		(pad "134" smd rect
			(at -2.050034 54.824884 270)
			(size 0.519938 1.4986)
			(layers "F.Cu" "F.Mask" "F.Paste")
			(net "GND")
		)
		(pad "135" smd rect
			(at -2.050034 55.675022 270)
			(size 0.519938 1.4986)
			(layers "F.Cu" "F.Mask" "F.Paste")
			(net "M_A_CPU0_SB_DQ<25>")
		)
		(pad "136" smd rect
			(at -2.050034 56.524906 270)
			(size 0.519938 1.4986)
			(layers "F.Cu" "F.Mask" "F.Paste")
			(net "GND")
		)
		(pad "137" smd rect
			(at -2.050034 57.375044 270)
			(size 0.519938 1.4986)
			(layers "F.Cu" "F.Mask" "F.Paste")
			(net "M_A_CPU0_SB_DQS_DP<3>")
		)
		(pad "138" smd rect
			(at -2.050034 58.224928 270)
			(size 0.519938 1.4986)
			(layers "F.Cu" "F.Mask" "F.Paste")
			(net "M_A_CPU0_SB_DQS_DN<3>")
		)
		(pad "139" smd rect
			(at -2.050034 59.075066 270)
			(size 0.519938 1.4986)
			(layers "F.Cu" "F.Mask" "F.Paste")
			(net "GND")
		)
		(pad "140" smd rect
			(at -2.050034 59.92495 270)
			(size 0.519938 1.4986)
			(layers "F.Cu" "F.Mask" "F.Paste")
			(net "M_A_CPU0_SB_DQ<28>")
		)
		(pad "141" smd rect
			(at -2.050034 60.775088 270)
			(size 0.519938 1.4986)
			(layers "F.Cu" "F.Mask" "F.Paste")
			(net "GND")
		)
		(pad "142" smd rect
			(at -2.050034 61.624972 270)
			(size 0.519938 1.4986)
			(layers "F.Cu" "F.Mask" "F.Paste")
			(net "M_A_CPU0_SB_DQ<29>")
		)
		(pad "143" smd rect
			(at -2.050034 62.47511 270)
			(size 0.519938 1.4986)
			(layers "F.Cu" "F.Mask" "F.Paste")
			(net "GND")
		)
		(pad "144" smd rect
			(at -2.050034 63.324994 270)
			(size 0.519938 1.4986)
			(layers "F.Cu" "F.Mask" "F.Paste")
			(net "TP_CHA_CPU0_DIMM2_FRU_1")
		)
		(pad "145" smd rect
			(at 2.050034 -63.324994 270)
			(size 0.519938 1.4986)
			(layers "F.Cu" "F.Mask" "F.Paste")
			(net "P12V_S3_AUX_CPU0_NVDIMM")
		)
		(pad "146" smd rect
			(at 2.050034 -62.47511 270)
			(size 0.519938 1.4986)
			(layers "F.Cu" "F.Mask" "F.Paste")
			(net "P12V_S3_AUX_CPU0_NVDIMM")
		)
		(pad "147" smd rect
			(at 2.050034 -61.624972 270)
			(size 0.519938 1.4986)
			(layers "F.Cu" "F.Mask" "F.Paste")
			(net "PWRGD_CHA_CPU0_DIMM2")
		)
		(pad "148" smd rect
			(at 2.050034 -60.775088 270)
			(size 0.519938 1.4986)
			(layers "F.Cu" "F.Mask" "F.Paste")
			(net "PD_CHA_CPU0_DIMM2_SAA")
		)
		(pad "149" smd rect
			(at 2.050034 -59.92495 270)
			(size 0.519938 1.4986)
			(layers "F.Cu" "F.Mask" "F.Paste")
			(net "TP_CHA_CPU0_DIMM2_FRU_2")
		)
		(pad "150" smd rect
			(at 2.050034 -59.075066 270)
			(size 0.519938 1.4986)
			(layers "F.Cu" "F.Mask" "F.Paste")
			(net "TP_CHA_CPU0_DIMM2_FRU_3")
		)
		(pad "151" smd rect
			(at 2.050034 -58.224928 270)
			(size 0.519938 1.4986)
			(layers "F.Cu" "F.Mask" "F.Paste")
			(net "GND")
		)
		(pad "152" smd rect
			(at 2.050034 -57.375044 270)
			(size 0.519938 1.4986)
			(layers "F.Cu" "F.Mask" "F.Paste")
			(net "M_A_CPU0_SA_DQ<2>")
		)
		(pad "153" smd rect
			(at 2.050034 -56.524906 270)
			(size 0.519938 1.4986)
			(layers "F.Cu" "F.Mask" "F.Paste")
			(net "GND")
		)
		(pad "154" smd rect
			(at 2.050034 -55.675022 270)
			(size 0.519938 1.4986)
			(layers "F.Cu" "F.Mask" "F.Paste")
			(net "M_A_CPU0_SA_DQ<3>")
		)
		(pad "155" smd rect
			(at 2.050034 -54.824884 270)
			(size 0.519938 1.4986)
			(layers "F.Cu" "F.Mask" "F.Paste")
			(net "GND")
		)
		(pad "156" smd rect
			(at 2.050034 -53.975 270)
			(size 0.519938 1.4986)
			(layers "F.Cu" "F.Mask" "F.Paste")
			(net "M_A_CPU0_SA_DQS_DN<5>")
		)
		(pad "157" smd rect
			(at 2.050034 -53.125116 270)
			(size 0.519938 1.4986)
			(layers "F.Cu" "F.Mask" "F.Paste")
			(net "M_A_CPU0_SA_DQS_DP<5>")
		)
		(pad "158" smd rect
			(at 2.050034 -52.274978 270)
			(size 0.519938 1.4986)
			(layers "F.Cu" "F.Mask" "F.Paste")
			(net "GND")
		)
		(pad "159" smd rect
			(at 2.050034 -51.425094 270)
			(size 0.519938 1.4986)
			(layers "F.Cu" "F.Mask" "F.Paste")
			(net "M_A_CPU0_SA_DQ<6>")
		)
		(pad "160" smd rect
			(at 2.050034 -50.574956 270)
			(size 0.519938 1.4986)
			(layers "F.Cu" "F.Mask" "F.Paste")
			(net "GND")
		)
		(pad "161" smd rect
			(at 2.050034 -49.725072 270)
			(size 0.519938 1.4986)
			(layers "F.Cu" "F.Mask" "F.Paste")
			(net "M_A_CPU0_SA_DQ<7>")
		)
		(pad "162" smd rect
			(at 2.050034 -48.874934 270)
			(size 0.519938 1.4986)
			(layers "F.Cu" "F.Mask" "F.Paste")
			(net "GND")
		)
		(pad "163" smd rect
			(at 2.050034 -48.02505 270)
			(size 0.519938 1.4986)
			(layers "F.Cu" "F.Mask" "F.Paste")
			(net "M_A_CPU0_SA_DQ<10>")
		)
		(pad "164" smd rect
			(at 2.050034 -47.174912 270)
			(size 0.519938 1.4986)
			(layers "F.Cu" "F.Mask" "F.Paste")
			(net "GND")
		)
		(pad "165" smd rect
			(at 2.050034 -46.325028 270)
			(size 0.519938 1.4986)
			(layers "F.Cu" "F.Mask" "F.Paste")
			(net "M_A_CPU0_SA_DQ<11>")
		)
		(pad "166" smd rect
			(at 2.050034 -45.47489 270)
			(size 0.519938 1.4986)
			(layers "F.Cu" "F.Mask" "F.Paste")
			(net "GND")
		)
		(pad "167" smd rect
			(at 2.050034 -44.625006 270)
			(size 0.519938 1.4986)
			(layers "F.Cu" "F.Mask" "F.Paste")
			(net "M_A_CPU0_SA_DQS_DN<6>")
		)
		(pad "168" smd rect
			(at 2.050034 -43.775122 270)
			(size 0.519938 1.4986)
			(layers "F.Cu" "F.Mask" "F.Paste")
			(net "M_A_CPU0_SA_DQS_DP<6>")
		)
		(pad "169" smd rect
			(at 2.050034 -42.924984 270)
			(size 0.519938 1.4986)
			(layers "F.Cu" "F.Mask" "F.Paste")
			(net "GND")
		)
		(pad "170" smd rect
			(at 2.050034 -42.0751 270)
			(size 0.519938 1.4986)
			(layers "F.Cu" "F.Mask" "F.Paste")
			(net "M_A_CPU0_SA_DQ<14>")
		)
		(pad "171" smd rect
			(at 2.050034 -41.224962 270)
			(size 0.519938 1.4986)
			(layers "F.Cu" "F.Mask" "F.Paste")
			(net "GND")
		)
		(pad "172" smd rect
			(at 2.050034 -40.375078 270)
			(size 0.519938 1.4986)
			(layers "F.Cu" "F.Mask" "F.Paste")
			(net "M_A_CPU0_SA_DQ<15>")
		)
		(pad "173" smd rect
			(at 2.050034 -39.52494 270)
			(size 0.519938 1.4986)
			(layers "F.Cu" "F.Mask" "F.Paste")
			(net "GND")
		)
		(pad "174" smd rect
			(at 2.050034 -38.675056 270)
			(size 0.519938 1.4986)
			(layers "F.Cu" "F.Mask" "F.Paste")
			(net "M_A_CPU0_SA_DQ<18>")
		)
		(pad "175" smd rect
			(at 2.050034 -37.824918 270)
			(size 0.519938 1.4986)
			(layers "F.Cu" "F.Mask" "F.Paste")
			(net "GND")
		)
		(pad "176" smd rect
			(at 2.050034 -36.975034 270)
			(size 0.519938 1.4986)
			(layers "F.Cu" "F.Mask" "F.Paste")
			(net "M_A_CPU0_SA_DQ<19>")
		)
		(pad "177" smd rect
			(at 2.050034 -36.124896 270)
			(size 0.519938 1.4986)
			(layers "F.Cu" "F.Mask" "F.Paste")
			(net "GND")
		)
		(pad "178" smd rect
			(at 2.050034 -35.275012 270)
			(size 0.519938 1.4986)
			(layers "F.Cu" "F.Mask" "F.Paste")
			(net "M_A_CPU0_SA_DQS_DN<7>")
		)
		(pad "179" smd rect
			(at 2.050034 -34.425128 270)
			(size 0.519938 1.4986)
			(layers "F.Cu" "F.Mask" "F.Paste")
			(net "M_A_CPU0_SA_DQS_DP<7>")
		)
		(pad "180" smd rect
			(at 2.050034 -33.57499 270)
			(size 0.519938 1.4986)
			(layers "F.Cu" "F.Mask" "F.Paste")
			(net "GND")
		)
		(pad "181" smd rect
			(at 2.050034 -32.725106 270)
			(size 0.519938 1.4986)
			(layers "F.Cu" "F.Mask" "F.Paste")
			(net "M_A_CPU0_SA_DQ<22>")
		)
		(pad "182" smd rect
			(at 2.050034 -31.874968 270)
			(size 0.519938 1.4986)
			(layers "F.Cu" "F.Mask" "F.Paste")
			(net "GND")
		)
		(pad "183" smd rect
			(at 2.050034 -31.025084 270)
			(size 0.519938 1.4986)
			(layers "F.Cu" "F.Mask" "F.Paste")
			(net "M_A_CPU0_SA_DQ<23>")
		)
		(pad "184" smd rect
			(at 2.050034 -30.174946 270)
			(size 0.519938 1.4986)
			(layers "F.Cu" "F.Mask" "F.Paste")
			(net "GND")
		)
		(pad "185" smd rect
			(at 2.050034 -29.325062 270)
			(size 0.519938 1.4986)
			(layers "F.Cu" "F.Mask" "F.Paste")
			(net "M_A_CPU0_SA_DQ<26>")
		)
		(pad "186" smd rect
			(at 2.050034 -28.474924 270)
			(size 0.519938 1.4986)
			(layers "F.Cu" "F.Mask" "F.Paste")
			(net "GND")
		)
		(pad "187" smd rect
			(at 2.050034 -27.62504 270)
			(size 0.519938 1.4986)
			(layers "F.Cu" "F.Mask" "F.Paste")
			(net "M_A_CPU0_SA_DQ<27>")
		)
		(pad "188" smd rect
			(at 2.050034 -26.774902 270)
			(size 0.519938 1.4986)
			(layers "F.Cu" "F.Mask" "F.Paste")
			(net "GND")
		)
		(pad "189" smd rect
			(at 2.050034 -25.925018 270)
			(size 0.519938 1.4986)
			(layers "F.Cu" "F.Mask" "F.Paste")
			(net "M_A_CPU0_SA_DQS_DN<8>")
		)
		(pad "190" smd rect
			(at 2.050034 -25.07488 270)
			(size 0.519938 1.4986)
			(layers "F.Cu" "F.Mask" "F.Paste")
			(net "M_A_CPU0_SA_DQS_DP<8>")
		)
		(pad "191" smd rect
			(at 2.050034 -24.224996 270)
			(size 0.519938 1.4986)
			(layers "F.Cu" "F.Mask" "F.Paste")
			(net "GND")
		)
		(pad "192" smd rect
			(at 2.050034 -23.375112 270)
			(size 0.519938 1.4986)
			(layers "F.Cu" "F.Mask" "F.Paste")
			(net "M_A_CPU0_SA_DQ<30>")
		)
		(pad "193" smd rect
			(at 2.050034 -22.524974 270)
			(size 0.519938 1.4986)
			(layers "F.Cu" "F.Mask" "F.Paste")
			(net "GND")
		)
		(pad "194" smd rect
			(at 2.050034 -21.67509 270)
			(size 0.519938 1.4986)
			(layers "F.Cu" "F.Mask" "F.Paste")
			(net "M_A_CPU0_SA_DQ<31>")
		)
		(pad "195" smd rect
			(at 2.050034 -20.824952 270)
			(size 0.519938 1.4986)
			(layers "F.Cu" "F.Mask" "F.Paste")
			(net "GND")
		)
		(pad "196" smd rect
			(at 2.050034 -19.975068 270)
			(size 0.519938 1.4986)
			(layers "F.Cu" "F.Mask" "F.Paste")
			(net "M_A_CPU0_SA_CB<2>")
		)
		(pad "197" smd rect
			(at 2.050034 -19.12493 270)
			(size 0.519938 1.4986)
			(layers "F.Cu" "F.Mask" "F.Paste")
			(net "GND")
		)
		(pad "198" smd rect
			(at 2.050034 -18.275046 270)
			(size 0.519938 1.4986)
			(layers "F.Cu" "F.Mask" "F.Paste")
			(net "M_A_CPU0_SA_CB<3>")
		)
		(pad "199" smd rect
			(at 2.050034 -17.424908 270)
			(size 0.519938 1.4986)
			(layers "F.Cu" "F.Mask" "F.Paste")
			(net "GND")
		)
		(pad "200" smd rect
			(at 2.050034 -16.575024 270)
			(size 0.519938 1.4986)
			(layers "F.Cu" "F.Mask" "F.Paste")
			(net "M_A_CPU0_SA_DQS_DN<9>")
		)
		(pad "201" smd rect
			(at 2.050034 -15.724886 270)
			(size 0.519938 1.4986)
			(layers "F.Cu" "F.Mask" "F.Paste")
			(net "M_A_CPU0_SA_DQS_DP<9>")
		)
		(pad "202" smd rect
			(at 2.050034 -14.875002 270)
			(size 0.519938 1.4986)
			(layers "F.Cu" "F.Mask" "F.Paste")
			(net "GND")
		)
		(pad "203" smd rect
			(at 2.050034 -14.025118 270)
			(size 0.519938 1.4986)
			(layers "F.Cu" "F.Mask" "F.Paste")
			(net "M_A_CPU0_SA_CB<6>")
		)
		(pad "204" smd rect
			(at 2.050034 -13.17498 270)
			(size 0.519938 1.4986)
			(layers "F.Cu" "F.Mask" "F.Paste")
			(net "GND")
		)
		(pad "205" smd rect
			(at 2.050034 -12.325096 270)
			(size 0.519938 1.4986)
			(layers "F.Cu" "F.Mask" "F.Paste")
			(net "M_A_CPU0_SA_CB<7>")
		)
		(pad "206" smd rect
			(at 2.050034 -11.474958 270)
			(size 0.519938 1.4986)
			(layers "F.Cu" "F.Mask" "F.Paste")
			(net "GND")
		)
		(pad "207" smd rect
			(at 2.050034 -10.625074 270)
			(size 0.519938 1.4986)
			(layers "F.Cu" "F.Mask" "F.Paste")
			(net "RST_M_AB_CPU0_FPGA_N")
		)
		(pad "208" smd rect
			(at 2.050034 -9.774936 270)
			(size 0.519938 1.4986)
			(layers "F.Cu" "F.Mask" "F.Paste")
			(net "GND")
		)
		(pad "209" smd rect
			(at 2.050034 -8.925052 270)
			(size 0.519938 1.4986)
			(layers "F.Cu" "F.Mask" "F.Paste")
			(net "M_A_CPU0_SA_CS_N<3>")
		)
		(pad "210" smd rect
			(at 2.050034 -8.074914 270)
			(size 0.519938 1.4986)
			(layers "F.Cu" "F.Mask" "F.Paste")
			(net "GND")
		)
		(pad "211" smd rect
			(at 2.050034 -7.22503 270)
			(size 0.519938 1.4986)
			(layers "F.Cu" "F.Mask" "F.Paste")
			(net "M_A_CPU0_SA_CA<1>")
		)
		(pad "212" smd rect
			(at 2.050034 -6.374892 270)
			(size 0.519938 1.4986)
			(layers "F.Cu" "F.Mask" "F.Paste")
			(net "GND")
		)
		(pad "213" smd rect
			(at 2.050034 -5.525008 270)
			(size 0.519938 1.4986)
			(layers "F.Cu" "F.Mask" "F.Paste")
			(net "M_A_CPU0_SA_CA<3>")
		)
		(pad "214" smd rect
			(at 2.050034 -4.675124 270)
			(size 0.519938 1.4986)
			(layers "F.Cu" "F.Mask" "F.Paste")
			(net "GND")
		)
		(pad "215" smd rect
			(at 2.050034 -3.824986 270)
			(size 0.519938 1.4986)
			(layers "F.Cu" "F.Mask" "F.Paste")
			(net "M_A_CPU0_SA_CA<5>")
		)
		(pad "216" smd rect
			(at 2.050034 -2.975102 270)
			(size 0.519938 1.4986)
			(layers "F.Cu" "F.Mask" "F.Paste")
			(net "GND")
		)
		(pad "217" smd rect
			(at 2.050034 -2.124964 270)
			(size 0.519938 1.4986)
			(layers "F.Cu" "F.Mask" "F.Paste")
			(net "M_A_CPU0_CLK_DP<1>")
		)
		(pad "218" smd rect
			(at 2.050034 -1.27508 270)
			(size 0.519938 1.4986)
			(layers "F.Cu" "F.Mask" "F.Paste")
			(net "M_A_CPU0_CLK_DN<1>")
		)
		(pad "219" smd rect
			(at 2.050034 -0.424942 270)
			(size 0.519938 1.4986)
			(layers "F.Cu" "F.Mask" "F.Paste")
			(net "GND")
		)
		(pad "220" smd rect
			(at 2.050034 5.525008 270)
			(size 0.519938 1.4986)
			(layers "F.Cu" "F.Mask" "F.Paste")
			(net "TP_CHA_CPU0_DIMM2_FRU_4")
		)
		(pad "221" smd rect
			(at 2.050034 6.374892 270)
			(size 0.519938 1.4986)
			(layers "F.Cu" "F.Mask" "F.Paste")
			(net "M_A_CPU0_SB_CA<1>")
		)
		(pad "222" smd rect
			(at 2.050034 7.22503 270)
			(size 0.519938 1.4986)
			(layers "F.Cu" "F.Mask" "F.Paste")
			(net "GND")
		)
		(pad "223" smd rect
			(at 2.050034 8.074914 270)
			(size 0.519938 1.4986)
			(layers "F.Cu" "F.Mask" "F.Paste")
			(net "M_A_CPU0_SB_CA<3>")
		)
		(pad "224" smd rect
			(at 2.050034 8.925052 270)
			(size 0.519938 1.4986)
			(layers "F.Cu" "F.Mask" "F.Paste")
			(net "GND")
		)
		(pad "225" smd rect
			(at 2.050034 9.774936 270)
			(size 0.519938 1.4986)
			(layers "F.Cu" "F.Mask" "F.Paste")
			(net "M_A_CPU0_SB_CA<5>")
		)
		(pad "226" smd rect
			(at 2.050034 10.625074 270)
			(size 0.519938 1.4986)
			(layers "F.Cu" "F.Mask" "F.Paste")
			(net "GND")
		)
		(pad "227" smd rect
			(at 2.050034 11.474958 270)
			(size 0.519938 1.4986)
			(layers "F.Cu" "F.Mask" "F.Paste")
			(net "M_A_CPU0_SB_PAR")
		)
		(pad "228" smd rect
			(at 2.050034 12.325096 270)
			(size 0.519938 1.4986)
			(layers "F.Cu" "F.Mask" "F.Paste")
			(net "GND")
		)
		(pad "229" smd rect
			(at 2.050034 13.17498 270)
			(size 0.519938 1.4986)
			(layers "F.Cu" "F.Mask" "F.Paste")
			(net "M_A_CPU0_SB_CS_N<3>")
		)
		(pad "230" smd rect
			(at 2.050034 14.025118 270)
			(size 0.519938 1.4986)
			(layers "F.Cu" "F.Mask" "F.Paste")
			(net "GND")
		)
		(pad "231" smd rect
			(at 2.050034 14.875002 270)
			(size 0.519938 1.4986)
			(layers "F.Cu" "F.Mask" "F.Paste")
			(net "TP_CHA_CPU0_DIMM2_FRU_5")
		)
		(pad "232" smd rect
			(at 2.050034 15.724886 270)
			(size 0.519938 1.4986)
			(layers "F.Cu" "F.Mask" "F.Paste")
			(net "TP_CHA_CPU0_DIMM2_FRU_6")
		)
		(pad "233" smd rect
			(at 2.050034 16.575024 270)
			(size 0.519938 1.4986)
			(layers "F.Cu" "F.Mask" "F.Paste")
			(net "GND")
		)
		(pad "234" smd rect
			(at 2.050034 17.424908 270)
			(size 0.519938 1.4986)
			(layers "F.Cu" "F.Mask" "F.Paste")
			(net "M_A_CPU0_SB_CB<6>")
		)
		(pad "235" smd rect
			(at 2.050034 18.275046 270)
			(size 0.519938 1.4986)
			(layers "F.Cu" "F.Mask" "F.Paste")
			(net "GND")
		)
		(pad "236" smd rect
			(at 2.050034 19.12493 270)
			(size 0.519938 1.4986)
			(layers "F.Cu" "F.Mask" "F.Paste")
			(net "M_A_CPU0_SB_CB<7>")
		)
		(pad "237" smd rect
			(at 2.050034 19.975068 270)
			(size 0.519938 1.4986)
			(layers "F.Cu" "F.Mask" "F.Paste")
			(net "GND")
		)
		(pad "238" smd rect
			(at 2.050034 20.824952 270)
			(size 0.519938 1.4986)
			(layers "F.Cu" "F.Mask" "F.Paste")
			(net "M_A_CPU0_SB_DQS_DN<4>")
		)
		(pad "239" smd rect
			(at 2.050034 21.67509 270)
			(size 0.519938 1.4986)
			(layers "F.Cu" "F.Mask" "F.Paste")
			(net "M_A_CPU0_SB_DQS_DP<4>")
		)
		(pad "240" smd rect
			(at 2.050034 22.524974 270)
			(size 0.519938 1.4986)
			(layers "F.Cu" "F.Mask" "F.Paste")
			(net "GND")
		)
		(pad "241" smd rect
			(at 2.050034 23.375112 270)
			(size 0.519938 1.4986)
			(layers "F.Cu" "F.Mask" "F.Paste")
			(net "M_A_CPU0_SB_CB<2>")
		)
		(pad "242" smd rect
			(at 2.050034 24.224996 270)
			(size 0.519938 1.4986)
			(layers "F.Cu" "F.Mask" "F.Paste")
			(net "GND")
		)
		(pad "243" smd rect
			(at 2.050034 25.07488 270)
			(size 0.519938 1.4986)
			(layers "F.Cu" "F.Mask" "F.Paste")
			(net "M_A_CPU0_SB_CB<3>")
		)
		(pad "244" smd rect
			(at 2.050034 25.925018 270)
			(size 0.519938 1.4986)
			(layers "F.Cu" "F.Mask" "F.Paste")
			(net "GND")
		)
		(pad "245" smd rect
			(at 2.050034 26.774902 270)
			(size 0.519938 1.4986)
			(layers "F.Cu" "F.Mask" "F.Paste")
			(net "M_A_CPU0_SB_DQ<2>")
		)
		(pad "246" smd rect
			(at 2.050034 27.62504 270)
			(size 0.519938 1.4986)
			(layers "F.Cu" "F.Mask" "F.Paste")
			(net "GND")
		)
		(pad "247" smd rect
			(at 2.050034 28.474924 270)
			(size 0.519938 1.4986)
			(layers "F.Cu" "F.Mask" "F.Paste")
			(net "M_A_CPU0_SB_DQ<3>")
		)
		(pad "248" smd rect
			(at 2.050034 29.325062 270)
			(size 0.519938 1.4986)
			(layers "F.Cu" "F.Mask" "F.Paste")
			(net "GND")
		)
		(pad "249" smd rect
			(at 2.050034 30.174946 270)
			(size 0.519938 1.4986)
			(layers "F.Cu" "F.Mask" "F.Paste")
			(net "M_A_CPU0_SB_DQS_DN<5>")
		)
		(pad "250" smd rect
			(at 2.050034 31.025084 270)
			(size 0.519938 1.4986)
			(layers "F.Cu" "F.Mask" "F.Paste")
			(net "M_A_CPU0_SB_DQS_DP<5>")
		)
		(pad "251" smd rect
			(at 2.050034 31.874968 270)
			(size 0.519938 1.4986)
			(layers "F.Cu" "F.Mask" "F.Paste")
			(net "GND")
		)
		(pad "252" smd rect
			(at 2.050034 32.725106 270)
			(size 0.519938 1.4986)
			(layers "F.Cu" "F.Mask" "F.Paste")
			(net "M_A_CPU0_SB_DQ<6>")
		)
		(pad "253" smd rect
			(at 2.050034 33.57499 270)
			(size 0.519938 1.4986)
			(layers "F.Cu" "F.Mask" "F.Paste")
			(net "GND")
		)
		(pad "254" smd rect
			(at 2.050034 34.425128 270)
			(size 0.519938 1.4986)
			(layers "F.Cu" "F.Mask" "F.Paste")
			(net "M_A_CPU0_SB_DQ<7>")
		)
		(pad "255" smd rect
			(at 2.050034 35.275012 270)
			(size 0.519938 1.4986)
			(layers "F.Cu" "F.Mask" "F.Paste")
			(net "GND")
		)
		(pad "256" smd rect
			(at 2.050034 36.124896 270)
			(size 0.519938 1.4986)
			(layers "F.Cu" "F.Mask" "F.Paste")
			(net "M_A_CPU0_SB_DQ<10>")
		)
		(pad "257" smd rect
			(at 2.050034 36.975034 270)
			(size 0.519938 1.4986)
			(layers "F.Cu" "F.Mask" "F.Paste")
			(net "GND")
		)
		(pad "258" smd rect
			(at 2.050034 37.824918 270)
			(size 0.519938 1.4986)
			(layers "F.Cu" "F.Mask" "F.Paste")
			(net "M_A_CPU0_SB_DQ<11>")
		)
		(pad "259" smd rect
			(at 2.050034 38.675056 270)
			(size 0.519938 1.4986)
			(layers "F.Cu" "F.Mask" "F.Paste")
			(net "GND")
		)
		(pad "260" smd rect
			(at 2.050034 39.52494 270)
			(size 0.519938 1.4986)
			(layers "F.Cu" "F.Mask" "F.Paste")
			(net "M_A_CPU0_SB_DQS_DN<6>")
		)
		(pad "261" smd rect
			(at 2.050034 40.375078 270)
			(size 0.519938 1.4986)
			(layers "F.Cu" "F.Mask" "F.Paste")
			(net "M_A_CPU0_SB_DQS_DP<6>")
		)
		(pad "262" smd rect
			(at 2.050034 41.224962 270)
			(size 0.519938 1.4986)
			(layers "F.Cu" "F.Mask" "F.Paste")
			(net "GND")
		)
		(pad "263" smd rect
			(at 2.050034 42.0751 270)
			(size 0.519938 1.4986)
			(layers "F.Cu" "F.Mask" "F.Paste")
			(net "M_A_CPU0_SB_DQ<14>")
		)
		(pad "264" smd rect
			(at 2.050034 42.924984 270)
			(size 0.519938 1.4986)
			(layers "F.Cu" "F.Mask" "F.Paste")
			(net "GND")
		)
		(pad "265" smd rect
			(at 2.050034 43.775122 270)
			(size 0.519938 1.4986)
			(layers "F.Cu" "F.Mask" "F.Paste")
			(net "M_A_CPU0_SB_DQ<15>")
		)
		(pad "266" smd rect
			(at 2.050034 44.625006 270)
			(size 0.519938 1.4986)
			(layers "F.Cu" "F.Mask" "F.Paste")
			(net "GND")
		)
		(pad "267" smd rect
			(at 2.050034 45.47489 270)
			(size 0.519938 1.4986)
			(layers "F.Cu" "F.Mask" "F.Paste")
			(net "M_A_CPU0_SB_DQ<18>")
		)
		(pad "268" smd rect
			(at 2.050034 46.325028 270)
			(size 0.519938 1.4986)
			(layers "F.Cu" "F.Mask" "F.Paste")
			(net "GND")
		)
		(pad "269" smd rect
			(at 2.050034 47.174912 270)
			(size 0.519938 1.4986)
			(layers "F.Cu" "F.Mask" "F.Paste")
			(net "M_A_CPU0_SB_DQ<19>")
		)
		(pad "270" smd rect
			(at 2.050034 48.02505 270)
			(size 0.519938 1.4986)
			(layers "F.Cu" "F.Mask" "F.Paste")
			(net "GND")
		)
		(pad "271" smd rect
			(at 2.050034 48.874934 270)
			(size 0.519938 1.4986)
			(layers "F.Cu" "F.Mask" "F.Paste")
			(net "M_A_CPU0_SB_DQS_DN<7>")
		)
		(pad "272" smd rect
			(at 2.050034 49.725072 270)
			(size 0.519938 1.4986)
			(layers "F.Cu" "F.Mask" "F.Paste")
			(net "M_A_CPU0_SB_DQS_DP<7>")
		)
		(pad "273" smd rect
			(at 2.050034 50.574956 270)
			(size 0.519938 1.4986)
			(layers "F.Cu" "F.Mask" "F.Paste")
			(net "GND")
		)
		(pad "274" smd rect
			(at 2.050034 51.425094 270)
			(size 0.519938 1.4986)
			(layers "F.Cu" "F.Mask" "F.Paste")
			(net "M_A_CPU0_SB_DQ<22>")
		)
		(pad "275" smd rect
			(at 2.050034 52.274978 270)
			(size 0.519938 1.4986)
			(layers "F.Cu" "F.Mask" "F.Paste")
			(net "GND")
		)
		(pad "276" smd rect
			(at 2.050034 53.125116 270)
			(size 0.519938 1.4986)
			(layers "F.Cu" "F.Mask" "F.Paste")
			(net "M_A_CPU0_SB_DQ<23>")
		)
		(pad "277" smd rect
			(at 2.050034 53.975 270)
			(size 0.519938 1.4986)
			(layers "F.Cu" "F.Mask" "F.Paste")
			(net "GND")
		)
		(pad "278" smd rect
			(at 2.050034 54.824884 270)
			(size 0.519938 1.4986)
			(layers "F.Cu" "F.Mask" "F.Paste")
			(net "M_A_CPU0_SB_DQ<26>")
		)
		(pad "279" smd rect
			(at 2.050034 55.675022 270)
			(size 0.519938 1.4986)
			(layers "F.Cu" "F.Mask" "F.Paste")
			(net "GND")
		)
		(pad "280" smd rect
			(at 2.050034 56.524906 270)
			(size 0.519938 1.4986)
			(layers "F.Cu" "F.Mask" "F.Paste")
			(net "M_A_CPU0_SB_DQ<27>")
		)
		(pad "281" smd rect
			(at 2.050034 57.375044 270)
			(size 0.519938 1.4986)
			(layers "F.Cu" "F.Mask" "F.Paste")
			(net "GND")
		)
		(pad "282" smd rect
			(at 2.050034 58.224928 270)
			(size 0.519938 1.4986)
			(layers "F.Cu" "F.Mask" "F.Paste")
			(net "M_A_CPU0_SB_DQS_DN<8>")
		)
		(pad "283" smd rect
			(at 2.050034 59.075066 270)
			(size 0.519938 1.4986)
			(layers "F.Cu" "F.Mask" "F.Paste")
			(net "M_A_CPU0_SB_DQS_DP<8>")
		)
		(pad "284" smd rect
			(at 2.050034 59.92495 270)
			(size 0.519938 1.4986)
			(layers "F.Cu" "F.Mask" "F.Paste")
			(net "GND")
		)
		(pad "285" smd rect
			(at 2.050034 60.775088 270)
			(size 0.519938 1.4986)
			(layers "F.Cu" "F.Mask" "F.Paste")
			(net "M_A_CPU0_SB_DQ<30>")
		)
		(pad "286" smd rect
			(at 2.050034 61.624972 270)
			(size 0.519938 1.4986)
			(layers "F.Cu" "F.Mask" "F.Paste")
			(net "GND")
		)
		(pad "287" smd rect
			(at 2.050034 62.47511 270)
			(size 0.519938 1.4986)
			(layers "F.Cu" "F.Mask" "F.Paste")
			(net "M_A_CPU0_SB_DQ<31>")
		)
		(pad "288" smd rect
			(at 2.050034 63.324994 270)
			(size 0.519938 1.4986)
			(layers "F.Cu" "F.Mask" "F.Paste")
			(net "GND")
		)
		(pad "G1" thru_hole oval
			(at 0 -68.97497)
			(size 2.8194 1.5748)
			(drill oval 2.4384 1.1938)
			(layers "*.Cu" "*.Mask")
			(remove_unused_layers no)
			(net "GND")
			(clearance 0.127)
			(thermal_gap 0.127)
		)
		(pad "G2" thru_hole oval
			(at 0 3.875024)
			(size 2.8194 1.5748)
			(drill oval 2.4384 1.1938)
			(layers "*.Cu" "*.Mask")
			(remove_unused_layers no)
			(net "GND")
			(clearance 0.127)
			(thermal_gap 0.127)
		)
		(pad "G3" thru_hole oval
			(at 0 68.97497)
			(size 2.8194 1.5748)
			(drill oval 2.4384 1.1938)
			(layers "*.Cu" "*.Mask")
			(remove_unused_layers no)
			(net "GND")
			(clearance 0.127)
			(thermal_gap 0.127)
		)
	)
	(footprint ""
		(layer "F.Cu")
		(at 140.70838 -34.994596 180)
		(property "Reference" "R3306"
			(at 0 0 180)
			(layer "F.SilkS")
			(hide yes)
			(effects
				(font
					(size 1.27 1.27)
				)
			)
		)
		(property "Value" ""
			(at 0 0 180)
			(layer "F.Fab")
			(effects
				(font
					(size 1.27 1.27)
				)
			)
		)
		(duplicate_pad_numbers_are_jumpers no)
		(fp_line
			(start 0.7874 0.4064)
			(end -0.7874 0.4064)
			(stroke
				(width 0.1524)
				(type default)
			)
			(layer "F.SilkS")
		)
		(fp_line
			(start 0.7874 -0.4064)
			(end 0.7874 0.4064)
			(stroke
				(width 0.1524)
				(type default)
			)
			(layer "F.SilkS")
		)
		(fp_line
			(start -0.7874 0.4064)
			(end -0.7874 -0.4064)
			(stroke
				(width 0.1524)
				(type default)
			)
			(layer "F.SilkS")
		)
		(fp_line
			(start -0.7874 -0.4064)
			(end 0.7874 -0.4064)
			(stroke
				(width 0.1524)
				(type default)
			)
			(layer "F.SilkS")
		)
		(fp_line
			(start 0.67945 0.3048)
			(end 0.120396 0.3048)
			(stroke
				(width 0.1)
				(type default)
			)
			(layer "F.Fab")
		)
		(fp_line
			(start 0.67945 -0.3048)
			(end 0.67945 0.3048)
			(stroke
				(width 0.1)
				(type default)
			)
			(layer "F.Fab")
		)
		(fp_line
			(start 0.12065 -0.2794)
			(end 0.12065 -0.3048)
			(stroke
				(width 0.1)
				(type default)
			)
			(layer "F.Fab")
		)
		(fp_line
			(start 0.12065 -0.3048)
			(end 0.67945 -0.3048)
			(stroke
				(width 0.1)
				(type default)
			)
			(layer "F.Fab")
		)
		(fp_line
			(start 0.120396 0.3048)
			(end 0.120396 0.2794)
			(stroke
				(width 0.1)
				(type default)
			)
			(layer "F.Fab")
		)
		(fp_line
			(start 0.120396 0.2794)
			(end -0.12065 0.2794)
			(stroke
				(width 0.1)
				(type default)
			)
			(layer "F.Fab")
		)
		(fp_line
			(start -0.12065 0.3048)
			(end -0.67945 0.3048)
			(stroke
				(width 0.1)
				(type default)
			)
			(layer "F.Fab")
		)
		(fp_line
			(start -0.12065 0.2794)
			(end -0.12065 0.3048)
			(stroke
				(width 0.1)
				(type default)
			)
			(layer "F.Fab")
		)
		(fp_line
			(start -0.12065 -0.2794)
			(end 0.12065 -0.2794)
			(stroke
				(width 0.1)
				(type default)
			)
			(layer "F.Fab")
		)
		(fp_line
			(start -0.12065 -0.305054)
			(end -0.12065 -0.2794)
			(stroke
				(width 0.1)
				(type default)
			)
			(layer "F.Fab")
		)
		(fp_line
			(start -0.67945 0.3048)
			(end -0.67945 -0.305054)
			(stroke
				(width 0.1)
				(type default)
			)
			(layer "F.Fab")
		)
		(fp_line
			(start -0.67945 -0.305054)
			(end -0.12065 -0.305054)
			(stroke
				(width 0.1)
				(type default)
			)
			(layer "F.Fab")
		)
		(pad "1" smd circle
			(at -0.40005 0 180)
			(size 0 0)
			(layers "F.Cu" "F.Mask" "F.Paste")
			(net "OCP_V3_2_PRSNT_ALL_R_N")
		)
		(pad "2" smd circle
			(at 0.40005 0 180)
			(size 0 0)
			(layers "F.Cu" "F.Mask" "F.Paste")
			(net "OCP_V3_2_PRSNT_ALL_R3_N")
		)
	)
	(footprint ""
		(layer "F.Cu")
		(at 18.640806 -396.010638 90)
		(property "Reference" "C1870"
			(at 0 0 90)
			(layer "F.SilkS")
			(hide yes)
			(effects
				(font
					(size 1.27 1.27)
				)
			)
		)
		(property "Value" ""
			(at 0 0 90)
			(layer "F.Fab")
			(effects
				(font
					(size 1.27 1.27)
				)
			)
		)
		(duplicate_pad_numbers_are_jumpers no)
		(fp_line
			(start 0.7874 -0.4064)
			(end 0.7874 0.4064)
			(stroke
				(width 0.1524)
				(type default)
			)
			(layer "F.SilkS")
		)
		(fp_line
			(start -0.7874 -0.4064)
			(end 0.7874 -0.4064)
			(stroke
				(width 0.1524)
				(type default)
			)
			(layer "F.SilkS")
		)
		(fp_line
			(start 0.003302 0.4064)
			(end -0.7874 0.4064)
			(stroke
				(width 0.1524)
				(type default)
			)
			(layer "F.SilkS")
		)
		(fp_line
			(start 0.6858 -0.3048)
			(end 0.6858 0.3048)
			(stroke
				(width 0.1)
				(type default)
			)
			(layer "F.Fab")
		)
		(fp_line
			(start 0.1016 -0.3048)
			(end 0.6858 -0.3048)
			(stroke
				(width 0.1)
				(type default)
			)
			(layer "F.Fab")
		)
		(fp_line
			(start -0.1016 -0.3048)
			(end -0.1016 -0.2794)
			(stroke
				(width 0.1)
				(type default)
			)
			(layer "F.Fab")
		)
		(fp_line
			(start -0.6858 -0.3048)
			(end -0.1016 -0.3048)
			(stroke
				(width 0.1)
				(type default)
			)
			(layer "F.Fab")
		)
		(fp_line
			(start 0.1016 -0.2794)
			(end 0.1016 -0.3048)
			(stroke
				(width 0.1)
				(type default)
			)
			(layer "F.Fab")
		)
		(fp_line
			(start -0.1016 -0.2794)
			(end 0.1016 -0.2794)
			(stroke
				(width 0.1)
				(type default)
			)
			(layer "F.Fab")
		)
		(fp_line
			(start 0.1016 0.2794)
			(end -0.1016 0.2794)
			(stroke
				(width 0.1)
				(type default)
			)
			(layer "F.Fab")
		)
		(fp_line
			(start -0.1016 0.2794)
			(end -0.1016 0.3048)
			(stroke
				(width 0.1)
				(type default)
			)
			(layer "F.Fab")
		)
		(fp_line
			(start 0.6858 0.3048)
			(end 0.1016 0.3048)
			(stroke
				(width 0.1)
				(type default)
			)
			(layer "F.Fab")
		)
		(fp_line
			(start 0.1016 0.3048)
			(end 0.1016 0.2794)
			(stroke
				(width 0.1)
				(type default)
			)
			(layer "F.Fab")
		)
		(fp_line
			(start -0.1016 0.3048)
			(end -0.6858 0.3048)
			(stroke
				(width 0.1)
				(type default)
			)
			(layer "F.Fab")
		)
		(fp_line
			(start -0.6858 0.3048)
			(end -0.6858 -0.3048)
			(stroke
				(width 0.1)
				(type default)
			)
			(layer "F.Fab")
		)
		(pad "1" smd rect
			(at -0.40005 0 270)
			(size 0.4572 0.508)
			(layers "F.Cu" "F.Mask" "F.Paste")
			(net "P2E_MB_BMC_TX_BUF_DP<0>")
		)
		(pad "2" smd rect
			(at 0.40005 0 270)
			(size 0.4572 0.508)
			(layers "F.Cu" "F.Mask" "F.Paste")
			(net "P2E_MB_BMC_TX_BUF_C_DP<0>")
		)
	)
	(footprint ""
		(layer "F.Cu")
		(at 74.580496 -70.78599)
		(property "Reference" "D67"
			(at -38.897306 50.178462 90)
			(unlocked yes)
			(layer "F.SilkS")
			(effects
				(font
					(size 0.635 0.4064)
					(thickness 0.1524)
				)
				(justify left)
			)
		)
		(property "Value" ""
			(at 0 0 0)
			(layer "F.Fab")
			(effects
				(font
					(size 1.27 1.27)
				)
			)
		)
		(duplicate_pad_numbers_are_jumpers no)
		(fp_line
			(start -0.90678 0.4826)
			(end -0.90678 -0.4699)
			(stroke
				(width 0.1524)
				(type default)
			)
			(layer "F.SilkS")
		)
		(fp_line
			(start -0.89408 -0.4826)
			(end 0.90678 -0.4826)
			(stroke
				(width 0.1524)
				(type default)
			)
			(layer "F.SilkS")
		)
		(fp_line
			(start -0.79248 -0.4826)
			(end 1.03378 -0.4826)
			(stroke
				(width 0.1524)
				(type default)
			)
			(layer "F.SilkS")
		)
		(fp_line
			(start -0.64008 -0.4826)
			(end 1.16078 -0.4826)
			(stroke
				(width 0.1524)
				(type default)
			)
			(layer "F.SilkS")
		)
		(fp_line
			(start 0.90678 -0.4826)
			(end 0.90678 0.4826)
			(stroke
				(width 0.1524)
				(type default)
			)
			(layer "F.SilkS")
		)
		(fp_line
			(start 0.90678 0.4826)
			(end -0.90678 0.4826)
			(stroke
				(width 0.1524)
				(type default)
			)
			(layer "F.SilkS")
		)
		(fp_line
			(start 1.03378 -0.4826)
			(end 1.03378 0.4826)
			(stroke
				(width 0.1524)
				(type default)
			)
			(layer "F.SilkS")
		)
		(fp_line
			(start 1.03378 0.4826)
			(end -0.79248 0.4826)
			(stroke
				(width 0.1524)
				(type default)
			)
			(layer "F.SilkS")
		)
		(fp_line
			(start 1.16078 -0.4826)
			(end 1.16078 0.4826)
			(stroke
				(width 0.1524)
				(type default)
			)
			(layer "F.SilkS")
		)
		(fp_line
			(start 1.16078 0.4826)
			(end -0.64008 0.4826)
			(stroke
				(width 0.1524)
				(type default)
			)
			(layer "F.SilkS")
		)
		(fp_line
			(start -0.499872 -0.249936)
			(end 0.499872 -0.249936)
			(stroke
				(width 0.1)
				(type default)
			)
			(layer "F.Fab")
		)
		(fp_line
			(start -0.499872 0.249936)
			(end -0.499872 -0.249936)
			(stroke
				(width 0.1)
				(type default)
			)
			(layer "F.Fab")
		)
		(fp_line
			(start 0.499872 -0.249936)
			(end 0.499872 0.249936)
			(stroke
				(width 0.1)
				(type default)
			)
			(layer "F.Fab")
		)
		(fp_line
			(start 0.499872 0.249936)
			(end -0.499872 0.249936)
			(stroke
				(width 0.1)
				(type default)
			)
			(layer "F.Fab")
		)
		(pad "A" smd rect
			(at -0.47498 0)
			(size 0.6096 0.7112)
			(layers "F.Cu" "F.Mask" "F.Paste")
			(net "LED_RST_PLD_CPU0_DRAM_EF_N")
		)
		(pad "C" smd rect
			(at 0.47498 0)
			(size 0.6096 0.7112)
			(layers "F.Cu" "F.Mask" "F.Paste")
			(net "LED_RST_PLD_CPU0_DRAM_EF_N_D")
		)
	)
	(footprint ""
		(layer "F.Cu")
		(at 326.311768 -402.371052 -90)
		(property "Reference" "C1565"
			(at 0 0 270)
			(layer "F.SilkS")
			(hide yes)
			(effects
				(font
					(size 1.27 1.27)
				)
			)
		)
		(property "Value" ""
			(at 0 0 270)
			(layer "F.Fab")
			(effects
				(font
					(size 1.27 1.27)
				)
			)
		)
		(duplicate_pad_numbers_are_jumpers no)
		(fp_line
			(start -0.299974 0.150114)
			(end -0.299974 -0.150114)
			(stroke
				(width 0.1)
				(type default)
			)
			(layer "F.Fab")
		)
		(fp_line
			(start 0.299974 0.150114)
			(end -0.299974 0.150114)
			(stroke
				(width 0.1)
				(type default)
			)
			(layer "F.Fab")
		)
		(fp_line
			(start -0.299974 -0.150114)
			(end 0.299974 -0.150114)
			(stroke
				(width 0.1)
				(type default)
			)
			(layer "F.Fab")
		)
		(fp_line
			(start 0.299974 -0.150114)
			(end 0.299974 0.150114)
			(stroke
				(width 0.1)
				(type default)
			)
			(layer "F.Fab")
		)
		(pad "1" smd rect
			(at -0.2667 0 270)
			(size 0.3048 0.381)
			(layers "F.Cu" "F.Mask" "F.Paste")
			(net "P5E_CPU0_PE4_TX_C_DP<7>")
		)
		(pad "2" smd rect
			(at 0.2667 0 270)
			(size 0.3048 0.381)
			(layers "F.Cu" "F.Mask" "F.Paste")
			(net "P5E_CPU0_PE4_TX_DP<7>")
		)
	)
	(footprint ""
		(layer "F.Cu")
		(at 78.160626 -152.226772 180)
		(property "Reference" "R674"
			(at 0 0 180)
			(layer "F.SilkS")
			(hide yes)
			(effects
				(font
					(size 1.27 1.27)
				)
			)
		)
		(property "Value" ""
			(at 0 0 180)
			(layer "F.Fab")
			(effects
				(font
					(size 1.27 1.27)
				)
			)
		)
		(duplicate_pad_numbers_are_jumpers no)
		(fp_line
			(start 0.7874 0.4064)
			(end -0.7874 0.4064)
			(stroke
				(width 0.1524)
				(type default)
			)
			(layer "F.SilkS")
		)
		(fp_line
			(start 0.7874 -0.4064)
			(end 0.7874 0.4064)
			(stroke
				(width 0.1524)
				(type default)
			)
			(layer "F.SilkS")
		)
		(fp_line
			(start -0.7874 0.4064)
			(end -0.7874 -0.4064)
			(stroke
				(width 0.1524)
				(type default)
			)
			(layer "F.SilkS")
		)
		(fp_line
			(start -0.7874 -0.4064)
			(end 0.7874 -0.4064)
			(stroke
				(width 0.1524)
				(type default)
			)
			(layer "F.SilkS")
		)
		(fp_line
			(start 0.67945 0.3048)
			(end 0.120396 0.3048)
			(stroke
				(width 0.1)
				(type default)
			)
			(layer "F.Fab")
		)
		(fp_line
			(start 0.67945 -0.3048)
			(end 0.67945 0.3048)
			(stroke
				(width 0.1)
				(type default)
			)
			(layer "F.Fab")
		)
		(fp_line
			(start 0.12065 -0.2794)
			(end 0.12065 -0.3048)
			(stroke
				(width 0.1)
				(type default)
			)
			(layer "F.Fab")
		)
		(fp_line
			(start 0.12065 -0.3048)
			(end 0.67945 -0.3048)
			(stroke
				(width 0.1)
				(type default)
			)
			(layer "F.Fab")
		)
		(fp_line
			(start 0.120396 0.3048)
			(end 0.120396 0.2794)
			(stroke
				(width 0.1)
				(type default)
			)
			(layer "F.Fab")
		)
		(fp_line
			(start 0.120396 0.2794)
			(end -0.12065 0.2794)
			(stroke
				(width 0.1)
				(type default)
			)
			(layer "F.Fab")
		)
		(fp_line
			(start -0.12065 0.3048)
			(end -0.67945 0.3048)
			(stroke
				(width 0.1)
				(type default)
			)
			(layer "F.Fab")
		)
		(fp_line
			(start -0.12065 0.2794)
			(end -0.12065 0.3048)
			(stroke
				(width 0.1)
				(type default)
			)
			(layer "F.Fab")
		)
		(fp_line
			(start -0.12065 -0.2794)
			(end 0.12065 -0.2794)
			(stroke
				(width 0.1)
				(type default)
			)
			(layer "F.Fab")
		)
		(fp_line
			(start -0.12065 -0.305054)
			(end -0.12065 -0.2794)
			(stroke
				(width 0.1)
				(type default)
			)
			(layer "F.Fab")
		)
		(fp_line
			(start -0.67945 0.3048)
			(end -0.67945 -0.305054)
			(stroke
				(width 0.1)
				(type default)
			)
			(layer "F.Fab")
		)
		(fp_line
			(start -0.67945 -0.305054)
			(end -0.12065 -0.305054)
			(stroke
				(width 0.1)
				(type default)
			)
			(layer "F.Fab")
		)
		(pad "1" smd circle
			(at -0.40005 0 180)
			(size 0 0)
			(layers "F.Cu" "F.Mask" "F.Paste")
			(net "I3C_SPD_DDRABCD_CPU1_LVC1_R_SCL")
		)
		(pad "2" smd circle
			(at 0.40005 0 180)
			(size 0 0)
			(layers "F.Cu" "F.Mask" "F.Paste")
			(net "I3C_SPD_DDRABCD_CPU1_LVC1_SCL")
		)
	)
	(footprint ""
		(layer "F.Cu")
		(at 208.49336 -119.1006 180)
		(property "Reference" "R4719"
			(at 0 0 180)
			(layer "F.SilkS")
			(hide yes)
			(effects
				(font
					(size 1.27 1.27)
				)
			)
		)
		(property "Value" ""
			(at 0 0 180)
			(layer "F.Fab")
			(effects
				(font
					(size 1.27 1.27)
				)
			)
		)
		(duplicate_pad_numbers_are_jumpers no)
		(fp_line
			(start 0.7874 0.4064)
			(end -0.7874 0.4064)
			(stroke
				(width 0.1524)
				(type default)
			)
			(layer "F.SilkS")
		)
		(fp_line
			(start 0.7874 -0.4064)
			(end 0.7874 0.4064)
			(stroke
				(width 0.1524)
				(type default)
			)
			(layer "F.SilkS")
		)
		(fp_line
			(start -0.7874 0.4064)
			(end -0.7874 -0.4064)
			(stroke
				(width 0.1524)
				(type default)
			)
			(layer "F.SilkS")
		)
		(fp_line
			(start -0.7874 -0.4064)
			(end 0.7874 -0.4064)
			(stroke
				(width 0.1524)
				(type default)
			)
			(layer "F.SilkS")
		)
		(fp_line
			(start 0.67945 0.3048)
			(end 0.120396 0.3048)
			(stroke
				(width 0.1)
				(type default)
			)
			(layer "F.Fab")
		)
		(fp_line
			(start 0.67945 -0.3048)
			(end 0.67945 0.3048)
			(stroke
				(width 0.1)
				(type default)
			)
			(layer "F.Fab")
		)
		(fp_line
			(start 0.12065 -0.2794)
			(end 0.12065 -0.3048)
			(stroke
				(width 0.1)
				(type default)
			)
			(layer "F.Fab")
		)
		(fp_line
			(start 0.12065 -0.3048)
			(end 0.67945 -0.3048)
			(stroke
				(width 0.1)
				(type default)
			)
			(layer "F.Fab")
		)
		(fp_line
			(start 0.120396 0.3048)
			(end 0.120396 0.2794)
			(stroke
				(width 0.1)
				(type default)
			)
			(layer "F.Fab")
		)
		(fp_line
			(start 0.120396 0.2794)
			(end -0.12065 0.2794)
			(stroke
				(width 0.1)
				(type default)
			)
			(layer "F.Fab")
		)
		(fp_line
			(start -0.12065 0.3048)
			(end -0.67945 0.3048)
			(stroke
				(width 0.1)
				(type default)
			)
			(layer "F.Fab")
		)
		(fp_line
			(start -0.12065 0.2794)
			(end -0.12065 0.3048)
			(stroke
				(width 0.1)
				(type default)
			)
			(layer "F.Fab")
		)
		(fp_line
			(start -0.12065 -0.2794)
			(end 0.12065 -0.2794)
			(stroke
				(width 0.1)
				(type default)
			)
			(layer "F.Fab")
		)
		(fp_line
			(start -0.12065 -0.305054)
			(end -0.12065 -0.2794)
			(stroke
				(width 0.1)
				(type default)
			)
			(layer "F.Fab")
		)
		(fp_line
			(start -0.67945 0.3048)
			(end -0.67945 -0.305054)
			(stroke
				(width 0.1)
				(type default)
			)
			(layer "F.Fab")
		)
		(fp_line
			(start -0.67945 -0.305054)
			(end -0.12065 -0.305054)
			(stroke
				(width 0.1)
				(type default)
			)
			(layer "F.Fab")
		)
		(pad "1" smd circle
			(at -0.40005 0 180)
			(size 0 0)
			(layers "F.Cu" "F.Mask" "F.Paste")
			(net "P3V3_AUX")
		)
		(pad "2" smd circle
			(at 0.40005 0 180)
			(size 0 0)
			(layers "F.Cu" "F.Mask" "F.Paste")
			(net "FM_AC_PWR_BTN_PLD_ISO_N")
		)
	)
	(footprint ""
		(layer "F.Cu")
		(at 21.096478 -16.099536 90)
		(property "Reference" "C811"
			(at 0 0 90)
			(layer "F.SilkS")
			(hide yes)
			(effects
				(font
					(size 1.27 1.27)
				)
			)
		)
		(property "Value" ""
			(at 0 0 90)
			(layer "F.Fab")
			(effects
				(font
					(size 1.27 1.27)
				)
			)
		)
		(duplicate_pad_numbers_are_jumpers no)
		(fp_line
			(start 0.299974 -0.150114)
			(end 0.299974 0.150114)
			(stroke
				(width 0.1)
				(type default)
			)
			(layer "F.Fab")
		)
		(fp_line
			(start -0.299974 -0.150114)
			(end 0.299974 -0.150114)
			(stroke
				(width 0.1)
				(type default)
			)
			(layer "F.Fab")
		)
		(fp_line
			(start 0.299974 0.150114)
			(end -0.299974 0.150114)
			(stroke
				(width 0.1)
				(type default)
			)
			(layer "F.Fab")
		)
		(fp_line
			(start -0.299974 0.150114)
			(end -0.299974 -0.150114)
			(stroke
				(width 0.1)
				(type default)
			)
			(layer "F.Fab")
		)
		(pad "1" smd rect
			(at -0.2667 0 90)
			(size 0.3048 0.381)
			(layers "F.Cu" "F.Mask" "F.Paste")
			(net "P5E_CPU1_PE1_TX_C_DP<13>")
		)
		(pad "2" smd rect
			(at 0.2667 0 90)
			(size 0.3048 0.381)
			(layers "F.Cu" "F.Mask" "F.Paste")
			(net "P5E_CPU1_PE1_TX_DP<13>")
		)
	)
	(footprint ""
		(layer "F.Cu")
		(at 179.342288 -406.898602)
		(property "Reference" "R3933"
			(at 0 0 0)
			(layer "F.SilkS")
			(hide yes)
			(effects
				(font
					(size 1.27 1.27)
				)
			)
		)
		(property "Value" ""
			(at 0 0 0)
			(layer "F.Fab")
			(effects
				(font
					(size 1.27 1.27)
				)
			)
		)
		(duplicate_pad_numbers_are_jumpers no)
		(fp_line
			(start -0.7874 -0.4064)
			(end 0.7874 -0.4064)
			(stroke
				(width 0.1524)
				(type default)
			)
			(layer "F.SilkS")
		)
		(fp_line
			(start -0.7874 0.4064)
			(end -0.7874 -0.4064)
			(stroke
				(width 0.1524)
				(type default)
			)
			(layer "F.SilkS")
		)
		(fp_line
			(start 0.7874 -0.4064)
			(end 0.7874 0.4064)
			(stroke
				(width 0.1524)
				(type default)
			)
			(layer "F.SilkS")
		)
		(fp_line
			(start 0.7874 0.4064)
			(end -0.7874 0.4064)
			(stroke
				(width 0.1524)
				(type default)
			)
			(layer "F.SilkS")
		)
		(fp_line
			(start -0.67945 -0.305054)
			(end -0.12065 -0.305054)
			(stroke
				(width 0.1)
				(type default)
			)
			(layer "F.Fab")
		)
		(fp_line
			(start -0.67945 0.3048)
			(end -0.67945 -0.305054)
			(stroke
				(width 0.1)
				(type default)
			)
			(layer "F.Fab")
		)
		(fp_line
			(start -0.12065 -0.305054)
			(end -0.12065 -0.2794)
			(stroke
				(width 0.1)
				(type default)
			)
			(layer "F.Fab")
		)
		(fp_line
			(start -0.12065 -0.2794)
			(end 0.12065 -0.2794)
			(stroke
				(width 0.1)
				(type default)
			)
			(layer "F.Fab")
		)
		(fp_line
			(start -0.12065 0.2794)
			(end -0.12065 0.3048)
			(stroke
				(width 0.1)
				(type default)
			)
			(layer "F.Fab")
		)
		(fp_line
			(start -0.12065 0.3048)
			(end -0.67945 0.3048)
			(stroke
				(width 0.1)
				(type default)
			)
			(layer "F.Fab")
		)
		(fp_line
			(start 0.120396 0.2794)
			(end -0.12065 0.2794)
			(stroke
				(width 0.1)
				(type default)
			)
			(layer "F.Fab")
		)
		(fp_line
			(start 0.120396 0.3048)
			(end 0.120396 0.2794)
			(stroke
				(width 0.1)
				(type default)
			)
			(layer "F.Fab")
		)
		(fp_line
			(start 0.12065 -0.3048)
			(end 0.67945 -0.3048)
			(stroke
				(width 0.1)
				(type default)
			)
			(layer "F.Fab")
		)
		(fp_line
			(start 0.12065 -0.2794)
			(end 0.12065 -0.3048)
			(stroke
				(width 0.1)
				(type default)
			)
			(layer "F.Fab")
		)
		(fp_line
			(start 0.67945 -0.3048)
			(end 0.67945 0.3048)
			(stroke
				(width 0.1)
				(type default)
			)
			(layer "F.Fab")
		)
		(fp_line
			(start 0.67945 0.3048)
			(end 0.120396 0.3048)
			(stroke
				(width 0.1)
				(type default)
			)
			(layer "F.Fab")
		)
		(pad "1" smd circle
			(at -0.40005 0)
			(size 0 0)
			(layers "F.Cu" "F.Mask" "F.Paste")
			(net "P12V_AUX")
		)
		(pad "2" smd circle
			(at 0.40005 0)
			(size 0 0)
			(layers "F.Cu" "F.Mask" "F.Paste")
			(net "MB0_P12V_STBY_PWRGD")
		)
	)
	(footprint ""
		(layer "F.Cu")
		(at 189.65037 -427.319948 180)
		(property "Reference" "C1797"
			(at 0 0 180)
			(layer "F.SilkS")
			(hide yes)
			(effects
				(font
					(size 1.27 1.27)
				)
			)
		)
		(property "Value" ""
			(at 0 0 180)
			(layer "F.Fab")
			(effects
				(font
					(size 1.27 1.27)
				)
			)
		)
		(duplicate_pad_numbers_are_jumpers no)
		(fp_line
			(start 0.7874 0.4064)
			(end -0.7874 0.4064)
			(stroke
				(width 0.1524)
				(type default)
			)
			(layer "F.SilkS")
		)
		(fp_line
			(start 0.7874 -0.4064)
			(end 0.7874 0.4064)
			(stroke
				(width 0.1524)
				(type default)
			)
			(layer "F.SilkS")
		)
		(fp_line
			(start -0.7874 0.4064)
			(end -0.7874 -0.4064)
			(stroke
				(width 0.1524)
				(type default)
			)
			(layer "F.SilkS")
		)
		(fp_line
			(start -0.7874 -0.4064)
			(end 0.7874 -0.4064)
			(stroke
				(width 0.1524)
				(type default)
			)
			(layer "F.SilkS")
		)
		(fp_line
			(start 0.67945 0.3048)
			(end 0.120396 0.3048)
			(stroke
				(width 0.1)
				(type default)
			)
			(layer "F.Fab")
		)
		(fp_line
			(start 0.67945 -0.3048)
			(end 0.67945 0.3048)
			(stroke
				(width 0.1)
				(type default)
			)
			(layer "F.Fab")
		)
		(fp_line
			(start 0.12065 -0.2794)
			(end 0.12065 -0.3048)
			(stroke
				(width 0.1)
				(type default)
			)
			(layer "F.Fab")
		)
		(fp_line
			(start 0.12065 -0.3048)
			(end 0.67945 -0.3048)
			(stroke
				(width 0.1)
				(type default)
			)
			(layer "F.Fab")
		)
		(fp_line
			(start 0.120396 0.3048)
			(end 0.120396 0.2794)
			(stroke
				(width 0.1)
				(type default)
			)
			(layer "F.Fab")
		)
		(fp_line
			(start 0.120396 0.2794)
			(end -0.12065 0.2794)
			(stroke
				(width 0.1)
				(type default)
			)
			(layer "F.Fab")
		)
		(fp_line
			(start -0.12065 0.3048)
			(end -0.67945 0.3048)
			(stroke
				(width 0.1)
				(type default)
			)
			(layer "F.Fab")
		)
		(fp_line
			(start -0.12065 0.2794)
			(end -0.12065 0.3048)
			(stroke
				(width 0.1)
				(type default)
			)
			(layer "F.Fab")
		)
		(fp_line
			(start -0.12065 -0.2794)
			(end 0.12065 -0.2794)
			(stroke
				(width 0.1)
				(type default)
			)
			(layer "F.Fab")
		)
		(fp_line
			(start -0.12065 -0.305054)
			(end -0.12065 -0.2794)
			(stroke
				(width 0.1)
				(type default)
			)
			(layer "F.Fab")
		)
		(fp_line
			(start -0.67945 0.3048)
			(end -0.67945 -0.305054)
			(stroke
				(width 0.1)
				(type default)
			)
			(layer "F.Fab")
		)
		(fp_line
			(start -0.67945 -0.305054)
			(end -0.12065 -0.305054)
			(stroke
				(width 0.1)
				(type default)
			)
			(layer "F.Fab")
		)
		(pad "1" smd circle
			(at -0.40005 0 180)
			(size 0 0)
			(layers "F.Cu" "F.Mask" "F.Paste")
			(net "PDB_PRSNT_N")
		)
		(pad "2" smd circle
			(at 0.40005 0 180)
			(size 0 0)
			(layers "F.Cu" "F.Mask" "F.Paste")
			(net "GND")
		)
	)
	(footprint ""
		(layer "F.Cu")
		(at 351.806764 -360.934762 90)
		(property "Reference" "C3266"
			(at 0 0 90)
			(layer "F.SilkS")
			(hide yes)
			(effects
				(font
					(size 1.27 1.27)
				)
			)
		)
		(property "Value" ""
			(at 0 0 90)
			(layer "F.Fab")
			(effects
				(font
					(size 1.27 1.27)
				)
			)
		)
		(duplicate_pad_numbers_are_jumpers no)
		(fp_line
			(start 0.7874 -0.4064)
			(end 0.7874 0.4064)
			(stroke
				(width 0.1524)
				(type default)
			)
			(layer "F.SilkS")
		)
		(fp_line
			(start -0.7874 -0.4064)
			(end 0.7874 -0.4064)
			(stroke
				(width 0.1524)
				(type default)
			)
			(layer "F.SilkS")
		)
		(fp_line
			(start 0.7874 0.4064)
			(end -0.7874 0.4064)
			(stroke
				(width 0.1524)
				(type default)
			)
			(layer "F.SilkS")
		)
		(fp_line
			(start -0.7874 0.4064)
			(end -0.7874 -0.4064)
			(stroke
				(width 0.1524)
				(type default)
			)
			(layer "F.SilkS")
		)
		(fp_line
			(start -0.12065 -0.305054)
			(end -0.12065 -0.2794)
			(stroke
				(width 0.1)
				(type default)
			)
			(layer "F.Fab")
		)
		(fp_line
			(start -0.67945 -0.305054)
			(end -0.12065 -0.305054)
			(stroke
				(width 0.1)
				(type default)
			)
			(layer "F.Fab")
		)
		(fp_line
			(start 0.67945 -0.3048)
			(end 0.67945 0.3048)
			(stroke
				(width 0.1)
				(type default)
			)
			(layer "F.Fab")
		)
		(fp_line
			(start 0.12065 -0.3048)
			(end 0.67945 -0.3048)
			(stroke
				(width 0.1)
				(type default)
			)
			(layer "F.Fab")
		)
		(fp_line
			(start 0.12065 -0.2794)
			(end 0.12065 -0.3048)
			(stroke
				(width 0.1)
				(type default)
			)
			(layer "F.Fab")
		)
		(fp_line
			(start -0.12065 -0.2794)
			(end 0.12065 -0.2794)
			(stroke
				(width 0.1)
				(type default)
			)
			(layer "F.Fab")
		)
		(fp_line
			(start 0.120396 0.2794)
			(end -0.12065 0.2794)
			(stroke
				(width 0.1)
				(type default)
			)
			(layer "F.Fab")
		)
		(fp_line
			(start -0.12065 0.2794)
			(end -0.12065 0.3048)
			(stroke
				(width 0.1)
				(type default)
			)
			(layer "F.Fab")
		)
		(fp_line
			(start 0.67945 0.3048)
			(end 0.120396 0.3048)
			(stroke
				(width 0.1)
				(type default)
			)
			(layer "F.Fab")
		)
		(fp_line
			(start 0.120396 0.3048)
			(end 0.120396 0.2794)
			(stroke
				(width 0.1)
				(type default)
			)
			(layer "F.Fab")
		)
		(fp_line
			(start -0.12065 0.3048)
			(end -0.67945 0.3048)
			(stroke
				(width 0.1)
				(type default)
			)
			(layer "F.Fab")
		)
		(fp_line
			(start -0.67945 0.3048)
			(end -0.67945 -0.305054)
			(stroke
				(width 0.1)
				(type default)
			)
			(layer "F.Fab")
		)
		(pad "1" smd circle
			(at -0.40005 0 90)
			(size 0 0)
			(layers "F.Cu" "F.Mask" "F.Paste")
			(net "PWRGD_PVCCIN_CPU0_R")
		)
		(pad "2" smd circle
			(at 0.40005 0 90)
			(size 0 0)
			(layers "F.Cu" "F.Mask" "F.Paste")
			(net "GND")
		)
	)
	(footprint ""
		(layer "F.Cu")
		(at 422.55694 -101.270308 -90)
		(property "Reference" "PR3844"
			(at 0 0 270)
			(layer "F.SilkS")
			(hide yes)
			(effects
				(font
					(size 1.27 1.27)
				)
			)
		)
		(property "Value" ""
			(at 0 0 270)
			(layer "F.Fab")
			(effects
				(font
					(size 1.27 1.27)
				)
			)
		)
		(duplicate_pad_numbers_are_jumpers no)
		(fp_line
			(start -0.7874 0.4064)
			(end -0.7874 -0.4064)
			(stroke
				(width 0.1524)
				(type default)
			)
			(layer "F.SilkS")
		)
		(fp_line
			(start 0.7874 0.4064)
			(end -0.7874 0.4064)
			(stroke
				(width 0.1524)
				(type default)
			)
			(layer "F.SilkS")
		)
		(fp_line
			(start -0.7874 -0.4064)
			(end 0.7874 -0.4064)
			(stroke
				(width 0.1524)
				(type default)
			)
			(layer "F.SilkS")
		)
		(fp_line
			(start 0.7874 -0.4064)
			(end 0.7874 0.4064)
			(stroke
				(width 0.1524)
				(type default)
			)
			(layer "F.SilkS")
		)
		(fp_line
			(start -0.67945 0.3048)
			(end -0.67945 -0.305054)
			(stroke
				(width 0.1)
				(type default)
			)
			(layer "F.Fab")
		)
		(fp_line
			(start -0.12065 0.3048)
			(end -0.67945 0.3048)
			(stroke
				(width 0.1)
				(type default)
			)
			(layer "F.Fab")
		)
		(fp_line
			(start 0.120396 0.3048)
			(end 0.120396 0.2794)
			(stroke
				(width 0.1)
				(type default)
			)
			(layer "F.Fab")
		)
		(fp_line
			(start 0.67945 0.3048)
			(end 0.120396 0.3048)
			(stroke
				(width 0.1)
				(type default)
			)
			(layer "F.Fab")
		)
		(fp_line
			(start -0.12065 0.2794)
			(end -0.12065 0.3048)
			(stroke
				(width 0.1)
				(type default)
			)
			(layer "F.Fab")
		)
		(fp_line
			(start 0.120396 0.2794)
			(end -0.12065 0.2794)
			(stroke
				(width 0.1)
				(type default)
			)
			(layer "F.Fab")
		)
		(fp_line
			(start -0.12065 -0.2794)
			(end 0.12065 -0.2794)
			(stroke
				(width 0.1)
				(type default)
			)
			(layer "F.Fab")
		)
		(fp_line
			(start 0.12065 -0.2794)
			(end 0.12065 -0.3048)
			(stroke
				(width 0.1)
				(type default)
			)
			(layer "F.Fab")
		)
		(fp_line
			(start 0.12065 -0.3048)
			(end 0.67945 -0.3048)
			(stroke
				(width 0.1)
				(type default)
			)
			(layer "F.Fab")
		)
		(fp_line
			(start 0.67945 -0.3048)
			(end 0.67945 0.3048)
			(stroke
				(width 0.1)
				(type default)
			)
			(layer "F.Fab")
		)
		(fp_line
			(start -0.67945 -0.305054)
			(end -0.12065 -0.305054)
			(stroke
				(width 0.1)
				(type default)
			)
			(layer "F.Fab")
		)
		(fp_line
			(start -0.12065 -0.305054)
			(end -0.12065 -0.2794)
			(stroke
				(width 0.1)
				(type default)
			)
			(layer "F.Fab")
		)
		(pad "1" smd circle
			(at -0.40005 0 270)
			(size 0 0)
			(layers "F.Cu" "F.Mask" "F.Paste")
			(net "P3V3_OCP_MODE_1")
		)
		(pad "2" smd circle
			(at 0.40005 0 270)
			(size 0 0)
			(layers "F.Cu" "F.Mask" "F.Paste")
			(net "GND")
		)
	)
	(footprint ""
		(layer "F.Cu")
		(at 372.31193 -402.371052 -90)
		(property "Reference" "C935"
			(at 0 0 270)
			(layer "F.SilkS")
			(hide yes)
			(effects
				(font
					(size 1.27 1.27)
				)
			)
		)
		(property "Value" ""
			(at 0 0 270)
			(layer "F.Fab")
			(effects
				(font
					(size 1.27 1.27)
				)
			)
		)
		(duplicate_pad_numbers_are_jumpers no)
		(fp_line
			(start -0.299974 0.150114)
			(end -0.299974 -0.150114)
			(stroke
				(width 0.1)
				(type default)
			)
			(layer "F.Fab")
		)
		(fp_line
			(start 0.299974 0.150114)
			(end -0.299974 0.150114)
			(stroke
				(width 0.1)
				(type default)
			)
			(layer "F.Fab")
		)
		(fp_line
			(start -0.299974 -0.150114)
			(end 0.299974 -0.150114)
			(stroke
				(width 0.1)
				(type default)
			)
			(layer "F.Fab")
		)
		(fp_line
			(start 0.299974 -0.150114)
			(end 0.299974 0.150114)
			(stroke
				(width 0.1)
				(type default)
			)
			(layer "F.Fab")
		)
		(pad "1" smd rect
			(at -0.2667 0 270)
			(size 0.3048 0.381)
			(layers "F.Cu" "F.Mask" "F.Paste")
			(net "P5E_CPU0_PE2_TX_C_DP<15>")
		)
		(pad "2" smd rect
			(at 0.2667 0 270)
			(size 0.3048 0.381)
			(layers "F.Cu" "F.Mask" "F.Paste")
			(net "P5E_CPU0_PE2_TX_DP<15>")
		)
	)
	(footprint ""
		(layer "F.Cu")
		(at 64.616838 -408.517344 -90)
		(property "Reference" "C698"
			(at 0 0 270)
			(layer "F.SilkS")
			(hide yes)
			(effects
				(font
					(size 1.27 1.27)
				)
			)
		)
		(property "Value" ""
			(at 0 0 270)
			(layer "F.Fab")
			(effects
				(font
					(size 1.27 1.27)
				)
			)
		)
		(duplicate_pad_numbers_are_jumpers no)
		(fp_line
			(start -0.299974 0.150114)
			(end -0.299974 -0.150114)
			(stroke
				(width 0.1)
				(type default)
			)
			(layer "F.Fab")
		)
		(fp_line
			(start 0.299974 0.150114)
			(end -0.299974 0.150114)
			(stroke
				(width 0.1)
				(type default)
			)
			(layer "F.Fab")
		)
		(fp_line
			(start -0.299974 -0.150114)
			(end 0.299974 -0.150114)
			(stroke
				(width 0.1)
				(type default)
			)
			(layer "F.Fab")
		)
		(fp_line
			(start 0.299974 -0.150114)
			(end 0.299974 0.150114)
			(stroke
				(width 0.1)
				(type default)
			)
			(layer "F.Fab")
		)
		(pad "1" smd rect
			(at -0.2667 0 270)
			(size 0.3048 0.381)
			(layers "F.Cu" "F.Mask" "F.Paste")
			(net "P5E_CPU1_PE4_TX_C_DN<5>")
		)
		(pad "2" smd rect
			(at 0.2667 0 270)
			(size 0.3048 0.381)
			(layers "F.Cu" "F.Mask" "F.Paste")
			(net "P5E_CPU1_PE4_TX_DN<5>")
		)
	)
	(footprint ""
		(layer "F.Cu")
		(at 237.171738 -119.183658 -90)
		(property "Reference" "R3196"
			(at 0 0 270)
			(layer "F.SilkS")
			(hide yes)
			(effects
				(font
					(size 1.27 1.27)
				)
			)
		)
		(property "Value" ""
			(at 0 0 270)
			(layer "F.Fab")
			(effects
				(font
					(size 1.27 1.27)
				)
			)
		)
		(duplicate_pad_numbers_are_jumpers no)
		(fp_line
			(start -0.7874 0.4064)
			(end -0.7874 -0.064262)
			(stroke
				(width 0.1524)
				(type default)
			)
			(layer "F.SilkS")
		)
		(fp_line
			(start 0.7874 0.4064)
			(end -0.7874 0.4064)
			(stroke
				(width 0.1524)
				(type default)
			)
			(layer "F.SilkS")
		)
		(fp_line
			(start 0.7874 -0.016002)
			(end 0.7874 0.4064)
			(stroke
				(width 0.1524)
				(type default)
			)
			(layer "F.SilkS")
		)
		(fp_line
			(start -0.287782 -0.4064)
			(end 0.438658 -0.4064)
			(stroke
				(width 0.1524)
				(type default)
			)
			(layer "F.SilkS")
		)
		(fp_line
			(start -0.67945 0.3048)
			(end -0.67945 -0.305054)
			(stroke
				(width 0.1)
				(type default)
			)
			(layer "F.Fab")
		)
		(fp_line
			(start -0.12065 0.3048)
			(end -0.67945 0.3048)
			(stroke
				(width 0.1)
				(type default)
			)
			(layer "F.Fab")
		)
		(fp_line
			(start 0.120396 0.3048)
			(end 0.120396 0.2794)
			(stroke
				(width 0.1)
				(type default)
			)
			(layer "F.Fab")
		)
		(fp_line
			(start 0.67945 0.3048)
			(end 0.120396 0.3048)
			(stroke
				(width 0.1)
				(type default)
			)
			(layer "F.Fab")
		)
		(fp_line
			(start -0.12065 0.2794)
			(end -0.12065 0.3048)
			(stroke
				(width 0.1)
				(type default)
			)
			(layer "F.Fab")
		)
		(fp_line
			(start 0.120396 0.2794)
			(end -0.12065 0.2794)
			(stroke
				(width 0.1)
				(type default)
			)
			(layer "F.Fab")
		)
		(fp_line
			(start -0.12065 -0.2794)
			(end 0.12065 -0.2794)
			(stroke
				(width 0.1)
				(type default)
			)
			(layer "F.Fab")
		)
		(fp_line
			(start 0.12065 -0.2794)
			(end 0.12065 -0.3048)
			(stroke
				(width 0.1)
				(type default)
			)
			(layer "F.Fab")
		)
		(fp_line
			(start 0.12065 -0.3048)
			(end 0.67945 -0.3048)
			(stroke
				(width 0.1)
				(type default)
			)
			(layer "F.Fab")
		)
		(fp_line
			(start 0.67945 -0.3048)
			(end 0.67945 0.3048)
			(stroke
				(width 0.1)
				(type default)
			)
			(layer "F.Fab")
		)
		(fp_line
			(start -0.67945 -0.305054)
			(end -0.12065 -0.305054)
			(stroke
				(width 0.1)
				(type default)
			)
			(layer "F.Fab")
		)
		(fp_line
			(start -0.12065 -0.305054)
			(end -0.12065 -0.2794)
			(stroke
				(width 0.1)
				(type default)
			)
			(layer "F.Fab")
		)
		(pad "1" smd circle
			(at -0.40005 0 270)
			(size 0 0)
			(layers "F.Cu" "F.Mask" "F.Paste")
			(net "CLK_100M_OCP_V3_2_B_R_DP")
		)
		(pad "2" smd circle
			(at 0.40005 0 270)
			(size 0 0)
			(layers "F.Cu" "F.Mask" "F.Paste")
			(net "CLK_100M_OCP_V3_2_B_DP")
		)
	)
	(footprint ""
		(layer "F.Cu")
		(at 138.508994 -402.371052 -90)
		(property "Reference" "C755"
			(at 0 0 270)
			(layer "F.SilkS")
			(hide yes)
			(effects
				(font
					(size 1.27 1.27)
				)
			)
		)
		(property "Value" ""
			(at 0 0 270)
			(layer "F.Fab")
			(effects
				(font
					(size 1.27 1.27)
				)
			)
		)
		(duplicate_pad_numbers_are_jumpers no)
		(fp_line
			(start -0.299974 0.150114)
			(end -0.299974 -0.150114)
			(stroke
				(width 0.1)
				(type default)
			)
			(layer "F.Fab")
		)
		(fp_line
			(start 0.299974 0.150114)
			(end -0.299974 0.150114)
			(stroke
				(width 0.1)
				(type default)
			)
			(layer "F.Fab")
		)
		(fp_line
			(start -0.299974 -0.150114)
			(end 0.299974 -0.150114)
			(stroke
				(width 0.1)
				(type default)
			)
			(layer "F.Fab")
		)
		(fp_line
			(start 0.299974 -0.150114)
			(end 0.299974 0.150114)
			(stroke
				(width 0.1)
				(type default)
			)
			(layer "F.Fab")
		)
		(pad "1" smd rect
			(at -0.2667 0 270)
			(size 0.3048 0.381)
			(layers "F.Cu" "F.Mask" "F.Paste")
			(net "P5E_CPU1_PE2_TX_C_DP<9>")
		)
		(pad "2" smd rect
			(at 0.2667 0 270)
			(size 0.3048 0.381)
			(layers "F.Cu" "F.Mask" "F.Paste")
			(net "P5E_CPU1_PE2_TX_DP<9>")
		)
	)
	(footprint ""
		(layer "F.Cu")
		(at 384.458972 -354.434902)
		(property "Reference" "H44"
			(at -3.03276 -5.138928 0)
			(unlocked yes)
			(layer "F.SilkS")
			(effects
				(font
					(size 0.7874 0.5842)
					(thickness 0.1524)
				)
				(justify left)
			)
		)
		(property "Value" ""
			(at 0 0 0)
			(layer "F.Fab")
			(effects
				(font
					(size 1.27 1.27)
				)
			)
		)
		(duplicate_pad_numbers_are_jumpers no)
		(pad "1" thru_hole circle
			(at 0 0)
			(size 8.001 8.001)
			(drill 3.2004)
			(layers "*.Cu" "*.Mask")
			(remove_unused_layers no)
			(net "GND")
			(clearance -2.1463)
			(padstack
				(mode front_inner_back)
				(layer "Inner"
					(shape circle)
					(size 5.0038 5.0038)
					(clearance -0.6477)
				)
				(layer "B.Cu"
					(shape circle)
					(size 8.001 8.001)
					(clearance -2.1463)
				)
			)
		)
	)
	(footprint ""
		(layer "F.Cu")
		(at 31.503366 -48.385476)
		(property "Reference" "ME29"
			(at 0 0 0)
			(layer "F.SilkS")
			(hide yes)
			(effects
				(font
					(size 1.27 1.27)
				)
			)
		)
		(property "Value" ""
			(at 0 0 0)
			(layer "F.Fab")
			(effects
				(font
					(size 1.27 1.27)
				)
			)
		)
		(duplicate_pad_numbers_are_jumpers no)
		(fp_line
			(start 0 -4.99999)
			(end 0 -3.47599)
			(stroke
				(width 0.1524)
				(type default)
			)
			(layer "F.SilkS")
		)
		(fp_line
			(start 0 -0.524002)
			(end 0 0.999998)
			(stroke
				(width 0.1524)
				(type default)
			)
			(layer "F.SilkS")
		)
		(fp_line
			(start 0 0.999998)
			(end 1.524 0.999998)
			(stroke
				(width 0.1524)
				(type default)
			)
			(layer "F.SilkS")
		)
		(fp_line
			(start 1.524 -4.99999)
			(end 0 -4.99999)
			(stroke
				(width 0.1524)
				(type default)
			)
			(layer "F.SilkS")
		)
		(fp_line
			(start 15.475966 0.999998)
			(end 16.999966 0.999998)
			(stroke
				(width 0.1524)
				(type default)
			)
			(layer "F.SilkS")
		)
		(fp_line
			(start 16.999966 -4.99999)
			(end 15.475966 -4.99999)
			(stroke
				(width 0.1524)
				(type default)
			)
			(layer "F.SilkS")
		)
		(fp_line
			(start 16.999966 -3.47599)
			(end 16.999966 -4.99999)
			(stroke
				(width 0.1524)
				(type default)
			)
			(layer "F.SilkS")
		)
		(fp_line
			(start 16.999966 0.999998)
			(end 16.999966 -0.524002)
			(stroke
				(width 0.1524)
				(type default)
			)
			(layer "F.SilkS")
		)
		(fp_text user "S/N"
			(at 0.1016 -3.54965 0)
			(unlocked yes)
			(layer "F.SilkS")
			(effects
				(font
					(size 1.905 1.4224)
					(thickness 0.1524)
				)
				(justify left)
			)
		)
	)
	(footprint ""
		(layer "F.Cu")
		(at 198.58228 -258.091686)
		(property "Reference" "J29"
			(at -3.683 -81.702148 0)
			(unlocked yes)
			(layer "F.SilkS")
			(effects
				(font
					(size 0.7874 0.5842)
					(thickness 0.1524)
				)
				(justify left)
			)
		)
		(property "Value" ""
			(at 0 0 0)
			(layer "F.Fab")
			(effects
				(font
					(size 1.27 1.27)
				)
			)
		)
		(duplicate_pad_numbers_are_jumpers no)
		(fp_line
			(start -3.24993 -81.000092)
			(end -3.24993 78.977998)
			(stroke
				(width 0.1524)
				(type default)
			)
			(layer "F.SilkS")
		)
		(fp_line
			(start -3.24993 80.324198)
			(end -3.24993 81.000092)
			(stroke
				(width 0.1524)
				(type default)
			)
			(layer "F.SilkS")
		)
		(fp_line
			(start -3.24993 81.000092)
			(end 3.24993 81.000092)
			(stroke
				(width 0.1524)
				(type default)
			)
			(layer "F.SilkS")
		)
		(fp_line
			(start 3.24993 -81.000092)
			(end -3.24993 -81.000092)
			(stroke
				(width 0.1524)
				(type default)
			)
			(layer "F.SilkS")
		)
		(fp_line
			(start 3.24993 -72.00011)
			(end -3.24993 -72.00011)
			(stroke
				(width 0.1524)
				(type default)
			)
			(layer "F.SilkS")
		)
		(fp_line
			(start 3.24993 72.00011)
			(end -3.24993 72.00011)
			(stroke
				(width 0.1524)
				(type default)
			)
			(layer "F.SilkS")
		)
		(fp_line
			(start 3.24993 76.239878)
			(end 3.24993 -81.000092)
			(stroke
				(width 0.1524)
				(type default)
			)
			(layer "F.SilkS")
		)
		(fp_line
			(start 3.24993 81.000092)
			(end 3.24993 77.601318)
			(stroke
				(width 0.1524)
				(type default)
			)
			(layer "F.SilkS")
		)
		(fp_poly
			(pts
				(xy -4.193794 -63.733426) (xy -3.325368 -63.299086) (xy -4.193794 -62.864746)
			)
			(stroke
				(width 0)
				(type default)
			)
			(fill yes)
			(layer "F.SilkS")
		)
		(fp_line
			(start -3.24993 -81.000092)
			(end -3.24993 81.000092)
			(stroke
				(width 0.1)
				(type default)
			)
			(layer "F.Fab")
		)
		(fp_line
			(start -3.24993 81.000092)
			(end 3.24993 81.000092)
			(stroke
				(width 0.1)
				(type default)
			)
			(layer "F.Fab")
		)
		(fp_line
			(start 3.24993 -81.000092)
			(end -3.24993 -81.000092)
			(stroke
				(width 0.1)
				(type default)
			)
			(layer "F.Fab")
		)
		(fp_line
			(start 3.24993 -72.00011)
			(end -3.24993 -72.00011)
			(stroke
				(width 0.1)
				(type default)
			)
			(layer "F.Fab")
		)
		(fp_line
			(start 3.24993 -71.000112)
			(end -3.24993 -71.000112)
			(stroke
				(width 0.1)
				(type default)
			)
			(layer "F.Fab")
		)
		(fp_line
			(start 3.24993 71.000112)
			(end -3.24993 71.000112)
			(stroke
				(width 0.1)
				(type default)
			)
			(layer "F.Fab")
		)
		(fp_line
			(start 3.24993 72.00011)
			(end -3.24993 72.00011)
			(stroke
				(width 0.1)
				(type default)
			)
			(layer "F.Fab")
		)
		(fp_line
			(start 3.24993 81.000092)
			(end 3.24993 -81.000092)
			(stroke
				(width 0.1)
				(type default)
			)
			(layer "F.Fab")
		)
		(fp_poly
			(pts
				(xy -4.445 -63.832994) (xy -4.445 -62.816994) (xy -3.429 -63.324994)
			)
			(stroke
				(width 0)
				(type default)
			)
			(fill yes)
			(layer "F.Fab")
		)
		(pad "1" smd rect
			(at -2.050034 -63.324994 270)
			(size 0.519938 1.4986)
			(layers "F.Cu" "F.Mask" "F.Paste")
			(net "P12V_S3_AUX_CPU1_NVDIMM")
		)
		(pad "2" smd rect
			(at -2.050034 -62.47511 270)
			(size 0.519938 1.4986)
			(layers "F.Cu" "F.Mask" "F.Paste")
			(net "TP_CHG_CPU1_DIMM1_FRU_0")
		)
		(pad "3" smd rect
			(at -2.050034 -61.624972 270)
			(size 0.519938 1.4986)
			(layers "F.Cu" "F.Mask" "F.Paste")
			(net "P3V3_AUX")
		)
		(pad "4" smd rect
			(at -2.050034 -60.775088 270)
			(size 0.519938 1.4986)
			(layers "F.Cu" "F.Mask" "F.Paste")
			(net "I3C_SPD_DDREFGH_CPU1_LVC1_SCL_4")
		)
		(pad "5" smd rect
			(at -2.050034 -59.92495 270)
			(size 0.519938 1.4986)
			(layers "F.Cu" "F.Mask" "F.Paste")
			(net "I3C_SPD_DDREFGH_CPU1_LVC1_SDA")
		)
		(pad "6" smd rect
			(at -2.050034 -59.075066 270)
			(size 0.519938 1.4986)
			(layers "F.Cu" "F.Mask" "F.Paste")
			(net "GND")
		)
		(pad "7" smd rect
			(at -2.050034 -58.224928 270)
			(size 0.519938 1.4986)
			(layers "F.Cu" "F.Mask" "F.Paste")
			(net "M_G_CPU1_SA_DQ<0>")
		)
		(pad "8" smd rect
			(at -2.050034 -57.375044 270)
			(size 0.519938 1.4986)
			(layers "F.Cu" "F.Mask" "F.Paste")
			(net "GND")
		)
		(pad "9" smd rect
			(at -2.050034 -56.524906 270)
			(size 0.519938 1.4986)
			(layers "F.Cu" "F.Mask" "F.Paste")
			(net "M_G_CPU1_SA_DQ<1>")
		)
		(pad "10" smd rect
			(at -2.050034 -55.675022 270)
			(size 0.519938 1.4986)
			(layers "F.Cu" "F.Mask" "F.Paste")
			(net "GND")
		)
		(pad "11" smd rect
			(at -2.050034 -54.824884 270)
			(size 0.519938 1.4986)
			(layers "F.Cu" "F.Mask" "F.Paste")
			(net "M_G_CPU1_SA_DQS_DP<0>")
		)
		(pad "12" smd rect
			(at -2.050034 -53.975 270)
			(size 0.519938 1.4986)
			(layers "F.Cu" "F.Mask" "F.Paste")
			(net "M_G_CPU1_SA_DQS_DN<0>")
		)
		(pad "13" smd rect
			(at -2.050034 -53.125116 270)
			(size 0.519938 1.4986)
			(layers "F.Cu" "F.Mask" "F.Paste")
			(net "GND")
		)
		(pad "14" smd rect
			(at -2.050034 -52.274978 270)
			(size 0.519938 1.4986)
			(layers "F.Cu" "F.Mask" "F.Paste")
			(net "M_G_CPU1_SA_DQ<4>")
		)
		(pad "15" smd rect
			(at -2.050034 -51.425094 270)
			(size 0.519938 1.4986)
			(layers "F.Cu" "F.Mask" "F.Paste")
			(net "GND")
		)
		(pad "16" smd rect
			(at -2.050034 -50.574956 270)
			(size 0.519938 1.4986)
			(layers "F.Cu" "F.Mask" "F.Paste")
			(net "M_G_CPU1_SA_DQ<5>")
		)
		(pad "17" smd rect
			(at -2.050034 -49.725072 270)
			(size 0.519938 1.4986)
			(layers "F.Cu" "F.Mask" "F.Paste")
			(net "GND")
		)
		(pad "18" smd rect
			(at -2.050034 -48.874934 270)
			(size 0.519938 1.4986)
			(layers "F.Cu" "F.Mask" "F.Paste")
			(net "M_G_CPU1_SA_DQ<8>")
		)
		(pad "19" smd rect
			(at -2.050034 -48.02505 270)
			(size 0.519938 1.4986)
			(layers "F.Cu" "F.Mask" "F.Paste")
			(net "GND")
		)
		(pad "20" smd rect
			(at -2.050034 -47.174912 270)
			(size 0.519938 1.4986)
			(layers "F.Cu" "F.Mask" "F.Paste")
			(net "M_G_CPU1_SA_DQ<9>")
		)
		(pad "21" smd rect
			(at -2.050034 -46.325028 270)
			(size 0.519938 1.4986)
			(layers "F.Cu" "F.Mask" "F.Paste")
			(net "GND")
		)
		(pad "22" smd rect
			(at -2.050034 -45.47489 270)
			(size 0.519938 1.4986)
			(layers "F.Cu" "F.Mask" "F.Paste")
			(net "M_G_CPU1_SA_DQS_DP<1>")
		)
		(pad "23" smd rect
			(at -2.050034 -44.625006 270)
			(size 0.519938 1.4986)
			(layers "F.Cu" "F.Mask" "F.Paste")
			(net "M_G_CPU1_SA_DQS_DN<1>")
		)
		(pad "24" smd rect
			(at -2.050034 -43.775122 270)
			(size 0.519938 1.4986)
			(layers "F.Cu" "F.Mask" "F.Paste")
			(net "GND")
		)
		(pad "25" smd rect
			(at -2.050034 -42.924984 270)
			(size 0.519938 1.4986)
			(layers "F.Cu" "F.Mask" "F.Paste")
			(net "M_G_CPU1_SA_DQ<12>")
		)
		(pad "26" smd rect
			(at -2.050034 -42.0751 270)
			(size 0.519938 1.4986)
			(layers "F.Cu" "F.Mask" "F.Paste")
			(net "GND")
		)
		(pad "27" smd rect
			(at -2.050034 -41.224962 270)
			(size 0.519938 1.4986)
			(layers "F.Cu" "F.Mask" "F.Paste")
			(net "M_G_CPU1_SA_DQ<13>")
		)
		(pad "28" smd rect
			(at -2.050034 -40.375078 270)
			(size 0.519938 1.4986)
			(layers "F.Cu" "F.Mask" "F.Paste")
			(net "GND")
		)
		(pad "29" smd rect
			(at -2.050034 -39.52494 270)
			(size 0.519938 1.4986)
			(layers "F.Cu" "F.Mask" "F.Paste")
			(net "M_G_CPU1_SA_DQ<16>")
		)
		(pad "30" smd rect
			(at -2.050034 -38.675056 270)
			(size 0.519938 1.4986)
			(layers "F.Cu" "F.Mask" "F.Paste")
			(net "GND")
		)
		(pad "31" smd rect
			(at -2.050034 -37.824918 270)
			(size 0.519938 1.4986)
			(layers "F.Cu" "F.Mask" "F.Paste")
			(net "M_G_CPU1_SA_DQ<17>")
		)
		(pad "32" smd rect
			(at -2.050034 -36.975034 270)
			(size 0.519938 1.4986)
			(layers "F.Cu" "F.Mask" "F.Paste")
			(net "GND")
		)
		(pad "33" smd rect
			(at -2.050034 -36.124896 270)
			(size 0.519938 1.4986)
			(layers "F.Cu" "F.Mask" "F.Paste")
			(net "M_G_CPU1_SA_DQS_DP<2>")
		)
		(pad "34" smd rect
			(at -2.050034 -35.275012 270)
			(size 0.519938 1.4986)
			(layers "F.Cu" "F.Mask" "F.Paste")
			(net "M_G_CPU1_SA_DQS_DN<2>")
		)
		(pad "35" smd rect
			(at -2.050034 -34.425128 270)
			(size 0.519938 1.4986)
			(layers "F.Cu" "F.Mask" "F.Paste")
			(net "GND")
		)
		(pad "36" smd rect
			(at -2.050034 -33.57499 270)
			(size 0.519938 1.4986)
			(layers "F.Cu" "F.Mask" "F.Paste")
			(net "M_G_CPU1_SA_DQ<20>")
		)
		(pad "37" smd rect
			(at -2.050034 -32.725106 270)
			(size 0.519938 1.4986)
			(layers "F.Cu" "F.Mask" "F.Paste")
			(net "GND")
		)
		(pad "38" smd rect
			(at -2.050034 -31.874968 270)
			(size 0.519938 1.4986)
			(layers "F.Cu" "F.Mask" "F.Paste")
			(net "M_G_CPU1_SA_DQ<21>")
		)
		(pad "39" smd rect
			(at -2.050034 -31.025084 270)
			(size 0.519938 1.4986)
			(layers "F.Cu" "F.Mask" "F.Paste")
			(net "GND")
		)
		(pad "40" smd rect
			(at -2.050034 -30.174946 270)
			(size 0.519938 1.4986)
			(layers "F.Cu" "F.Mask" "F.Paste")
			(net "M_G_CPU1_SA_DQ<24>")
		)
		(pad "41" smd rect
			(at -2.050034 -29.325062 270)
			(size 0.519938 1.4986)
			(layers "F.Cu" "F.Mask" "F.Paste")
			(net "GND")
		)
		(pad "42" smd rect
			(at -2.050034 -28.474924 270)
			(size 0.519938 1.4986)
			(layers "F.Cu" "F.Mask" "F.Paste")
			(net "M_G_CPU1_SA_DQ<25>")
		)
		(pad "43" smd rect
			(at -2.050034 -27.62504 270)
			(size 0.519938 1.4986)
			(layers "F.Cu" "F.Mask" "F.Paste")
			(net "GND")
		)
		(pad "44" smd rect
			(at -2.050034 -26.774902 270)
			(size 0.519938 1.4986)
			(layers "F.Cu" "F.Mask" "F.Paste")
			(net "M_G_CPU1_SA_DQS_DP<3>")
		)
		(pad "45" smd rect
			(at -2.050034 -25.925018 270)
			(size 0.519938 1.4986)
			(layers "F.Cu" "F.Mask" "F.Paste")
			(net "M_G_CPU1_SA_DQS_DN<3>")
		)
		(pad "46" smd rect
			(at -2.050034 -25.07488 270)
			(size 0.519938 1.4986)
			(layers "F.Cu" "F.Mask" "F.Paste")
			(net "GND")
		)
		(pad "47" smd rect
			(at -2.050034 -24.224996 270)
			(size 0.519938 1.4986)
			(layers "F.Cu" "F.Mask" "F.Paste")
			(net "M_G_CPU1_SA_DQ<28>")
		)
		(pad "48" smd rect
			(at -2.050034 -23.375112 270)
			(size 0.519938 1.4986)
			(layers "F.Cu" "F.Mask" "F.Paste")
			(net "GND")
		)
		(pad "49" smd rect
			(at -2.050034 -22.524974 270)
			(size 0.519938 1.4986)
			(layers "F.Cu" "F.Mask" "F.Paste")
			(net "M_G_CPU1_SA_DQ<29>")
		)
		(pad "50" smd rect
			(at -2.050034 -21.67509 270)
			(size 0.519938 1.4986)
			(layers "F.Cu" "F.Mask" "F.Paste")
			(net "GND")
		)
		(pad "51" smd rect
			(at -2.050034 -20.824952 270)
			(size 0.519938 1.4986)
			(layers "F.Cu" "F.Mask" "F.Paste")
			(net "M_G_CPU1_SA_CB<0>")
		)
		(pad "52" smd rect
			(at -2.050034 -19.975068 270)
			(size 0.519938 1.4986)
			(layers "F.Cu" "F.Mask" "F.Paste")
			(net "GND")
		)
		(pad "53" smd rect
			(at -2.050034 -19.12493 270)
			(size 0.519938 1.4986)
			(layers "F.Cu" "F.Mask" "F.Paste")
			(net "M_G_CPU1_SA_CB<1>")
		)
		(pad "54" smd rect
			(at -2.050034 -18.275046 270)
			(size 0.519938 1.4986)
			(layers "F.Cu" "F.Mask" "F.Paste")
			(net "GND")
		)
		(pad "55" smd rect
			(at -2.050034 -17.424908 270)
			(size 0.519938 1.4986)
			(layers "F.Cu" "F.Mask" "F.Paste")
			(net "M_G_CPU1_SA_DQS_DP<4>")
		)
		(pad "56" smd rect
			(at -2.050034 -16.575024 270)
			(size 0.519938 1.4986)
			(layers "F.Cu" "F.Mask" "F.Paste")
			(net "M_G_CPU1_SA_DQS_DN<4>")
		)
		(pad "57" smd rect
			(at -2.050034 -15.724886 270)
			(size 0.519938 1.4986)
			(layers "F.Cu" "F.Mask" "F.Paste")
			(net "GND")
		)
		(pad "58" smd rect
			(at -2.050034 -14.875002 270)
			(size 0.519938 1.4986)
			(layers "F.Cu" "F.Mask" "F.Paste")
			(net "M_G_CPU1_SA_CB<4>")
		)
		(pad "59" smd rect
			(at -2.050034 -14.025118 270)
			(size 0.519938 1.4986)
			(layers "F.Cu" "F.Mask" "F.Paste")
			(net "GND")
		)
		(pad "60" smd rect
			(at -2.050034 -13.17498 270)
			(size 0.519938 1.4986)
			(layers "F.Cu" "F.Mask" "F.Paste")
			(net "M_G_CPU1_SA_CB<5>")
		)
		(pad "61" smd rect
			(at -2.050034 -12.325096 270)
			(size 0.519938 1.4986)
			(layers "F.Cu" "F.Mask" "F.Paste")
			(net "GND")
		)
		(pad "62" smd rect
			(at -2.050034 -11.474958 270)
			(size 0.519938 1.4986)
			(layers "F.Cu" "F.Mask" "F.Paste")
			(net "M_G_CPU1_ALERT_N")
		)
		(pad "63" smd rect
			(at -2.050034 -10.625074 270)
			(size 0.519938 1.4986)
			(layers "F.Cu" "F.Mask" "F.Paste")
			(net "GND")
		)
		(pad "64" smd rect
			(at -2.050034 -9.774936 270)
			(size 0.519938 1.4986)
			(layers "F.Cu" "F.Mask" "F.Paste")
			(net "M_G_CPU1_SA_CS_N<0>")
		)
		(pad "65" smd rect
			(at -2.050034 -8.925052 270)
			(size 0.519938 1.4986)
			(layers "F.Cu" "F.Mask" "F.Paste")
			(net "GND")
		)
		(pad "66" smd rect
			(at -2.050034 -8.074914 270)
			(size 0.519938 1.4986)
			(layers "F.Cu" "F.Mask" "F.Paste")
			(net "M_G_CPU1_SA_CA<0>")
		)
		(pad "67" smd rect
			(at -2.050034 -7.22503 270)
			(size 0.519938 1.4986)
			(layers "F.Cu" "F.Mask" "F.Paste")
			(net "GND")
		)
		(pad "68" smd rect
			(at -2.050034 -6.374892 270)
			(size 0.519938 1.4986)
			(layers "F.Cu" "F.Mask" "F.Paste")
			(net "M_G_CPU1_SA_CA<2>")
		)
		(pad "69" smd rect
			(at -2.050034 -5.525008 270)
			(size 0.519938 1.4986)
			(layers "F.Cu" "F.Mask" "F.Paste")
			(net "GND")
		)
		(pad "70" smd rect
			(at -2.050034 -4.675124 270)
			(size 0.519938 1.4986)
			(layers "F.Cu" "F.Mask" "F.Paste")
			(net "M_G_CPU1_SA_CA<4>")
		)
		(pad "71" smd rect
			(at -2.050034 -3.824986 270)
			(size 0.519938 1.4986)
			(layers "F.Cu" "F.Mask" "F.Paste")
			(net "GND")
		)
		(pad "72" smd rect
			(at -2.050034 -2.975102 270)
			(size 0.519938 1.4986)
			(layers "F.Cu" "F.Mask" "F.Paste")
			(net "M_G_CPU1_SA_CA<6>")
		)
		(pad "73" smd rect
			(at -2.050034 -2.124964 270)
			(size 0.519938 1.4986)
			(layers "F.Cu" "F.Mask" "F.Paste")
			(net "GND")
		)
		(pad "74" smd rect
			(at -2.050034 -1.27508 270)
			(size 0.519938 1.4986)
			(layers "F.Cu" "F.Mask" "F.Paste")
			(net "M_G_CPU1_SA_PAR")
		)
		(pad "75" smd rect
			(at -2.050034 -0.424942 270)
			(size 0.519938 1.4986)
			(layers "F.Cu" "F.Mask" "F.Paste")
			(net "GND")
		)
		(pad "76" smd rect
			(at -2.050034 5.525008 270)
			(size 0.519938 1.4986)
			(layers "F.Cu" "F.Mask" "F.Paste")
			(net "M_G_CPU1_SB_CA<0>")
		)
		(pad "77" smd rect
			(at -2.050034 6.374892 270)
			(size 0.519938 1.4986)
			(layers "F.Cu" "F.Mask" "F.Paste")
			(net "GND")
		)
		(pad "78" smd rect
			(at -2.050034 7.22503 270)
			(size 0.519938 1.4986)
			(layers "F.Cu" "F.Mask" "F.Paste")
			(net "M_G_CPU1_SB_CA<2>")
		)
		(pad "79" smd rect
			(at -2.050034 8.074914 270)
			(size 0.519938 1.4986)
			(layers "F.Cu" "F.Mask" "F.Paste")
			(net "GND")
		)
		(pad "80" smd rect
			(at -2.050034 8.925052 270)
			(size 0.519938 1.4986)
			(layers "F.Cu" "F.Mask" "F.Paste")
			(net "M_G_CPU1_SB_CA<4>")
		)
		(pad "81" smd rect
			(at -2.050034 9.774936 270)
			(size 0.519938 1.4986)
			(layers "F.Cu" "F.Mask" "F.Paste")
			(net "GND")
		)
		(pad "82" smd rect
			(at -2.050034 10.625074 270)
			(size 0.519938 1.4986)
			(layers "F.Cu" "F.Mask" "F.Paste")
			(net "M_G_CPU1_SB_CA<6>")
		)
		(pad "83" smd rect
			(at -2.050034 11.474958 270)
			(size 0.519938 1.4986)
			(layers "F.Cu" "F.Mask" "F.Paste")
			(net "GND")
		)
		(pad "84" smd rect
			(at -2.050034 12.325096 270)
			(size 0.519938 1.4986)
			(layers "F.Cu" "F.Mask" "F.Paste")
			(net "M_G_CPU1_SB_CS_N<0>")
		)
		(pad "85" smd rect
			(at -2.050034 13.17498 270)
			(size 0.519938 1.4986)
			(layers "F.Cu" "F.Mask" "F.Paste")
			(net "GND")
		)
		(pad "86" smd rect
			(at -2.050034 14.025118 270)
			(size 0.519938 1.4986)
			(layers "F.Cu" "F.Mask" "F.Paste")
			(net "M_G_CPU1_SA_RSP<0>")
		)
		(pad "87" smd rect
			(at -2.050034 14.875002 270)
			(size 0.519938 1.4986)
			(layers "F.Cu" "F.Mask" "F.Paste")
			(net "M_G_CPU1_SB_RSP<0>")
		)
		(pad "88" smd rect
			(at -2.050034 15.724886 270)
			(size 0.519938 1.4986)
			(layers "F.Cu" "F.Mask" "F.Paste")
			(net "GND")
		)
		(pad "89" smd rect
			(at -2.050034 16.575024 270)
			(size 0.519938 1.4986)
			(layers "F.Cu" "F.Mask" "F.Paste")
			(net "M_G_CPU1_SB_CB<4>")
		)
		(pad "90" smd rect
			(at -2.050034 17.424908 270)
			(size 0.519938 1.4986)
			(layers "F.Cu" "F.Mask" "F.Paste")
			(net "GND")
		)
		(pad "91" smd rect
			(at -2.050034 18.275046 270)
			(size 0.519938 1.4986)
			(layers "F.Cu" "F.Mask" "F.Paste")
			(net "M_G_CPU1_SB_CB<5>")
		)
		(pad "92" smd rect
			(at -2.050034 19.12493 270)
			(size 0.519938 1.4986)
			(layers "F.Cu" "F.Mask" "F.Paste")
			(net "GND")
		)
		(pad "93" smd rect
			(at -2.050034 19.975068 270)
			(size 0.519938 1.4986)
			(layers "F.Cu" "F.Mask" "F.Paste")
			(net "M_G_CPU1_SB_DQS_DP<9>")
		)
		(pad "94" smd rect
			(at -2.050034 20.824952 270)
			(size 0.519938 1.4986)
			(layers "F.Cu" "F.Mask" "F.Paste")
			(net "M_G_CPU1_SB_DQS_DN<9>")
		)
		(pad "95" smd rect
			(at -2.050034 21.67509 270)
			(size 0.519938 1.4986)
			(layers "F.Cu" "F.Mask" "F.Paste")
			(net "GND")
		)
		(pad "96" smd rect
			(at -2.050034 22.524974 270)
			(size 0.519938 1.4986)
			(layers "F.Cu" "F.Mask" "F.Paste")
			(net "M_G_CPU1_SB_CB<0>")
		)
		(pad "97" smd rect
			(at -2.050034 23.375112 270)
			(size 0.519938 1.4986)
			(layers "F.Cu" "F.Mask" "F.Paste")
			(net "GND")
		)
		(pad "98" smd rect
			(at -2.050034 24.224996 270)
			(size 0.519938 1.4986)
			(layers "F.Cu" "F.Mask" "F.Paste")
			(net "M_G_CPU1_SB_CB<1>")
		)
		(pad "99" smd rect
			(at -2.050034 25.07488 270)
			(size 0.519938 1.4986)
			(layers "F.Cu" "F.Mask" "F.Paste")
			(net "GND")
		)
		(pad "100" smd rect
			(at -2.050034 25.925018 270)
			(size 0.519938 1.4986)
			(layers "F.Cu" "F.Mask" "F.Paste")
			(net "M_G_CPU1_SB_DQ<0>")
		)
		(pad "101" smd rect
			(at -2.050034 26.774902 270)
			(size 0.519938 1.4986)
			(layers "F.Cu" "F.Mask" "F.Paste")
			(net "GND")
		)
		(pad "102" smd rect
			(at -2.050034 27.62504 270)
			(size 0.519938 1.4986)
			(layers "F.Cu" "F.Mask" "F.Paste")
			(net "M_G_CPU1_SB_DQ<1>")
		)
		(pad "103" smd rect
			(at -2.050034 28.474924 270)
			(size 0.519938 1.4986)
			(layers "F.Cu" "F.Mask" "F.Paste")
			(net "GND")
		)
		(pad "104" smd rect
			(at -2.050034 29.325062 270)
			(size 0.519938 1.4986)
			(layers "F.Cu" "F.Mask" "F.Paste")
			(net "M_G_CPU1_SB_DQS_DP<0>")
		)
		(pad "105" smd rect
			(at -2.050034 30.174946 270)
			(size 0.519938 1.4986)
			(layers "F.Cu" "F.Mask" "F.Paste")
			(net "M_G_CPU1_SB_DQS_DN<0>")
		)
		(pad "106" smd rect
			(at -2.050034 31.025084 270)
			(size 0.519938 1.4986)
			(layers "F.Cu" "F.Mask" "F.Paste")
			(net "GND")
		)
		(pad "107" smd rect
			(at -2.050034 31.874968 270)
			(size 0.519938 1.4986)
			(layers "F.Cu" "F.Mask" "F.Paste")
			(net "M_G_CPU1_SB_DQ<4>")
		)
		(pad "108" smd rect
			(at -2.050034 32.725106 270)
			(size 0.519938 1.4986)
			(layers "F.Cu" "F.Mask" "F.Paste")
			(net "GND")
		)
		(pad "109" smd rect
			(at -2.050034 33.57499 270)
			(size 0.519938 1.4986)
			(layers "F.Cu" "F.Mask" "F.Paste")
			(net "M_G_CPU1_SB_DQ<5>")
		)
		(pad "110" smd rect
			(at -2.050034 34.425128 270)
			(size 0.519938 1.4986)
			(layers "F.Cu" "F.Mask" "F.Paste")
			(net "GND")
		)
		(pad "111" smd rect
			(at -2.050034 35.275012 270)
			(size 0.519938 1.4986)
			(layers "F.Cu" "F.Mask" "F.Paste")
			(net "M_G_CPU1_SB_DQ<8>")
		)
		(pad "112" smd rect
			(at -2.050034 36.124896 270)
			(size 0.519938 1.4986)
			(layers "F.Cu" "F.Mask" "F.Paste")
			(net "GND")
		)
		(pad "113" smd rect
			(at -2.050034 36.975034 270)
			(size 0.519938 1.4986)
			(layers "F.Cu" "F.Mask" "F.Paste")
			(net "M_G_CPU1_SB_DQ<9>")
		)
		(pad "114" smd rect
			(at -2.050034 37.824918 270)
			(size 0.519938 1.4986)
			(layers "F.Cu" "F.Mask" "F.Paste")
			(net "GND")
		)
		(pad "115" smd rect
			(at -2.050034 38.675056 270)
			(size 0.519938 1.4986)
			(layers "F.Cu" "F.Mask" "F.Paste")
			(net "M_G_CPU1_SB_DQS_DP<1>")
		)
		(pad "116" smd rect
			(at -2.050034 39.52494 270)
			(size 0.519938 1.4986)
			(layers "F.Cu" "F.Mask" "F.Paste")
			(net "M_G_CPU1_SB_DQS_DN<1>")
		)
		(pad "117" smd rect
			(at -2.050034 40.375078 270)
			(size 0.519938 1.4986)
			(layers "F.Cu" "F.Mask" "F.Paste")
			(net "GND")
		)
		(pad "118" smd rect
			(at -2.050034 41.224962 270)
			(size 0.519938 1.4986)
			(layers "F.Cu" "F.Mask" "F.Paste")
			(net "M_G_CPU1_SB_DQ<12>")
		)
		(pad "119" smd rect
			(at -2.050034 42.0751 270)
			(size 0.519938 1.4986)
			(layers "F.Cu" "F.Mask" "F.Paste")
			(net "GND")
		)
		(pad "120" smd rect
			(at -2.050034 42.924984 270)
			(size 0.519938 1.4986)
			(layers "F.Cu" "F.Mask" "F.Paste")
			(net "M_G_CPU1_SB_DQ<13>")
		)
		(pad "121" smd rect
			(at -2.050034 43.775122 270)
			(size 0.519938 1.4986)
			(layers "F.Cu" "F.Mask" "F.Paste")
			(net "GND")
		)
		(pad "122" smd rect
			(at -2.050034 44.625006 270)
			(size 0.519938 1.4986)
			(layers "F.Cu" "F.Mask" "F.Paste")
			(net "M_G_CPU1_SB_DQ<16>")
		)
		(pad "123" smd rect
			(at -2.050034 45.47489 270)
			(size 0.519938 1.4986)
			(layers "F.Cu" "F.Mask" "F.Paste")
			(net "GND")
		)
		(pad "124" smd rect
			(at -2.050034 46.325028 270)
			(size 0.519938 1.4986)
			(layers "F.Cu" "F.Mask" "F.Paste")
			(net "M_G_CPU1_SB_DQ<17>")
		)
		(pad "125" smd rect
			(at -2.050034 47.174912 270)
			(size 0.519938 1.4986)
			(layers "F.Cu" "F.Mask" "F.Paste")
			(net "GND")
		)
		(pad "126" smd rect
			(at -2.050034 48.02505 270)
			(size 0.519938 1.4986)
			(layers "F.Cu" "F.Mask" "F.Paste")
			(net "M_G_CPU1_SB_DQS_DP<2>")
		)
		(pad "127" smd rect
			(at -2.050034 48.874934 270)
			(size 0.519938 1.4986)
			(layers "F.Cu" "F.Mask" "F.Paste")
			(net "M_G_CPU1_SB_DQS_DN<2>")
		)
		(pad "128" smd rect
			(at -2.050034 49.725072 270)
			(size 0.519938 1.4986)
			(layers "F.Cu" "F.Mask" "F.Paste")
			(net "GND")
		)
		(pad "129" smd rect
			(at -2.050034 50.574956 270)
			(size 0.519938 1.4986)
			(layers "F.Cu" "F.Mask" "F.Paste")
			(net "M_G_CPU1_SB_DQ<20>")
		)
		(pad "130" smd rect
			(at -2.050034 51.425094 270)
			(size 0.519938 1.4986)
			(layers "F.Cu" "F.Mask" "F.Paste")
			(net "GND")
		)
		(pad "131" smd rect
			(at -2.050034 52.274978 270)
			(size 0.519938 1.4986)
			(layers "F.Cu" "F.Mask" "F.Paste")
			(net "M_G_CPU1_SB_DQ<21>")
		)
		(pad "132" smd rect
			(at -2.050034 53.125116 270)
			(size 0.519938 1.4986)
			(layers "F.Cu" "F.Mask" "F.Paste")
			(net "GND")
		)
		(pad "133" smd rect
			(at -2.050034 53.975 270)
			(size 0.519938 1.4986)
			(layers "F.Cu" "F.Mask" "F.Paste")
			(net "M_G_CPU1_SB_DQ<24>")
		)
		(pad "134" smd rect
			(at -2.050034 54.824884 270)
			(size 0.519938 1.4986)
			(layers "F.Cu" "F.Mask" "F.Paste")
			(net "GND")
		)
		(pad "135" smd rect
			(at -2.050034 55.675022 270)
			(size 0.519938 1.4986)
			(layers "F.Cu" "F.Mask" "F.Paste")
			(net "M_G_CPU1_SB_DQ<25>")
		)
		(pad "136" smd rect
			(at -2.050034 56.524906 270)
			(size 0.519938 1.4986)
			(layers "F.Cu" "F.Mask" "F.Paste")
			(net "GND")
		)
		(pad "137" smd rect
			(at -2.050034 57.375044 270)
			(size 0.519938 1.4986)
			(layers "F.Cu" "F.Mask" "F.Paste")
			(net "M_G_CPU1_SB_DQS_DP<3>")
		)
		(pad "138" smd rect
			(at -2.050034 58.224928 270)
			(size 0.519938 1.4986)
			(layers "F.Cu" "F.Mask" "F.Paste")
			(net "M_G_CPU1_SB_DQS_DN<3>")
		)
		(pad "139" smd rect
			(at -2.050034 59.075066 270)
			(size 0.519938 1.4986)
			(layers "F.Cu" "F.Mask" "F.Paste")
			(net "GND")
		)
		(pad "140" smd rect
			(at -2.050034 59.92495 270)
			(size 0.519938 1.4986)
			(layers "F.Cu" "F.Mask" "F.Paste")
			(net "M_G_CPU1_SB_DQ<28>")
		)
		(pad "141" smd rect
			(at -2.050034 60.775088 270)
			(size 0.519938 1.4986)
			(layers "F.Cu" "F.Mask" "F.Paste")
			(net "GND")
		)
		(pad "142" smd rect
			(at -2.050034 61.624972 270)
			(size 0.519938 1.4986)
			(layers "F.Cu" "F.Mask" "F.Paste")
			(net "M_G_CPU1_SB_DQ<29>")
		)
		(pad "143" smd rect
			(at -2.050034 62.47511 270)
			(size 0.519938 1.4986)
			(layers "F.Cu" "F.Mask" "F.Paste")
			(net "GND")
		)
		(pad "144" smd rect
			(at -2.050034 63.324994 270)
			(size 0.519938 1.4986)
			(layers "F.Cu" "F.Mask" "F.Paste")
			(net "TP_CHG_CPU1_DIMM1_FRU_1")
		)
		(pad "145" smd rect
			(at 2.050034 -63.324994 270)
			(size 0.519938 1.4986)
			(layers "F.Cu" "F.Mask" "F.Paste")
			(net "P12V_S3_AUX_CPU1_NVDIMM")
		)
		(pad "146" smd rect
			(at 2.050034 -62.47511 270)
			(size 0.519938 1.4986)
			(layers "F.Cu" "F.Mask" "F.Paste")
			(net "P12V_S3_AUX_CPU1_NVDIMM")
		)
		(pad "147" smd rect
			(at 2.050034 -61.624972 270)
			(size 0.519938 1.4986)
			(layers "F.Cu" "F.Mask" "F.Paste")
			(net "PWRGD_CHG_CPU1_DIMM1")
		)
		(pad "148" smd rect
			(at 2.050034 -60.775088 270)
			(size 0.519938 1.4986)
			(layers "F.Cu" "F.Mask" "F.Paste")
			(net "PD_CHG_CPU1_DIMM1_SAA")
		)
		(pad "149" smd rect
			(at 2.050034 -59.92495 270)
			(size 0.519938 1.4986)
			(layers "F.Cu" "F.Mask" "F.Paste")
			(net "TP_CHG_CPU1_DIMM1_FRU_2")
		)
		(pad "150" smd rect
			(at 2.050034 -59.075066 270)
			(size 0.519938 1.4986)
			(layers "F.Cu" "F.Mask" "F.Paste")
			(net "TP_CHG_CPU1_DIMM1_FRU_3")
		)
		(pad "151" smd rect
			(at 2.050034 -58.224928 270)
			(size 0.519938 1.4986)
			(layers "F.Cu" "F.Mask" "F.Paste")
			(net "GND")
		)
		(pad "152" smd rect
			(at 2.050034 -57.375044 270)
			(size 0.519938 1.4986)
			(layers "F.Cu" "F.Mask" "F.Paste")
			(net "M_G_CPU1_SA_DQ<2>")
		)
		(pad "153" smd rect
			(at 2.050034 -56.524906 270)
			(size 0.519938 1.4986)
			(layers "F.Cu" "F.Mask" "F.Paste")
			(net "GND")
		)
		(pad "154" smd rect
			(at 2.050034 -55.675022 270)
			(size 0.519938 1.4986)
			(layers "F.Cu" "F.Mask" "F.Paste")
			(net "M_G_CPU1_SA_DQ<3>")
		)
		(pad "155" smd rect
			(at 2.050034 -54.824884 270)
			(size 0.519938 1.4986)
			(layers "F.Cu" "F.Mask" "F.Paste")
			(net "GND")
		)
		(pad "156" smd rect
			(at 2.050034 -53.975 270)
			(size 0.519938 1.4986)
			(layers "F.Cu" "F.Mask" "F.Paste")
			(net "M_G_CPU1_SA_DQS_DN<5>")
		)
		(pad "157" smd rect
			(at 2.050034 -53.125116 270)
			(size 0.519938 1.4986)
			(layers "F.Cu" "F.Mask" "F.Paste")
			(net "M_G_CPU1_SA_DQS_DP<5>")
		)
		(pad "158" smd rect
			(at 2.050034 -52.274978 270)
			(size 0.519938 1.4986)
			(layers "F.Cu" "F.Mask" "F.Paste")
			(net "GND")
		)
		(pad "159" smd rect
			(at 2.050034 -51.425094 270)
			(size 0.519938 1.4986)
			(layers "F.Cu" "F.Mask" "F.Paste")
			(net "M_G_CPU1_SA_DQ<6>")
		)
		(pad "160" smd rect
			(at 2.050034 -50.574956 270)
			(size 0.519938 1.4986)
			(layers "F.Cu" "F.Mask" "F.Paste")
			(net "GND")
		)
		(pad "161" smd rect
			(at 2.050034 -49.725072 270)
			(size 0.519938 1.4986)
			(layers "F.Cu" "F.Mask" "F.Paste")
			(net "M_G_CPU1_SA_DQ<7>")
		)
		(pad "162" smd rect
			(at 2.050034 -48.874934 270)
			(size 0.519938 1.4986)
			(layers "F.Cu" "F.Mask" "F.Paste")
			(net "GND")
		)
		(pad "163" smd rect
			(at 2.050034 -48.02505 270)
			(size 0.519938 1.4986)
			(layers "F.Cu" "F.Mask" "F.Paste")
			(net "M_G_CPU1_SA_DQ<10>")
		)
		(pad "164" smd rect
			(at 2.050034 -47.174912 270)
			(size 0.519938 1.4986)
			(layers "F.Cu" "F.Mask" "F.Paste")
			(net "GND")
		)
		(pad "165" smd rect
			(at 2.050034 -46.325028 270)
			(size 0.519938 1.4986)
			(layers "F.Cu" "F.Mask" "F.Paste")
			(net "M_G_CPU1_SA_DQ<11>")
		)
		(pad "166" smd rect
			(at 2.050034 -45.47489 270)
			(size 0.519938 1.4986)
			(layers "F.Cu" "F.Mask" "F.Paste")
			(net "GND")
		)
		(pad "167" smd rect
			(at 2.050034 -44.625006 270)
			(size 0.519938 1.4986)
			(layers "F.Cu" "F.Mask" "F.Paste")
			(net "M_G_CPU1_SA_DQS_DN<6>")
		)
		(pad "168" smd rect
			(at 2.050034 -43.775122 270)
			(size 0.519938 1.4986)
			(layers "F.Cu" "F.Mask" "F.Paste")
			(net "M_G_CPU1_SA_DQS_DP<6>")
		)
		(pad "169" smd rect
			(at 2.050034 -42.924984 270)
			(size 0.519938 1.4986)
			(layers "F.Cu" "F.Mask" "F.Paste")
			(net "GND")
		)
		(pad "170" smd rect
			(at 2.050034 -42.0751 270)
			(size 0.519938 1.4986)
			(layers "F.Cu" "F.Mask" "F.Paste")
			(net "M_G_CPU1_SA_DQ<14>")
		)
		(pad "171" smd rect
			(at 2.050034 -41.224962 270)
			(size 0.519938 1.4986)
			(layers "F.Cu" "F.Mask" "F.Paste")
			(net "GND")
		)
		(pad "172" smd rect
			(at 2.050034 -40.375078 270)
			(size 0.519938 1.4986)
			(layers "F.Cu" "F.Mask" "F.Paste")
			(net "M_G_CPU1_SA_DQ<15>")
		)
		(pad "173" smd rect
			(at 2.050034 -39.52494 270)
			(size 0.519938 1.4986)
			(layers "F.Cu" "F.Mask" "F.Paste")
			(net "GND")
		)
		(pad "174" smd rect
			(at 2.050034 -38.675056 270)
			(size 0.519938 1.4986)
			(layers "F.Cu" "F.Mask" "F.Paste")
			(net "M_G_CPU1_SA_DQ<18>")
		)
		(pad "175" smd rect
			(at 2.050034 -37.824918 270)
			(size 0.519938 1.4986)
			(layers "F.Cu" "F.Mask" "F.Paste")
			(net "GND")
		)
		(pad "176" smd rect
			(at 2.050034 -36.975034 270)
			(size 0.519938 1.4986)
			(layers "F.Cu" "F.Mask" "F.Paste")
			(net "M_G_CPU1_SA_DQ<19>")
		)
		(pad "177" smd rect
			(at 2.050034 -36.124896 270)
			(size 0.519938 1.4986)
			(layers "F.Cu" "F.Mask" "F.Paste")
			(net "GND")
		)
		(pad "178" smd rect
			(at 2.050034 -35.275012 270)
			(size 0.519938 1.4986)
			(layers "F.Cu" "F.Mask" "F.Paste")
			(net "M_G_CPU1_SA_DQS_DN<7>")
		)
		(pad "179" smd rect
			(at 2.050034 -34.425128 270)
			(size 0.519938 1.4986)
			(layers "F.Cu" "F.Mask" "F.Paste")
			(net "M_G_CPU1_SA_DQS_DP<7>")
		)
		(pad "180" smd rect
			(at 2.050034 -33.57499 270)
			(size 0.519938 1.4986)
			(layers "F.Cu" "F.Mask" "F.Paste")
			(net "GND")
		)
		(pad "181" smd rect
			(at 2.050034 -32.725106 270)
			(size 0.519938 1.4986)
			(layers "F.Cu" "F.Mask" "F.Paste")
			(net "M_G_CPU1_SA_DQ<22>")
		)
		(pad "182" smd rect
			(at 2.050034 -31.874968 270)
			(size 0.519938 1.4986)
			(layers "F.Cu" "F.Mask" "F.Paste")
			(net "GND")
		)
		(pad "183" smd rect
			(at 2.050034 -31.025084 270)
			(size 0.519938 1.4986)
			(layers "F.Cu" "F.Mask" "F.Paste")
			(net "M_G_CPU1_SA_DQ<23>")
		)
		(pad "184" smd rect
			(at 2.050034 -30.174946 270)
			(size 0.519938 1.4986)
			(layers "F.Cu" "F.Mask" "F.Paste")
			(net "GND")
		)
		(pad "185" smd rect
			(at 2.050034 -29.325062 270)
			(size 0.519938 1.4986)
			(layers "F.Cu" "F.Mask" "F.Paste")
			(net "M_G_CPU1_SA_DQ<26>")
		)
		(pad "186" smd rect
			(at 2.050034 -28.474924 270)
			(size 0.519938 1.4986)
			(layers "F.Cu" "F.Mask" "F.Paste")
			(net "GND")
		)
		(pad "187" smd rect
			(at 2.050034 -27.62504 270)
			(size 0.519938 1.4986)
			(layers "F.Cu" "F.Mask" "F.Paste")
			(net "M_G_CPU1_SA_DQ<27>")
		)
		(pad "188" smd rect
			(at 2.050034 -26.774902 270)
			(size 0.519938 1.4986)
			(layers "F.Cu" "F.Mask" "F.Paste")
			(net "GND")
		)
		(pad "189" smd rect
			(at 2.050034 -25.925018 270)
			(size 0.519938 1.4986)
			(layers "F.Cu" "F.Mask" "F.Paste")
			(net "M_G_CPU1_SA_DQS_DN<8>")
		)
		(pad "190" smd rect
			(at 2.050034 -25.07488 270)
			(size 0.519938 1.4986)
			(layers "F.Cu" "F.Mask" "F.Paste")
			(net "M_G_CPU1_SA_DQS_DP<8>")
		)
		(pad "191" smd rect
			(at 2.050034 -24.224996 270)
			(size 0.519938 1.4986)
			(layers "F.Cu" "F.Mask" "F.Paste")
			(net "GND")
		)
		(pad "192" smd rect
			(at 2.050034 -23.375112 270)
			(size 0.519938 1.4986)
			(layers "F.Cu" "F.Mask" "F.Paste")
			(net "M_G_CPU1_SA_DQ<30>")
		)
		(pad "193" smd rect
			(at 2.050034 -22.524974 270)
			(size 0.519938 1.4986)
			(layers "F.Cu" "F.Mask" "F.Paste")
			(net "GND")
		)
		(pad "194" smd rect
			(at 2.050034 -21.67509 270)
			(size 0.519938 1.4986)
			(layers "F.Cu" "F.Mask" "F.Paste")
			(net "M_G_CPU1_SA_DQ<31>")
		)
		(pad "195" smd rect
			(at 2.050034 -20.824952 270)
			(size 0.519938 1.4986)
			(layers "F.Cu" "F.Mask" "F.Paste")
			(net "GND")
		)
		(pad "196" smd rect
			(at 2.050034 -19.975068 270)
			(size 0.519938 1.4986)
			(layers "F.Cu" "F.Mask" "F.Paste")
			(net "M_G_CPU1_SA_CB<2>")
		)
		(pad "197" smd rect
			(at 2.050034 -19.12493 270)
			(size 0.519938 1.4986)
			(layers "F.Cu" "F.Mask" "F.Paste")
			(net "GND")
		)
		(pad "198" smd rect
			(at 2.050034 -18.275046 270)
			(size 0.519938 1.4986)
			(layers "F.Cu" "F.Mask" "F.Paste")
			(net "M_G_CPU1_SA_CB<3>")
		)
		(pad "199" smd rect
			(at 2.050034 -17.424908 270)
			(size 0.519938 1.4986)
			(layers "F.Cu" "F.Mask" "F.Paste")
			(net "GND")
		)
		(pad "200" smd rect
			(at 2.050034 -16.575024 270)
			(size 0.519938 1.4986)
			(layers "F.Cu" "F.Mask" "F.Paste")
			(net "M_G_CPU1_SA_DQS_DN<9>")
		)
		(pad "201" smd rect
			(at 2.050034 -15.724886 270)
			(size 0.519938 1.4986)
			(layers "F.Cu" "F.Mask" "F.Paste")
			(net "M_G_CPU1_SA_DQS_DP<9>")
		)
		(pad "202" smd rect
			(at 2.050034 -14.875002 270)
			(size 0.519938 1.4986)
			(layers "F.Cu" "F.Mask" "F.Paste")
			(net "GND")
		)
		(pad "203" smd rect
			(at 2.050034 -14.025118 270)
			(size 0.519938 1.4986)
			(layers "F.Cu" "F.Mask" "F.Paste")
			(net "M_G_CPU1_SA_CB<6>")
		)
		(pad "204" smd rect
			(at 2.050034 -13.17498 270)
			(size 0.519938 1.4986)
			(layers "F.Cu" "F.Mask" "F.Paste")
			(net "GND")
		)
		(pad "205" smd rect
			(at 2.050034 -12.325096 270)
			(size 0.519938 1.4986)
			(layers "F.Cu" "F.Mask" "F.Paste")
			(net "M_G_CPU1_SA_CB<7>")
		)
		(pad "206" smd rect
			(at 2.050034 -11.474958 270)
			(size 0.519938 1.4986)
			(layers "F.Cu" "F.Mask" "F.Paste")
			(net "GND")
		)
		(pad "207" smd rect
			(at 2.050034 -10.625074 270)
			(size 0.519938 1.4986)
			(layers "F.Cu" "F.Mask" "F.Paste")
			(net "RST_M_GH_CPU1_FPGA_N")
		)
		(pad "208" smd rect
			(at 2.050034 -9.774936 270)
			(size 0.519938 1.4986)
			(layers "F.Cu" "F.Mask" "F.Paste")
			(net "GND")
		)
		(pad "209" smd rect
			(at 2.050034 -8.925052 270)
			(size 0.519938 1.4986)
			(layers "F.Cu" "F.Mask" "F.Paste")
			(net "M_G_CPU1_SA_CS_N<1>")
		)
		(pad "210" smd rect
			(at 2.050034 -8.074914 270)
			(size 0.519938 1.4986)
			(layers "F.Cu" "F.Mask" "F.Paste")
			(net "GND")
		)
		(pad "211" smd rect
			(at 2.050034 -7.22503 270)
			(size 0.519938 1.4986)
			(layers "F.Cu" "F.Mask" "F.Paste")
			(net "M_G_CPU1_SA_CA<1>")
		)
		(pad "212" smd rect
			(at 2.050034 -6.374892 270)
			(size 0.519938 1.4986)
			(layers "F.Cu" "F.Mask" "F.Paste")
			(net "GND")
		)
		(pad "213" smd rect
			(at 2.050034 -5.525008 270)
			(size 0.519938 1.4986)
			(layers "F.Cu" "F.Mask" "F.Paste")
			(net "M_G_CPU1_SA_CA<3>")
		)
		(pad "214" smd rect
			(at 2.050034 -4.675124 270)
			(size 0.519938 1.4986)
			(layers "F.Cu" "F.Mask" "F.Paste")
			(net "GND")
		)
		(pad "215" smd rect
			(at 2.050034 -3.824986 270)
			(size 0.519938 1.4986)
			(layers "F.Cu" "F.Mask" "F.Paste")
			(net "M_G_CPU1_SA_CA<5>")
		)
		(pad "216" smd rect
			(at 2.050034 -2.975102 270)
			(size 0.519938 1.4986)
			(layers "F.Cu" "F.Mask" "F.Paste")
			(net "GND")
		)
		(pad "217" smd rect
			(at 2.050034 -2.124964 270)
			(size 0.519938 1.4986)
			(layers "F.Cu" "F.Mask" "F.Paste")
			(net "M_G_CPU1_CLK_DP<0>")
		)
		(pad "218" smd rect
			(at 2.050034 -1.27508 270)
			(size 0.519938 1.4986)
			(layers "F.Cu" "F.Mask" "F.Paste")
			(net "M_G_CPU1_CLK_DN<0>")
		)
		(pad "219" smd rect
			(at 2.050034 -0.424942 270)
			(size 0.519938 1.4986)
			(layers "F.Cu" "F.Mask" "F.Paste")
			(net "GND")
		)
		(pad "220" smd rect
			(at 2.050034 5.525008 270)
			(size 0.519938 1.4986)
			(layers "F.Cu" "F.Mask" "F.Paste")
			(net "TP_CHG_CPU1_DIMM1_FRU_4")
		)
		(pad "221" smd rect
			(at 2.050034 6.374892 270)
			(size 0.519938 1.4986)
			(layers "F.Cu" "F.Mask" "F.Paste")
			(net "M_G_CPU1_SB_CA<1>")
		)
		(pad "222" smd rect
			(at 2.050034 7.22503 270)
			(size 0.519938 1.4986)
			(layers "F.Cu" "F.Mask" "F.Paste")
			(net "GND")
		)
		(pad "223" smd rect
			(at 2.050034 8.074914 270)
			(size 0.519938 1.4986)
			(layers "F.Cu" "F.Mask" "F.Paste")
			(net "M_G_CPU1_SB_CA<3>")
		)
		(pad "224" smd rect
			(at 2.050034 8.925052 270)
			(size 0.519938 1.4986)
			(layers "F.Cu" "F.Mask" "F.Paste")
			(net "GND")
		)
		(pad "225" smd rect
			(at 2.050034 9.774936 270)
			(size 0.519938 1.4986)
			(layers "F.Cu" "F.Mask" "F.Paste")
			(net "M_G_CPU1_SB_CA<5>")
		)
		(pad "226" smd rect
			(at 2.050034 10.625074 270)
			(size 0.519938 1.4986)
			(layers "F.Cu" "F.Mask" "F.Paste")
			(net "GND")
		)
		(pad "227" smd rect
			(at 2.050034 11.474958 270)
			(size 0.519938 1.4986)
			(layers "F.Cu" "F.Mask" "F.Paste")
			(net "M_G_CPU1_SB_PAR")
		)
		(pad "228" smd rect
			(at 2.050034 12.325096 270)
			(size 0.519938 1.4986)
			(layers "F.Cu" "F.Mask" "F.Paste")
			(net "GND")
		)
		(pad "229" smd rect
			(at 2.050034 13.17498 270)
			(size 0.519938 1.4986)
			(layers "F.Cu" "F.Mask" "F.Paste")
			(net "M_G_CPU1_SB_CS_N<1>")
		)
		(pad "230" smd rect
			(at 2.050034 14.025118 270)
			(size 0.519938 1.4986)
			(layers "F.Cu" "F.Mask" "F.Paste")
			(net "GND")
		)
		(pad "231" smd rect
			(at 2.050034 14.875002 270)
			(size 0.519938 1.4986)
			(layers "F.Cu" "F.Mask" "F.Paste")
			(net "TP_CHG_CPU1_DIMM1_FRU_5")
		)
		(pad "232" smd rect
			(at 2.050034 15.724886 270)
			(size 0.519938 1.4986)
			(layers "F.Cu" "F.Mask" "F.Paste")
			(net "TP_CHG_CPU1_DIMM1_FRU_6")
		)
		(pad "233" smd rect
			(at 2.050034 16.575024 270)
			(size 0.519938 1.4986)
			(layers "F.Cu" "F.Mask" "F.Paste")
			(net "GND")
		)
		(pad "234" smd rect
			(at 2.050034 17.424908 270)
			(size 0.519938 1.4986)
			(layers "F.Cu" "F.Mask" "F.Paste")
			(net "M_G_CPU1_SB_CB<6>")
		)
		(pad "235" smd rect
			(at 2.050034 18.275046 270)
			(size 0.519938 1.4986)
			(layers "F.Cu" "F.Mask" "F.Paste")
			(net "GND")
		)
		(pad "236" smd rect
			(at 2.050034 19.12493 270)
			(size 0.519938 1.4986)
			(layers "F.Cu" "F.Mask" "F.Paste")
			(net "M_G_CPU1_SB_CB<7>")
		)
		(pad "237" smd rect
			(at 2.050034 19.975068 270)
			(size 0.519938 1.4986)
			(layers "F.Cu" "F.Mask" "F.Paste")
			(net "GND")
		)
		(pad "238" smd rect
			(at 2.050034 20.824952 270)
			(size 0.519938 1.4986)
			(layers "F.Cu" "F.Mask" "F.Paste")
			(net "M_G_CPU1_SB_DQS_DN<4>")
		)
		(pad "239" smd rect
			(at 2.050034 21.67509 270)
			(size 0.519938 1.4986)
			(layers "F.Cu" "F.Mask" "F.Paste")
			(net "M_G_CPU1_SB_DQS_DP<4>")
		)
		(pad "240" smd rect
			(at 2.050034 22.524974 270)
			(size 0.519938 1.4986)
			(layers "F.Cu" "F.Mask" "F.Paste")
			(net "GND")
		)
		(pad "241" smd rect
			(at 2.050034 23.375112 270)
			(size 0.519938 1.4986)
			(layers "F.Cu" "F.Mask" "F.Paste")
			(net "M_G_CPU1_SB_CB<2>")
		)
		(pad "242" smd rect
			(at 2.050034 24.224996 270)
			(size 0.519938 1.4986)
			(layers "F.Cu" "F.Mask" "F.Paste")
			(net "GND")
		)
		(pad "243" smd rect
			(at 2.050034 25.07488 270)
			(size 0.519938 1.4986)
			(layers "F.Cu" "F.Mask" "F.Paste")
			(net "M_G_CPU1_SB_CB<3>")
		)
		(pad "244" smd rect
			(at 2.050034 25.925018 270)
			(size 0.519938 1.4986)
			(layers "F.Cu" "F.Mask" "F.Paste")
			(net "GND")
		)
		(pad "245" smd rect
			(at 2.050034 26.774902 270)
			(size 0.519938 1.4986)
			(layers "F.Cu" "F.Mask" "F.Paste")
			(net "M_G_CPU1_SB_DQ<2>")
		)
		(pad "246" smd rect
			(at 2.050034 27.62504 270)
			(size 0.519938 1.4986)
			(layers "F.Cu" "F.Mask" "F.Paste")
			(net "GND")
		)
		(pad "247" smd rect
			(at 2.050034 28.474924 270)
			(size 0.519938 1.4986)
			(layers "F.Cu" "F.Mask" "F.Paste")
			(net "M_G_CPU1_SB_DQ<3>")
		)
		(pad "248" smd rect
			(at 2.050034 29.325062 270)
			(size 0.519938 1.4986)
			(layers "F.Cu" "F.Mask" "F.Paste")
			(net "GND")
		)
		(pad "249" smd rect
			(at 2.050034 30.174946 270)
			(size 0.519938 1.4986)
			(layers "F.Cu" "F.Mask" "F.Paste")
			(net "M_G_CPU1_SB_DQS_DN<5>")
		)
		(pad "250" smd rect
			(at 2.050034 31.025084 270)
			(size 0.519938 1.4986)
			(layers "F.Cu" "F.Mask" "F.Paste")
			(net "M_G_CPU1_SB_DQS_DP<5>")
		)
		(pad "251" smd rect
			(at 2.050034 31.874968 270)
			(size 0.519938 1.4986)
			(layers "F.Cu" "F.Mask" "F.Paste")
			(net "GND")
		)
		(pad "252" smd rect
			(at 2.050034 32.725106 270)
			(size 0.519938 1.4986)
			(layers "F.Cu" "F.Mask" "F.Paste")
			(net "M_G_CPU1_SB_DQ<6>")
		)
		(pad "253" smd rect
			(at 2.050034 33.57499 270)
			(size 0.519938 1.4986)
			(layers "F.Cu" "F.Mask" "F.Paste")
			(net "GND")
		)
		(pad "254" smd rect
			(at 2.050034 34.425128 270)
			(size 0.519938 1.4986)
			(layers "F.Cu" "F.Mask" "F.Paste")
			(net "M_G_CPU1_SB_DQ<7>")
		)
		(pad "255" smd rect
			(at 2.050034 35.275012 270)
			(size 0.519938 1.4986)
			(layers "F.Cu" "F.Mask" "F.Paste")
			(net "GND")
		)
		(pad "256" smd rect
			(at 2.050034 36.124896 270)
			(size 0.519938 1.4986)
			(layers "F.Cu" "F.Mask" "F.Paste")
			(net "M_G_CPU1_SB_DQ<10>")
		)
		(pad "257" smd rect
			(at 2.050034 36.975034 270)
			(size 0.519938 1.4986)
			(layers "F.Cu" "F.Mask" "F.Paste")
			(net "GND")
		)
		(pad "258" smd rect
			(at 2.050034 37.824918 270)
			(size 0.519938 1.4986)
			(layers "F.Cu" "F.Mask" "F.Paste")
			(net "M_G_CPU1_SB_DQ<11>")
		)
		(pad "259" smd rect
			(at 2.050034 38.675056 270)
			(size 0.519938 1.4986)
			(layers "F.Cu" "F.Mask" "F.Paste")
			(net "GND")
		)
		(pad "260" smd rect
			(at 2.050034 39.52494 270)
			(size 0.519938 1.4986)
			(layers "F.Cu" "F.Mask" "F.Paste")
			(net "M_G_CPU1_SB_DQS_DN<6>")
		)
		(pad "261" smd rect
			(at 2.050034 40.375078 270)
			(size 0.519938 1.4986)
			(layers "F.Cu" "F.Mask" "F.Paste")
			(net "M_G_CPU1_SB_DQS_DP<6>")
		)
		(pad "262" smd rect
			(at 2.050034 41.224962 270)
			(size 0.519938 1.4986)
			(layers "F.Cu" "F.Mask" "F.Paste")
			(net "GND")
		)
		(pad "263" smd rect
			(at 2.050034 42.0751 270)
			(size 0.519938 1.4986)
			(layers "F.Cu" "F.Mask" "F.Paste")
			(net "M_G_CPU1_SB_DQ<14>")
		)
		(pad "264" smd rect
			(at 2.050034 42.924984 270)
			(size 0.519938 1.4986)
			(layers "F.Cu" "F.Mask" "F.Paste")
			(net "GND")
		)
		(pad "265" smd rect
			(at 2.050034 43.775122 270)
			(size 0.519938 1.4986)
			(layers "F.Cu" "F.Mask" "F.Paste")
			(net "M_G_CPU1_SB_DQ<15>")
		)
		(pad "266" smd rect
			(at 2.050034 44.625006 270)
			(size 0.519938 1.4986)
			(layers "F.Cu" "F.Mask" "F.Paste")
			(net "GND")
		)
		(pad "267" smd rect
			(at 2.050034 45.47489 270)
			(size 0.519938 1.4986)
			(layers "F.Cu" "F.Mask" "F.Paste")
			(net "M_G_CPU1_SB_DQ<18>")
		)
		(pad "268" smd rect
			(at 2.050034 46.325028 270)
			(size 0.519938 1.4986)
			(layers "F.Cu" "F.Mask" "F.Paste")
			(net "GND")
		)
		(pad "269" smd rect
			(at 2.050034 47.174912 270)
			(size 0.519938 1.4986)
			(layers "F.Cu" "F.Mask" "F.Paste")
			(net "M_G_CPU1_SB_DQ<19>")
		)
		(pad "270" smd rect
			(at 2.050034 48.02505 270)
			(size 0.519938 1.4986)
			(layers "F.Cu" "F.Mask" "F.Paste")
			(net "GND")
		)
		(pad "271" smd rect
			(at 2.050034 48.874934 270)
			(size 0.519938 1.4986)
			(layers "F.Cu" "F.Mask" "F.Paste")
			(net "M_G_CPU1_SB_DQS_DN<7>")
		)
		(pad "272" smd rect
			(at 2.050034 49.725072 270)
			(size 0.519938 1.4986)
			(layers "F.Cu" "F.Mask" "F.Paste")
			(net "M_G_CPU1_SB_DQS_DP<7>")
		)
		(pad "273" smd rect
			(at 2.050034 50.574956 270)
			(size 0.519938 1.4986)
			(layers "F.Cu" "F.Mask" "F.Paste")
			(net "GND")
		)
		(pad "274" smd rect
			(at 2.050034 51.425094 270)
			(size 0.519938 1.4986)
			(layers "F.Cu" "F.Mask" "F.Paste")
			(net "M_G_CPU1_SB_DQ<22>")
		)
		(pad "275" smd rect
			(at 2.050034 52.274978 270)
			(size 0.519938 1.4986)
			(layers "F.Cu" "F.Mask" "F.Paste")
			(net "GND")
		)
		(pad "276" smd rect
			(at 2.050034 53.125116 270)
			(size 0.519938 1.4986)
			(layers "F.Cu" "F.Mask" "F.Paste")
			(net "M_G_CPU1_SB_DQ<23>")
		)
		(pad "277" smd rect
			(at 2.050034 53.975 270)
			(size 0.519938 1.4986)
			(layers "F.Cu" "F.Mask" "F.Paste")
			(net "GND")
		)
		(pad "278" smd rect
			(at 2.050034 54.824884 270)
			(size 0.519938 1.4986)
			(layers "F.Cu" "F.Mask" "F.Paste")
			(net "M_G_CPU1_SB_DQ<26>")
		)
		(pad "279" smd rect
			(at 2.050034 55.675022 270)
			(size 0.519938 1.4986)
			(layers "F.Cu" "F.Mask" "F.Paste")
			(net "GND")
		)
		(pad "280" smd rect
			(at 2.050034 56.524906 270)
			(size 0.519938 1.4986)
			(layers "F.Cu" "F.Mask" "F.Paste")
			(net "M_G_CPU1_SB_DQ<27>")
		)
		(pad "281" smd rect
			(at 2.050034 57.375044 270)
			(size 0.519938 1.4986)
			(layers "F.Cu" "F.Mask" "F.Paste")
			(net "GND")
		)
		(pad "282" smd rect
			(at 2.050034 58.224928 270)
			(size 0.519938 1.4986)
			(layers "F.Cu" "F.Mask" "F.Paste")
			(net "M_G_CPU1_SB_DQS_DN<8>")
		)
		(pad "283" smd rect
			(at 2.050034 59.075066 270)
			(size 0.519938 1.4986)
			(layers "F.Cu" "F.Mask" "F.Paste")
			(net "M_G_CPU1_SB_DQS_DP<8>")
		)
		(pad "284" smd rect
			(at 2.050034 59.92495 270)
			(size 0.519938 1.4986)
			(layers "F.Cu" "F.Mask" "F.Paste")
			(net "GND")
		)
		(pad "285" smd rect
			(at 2.050034 60.775088 270)
			(size 0.519938 1.4986)
			(layers "F.Cu" "F.Mask" "F.Paste")
			(net "M_G_CPU1_SB_DQ<30>")
		)
		(pad "286" smd rect
			(at 2.050034 61.624972 270)
			(size 0.519938 1.4986)
			(layers "F.Cu" "F.Mask" "F.Paste")
			(net "GND")
		)
		(pad "287" smd rect
			(at 2.050034 62.47511 270)
			(size 0.519938 1.4986)
			(layers "F.Cu" "F.Mask" "F.Paste")
			(net "M_G_CPU1_SB_DQ<31>")
		)
		(pad "288" smd rect
			(at 2.050034 63.324994 270)
			(size 0.519938 1.4986)
			(layers "F.Cu" "F.Mask" "F.Paste")
			(net "GND")
		)
		(pad "G1" thru_hole oval
			(at 0 -68.97497)
			(size 2.8194 1.5748)
			(drill oval 2.4384 1.1938)
			(layers "*.Cu" "*.Mask")
			(remove_unused_layers no)
			(net "GND")
			(clearance 0.127)
			(thermal_gap 0.127)
		)
		(pad "G2" thru_hole oval
			(at 0 3.875024)
			(size 2.8194 1.5748)
			(drill oval 2.4384 1.1938)
			(layers "*.Cu" "*.Mask")
			(remove_unused_layers no)
			(net "GND")
			(clearance 0.127)
			(thermal_gap 0.127)
		)
		(pad "G3" thru_hole oval
			(at 0 68.97497)
			(size 2.8194 1.5748)
			(drill oval 2.4384 1.1938)
			(layers "*.Cu" "*.Mask")
			(remove_unused_layers no)
			(net "GND")
			(clearance 0.127)
			(thermal_gap 0.127)
		)
	)
	(footprint ""
		(layer "F.Cu")
		(at 201.00036 -118.074948)
		(property "Reference" "R1470"
			(at 0 0 0)
			(layer "F.SilkS")
			(hide yes)
			(effects
				(font
					(size 1.27 1.27)
				)
			)
		)
		(property "Value" ""
			(at 0 0 0)
			(layer "F.Fab")
			(effects
				(font
					(size 1.27 1.27)
				)
			)
		)
		(duplicate_pad_numbers_are_jumpers no)
		(fp_line
			(start -0.7874 -0.4064)
			(end 0.7874 -0.4064)
			(stroke
				(width 0.1524)
				(type default)
			)
			(layer "F.SilkS")
		)
		(fp_line
			(start -0.7874 0.4064)
			(end -0.7874 -0.4064)
			(stroke
				(width 0.1524)
				(type default)
			)
			(layer "F.SilkS")
		)
		(fp_line
			(start 0.7874 -0.4064)
			(end 0.7874 0.4064)
			(stroke
				(width 0.1524)
				(type default)
			)
			(layer "F.SilkS")
		)
		(fp_line
			(start 0.7874 0.4064)
			(end -0.7874 0.4064)
			(stroke
				(width 0.1524)
				(type default)
			)
			(layer "F.SilkS")
		)
		(fp_line
			(start -0.67945 -0.305054)
			(end -0.12065 -0.305054)
			(stroke
				(width 0.1)
				(type default)
			)
			(layer "F.Fab")
		)
		(fp_line
			(start -0.67945 0.3048)
			(end -0.67945 -0.305054)
			(stroke
				(width 0.1)
				(type default)
			)
			(layer "F.Fab")
		)
		(fp_line
			(start -0.12065 -0.305054)
			(end -0.12065 -0.2794)
			(stroke
				(width 0.1)
				(type default)
			)
			(layer "F.Fab")
		)
		(fp_line
			(start -0.12065 -0.2794)
			(end 0.12065 -0.2794)
			(stroke
				(width 0.1)
				(type default)
			)
			(layer "F.Fab")
		)
		(fp_line
			(start -0.12065 0.2794)
			(end -0.12065 0.3048)
			(stroke
				(width 0.1)
				(type default)
			)
			(layer "F.Fab")
		)
		(fp_line
			(start -0.12065 0.3048)
			(end -0.67945 0.3048)
			(stroke
				(width 0.1)
				(type default)
			)
			(layer "F.Fab")
		)
		(fp_line
			(start 0.120396 0.2794)
			(end -0.12065 0.2794)
			(stroke
				(width 0.1)
				(type default)
			)
			(layer "F.Fab")
		)
		(fp_line
			(start 0.120396 0.3048)
			(end 0.120396 0.2794)
			(stroke
				(width 0.1)
				(type default)
			)
			(layer "F.Fab")
		)
		(fp_line
			(start 0.12065 -0.3048)
			(end 0.67945 -0.3048)
			(stroke
				(width 0.1)
				(type default)
			)
			(layer "F.Fab")
		)
		(fp_line
			(start 0.12065 -0.2794)
			(end 0.12065 -0.3048)
			(stroke
				(width 0.1)
				(type default)
			)
			(layer "F.Fab")
		)
		(fp_line
			(start 0.67945 -0.3048)
			(end 0.67945 0.3048)
			(stroke
				(width 0.1)
				(type default)
			)
			(layer "F.Fab")
		)
		(fp_line
			(start 0.67945 0.3048)
			(end 0.120396 0.3048)
			(stroke
				(width 0.1)
				(type default)
			)
			(layer "F.Fab")
		)
		(pad "1" smd circle
			(at -0.40005 0)
			(size 0 0)
			(layers "F.Cu" "F.Mask" "F.Paste")
			(net "RST_PLTRST_PLD_B_N")
		)
		(pad "2" smd circle
			(at 0.40005 0)
			(size 0 0)
			(layers "F.Cu" "F.Mask" "F.Paste")
			(net "RST_PLTRST_B_MUX_N")
		)
	)
	(footprint ""
		(layer "F.Cu")
		(at 239.152684 -58.32729 180)
		(property "Reference" "C1989"
			(at 0 0 180)
			(layer "F.SilkS")
			(hide yes)
			(effects
				(font
					(size 1.27 1.27)
				)
			)
		)
		(property "Value" ""
			(at 0 0 180)
			(layer "F.Fab")
			(effects
				(font
					(size 1.27 1.27)
				)
			)
		)
		(duplicate_pad_numbers_are_jumpers no)
		(fp_line
			(start 0.299974 0.150114)
			(end -0.299974 0.150114)
			(stroke
				(width 0.1)
				(type default)
			)
			(layer "F.Fab")
		)
		(fp_line
			(start 0.299974 -0.150114)
			(end 0.299974 0.150114)
			(stroke
				(width 0.1)
				(type default)
			)
			(layer "F.Fab")
		)
		(fp_line
			(start -0.299974 0.150114)
			(end -0.299974 -0.150114)
			(stroke
				(width 0.1)
				(type default)
			)
			(layer "F.Fab")
		)
		(fp_line
			(start -0.299974 -0.150114)
			(end 0.299974 -0.150114)
			(stroke
				(width 0.1)
				(type default)
			)
			(layer "F.Fab")
		)
		(pad "1" smd rect
			(at -0.2667 0 180)
			(size 0.3048 0.381)
			(layers "F.Cu" "F.Mask" "F.Paste")
			(net "P3E_PCH_E1S_TX_DP<3>")
		)
		(pad "2" smd rect
			(at 0.2667 0 180)
			(size 0.3048 0.381)
			(layers "F.Cu" "F.Mask" "F.Paste")
			(net "P3E_PCH_E1S_TX_C_DP<3>")
		)
		(zone
			(layer "In1.Cu")
			(hatch none 0.5)
			(connect_pads
				(clearance 0)
			)
			(min_thickness 0.25)
			(keepout
				(tracks not_allowed)
				(vias allowed)
				(pads allowed)
				(copperpour not_allowed)
				(footprints allowed)
			)
			(placement
				(enabled no)
				(sheetname "")
			)
			(fill
				(thermal_gap 0.5)
				(thermal_bridge_width 0.5)
				(island_removal_mode 0)
			)
			(polygon
				(pts
					(arc
						(start 239.012984 -58.567574)
						(mid 239.066866 -58.545256)
						(end 239.089184 -58.491374)
					)
					(arc
						(start 239.089184 -58.161174)
						(mid 239.066866 -58.107292)
						(end 239.012984 -58.084974)
					)
					(arc
						(start 238.758984 -58.084974)
						(mid 238.705102 -58.107292)
						(end 238.682784 -58.161174)
					)
					(arc
						(start 238.682784 -58.491374)
						(mid 238.705102 -58.545256)
						(end 238.758984 -58.567574)
					)
				)
			)
		)
		(zone
			(layer "In1.Cu")
			(hatch none 0.5)
			(connect_pads
				(clearance 0)
			)
			(min_thickness 0.25)
			(keepout
				(tracks not_allowed)
				(vias allowed)
				(pads allowed)
				(copperpour not_allowed)
				(footprints allowed)
			)
			(placement
				(enabled no)
				(sheetname "")
			)
			(fill
				(thermal_gap 0.5)
				(thermal_bridge_width 0.5)
				(island_removal_mode 0)
			)
			(polygon
				(pts
					(arc
						(start 239.546384 -58.567574)
						(mid 239.600266 -58.545256)
						(end 239.622584 -58.491374)
					)
					(arc
						(start 239.622584 -58.161174)
						(mid 239.600266 -58.107292)
						(end 239.546384 -58.084974)
					)
					(arc
						(start 239.292384 -58.084974)
						(mid 239.238502 -58.107292)
						(end 239.216184 -58.161174)
					)
					(arc
						(start 239.216184 -58.491374)
						(mid 239.238502 -58.545256)
						(end 239.292384 -58.567574)
					)
				)
			)
		)
	)
	(footprint ""
		(layer "F.Cu")
		(at 29.954728 -153.76652)
		(property "Reference" "H126"
			(at -10.20572 0.41783 0)
			(unlocked yes)
			(layer "F.SilkS")
			(effects
				(font
					(size 0.7874 0.5842)
					(thickness 0.1524)
				)
				(justify left)
			)
		)
		(property "Value" ""
			(at 0 0 0)
			(layer "F.Fab")
			(effects
				(font
					(size 1.27 1.27)
				)
			)
		)
		(duplicate_pad_numbers_are_jumpers no)
		(fp_circle
			(center 0 0)
			(end 5.8166 0)
			(stroke
				(width 0.1524)
				(type default)
			)
			(fill no)
			(layer "F.SilkS")
		)
		(fp_circle
			(center 0 0)
			(end 5.8166 0)
			(stroke
				(width 0.1524)
				(type default)
			)
			(fill no)
			(layer "B.SilkS")
		)
		(fp_circle
			(center 0 0)
			(end 5.8166 0)
			(stroke
				(width 0.1)
				(type default)
			)
			(fill no)
			(layer "B.Fab")
		)
		(fp_circle
			(center 0 0)
			(end 5.8166 0)
			(stroke
				(width 0.1)
				(type default)
			)
			(fill no)
			(layer "F.Fab")
		)
		(pad "" np_thru_hole circle
			(at 0 0)
			(size 10.0076 10.0076)
			(drill 10.0076)
			(layers "*.Cu" "*.Mask")
			(clearance 0.381)
			(thermal_gap 0.381)
		)
	)
	(footprint ""
		(layer "F.Cu")
		(at 355.228144 -240.276888 90)
		(property "Reference" "C1035"
			(at 0 0 90)
			(layer "F.SilkS")
			(hide yes)
			(effects
				(font
					(size 1.27 1.27)
				)
			)
		)
		(property "Value" ""
			(at 0 0 90)
			(layer "F.Fab")
			(effects
				(font
					(size 1.27 1.27)
				)
			)
		)
		(duplicate_pad_numbers_are_jumpers no)
		(fp_line
			(start 0.7874 -0.4064)
			(end 0.7874 0.4064)
			(stroke
				(width 0.1524)
				(type default)
			)
			(layer "F.SilkS")
		)
		(fp_line
			(start -0.7874 -0.4064)
			(end 0.7874 -0.4064)
			(stroke
				(width 0.1524)
				(type default)
			)
			(layer "F.SilkS")
		)
		(fp_line
			(start 0.7874 0.4064)
			(end -0.7874 0.4064)
			(stroke
				(width 0.1524)
				(type default)
			)
			(layer "F.SilkS")
		)
		(fp_line
			(start -0.7874 0.4064)
			(end -0.7874 -0.4064)
			(stroke
				(width 0.1524)
				(type default)
			)
			(layer "F.SilkS")
		)
		(fp_line
			(start -0.12065 -0.305054)
			(end -0.12065 -0.2794)
			(stroke
				(width 0.1)
				(type default)
			)
			(layer "F.Fab")
		)
		(fp_line
			(start -0.67945 -0.305054)
			(end -0.12065 -0.305054)
			(stroke
				(width 0.1)
				(type default)
			)
			(layer "F.Fab")
		)
		(fp_line
			(start 0.67945 -0.3048)
			(end 0.67945 0.3048)
			(stroke
				(width 0.1)
				(type default)
			)
			(layer "F.Fab")
		)
		(fp_line
			(start 0.12065 -0.3048)
			(end 0.67945 -0.3048)
			(stroke
				(width 0.1)
				(type default)
			)
			(layer "F.Fab")
		)
		(fp_line
			(start 0.12065 -0.2794)
			(end 0.12065 -0.3048)
			(stroke
				(width 0.1)
				(type default)
			)
			(layer "F.Fab")
		)
		(fp_line
			(start -0.12065 -0.2794)
			(end 0.12065 -0.2794)
			(stroke
				(width 0.1)
				(type default)
			)
			(layer "F.Fab")
		)
		(fp_line
			(start 0.120396 0.2794)
			(end -0.12065 0.2794)
			(stroke
				(width 0.1)
				(type default)
			)
			(layer "F.Fab")
		)
		(fp_line
			(start -0.12065 0.2794)
			(end -0.12065 0.3048)
			(stroke
				(width 0.1)
				(type default)
			)
			(layer "F.Fab")
		)
		(fp_line
			(start 0.67945 0.3048)
			(end 0.120396 0.3048)
			(stroke
				(width 0.1)
				(type default)
			)
			(layer "F.Fab")
		)
		(fp_line
			(start 0.120396 0.3048)
			(end 0.120396 0.2794)
			(stroke
				(width 0.1)
				(type default)
			)
			(layer "F.Fab")
		)
		(fp_line
			(start -0.12065 0.3048)
			(end -0.67945 0.3048)
			(stroke
				(width 0.1)
				(type default)
			)
			(layer "F.Fab")
		)
		(fp_line
			(start -0.67945 0.3048)
			(end -0.67945 -0.305054)
			(stroke
				(width 0.1)
				(type default)
			)
			(layer "F.Fab")
		)
		(pad "1" smd circle
			(at -0.40005 0 90)
			(size 0 0)
			(layers "F.Cu" "F.Mask" "F.Paste")
			(net "PVCCIN_CPU0")
		)
		(pad "2" smd circle
			(at 0.40005 0 90)
			(size 0 0)
			(layers "F.Cu" "F.Mask" "F.Paste")
			(net "GND")
		)
	)
	(footprint ""
		(layer "F.Cu")
		(at 353.88423 -338.180172 90)
		(property "Reference" "PR1786"
			(at 0 0 90)
			(layer "F.SilkS")
			(hide yes)
			(effects
				(font
					(size 1.27 1.27)
				)
			)
		)
		(property "Value" ""
			(at 0 0 90)
			(layer "F.Fab")
			(effects
				(font
					(size 1.27 1.27)
				)
			)
		)
		(duplicate_pad_numbers_are_jumpers no)
		(fp_line
			(start 0.7874 -0.4064)
			(end 0.7874 0.4064)
			(stroke
				(width 0.1524)
				(type default)
			)
			(layer "F.SilkS")
		)
		(fp_line
			(start -0.7874 -0.4064)
			(end 0.7874 -0.4064)
			(stroke
				(width 0.1524)
				(type default)
			)
			(layer "F.SilkS")
		)
		(fp_line
			(start 0.7874 0.4064)
			(end -0.7874 0.4064)
			(stroke
				(width 0.1524)
				(type default)
			)
			(layer "F.SilkS")
		)
		(fp_line
			(start -0.7874 0.4064)
			(end -0.7874 -0.4064)
			(stroke
				(width 0.1524)
				(type default)
			)
			(layer "F.SilkS")
		)
		(fp_line
			(start -0.12065 -0.305054)
			(end -0.12065 -0.2794)
			(stroke
				(width 0.1)
				(type default)
			)
			(layer "F.Fab")
		)
		(fp_line
			(start -0.67945 -0.305054)
			(end -0.12065 -0.305054)
			(stroke
				(width 0.1)
				(type default)
			)
			(layer "F.Fab")
		)
		(fp_line
			(start 0.67945 -0.3048)
			(end 0.67945 0.3048)
			(stroke
				(width 0.1)
				(type default)
			)
			(layer "F.Fab")
		)
		(fp_line
			(start 0.12065 -0.3048)
			(end 0.67945 -0.3048)
			(stroke
				(width 0.1)
				(type default)
			)
			(layer "F.Fab")
		)
		(fp_line
			(start 0.12065 -0.2794)
			(end 0.12065 -0.3048)
			(stroke
				(width 0.1)
				(type default)
			)
			(layer "F.Fab")
		)
		(fp_line
			(start -0.12065 -0.2794)
			(end 0.12065 -0.2794)
			(stroke
				(width 0.1)
				(type default)
			)
			(layer "F.Fab")
		)
		(fp_line
			(start 0.120396 0.2794)
			(end -0.12065 0.2794)
			(stroke
				(width 0.1)
				(type default)
			)
			(layer "F.Fab")
		)
		(fp_line
			(start -0.12065 0.2794)
			(end -0.12065 0.3048)
			(stroke
				(width 0.1)
				(type default)
			)
			(layer "F.Fab")
		)
		(fp_line
			(start 0.67945 0.3048)
			(end 0.120396 0.3048)
			(stroke
				(width 0.1)
				(type default)
			)
			(layer "F.Fab")
		)
		(fp_line
			(start 0.120396 0.3048)
			(end 0.120396 0.2794)
			(stroke
				(width 0.1)
				(type default)
			)
			(layer "F.Fab")
		)
		(fp_line
			(start -0.12065 0.3048)
			(end -0.67945 0.3048)
			(stroke
				(width 0.1)
				(type default)
			)
			(layer "F.Fab")
		)
		(fp_line
			(start -0.67945 0.3048)
			(end -0.67945 -0.305054)
			(stroke
				(width 0.1)
				(type default)
			)
			(layer "F.Fab")
		)
		(pad "1" smd circle
			(at -0.40005 0 90)
			(size 0 0)
			(layers "F.Cu" "F.Mask" "F.Paste")
			(net "SW_PVCCIN_CPU0_BOOT2")
		)
		(pad "2" smd circle
			(at 0.40005 0 90)
			(size 0 0)
			(layers "F.Cu" "F.Mask" "F.Paste")
			(net "SW_PVCCIN_CPU0_BOOT2_R")
		)
	)
	(footprint ""
		(layer "F.Cu")
		(at 215.259666 -54.455314)
		(property "Reference" "U276"
			(at 3.789934 1.423416 0)
			(unlocked yes)
			(layer "F.SilkS")
			(effects
				(font
					(size 0.7874 0.5842)
					(thickness 0.1524)
				)
			)
		)
		(property "Value" ""
			(at 0 0 0)
			(layer "F.Fab")
			(effects
				(font
					(size 1.27 1.27)
				)
			)
		)
		(duplicate_pad_numbers_are_jumpers no)
		(fp_line
			(start -1.500124 -1.500124)
			(end -1.004062 -1.500124)
			(stroke
				(width 0.1524)
				(type default)
			)
			(layer "F.SilkS")
		)
		(fp_line
			(start -1.500124 -1.004062)
			(end -1.500124 -1.500124)
			(stroke
				(width 0.1524)
				(type default)
			)
			(layer "F.SilkS")
		)
		(fp_line
			(start -1.500124 1.500124)
			(end -1.500124 1.004062)
			(stroke
				(width 0.1524)
				(type default)
			)
			(layer "F.SilkS")
		)
		(fp_line
			(start -1.004062 1.500124)
			(end -1.500124 1.500124)
			(stroke
				(width 0.1524)
				(type default)
			)
			(layer "F.SilkS")
		)
		(fp_line
			(start 1.004062 -1.500124)
			(end 1.500124 -1.500124)
			(stroke
				(width 0.1524)
				(type default)
			)
			(layer "F.SilkS")
		)
		(fp_line
			(start 1.500124 -1.500124)
			(end 1.500124 -1.004062)
			(stroke
				(width 0.1524)
				(type default)
			)
			(layer "F.SilkS")
		)
		(fp_line
			(start 1.500124 1.004062)
			(end 1.500124 1.500124)
			(stroke
				(width 0.1524)
				(type default)
			)
			(layer "F.SilkS")
		)
		(fp_line
			(start 1.500124 1.500124)
			(end 1.004062 1.500124)
			(stroke
				(width 0.1524)
				(type default)
			)
			(layer "F.SilkS")
		)
		(fp_poly
			(pts
				(xy -2.468626 -1.082294) (xy -1.783588 -0.739902) (xy -2.468626 -0.39751)
			)
			(stroke
				(width 0)
				(type default)
			)
			(fill yes)
			(layer "F.SilkS")
		)
		(fp_line
			(start -1.500124 -1.500124)
			(end 1.500124 -1.500124)
			(stroke
				(width 0.1)
				(type default)
			)
			(layer "F.Fab")
		)
		(fp_line
			(start -1.500124 1.500124)
			(end -1.500124 -1.500124)
			(stroke
				(width 0.1)
				(type default)
			)
			(layer "F.Fab")
		)
		(fp_line
			(start 1.500124 -1.500124)
			(end 1.500124 1.500124)
			(stroke
				(width 0.1)
				(type default)
			)
			(layer "F.Fab")
		)
		(fp_line
			(start 1.500124 1.500124)
			(end -1.500124 1.500124)
			(stroke
				(width 0.1)
				(type default)
			)
			(layer "F.Fab")
		)
		(fp_poly
			(pts
				(xy -2.847848 -1.258062) (xy -2.847848 -0.242062) (xy -1.831848 -0.750062)
			)
			(stroke
				(width 0)
				(type default)
			)
			(fill yes)
			(layer "F.Fab")
		)
		(pad "1" smd rect
			(at -1.400048 -0.750062 270)
			(size 0.2286 0.6096)
			(layers "F.Cu" "F.Mask" "F.Paste")
			(net "INA230_2_A1")
		)
		(pad "2" smd rect
			(at -1.400048 -0.249936 270)
			(size 0.2286 0.6096)
			(layers "F.Cu" "F.Mask" "F.Paste")
			(net "INA230_2_A0")
		)
		(pad "3" smd rect
			(at -1.400048 0.249936 270)
			(size 0.2286 0.6096)
			(layers "F.Cu" "F.Mask" "F.Paste")
			(net "E1S_0_P3V3_ADC_ALERT_R")
		)
		(pad "4" smd rect
			(at -1.400048 0.750062 270)
			(size 0.2286 0.6096)
			(layers "F.Cu" "F.Mask" "F.Paste")
			(net "SMB_INA230_2_3V3AUX_SDA_R1")
		)
		(pad "5" smd rect
			(at -0.750062 1.400048)
			(size 0.2286 0.6096)
			(layers "F.Cu" "F.Mask" "F.Paste")
			(net "SMB_INA230_2_3V3AUX_SCL_R1")
		)
		(pad "6" smd rect
			(at -0.249936 1.400048)
			(size 0.2286 0.6096)
			(layers "F.Cu" "F.Mask" "F.Paste")
			(net "NC_INA230_2_NC0")
		)
		(pad "7" smd rect
			(at 0.249936 1.400048)
			(size 0.2286 0.6096)
			(layers "F.Cu" "F.Mask" "F.Paste")
			(net "NC_INA230_2_NC1")
		)
		(pad "8" smd rect
			(at 0.750062 1.400048)
			(size 0.2286 0.6096)
			(layers "F.Cu" "F.Mask" "F.Paste")
			(net "NC_INA230_2_NC2")
		)
		(pad "9" smd rect
			(at 1.400048 0.750062 270)
			(size 0.2286 0.6096)
			(layers "F.Cu" "F.Mask" "F.Paste")
			(net "P3V3_AUX")
		)
		(pad "10" smd rect
			(at 1.400048 0.249936 270)
			(size 0.2286 0.6096)
			(layers "F.Cu" "F.Mask" "F.Paste")
			(net "GND")
		)
		(pad "11" smd rect
			(at 1.400048 -0.249936 270)
			(size 0.2286 0.6096)
			(layers "F.Cu" "F.Mask" "F.Paste")
			(net "P3V3_E1S_0_R")
		)
		(pad "12" smd rect
			(at 1.400048 -0.750062 270)
			(size 0.2286 0.6096)
			(layers "F.Cu" "F.Mask" "F.Paste")
			(net "VSENSE_P3V3_INA230_2_INN")
		)
		(pad "13" smd rect
			(at 0.750062 -1.400048)
			(size 0.2286 0.6096)
			(layers "F.Cu" "F.Mask" "F.Paste")
			(net "VSENSE_P3V3_INA230_2_INP")
		)
		(pad "14" smd rect
			(at 0.249936 -1.400048)
			(size 0.2286 0.6096)
			(layers "F.Cu" "F.Mask" "F.Paste")
			(net "NC_INA230_2_NC3")
		)
		(pad "15" smd rect
			(at -0.249936 -1.400048)
			(size 0.2286 0.6096)
			(layers "F.Cu" "F.Mask" "F.Paste")
			(net "NC_INA230_2_NC4")
		)
		(pad "16" smd rect
			(at -0.750062 -1.400048)
			(size 0.2286 0.6096)
			(layers "F.Cu" "F.Mask" "F.Paste")
			(net "NC_INA230_2_NC5")
		)
		(pad "TH" smd rect
			(at 0 0)
			(size 1.7018 1.7018)
			(layers "F.Cu" "F.Mask" "F.Paste")
			(net "GND")
		)
		(zone
			(layer "F.Cu")
			(hatch none 0.5)
			(connect_pads
				(clearance 0)
			)
			(min_thickness 0.25)
			(keepout
				(tracks not_allowed)
				(vias allowed)
				(pads allowed)
				(copperpour not_allowed)
				(footprints allowed)
			)
			(placement
				(enabled no)
				(sheetname "")
			)
			(fill
				(thermal_gap 0.5)
				(thermal_bridge_width 0.5)
				(island_removal_mode 0)
			)
			(polygon
				(pts
					(xy 214.215218 -54.455314) (xy 214.357966 -54.455314) (xy 214.357966 -53.553614) (xy 216.161366 -53.553614)
					(xy 216.161366 -53.967888) (xy 216.304114 -53.967888) (xy 216.304114 -53.410866) (xy 214.215218 -53.410866)
				)
			)
		)
	)
	(footprint ""
		(layer "F.Cu")
		(at 150.04796 -37.904166)
		(property "Reference" "Y9"
			(at -1.3462 -2.174748 0)
			(unlocked yes)
			(layer "F.SilkS")
			(effects
				(font
					(size 0.7874 0.5842)
					(thickness 0.1524)
				)
				(justify left)
			)
		)
		(property "Value" ""
			(at 0 0 0)
			(layer "F.Fab")
			(effects
				(font
					(size 1.27 1.27)
				)
			)
		)
		(duplicate_pad_numbers_are_jumpers no)
		(fp_line
			(start -1.2446 -1.4986)
			(end -1.2446 1.4986)
			(stroke
				(width 0.1524)
				(type default)
			)
			(layer "F.SilkS")
		)
		(fp_line
			(start -1.2446 1.4986)
			(end 1.2446 1.4986)
			(stroke
				(width 0.1524)
				(type default)
			)
			(layer "F.SilkS")
		)
		(fp_line
			(start 1.2446 -1.4986)
			(end -1.2446 -1.4986)
			(stroke
				(width 0.1524)
				(type default)
			)
			(layer "F.SilkS")
		)
		(fp_line
			(start 1.2446 1.4986)
			(end 1.2446 -1.4986)
			(stroke
				(width 0.1524)
				(type default)
			)
			(layer "F.SilkS")
		)
		(fp_poly
			(pts
				(xy -2.4638 -1.357884) (xy -1.4478 -0.849884) (xy -2.4638 -0.341884)
			)
			(stroke
				(width 0)
				(type default)
			)
			(fill yes)
			(layer "F.SilkS")
		)
		(fp_line
			(start -1.050036 -1.299972)
			(end -1.050036 1.299972)
			(stroke
				(width 0.1)
				(type default)
			)
			(layer "F.Fab")
		)
		(fp_line
			(start -1.050036 1.299972)
			(end 1.050036 1.299972)
			(stroke
				(width 0.1)
				(type default)
			)
			(layer "F.Fab")
		)
		(fp_line
			(start 1.050036 -1.299972)
			(end -1.050036 -1.299972)
			(stroke
				(width 0.1)
				(type default)
			)
			(layer "F.Fab")
		)
		(fp_line
			(start 1.050036 1.299972)
			(end 1.050036 -1.299972)
			(stroke
				(width 0.1)
				(type default)
			)
			(layer "F.Fab")
		)
		(fp_poly
			(pts
				(xy -2.4638 -1.357884) (xy -2.4638 -0.341884) (xy -1.4478 -0.849884)
			)
			(stroke
				(width 0)
				(type default)
			)
			(fill yes)
			(layer "F.Fab")
		)
		(pad "1" smd rect
			(at -0.649986 -0.849884 180)
			(size 0.9144 1.016)
			(layers "F.Cu" "F.Mask" "F.Paste")
			(net "USB_HUB_2_XTAL_IN")
		)
		(pad "2" smd rect
			(at -0.649986 0.849884 180)
			(size 0.9144 1.016)
			(layers "F.Cu" "F.Mask" "F.Paste")
			(net "GND")
		)
		(pad "3" smd rect
			(at 0.649986 0.849884 180)
			(size 0.9144 1.016)
			(layers "F.Cu" "F.Mask" "F.Paste")
			(net "USB_HUB_2_XTAL_OUT")
		)
		(pad "4" smd rect
			(at 0.649986 -0.849884 180)
			(size 0.9144 1.016)
			(layers "F.Cu" "F.Mask" "F.Paste")
			(net "GND")
		)
	)
	(footprint ""
		(layer "F.Cu")
		(at 366.48263 -256.654046 -90)
		(property "Reference" "C992"
			(at 0 0 270)
			(layer "F.SilkS")
			(hide yes)
			(effects
				(font
					(size 1.27 1.27)
				)
			)
		)
		(property "Value" ""
			(at 0 0 270)
			(layer "F.Fab")
			(effects
				(font
					(size 1.27 1.27)
				)
			)
		)
		(duplicate_pad_numbers_are_jumpers no)
		(fp_line
			(start -0.7874 0.4064)
			(end -0.7874 -0.4064)
			(stroke
				(width 0.1524)
				(type default)
			)
			(layer "F.SilkS")
		)
		(fp_line
			(start 0.7874 0.4064)
			(end -0.7874 0.4064)
			(stroke
				(width 0.1524)
				(type default)
			)
			(layer "F.SilkS")
		)
		(fp_line
			(start -0.7874 -0.4064)
			(end 0.7874 -0.4064)
			(stroke
				(width 0.1524)
				(type default)
			)
			(layer "F.SilkS")
		)
		(fp_line
			(start 0.7874 -0.4064)
			(end 0.7874 0.4064)
			(stroke
				(width 0.1524)
				(type default)
			)
			(layer "F.SilkS")
		)
		(fp_line
			(start -0.67945 0.3048)
			(end -0.67945 -0.305054)
			(stroke
				(width 0.1)
				(type default)
			)
			(layer "F.Fab")
		)
		(fp_line
			(start -0.12065 0.3048)
			(end -0.67945 0.3048)
			(stroke
				(width 0.1)
				(type default)
			)
			(layer "F.Fab")
		)
		(fp_line
			(start 0.120396 0.3048)
			(end 0.120396 0.2794)
			(stroke
				(width 0.1)
				(type default)
			)
			(layer "F.Fab")
		)
		(fp_line
			(start 0.67945 0.3048)
			(end 0.120396 0.3048)
			(stroke
				(width 0.1)
				(type default)
			)
			(layer "F.Fab")
		)
		(fp_line
			(start -0.12065 0.2794)
			(end -0.12065 0.3048)
			(stroke
				(width 0.1)
				(type default)
			)
			(layer "F.Fab")
		)
		(fp_line
			(start 0.120396 0.2794)
			(end -0.12065 0.2794)
			(stroke
				(width 0.1)
				(type default)
			)
			(layer "F.Fab")
		)
		(fp_line
			(start -0.12065 -0.2794)
			(end 0.12065 -0.2794)
			(stroke
				(width 0.1)
				(type default)
			)
			(layer "F.Fab")
		)
		(fp_line
			(start 0.12065 -0.2794)
			(end 0.12065 -0.3048)
			(stroke
				(width 0.1)
				(type default)
			)
			(layer "F.Fab")
		)
		(fp_line
			(start 0.12065 -0.3048)
			(end 0.67945 -0.3048)
			(stroke
				(width 0.1)
				(type default)
			)
			(layer "F.Fab")
		)
		(fp_line
			(start 0.67945 -0.3048)
			(end 0.67945 0.3048)
			(stroke
				(width 0.1)
				(type default)
			)
			(layer "F.Fab")
		)
		(fp_line
			(start -0.67945 -0.305054)
			(end -0.12065 -0.305054)
			(stroke
				(width 0.1)
				(type default)
			)
			(layer "F.Fab")
		)
		(fp_line
			(start -0.12065 -0.305054)
			(end -0.12065 -0.2794)
			(stroke
				(width 0.1)
				(type default)
			)
			(layer "F.Fab")
		)
		(pad "1" smd circle
			(at -0.40005 0 270)
			(size 0 0)
			(layers "F.Cu" "F.Mask" "F.Paste")
			(net "PVCCIN_CPU0")
		)
		(pad "2" smd circle
			(at 0.40005 0 270)
			(size 0 0)
			(layers "F.Cu" "F.Mask" "F.Paste")
			(net "GND")
		)
	)
	(footprint ""
		(layer "F.Cu")
		(at 200.03008 -131.694428 90)
		(property "Reference" "R2529"
			(at 0 0 90)
			(layer "F.SilkS")
			(hide yes)
			(effects
				(font
					(size 1.27 1.27)
				)
			)
		)
		(property "Value" ""
			(at 0 0 90)
			(layer "F.Fab")
			(effects
				(font
					(size 1.27 1.27)
				)
			)
		)
		(duplicate_pad_numbers_are_jumpers no)
		(fp_line
			(start 0.7874 -0.4064)
			(end 0.7874 0.4064)
			(stroke
				(width 0.1524)
				(type default)
			)
			(layer "F.SilkS")
		)
		(fp_line
			(start -0.7874 -0.4064)
			(end 0.7874 -0.4064)
			(stroke
				(width 0.1524)
				(type default)
			)
			(layer "F.SilkS")
		)
		(fp_line
			(start 0.7874 0.4064)
			(end -0.7874 0.4064)
			(stroke
				(width 0.1524)
				(type default)
			)
			(layer "F.SilkS")
		)
		(fp_line
			(start -0.7874 0.4064)
			(end -0.7874 -0.4064)
			(stroke
				(width 0.1524)
				(type default)
			)
			(layer "F.SilkS")
		)
		(fp_line
			(start -0.12065 -0.305054)
			(end -0.12065 -0.2794)
			(stroke
				(width 0.1)
				(type default)
			)
			(layer "F.Fab")
		)
		(fp_line
			(start -0.67945 -0.305054)
			(end -0.12065 -0.305054)
			(stroke
				(width 0.1)
				(type default)
			)
			(layer "F.Fab")
		)
		(fp_line
			(start 0.67945 -0.3048)
			(end 0.67945 0.3048)
			(stroke
				(width 0.1)
				(type default)
			)
			(layer "F.Fab")
		)
		(fp_line
			(start 0.12065 -0.3048)
			(end 0.67945 -0.3048)
			(stroke
				(width 0.1)
				(type default)
			)
			(layer "F.Fab")
		)
		(fp_line
			(start 0.12065 -0.2794)
			(end 0.12065 -0.3048)
			(stroke
				(width 0.1)
				(type default)
			)
			(layer "F.Fab")
		)
		(fp_line
			(start -0.12065 -0.2794)
			(end 0.12065 -0.2794)
			(stroke
				(width 0.1)
				(type default)
			)
			(layer "F.Fab")
		)
		(fp_line
			(start 0.120396 0.2794)
			(end -0.12065 0.2794)
			(stroke
				(width 0.1)
				(type default)
			)
			(layer "F.Fab")
		)
		(fp_line
			(start -0.12065 0.2794)
			(end -0.12065 0.3048)
			(stroke
				(width 0.1)
				(type default)
			)
			(layer "F.Fab")
		)
		(fp_line
			(start 0.67945 0.3048)
			(end 0.120396 0.3048)
			(stroke
				(width 0.1)
				(type default)
			)
			(layer "F.Fab")
		)
		(fp_line
			(start 0.120396 0.3048)
			(end 0.120396 0.2794)
			(stroke
				(width 0.1)
				(type default)
			)
			(layer "F.Fab")
		)
		(fp_line
			(start -0.12065 0.3048)
			(end -0.67945 0.3048)
			(stroke
				(width 0.1)
				(type default)
			)
			(layer "F.Fab")
		)
		(fp_line
			(start -0.67945 0.3048)
			(end -0.67945 -0.305054)
			(stroke
				(width 0.1)
				(type default)
			)
			(layer "F.Fab")
		)
		(pad "1" smd circle
			(at -0.40005 0 90)
			(size 0 0)
			(layers "F.Cu" "F.Mask" "F.Paste")
			(net "FM_P12V_HSC_EN_N")
		)
		(pad "2" smd circle
			(at 0.40005 0 90)
			(size 0 0)
			(layers "F.Cu" "F.Mask" "F.Paste")
			(net "FM_P12V_HSC_EN_R_N")
		)
	)
	(footprint ""
		(layer "F.Cu")
		(at 226.903788 -222.09887 180)
		(property "Reference" "R972"
			(at 0 0 180)
			(layer "F.SilkS")
			(hide yes)
			(effects
				(font
					(size 1.27 1.27)
				)
			)
		)
		(property "Value" ""
			(at 0 0 180)
			(layer "F.Fab")
			(effects
				(font
					(size 1.27 1.27)
				)
			)
		)
		(duplicate_pad_numbers_are_jumpers no)
		(fp_line
			(start 0.7874 0.4064)
			(end -0.7874 0.4064)
			(stroke
				(width 0.1524)
				(type default)
			)
			(layer "F.SilkS")
		)
		(fp_line
			(start 0.7874 -0.4064)
			(end 0.7874 0.4064)
			(stroke
				(width 0.1524)
				(type default)
			)
			(layer "F.SilkS")
		)
		(fp_line
			(start -0.7874 0.4064)
			(end -0.7874 -0.4064)
			(stroke
				(width 0.1524)
				(type default)
			)
			(layer "F.SilkS")
		)
		(fp_line
			(start -0.7874 -0.4064)
			(end 0.7874 -0.4064)
			(stroke
				(width 0.1524)
				(type default)
			)
			(layer "F.SilkS")
		)
		(fp_line
			(start 0.67945 0.3048)
			(end 0.120396 0.3048)
			(stroke
				(width 0.1)
				(type default)
			)
			(layer "F.Fab")
		)
		(fp_line
			(start 0.67945 -0.3048)
			(end 0.67945 0.3048)
			(stroke
				(width 0.1)
				(type default)
			)
			(layer "F.Fab")
		)
		(fp_line
			(start 0.12065 -0.2794)
			(end 0.12065 -0.3048)
			(stroke
				(width 0.1)
				(type default)
			)
			(layer "F.Fab")
		)
		(fp_line
			(start 0.12065 -0.3048)
			(end 0.67945 -0.3048)
			(stroke
				(width 0.1)
				(type default)
			)
			(layer "F.Fab")
		)
		(fp_line
			(start 0.120396 0.3048)
			(end 0.120396 0.2794)
			(stroke
				(width 0.1)
				(type default)
			)
			(layer "F.Fab")
		)
		(fp_line
			(start 0.120396 0.2794)
			(end -0.12065 0.2794)
			(stroke
				(width 0.1)
				(type default)
			)
			(layer "F.Fab")
		)
		(fp_line
			(start -0.12065 0.3048)
			(end -0.67945 0.3048)
			(stroke
				(width 0.1)
				(type default)
			)
			(layer "F.Fab")
		)
		(fp_line
			(start -0.12065 0.2794)
			(end -0.12065 0.3048)
			(stroke
				(width 0.1)
				(type default)
			)
			(layer "F.Fab")
		)
		(fp_line
			(start -0.12065 -0.2794)
			(end 0.12065 -0.2794)
			(stroke
				(width 0.1)
				(type default)
			)
			(layer "F.Fab")
		)
		(fp_line
			(start -0.12065 -0.305054)
			(end -0.12065 -0.2794)
			(stroke
				(width 0.1)
				(type default)
			)
			(layer "F.Fab")
		)
		(fp_line
			(start -0.67945 0.3048)
			(end -0.67945 -0.305054)
			(stroke
				(width 0.1)
				(type default)
			)
			(layer "F.Fab")
		)
		(fp_line
			(start -0.67945 -0.305054)
			(end -0.12065 -0.305054)
			(stroke
				(width 0.1)
				(type default)
			)
			(layer "F.Fab")
		)
		(pad "1" smd circle
			(at -0.40005 0 180)
			(size 0 0)
			(layers "F.Cu" "F.Mask" "F.Paste")
			(net "PVNN_TERM_CPU1")
		)
		(pad "2" smd circle
			(at 0.40005 0 180)
			(size 0 0)
			(layers "F.Cu" "F.Mask" "F.Paste")
			(net "SMB_S3M_CPU1_R_SDA")
		)
	)
	(footprint ""
		(layer "F.Cu")
		(at 96.141286 -427.776386 -90)
		(property "Reference" "R3525"
			(at 0 0 270)
			(layer "F.SilkS")
			(hide yes)
			(effects
				(font
					(size 1.27 1.27)
				)
			)
		)
		(property "Value" ""
			(at 0 0 270)
			(layer "F.Fab")
			(effects
				(font
					(size 1.27 1.27)
				)
			)
		)
		(duplicate_pad_numbers_are_jumpers no)
		(fp_line
			(start -0.7874 0.4064)
			(end -0.7874 -0.4064)
			(stroke
				(width 0.1524)
				(type default)
			)
			(layer "F.SilkS")
		)
		(fp_line
			(start 0.7874 0.4064)
			(end -0.7874 0.4064)
			(stroke
				(width 0.1524)
				(type default)
			)
			(layer "F.SilkS")
		)
		(fp_line
			(start -0.7874 -0.4064)
			(end 0.7874 -0.4064)
			(stroke
				(width 0.1524)
				(type default)
			)
			(layer "F.SilkS")
		)
		(fp_line
			(start 0.7874 -0.4064)
			(end 0.7874 0.4064)
			(stroke
				(width 0.1524)
				(type default)
			)
			(layer "F.SilkS")
		)
		(fp_line
			(start -0.67945 0.3048)
			(end -0.67945 -0.305054)
			(stroke
				(width 0.1)
				(type default)
			)
			(layer "F.Fab")
		)
		(fp_line
			(start -0.12065 0.3048)
			(end -0.67945 0.3048)
			(stroke
				(width 0.1)
				(type default)
			)
			(layer "F.Fab")
		)
		(fp_line
			(start 0.120396 0.3048)
			(end 0.120396 0.2794)
			(stroke
				(width 0.1)
				(type default)
			)
			(layer "F.Fab")
		)
		(fp_line
			(start 0.67945 0.3048)
			(end 0.120396 0.3048)
			(stroke
				(width 0.1)
				(type default)
			)
			(layer "F.Fab")
		)
		(fp_line
			(start -0.12065 0.2794)
			(end -0.12065 0.3048)
			(stroke
				(width 0.1)
				(type default)
			)
			(layer "F.Fab")
		)
		(fp_line
			(start 0.120396 0.2794)
			(end -0.12065 0.2794)
			(stroke
				(width 0.1)
				(type default)
			)
			(layer "F.Fab")
		)
		(fp_line
			(start -0.12065 -0.2794)
			(end 0.12065 -0.2794)
			(stroke
				(width 0.1)
				(type default)
			)
			(layer "F.Fab")
		)
		(fp_line
			(start 0.12065 -0.2794)
			(end 0.12065 -0.3048)
			(stroke
				(width 0.1)
				(type default)
			)
			(layer "F.Fab")
		)
		(fp_line
			(start 0.12065 -0.3048)
			(end 0.67945 -0.3048)
			(stroke
				(width 0.1)
				(type default)
			)
			(layer "F.Fab")
		)
		(fp_line
			(start 0.67945 -0.3048)
			(end 0.67945 0.3048)
			(stroke
				(width 0.1)
				(type default)
			)
			(layer "F.Fab")
		)
		(fp_line
			(start -0.67945 -0.305054)
			(end -0.12065 -0.305054)
			(stroke
				(width 0.1)
				(type default)
			)
			(layer "F.Fab")
		)
		(fp_line
			(start -0.12065 -0.305054)
			(end -0.12065 -0.2794)
			(stroke
				(width 0.1)
				(type default)
			)
			(layer "F.Fab")
		)
		(pad "1" smd circle
			(at -0.40005 0 270)
			(size 0 0)
			(layers "F.Cu" "F.Mask" "F.Paste")
			(net "P3V3_AUX")
		)
		(pad "2" smd circle
			(at 0.40005 0 270)
			(size 0 0)
			(layers "F.Cu" "F.Mask" "F.Paste")
			(net "GPU_FPGA_EROT_FATALERR_N")
		)
	)
	(footprint ""
		(layer "F.Cu")
		(at 106.584496 -70.78599)
		(property "Reference" "D78"
			(at -53.121306 50.178462 90)
			(unlocked yes)
			(layer "F.SilkS")
			(effects
				(font
					(size 0.635 0.4064)
					(thickness 0.1524)
				)
				(justify left)
			)
		)
		(property "Value" ""
			(at 0 0 0)
			(layer "F.Fab")
			(effects
				(font
					(size 1.27 1.27)
				)
			)
		)
		(duplicate_pad_numbers_are_jumpers no)
		(fp_line
			(start -0.90678 0.4826)
			(end -0.90678 -0.4699)
			(stroke
				(width 0.1524)
				(type default)
			)
			(layer "F.SilkS")
		)
		(fp_line
			(start -0.89408 -0.4826)
			(end 0.90678 -0.4826)
			(stroke
				(width 0.1524)
				(type default)
			)
			(layer "F.SilkS")
		)
		(fp_line
			(start -0.79248 -0.4826)
			(end 1.03378 -0.4826)
			(stroke
				(width 0.1524)
				(type default)
			)
			(layer "F.SilkS")
		)
		(fp_line
			(start -0.64008 -0.4826)
			(end 1.16078 -0.4826)
			(stroke
				(width 0.1524)
				(type default)
			)
			(layer "F.SilkS")
		)
		(fp_line
			(start 0.90678 -0.4826)
			(end 0.90678 0.4826)
			(stroke
				(width 0.1524)
				(type default)
			)
			(layer "F.SilkS")
		)
		(fp_line
			(start 0.90678 0.4826)
			(end -0.90678 0.4826)
			(stroke
				(width 0.1524)
				(type default)
			)
			(layer "F.SilkS")
		)
		(fp_line
			(start 1.03378 -0.4826)
			(end 1.03378 0.4826)
			(stroke
				(width 0.1524)
				(type default)
			)
			(layer "F.SilkS")
		)
		(fp_line
			(start 1.03378 0.4826)
			(end -0.79248 0.4826)
			(stroke
				(width 0.1524)
				(type default)
			)
			(layer "F.SilkS")
		)
		(fp_line
			(start 1.16078 -0.4826)
			(end 1.16078 0.4826)
			(stroke
				(width 0.1524)
				(type default)
			)
			(layer "F.SilkS")
		)
		(fp_line
			(start 1.16078 0.4826)
			(end -0.64008 0.4826)
			(stroke
				(width 0.1524)
				(type default)
			)
			(layer "F.SilkS")
		)
		(fp_line
			(start -0.499872 -0.249936)
			(end 0.499872 -0.249936)
			(stroke
				(width 0.1)
				(type default)
			)
			(layer "F.Fab")
		)
		(fp_line
			(start -0.499872 0.249936)
			(end -0.499872 -0.249936)
			(stroke
				(width 0.1)
				(type default)
			)
			(layer "F.Fab")
		)
		(fp_line
			(start 0.499872 -0.249936)
			(end 0.499872 0.249936)
			(stroke
				(width 0.1)
				(type default)
			)
			(layer "F.Fab")
		)
		(fp_line
			(start 0.499872 0.249936)
			(end -0.499872 0.249936)
			(stroke
				(width 0.1)
				(type default)
			)
			(layer "F.Fab")
		)
		(pad "A" smd rect
			(at -0.47498 0)
			(size 0.6096 0.7112)
			(layers "F.Cu" "F.Mask" "F.Paste")
			(net "LED_PWRGD_PVNN_MAIN_CPU0")
		)
		(pad "C" smd rect
			(at 0.47498 0)
			(size 0.6096 0.7112)
			(layers "F.Cu" "F.Mask" "F.Paste")
			(net "LED_PWRGD_PVNN_MAIN_CPU0_D")
		)
	)
	(footprint ""
		(layer "F.Cu")
		(at 363.64672 -403.322028)
		(property "Reference" "U204"
			(at -0.13208 1.83261 0)
			(unlocked yes)
			(layer "F.SilkS")
			(effects
				(font
					(size 0.7874 0.5842)
					(thickness 0.1524)
				)
				(justify left)
			)
		)
		(property "Value" ""
			(at 0 0 0)
			(layer "F.Fab")
			(effects
				(font
					(size 1.27 1.27)
				)
			)
		)
		(duplicate_pad_numbers_are_jumpers no)
		(fp_line
			(start -1.400048 1.100074)
			(end -1.400048 -1.100074)
			(stroke
				(width 0.1524)
				(type default)
			)
			(layer "F.SilkS")
		)
		(fp_line
			(start 1.400048 -1.100074)
			(end -1.400048 -1.100074)
			(stroke
				(width 0.1524)
				(type default)
			)
			(layer "F.SilkS")
		)
		(fp_line
			(start 1.400048 -1.100074)
			(end 1.400048 1.100074)
			(stroke
				(width 0.1524)
				(type default)
			)
			(layer "F.SilkS")
		)
		(fp_line
			(start 1.400048 1.100074)
			(end -1.400048 1.100074)
			(stroke
				(width 0.1524)
				(type default)
			)
			(layer "F.SilkS")
		)
		(fp_poly
			(pts
				(xy -0.95631 -1.391412) (xy -1.46431 -2.407412) (xy -0.44831 -2.407412)
			)
			(stroke
				(width 0)
				(type default)
			)
			(fill yes)
			(layer "F.SilkS")
		)
		(fp_line
			(start -0.674878 -1.100074)
			(end 0.674878 -1.100074)
			(stroke
				(width 0.1)
				(type default)
			)
			(layer "F.Fab")
		)
		(fp_line
			(start -0.674878 1.100074)
			(end -0.674878 -1.100074)
			(stroke
				(width 0.1)
				(type default)
			)
			(layer "F.Fab")
		)
		(fp_line
			(start 0.674878 -1.100074)
			(end 0.674878 1.100074)
			(stroke
				(width 0.1)
				(type default)
			)
			(layer "F.Fab")
		)
		(fp_line
			(start 0.674878 1.100074)
			(end -0.674878 1.100074)
			(stroke
				(width 0.1)
				(type default)
			)
			(layer "F.Fab")
		)
		(fp_poly
			(pts
				(xy -1.590548 -0.649986) (xy -2.606548 -1.157986) (xy -2.606548 -0.141986)
			)
			(stroke
				(width 0)
				(type default)
			)
			(fill yes)
			(layer "F.Fab")
		)
		(pad "1" smd rect
			(at -0.94996 -0.649986 270)
			(size 0.4318 0.6096)
			(layers "F.Cu" "F.Mask" "F.Paste")
			(net "FM_UART_EN")
		)
		(pad "2" smd rect
			(at -0.94996 0 270)
			(size 0.4318 0.6096)
			(layers "F.Cu" "F.Mask" "F.Paste")
			(net "UART_BMC_BIC_R_RX")
		)
		(pad "3" smd rect
			(at -0.94996 0.649986 270)
			(size 0.4318 0.6096)
			(layers "F.Cu" "F.Mask" "F.Paste")
			(net "GND")
		)
		(pad "4" smd rect
			(at 0.94996 0.649986 270)
			(size 0.4318 0.6096)
			(layers "F.Cu" "F.Mask" "F.Paste")
			(net "UART_BMC_BIC_R_BUF_RX")
		)
		(pad "5" smd rect
			(at 0.94996 -0.649986 270)
			(size 0.4318 0.6096)
			(layers "F.Cu" "F.Mask" "F.Paste")
			(net "P3V3_AUX")
		)
	)
	(footprint ""
		(layer "F.Cu")
		(at 466.67547 -48.940212 180)
		(property "Reference" "R1592"
			(at 0 0 180)
			(layer "F.SilkS")
			(hide yes)
			(effects
				(font
					(size 1.27 1.27)
				)
			)
		)
		(property "Value" ""
			(at 0 0 180)
			(layer "F.Fab")
			(effects
				(font
					(size 1.27 1.27)
				)
			)
		)
		(duplicate_pad_numbers_are_jumpers no)
		(fp_line
			(start 0.7874 0.4064)
			(end -0.7874 0.4064)
			(stroke
				(width 0.1524)
				(type default)
			)
			(layer "F.SilkS")
		)
		(fp_line
			(start 0.7874 -0.4064)
			(end 0.7874 0.4064)
			(stroke
				(width 0.1524)
				(type default)
			)
			(layer "F.SilkS")
		)
		(fp_line
			(start -0.7874 0.4064)
			(end -0.7874 -0.4064)
			(stroke
				(width 0.1524)
				(type default)
			)
			(layer "F.SilkS")
		)
		(fp_line
			(start -0.7874 -0.4064)
			(end 0.7874 -0.4064)
			(stroke
				(width 0.1524)
				(type default)
			)
			(layer "F.SilkS")
		)
		(fp_line
			(start 0.67945 0.3048)
			(end 0.120396 0.3048)
			(stroke
				(width 0.1)
				(type default)
			)
			(layer "F.Fab")
		)
		(fp_line
			(start 0.67945 -0.3048)
			(end 0.67945 0.3048)
			(stroke
				(width 0.1)
				(type default)
			)
			(layer "F.Fab")
		)
		(fp_line
			(start 0.12065 -0.2794)
			(end 0.12065 -0.3048)
			(stroke
				(width 0.1)
				(type default)
			)
			(layer "F.Fab")
		)
		(fp_line
			(start 0.12065 -0.3048)
			(end 0.67945 -0.3048)
			(stroke
				(width 0.1)
				(type default)
			)
			(layer "F.Fab")
		)
		(fp_line
			(start 0.120396 0.3048)
			(end 0.120396 0.2794)
			(stroke
				(width 0.1)
				(type default)
			)
			(layer "F.Fab")
		)
		(fp_line
			(start 0.120396 0.2794)
			(end -0.12065 0.2794)
			(stroke
				(width 0.1)
				(type default)
			)
			(layer "F.Fab")
		)
		(fp_line
			(start -0.12065 0.3048)
			(end -0.67945 0.3048)
			(stroke
				(width 0.1)
				(type default)
			)
			(layer "F.Fab")
		)
		(fp_line
			(start -0.12065 0.2794)
			(end -0.12065 0.3048)
			(stroke
				(width 0.1)
				(type default)
			)
			(layer "F.Fab")
		)
		(fp_line
			(start -0.12065 -0.2794)
			(end 0.12065 -0.2794)
			(stroke
				(width 0.1)
				(type default)
			)
			(layer "F.Fab")
		)
		(fp_line
			(start -0.12065 -0.305054)
			(end -0.12065 -0.2794)
			(stroke
				(width 0.1)
				(type default)
			)
			(layer "F.Fab")
		)
		(fp_line
			(start -0.67945 0.3048)
			(end -0.67945 -0.305054)
			(stroke
				(width 0.1)
				(type default)
			)
			(layer "F.Fab")
		)
		(fp_line
			(start -0.67945 -0.305054)
			(end -0.12065 -0.305054)
			(stroke
				(width 0.1)
				(type default)
			)
			(layer "F.Fab")
		)
		(pad "1" smd circle
			(at -0.40005 0 180)
			(size 0 0)
			(layers "F.Cu" "F.Mask" "F.Paste")
			(net "P3V3_OCP_SFF")
		)
		(pad "2" smd circle
			(at 0.40005 0 180)
			(size 0 0)
			(layers "F.Cu" "F.Mask" "F.Paste")
			(net "PU_OCP_SFF_WAKE_OE")
		)
	)
	(footprint ""
		(layer "F.Cu")
		(at 46.626018 -440.205368 180)
		(property "Reference" "R3107"
			(at 0 0 180)
			(layer "F.SilkS")
			(hide yes)
			(effects
				(font
					(size 1.27 1.27)
				)
			)
		)
		(property "Value" ""
			(at 0 0 180)
			(layer "F.Fab")
			(effects
				(font
					(size 1.27 1.27)
				)
			)
		)
		(duplicate_pad_numbers_are_jumpers no)
		(fp_line
			(start 0.7874 0.4064)
			(end -0.7874 0.4064)
			(stroke
				(width 0.1524)
				(type default)
			)
			(layer "F.SilkS")
		)
		(fp_line
			(start 0.7874 -0.4064)
			(end 0.7874 0.4064)
			(stroke
				(width 0.1524)
				(type default)
			)
			(layer "F.SilkS")
		)
		(fp_line
			(start -0.7874 0.4064)
			(end -0.7874 -0.4064)
			(stroke
				(width 0.1524)
				(type default)
			)
			(layer "F.SilkS")
		)
		(fp_line
			(start -0.7874 -0.4064)
			(end 0.7874 -0.4064)
			(stroke
				(width 0.1524)
				(type default)
			)
			(layer "F.SilkS")
		)
		(fp_line
			(start 0.67945 0.3048)
			(end 0.120396 0.3048)
			(stroke
				(width 0.1)
				(type default)
			)
			(layer "F.Fab")
		)
		(fp_line
			(start 0.67945 -0.3048)
			(end 0.67945 0.3048)
			(stroke
				(width 0.1)
				(type default)
			)
			(layer "F.Fab")
		)
		(fp_line
			(start 0.12065 -0.2794)
			(end 0.12065 -0.3048)
			(stroke
				(width 0.1)
				(type default)
			)
			(layer "F.Fab")
		)
		(fp_line
			(start 0.12065 -0.3048)
			(end 0.67945 -0.3048)
			(stroke
				(width 0.1)
				(type default)
			)
			(layer "F.Fab")
		)
		(fp_line
			(start 0.120396 0.3048)
			(end 0.120396 0.2794)
			(stroke
				(width 0.1)
				(type default)
			)
			(layer "F.Fab")
		)
		(fp_line
			(start 0.120396 0.2794)
			(end -0.12065 0.2794)
			(stroke
				(width 0.1)
				(type default)
			)
			(layer "F.Fab")
		)
		(fp_line
			(start -0.12065 0.3048)
			(end -0.67945 0.3048)
			(stroke
				(width 0.1)
				(type default)
			)
			(layer "F.Fab")
		)
		(fp_line
			(start -0.12065 0.2794)
			(end -0.12065 0.3048)
			(stroke
				(width 0.1)
				(type default)
			)
			(layer "F.Fab")
		)
		(fp_line
			(start -0.12065 -0.2794)
			(end 0.12065 -0.2794)
			(stroke
				(width 0.1)
				(type default)
			)
			(layer "F.Fab")
		)
		(fp_line
			(start -0.12065 -0.305054)
			(end -0.12065 -0.2794)
			(stroke
				(width 0.1)
				(type default)
			)
			(layer "F.Fab")
		)
		(fp_line
			(start -0.67945 0.3048)
			(end -0.67945 -0.305054)
			(stroke
				(width 0.1)
				(type default)
			)
			(layer "F.Fab")
		)
		(fp_line
			(start -0.67945 -0.305054)
			(end -0.12065 -0.305054)
			(stroke
				(width 0.1)
				(type default)
			)
			(layer "F.Fab")
		)
		(pad "1" smd circle
			(at -0.40005 0 180)
			(size 0 0)
			(layers "F.Cu" "F.Mask" "F.Paste")
			(net "SMB_2_BMC_GPU_SCL")
		)
		(pad "2" smd circle
			(at 0.40005 0 180)
			(size 0 0)
			(layers "F.Cu" "F.Mask" "F.Paste")
			(net "SMB_2_BMC_GPU_R_SCL")
		)
	)
	(footprint ""
		(layer "F.Cu")
		(at 46.626018 -439.189368 180)
		(property "Reference" "R3521"
			(at 0 0 180)
			(layer "F.SilkS")
			(hide yes)
			(effects
				(font
					(size 1.27 1.27)
				)
			)
		)
		(property "Value" ""
			(at 0 0 180)
			(layer "F.Fab")
			(effects
				(font
					(size 1.27 1.27)
				)
			)
		)
		(duplicate_pad_numbers_are_jumpers no)
		(fp_line
			(start 0.7874 0.4064)
			(end -0.7874 0.4064)
			(stroke
				(width 0.1524)
				(type default)
			)
			(layer "F.SilkS")
		)
		(fp_line
			(start 0.7874 -0.4064)
			(end 0.7874 0.4064)
			(stroke
				(width 0.1524)
				(type default)
			)
			(layer "F.SilkS")
		)
		(fp_line
			(start -0.7874 0.4064)
			(end -0.7874 -0.4064)
			(stroke
				(width 0.1524)
				(type default)
			)
			(layer "F.SilkS")
		)
		(fp_line
			(start -0.7874 -0.4064)
			(end 0.7874 -0.4064)
			(stroke
				(width 0.1524)
				(type default)
			)
			(layer "F.SilkS")
		)
		(fp_line
			(start 0.67945 0.3048)
			(end 0.120396 0.3048)
			(stroke
				(width 0.1)
				(type default)
			)
			(layer "F.Fab")
		)
		(fp_line
			(start 0.67945 -0.3048)
			(end 0.67945 0.3048)
			(stroke
				(width 0.1)
				(type default)
			)
			(layer "F.Fab")
		)
		(fp_line
			(start 0.12065 -0.2794)
			(end 0.12065 -0.3048)
			(stroke
				(width 0.1)
				(type default)
			)
			(layer "F.Fab")
		)
		(fp_line
			(start 0.12065 -0.3048)
			(end 0.67945 -0.3048)
			(stroke
				(width 0.1)
				(type default)
			)
			(layer "F.Fab")
		)
		(fp_line
			(start 0.120396 0.3048)
			(end 0.120396 0.2794)
			(stroke
				(width 0.1)
				(type default)
			)
			(layer "F.Fab")
		)
		(fp_line
			(start 0.120396 0.2794)
			(end -0.12065 0.2794)
			(stroke
				(width 0.1)
				(type default)
			)
			(layer "F.Fab")
		)
		(fp_line
			(start -0.12065 0.3048)
			(end -0.67945 0.3048)
			(stroke
				(width 0.1)
				(type default)
			)
			(layer "F.Fab")
		)
		(fp_line
			(start -0.12065 0.2794)
			(end -0.12065 0.3048)
			(stroke
				(width 0.1)
				(type default)
			)
			(layer "F.Fab")
		)
		(fp_line
			(start -0.12065 -0.2794)
			(end 0.12065 -0.2794)
			(stroke
				(width 0.1)
				(type default)
			)
			(layer "F.Fab")
		)
		(fp_line
			(start -0.12065 -0.305054)
			(end -0.12065 -0.2794)
			(stroke
				(width 0.1)
				(type default)
			)
			(layer "F.Fab")
		)
		(fp_line
			(start -0.67945 0.3048)
			(end -0.67945 -0.305054)
			(stroke
				(width 0.1)
				(type default)
			)
			(layer "F.Fab")
		)
		(fp_line
			(start -0.67945 -0.305054)
			(end -0.12065 -0.305054)
			(stroke
				(width 0.1)
				(type default)
			)
			(layer "F.Fab")
		)
		(pad "1" smd circle
			(at -0.40005 0 180)
			(size 0 0)
			(layers "F.Cu" "F.Mask" "F.Paste")
			(net "P3V3_AUX")
		)
		(pad "2" smd circle
			(at 0.40005 0 180)
			(size 0 0)
			(layers "F.Cu" "F.Mask" "F.Paste")
			(net "SMB_2_BMC_GPU_BUF_R_SCL")
		)
	)
	(footprint ""
		(layer "F.Cu")
		(at 208.49336 -121.1072 180)
		(property "Reference" "C2370"
			(at 0 0 180)
			(layer "F.SilkS")
			(hide yes)
			(effects
				(font
					(size 1.27 1.27)
				)
			)
		)
		(property "Value" ""
			(at 0 0 180)
			(layer "F.Fab")
			(effects
				(font
					(size 1.27 1.27)
				)
			)
		)
		(duplicate_pad_numbers_are_jumpers no)
		(fp_line
			(start 0.7874 0.4064)
			(end -0.7874 0.4064)
			(stroke
				(width 0.1524)
				(type default)
			)
			(layer "F.SilkS")
		)
		(fp_line
			(start 0.7874 -0.4064)
			(end 0.7874 0.4064)
			(stroke
				(width 0.1524)
				(type default)
			)
			(layer "F.SilkS")
		)
		(fp_line
			(start -0.7874 0.4064)
			(end -0.7874 -0.4064)
			(stroke
				(width 0.1524)
				(type default)
			)
			(layer "F.SilkS")
		)
		(fp_line
			(start -0.7874 -0.4064)
			(end 0.7874 -0.4064)
			(stroke
				(width 0.1524)
				(type default)
			)
			(layer "F.SilkS")
		)
		(fp_line
			(start 0.67945 0.3048)
			(end 0.120396 0.3048)
			(stroke
				(width 0.1)
				(type default)
			)
			(layer "F.Fab")
		)
		(fp_line
			(start 0.67945 -0.3048)
			(end 0.67945 0.3048)
			(stroke
				(width 0.1)
				(type default)
			)
			(layer "F.Fab")
		)
		(fp_line
			(start 0.12065 -0.2794)
			(end 0.12065 -0.3048)
			(stroke
				(width 0.1)
				(type default)
			)
			(layer "F.Fab")
		)
		(fp_line
			(start 0.12065 -0.3048)
			(end 0.67945 -0.3048)
			(stroke
				(width 0.1)
				(type default)
			)
			(layer "F.Fab")
		)
		(fp_line
			(start 0.120396 0.3048)
			(end 0.120396 0.2794)
			(stroke
				(width 0.1)
				(type default)
			)
			(layer "F.Fab")
		)
		(fp_line
			(start 0.120396 0.2794)
			(end -0.12065 0.2794)
			(stroke
				(width 0.1)
				(type default)
			)
			(layer "F.Fab")
		)
		(fp_line
			(start -0.12065 0.3048)
			(end -0.67945 0.3048)
			(stroke
				(width 0.1)
				(type default)
			)
			(layer "F.Fab")
		)
		(fp_line
			(start -0.12065 0.2794)
			(end -0.12065 0.3048)
			(stroke
				(width 0.1)
				(type default)
			)
			(layer "F.Fab")
		)
		(fp_line
			(start -0.12065 -0.2794)
			(end 0.12065 -0.2794)
			(stroke
				(width 0.1)
				(type default)
			)
			(layer "F.Fab")
		)
		(fp_line
			(start -0.12065 -0.305054)
			(end -0.12065 -0.2794)
			(stroke
				(width 0.1)
				(type default)
			)
			(layer "F.Fab")
		)
		(fp_line
			(start -0.67945 0.3048)
			(end -0.67945 -0.305054)
			(stroke
				(width 0.1)
				(type default)
			)
			(layer "F.Fab")
		)
		(fp_line
			(start -0.67945 -0.305054)
			(end -0.12065 -0.305054)
			(stroke
				(width 0.1)
				(type default)
			)
			(layer "F.Fab")
		)
		(pad "1" smd circle
			(at -0.40005 0 180)
			(size 0 0)
			(layers "F.Cu" "F.Mask" "F.Paste")
			(net "P3V3_AUX")
		)
		(pad "2" smd circle
			(at 0.40005 0 180)
			(size 0 0)
			(layers "F.Cu" "F.Mask" "F.Paste")
			(net "GND")
		)
	)
	(footprint ""
		(layer "F.Cu")
		(at 282.61818 -137.577068)
		(property "Reference" ""
			(at 0 0 0)
			(layer "F.SilkS")
			(hide yes)
			(effects
				(font
					(size 1.27 1.27)
				)
			)
		)
		(property "Value" ""
			(at 0 0 0)
			(layer "F.Fab")
			(effects
				(font
					(size 1.27 1.27)
				)
			)
		)
		(duplicate_pad_numbers_are_jumpers no)
		(pad "1" smd circle
			(at 0 0)
			(size 0.9906 0.9906)
			(layers "F.Cu" "F.Mask" "F.Paste")
			(net "Net_289")
		)
		(zone
			(layer "F.Cu")
			(hatch none 0.5)
			(connect_pads
				(clearance 0)
			)
			(min_thickness 0.25)
			(keepout
				(tracks not_allowed)
				(vias allowed)
				(pads allowed)
				(copperpour not_allowed)
				(footprints allowed)
			)
			(placement
				(enabled no)
				(sheetname "")
			)
			(fill
				(thermal_gap 0.5)
				(thermal_bridge_width 0.5)
				(island_removal_mode 0)
			)
			(polygon
				(pts
					(arc
						(start 284.24378 -137.577068)
						(mid 280.99258 -137.577068)
						(end 284.24378 -137.577068)
					)
				)
			)
		)
	)
	(footprint ""
		(layer "F.Cu")
		(at 106.70921 -415.757868 180)
		(property "Reference" "R3352"
			(at 0 0 180)
			(layer "F.SilkS")
			(hide yes)
			(effects
				(font
					(size 1.27 1.27)
				)
			)
		)
		(property "Value" ""
			(at 0 0 180)
			(layer "F.Fab")
			(effects
				(font
					(size 1.27 1.27)
				)
			)
		)
		(duplicate_pad_numbers_are_jumpers no)
		(fp_line
			(start 0.7874 0.4064)
			(end -0.7874 0.4064)
			(stroke
				(width 0.1524)
				(type default)
			)
			(layer "F.SilkS")
		)
		(fp_line
			(start 0.7874 -0.1397)
			(end 0.7874 0.4064)
			(stroke
				(width 0.1524)
				(type default)
			)
			(layer "F.SilkS")
		)
		(fp_line
			(start -0.44577 -0.4064)
			(end 0.47371 -0.4064)
			(stroke
				(width 0.1524)
				(type default)
			)
			(layer "F.SilkS")
		)
		(fp_line
			(start -0.7874 0.4064)
			(end -0.7874 -0.16256)
			(stroke
				(width 0.1524)
				(type default)
			)
			(layer "F.SilkS")
		)
		(fp_line
			(start 0.67945 0.3048)
			(end 0.120396 0.3048)
			(stroke
				(width 0.1)
				(type default)
			)
			(layer "F.Fab")
		)
		(fp_line
			(start 0.67945 -0.3048)
			(end 0.67945 0.3048)
			(stroke
				(width 0.1)
				(type default)
			)
			(layer "F.Fab")
		)
		(fp_line
			(start 0.12065 -0.2794)
			(end 0.12065 -0.3048)
			(stroke
				(width 0.1)
				(type default)
			)
			(layer "F.Fab")
		)
		(fp_line
			(start 0.12065 -0.3048)
			(end 0.67945 -0.3048)
			(stroke
				(width 0.1)
				(type default)
			)
			(layer "F.Fab")
		)
		(fp_line
			(start 0.120396 0.3048)
			(end 0.120396 0.2794)
			(stroke
				(width 0.1)
				(type default)
			)
			(layer "F.Fab")
		)
		(fp_line
			(start 0.120396 0.2794)
			(end -0.12065 0.2794)
			(stroke
				(width 0.1)
				(type default)
			)
			(layer "F.Fab")
		)
		(fp_line
			(start -0.12065 0.3048)
			(end -0.67945 0.3048)
			(stroke
				(width 0.1)
				(type default)
			)
			(layer "F.Fab")
		)
		(fp_line
			(start -0.12065 0.2794)
			(end -0.12065 0.3048)
			(stroke
				(width 0.1)
				(type default)
			)
			(layer "F.Fab")
		)
		(fp_line
			(start -0.12065 -0.2794)
			(end 0.12065 -0.2794)
			(stroke
				(width 0.1)
				(type default)
			)
			(layer "F.Fab")
		)
		(fp_line
			(start -0.12065 -0.305054)
			(end -0.12065 -0.2794)
			(stroke
				(width 0.1)
				(type default)
			)
			(layer "F.Fab")
		)
		(fp_line
			(start -0.67945 0.3048)
			(end -0.67945 -0.305054)
			(stroke
				(width 0.1)
				(type default)
			)
			(layer "F.Fab")
		)
		(fp_line
			(start -0.67945 -0.305054)
			(end -0.12065 -0.305054)
			(stroke
				(width 0.1)
				(type default)
			)
			(layer "F.Fab")
		)
		(pad "1" smd circle
			(at -0.40005 0 180)
			(size 0 0)
			(layers "F.Cu" "F.Mask" "F.Paste")
			(net "CLK_100M_GPU_1_R_DP")
		)
		(pad "2" smd circle
			(at 0.40005 0 180)
			(size 0 0)
			(layers "F.Cu" "F.Mask" "F.Paste")
			(net "CLK_100M_GPU_1_DP")
		)
	)
	(footprint ""
		(layer "F.Cu")
		(at 348.390464 -357.494332 180)
		(property "Reference" "R2381"
			(at 0 0 180)
			(layer "F.SilkS")
			(hide yes)
			(effects
				(font
					(size 1.27 1.27)
				)
			)
		)
		(property "Value" ""
			(at 0 0 180)
			(layer "F.Fab")
			(effects
				(font
					(size 1.27 1.27)
				)
			)
		)
		(duplicate_pad_numbers_are_jumpers no)
		(fp_line
			(start 0.7874 0.4064)
			(end -0.7874 0.4064)
			(stroke
				(width 0.1524)
				(type default)
			)
			(layer "F.SilkS")
		)
		(fp_line
			(start 0.7874 -0.4064)
			(end 0.7874 0.4064)
			(stroke
				(width 0.1524)
				(type default)
			)
			(layer "F.SilkS")
		)
		(fp_line
			(start -0.7874 0.4064)
			(end -0.7874 -0.4064)
			(stroke
				(width 0.1524)
				(type default)
			)
			(layer "F.SilkS")
		)
		(fp_line
			(start -0.7874 -0.4064)
			(end 0.7874 -0.4064)
			(stroke
				(width 0.1524)
				(type default)
			)
			(layer "F.SilkS")
		)
		(fp_line
			(start 0.67945 0.3048)
			(end 0.120396 0.3048)
			(stroke
				(width 0.1)
				(type default)
			)
			(layer "F.Fab")
		)
		(fp_line
			(start 0.67945 -0.3048)
			(end 0.67945 0.3048)
			(stroke
				(width 0.1)
				(type default)
			)
			(layer "F.Fab")
		)
		(fp_line
			(start 0.12065 -0.2794)
			(end 0.12065 -0.3048)
			(stroke
				(width 0.1)
				(type default)
			)
			(layer "F.Fab")
		)
		(fp_line
			(start 0.12065 -0.3048)
			(end 0.67945 -0.3048)
			(stroke
				(width 0.1)
				(type default)
			)
			(layer "F.Fab")
		)
		(fp_line
			(start 0.120396 0.3048)
			(end 0.120396 0.2794)
			(stroke
				(width 0.1)
				(type default)
			)
			(layer "F.Fab")
		)
		(fp_line
			(start 0.120396 0.2794)
			(end -0.12065 0.2794)
			(stroke
				(width 0.1)
				(type default)
			)
			(layer "F.Fab")
		)
		(fp_line
			(start -0.12065 0.3048)
			(end -0.67945 0.3048)
			(stroke
				(width 0.1)
				(type default)
			)
			(layer "F.Fab")
		)
		(fp_line
			(start -0.12065 0.2794)
			(end -0.12065 0.3048)
			(stroke
				(width 0.1)
				(type default)
			)
			(layer "F.Fab")
		)
		(fp_line
			(start -0.12065 -0.2794)
			(end 0.12065 -0.2794)
			(stroke
				(width 0.1)
				(type default)
			)
			(layer "F.Fab")
		)
		(fp_line
			(start -0.12065 -0.305054)
			(end -0.12065 -0.2794)
			(stroke
				(width 0.1)
				(type default)
			)
			(layer "F.Fab")
		)
		(fp_line
			(start -0.67945 0.3048)
			(end -0.67945 -0.305054)
			(stroke
				(width 0.1)
				(type default)
			)
			(layer "F.Fab")
		)
		(fp_line
			(start -0.67945 -0.305054)
			(end -0.12065 -0.305054)
			(stroke
				(width 0.1)
				(type default)
			)
			(layer "F.Fab")
		)
		(pad "1" smd circle
			(at -0.40005 0 180)
			(size 0 0)
			(layers "F.Cu" "F.Mask" "F.Paste")
			(net "SVID_CLK0_CPU0_R")
		)
		(pad "2" smd circle
			(at 0.40005 0 180)
			(size 0 0)
			(layers "F.Cu" "F.Mask" "F.Paste")
			(net "PVNN_TERM_CPU0")
		)
	)
	(footprint ""
		(layer "F.Cu")
		(at 28.08605 -47.335948)
		(property "Reference" "R3054"
			(at 0 0 0)
			(layer "F.SilkS")
			(hide yes)
			(effects
				(font
					(size 1.27 1.27)
				)
			)
		)
		(property "Value" ""
			(at 0 0 0)
			(layer "F.Fab")
			(effects
				(font
					(size 1.27 1.27)
				)
			)
		)
		(duplicate_pad_numbers_are_jumpers no)
		(fp_line
			(start -0.7874 -0.4064)
			(end 0.7874 -0.4064)
			(stroke
				(width 0.1524)
				(type default)
			)
			(layer "F.SilkS")
		)
		(fp_line
			(start -0.7874 0.4064)
			(end -0.7874 -0.4064)
			(stroke
				(width 0.1524)
				(type default)
			)
			(layer "F.SilkS")
		)
		(fp_line
			(start 0.7874 -0.4064)
			(end 0.7874 0.4064)
			(stroke
				(width 0.1524)
				(type default)
			)
			(layer "F.SilkS")
		)
		(fp_line
			(start 0.7874 0.4064)
			(end -0.7874 0.4064)
			(stroke
				(width 0.1524)
				(type default)
			)
			(layer "F.SilkS")
		)
		(fp_line
			(start -0.67945 -0.305054)
			(end -0.12065 -0.305054)
			(stroke
				(width 0.1)
				(type default)
			)
			(layer "F.Fab")
		)
		(fp_line
			(start -0.67945 0.3048)
			(end -0.67945 -0.305054)
			(stroke
				(width 0.1)
				(type default)
			)
			(layer "F.Fab")
		)
		(fp_line
			(start -0.12065 -0.305054)
			(end -0.12065 -0.2794)
			(stroke
				(width 0.1)
				(type default)
			)
			(layer "F.Fab")
		)
		(fp_line
			(start -0.12065 -0.2794)
			(end 0.12065 -0.2794)
			(stroke
				(width 0.1)
				(type default)
			)
			(layer "F.Fab")
		)
		(fp_line
			(start -0.12065 0.2794)
			(end -0.12065 0.3048)
			(stroke
				(width 0.1)
				(type default)
			)
			(layer "F.Fab")
		)
		(fp_line
			(start -0.12065 0.3048)
			(end -0.67945 0.3048)
			(stroke
				(width 0.1)
				(type default)
			)
			(layer "F.Fab")
		)
		(fp_line
			(start 0.120396 0.2794)
			(end -0.12065 0.2794)
			(stroke
				(width 0.1)
				(type default)
			)
			(layer "F.Fab")
		)
		(fp_line
			(start 0.120396 0.3048)
			(end 0.120396 0.2794)
			(stroke
				(width 0.1)
				(type default)
			)
			(layer "F.Fab")
		)
		(fp_line
			(start 0.12065 -0.3048)
			(end 0.67945 -0.3048)
			(stroke
				(width 0.1)
				(type default)
			)
			(layer "F.Fab")
		)
		(fp_line
			(start 0.12065 -0.2794)
			(end 0.12065 -0.3048)
			(stroke
				(width 0.1)
				(type default)
			)
			(layer "F.Fab")
		)
		(fp_line
			(start 0.67945 -0.3048)
			(end 0.67945 0.3048)
			(stroke
				(width 0.1)
				(type default)
			)
			(layer "F.Fab")
		)
		(fp_line
			(start 0.67945 0.3048)
			(end 0.120396 0.3048)
			(stroke
				(width 0.1)
				(type default)
			)
			(layer "F.Fab")
		)
		(pad "1" smd circle
			(at -0.40005 0)
			(size 0 0)
			(layers "F.Cu" "F.Mask" "F.Paste")
			(net "PWRGD_PS_PWROK_ME_CONN")
		)
		(pad "2" smd circle
			(at 0.40005 0)
			(size 0 0)
			(layers "F.Cu" "F.Mask" "F.Paste")
			(net "PWRGD_PS_PWROK")
		)
	)
	(footprint ""
		(layer "F.Cu")
		(at 85.9028 -36.032948 180)
		(property "Reference" "R1132"
			(at 0 0 180)
			(layer "F.SilkS")
			(hide yes)
			(effects
				(font
					(size 1.27 1.27)
				)
			)
		)
		(property "Value" ""
			(at 0 0 180)
			(layer "F.Fab")
			(effects
				(font
					(size 1.27 1.27)
				)
			)
		)
		(duplicate_pad_numbers_are_jumpers no)
		(fp_line
			(start 0.7874 0.4064)
			(end -0.7874 0.4064)
			(stroke
				(width 0.1524)
				(type default)
			)
			(layer "F.SilkS")
		)
		(fp_line
			(start 0.7874 -0.4064)
			(end 0.7874 0.4064)
			(stroke
				(width 0.1524)
				(type default)
			)
			(layer "F.SilkS")
		)
		(fp_line
			(start -0.7874 0.4064)
			(end -0.7874 -0.4064)
			(stroke
				(width 0.1524)
				(type default)
			)
			(layer "F.SilkS")
		)
		(fp_line
			(start -0.7874 -0.4064)
			(end 0.7874 -0.4064)
			(stroke
				(width 0.1524)
				(type default)
			)
			(layer "F.SilkS")
		)
		(fp_line
			(start 0.67945 0.3048)
			(end 0.120396 0.3048)
			(stroke
				(width 0.1)
				(type default)
			)
			(layer "F.Fab")
		)
		(fp_line
			(start 0.67945 -0.3048)
			(end 0.67945 0.3048)
			(stroke
				(width 0.1)
				(type default)
			)
			(layer "F.Fab")
		)
		(fp_line
			(start 0.12065 -0.2794)
			(end 0.12065 -0.3048)
			(stroke
				(width 0.1)
				(type default)
			)
			(layer "F.Fab")
		)
		(fp_line
			(start 0.12065 -0.3048)
			(end 0.67945 -0.3048)
			(stroke
				(width 0.1)
				(type default)
			)
			(layer "F.Fab")
		)
		(fp_line
			(start 0.120396 0.3048)
			(end 0.120396 0.2794)
			(stroke
				(width 0.1)
				(type default)
			)
			(layer "F.Fab")
		)
		(fp_line
			(start 0.120396 0.2794)
			(end -0.12065 0.2794)
			(stroke
				(width 0.1)
				(type default)
			)
			(layer "F.Fab")
		)
		(fp_line
			(start -0.12065 0.3048)
			(end -0.67945 0.3048)
			(stroke
				(width 0.1)
				(type default)
			)
			(layer "F.Fab")
		)
		(fp_line
			(start -0.12065 0.2794)
			(end -0.12065 0.3048)
			(stroke
				(width 0.1)
				(type default)
			)
			(layer "F.Fab")
		)
		(fp_line
			(start -0.12065 -0.2794)
			(end 0.12065 -0.2794)
			(stroke
				(width 0.1)
				(type default)
			)
			(layer "F.Fab")
		)
		(fp_line
			(start -0.12065 -0.305054)
			(end -0.12065 -0.2794)
			(stroke
				(width 0.1)
				(type default)
			)
			(layer "F.Fab")
		)
		(fp_line
			(start -0.67945 0.3048)
			(end -0.67945 -0.305054)
			(stroke
				(width 0.1)
				(type default)
			)
			(layer "F.Fab")
		)
		(fp_line
			(start -0.67945 -0.305054)
			(end -0.12065 -0.305054)
			(stroke
				(width 0.1)
				(type default)
			)
			(layer "F.Fab")
		)
		(pad "1" smd circle
			(at -0.40005 0 180)
			(size 0 0)
			(layers "F.Cu" "F.Mask" "F.Paste")
			(net "P3V3_AUX")
		)
		(pad "2" smd circle
			(at 0.40005 0 180)
			(size 0 0)
			(layers "F.Cu" "F.Mask" "F.Paste")
			(net "HP_OCP_V3_2_RST_R")
		)
	)
	(footprint ""
		(layer "F.Cu")
		(at 154.65933 -70.26402 90)
		(property "Reference" "R2308"
			(at 0 0 90)
			(layer "F.SilkS")
			(hide yes)
			(effects
				(font
					(size 1.27 1.27)
				)
			)
		)
		(property "Value" ""
			(at 0 0 90)
			(layer "F.Fab")
			(effects
				(font
					(size 1.27 1.27)
				)
			)
		)
		(duplicate_pad_numbers_are_jumpers no)
		(fp_line
			(start 0.7874 -0.4064)
			(end 0.7874 0.4064)
			(stroke
				(width 0.1524)
				(type default)
			)
			(layer "F.SilkS")
		)
		(fp_line
			(start -0.7874 -0.4064)
			(end 0.7874 -0.4064)
			(stroke
				(width 0.1524)
				(type default)
			)
			(layer "F.SilkS")
		)
		(fp_line
			(start 0.7874 0.4064)
			(end -0.7874 0.4064)
			(stroke
				(width 0.1524)
				(type default)
			)
			(layer "F.SilkS")
		)
		(fp_line
			(start -0.7874 0.4064)
			(end -0.7874 -0.4064)
			(stroke
				(width 0.1524)
				(type default)
			)
			(layer "F.SilkS")
		)
		(fp_line
			(start -0.12065 -0.305054)
			(end -0.12065 -0.2794)
			(stroke
				(width 0.1)
				(type default)
			)
			(layer "F.Fab")
		)
		(fp_line
			(start -0.67945 -0.305054)
			(end -0.12065 -0.305054)
			(stroke
				(width 0.1)
				(type default)
			)
			(layer "F.Fab")
		)
		(fp_line
			(start 0.67945 -0.3048)
			(end 0.67945 0.3048)
			(stroke
				(width 0.1)
				(type default)
			)
			(layer "F.Fab")
		)
		(fp_line
			(start 0.12065 -0.3048)
			(end 0.67945 -0.3048)
			(stroke
				(width 0.1)
				(type default)
			)
			(layer "F.Fab")
		)
		(fp_line
			(start 0.12065 -0.2794)
			(end 0.12065 -0.3048)
			(stroke
				(width 0.1)
				(type default)
			)
			(layer "F.Fab")
		)
		(fp_line
			(start -0.12065 -0.2794)
			(end 0.12065 -0.2794)
			(stroke
				(width 0.1)
				(type default)
			)
			(layer "F.Fab")
		)
		(fp_line
			(start 0.120396 0.2794)
			(end -0.12065 0.2794)
			(stroke
				(width 0.1)
				(type default)
			)
			(layer "F.Fab")
		)
		(fp_line
			(start -0.12065 0.2794)
			(end -0.12065 0.3048)
			(stroke
				(width 0.1)
				(type default)
			)
			(layer "F.Fab")
		)
		(fp_line
			(start 0.67945 0.3048)
			(end 0.120396 0.3048)
			(stroke
				(width 0.1)
				(type default)
			)
			(layer "F.Fab")
		)
		(fp_line
			(start 0.120396 0.3048)
			(end 0.120396 0.2794)
			(stroke
				(width 0.1)
				(type default)
			)
			(layer "F.Fab")
		)
		(fp_line
			(start -0.12065 0.3048)
			(end -0.67945 0.3048)
			(stroke
				(width 0.1)
				(type default)
			)
			(layer "F.Fab")
		)
		(fp_line
			(start -0.67945 0.3048)
			(end -0.67945 -0.305054)
			(stroke
				(width 0.1)
				(type default)
			)
			(layer "F.Fab")
		)
		(pad "1" smd circle
			(at -0.40005 0 90)
			(size 0 0)
			(layers "F.Cu" "F.Mask" "F.Paste")
			(net "P3V3_AUX")
		)
		(pad "2" smd circle
			(at 0.40005 0 90)
			(size 0 0)
			(layers "F.Cu" "F.Mask" "F.Paste")
			(net "PCA9543_S3M_ADDR1")
		)
	)
	(footprint ""
		(layer "F.Cu")
		(at 39.827454 -109.444282 180)
		(property "Reference" "R3686"
			(at 0 0 180)
			(layer "F.SilkS")
			(hide yes)
			(effects
				(font
					(size 1.27 1.27)
				)
			)
		)
		(property "Value" ""
			(at 0 0 180)
			(layer "F.Fab")
			(effects
				(font
					(size 1.27 1.27)
				)
			)
		)
		(duplicate_pad_numbers_are_jumpers no)
		(fp_line
			(start 0.7874 0.4064)
			(end -0.7874 0.4064)
			(stroke
				(width 0.1524)
				(type default)
			)
			(layer "F.SilkS")
		)
		(fp_line
			(start 0.7874 -0.4064)
			(end 0.7874 0.4064)
			(stroke
				(width 0.1524)
				(type default)
			)
			(layer "F.SilkS")
		)
		(fp_line
			(start -0.7874 0.4064)
			(end -0.7874 -0.4064)
			(stroke
				(width 0.1524)
				(type default)
			)
			(layer "F.SilkS")
		)
		(fp_line
			(start -0.7874 -0.4064)
			(end 0.7874 -0.4064)
			(stroke
				(width 0.1524)
				(type default)
			)
			(layer "F.SilkS")
		)
		(fp_line
			(start 0.67945 0.3048)
			(end 0.120396 0.3048)
			(stroke
				(width 0.1)
				(type default)
			)
			(layer "F.Fab")
		)
		(fp_line
			(start 0.67945 -0.3048)
			(end 0.67945 0.3048)
			(stroke
				(width 0.1)
				(type default)
			)
			(layer "F.Fab")
		)
		(fp_line
			(start 0.12065 -0.2794)
			(end 0.12065 -0.3048)
			(stroke
				(width 0.1)
				(type default)
			)
			(layer "F.Fab")
		)
		(fp_line
			(start 0.12065 -0.3048)
			(end 0.67945 -0.3048)
			(stroke
				(width 0.1)
				(type default)
			)
			(layer "F.Fab")
		)
		(fp_line
			(start 0.120396 0.3048)
			(end 0.120396 0.2794)
			(stroke
				(width 0.1)
				(type default)
			)
			(layer "F.Fab")
		)
		(fp_line
			(start 0.120396 0.2794)
			(end -0.12065 0.2794)
			(stroke
				(width 0.1)
				(type default)
			)
			(layer "F.Fab")
		)
		(fp_line
			(start -0.12065 0.3048)
			(end -0.67945 0.3048)
			(stroke
				(width 0.1)
				(type default)
			)
			(layer "F.Fab")
		)
		(fp_line
			(start -0.12065 0.2794)
			(end -0.12065 0.3048)
			(stroke
				(width 0.1)
				(type default)
			)
			(layer "F.Fab")
		)
		(fp_line
			(start -0.12065 -0.2794)
			(end 0.12065 -0.2794)
			(stroke
				(width 0.1)
				(type default)
			)
			(layer "F.Fab")
		)
		(fp_line
			(start -0.12065 -0.305054)
			(end -0.12065 -0.2794)
			(stroke
				(width 0.1)
				(type default)
			)
			(layer "F.Fab")
		)
		(fp_line
			(start -0.67945 0.3048)
			(end -0.67945 -0.305054)
			(stroke
				(width 0.1)
				(type default)
			)
			(layer "F.Fab")
		)
		(fp_line
			(start -0.67945 -0.305054)
			(end -0.12065 -0.305054)
			(stroke
				(width 0.1)
				(type default)
			)
			(layer "F.Fab")
		)
		(pad "1" smd rect
			(at -0.40005 0)
			(size 0.4572 0.508)
			(layers "F.Cu" "F.Mask" "F.Paste")
			(net "P5V_ADC")
		)
		(pad "2" smd rect
			(at 0.40005 0)
			(size 0.4572 0.508)
			(layers "F.Cu" "F.Mask" "F.Paste")
			(net "P5V_ADC_TIC")
		)
	)
	(footprint ""
		(layer "F.Cu")
		(at 89.95283 -74.819764 -90)
		(property "Reference" "R3102"
			(at 0 0 270)
			(layer "F.SilkS")
			(hide yes)
			(effects
				(font
					(size 1.27 1.27)
				)
			)
		)
		(property "Value" ""
			(at 0 0 270)
			(layer "F.Fab")
			(effects
				(font
					(size 1.27 1.27)
				)
			)
		)
		(duplicate_pad_numbers_are_jumpers no)
		(fp_line
			(start -0.7874 0.4064)
			(end -0.7874 -0.4064)
			(stroke
				(width 0.1524)
				(type default)
			)
			(layer "F.SilkS")
		)
		(fp_line
			(start 0.7874 0.4064)
			(end -0.7874 0.4064)
			(stroke
				(width 0.1524)
				(type default)
			)
			(layer "F.SilkS")
		)
		(fp_line
			(start -0.7874 -0.4064)
			(end 0.7874 -0.4064)
			(stroke
				(width 0.1524)
				(type default)
			)
			(layer "F.SilkS")
		)
		(fp_line
			(start 0.7874 -0.4064)
			(end 0.7874 0.4064)
			(stroke
				(width 0.1524)
				(type default)
			)
			(layer "F.SilkS")
		)
		(fp_line
			(start -0.67945 0.3048)
			(end -0.67945 -0.305054)
			(stroke
				(width 0.1)
				(type default)
			)
			(layer "F.Fab")
		)
		(fp_line
			(start -0.12065 0.3048)
			(end -0.67945 0.3048)
			(stroke
				(width 0.1)
				(type default)
			)
			(layer "F.Fab")
		)
		(fp_line
			(start 0.120396 0.3048)
			(end 0.120396 0.2794)
			(stroke
				(width 0.1)
				(type default)
			)
			(layer "F.Fab")
		)
		(fp_line
			(start 0.67945 0.3048)
			(end 0.120396 0.3048)
			(stroke
				(width 0.1)
				(type default)
			)
			(layer "F.Fab")
		)
		(fp_line
			(start -0.12065 0.2794)
			(end -0.12065 0.3048)
			(stroke
				(width 0.1)
				(type default)
			)
			(layer "F.Fab")
		)
		(fp_line
			(start 0.120396 0.2794)
			(end -0.12065 0.2794)
			(stroke
				(width 0.1)
				(type default)
			)
			(layer "F.Fab")
		)
		(fp_line
			(start -0.12065 -0.2794)
			(end 0.12065 -0.2794)
			(stroke
				(width 0.1)
				(type default)
			)
			(layer "F.Fab")
		)
		(fp_line
			(start 0.12065 -0.2794)
			(end 0.12065 -0.3048)
			(stroke
				(width 0.1)
				(type default)
			)
			(layer "F.Fab")
		)
		(fp_line
			(start 0.12065 -0.3048)
			(end 0.67945 -0.3048)
			(stroke
				(width 0.1)
				(type default)
			)
			(layer "F.Fab")
		)
		(fp_line
			(start 0.67945 -0.3048)
			(end 0.67945 0.3048)
			(stroke
				(width 0.1)
				(type default)
			)
			(layer "F.Fab")
		)
		(fp_line
			(start -0.67945 -0.305054)
			(end -0.12065 -0.305054)
			(stroke
				(width 0.1)
				(type default)
			)
			(layer "F.Fab")
		)
		(fp_line
			(start -0.12065 -0.305054)
			(end -0.12065 -0.2794)
			(stroke
				(width 0.1)
				(type default)
			)
			(layer "F.Fab")
		)
		(pad "1" smd circle
			(at -0.40005 0 270)
			(size 0 0)
			(layers "F.Cu" "F.Mask" "F.Paste")
			(net "LED_P5V")
		)
		(pad "2" smd circle
			(at 0.40005 0 270)
			(size 0 0)
			(layers "F.Cu" "F.Mask" "F.Paste")
			(net "P5V")
		)
	)
	(footprint ""
		(layer "F.Cu")
		(at 376.488198 -359.871518 -90)
		(property "Reference" "PC2643"
			(at 0 0 270)
			(layer "F.SilkS")
			(hide yes)
			(effects
				(font
					(size 1.27 1.27)
				)
			)
		)
		(property "Value" ""
			(at 0 0 270)
			(layer "F.Fab")
			(effects
				(font
					(size 1.27 1.27)
				)
			)
		)
		(duplicate_pad_numbers_are_jumpers no)
		(fp_line
			(start -0.7874 0.4064)
			(end -0.7874 -0.4064)
			(stroke
				(width 0.1524)
				(type default)
			)
			(layer "F.SilkS")
		)
		(fp_line
			(start 0.7874 0.4064)
			(end -0.7874 0.4064)
			(stroke
				(width 0.1524)
				(type default)
			)
			(layer "F.SilkS")
		)
		(fp_line
			(start -0.7874 -0.4064)
			(end 0.7874 -0.4064)
			(stroke
				(width 0.1524)
				(type default)
			)
			(layer "F.SilkS")
		)
		(fp_line
			(start 0.7874 -0.4064)
			(end 0.7874 0.4064)
			(stroke
				(width 0.1524)
				(type default)
			)
			(layer "F.SilkS")
		)
		(fp_line
			(start -0.67945 0.3048)
			(end -0.67945 -0.305054)
			(stroke
				(width 0.1)
				(type default)
			)
			(layer "F.Fab")
		)
		(fp_line
			(start -0.12065 0.3048)
			(end -0.67945 0.3048)
			(stroke
				(width 0.1)
				(type default)
			)
			(layer "F.Fab")
		)
		(fp_line
			(start 0.120396 0.3048)
			(end 0.120396 0.2794)
			(stroke
				(width 0.1)
				(type default)
			)
			(layer "F.Fab")
		)
		(fp_line
			(start 0.67945 0.3048)
			(end 0.120396 0.3048)
			(stroke
				(width 0.1)
				(type default)
			)
			(layer "F.Fab")
		)
		(fp_line
			(start -0.12065 0.2794)
			(end -0.12065 0.3048)
			(stroke
				(width 0.1)
				(type default)
			)
			(layer "F.Fab")
		)
		(fp_line
			(start 0.120396 0.2794)
			(end -0.12065 0.2794)
			(stroke
				(width 0.1)
				(type default)
			)
			(layer "F.Fab")
		)
		(fp_line
			(start -0.12065 -0.2794)
			(end 0.12065 -0.2794)
			(stroke
				(width 0.1)
				(type default)
			)
			(layer "F.Fab")
		)
		(fp_line
			(start 0.12065 -0.2794)
			(end 0.12065 -0.3048)
			(stroke
				(width 0.1)
				(type default)
			)
			(layer "F.Fab")
		)
		(fp_line
			(start 0.12065 -0.3048)
			(end 0.67945 -0.3048)
			(stroke
				(width 0.1)
				(type default)
			)
			(layer "F.Fab")
		)
		(fp_line
			(start 0.67945 -0.3048)
			(end 0.67945 0.3048)
			(stroke
				(width 0.1)
				(type default)
			)
			(layer "F.Fab")
		)
		(fp_line
			(start -0.67945 -0.305054)
			(end -0.12065 -0.305054)
			(stroke
				(width 0.1)
				(type default)
			)
			(layer "F.Fab")
		)
		(fp_line
			(start -0.12065 -0.305054)
			(end -0.12065 -0.2794)
			(stroke
				(width 0.1)
				(type default)
			)
			(layer "F.Fab")
		)
		(pad "1" smd circle
			(at -0.40005 0 270)
			(size 0 0)
			(layers "F.Cu" "F.Mask" "F.Paste")
			(net "PVPP_HBM_CPU0_VCC")
		)
		(pad "2" smd circle
			(at 0.40005 0 270)
			(size 0 0)
			(layers "F.Cu" "F.Mask" "F.Paste")
			(net "GND")
		)
	)
	(footprint ""
		(layer "F.Cu")
		(at 175.883062 -23.283672 180)
		(property "Reference" "PR4006"
			(at 0 0 180)
			(layer "F.SilkS")
			(hide yes)
			(effects
				(font
					(size 1.27 1.27)
				)
			)
		)
		(property "Value" ""
			(at 0 0 180)
			(layer "F.Fab")
			(effects
				(font
					(size 1.27 1.27)
				)
			)
		)
		(duplicate_pad_numbers_are_jumpers no)
		(fp_line
			(start 0.7874 0.4064)
			(end -0.7874 0.4064)
			(stroke
				(width 0.1524)
				(type default)
			)
			(layer "F.SilkS")
		)
		(fp_line
			(start 0.7874 -0.4064)
			(end 0.7874 0.4064)
			(stroke
				(width 0.1524)
				(type default)
			)
			(layer "F.SilkS")
		)
		(fp_line
			(start -0.7874 0.4064)
			(end -0.7874 -0.4064)
			(stroke
				(width 0.1524)
				(type default)
			)
			(layer "F.SilkS")
		)
		(fp_line
			(start -0.7874 -0.4064)
			(end 0.7874 -0.4064)
			(stroke
				(width 0.1524)
				(type default)
			)
			(layer "F.SilkS")
		)
		(fp_line
			(start 0.67945 0.3048)
			(end 0.120396 0.3048)
			(stroke
				(width 0.1)
				(type default)
			)
			(layer "F.Fab")
		)
		(fp_line
			(start 0.67945 -0.3048)
			(end 0.67945 0.3048)
			(stroke
				(width 0.1)
				(type default)
			)
			(layer "F.Fab")
		)
		(fp_line
			(start 0.12065 -0.2794)
			(end 0.12065 -0.3048)
			(stroke
				(width 0.1)
				(type default)
			)
			(layer "F.Fab")
		)
		(fp_line
			(start 0.12065 -0.3048)
			(end 0.67945 -0.3048)
			(stroke
				(width 0.1)
				(type default)
			)
			(layer "F.Fab")
		)
		(fp_line
			(start 0.120396 0.3048)
			(end 0.120396 0.2794)
			(stroke
				(width 0.1)
				(type default)
			)
			(layer "F.Fab")
		)
		(fp_line
			(start 0.120396 0.2794)
			(end -0.12065 0.2794)
			(stroke
				(width 0.1)
				(type default)
			)
			(layer "F.Fab")
		)
		(fp_line
			(start -0.12065 0.3048)
			(end -0.67945 0.3048)
			(stroke
				(width 0.1)
				(type default)
			)
			(layer "F.Fab")
		)
		(fp_line
			(start -0.12065 0.2794)
			(end -0.12065 0.3048)
			(stroke
				(width 0.1)
				(type default)
			)
			(layer "F.Fab")
		)
		(fp_line
			(start -0.12065 -0.2794)
			(end 0.12065 -0.2794)
			(stroke
				(width 0.1)
				(type default)
			)
			(layer "F.Fab")
		)
		(fp_line
			(start -0.12065 -0.305054)
			(end -0.12065 -0.2794)
			(stroke
				(width 0.1)
				(type default)
			)
			(layer "F.Fab")
		)
		(fp_line
			(start -0.67945 0.3048)
			(end -0.67945 -0.305054)
			(stroke
				(width 0.1)
				(type default)
			)
			(layer "F.Fab")
		)
		(fp_line
			(start -0.67945 -0.305054)
			(end -0.12065 -0.305054)
			(stroke
				(width 0.1)
				(type default)
			)
			(layer "F.Fab")
		)
		(pad "1" smd circle
			(at -0.40005 0 180)
			(size 0 0)
			(layers "F.Cu" "F.Mask" "F.Paste")
			(net "P12V_SCM_R")
		)
		(pad "2" smd circle
			(at 0.40005 0 180)
			(size 0 0)
			(layers "F.Cu" "F.Mask" "F.Paste")
			(net "P12V_SCM_AVIN_PD")
		)
	)
	(footprint ""
		(layer "F.Cu")
		(at 465.821014 -117.651022 180)
		(property "Reference" "R1130"
			(at 0 0 180)
			(layer "F.SilkS")
			(hide yes)
			(effects
				(font
					(size 1.27 1.27)
				)
			)
		)
		(property "Value" ""
			(at 0 0 180)
			(layer "F.Fab")
			(effects
				(font
					(size 1.27 1.27)
				)
			)
		)
		(duplicate_pad_numbers_are_jumpers no)
		(fp_line
			(start 0.7874 0.4064)
			(end -0.7874 0.4064)
			(stroke
				(width 0.1524)
				(type default)
			)
			(layer "F.SilkS")
		)
		(fp_line
			(start 0.7874 -0.4064)
			(end 0.7874 0.4064)
			(stroke
				(width 0.1524)
				(type default)
			)
			(layer "F.SilkS")
		)
		(fp_line
			(start -0.7874 0.4064)
			(end -0.7874 -0.4064)
			(stroke
				(width 0.1524)
				(type default)
			)
			(layer "F.SilkS")
		)
		(fp_line
			(start -0.7874 -0.4064)
			(end 0.7874 -0.4064)
			(stroke
				(width 0.1524)
				(type default)
			)
			(layer "F.SilkS")
		)
		(fp_line
			(start 0.67945 0.3048)
			(end 0.120396 0.3048)
			(stroke
				(width 0.1)
				(type default)
			)
			(layer "F.Fab")
		)
		(fp_line
			(start 0.67945 -0.3048)
			(end 0.67945 0.3048)
			(stroke
				(width 0.1)
				(type default)
			)
			(layer "F.Fab")
		)
		(fp_line
			(start 0.12065 -0.2794)
			(end 0.12065 -0.3048)
			(stroke
				(width 0.1)
				(type default)
			)
			(layer "F.Fab")
		)
		(fp_line
			(start 0.12065 -0.3048)
			(end 0.67945 -0.3048)
			(stroke
				(width 0.1)
				(type default)
			)
			(layer "F.Fab")
		)
		(fp_line
			(start 0.120396 0.3048)
			(end 0.120396 0.2794)
			(stroke
				(width 0.1)
				(type default)
			)
			(layer "F.Fab")
		)
		(fp_line
			(start 0.120396 0.2794)
			(end -0.12065 0.2794)
			(stroke
				(width 0.1)
				(type default)
			)
			(layer "F.Fab")
		)
		(fp_line
			(start -0.12065 0.3048)
			(end -0.67945 0.3048)
			(stroke
				(width 0.1)
				(type default)
			)
			(layer "F.Fab")
		)
		(fp_line
			(start -0.12065 0.2794)
			(end -0.12065 0.3048)
			(stroke
				(width 0.1)
				(type default)
			)
			(layer "F.Fab")
		)
		(fp_line
			(start -0.12065 -0.2794)
			(end 0.12065 -0.2794)
			(stroke
				(width 0.1)
				(type default)
			)
			(layer "F.Fab")
		)
		(fp_line
			(start -0.12065 -0.305054)
			(end -0.12065 -0.2794)
			(stroke
				(width 0.1)
				(type default)
			)
			(layer "F.Fab")
		)
		(fp_line
			(start -0.67945 0.3048)
			(end -0.67945 -0.305054)
			(stroke
				(width 0.1)
				(type default)
			)
			(layer "F.Fab")
		)
		(fp_line
			(start -0.67945 -0.305054)
			(end -0.12065 -0.305054)
			(stroke
				(width 0.1)
				(type default)
			)
			(layer "F.Fab")
		)
		(pad "1" smd circle
			(at -0.40005 0 180)
			(size 0 0)
			(layers "F.Cu" "F.Mask" "F.Paste")
			(net "SMB_PEHPCPU0_LVC3_SCL")
		)
		(pad "2" smd circle
			(at 0.40005 0 180)
			(size 0 0)
			(layers "F.Cu" "F.Mask" "F.Paste")
			(net "SMB_PEHPCPU0_LVC3_R_SCL")
		)
	)
	(footprint ""
		(layer "F.Cu")
		(at 298.13504 -409.69184)
		(property "Reference" "R4894"
			(at 0 0 0)
			(layer "F.SilkS")
			(hide yes)
			(effects
				(font
					(size 1.27 1.27)
				)
			)
		)
		(property "Value" ""
			(at 0 0 0)
			(layer "F.Fab")
			(effects
				(font
					(size 1.27 1.27)
				)
			)
		)
		(duplicate_pad_numbers_are_jumpers no)
		(fp_line
			(start -0.7874 -0.4064)
			(end 0.7874 -0.4064)
			(stroke
				(width 0.1524)
				(type default)
			)
			(layer "F.SilkS")
		)
		(fp_line
			(start -0.7874 0.4064)
			(end -0.7874 -0.4064)
			(stroke
				(width 0.1524)
				(type default)
			)
			(layer "F.SilkS")
		)
		(fp_line
			(start 0.7874 -0.4064)
			(end 0.7874 0.4064)
			(stroke
				(width 0.1524)
				(type default)
			)
			(layer "F.SilkS")
		)
		(fp_line
			(start 0.7874 0.4064)
			(end -0.7874 0.4064)
			(stroke
				(width 0.1524)
				(type default)
			)
			(layer "F.SilkS")
		)
		(fp_line
			(start -0.67945 -0.305054)
			(end -0.12065 -0.305054)
			(stroke
				(width 0.1)
				(type default)
			)
			(layer "F.Fab")
		)
		(fp_line
			(start -0.67945 0.3048)
			(end -0.67945 -0.305054)
			(stroke
				(width 0.1)
				(type default)
			)
			(layer "F.Fab")
		)
		(fp_line
			(start -0.12065 -0.305054)
			(end -0.12065 -0.2794)
			(stroke
				(width 0.1)
				(type default)
			)
			(layer "F.Fab")
		)
		(fp_line
			(start -0.12065 -0.2794)
			(end 0.12065 -0.2794)
			(stroke
				(width 0.1)
				(type default)
			)
			(layer "F.Fab")
		)
		(fp_line
			(start -0.12065 0.2794)
			(end -0.12065 0.3048)
			(stroke
				(width 0.1)
				(type default)
			)
			(layer "F.Fab")
		)
		(fp_line
			(start -0.12065 0.3048)
			(end -0.67945 0.3048)
			(stroke
				(width 0.1)
				(type default)
			)
			(layer "F.Fab")
		)
		(fp_line
			(start 0.120396 0.2794)
			(end -0.12065 0.2794)
			(stroke
				(width 0.1)
				(type default)
			)
			(layer "F.Fab")
		)
		(fp_line
			(start 0.120396 0.3048)
			(end 0.120396 0.2794)
			(stroke
				(width 0.1)
				(type default)
			)
			(layer "F.Fab")
		)
		(fp_line
			(start 0.12065 -0.3048)
			(end 0.67945 -0.3048)
			(stroke
				(width 0.1)
				(type default)
			)
			(layer "F.Fab")
		)
		(fp_line
			(start 0.12065 -0.2794)
			(end 0.12065 -0.3048)
			(stroke
				(width 0.1)
				(type default)
			)
			(layer "F.Fab")
		)
		(fp_line
			(start 0.67945 -0.3048)
			(end 0.67945 0.3048)
			(stroke
				(width 0.1)
				(type default)
			)
			(layer "F.Fab")
		)
		(fp_line
			(start 0.67945 0.3048)
			(end 0.120396 0.3048)
			(stroke
				(width 0.1)
				(type default)
			)
			(layer "F.Fab")
		)
		(pad "1" smd circle
			(at -0.40005 0)
			(size 0 0)
			(layers "F.Cu" "F.Mask" "F.Paste")
			(net "P12V_HSC_TEMP_SCL")
		)
		(pad "2" smd circle
			(at 0.40005 0)
			(size 0 0)
			(layers "F.Cu" "F.Mask" "F.Paste")
			(net "SMB_LM75_0_3V3AUX_SCL")
		)
	)
	(footprint ""
		(layer "F.Cu")
		(at 385.740148 -342.917018)
		(property "Reference" "PU6_P0_8"
			(at -3.30454 -6.38683 0)
			(unlocked yes)
			(layer "F.SilkS")
			(effects
				(font
					(size 0.7874 0.5842)
					(thickness 0.1524)
				)
				(justify left)
			)
		)
		(property "Value" ""
			(at 0 0 0)
			(layer "F.Fab")
			(effects
				(font
					(size 1.27 1.27)
				)
			)
		)
		(duplicate_pad_numbers_are_jumpers no)
		(fp_line
			(start -2.500122 -2.999994)
			(end -2.24409 -2.999994)
			(stroke
				(width 0.1524)
				(type default)
			)
			(layer "F.SilkS")
		)
		(fp_line
			(start -2.500122 -2.529078)
			(end -2.500122 -2.999994)
			(stroke
				(width 0.1524)
				(type default)
			)
			(layer "F.SilkS")
		)
		(fp_line
			(start -2.500122 0.6604)
			(end -2.500122 0.229108)
			(stroke
				(width 0.1524)
				(type default)
			)
			(layer "F.SilkS")
		)
		(fp_line
			(start -2.500122 2.999994)
			(end -2.500122 2.339594)
			(stroke
				(width 0.1524)
				(type default)
			)
			(layer "F.SilkS")
		)
		(fp_line
			(start -2.2987 2.999994)
			(end -2.500122 2.999994)
			(stroke
				(width 0.1524)
				(type default)
			)
			(layer "F.SilkS")
		)
		(fp_line
			(start 2.31394 -2.999994)
			(end 2.500122 -2.999994)
			(stroke
				(width 0.1524)
				(type default)
			)
			(layer "F.SilkS")
		)
		(fp_line
			(start 2.500122 -2.999994)
			(end 2.500122 -2.44348)
			(stroke
				(width 0.1524)
				(type default)
			)
			(layer "F.SilkS")
		)
		(fp_line
			(start 2.500122 2.339594)
			(end 2.500122 2.999994)
			(stroke
				(width 0.1524)
				(type default)
			)
			(layer "F.SilkS")
		)
		(fp_line
			(start 2.500122 2.999994)
			(end 2.2987 2.999994)
			(stroke
				(width 0.1524)
				(type default)
			)
			(layer "F.SilkS")
		)
		(fp_poly
			(pts
				(xy -2.21996 -3.632454) (xy -2.72796 -2.616454) (xy -3.23596 -3.632454)
			)
			(stroke
				(width 0)
				(type default)
			)
			(fill yes)
			(layer "F.SilkS")
		)
		(fp_line
			(start -2.500122 -2.999994)
			(end 2.500122 -2.999994)
			(stroke
				(width 0.1)
				(type default)
			)
			(layer "F.Fab")
		)
		(fp_line
			(start -2.500122 2.999994)
			(end -2.500122 -2.999994)
			(stroke
				(width 0.1)
				(type default)
			)
			(layer "F.Fab")
		)
		(fp_line
			(start 2.500122 -2.999994)
			(end 2.500122 2.999994)
			(stroke
				(width 0.1)
				(type default)
			)
			(layer "F.Fab")
		)
		(fp_line
			(start 2.500122 2.999994)
			(end -2.500122 2.999994)
			(stroke
				(width 0.1)
				(type default)
			)
			(layer "F.Fab")
		)
		(fp_poly
			(pts
				(xy -4.218432 -2.783078) (xy -4.218432 -1.767078) (xy -3.202432 -2.275078)
			)
			(stroke
				(width 0)
				(type default)
			)
			(fill yes)
			(layer "F.Fab")
		)
		(pad "1" smd rect
			(at -2.400046 -2.275078 90)
			(size 0.2286 0.6096)
			(layers "F.Cu" "F.Mask" "F.Paste")
			(net "PVCCIN_CPU0_VOS8")
		)
		(pad "2" smd rect
			(at -2.400046 -1.82499 90)
			(size 0.2286 0.6096)
			(layers "F.Cu" "F.Mask" "F.Paste")
			(net "GND")
		)
		(pad "3" smd rect
			(at -2.400046 -1.374902 90)
			(size 0.2286 0.6096)
			(layers "F.Cu" "F.Mask" "F.Paste")
			(net "PVCCIN_CPU0_VDD8")
		)
		(pad "4" smd rect
			(at -2.400046 -0.925068 90)
			(size 0.2286 0.6096)
			(layers "F.Cu" "F.Mask" "F.Paste")
			(net "PVCCIN_CPU0_PVCC")
		)
		(pad "5" smd rect
			(at -2.400046 -0.47498 90)
			(size 0.2286 0.6096)
			(layers "F.Cu" "F.Mask" "F.Paste")
			(net "GND")
		)
		(pad "6" smd rect
			(at -2.400046 -0.024892 90)
			(size 0.2286 0.6096)
			(layers "F.Cu" "F.Mask" "F.Paste")
			(net "Net_8565")
		)
		(pad "7_9-20_24" smd circle
			(at 0 1.150112 90)
			(size 0 0)
			(layers "F.Cu" "F.Mask" "F.Paste")
			(net "GND")
		)
		(pad "10_19" smd rect
			(at 0 2.899918 90)
			(size 0.6096 4.318)
			(layers "F.Cu" "F.Mask" "F.Paste")
			(net "SW_PVCCIN_CPU0_SW8")
		)
		(pad "25_29" smd rect
			(at 1.549908 -1.279906 270)
			(size 2.0574 2.3114)
			(layers "F.Cu" "F.Mask" "F.Paste")
			(net "SW_P12V_PVCCIN_CPU0_FLT")
		)
		(pad "30" smd rect
			(at 2.05994 -2.899918)
			(size 0.2286 0.6096)
			(layers "F.Cu" "F.Mask" "F.Paste")
			(net "SW_P12V_PVCCIN_CPU0_FLT")
		)
		(pad "31" smd rect
			(at 1.610106 -2.899918)
			(size 0.2286 0.6096)
			(layers "F.Cu" "F.Mask" "F.Paste")
			(net "Net_8566")
		)
		(pad "32" smd rect
			(at 1.160018 -2.899918)
			(size 0.2286 0.6096)
			(layers "F.Cu" "F.Mask" "F.Paste")
			(net "SW_PVCCIN_CPU0_BOOTR8")
		)
		(pad "33" smd rect
			(at 0.70993 -2.899918)
			(size 0.2286 0.6096)
			(layers "F.Cu" "F.Mask" "F.Paste")
			(net "SW_PVCCIN_CPU0_BOOT8")
		)
		(pad "34" smd rect
			(at 0.260096 -2.899918)
			(size 0.2286 0.6096)
			(layers "F.Cu" "F.Mask" "F.Paste")
			(net "PVCCIN_CPU0_PWM8")
		)
		(pad "35" smd rect
			(at -0.189992 -2.899918)
			(size 0.2286 0.6096)
			(layers "F.Cu" "F.Mask" "F.Paste")
			(net "PVCCIN_CPU0_VDD8")
		)
		(pad "36" smd rect
			(at -0.64008 -2.899918)
			(size 0.2286 0.6096)
			(layers "F.Cu" "F.Mask" "F.Paste")
			(net "PVCCIN_CPU0_ATSEN")
		)
		(pad "37" smd rect
			(at -1.089914 -2.899918)
			(size 0.2286 0.6096)
			(layers "F.Cu" "F.Mask" "F.Paste")
			(net "PVCCIN_CPU0_LSET8")
		)
		(pad "38" smd rect
			(at -1.540002 -2.899918)
			(size 0.2286 0.6096)
			(layers "F.Cu" "F.Mask" "F.Paste")
			(net "PVCCIN_CPU0_IMON8")
		)
		(pad "39" smd rect
			(at -1.99009 -2.899918)
			(size 0.2286 0.6096)
			(layers "F.Cu" "F.Mask" "F.Paste")
			(net "PVCCIN_CPU0_VREF")
		)
		(pad "40" smd rect
			(at -0.87503 -1.27508)
			(size 1.7526 1.9558)
			(layers "F.Cu" "F.Mask" "F.Paste")
			(net "GND")
		)
		(pad "41" smd rect
			(at -1.525016 0.249936 270)
			(size 0.3048 0.4572)
			(layers "F.Cu" "F.Mask" "F.Paste")
			(net "Net_8564")
		)
		(zone
			(layer "F.Cu")
			(hatch none 0.5)
			(connect_pads
				(clearance 0)
			)
			(min_thickness 0.25)
			(keepout
				(tracks not_allowed)
				(vias allowed)
				(pads allowed)
				(copperpour not_allowed)
				(footprints allowed)
			)
			(placement
				(enabled no)
				(sheetname "")
			)
			(fill
				(thermal_gap 0.5)
				(thermal_bridge_width 0.5)
				(island_removal_mode 0)
			)
			(polygon
				(pts
					(xy 383.240026 -339.917024) (xy 383.240026 -340.666324) (xy 388.24027 -340.666324) (xy 388.24027 -339.917024)
					(xy 387.949948 -339.917024) (xy 387.949948 -340.3727) (xy 383.530348 -340.3727) (xy 383.530348 -339.917024)
				)
			)
		)
		(zone
			(layer "F.Cu")
			(hatch none 0.5)
			(connect_pads
				(clearance 0)
			)
			(min_thickness 0.25)
			(keepout
				(tracks not_allowed)
				(vias allowed)
				(pads allowed)
				(copperpour not_allowed)
				(footprints allowed)
			)
			(placement
				(enabled no)
				(sheetname "")
			)
			(fill
				(thermal_gap 0.5)
				(thermal_bridge_width 0.5)
				(island_removal_mode 0)
			)
			(polygon
				(pts
					(xy 384.494532 -342.844628) (xy 384.72364 -342.844628) (xy 384.789426 -342.778842) (xy 384.789426 -342.167718)
					(xy 383.240026 -342.167718) (xy 383.240026 -342.62441) (xy 383.935732 -342.62441) (xy 383.935732 -342.463882)
					(xy 384.494532 -342.463882)
				)
			)
		)
	)
	(footprint ""
		(layer "F.Cu")
		(at 397.254476 -148.010118 90)
		(property "Reference" "PR520"
			(at 0 0 90)
			(layer "F.SilkS")
			(hide yes)
			(effects
				(font
					(size 1.27 1.27)
				)
			)
		)
		(property "Value" ""
			(at 0 0 90)
			(layer "F.Fab")
			(effects
				(font
					(size 1.27 1.27)
				)
			)
		)
		(duplicate_pad_numbers_are_jumpers no)
		(fp_line
			(start 0.7874 -0.4064)
			(end 0.7874 0.4064)
			(stroke
				(width 0.1524)
				(type default)
			)
			(layer "F.SilkS")
		)
		(fp_line
			(start -0.7874 -0.4064)
			(end 0.7874 -0.4064)
			(stroke
				(width 0.1524)
				(type default)
			)
			(layer "F.SilkS")
		)
		(fp_line
			(start 0.7874 0.4064)
			(end -0.7874 0.4064)
			(stroke
				(width 0.1524)
				(type default)
			)
			(layer "F.SilkS")
		)
		(fp_line
			(start -0.7874 0.4064)
			(end -0.7874 -0.4064)
			(stroke
				(width 0.1524)
				(type default)
			)
			(layer "F.SilkS")
		)
		(fp_line
			(start -0.12065 -0.305054)
			(end -0.12065 -0.2794)
			(stroke
				(width 0.1)
				(type default)
			)
			(layer "F.Fab")
		)
		(fp_line
			(start -0.67945 -0.305054)
			(end -0.12065 -0.305054)
			(stroke
				(width 0.1)
				(type default)
			)
			(layer "F.Fab")
		)
		(fp_line
			(start 0.67945 -0.3048)
			(end 0.67945 0.3048)
			(stroke
				(width 0.1)
				(type default)
			)
			(layer "F.Fab")
		)
		(fp_line
			(start 0.12065 -0.3048)
			(end 0.67945 -0.3048)
			(stroke
				(width 0.1)
				(type default)
			)
			(layer "F.Fab")
		)
		(fp_line
			(start 0.12065 -0.2794)
			(end 0.12065 -0.3048)
			(stroke
				(width 0.1)
				(type default)
			)
			(layer "F.Fab")
		)
		(fp_line
			(start -0.12065 -0.2794)
			(end 0.12065 -0.2794)
			(stroke
				(width 0.1)
				(type default)
			)
			(layer "F.Fab")
		)
		(fp_line
			(start 0.120396 0.2794)
			(end -0.12065 0.2794)
			(stroke
				(width 0.1)
				(type default)
			)
			(layer "F.Fab")
		)
		(fp_line
			(start -0.12065 0.2794)
			(end -0.12065 0.3048)
			(stroke
				(width 0.1)
				(type default)
			)
			(layer "F.Fab")
		)
		(fp_line
			(start 0.67945 0.3048)
			(end 0.120396 0.3048)
			(stroke
				(width 0.1)
				(type default)
			)
			(layer "F.Fab")
		)
		(fp_line
			(start 0.120396 0.3048)
			(end 0.120396 0.2794)
			(stroke
				(width 0.1)
				(type default)
			)
			(layer "F.Fab")
		)
		(fp_line
			(start -0.12065 0.3048)
			(end -0.67945 0.3048)
			(stroke
				(width 0.1)
				(type default)
			)
			(layer "F.Fab")
		)
		(fp_line
			(start -0.67945 0.3048)
			(end -0.67945 -0.305054)
			(stroke
				(width 0.1)
				(type default)
			)
			(layer "F.Fab")
		)
		(pad "1" smd circle
			(at -0.40005 0 90)
			(size 0 0)
			(layers "F.Cu" "F.Mask" "F.Paste")
			(net "VSENSE_PVCCFA_EHV_CPU0_DN")
		)
		(pad "2" smd circle
			(at 0.40005 0 90)
			(size 0 0)
			(layers "F.Cu" "F.Mask" "F.Paste")
			(net "GND")
		)
	)
	(footprint ""
		(layer "F.Cu")
		(at 118.542816 -249.320558 -90)
		(property "Reference" "C229"
			(at 0 0 270)
			(layer "F.SilkS")
			(hide yes)
			(effects
				(font
					(size 1.27 1.27)
				)
			)
		)
		(property "Value" ""
			(at 0 0 270)
			(layer "F.Fab")
			(effects
				(font
					(size 1.27 1.27)
				)
			)
		)
		(duplicate_pad_numbers_are_jumpers no)
		(fp_line
			(start -0.7874 0.4064)
			(end -0.7874 -0.4064)
			(stroke
				(width 0.1524)
				(type default)
			)
			(layer "F.SilkS")
		)
		(fp_line
			(start 0.7874 0.4064)
			(end -0.7874 0.4064)
			(stroke
				(width 0.1524)
				(type default)
			)
			(layer "F.SilkS")
		)
		(fp_line
			(start -0.7874 -0.4064)
			(end 0.7874 -0.4064)
			(stroke
				(width 0.1524)
				(type default)
			)
			(layer "F.SilkS")
		)
		(fp_line
			(start 0.7874 -0.4064)
			(end 0.7874 0.4064)
			(stroke
				(width 0.1524)
				(type default)
			)
			(layer "F.SilkS")
		)
		(fp_line
			(start -0.67945 0.3048)
			(end -0.67945 -0.305054)
			(stroke
				(width 0.1)
				(type default)
			)
			(layer "F.Fab")
		)
		(fp_line
			(start -0.12065 0.3048)
			(end -0.67945 0.3048)
			(stroke
				(width 0.1)
				(type default)
			)
			(layer "F.Fab")
		)
		(fp_line
			(start 0.120396 0.3048)
			(end 0.120396 0.2794)
			(stroke
				(width 0.1)
				(type default)
			)
			(layer "F.Fab")
		)
		(fp_line
			(start 0.67945 0.3048)
			(end 0.120396 0.3048)
			(stroke
				(width 0.1)
				(type default)
			)
			(layer "F.Fab")
		)
		(fp_line
			(start -0.12065 0.2794)
			(end -0.12065 0.3048)
			(stroke
				(width 0.1)
				(type default)
			)
			(layer "F.Fab")
		)
		(fp_line
			(start 0.120396 0.2794)
			(end -0.12065 0.2794)
			(stroke
				(width 0.1)
				(type default)
			)
			(layer "F.Fab")
		)
		(fp_line
			(start -0.12065 -0.2794)
			(end 0.12065 -0.2794)
			(stroke
				(width 0.1)
				(type default)
			)
			(layer "F.Fab")
		)
		(fp_line
			(start 0.12065 -0.2794)
			(end 0.12065 -0.3048)
			(stroke
				(width 0.1)
				(type default)
			)
			(layer "F.Fab")
		)
		(fp_line
			(start 0.12065 -0.3048)
			(end 0.67945 -0.3048)
			(stroke
				(width 0.1)
				(type default)
			)
			(layer "F.Fab")
		)
		(fp_line
			(start 0.67945 -0.3048)
			(end 0.67945 0.3048)
			(stroke
				(width 0.1)
				(type default)
			)
			(layer "F.Fab")
		)
		(fp_line
			(start -0.67945 -0.305054)
			(end -0.12065 -0.305054)
			(stroke
				(width 0.1)
				(type default)
			)
			(layer "F.Fab")
		)
		(fp_line
			(start -0.12065 -0.305054)
			(end -0.12065 -0.2794)
			(stroke
				(width 0.1)
				(type default)
			)
			(layer "F.Fab")
		)
		(pad "1" smd circle
			(at -0.40005 0 270)
			(size 0 0)
			(layers "F.Cu" "F.Mask" "F.Paste")
			(net "PVCCIN_CPU1")
		)
		(pad "2" smd circle
			(at 0.40005 0 270)
			(size 0 0)
			(layers "F.Cu" "F.Mask" "F.Paste")
			(net "GND")
		)
	)
	(footprint ""
		(layer "F.Cu")
		(at 298.474384 -362.7755)
		(property "Reference" "PU70_P0_2"
			(at 8.245856 -3.740658 0)
			(unlocked yes)
			(layer "F.SilkS")
			(effects
				(font
					(size 0.7874 0.5842)
					(thickness 0.1524)
				)
				(justify left)
			)
		)
		(property "Value" ""
			(at 0 0 0)
			(layer "F.Fab")
			(effects
				(font
					(size 1.27 1.27)
				)
			)
		)
		(duplicate_pad_numbers_are_jumpers no)
		(fp_line
			(start -2.500122 -2.999994)
			(end -2.24409 -2.999994)
			(stroke
				(width 0.1524)
				(type default)
			)
			(layer "F.SilkS")
		)
		(fp_line
			(start -2.500122 -2.529078)
			(end -2.500122 -2.999994)
			(stroke
				(width 0.1524)
				(type default)
			)
			(layer "F.SilkS")
		)
		(fp_line
			(start -2.500122 0.6604)
			(end -2.500122 0.229108)
			(stroke
				(width 0.1524)
				(type default)
			)
			(layer "F.SilkS")
		)
		(fp_line
			(start -2.500122 2.999994)
			(end -2.500122 2.339594)
			(stroke
				(width 0.1524)
				(type default)
			)
			(layer "F.SilkS")
		)
		(fp_line
			(start -2.2987 2.999994)
			(end -2.500122 2.999994)
			(stroke
				(width 0.1524)
				(type default)
			)
			(layer "F.SilkS")
		)
		(fp_line
			(start 2.31394 -2.999994)
			(end 2.500122 -2.999994)
			(stroke
				(width 0.1524)
				(type default)
			)
			(layer "F.SilkS")
		)
		(fp_line
			(start 2.500122 -2.999994)
			(end 2.500122 -2.44348)
			(stroke
				(width 0.1524)
				(type default)
			)
			(layer "F.SilkS")
		)
		(fp_line
			(start 2.500122 2.339594)
			(end 2.500122 2.999994)
			(stroke
				(width 0.1524)
				(type default)
			)
			(layer "F.SilkS")
		)
		(fp_line
			(start 2.500122 2.999994)
			(end 2.2987 2.999994)
			(stroke
				(width 0.1524)
				(type default)
			)
			(layer "F.SilkS")
		)
		(fp_poly
			(pts
				(xy -2.164334 -3.650996) (xy -2.672334 -2.634996) (xy -3.180334 -3.650996)
			)
			(stroke
				(width 0)
				(type default)
			)
			(fill yes)
			(layer "F.SilkS")
		)
		(fp_line
			(start -2.500122 -2.999994)
			(end 2.500122 -2.999994)
			(stroke
				(width 0.1)
				(type default)
			)
			(layer "F.Fab")
		)
		(fp_line
			(start -2.500122 2.999994)
			(end -2.500122 -2.999994)
			(stroke
				(width 0.1)
				(type default)
			)
			(layer "F.Fab")
		)
		(fp_line
			(start 2.500122 -2.999994)
			(end 2.500122 2.999994)
			(stroke
				(width 0.1)
				(type default)
			)
			(layer "F.Fab")
		)
		(fp_line
			(start 2.500122 2.999994)
			(end -2.500122 2.999994)
			(stroke
				(width 0.1)
				(type default)
			)
			(layer "F.Fab")
		)
		(fp_poly
			(pts
				(xy -4.218432 -2.783078) (xy -4.218432 -1.767078) (xy -3.202432 -2.275078)
			)
			(stroke
				(width 0)
				(type default)
			)
			(fill yes)
			(layer "F.Fab")
		)
		(pad "1" smd rect
			(at -2.400046 -2.275078 90)
			(size 0.2286 0.6096)
			(layers "F.Cu" "F.Mask" "F.Paste")
			(net "PVCCFA_EHV_FIVRA_CPU0_VOS2")
		)
		(pad "2" smd rect
			(at -2.400046 -1.82499 90)
			(size 0.2286 0.6096)
			(layers "F.Cu" "F.Mask" "F.Paste")
			(net "GND")
		)
		(pad "3" smd rect
			(at -2.400046 -1.374902 90)
			(size 0.2286 0.6096)
			(layers "F.Cu" "F.Mask" "F.Paste")
			(net "PVCCFA_EHV_FIVRA_CPU0_VDD2")
		)
		(pad "4" smd rect
			(at -2.400046 -0.925068 90)
			(size 0.2286 0.6096)
			(layers "F.Cu" "F.Mask" "F.Paste")
			(net "PVCCFA_EHV_FIVRA_CPU0_PVCC2")
		)
		(pad "5" smd rect
			(at -2.400046 -0.47498 90)
			(size 0.2286 0.6096)
			(layers "F.Cu" "F.Mask" "F.Paste")
			(net "GND")
		)
		(pad "6" smd rect
			(at -2.400046 -0.024892 90)
			(size 0.2286 0.6096)
			(layers "F.Cu" "F.Mask" "F.Paste")
			(net "Net_8514")
		)
		(pad "7_9-20_24" smd circle
			(at 0 1.150112 90)
			(size 0 0)
			(layers "F.Cu" "F.Mask" "F.Paste")
			(net "GND")
		)
		(pad "10_19" smd rect
			(at 0 2.899918 90)
			(size 0.6096 4.318)
			(layers "F.Cu" "F.Mask" "F.Paste")
			(net "SW_PVCCFA_EHV_FIVRA_CPU0_SW2")
		)
		(pad "25_29" smd rect
			(at 1.549908 -1.279906 270)
			(size 2.0574 2.3114)
			(layers "F.Cu" "F.Mask" "F.Paste")
			(net "SW_P12V_PVCCFA_EHV_FIVRA_CPU0_L")
		)
		(pad "30" smd rect
			(at 2.05994 -2.899918)
			(size 0.2286 0.6096)
			(layers "F.Cu" "F.Mask" "F.Paste")
			(net "SW_P12V_PVCCFA_EHV_FIVRA_CPU0_L")
		)
		(pad "31" smd rect
			(at 1.610106 -2.899918)
			(size 0.2286 0.6096)
			(layers "F.Cu" "F.Mask" "F.Paste")
			(net "Net_8515")
		)
		(pad "32" smd rect
			(at 1.160018 -2.899918)
			(size 0.2286 0.6096)
			(layers "F.Cu" "F.Mask" "F.Paste")
			(net "SW_PVCCFA_EHV_FIVRA_CPU0_BOOTR2")
		)
		(pad "33" smd rect
			(at 0.70993 -2.899918)
			(size 0.2286 0.6096)
			(layers "F.Cu" "F.Mask" "F.Paste")
			(net "SW_PVCCFA_EHV_FIVRA_CPU0_BOOT2")
		)
		(pad "34" smd rect
			(at 0.260096 -2.899918)
			(size 0.2286 0.6096)
			(layers "F.Cu" "F.Mask" "F.Paste")
			(net "PVCCFA_EHV_FIVRA_CPU0_PWM2")
		)
		(pad "35" smd rect
			(at -0.189992 -2.899918)
			(size 0.2286 0.6096)
			(layers "F.Cu" "F.Mask" "F.Paste")
			(net "PVCCFA_EHV_FIVRA_CPU0_VDD2")
		)
		(pad "36" smd rect
			(at -0.64008 -2.899918)
			(size 0.2286 0.6096)
			(layers "F.Cu" "F.Mask" "F.Paste")
			(net "PVCCFA_EHV_FIVRA_CPU0_BTSEN")
		)
		(pad "37" smd rect
			(at -1.089914 -2.899918)
			(size 0.2286 0.6096)
			(layers "F.Cu" "F.Mask" "F.Paste")
			(net "PVCCFA_EHV_FIVRA_CPU0_LSET2")
		)
		(pad "38" smd rect
			(at -1.540002 -2.899918)
			(size 0.2286 0.6096)
			(layers "F.Cu" "F.Mask" "F.Paste")
			(net "PVCCFA_EHV_FIVRA_CPU0_IMON2")
		)
		(pad "39" smd rect
			(at -1.99009 -2.899918)
			(size 0.2286 0.6096)
			(layers "F.Cu" "F.Mask" "F.Paste")
			(net "PVCCIN_CPU0_VREF")
		)
		(pad "40" smd rect
			(at -0.87503 -1.27508)
			(size 1.7526 1.9558)
			(layers "F.Cu" "F.Mask" "F.Paste")
			(net "GND")
		)
		(pad "41" smd rect
			(at -1.525016 0.249936 270)
			(size 0.3048 0.4572)
			(layers "F.Cu" "F.Mask" "F.Paste")
			(net "Net_8513")
		)
		(zone
			(layer "F.Cu")
			(hatch none 0.5)
			(connect_pads
				(clearance 0)
			)
			(min_thickness 0.25)
			(keepout
				(tracks not_allowed)
				(vias allowed)
				(pads allowed)
				(copperpour not_allowed)
				(footprints allowed)
			)
			(placement
				(enabled no)
				(sheetname "")
			)
			(fill
				(thermal_gap 0.5)
				(thermal_bridge_width 0.5)
				(island_removal_mode 0)
			)
			(polygon
				(pts
					(xy 295.974262 -359.775506) (xy 295.974262 -360.512868) (xy 300.974506 -360.512868) (xy 300.974506 -359.775506)
					(xy 300.684184 -359.775506) (xy 300.684184 -360.231182) (xy 296.264584 -360.231182) (xy 296.264584 -359.775506)
				)
			)
		)
		(zone
			(layer "F.Cu")
			(hatch none 0.5)
			(connect_pads
				(clearance 0)
			)
			(min_thickness 0.25)
			(keepout
				(tracks not_allowed)
				(vias allowed)
				(pads allowed)
				(copperpour not_allowed)
				(footprints allowed)
			)
			(placement
				(enabled no)
				(sheetname "")
			)
			(fill
				(thermal_gap 0.5)
				(thermal_bridge_width 0.5)
				(island_removal_mode 0)
			)
			(polygon
				(pts
					(xy 296.73296 -363.02188) (xy 297.44924 -363.02188) (xy 297.44924 -362.699808) (xy 297.523662 -362.699808)
					(xy 297.523662 -362.075222) (xy 297.47464 -362.0262) (xy 295.974262 -362.0262) (xy 295.974262 -362.482892)
					(xy 296.669968 -362.482892) (xy 296.669968 -362.322364) (xy 297.228768 -362.322364) (xy 297.228768 -362.728764)
					(xy 296.669968 -362.728764) (xy 296.669968 -362.508292) (xy 295.974262 -362.508292) (xy 295.974262 -362.635292)
					(xy 296.429938 -362.635292) (xy 296.429938 -362.994448) (xy 296.73296 -362.994448)
				)
			)
		)
	)
	(footprint ""
		(layer "F.Cu")
		(at 434.86832 -126.850648 180)
		(property "Reference" "PC627"
			(at 0 0 180)
			(layer "F.SilkS")
			(hide yes)
			(effects
				(font
					(size 1.27 1.27)
				)
			)
		)
		(property "Value" ""
			(at 0 0 180)
			(layer "F.Fab")
			(effects
				(font
					(size 1.27 1.27)
				)
			)
		)
		(duplicate_pad_numbers_are_jumpers no)
		(fp_line
			(start 0.7874 0.4064)
			(end -0.7874 0.4064)
			(stroke
				(width 0.1524)
				(type default)
			)
			(layer "F.SilkS")
		)
		(fp_line
			(start 0.7874 -0.4064)
			(end 0.7874 0.4064)
			(stroke
				(width 0.1524)
				(type default)
			)
			(layer "F.SilkS")
		)
		(fp_line
			(start -0.7874 0.4064)
			(end -0.7874 -0.4064)
			(stroke
				(width 0.1524)
				(type default)
			)
			(layer "F.SilkS")
		)
		(fp_line
			(start -0.7874 -0.4064)
			(end 0.7874 -0.4064)
			(stroke
				(width 0.1524)
				(type default)
			)
			(layer "F.SilkS")
		)
		(fp_line
			(start 0.67945 0.3048)
			(end 0.120396 0.3048)
			(stroke
				(width 0.1)
				(type default)
			)
			(layer "F.Fab")
		)
		(fp_line
			(start 0.67945 -0.3048)
			(end 0.67945 0.3048)
			(stroke
				(width 0.1)
				(type default)
			)
			(layer "F.Fab")
		)
		(fp_line
			(start 0.12065 -0.2794)
			(end 0.12065 -0.3048)
			(stroke
				(width 0.1)
				(type default)
			)
			(layer "F.Fab")
		)
		(fp_line
			(start 0.12065 -0.3048)
			(end 0.67945 -0.3048)
			(stroke
				(width 0.1)
				(type default)
			)
			(layer "F.Fab")
		)
		(fp_line
			(start 0.120396 0.3048)
			(end 0.120396 0.2794)
			(stroke
				(width 0.1)
				(type default)
			)
			(layer "F.Fab")
		)
		(fp_line
			(start 0.120396 0.2794)
			(end -0.12065 0.2794)
			(stroke
				(width 0.1)
				(type default)
			)
			(layer "F.Fab")
		)
		(fp_line
			(start -0.12065 0.3048)
			(end -0.67945 0.3048)
			(stroke
				(width 0.1)
				(type default)
			)
			(layer "F.Fab")
		)
		(fp_line
			(start -0.12065 0.2794)
			(end -0.12065 0.3048)
			(stroke
				(width 0.1)
				(type default)
			)
			(layer "F.Fab")
		)
		(fp_line
			(start -0.12065 -0.2794)
			(end 0.12065 -0.2794)
			(stroke
				(width 0.1)
				(type default)
			)
			(layer "F.Fab")
		)
		(fp_line
			(start -0.12065 -0.305054)
			(end -0.12065 -0.2794)
			(stroke
				(width 0.1)
				(type default)
			)
			(layer "F.Fab")
		)
		(fp_line
			(start -0.67945 0.3048)
			(end -0.67945 -0.305054)
			(stroke
				(width 0.1)
				(type default)
			)
			(layer "F.Fab")
		)
		(fp_line
			(start -0.67945 -0.305054)
			(end -0.12065 -0.305054)
			(stroke
				(width 0.1)
				(type default)
			)
			(layer "F.Fab")
		)
		(pad "1" smd circle
			(at -0.40005 0 180)
			(size 0 0)
			(layers "F.Cu" "F.Mask" "F.Paste")
			(net "SH_PVCCD_HV_CPU0_R")
		)
		(pad "2" smd circle
			(at 0.40005 0 180)
			(size 0 0)
			(layers "F.Cu" "F.Mask" "F.Paste")
			(net "VSENSE_PVCCD_HV_CPU0_DN")
		)
	)
	(footprint ""
		(layer "F.Cu")
		(at 435.42712 -395.87678)
		(property "Reference" "ME28"
			(at 0 0 0)
			(layer "F.SilkS")
			(hide yes)
			(effects
				(font
					(size 1.27 1.27)
				)
			)
		)
		(property "Value" ""
			(at 0 0 0)
			(layer "F.Fab")
			(effects
				(font
					(size 1.27 1.27)
				)
			)
		)
		(duplicate_pad_numbers_are_jumpers no)
		(fp_line
			(start 0 -10.500106)
			(end 1.524 -10.500106)
			(stroke
				(width 0.1524)
				(type default)
			)
			(layer "F.SilkS")
		)
		(fp_line
			(start 0 -8.976106)
			(end 0 -10.500106)
			(stroke
				(width 0.1524)
				(type default)
			)
			(layer "F.SilkS")
		)
		(fp_line
			(start 0 0)
			(end 0 -1.524)
			(stroke
				(width 0.1524)
				(type default)
			)
			(layer "F.SilkS")
		)
		(fp_line
			(start 1.524 0)
			(end 0 0)
			(stroke
				(width 0.1524)
				(type default)
			)
			(layer "F.SilkS")
		)
		(fp_line
			(start 8.976106 0)
			(end 10.500106 0)
			(stroke
				(width 0.1524)
				(type default)
			)
			(layer "F.SilkS")
		)
		(fp_line
			(start 10.500106 -10.500106)
			(end 8.976106 -10.500106)
			(stroke
				(width 0.1524)
				(type default)
			)
			(layer "F.SilkS")
		)
		(fp_line
			(start 10.500106 -8.976106)
			(end 10.500106 -10.500106)
			(stroke
				(width 0.1524)
				(type default)
			)
			(layer "F.SilkS")
		)
		(fp_line
			(start 10.500106 0)
			(end 10.500106 -1.524)
			(stroke
				(width 0.1524)
				(type default)
			)
			(layer "F.SilkS")
		)
		(fp_text user "BIOS"
			(at 1.681226 -8.494776 0)
			(unlocked yes)
			(layer "F.SilkS")
			(effects
				(font
					(size 1.905 1.4224)
					(thickness 0.1524)
				)
				(justify left)
			)
		)
		(fp_text user "BMC"
			(at 2.303526 -1.865376 0)
			(unlocked yes)
			(layer "F.SilkS")
			(effects
				(font
					(size 1.905 1.4224)
					(thickness 0.1524)
				)
				(justify left)
			)
		)
		(fp_text user "&"
			(at 4.183126 -5.624576 0)
			(unlocked yes)
			(layer "F.SilkS")
			(effects
				(font
					(size 1.905 1.4224)
					(thickness 0.1524)
				)
				(justify left)
			)
		)
		(zone
			(layer "F.Cu")
			(hatch none 0.5)
			(connect_pads
				(clearance 0)
			)
			(min_thickness 0.25)
			(keepout
				(tracks not_allowed)
				(vias allowed)
				(pads allowed)
				(copperpour not_allowed)
				(footprints allowed)
			)
			(placement
				(enabled no)
				(sheetname "")
			)
			(fill
				(thermal_gap 0.5)
				(thermal_bridge_width 0.5)
				(island_removal_mode 0)
			)
			(polygon
				(pts
					(xy 435.42712 -395.87678) (xy 445.927226 -395.87678) (xy 445.927226 -406.376886) (xy 435.42712 -406.376886)
				)
			)
		)
	)
	(footprint ""
		(layer "F.Cu")
		(at 124.672344 -77.571092)
		(property "Reference" "R1813"
			(at 0 0 0)
			(layer "F.SilkS")
			(hide yes)
			(effects
				(font
					(size 1.27 1.27)
				)
			)
		)
		(property "Value" ""
			(at 0 0 0)
			(layer "F.Fab")
			(effects
				(font
					(size 1.27 1.27)
				)
			)
		)
		(duplicate_pad_numbers_are_jumpers no)
		(fp_line
			(start -0.7874 -0.4064)
			(end 0.7874 -0.4064)
			(stroke
				(width 0.1524)
				(type default)
			)
			(layer "F.SilkS")
		)
		(fp_line
			(start -0.7874 0.4064)
			(end -0.7874 -0.4064)
			(stroke
				(width 0.1524)
				(type default)
			)
			(layer "F.SilkS")
		)
		(fp_line
			(start 0.7874 -0.4064)
			(end 0.7874 0.4064)
			(stroke
				(width 0.1524)
				(type default)
			)
			(layer "F.SilkS")
		)
		(fp_line
			(start 0.7874 0.4064)
			(end -0.7874 0.4064)
			(stroke
				(width 0.1524)
				(type default)
			)
			(layer "F.SilkS")
		)
		(fp_line
			(start -0.67945 -0.305054)
			(end -0.12065 -0.305054)
			(stroke
				(width 0.1)
				(type default)
			)
			(layer "F.Fab")
		)
		(fp_line
			(start -0.67945 0.3048)
			(end -0.67945 -0.305054)
			(stroke
				(width 0.1)
				(type default)
			)
			(layer "F.Fab")
		)
		(fp_line
			(start -0.12065 -0.305054)
			(end -0.12065 -0.2794)
			(stroke
				(width 0.1)
				(type default)
			)
			(layer "F.Fab")
		)
		(fp_line
			(start -0.12065 -0.2794)
			(end 0.12065 -0.2794)
			(stroke
				(width 0.1)
				(type default)
			)
			(layer "F.Fab")
		)
		(fp_line
			(start -0.12065 0.2794)
			(end -0.12065 0.3048)
			(stroke
				(width 0.1)
				(type default)
			)
			(layer "F.Fab")
		)
		(fp_line
			(start -0.12065 0.3048)
			(end -0.67945 0.3048)
			(stroke
				(width 0.1)
				(type default)
			)
			(layer "F.Fab")
		)
		(fp_line
			(start 0.120396 0.2794)
			(end -0.12065 0.2794)
			(stroke
				(width 0.1)
				(type default)
			)
			(layer "F.Fab")
		)
		(fp_line
			(start 0.120396 0.3048)
			(end 0.120396 0.2794)
			(stroke
				(width 0.1)
				(type default)
			)
			(layer "F.Fab")
		)
		(fp_line
			(start 0.12065 -0.3048)
			(end 0.67945 -0.3048)
			(stroke
				(width 0.1)
				(type default)
			)
			(layer "F.Fab")
		)
		(fp_line
			(start 0.12065 -0.2794)
			(end 0.12065 -0.3048)
			(stroke
				(width 0.1)
				(type default)
			)
			(layer "F.Fab")
		)
		(fp_line
			(start 0.67945 -0.3048)
			(end 0.67945 0.3048)
			(stroke
				(width 0.1)
				(type default)
			)
			(layer "F.Fab")
		)
		(fp_line
			(start 0.67945 0.3048)
			(end 0.120396 0.3048)
			(stroke
				(width 0.1)
				(type default)
			)
			(layer "F.Fab")
		)
		(pad "1" smd circle
			(at -0.40005 0)
			(size 0 0)
			(layers "F.Cu" "F.Mask" "F.Paste")
			(net "P3V3_AUX")
		)
		(pad "2" smd circle
			(at 0.40005 0)
			(size 0 0)
			(layers "F.Cu" "F.Mask" "F.Paste")
			(net "FM_JTAG_BMC_MUX_SEL")
		)
	)
	(footprint ""
		(layer "F.Cu")
		(at 12.786106 -106.30408 -90)
		(property "Reference" "R2789"
			(at 0 0 270)
			(layer "F.SilkS")
			(hide yes)
			(effects
				(font
					(size 1.27 1.27)
				)
			)
		)
		(property "Value" ""
			(at 0 0 270)
			(layer "F.Fab")
			(effects
				(font
					(size 1.27 1.27)
				)
			)
		)
		(duplicate_pad_numbers_are_jumpers no)
		(fp_line
			(start -0.00254 0.4064)
			(end -0.7874 0.4064)
			(stroke
				(width 0.1524)
				(type default)
			)
			(layer "F.SilkS")
		)
		(fp_line
			(start -0.7874 -0.4064)
			(end 0.7874 -0.4064)
			(stroke
				(width 0.1524)
				(type default)
			)
			(layer "F.SilkS")
		)
		(fp_line
			(start 0.7874 -0.4064)
			(end 0.7874 0.4064)
			(stroke
				(width 0.1524)
				(type default)
			)
			(layer "F.SilkS")
		)
		(fp_line
			(start -0.67945 0.3048)
			(end -0.67945 -0.305054)
			(stroke
				(width 0.1)
				(type default)
			)
			(layer "F.Fab")
		)
		(fp_line
			(start -0.12065 0.3048)
			(end -0.67945 0.3048)
			(stroke
				(width 0.1)
				(type default)
			)
			(layer "F.Fab")
		)
		(fp_line
			(start 0.120396 0.3048)
			(end 0.120396 0.2794)
			(stroke
				(width 0.1)
				(type default)
			)
			(layer "F.Fab")
		)
		(fp_line
			(start 0.67945 0.3048)
			(end 0.120396 0.3048)
			(stroke
				(width 0.1)
				(type default)
			)
			(layer "F.Fab")
		)
		(fp_line
			(start -0.12065 0.2794)
			(end -0.12065 0.3048)
			(stroke
				(width 0.1)
				(type default)
			)
			(layer "F.Fab")
		)
		(fp_line
			(start 0.120396 0.2794)
			(end -0.12065 0.2794)
			(stroke
				(width 0.1)
				(type default)
			)
			(layer "F.Fab")
		)
		(fp_line
			(start -0.12065 -0.2794)
			(end 0.12065 -0.2794)
			(stroke
				(width 0.1)
				(type default)
			)
			(layer "F.Fab")
		)
		(fp_line
			(start 0.12065 -0.2794)
			(end 0.12065 -0.3048)
			(stroke
				(width 0.1)
				(type default)
			)
			(layer "F.Fab")
		)
		(fp_line
			(start 0.12065 -0.3048)
			(end 0.67945 -0.3048)
			(stroke
				(width 0.1)
				(type default)
			)
			(layer "F.Fab")
		)
		(fp_line
			(start 0.67945 -0.3048)
			(end 0.67945 0.3048)
			(stroke
				(width 0.1)
				(type default)
			)
			(layer "F.Fab")
		)
		(fp_line
			(start -0.67945 -0.305054)
			(end -0.12065 -0.305054)
			(stroke
				(width 0.1)
				(type default)
			)
			(layer "F.Fab")
		)
		(fp_line
			(start -0.12065 -0.305054)
			(end -0.12065 -0.2794)
			(stroke
				(width 0.1)
				(type default)
			)
			(layer "F.Fab")
		)
		(pad "1" smd rect
			(at -0.40005 0 90)
			(size 0.4572 0.508)
			(layers "F.Cu" "F.Mask" "F.Paste")
			(net "USB2_HOST_BMC_B_BUF_DN")
		)
		(pad "2" smd rect
			(at 0.40005 0 90)
			(size 0.4572 0.508)
			(layers "F.Cu" "F.Mask" "F.Paste")
			(net "USB2_HUB_BUF_SWB_R_DN")
		)
	)
	(footprint ""
		(layer "F.Cu")
		(at 356.51821 -358.848406 -90)
		(property "Reference" "PU14"
			(at -7.271512 3.70967 0)
			(unlocked yes)
			(layer "F.SilkS")
			(effects
				(font
					(size 0.7874 0.5842)
					(thickness 0.1524)
				)
				(justify left)
			)
		)
		(property "Value" ""
			(at 0 0 270)
			(layer "F.Fab")
			(effects
				(font
					(size 1.27 1.27)
				)
			)
		)
		(duplicate_pad_numbers_are_jumpers no)
		(fp_line
			(start -1.400048 3.86969)
			(end -1.400048 3.36169)
			(stroke
				(width 0.1524)
				(type default)
			)
			(layer "F.SilkS")
		)
		(fp_line
			(start 0.599948 3.366008)
			(end 0.599948 4.255008)
			(stroke
				(width 0.1524)
				(type default)
			)
			(layer "F.SilkS")
		)
		(fp_line
			(start -2.999994 2.999994)
			(end -2.999994 2.490978)
			(stroke
				(width 0.1524)
				(type default)
			)
			(layer "F.SilkS")
		)
		(fp_line
			(start -2.518156 2.999994)
			(end -2.999994 2.999994)
			(stroke
				(width 0.1524)
				(type default)
			)
			(layer "F.SilkS")
		)
		(fp_line
			(start 2.999994 2.999994)
			(end 2.47015 2.999994)
			(stroke
				(width 0.1524)
				(type default)
			)
			(layer "F.SilkS")
		)
		(fp_line
			(start 2.999994 2.490978)
			(end 2.999994 2.999994)
			(stroke
				(width 0.1524)
				(type default)
			)
			(layer "F.SilkS")
		)
		(fp_line
			(start 3.3782 2.199894)
			(end 3.8862 2.199894)
			(stroke
				(width 0.1524)
				(type default)
			)
			(layer "F.SilkS")
		)
		(fp_line
			(start -3.3782 1.400048)
			(end -4.2672 1.400048)
			(stroke
				(width 0.1524)
				(type default)
			)
			(layer "F.SilkS")
		)
		(fp_line
			(start 3.3528 0.199898)
			(end 4.2418 0.199898)
			(stroke
				(width 0.1524)
				(type default)
			)
			(layer "F.SilkS")
		)
		(fp_line
			(start -3.3782 -0.599948)
			(end -3.7592 -0.599948)
			(stroke
				(width 0.1524)
				(type default)
			)
			(layer "F.SilkS")
		)
		(fp_line
			(start 3.3528 -1.800098)
			(end 3.8608 -1.800098)
			(stroke
				(width 0.1524)
				(type default)
			)
			(layer "F.SilkS")
		)
		(fp_line
			(start -2.999994 -2.438654)
			(end -2.999994 -2.999994)
			(stroke
				(width 0.1524)
				(type default)
			)
			(layer "F.SilkS")
		)
		(fp_line
			(start -2.999994 -2.999994)
			(end -2.489962 -2.999994)
			(stroke
				(width 0.1524)
				(type default)
			)
			(layer "F.SilkS")
		)
		(fp_line
			(start 2.437384 -2.999994)
			(end 2.999994 -2.999994)
			(stroke
				(width 0.1524)
				(type default)
			)
			(layer "F.SilkS")
		)
		(fp_line
			(start 2.999994 -2.999994)
			(end 2.999994 -2.471166)
			(stroke
				(width 0.1524)
				(type default)
			)
			(layer "F.SilkS")
		)
		(fp_line
			(start -0.999998 -3.3782)
			(end -0.999998 -3.8862)
			(stroke
				(width 0.1524)
				(type default)
			)
			(layer "F.SilkS")
		)
		(fp_line
			(start 0.999998 -4.2545)
			(end 0.999998 -3.3655)
			(stroke
				(width 0.1524)
				(type default)
			)
			(layer "F.SilkS")
		)
		(fp_poly
			(pts
				(xy -3.299206 -2.199894) (xy -3.6449 -2.050034) (xy -3.6449 -2.352294)
			)
			(stroke
				(width 0)
				(type default)
			)
			(fill yes)
			(layer "F.SilkS")
		)
		(fp_line
			(start -1.400048 3.86969)
			(end -1.400048 3.36169)
			(stroke
				(width 0.1)
				(type default)
			)
			(layer "F.Fab")
		)
		(fp_line
			(start 0.599948 3.366008)
			(end 0.599948 4.255008)
			(stroke
				(width 0.1)
				(type default)
			)
			(layer "F.Fab")
		)
		(fp_line
			(start -2.999994 2.999994)
			(end -2.999994 -2.999994)
			(stroke
				(width 0.1)
				(type default)
			)
			(layer "F.Fab")
		)
		(fp_line
			(start 2.999994 2.999994)
			(end -2.999994 2.999994)
			(stroke
				(width 0.1)
				(type default)
			)
			(layer "F.Fab")
		)
		(fp_line
			(start 3.3782 2.199894)
			(end 3.8862 2.199894)
			(stroke
				(width 0.1)
				(type default)
			)
			(layer "F.Fab")
		)
		(fp_line
			(start -3.3782 1.400048)
			(end -4.2672 1.400048)
			(stroke
				(width 0.1)
				(type default)
			)
			(layer "F.Fab")
		)
		(fp_line
			(start 3.3528 0.199898)
			(end 4.2418 0.199898)
			(stroke
				(width 0.1)
				(type default)
			)
			(layer "F.Fab")
		)
		(fp_line
			(start -3.3782 -0.599948)
			(end -3.7592 -0.599948)
			(stroke
				(width 0.1)
				(type default)
			)
			(layer "F.Fab")
		)
		(fp_line
			(start 3.3528 -1.800098)
			(end 3.8608 -1.800098)
			(stroke
				(width 0.1)
				(type default)
			)
			(layer "F.Fab")
		)
		(fp_line
			(start -2.999994 -2.999994)
			(end 2.999994 -2.999994)
			(stroke
				(width 0.1)
				(type default)
			)
			(layer "F.Fab")
		)
		(fp_line
			(start 2.999994 -2.999994)
			(end 2.999994 2.999994)
			(stroke
				(width 0.1)
				(type default)
			)
			(layer "F.Fab")
		)
		(fp_line
			(start -0.999998 -3.3782)
			(end -0.999998 -3.8862)
			(stroke
				(width 0.1)
				(type default)
			)
			(layer "F.Fab")
		)
		(fp_line
			(start 0.999998 -4.2545)
			(end 0.999998 -3.3655)
			(stroke
				(width 0.1)
				(type default)
			)
			(layer "F.Fab")
		)
		(fp_poly
			(pts
				(xy -3.6449 -2.352294) (xy -3.6449 -2.050034) (xy -3.299206 -2.199894)
			)
			(stroke
				(width 0)
				(type default)
			)
			(fill yes)
			(layer "F.Fab")
		)
		(fp_text user "24"
			(at 4.862068 9.55675 0)
			(unlocked yes)
			(layer "F.SilkS")
			(effects
				(font
					(size 0.7874 0.5842)
					(thickness 0.1524)
				)
				(justify left)
			)
		)
		(fp_text user "13"
			(at -3.420872 4.73075 0)
			(unlocked yes)
			(layer "F.SilkS")
			(effects
				(font
					(size 0.7874 0.5842)
					(thickness 0.1524)
				)
				(justify left)
			)
		)
		(fp_text user "12"
			(at -5.600192 3.84937 0)
			(unlocked yes)
			(layer "F.SilkS")
			(effects
				(font
					(size 0.7874 0.5842)
					(thickness 0.1524)
				)
				(justify left)
			)
		)
		(fp_text user "25"
			(at 3.889248 1.95961 0)
			(unlocked yes)
			(layer "F.SilkS")
			(effects
				(font
					(size 0.7874 0.5842)
					(thickness 0.1524)
				)
				(justify left)
			)
		)
		(fp_text user "48"
			(at -4.271772 -1.27889 0)
			(unlocked yes)
			(layer "F.SilkS")
			(effects
				(font
					(size 0.7874 0.5842)
					(thickness 0.1524)
				)
				(justify left)
			)
		)
		(fp_text user "36"
			(at 4.679188 -2.01041 0)
			(unlocked yes)
			(layer "F.SilkS")
			(effects
				(font
					(size 0.7874 0.5842)
					(thickness 0.1524)
				)
				(justify left)
			)
		)
		(fp_text user "48"
			(at -6.788912 -2.77495 0)
			(unlocked yes)
			(layer "F.SilkS")
			(effects
				(font
					(size 0.7874 0.5842)
					(thickness 0.1524)
				)
				(justify left)
			)
		)
		(fp_text user "37"
			(at 2.708148 -3.30581 0)
			(unlocked yes)
			(layer "F.SilkS")
			(effects
				(font
					(size 0.7874 0.5842)
					(thickness 0.1524)
				)
				(justify left)
			)
		)
		(fp_text user "13"
			(at -3.5814 3.794252 270)
			(unlocked yes)
			(layer "F.Fab")
			(effects
				(font
					(size 0.7874 0.5842)
					(thickness 0.1524)
				)
				(justify left)
			)
		)
		(fp_text user "24"
			(at 2.1844 3.768852 270)
			(unlocked yes)
			(layer "F.Fab")
			(effects
				(font
					(size 0.7874 0.5842)
					(thickness 0.1524)
				)
				(justify left)
			)
		)
		(fp_text user "25"
			(at 3.2004 2.829052 270)
			(unlocked yes)
			(layer "F.Fab")
			(effects
				(font
					(size 0.7874 0.5842)
					(thickness 0.1524)
				)
				(justify left)
			)
		)
		(fp_text user "12"
			(at -4.6228 2.752852 270)
			(unlocked yes)
			(layer "F.Fab")
			(effects
				(font
					(size 0.7874 0.5842)
					(thickness 0.1524)
				)
				(justify left)
			)
		)
		(fp_text user "36"
			(at 3.2258 -2.733548 270)
			(unlocked yes)
			(layer "F.Fab")
			(effects
				(font
					(size 0.7874 0.5842)
					(thickness 0.1524)
				)
				(justify left)
			)
		)
		(fp_text user "37"
			(at 2.2352 -3.724148 270)
			(unlocked yes)
			(layer "F.Fab")
			(effects
				(font
					(size 0.7874 0.5842)
					(thickness 0.1524)
				)
				(justify left)
			)
		)
		(fp_text user "48"
			(at -3.509264 -3.740658 270)
			(unlocked yes)
			(layer "F.Fab")
			(effects
				(font
					(size 0.7874 0.5842)
					(thickness 0.1524)
				)
				(justify left)
			)
		)
		(pad "1" smd rect
			(at -2.875026 -2.199894)
			(size 0.1778 0.6604)
			(layers "F.Cu" "F.Mask" "F.Paste")
			(net "PVCCFA_EHV_FIVRA_CPU0_PWM1")
		)
		(pad "2" smd rect
			(at -2.875026 -1.800098)
			(size 0.1778 0.6604)
			(layers "F.Cu" "F.Mask" "F.Paste")
			(net "PVCCFA_EHV_FIVRA_CPU0_PWM2")
		)
		(pad "3" smd rect
			(at -2.875026 -1.400048)
			(size 0.1778 0.6604)
			(layers "F.Cu" "F.Mask" "F.Paste")
			(net "PVCCFA_EHV_FIVRA_CPU0_PWM3")
		)
		(pad "4" smd rect
			(at -2.875026 -0.999998)
			(size 0.1778 0.6604)
			(layers "F.Cu" "F.Mask" "F.Paste")
			(net "PVCCFA_EHV_FIVRA_CPU0_PWM4")
		)
		(pad "5" smd rect
			(at -2.875026 -0.599948)
			(size 0.1778 0.6604)
			(layers "F.Cu" "F.Mask" "F.Paste")
			(net "PVCCIN_CPU0_PWM8")
		)
		(pad "6" smd rect
			(at -2.875026 -0.199898)
			(size 0.1778 0.6604)
			(layers "F.Cu" "F.Mask" "F.Paste")
			(net "PVCCIN_CPU0_PWM7")
		)
		(pad "7" smd rect
			(at -2.875026 0.199898)
			(size 0.1778 0.6604)
			(layers "F.Cu" "F.Mask" "F.Paste")
			(net "PVCCIN_CPU0_PWM6")
		)
		(pad "8" smd rect
			(at -2.875026 0.599948)
			(size 0.1778 0.6604)
			(layers "F.Cu" "F.Mask" "F.Paste")
			(net "PVCCIN_CPU0_PWM5")
		)
		(pad "9" smd rect
			(at -2.875026 0.999998)
			(size 0.1778 0.6604)
			(layers "F.Cu" "F.Mask" "F.Paste")
			(net "PVCCIN_CPU0_PWM4")
		)
		(pad "10" smd rect
			(at -2.875026 1.400048)
			(size 0.1778 0.6604)
			(layers "F.Cu" "F.Mask" "F.Paste")
			(net "PVCCIN_CPU0_PWM3")
		)
		(pad "11" smd rect
			(at -2.875026 1.800098)
			(size 0.1778 0.6604)
			(layers "F.Cu" "F.Mask" "F.Paste")
			(net "PVCCIN_CPU0_PWM2")
		)
		(pad "12" smd rect
			(at -2.875026 2.199894)
			(size 0.1778 0.6604)
			(layers "F.Cu" "F.Mask" "F.Paste")
			(net "PVCCIN_CPU0_PWM1")
		)
		(pad "13" smd rect
			(at -2.199894 2.875026 270)
			(size 0.1778 0.6604)
			(layers "F.Cu" "F.Mask" "F.Paste")
			(net "SMB_DIO_PVCCIN_CPU0")
		)
		(pad "14" smd rect
			(at -1.800098 2.875026 270)
			(size 0.1778 0.6604)
			(layers "F.Cu" "F.Mask" "F.Paste")
			(net "SMB_CLK_PVCCIN_CPU0")
		)
		(pad "15" smd rect
			(at -1.400048 2.875026 270)
			(size 0.1778 0.6604)
			(layers "F.Cu" "F.Mask" "F.Paste")
			(net "NC_PVCCIN_CPU0_SMB_ALERT")
		)
		(pad "16" smd rect
			(at -0.999998 2.875026 270)
			(size 0.1778 0.6604)
			(layers "F.Cu" "F.Mask" "F.Paste")
			(net "PWRGD_PVCCIN_CPU0_R")
		)
		(pad "17" smd rect
			(at -0.599948 2.875026 270)
			(size 0.1778 0.6604)
			(layers "F.Cu" "F.Mask" "F.Paste")
			(net "PVCCIN_CPU0_EN_R")
		)
		(pad "18" smd rect
			(at -0.199898 2.875026 270)
			(size 0.1778 0.6604)
			(layers "F.Cu" "F.Mask" "F.Paste")
			(net "IRQ_PVCCIN_CPU0_VRHOT_N")
		)
		(pad "19" smd rect
			(at 0.199898 2.875026 270)
			(size 0.1778 0.6604)
			(layers "F.Cu" "F.Mask" "F.Paste")
			(net "PVCCIN_CPU0_PIN_ALERT")
		)
		(pad "20" smd rect
			(at 0.599948 2.875026 270)
			(size 0.1778 0.6604)
			(layers "F.Cu" "F.Mask" "F.Paste")
			(net "PWRGD_PVCCFA_EHV_FIVRA_CPU0_R")
		)
		(pad "21" smd rect
			(at 0.999998 2.875026 270)
			(size 0.1778 0.6604)
			(layers "F.Cu" "F.Mask" "F.Paste")
			(net "SVID_CLK_PVCCIN_CPU0_R")
		)
		(pad "22" smd rect
			(at 1.400048 2.875026 270)
			(size 0.1778 0.6604)
			(layers "F.Cu" "F.Mask" "F.Paste")
			(net "SVID_DIO_PVCCIN_CPU0_R")
		)
		(pad "23" smd rect
			(at 1.800098 2.875026 270)
			(size 0.1778 0.6604)
			(layers "F.Cu" "F.Mask" "F.Paste")
			(net "SVID_ALERT_PVCCIN_CPU0_R")
		)
		(pad "24" smd rect
			(at 2.199894 2.875026 270)
			(size 0.1778 0.6604)
			(layers "F.Cu" "F.Mask" "F.Paste")
			(net "PVCCFA_EHV_FIVRA_CPU0_EN_R")
		)
		(pad "25" smd rect
			(at 2.875026 2.199894)
			(size 0.1778 0.6604)
			(layers "F.Cu" "F.Mask" "F.Paste")
			(net "SH_PVCCIN_CPU0_R")
		)
		(pad "26" smd rect
			(at 2.875026 1.800098)
			(size 0.1778 0.6604)
			(layers "F.Cu" "F.Mask" "F.Paste")
			(net "VSENSE_PVCCIN_CPU0_DN")
		)
		(pad "27" smd rect
			(at 2.875026 1.400048)
			(size 0.1778 0.6604)
			(layers "F.Cu" "F.Mask" "F.Paste")
			(net "PVCCIN_CPU0_IMON1")
		)
		(pad "28" smd rect
			(at 2.875026 0.999998)
			(size 0.1778 0.6604)
			(layers "F.Cu" "F.Mask" "F.Paste")
			(net "PVCCIN_CPU0_IMON2")
		)
		(pad "29" smd rect
			(at 2.875026 0.599948)
			(size 0.1778 0.6604)
			(layers "F.Cu" "F.Mask" "F.Paste")
			(net "PVCCIN_CPU0_IMON3")
		)
		(pad "30" smd rect
			(at 2.875026 0.199898)
			(size 0.1778 0.6604)
			(layers "F.Cu" "F.Mask" "F.Paste")
			(net "PVCCIN_CPU0_IMON4")
		)
		(pad "31" smd rect
			(at 2.875026 -0.199898)
			(size 0.1778 0.6604)
			(layers "F.Cu" "F.Mask" "F.Paste")
			(net "PVCCIN_CPU0_IMON5")
		)
		(pad "32" smd rect
			(at 2.875026 -0.599948)
			(size 0.1778 0.6604)
			(layers "F.Cu" "F.Mask" "F.Paste")
			(net "PVCCIN_CPU0_IMON6")
		)
		(pad "33" smd rect
			(at 2.875026 -0.999998)
			(size 0.1778 0.6604)
			(layers "F.Cu" "F.Mask" "F.Paste")
			(net "PVCCIN_CPU0_IMON7")
		)
		(pad "34" smd rect
			(at 2.875026 -1.400048)
			(size 0.1778 0.6604)
			(layers "F.Cu" "F.Mask" "F.Paste")
			(net "PVCCIN_CPU0_IMON8")
		)
		(pad "35" smd rect
			(at 2.875026 -1.800098)
			(size 0.1778 0.6604)
			(layers "F.Cu" "F.Mask" "F.Paste")
			(net "PVCCFA_EHV_FIVRA_CPU0_IMON4")
		)
		(pad "36" smd rect
			(at 2.875026 -2.199894)
			(size 0.1778 0.6604)
			(layers "F.Cu" "F.Mask" "F.Paste")
			(net "PVCCFA_EHV_FIVRA_CPU0_IMON3")
		)
		(pad "37" smd rect
			(at 2.199894 -2.875026 270)
			(size 0.1778 0.6604)
			(layers "F.Cu" "F.Mask" "F.Paste")
			(net "PVCCFA_EHV_FIVRA_CPU0_IMON2")
		)
		(pad "38" smd rect
			(at 1.800098 -2.875026 270)
			(size 0.1778 0.6604)
			(layers "F.Cu" "F.Mask" "F.Paste")
			(net "PVCCFA_EHV_FIVRA_CPU0_IMON1")
		)
		(pad "39" smd rect
			(at 1.400048 -2.875026 270)
			(size 0.1778 0.6604)
			(layers "F.Cu" "F.Mask" "F.Paste")
			(net "VSENSE_PVCCFA_EHV_FIVRA_CPU0_DN")
		)
		(pad "40" smd rect
			(at 0.999998 -2.875026 270)
			(size 0.1778 0.6604)
			(layers "F.Cu" "F.Mask" "F.Paste")
			(net "SH_PVCCFA_EHV_FIVRA_CPU0_R")
		)
		(pad "41" smd rect
			(at 0.599948 -2.875026 270)
			(size 0.1778 0.6604)
			(layers "F.Cu" "F.Mask" "F.Paste")
			(net "PVCCIN_CPU0_VR_FAULT")
		)
		(pad "42" smd rect
			(at 0.199898 -2.875026 270)
			(size 0.1778 0.6604)
			(layers "F.Cu" "F.Mask" "F.Paste")
			(net "PVCCIN_CPU0_ADDR")
		)
		(pad "43" smd rect
			(at -0.199898 -2.875026 270)
			(size 0.1778 0.6604)
			(layers "F.Cu" "F.Mask" "F.Paste")
			(net "PVCCIN_CPU0_ATSEN")
		)
		(pad "44" smd rect
			(at -0.599948 -2.875026 270)
			(size 0.1778 0.6604)
			(layers "F.Cu" "F.Mask" "F.Paste")
			(net "PVCCFA_EHV_FIVRA_CPU0_BTSEN")
		)
		(pad "45" smd rect
			(at -0.999998 -2.875026 270)
			(size 0.1778 0.6604)
			(layers "F.Cu" "F.Mask" "F.Paste")
			(net "PVCCIN_CPU0_CSPIN")
		)
		(pad "46" smd rect
			(at -1.400048 -2.875026 270)
			(size 0.1778 0.6604)
			(layers "F.Cu" "F.Mask" "F.Paste")
			(net "PVCCIN_CPU0_VIN_CSNIN")
		)
		(pad "47" smd rect
			(at -1.800098 -2.875026 270)
			(size 0.1778 0.6604)
			(layers "F.Cu" "F.Mask" "F.Paste")
			(net "PVCCIN_CPU0_VCC")
		)
		(pad "48" smd rect
			(at -2.199894 -2.875026 270)
			(size 0.1778 0.6604)
			(layers "F.Cu" "F.Mask" "F.Paste")
			(net "PVCCIN_CPU0_VREF")
		)
		(pad "TH" smd rect
			(at 0 0 270)
			(size 4.4196 4.4196)
			(layers "F.Cu" "F.Mask" "F.Paste")
			(net "GND")
		)
		(zone
			(layer "F.Cu")
			(hatch none 0.5)
			(connect_pads
				(clearance 0)
			)
			(min_thickness 0.25)
			(keepout
				(tracks not_allowed)
				(vias allowed)
				(pads allowed)
				(copperpour not_allowed)
				(footprints allowed)
			)
			(placement
				(enabled no)
				(sheetname "")
			)
			(fill
				(thermal_gap 0.5)
				(thermal_bridge_width 0.5)
				(island_removal_mode 0)
			)
			(polygon
				(pts
					(xy 354.30841 -361.337606) (xy 354.30841 -361.236006) (xy 354.30841 -361.134406) (xy 354.23221 -361.134406)
					(xy 354.23221 -356.562406) (xy 358.80421 -356.562406) (xy 358.80421 -361.134406) (xy 354.33381 -361.134406)
					(xy 354.33381 -361.236006) (xy 354.33381 -361.337606) (xy 358.98201 -361.337606) (xy 359.00741 -361.337606)
					(xy 359.00741 -356.359206) (xy 358.98201 -356.359206) (xy 354.02901 -356.359206) (xy 354.02901 -361.337606)
				)
			)
		)
	)
	(footprint ""
		(layer "F.Cu")
		(at 346.840048 -402.371052 -90)
		(property "Reference" "C1550"
			(at 0 0 270)
			(layer "F.SilkS")
			(hide yes)
			(effects
				(font
					(size 1.27 1.27)
				)
			)
		)
		(property "Value" ""
			(at 0 0 270)
			(layer "F.Fab")
			(effects
				(font
					(size 1.27 1.27)
				)
			)
		)
		(duplicate_pad_numbers_are_jumpers no)
		(fp_line
			(start -0.299974 0.150114)
			(end -0.299974 -0.150114)
			(stroke
				(width 0.1)
				(type default)
			)
			(layer "F.Fab")
		)
		(fp_line
			(start 0.299974 0.150114)
			(end -0.299974 0.150114)
			(stroke
				(width 0.1)
				(type default)
			)
			(layer "F.Fab")
		)
		(fp_line
			(start -0.299974 -0.150114)
			(end 0.299974 -0.150114)
			(stroke
				(width 0.1)
				(type default)
			)
			(layer "F.Fab")
		)
		(fp_line
			(start 0.299974 -0.150114)
			(end 0.299974 0.150114)
			(stroke
				(width 0.1)
				(type default)
			)
			(layer "F.Fab")
		)
		(pad "1" smd rect
			(at -0.2667 0 270)
			(size 0.3048 0.381)
			(layers "F.Cu" "F.Mask" "F.Paste")
			(net "P5E_CPU0_PE4_TX_C_DN<14>")
		)
		(pad "2" smd rect
			(at 0.2667 0 270)
			(size 0.3048 0.381)
			(layers "F.Cu" "F.Mask" "F.Paste")
			(net "P5E_CPU0_PE4_TX_DN<14>")
		)
	)
	(footprint ""
		(layer "F.Cu")
		(at 317.7921 -76.585064 90)
		(property "Reference" "R2243"
			(at 0 0 90)
			(layer "F.SilkS")
			(hide yes)
			(effects
				(font
					(size 1.27 1.27)
				)
			)
		)
		(property "Value" ""
			(at 0 0 90)
			(layer "F.Fab")
			(effects
				(font
					(size 1.27 1.27)
				)
			)
		)
		(duplicate_pad_numbers_are_jumpers no)
		(fp_line
			(start 0.7874 -0.4064)
			(end 0.7874 0.4064)
			(stroke
				(width 0.1524)
				(type default)
			)
			(layer "F.SilkS")
		)
		(fp_line
			(start -0.7874 -0.4064)
			(end 0.7874 -0.4064)
			(stroke
				(width 0.1524)
				(type default)
			)
			(layer "F.SilkS")
		)
		(fp_line
			(start 0.7874 0.4064)
			(end -0.7874 0.4064)
			(stroke
				(width 0.1524)
				(type default)
			)
			(layer "F.SilkS")
		)
		(fp_line
			(start -0.7874 0.4064)
			(end -0.7874 -0.4064)
			(stroke
				(width 0.1524)
				(type default)
			)
			(layer "F.SilkS")
		)
		(fp_line
			(start -0.12065 -0.305054)
			(end -0.12065 -0.2794)
			(stroke
				(width 0.1)
				(type default)
			)
			(layer "F.Fab")
		)
		(fp_line
			(start -0.67945 -0.305054)
			(end -0.12065 -0.305054)
			(stroke
				(width 0.1)
				(type default)
			)
			(layer "F.Fab")
		)
		(fp_line
			(start 0.67945 -0.3048)
			(end 0.67945 0.3048)
			(stroke
				(width 0.1)
				(type default)
			)
			(layer "F.Fab")
		)
		(fp_line
			(start 0.12065 -0.3048)
			(end 0.67945 -0.3048)
			(stroke
				(width 0.1)
				(type default)
			)
			(layer "F.Fab")
		)
		(fp_line
			(start 0.12065 -0.2794)
			(end 0.12065 -0.3048)
			(stroke
				(width 0.1)
				(type default)
			)
			(layer "F.Fab")
		)
		(fp_line
			(start -0.12065 -0.2794)
			(end 0.12065 -0.2794)
			(stroke
				(width 0.1)
				(type default)
			)
			(layer "F.Fab")
		)
		(fp_line
			(start 0.120396 0.2794)
			(end -0.12065 0.2794)
			(stroke
				(width 0.1)
				(type default)
			)
			(layer "F.Fab")
		)
		(fp_line
			(start -0.12065 0.2794)
			(end -0.12065 0.3048)
			(stroke
				(width 0.1)
				(type default)
			)
			(layer "F.Fab")
		)
		(fp_line
			(start 0.67945 0.3048)
			(end 0.120396 0.3048)
			(stroke
				(width 0.1)
				(type default)
			)
			(layer "F.Fab")
		)
		(fp_line
			(start 0.120396 0.3048)
			(end 0.120396 0.2794)
			(stroke
				(width 0.1)
				(type default)
			)
			(layer "F.Fab")
		)
		(fp_line
			(start -0.12065 0.3048)
			(end -0.67945 0.3048)
			(stroke
				(width 0.1)
				(type default)
			)
			(layer "F.Fab")
		)
		(fp_line
			(start -0.67945 0.3048)
			(end -0.67945 -0.305054)
			(stroke
				(width 0.1)
				(type default)
			)
			(layer "F.Fab")
		)
		(pad "1" smd circle
			(at -0.40005 0 90)
			(size 0 0)
			(layers "F.Cu" "F.Mask" "F.Paste")
			(net "FM_BOARD_SKU_ID0")
		)
		(pad "2" smd circle
			(at 0.40005 0 90)
			(size 0 0)
			(layers "F.Cu" "F.Mask" "F.Paste")
			(net "GND")
		)
	)
	(footprint ""
		(layer "F.Cu")
		(at 265.172952 -127.548894)
		(property "Reference" "R4500"
			(at 0 0 0)
			(layer "F.SilkS")
			(hide yes)
			(effects
				(font
					(size 1.27 1.27)
				)
			)
		)
		(property "Value" ""
			(at 0 0 0)
			(layer "F.Fab")
			(effects
				(font
					(size 1.27 1.27)
				)
			)
		)
		(duplicate_pad_numbers_are_jumpers no)
		(fp_line
			(start -0.7874 -0.4064)
			(end 0.7874 -0.4064)
			(stroke
				(width 0.1524)
				(type default)
			)
			(layer "F.SilkS")
		)
		(fp_line
			(start -0.7874 0.4064)
			(end -0.7874 -0.4064)
			(stroke
				(width 0.1524)
				(type default)
			)
			(layer "F.SilkS")
		)
		(fp_line
			(start 0.7874 -0.4064)
			(end 0.7874 0.4064)
			(stroke
				(width 0.1524)
				(type default)
			)
			(layer "F.SilkS")
		)
		(fp_line
			(start 0.7874 0.4064)
			(end -0.7874 0.4064)
			(stroke
				(width 0.1524)
				(type default)
			)
			(layer "F.SilkS")
		)
		(fp_line
			(start -0.67945 -0.305054)
			(end -0.12065 -0.305054)
			(stroke
				(width 0.1)
				(type default)
			)
			(layer "F.Fab")
		)
		(fp_line
			(start -0.67945 0.3048)
			(end -0.67945 -0.305054)
			(stroke
				(width 0.1)
				(type default)
			)
			(layer "F.Fab")
		)
		(fp_line
			(start -0.12065 -0.305054)
			(end -0.12065 -0.2794)
			(stroke
				(width 0.1)
				(type default)
			)
			(layer "F.Fab")
		)
		(fp_line
			(start -0.12065 -0.2794)
			(end 0.12065 -0.2794)
			(stroke
				(width 0.1)
				(type default)
			)
			(layer "F.Fab")
		)
		(fp_line
			(start -0.12065 0.2794)
			(end -0.12065 0.3048)
			(stroke
				(width 0.1)
				(type default)
			)
			(layer "F.Fab")
		)
		(fp_line
			(start -0.12065 0.3048)
			(end -0.67945 0.3048)
			(stroke
				(width 0.1)
				(type default)
			)
			(layer "F.Fab")
		)
		(fp_line
			(start 0.120396 0.2794)
			(end -0.12065 0.2794)
			(stroke
				(width 0.1)
				(type default)
			)
			(layer "F.Fab")
		)
		(fp_line
			(start 0.120396 0.3048)
			(end 0.120396 0.2794)
			(stroke
				(width 0.1)
				(type default)
			)
			(layer "F.Fab")
		)
		(fp_line
			(start 0.12065 -0.3048)
			(end 0.67945 -0.3048)
			(stroke
				(width 0.1)
				(type default)
			)
			(layer "F.Fab")
		)
		(fp_line
			(start 0.12065 -0.2794)
			(end 0.12065 -0.3048)
			(stroke
				(width 0.1)
				(type default)
			)
			(layer "F.Fab")
		)
		(fp_line
			(start 0.67945 -0.3048)
			(end 0.67945 0.3048)
			(stroke
				(width 0.1)
				(type default)
			)
			(layer "F.Fab")
		)
		(fp_line
			(start 0.67945 0.3048)
			(end 0.120396 0.3048)
			(stroke
				(width 0.1)
				(type default)
			)
			(layer "F.Fab")
		)
		(pad "1" smd circle
			(at -0.40005 0)
			(size 0 0)
			(layers "F.Cu" "F.Mask" "F.Paste")
			(net "P3V3")
		)
		(pad "2" smd circle
			(at 0.40005 0)
			(size 0 0)
			(layers "F.Cu" "F.Mask" "F.Paste")
			(net "PU_CLK_BUF_ISO_EN")
		)
	)
	(footprint ""
		(layer "F.Cu")
		(at 361.288838 -324.445376)
		(property "Reference" "PL112"
			(at 15.670022 5.810758 0)
			(unlocked yes)
			(layer "F.SilkS")
			(effects
				(font
					(size 0.7874 0.5842)
					(thickness 0.1524)
				)
				(justify left)
			)
		)
		(property "Value" ""
			(at 0 0 0)
			(layer "F.Fab")
			(effects
				(font
					(size 1.27 1.27)
				)
			)
		)
		(duplicate_pad_numbers_are_jumpers no)
		(fp_line
			(start -3.750056 -5.500116)
			(end -2.393442 -5.500116)
			(stroke
				(width 0.1524)
				(type default)
			)
			(layer "F.SilkS")
		)
		(fp_line
			(start -3.750056 5.500116)
			(end -3.750056 -5.500116)
			(stroke
				(width 0.1524)
				(type default)
			)
			(layer "F.SilkS")
		)
		(fp_line
			(start -2.393442 5.500116)
			(end -3.750056 5.500116)
			(stroke
				(width 0.1524)
				(type default)
			)
			(layer "F.SilkS")
		)
		(fp_line
			(start 2.393442 5.500116)
			(end 3.750056 5.500116)
			(stroke
				(width 0.1524)
				(type default)
			)
			(layer "F.SilkS")
		)
		(fp_line
			(start 3.750056 -5.500116)
			(end 2.393442 -5.500116)
			(stroke
				(width 0.1524)
				(type default)
			)
			(layer "F.SilkS")
		)
		(fp_line
			(start 3.750056 -4.449572)
			(end 3.750056 -5.500116)
			(stroke
				(width 0.1524)
				(type default)
			)
			(layer "F.SilkS")
		)
		(fp_line
			(start 3.750056 5.500116)
			(end 3.750056 -3.687572)
			(stroke
				(width 0.1524)
				(type default)
			)
			(layer "F.SilkS")
		)
		(fp_poly
			(pts
				(xy -3.380994 -7.001764) (xy -3.021838 -5.924042) (xy -4.099306 -6.283198)
			)
			(stroke
				(width 0)
				(type default)
			)
			(fill yes)
			(layer "F.SilkS")
		)
		(fp_line
			(start -3.750056 -5.500116)
			(end -3.750056 5.500116)
			(stroke
				(width 0.1)
				(type default)
			)
			(layer "F.Fab")
		)
		(fp_line
			(start -3.750056 5.500116)
			(end 3.750056 5.500116)
			(stroke
				(width 0.1)
				(type default)
			)
			(layer "F.Fab")
		)
		(fp_line
			(start 3.750056 -5.500116)
			(end -3.750056 -5.500116)
			(stroke
				(width 0.1)
				(type default)
			)
			(layer "F.Fab")
		)
		(fp_line
			(start 3.750056 5.500116)
			(end 3.750056 -5.500116)
			(stroke
				(width 0.1)
				(type default)
			)
			(layer "F.Fab")
		)
		(fp_poly
			(pts
				(xy -4.9276 -4.757928) (xy -4.9276 -3.741928) (xy -3.9116 -4.249928)
			)
			(stroke
				(width 0)
				(type default)
			)
			(fill yes)
			(layer "F.Fab")
		)
		(pad "1" smd rect
			(at 0 -4.249928 270)
			(size 2.413 4.5212)
			(layers "F.Cu" "F.Mask" "F.Paste")
			(net "SW_PVCCIN_CPU0_SW3")
		)
		(pad "2" smd rect
			(at 0 -1.175004 270)
			(size 1.3716 4.5212)
			(layers "F.Cu" "F.Mask" "F.Paste")
			(net "IND_P0_CPL3")
		)
		(pad "3" smd rect
			(at 0 1.175004 270)
			(size 1.3716 4.5212)
			(layers "F.Cu" "F.Mask" "F.Paste")
			(net "IND_P0_CPL4")
		)
		(pad "4" smd rect
			(at 0 4.249928 270)
			(size 2.413 4.5212)
			(layers "F.Cu" "F.Mask" "F.Paste")
			(net "PVCCIN_CPU0")
		)
	)
	(footprint ""
		(layer "F.Cu")
		(at 366.48263 -251.375418 90)
		(property "Reference" "C1040"
			(at 0 0 90)
			(layer "F.SilkS")
			(hide yes)
			(effects
				(font
					(size 1.27 1.27)
				)
			)
		)
		(property "Value" ""
			(at 0 0 90)
			(layer "F.Fab")
			(effects
				(font
					(size 1.27 1.27)
				)
			)
		)
		(duplicate_pad_numbers_are_jumpers no)
		(fp_line
			(start 0.7874 -0.4064)
			(end 0.7874 0.4064)
			(stroke
				(width 0.1524)
				(type default)
			)
			(layer "F.SilkS")
		)
		(fp_line
			(start -0.7874 -0.4064)
			(end 0.7874 -0.4064)
			(stroke
				(width 0.1524)
				(type default)
			)
			(layer "F.SilkS")
		)
		(fp_line
			(start 0.7874 0.4064)
			(end -0.7874 0.4064)
			(stroke
				(width 0.1524)
				(type default)
			)
			(layer "F.SilkS")
		)
		(fp_line
			(start -0.7874 0.4064)
			(end -0.7874 -0.4064)
			(stroke
				(width 0.1524)
				(type default)
			)
			(layer "F.SilkS")
		)
		(fp_line
			(start -0.12065 -0.305054)
			(end -0.12065 -0.2794)
			(stroke
				(width 0.1)
				(type default)
			)
			(layer "F.Fab")
		)
		(fp_line
			(start -0.67945 -0.305054)
			(end -0.12065 -0.305054)
			(stroke
				(width 0.1)
				(type default)
			)
			(layer "F.Fab")
		)
		(fp_line
			(start 0.67945 -0.3048)
			(end 0.67945 0.3048)
			(stroke
				(width 0.1)
				(type default)
			)
			(layer "F.Fab")
		)
		(fp_line
			(start 0.12065 -0.3048)
			(end 0.67945 -0.3048)
			(stroke
				(width 0.1)
				(type default)
			)
			(layer "F.Fab")
		)
		(fp_line
			(start 0.12065 -0.2794)
			(end 0.12065 -0.3048)
			(stroke
				(width 0.1)
				(type default)
			)
			(layer "F.Fab")
		)
		(fp_line
			(start -0.12065 -0.2794)
			(end 0.12065 -0.2794)
			(stroke
				(width 0.1)
				(type default)
			)
			(layer "F.Fab")
		)
		(fp_line
			(start 0.120396 0.2794)
			(end -0.12065 0.2794)
			(stroke
				(width 0.1)
				(type default)
			)
			(layer "F.Fab")
		)
		(fp_line
			(start -0.12065 0.2794)
			(end -0.12065 0.3048)
			(stroke
				(width 0.1)
				(type default)
			)
			(layer "F.Fab")
		)
		(fp_line
			(start 0.67945 0.3048)
			(end 0.120396 0.3048)
			(stroke
				(width 0.1)
				(type default)
			)
			(layer "F.Fab")
		)
		(fp_line
			(start 0.120396 0.3048)
			(end 0.120396 0.2794)
			(stroke
				(width 0.1)
				(type default)
			)
			(layer "F.Fab")
		)
		(fp_line
			(start -0.12065 0.3048)
			(end -0.67945 0.3048)
			(stroke
				(width 0.1)
				(type default)
			)
			(layer "F.Fab")
		)
		(fp_line
			(start -0.67945 0.3048)
			(end -0.67945 -0.305054)
			(stroke
				(width 0.1)
				(type default)
			)
			(layer "F.Fab")
		)
		(pad "1" smd circle
			(at -0.40005 0 90)
			(size 0 0)
			(layers "F.Cu" "F.Mask" "F.Paste")
			(net "PVCCIN_CPU0")
		)
		(pad "2" smd circle
			(at 0.40005 0 90)
			(size 0 0)
			(layers "F.Cu" "F.Mask" "F.Paste")
			(net "GND")
		)
	)
	(footprint ""
		(layer "F.Cu")
		(at 164.64788 -107.025948 180)
		(property "Reference" "R2939"
			(at 0 0 180)
			(layer "F.SilkS")
			(hide yes)
			(effects
				(font
					(size 1.27 1.27)
				)
			)
		)
		(property "Value" ""
			(at 0 0 180)
			(layer "F.Fab")
			(effects
				(font
					(size 1.27 1.27)
				)
			)
		)
		(duplicate_pad_numbers_are_jumpers no)
		(fp_line
			(start 0.7874 0.4064)
			(end -0.7874 0.4064)
			(stroke
				(width 0.1524)
				(type default)
			)
			(layer "F.SilkS")
		)
		(fp_line
			(start 0.7874 -0.4064)
			(end 0.7874 0.4064)
			(stroke
				(width 0.1524)
				(type default)
			)
			(layer "F.SilkS")
		)
		(fp_line
			(start -0.7874 0.4064)
			(end -0.7874 -0.4064)
			(stroke
				(width 0.1524)
				(type default)
			)
			(layer "F.SilkS")
		)
		(fp_line
			(start -0.7874 -0.4064)
			(end 0.7874 -0.4064)
			(stroke
				(width 0.1524)
				(type default)
			)
			(layer "F.SilkS")
		)
		(fp_line
			(start 0.67945 0.3048)
			(end 0.120396 0.3048)
			(stroke
				(width 0.1)
				(type default)
			)
			(layer "F.Fab")
		)
		(fp_line
			(start 0.67945 -0.3048)
			(end 0.67945 0.3048)
			(stroke
				(width 0.1)
				(type default)
			)
			(layer "F.Fab")
		)
		(fp_line
			(start 0.12065 -0.2794)
			(end 0.12065 -0.3048)
			(stroke
				(width 0.1)
				(type default)
			)
			(layer "F.Fab")
		)
		(fp_line
			(start 0.12065 -0.3048)
			(end 0.67945 -0.3048)
			(stroke
				(width 0.1)
				(type default)
			)
			(layer "F.Fab")
		)
		(fp_line
			(start 0.120396 0.3048)
			(end 0.120396 0.2794)
			(stroke
				(width 0.1)
				(type default)
			)
			(layer "F.Fab")
		)
		(fp_line
			(start 0.120396 0.2794)
			(end -0.12065 0.2794)
			(stroke
				(width 0.1)
				(type default)
			)
			(layer "F.Fab")
		)
		(fp_line
			(start -0.12065 0.3048)
			(end -0.67945 0.3048)
			(stroke
				(width 0.1)
				(type default)
			)
			(layer "F.Fab")
		)
		(fp_line
			(start -0.12065 0.2794)
			(end -0.12065 0.3048)
			(stroke
				(width 0.1)
				(type default)
			)
			(layer "F.Fab")
		)
		(fp_line
			(start -0.12065 -0.2794)
			(end 0.12065 -0.2794)
			(stroke
				(width 0.1)
				(type default)
			)
			(layer "F.Fab")
		)
		(fp_line
			(start -0.12065 -0.305054)
			(end -0.12065 -0.2794)
			(stroke
				(width 0.1)
				(type default)
			)
			(layer "F.Fab")
		)
		(fp_line
			(start -0.67945 0.3048)
			(end -0.67945 -0.305054)
			(stroke
				(width 0.1)
				(type default)
			)
			(layer "F.Fab")
		)
		(fp_line
			(start -0.67945 -0.305054)
			(end -0.12065 -0.305054)
			(stroke
				(width 0.1)
				(type default)
			)
			(layer "F.Fab")
		)
		(pad "1" smd circle
			(at -0.40005 0 180)
			(size 0 0)
			(layers "F.Cu" "F.Mask" "F.Paste")
			(net "FM_GPU_HSC_EN_R")
		)
		(pad "2" smd circle
			(at 0.40005 0 180)
			(size 0 0)
			(layers "F.Cu" "F.Mask" "F.Paste")
			(net "FM_GPU_HSC_EN")
		)
	)
	(footprint ""
		(layer "F.Cu")
		(at 345.79179 -69.36994 90)
		(property "Reference" "C150"
			(at 0 0 90)
			(layer "F.SilkS")
			(hide yes)
			(effects
				(font
					(size 1.27 1.27)
				)
			)
		)
		(property "Value" ""
			(at 0 0 90)
			(layer "F.Fab")
			(effects
				(font
					(size 1.27 1.27)
				)
			)
		)
		(duplicate_pad_numbers_are_jumpers no)
		(fp_line
			(start 0.299974 -0.150114)
			(end 0.299974 0.150114)
			(stroke
				(width 0.1)
				(type default)
			)
			(layer "F.Fab")
		)
		(fp_line
			(start -0.299974 -0.150114)
			(end 0.299974 -0.150114)
			(stroke
				(width 0.1)
				(type default)
			)
			(layer "F.Fab")
		)
		(fp_line
			(start 0.299974 0.150114)
			(end -0.299974 0.150114)
			(stroke
				(width 0.1)
				(type default)
			)
			(layer "F.Fab")
		)
		(fp_line
			(start -0.299974 0.150114)
			(end -0.299974 -0.150114)
			(stroke
				(width 0.1)
				(type default)
			)
			(layer "F.Fab")
		)
		(pad "1" smd rect
			(at -0.2667 0 90)
			(size 0.3048 0.381)
			(layers "F.Cu" "F.Mask" "F.Paste")
			(net "DMI_CPU0_PCH_TX_C_DP<2>")
		)
		(pad "2" smd rect
			(at 0.2667 0 90)
			(size 0.3048 0.381)
			(layers "F.Cu" "F.Mask" "F.Paste")
			(net "DMI_CPU0_PCH_TX_DP<2>")
		)
	)
	(footprint ""
		(layer "F.Cu")
		(at 160.83788 -131.155948 90)
		(property "Reference" "Q53"
			(at 3.93573 -0.59436 0)
			(unlocked yes)
			(layer "F.SilkS")
			(effects
				(font
					(size 0.7874 0.5842)
					(thickness 0.1524)
				)
				(justify left)
			)
		)
		(property "Value" ""
			(at 0 0 90)
			(layer "F.Fab")
			(effects
				(font
					(size 1.27 1.27)
				)
			)
		)
		(duplicate_pad_numbers_are_jumpers no)
		(fp_line
			(start 1.603248 -1.500124)
			(end 1.603248 1.500124)
			(stroke
				(width 0.1524)
				(type default)
			)
			(layer "F.SilkS")
		)
		(fp_line
			(start -1.603248 -1.500124)
			(end 1.603248 -1.500124)
			(stroke
				(width 0.1524)
				(type default)
			)
			(layer "F.SilkS")
		)
		(fp_line
			(start 1.603248 1.500124)
			(end -1.603248 1.500124)
			(stroke
				(width 0.1524)
				(type default)
			)
			(layer "F.SilkS")
		)
		(fp_line
			(start -1.603248 1.500124)
			(end -1.603248 -1.500124)
			(stroke
				(width 0.1524)
				(type default)
			)
			(layer "F.SilkS")
		)
		(fp_line
			(start 0.700024 -1.500124)
			(end -0.700024 -1.500124)
			(stroke
				(width 0.1)
				(type default)
			)
			(layer "F.Fab")
		)
		(fp_line
			(start -0.700024 -1.500124)
			(end -0.700024 -1.169924)
			(stroke
				(width 0.1)
				(type default)
			)
			(layer "F.Fab")
		)
		(fp_line
			(start -0.700024 -1.169924)
			(end -1.249934 -1.169924)
			(stroke
				(width 0.1)
				(type default)
			)
			(layer "F.Fab")
		)
		(fp_line
			(start -1.249934 -1.169924)
			(end -1.249934 -0.729996)
			(stroke
				(width 0.1)
				(type default)
			)
			(layer "F.Fab")
		)
		(fp_line
			(start -0.6985 -0.729996)
			(end -0.6985 0.729996)
			(stroke
				(width 0.1)
				(type default)
			)
			(layer "F.Fab")
		)
		(fp_line
			(start -1.249934 -0.729996)
			(end -0.6985 -0.729996)
			(stroke
				(width 0.1)
				(type default)
			)
			(layer "F.Fab")
		)
		(fp_line
			(start 1.249934 -0.219964)
			(end 0.700024 -0.219964)
			(stroke
				(width 0.1)
				(type default)
			)
			(layer "F.Fab")
		)
		(fp_line
			(start 0.700024 -0.219964)
			(end 0.700024 -1.500124)
			(stroke
				(width 0.1)
				(type default)
			)
			(layer "F.Fab")
		)
		(fp_line
			(start 1.249934 0.219964)
			(end 1.249934 -0.219964)
			(stroke
				(width 0.1)
				(type default)
			)
			(layer "F.Fab")
		)
		(fp_line
			(start 0.700024 0.219964)
			(end 1.249934 0.219964)
			(stroke
				(width 0.1)
				(type default)
			)
			(layer "F.Fab")
		)
		(fp_line
			(start -0.6985 0.729996)
			(end -1.249934 0.729996)
			(stroke
				(width 0.1)
				(type default)
			)
			(layer "F.Fab")
		)
		(fp_line
			(start -1.249934 0.729996)
			(end -1.249934 1.169924)
			(stroke
				(width 0.1)
				(type default)
			)
			(layer "F.Fab")
		)
		(fp_line
			(start -0.700024 1.169924)
			(end -0.700024 1.500124)
			(stroke
				(width 0.1)
				(type default)
			)
			(layer "F.Fab")
		)
		(fp_line
			(start -1.249934 1.169924)
			(end -0.700024 1.169924)
			(stroke
				(width 0.1)
				(type default)
			)
			(layer "F.Fab")
		)
		(fp_line
			(start 0.700024 1.500124)
			(end 0.700024 0.219964)
			(stroke
				(width 0.1)
				(type default)
			)
			(layer "F.Fab")
		)
		(fp_line
			(start -0.700024 1.500124)
			(end 0.700024 1.500124)
			(stroke
				(width 0.1)
				(type default)
			)
			(layer "F.Fab")
		)
		(fp_rect
			(start -0.700024 1.500124)
			(end 0.700024 -1.500124)
			(stroke
				(width 0)
				(type default)
			)
			(fill no)
			(layer "F.Fab")
		)
		(pad "D" smd rect
			(at 0.999998 0)
			(size 0.8128 0.9144)
			(layers "F.Cu" "F.Mask" "F.Paste")
			(net "PWRGD_P3V3_AUX_R2")
		)
		(pad "G" smd rect
			(at -0.999998 -0.94996)
			(size 0.8128 0.9144)
			(layers "F.Cu" "F.Mask" "F.Paste")
			(net "PWRGD_P3V3_AUX")
		)
		(pad "S" smd rect
			(at -0.999998 0.94996)
			(size 0.8128 0.9144)
			(layers "F.Cu" "F.Mask" "F.Paste")
			(net "GND")
		)
	)
	(footprint ""
		(layer "F.Cu")
		(at 103.103426 -409.57754 90)
		(property "Reference" "C2076"
			(at 0 0 90)
			(layer "F.SilkS")
			(hide yes)
			(effects
				(font
					(size 1.27 1.27)
				)
			)
		)
		(property "Value" ""
			(at 0 0 90)
			(layer "F.Fab")
			(effects
				(font
					(size 1.27 1.27)
				)
			)
		)
		(duplicate_pad_numbers_are_jumpers no)
		(fp_line
			(start 0.299974 -0.150114)
			(end 0.299974 0.150114)
			(stroke
				(width 0.1)
				(type default)
			)
			(layer "F.Fab")
		)
		(fp_line
			(start -0.299974 -0.150114)
			(end 0.299974 -0.150114)
			(stroke
				(width 0.1)
				(type default)
			)
			(layer "F.Fab")
		)
		(fp_line
			(start 0.299974 0.150114)
			(end -0.299974 0.150114)
			(stroke
				(width 0.1)
				(type default)
			)
			(layer "F.Fab")
		)
		(fp_line
			(start -0.299974 0.150114)
			(end -0.299974 -0.150114)
			(stroke
				(width 0.1)
				(type default)
			)
			(layer "F.Fab")
		)
		(pad "1" smd rect
			(at -0.2667 0 90)
			(size 0.3048 0.381)
			(layers "F.Cu" "F.Mask" "F.Paste")
			(net "P3E_PCH_NVS_TX_DN<0>")
		)
		(pad "2" smd rect
			(at 0.2667 0 90)
			(size 0.3048 0.381)
			(layers "F.Cu" "F.Mask" "F.Paste")
			(net "P3E_PCH_NVS_TX_C_DN<0>")
		)
		(zone
			(layer "In1.Cu")
			(hatch none 0.5)
			(connect_pads
				(clearance 0)
			)
			(min_thickness 0.25)
			(keepout
				(tracks not_allowed)
				(vias allowed)
				(pads allowed)
				(copperpour not_allowed)
				(footprints allowed)
			)
			(placement
				(enabled no)
				(sheetname "")
			)
			(fill
				(thermal_gap 0.5)
				(thermal_bridge_width 0.5)
				(island_removal_mode 0)
			)
			(polygon
				(pts
					(arc
						(start 103.344726 -409.71724)
						(mid 103.322408 -409.663358)
						(end 103.268526 -409.64104)
					)
					(arc
						(start 102.938326 -409.64104)
						(mid 102.884444 -409.663358)
						(end 102.862126 -409.71724)
					)
					(arc
						(start 102.862126 -409.97124)
						(mid 102.884444 -410.025122)
						(end 102.938326 -410.04744)
					)
					(arc
						(start 103.268526 -410.04744)
						(mid 103.322408 -410.025122)
						(end 103.344726 -409.97124)
					)
				)
			)
		)
		(zone
			(layer "In1.Cu")
			(hatch none 0.5)
			(connect_pads
				(clearance 0)
			)
			(min_thickness 0.25)
			(keepout
				(tracks not_allowed)
				(vias allowed)
				(pads allowed)
				(copperpour not_allowed)
				(footprints allowed)
			)
			(placement
				(enabled no)
				(sheetname "")
			)
			(fill
				(thermal_gap 0.5)
				(thermal_bridge_width 0.5)
				(island_removal_mode 0)
			)
			(polygon
				(pts
					(arc
						(start 103.344726 -409.18384)
						(mid 103.322408 -409.129958)
						(end 103.268526 -409.10764)
					)
					(arc
						(start 102.938326 -409.10764)
						(mid 102.884444 -409.129958)
						(end 102.862126 -409.18384)
					)
					(arc
						(start 102.862126 -409.43784)
						(mid 102.884444 -409.491722)
						(end 102.938326 -409.51404)
					)
					(arc
						(start 103.268526 -409.51404)
						(mid 103.322408 -409.491722)
						(end 103.344726 -409.43784)
					)
				)
			)
		)
	)
	(footprint ""
		(layer "F.Cu")
		(at 147.08378 -125.275848 180)
		(property "Reference" "R3156"
			(at 0 0 180)
			(layer "F.SilkS")
			(hide yes)
			(effects
				(font
					(size 1.27 1.27)
				)
			)
		)
		(property "Value" ""
			(at 0 0 180)
			(layer "F.Fab")
			(effects
				(font
					(size 1.27 1.27)
				)
			)
		)
		(duplicate_pad_numbers_are_jumpers no)
		(fp_line
			(start 0.7874 0.4064)
			(end -0.7874 0.4064)
			(stroke
				(width 0.1524)
				(type default)
			)
			(layer "F.SilkS")
		)
		(fp_line
			(start 0.7874 -0.4064)
			(end 0.7874 0.4064)
			(stroke
				(width 0.1524)
				(type default)
			)
			(layer "F.SilkS")
		)
		(fp_line
			(start -0.7874 0.4064)
			(end -0.7874 -0.4064)
			(stroke
				(width 0.1524)
				(type default)
			)
			(layer "F.SilkS")
		)
		(fp_line
			(start -0.7874 -0.4064)
			(end 0.7874 -0.4064)
			(stroke
				(width 0.1524)
				(type default)
			)
			(layer "F.SilkS")
		)
		(fp_line
			(start 0.67945 0.3048)
			(end 0.120396 0.3048)
			(stroke
				(width 0.1)
				(type default)
			)
			(layer "F.Fab")
		)
		(fp_line
			(start 0.67945 -0.3048)
			(end 0.67945 0.3048)
			(stroke
				(width 0.1)
				(type default)
			)
			(layer "F.Fab")
		)
		(fp_line
			(start 0.12065 -0.2794)
			(end 0.12065 -0.3048)
			(stroke
				(width 0.1)
				(type default)
			)
			(layer "F.Fab")
		)
		(fp_line
			(start 0.12065 -0.3048)
			(end 0.67945 -0.3048)
			(stroke
				(width 0.1)
				(type default)
			)
			(layer "F.Fab")
		)
		(fp_line
			(start 0.120396 0.3048)
			(end 0.120396 0.2794)
			(stroke
				(width 0.1)
				(type default)
			)
			(layer "F.Fab")
		)
		(fp_line
			(start 0.120396 0.2794)
			(end -0.12065 0.2794)
			(stroke
				(width 0.1)
				(type default)
			)
			(layer "F.Fab")
		)
		(fp_line
			(start -0.12065 0.3048)
			(end -0.67945 0.3048)
			(stroke
				(width 0.1)
				(type default)
			)
			(layer "F.Fab")
		)
		(fp_line
			(start -0.12065 0.2794)
			(end -0.12065 0.3048)
			(stroke
				(width 0.1)
				(type default)
			)
			(layer "F.Fab")
		)
		(fp_line
			(start -0.12065 -0.2794)
			(end 0.12065 -0.2794)
			(stroke
				(width 0.1)
				(type default)
			)
			(layer "F.Fab")
		)
		(fp_line
			(start -0.12065 -0.305054)
			(end -0.12065 -0.2794)
			(stroke
				(width 0.1)
				(type default)
			)
			(layer "F.Fab")
		)
		(fp_line
			(start -0.67945 0.3048)
			(end -0.67945 -0.305054)
			(stroke
				(width 0.1)
				(type default)
			)
			(layer "F.Fab")
		)
		(fp_line
			(start -0.67945 -0.305054)
			(end -0.12065 -0.305054)
			(stroke
				(width 0.1)
				(type default)
			)
			(layer "F.Fab")
		)
		(pad "1" smd circle
			(at -0.40005 0 180)
			(size 0 0)
			(layers "F.Cu" "F.Mask" "F.Paste")
			(net "SMB_PEHPCPU1_LVC3_SCL")
		)
		(pad "2" smd circle
			(at 0.40005 0 180)
			(size 0 0)
			(layers "F.Cu" "F.Mask" "F.Paste")
			(net "SMB_PEHPCPU1_LVC3_R3_SCL")
		)
	)
	(footprint ""
		(layer "F.Cu")
		(at 522.584426 2.295652 -90)
		(property "Reference" "X13"
			(at -1.331976 3.323336 90)
			(unlocked yes)
			(layer "F.SilkS")
			(effects
				(font
					(size 0.7874 0.5842)
					(thickness 0.1524)
				)
				(justify left)
			)
		)
		(property "Value" ""
			(at 0 0 270)
			(layer "F.Fab")
			(effects
				(font
					(size 1.27 1.27)
				)
			)
		)
		(property "Device Type" "TP_TDR_4P_FTS_MPKT4_H025P0200_I"
			(at 1.30175 1.27 0)
			(unlocked yes)
			(layer "F.Fab")
			(hide yes)
			(effects
				(font
					(size 0.635 0.4064)
					(thickness 0.1524)
				)
			)
		)
		(property "User Part Number" "TP15"
			(at 1.30175 1.27 0)
			(unlocked yes)
			(layer "Cmts.User")
			(hide yes)
			(effects
				(font
					(size 0.635 0.4064)
					(thickness 0.1524)
				)
			)
		)
		(duplicate_pad_numbers_are_jumpers no)
		(fp_line
			(start 0 3.81)
			(end 2.54 3.81)
			(stroke
				(width 0.1524)
				(type default)
			)
			(layer "F.SilkS")
		)
		(fp_line
			(start 2.54 3.81)
			(end 2.54 3.6703)
			(stroke
				(width 0.1524)
				(type default)
			)
			(layer "F.SilkS")
		)
		(fp_line
			(start 0 3.175)
			(end 0 3.81)
			(stroke
				(width 0.1524)
				(type default)
			)
			(layer "F.SilkS")
		)
		(fp_line
			(start 2.54 1.4097)
			(end 2.54 1.1303)
			(stroke
				(width 0.1524)
				(type default)
			)
			(layer "F.SilkS")
		)
		(fp_line
			(start 0 0.635)
			(end 0 1.905)
			(stroke
				(width 0.1524)
				(type default)
			)
			(layer "F.SilkS")
		)
		(fp_line
			(start 2.54 -1.1303)
			(end 2.54 -1.27)
			(stroke
				(width 0.1524)
				(type default)
			)
			(layer "F.SilkS")
		)
		(fp_line
			(start 0 -1.27)
			(end 0 -0.635)
			(stroke
				(width 0.1524)
				(type default)
			)
			(layer "F.SilkS")
		)
		(fp_line
			(start 2.54 -1.27)
			(end 0 -1.27)
			(stroke
				(width 0.1524)
				(type default)
			)
			(layer "F.SilkS")
		)
		(fp_poly
			(pts
				(xy -1.447292 0.108966) (xy -2.971292 0.870966) (xy -2.971292 -0.653034)
			)
			(stroke
				(width 0)
				(type default)
			)
			(fill yes)
			(layer "F.SilkS")
		)
		(fp_line
			(start 0 3.81)
			(end 2.54 3.81)
			(stroke
				(width 0.1)
				(type default)
			)
			(layer "F.Fab")
		)
		(fp_line
			(start 2.54 3.81)
			(end 2.54 -1.27)
			(stroke
				(width 0.1)
				(type default)
			)
			(layer "F.Fab")
		)
		(fp_line
			(start 0 -1.27)
			(end 0 3.81)
			(stroke
				(width 0.1)
				(type default)
			)
			(layer "F.Fab")
		)
		(fp_line
			(start 2.54 -1.27)
			(end 0 -1.27)
			(stroke
				(width 0.1)
				(type default)
			)
			(layer "F.Fab")
		)
		(fp_poly
			(pts
				(xy -0.761746 0) (xy -2.285746 -0.762) (xy -2.285746 0.762)
			)
			(stroke
				(width 0)
				(type default)
			)
			(fill yes)
			(layer "F.Fab")
		)
		(pad "1" thru_hole circle
			(at 0 0 270)
			(size 1.0033 1.0033)
			(drill 0.249936)
			(layers "*.Cu" "*.Mask")
			(remove_unused_layers no)
			(net "TDR_DIFF_100_TOP_DP")
			(clearance 0.10795)
			(thermal_gap 0.10795)
			(padstack
				(mode front_inner_back)
				(layer "Inner"
					(shape circle)
					(size 0.8001 0.8001)
					(clearance 0.1524)
				)
				(layer "B.Cu"
					(shape circle)
					(size 1.0033 1.0033)
					(clearance 0.10795)
				)
			)
		)
		(pad "2" thru_hole circle
			(at 2.54 0 270)
			(size 1.9939 1.9939)
			(drill 0.249936)
			(layers "*.Cu" "*.Mask")
			(remove_unused_layers no)
			(net "T1_GND")
			(clearance 0.10795)
			(thermal_gap 0.10795)
			(padstack
				(mode front_inner_back)
				(layer "Inner"
					(shape circle)
					(size 0.8001 0.8001)
					(clearance 0.1524)
				)
				(layer "B.Cu"
					(shape circle)
					(size 1.9939 1.9939)
					(clearance 0.10795)
				)
			)
		)
		(pad "3" thru_hole circle
			(at 2.54 2.54 270)
			(size 1.9939 1.9939)
			(drill 0.249936)
			(layers "*.Cu" "*.Mask")
			(remove_unused_layers no)
			(net "T1_GND")
			(clearance 0.10795)
			(thermal_gap 0.10795)
			(padstack
				(mode front_inner_back)
				(layer "Inner"
					(shape circle)
					(size 0.8001 0.8001)
					(clearance 0.1524)
				)
				(layer "B.Cu"
					(shape circle)
					(size 1.9939 1.9939)
					(clearance 0.10795)
				)
			)
		)
		(pad "4" thru_hole circle
			(at 0 2.54 270)
			(size 1.0033 1.0033)
			(drill 0.249936)
			(layers "*.Cu" "*.Mask")
			(remove_unused_layers no)
			(net "TDR_DIFF_100_TOP_DN")
			(clearance 0.10795)
			(thermal_gap 0.10795)
			(padstack
				(mode front_inner_back)
				(layer "Inner"
					(shape circle)
					(size 0.8001 0.8001)
					(clearance 0.1524)
				)
				(layer "B.Cu"
					(shape circle)
					(size 1.0033 1.0033)
					(clearance 0.10795)
				)
			)
		)
	)
	(footprint ""
		(layer "F.Cu")
		(at 36.930584 -111.603282)
		(property "Reference" "C2178"
			(at 0 0 0)
			(layer "F.SilkS")
			(hide yes)
			(effects
				(font
					(size 1.27 1.27)
				)
			)
		)
		(property "Value" ""
			(at 0 0 0)
			(layer "F.Fab")
			(effects
				(font
					(size 1.27 1.27)
				)
			)
		)
		(duplicate_pad_numbers_are_jumpers no)
		(fp_line
			(start -0.7874 -0.4064)
			(end 0.7874 -0.4064)
			(stroke
				(width 0.1524)
				(type default)
			)
			(layer "F.SilkS")
		)
		(fp_line
			(start -0.7874 0.4064)
			(end -0.7874 -0.4064)
			(stroke
				(width 0.1524)
				(type default)
			)
			(layer "F.SilkS")
		)
		(fp_line
			(start 0.7874 -0.4064)
			(end 0.7874 0.4064)
			(stroke
				(width 0.1524)
				(type default)
			)
			(layer "F.SilkS")
		)
		(fp_line
			(start 0.7874 0.4064)
			(end -0.7874 0.4064)
			(stroke
				(width 0.1524)
				(type default)
			)
			(layer "F.SilkS")
		)
		(fp_line
			(start -0.67945 -0.305054)
			(end -0.12065 -0.305054)
			(stroke
				(width 0.1)
				(type default)
			)
			(layer "F.Fab")
		)
		(fp_line
			(start -0.67945 0.3048)
			(end -0.67945 -0.305054)
			(stroke
				(width 0.1)
				(type default)
			)
			(layer "F.Fab")
		)
		(fp_line
			(start -0.12065 -0.305054)
			(end -0.12065 -0.2794)
			(stroke
				(width 0.1)
				(type default)
			)
			(layer "F.Fab")
		)
		(fp_line
			(start -0.12065 -0.2794)
			(end 0.12065 -0.2794)
			(stroke
				(width 0.1)
				(type default)
			)
			(layer "F.Fab")
		)
		(fp_line
			(start -0.12065 0.2794)
			(end -0.12065 0.3048)
			(stroke
				(width 0.1)
				(type default)
			)
			(layer "F.Fab")
		)
		(fp_line
			(start -0.12065 0.3048)
			(end -0.67945 0.3048)
			(stroke
				(width 0.1)
				(type default)
			)
			(layer "F.Fab")
		)
		(fp_line
			(start 0.120396 0.2794)
			(end -0.12065 0.2794)
			(stroke
				(width 0.1)
				(type default)
			)
			(layer "F.Fab")
		)
		(fp_line
			(start 0.120396 0.3048)
			(end 0.120396 0.2794)
			(stroke
				(width 0.1)
				(type default)
			)
			(layer "F.Fab")
		)
		(fp_line
			(start 0.12065 -0.3048)
			(end 0.67945 -0.3048)
			(stroke
				(width 0.1)
				(type default)
			)
			(layer "F.Fab")
		)
		(fp_line
			(start 0.12065 -0.2794)
			(end 0.12065 -0.3048)
			(stroke
				(width 0.1)
				(type default)
			)
			(layer "F.Fab")
		)
		(fp_line
			(start 0.67945 -0.3048)
			(end 0.67945 0.3048)
			(stroke
				(width 0.1)
				(type default)
			)
			(layer "F.Fab")
		)
		(fp_line
			(start 0.67945 0.3048)
			(end 0.120396 0.3048)
			(stroke
				(width 0.1)
				(type default)
			)
			(layer "F.Fab")
		)
		(pad "1" smd circle
			(at -0.40005 0)
			(size 0 0)
			(layers "F.Cu" "F.Mask" "F.Paste")
			(net "P12V_OCP_SFF_ISENSE_TIC")
		)
		(pad "2" smd circle
			(at 0.40005 0)
			(size 0 0)
			(layers "F.Cu" "F.Mask" "F.Paste")
			(net "GND")
		)
	)
	(footprint ""
		(layer "F.Cu")
		(at 453.719946 -108.059728)
		(property "Reference" "R1905"
			(at 0 0 0)
			(layer "F.SilkS")
			(hide yes)
			(effects
				(font
					(size 1.27 1.27)
				)
			)
		)
		(property "Value" ""
			(at 0 0 0)
			(layer "F.Fab")
			(effects
				(font
					(size 1.27 1.27)
				)
			)
		)
		(duplicate_pad_numbers_are_jumpers no)
		(fp_line
			(start -0.7874 -0.4064)
			(end 0.7874 -0.4064)
			(stroke
				(width 0.1524)
				(type default)
			)
			(layer "F.SilkS")
		)
		(fp_line
			(start -0.7874 0.4064)
			(end -0.7874 -0.4064)
			(stroke
				(width 0.1524)
				(type default)
			)
			(layer "F.SilkS")
		)
		(fp_line
			(start 0.7874 -0.4064)
			(end 0.7874 0.4064)
			(stroke
				(width 0.1524)
				(type default)
			)
			(layer "F.SilkS")
		)
		(fp_line
			(start 0.7874 0.4064)
			(end -0.7874 0.4064)
			(stroke
				(width 0.1524)
				(type default)
			)
			(layer "F.SilkS")
		)
		(fp_line
			(start -0.67945 -0.305054)
			(end -0.12065 -0.305054)
			(stroke
				(width 0.1)
				(type default)
			)
			(layer "F.Fab")
		)
		(fp_line
			(start -0.67945 0.3048)
			(end -0.67945 -0.305054)
			(stroke
				(width 0.1)
				(type default)
			)
			(layer "F.Fab")
		)
		(fp_line
			(start -0.12065 -0.305054)
			(end -0.12065 -0.2794)
			(stroke
				(width 0.1)
				(type default)
			)
			(layer "F.Fab")
		)
		(fp_line
			(start -0.12065 -0.2794)
			(end 0.12065 -0.2794)
			(stroke
				(width 0.1)
				(type default)
			)
			(layer "F.Fab")
		)
		(fp_line
			(start -0.12065 0.2794)
			(end -0.12065 0.3048)
			(stroke
				(width 0.1)
				(type default)
			)
			(layer "F.Fab")
		)
		(fp_line
			(start -0.12065 0.3048)
			(end -0.67945 0.3048)
			(stroke
				(width 0.1)
				(type default)
			)
			(layer "F.Fab")
		)
		(fp_line
			(start 0.120396 0.2794)
			(end -0.12065 0.2794)
			(stroke
				(width 0.1)
				(type default)
			)
			(layer "F.Fab")
		)
		(fp_line
			(start 0.120396 0.3048)
			(end 0.120396 0.2794)
			(stroke
				(width 0.1)
				(type default)
			)
			(layer "F.Fab")
		)
		(fp_line
			(start 0.12065 -0.3048)
			(end 0.67945 -0.3048)
			(stroke
				(width 0.1)
				(type default)
			)
			(layer "F.Fab")
		)
		(fp_line
			(start 0.12065 -0.2794)
			(end 0.12065 -0.3048)
			(stroke
				(width 0.1)
				(type default)
			)
			(layer "F.Fab")
		)
		(fp_line
			(start 0.67945 -0.3048)
			(end 0.67945 0.3048)
			(stroke
				(width 0.1)
				(type default)
			)
			(layer "F.Fab")
		)
		(fp_line
			(start 0.67945 0.3048)
			(end 0.120396 0.3048)
			(stroke
				(width 0.1)
				(type default)
			)
			(layer "F.Fab")
		)
		(pad "1" smd circle
			(at -0.40005 0)
			(size 0 0)
			(layers "F.Cu" "F.Mask" "F.Paste")
			(net "P3V3_AUX")
		)
		(pad "2" smd circle
			(at 0.40005 0)
			(size 0 0)
			(layers "F.Cu" "F.Mask" "F.Paste")
			(net "OCP_SFF_PRSNT0_R_N")
		)
	)
	(footprint ""
		(layer "F.Cu")
		(at 7.42188 -54.955948)
		(property "Reference" "R2996"
			(at 0 0 0)
			(layer "F.SilkS")
			(hide yes)
			(effects
				(font
					(size 1.27 1.27)
				)
			)
		)
		(property "Value" ""
			(at 0 0 0)
			(layer "F.Fab")
			(effects
				(font
					(size 1.27 1.27)
				)
			)
		)
		(duplicate_pad_numbers_are_jumpers no)
		(fp_line
			(start -0.7874 -0.4064)
			(end 0.7874 -0.4064)
			(stroke
				(width 0.1524)
				(type default)
			)
			(layer "F.SilkS")
		)
		(fp_line
			(start -0.7874 0.4064)
			(end -0.7874 -0.4064)
			(stroke
				(width 0.1524)
				(type default)
			)
			(layer "F.SilkS")
		)
		(fp_line
			(start 0.7874 -0.4064)
			(end 0.7874 0.4064)
			(stroke
				(width 0.1524)
				(type default)
			)
			(layer "F.SilkS")
		)
		(fp_line
			(start 0.7874 0.4064)
			(end -0.7874 0.4064)
			(stroke
				(width 0.1524)
				(type default)
			)
			(layer "F.SilkS")
		)
		(fp_line
			(start -0.67945 -0.305054)
			(end -0.12065 -0.305054)
			(stroke
				(width 0.1)
				(type default)
			)
			(layer "F.Fab")
		)
		(fp_line
			(start -0.67945 0.3048)
			(end -0.67945 -0.305054)
			(stroke
				(width 0.1)
				(type default)
			)
			(layer "F.Fab")
		)
		(fp_line
			(start -0.12065 -0.305054)
			(end -0.12065 -0.2794)
			(stroke
				(width 0.1)
				(type default)
			)
			(layer "F.Fab")
		)
		(fp_line
			(start -0.12065 -0.2794)
			(end 0.12065 -0.2794)
			(stroke
				(width 0.1)
				(type default)
			)
			(layer "F.Fab")
		)
		(fp_line
			(start -0.12065 0.2794)
			(end -0.12065 0.3048)
			(stroke
				(width 0.1)
				(type default)
			)
			(layer "F.Fab")
		)
		(fp_line
			(start -0.12065 0.3048)
			(end -0.67945 0.3048)
			(stroke
				(width 0.1)
				(type default)
			)
			(layer "F.Fab")
		)
		(fp_line
			(start 0.120396 0.2794)
			(end -0.12065 0.2794)
			(stroke
				(width 0.1)
				(type default)
			)
			(layer "F.Fab")
		)
		(fp_line
			(start 0.120396 0.3048)
			(end 0.120396 0.2794)
			(stroke
				(width 0.1)
				(type default)
			)
			(layer "F.Fab")
		)
		(fp_line
			(start 0.12065 -0.3048)
			(end 0.67945 -0.3048)
			(stroke
				(width 0.1)
				(type default)
			)
			(layer "F.Fab")
		)
		(fp_line
			(start 0.12065 -0.2794)
			(end 0.12065 -0.3048)
			(stroke
				(width 0.1)
				(type default)
			)
			(layer "F.Fab")
		)
		(fp_line
			(start 0.67945 -0.3048)
			(end 0.67945 0.3048)
			(stroke
				(width 0.1)
				(type default)
			)
			(layer "F.Fab")
		)
		(fp_line
			(start 0.67945 0.3048)
			(end 0.120396 0.3048)
			(stroke
				(width 0.1)
				(type default)
			)
			(layer "F.Fab")
		)
		(pad "1" smd circle
			(at -0.40005 0)
			(size 0 0)
			(layers "F.Cu" "F.Mask" "F.Paste")
			(net "SMB_SML1_PMBUS_3V3AUX_PCH_SDA")
		)
		(pad "2" smd circle
			(at 0.40005 0)
			(size 0 0)
			(layers "F.Cu" "F.Mask" "F.Paste")
			(net "SMB_SML1_PMBUS_HSC_SDA_R3")
		)
	)
	(footprint ""
		(layer "F.Cu")
		(at 135.02894 -347.509846 -90)
		(property "Reference" "PC1362"
			(at 0 0 270)
			(layer "F.SilkS")
			(hide yes)
			(effects
				(font
					(size 1.27 1.27)
				)
			)
		)
		(property "Value" ""
			(at 0 0 270)
			(layer "F.Fab")
			(effects
				(font
					(size 1.27 1.27)
				)
			)
		)
		(duplicate_pad_numbers_are_jumpers no)
		(fp_line
			(start -0.7874 0.4064)
			(end -0.7874 -0.4064)
			(stroke
				(width 0.1524)
				(type default)
			)
			(layer "F.SilkS")
		)
		(fp_line
			(start 0.7874 0.4064)
			(end -0.7874 0.4064)
			(stroke
				(width 0.1524)
				(type default)
			)
			(layer "F.SilkS")
		)
		(fp_line
			(start -0.7874 -0.4064)
			(end 0.7874 -0.4064)
			(stroke
				(width 0.1524)
				(type default)
			)
			(layer "F.SilkS")
		)
		(fp_line
			(start 0.7874 -0.4064)
			(end 0.7874 0.4064)
			(stroke
				(width 0.1524)
				(type default)
			)
			(layer "F.SilkS")
		)
		(fp_line
			(start -0.67945 0.3048)
			(end -0.67945 -0.305054)
			(stroke
				(width 0.1)
				(type default)
			)
			(layer "F.Fab")
		)
		(fp_line
			(start -0.12065 0.3048)
			(end -0.67945 0.3048)
			(stroke
				(width 0.1)
				(type default)
			)
			(layer "F.Fab")
		)
		(fp_line
			(start 0.120396 0.3048)
			(end 0.120396 0.2794)
			(stroke
				(width 0.1)
				(type default)
			)
			(layer "F.Fab")
		)
		(fp_line
			(start 0.67945 0.3048)
			(end 0.120396 0.3048)
			(stroke
				(width 0.1)
				(type default)
			)
			(layer "F.Fab")
		)
		(fp_line
			(start -0.12065 0.2794)
			(end -0.12065 0.3048)
			(stroke
				(width 0.1)
				(type default)
			)
			(layer "F.Fab")
		)
		(fp_line
			(start 0.120396 0.2794)
			(end -0.12065 0.2794)
			(stroke
				(width 0.1)
				(type default)
			)
			(layer "F.Fab")
		)
		(fp_line
			(start -0.12065 -0.2794)
			(end 0.12065 -0.2794)
			(stroke
				(width 0.1)
				(type default)
			)
			(layer "F.Fab")
		)
		(fp_line
			(start 0.12065 -0.2794)
			(end 0.12065 -0.3048)
			(stroke
				(width 0.1)
				(type default)
			)
			(layer "F.Fab")
		)
		(fp_line
			(start 0.12065 -0.3048)
			(end 0.67945 -0.3048)
			(stroke
				(width 0.1)
				(type default)
			)
			(layer "F.Fab")
		)
		(fp_line
			(start 0.67945 -0.3048)
			(end 0.67945 0.3048)
			(stroke
				(width 0.1)
				(type default)
			)
			(layer "F.Fab")
		)
		(fp_line
			(start -0.67945 -0.305054)
			(end -0.12065 -0.305054)
			(stroke
				(width 0.1)
				(type default)
			)
			(layer "F.Fab")
		)
		(fp_line
			(start -0.12065 -0.305054)
			(end -0.12065 -0.2794)
			(stroke
				(width 0.1)
				(type default)
			)
			(layer "F.Fab")
		)
		(pad "1" smd circle
			(at -0.40005 0 270)
			(size 0 0)
			(layers "F.Cu" "F.Mask" "F.Paste")
			(net "GND")
		)
		(pad "2" smd circle
			(at 0.40005 0 270)
			(size 0 0)
			(layers "F.Cu" "F.Mask" "F.Paste")
			(net "PVCCIN_CPU1_VREF")
		)
	)
	(footprint ""
		(layer "F.Cu")
		(at 7.42188 -61.051948 180)
		(property "Reference" "R581"
			(at 0 0 180)
			(layer "F.SilkS")
			(hide yes)
			(effects
				(font
					(size 1.27 1.27)
				)
			)
		)
		(property "Value" ""
			(at 0 0 180)
			(layer "F.Fab")
			(effects
				(font
					(size 1.27 1.27)
				)
			)
		)
		(duplicate_pad_numbers_are_jumpers no)
		(fp_line
			(start 0.7874 0.4064)
			(end -0.7874 0.4064)
			(stroke
				(width 0.1524)
				(type default)
			)
			(layer "F.SilkS")
		)
		(fp_line
			(start 0.7874 -0.4064)
			(end 0.7874 0.4064)
			(stroke
				(width 0.1524)
				(type default)
			)
			(layer "F.SilkS")
		)
		(fp_line
			(start -0.7874 0.4064)
			(end -0.7874 -0.4064)
			(stroke
				(width 0.1524)
				(type default)
			)
			(layer "F.SilkS")
		)
		(fp_line
			(start -0.7874 -0.4064)
			(end 0.7874 -0.4064)
			(stroke
				(width 0.1524)
				(type default)
			)
			(layer "F.SilkS")
		)
		(fp_line
			(start 0.67945 0.3048)
			(end 0.120396 0.3048)
			(stroke
				(width 0.1)
				(type default)
			)
			(layer "F.Fab")
		)
		(fp_line
			(start 0.67945 -0.3048)
			(end 0.67945 0.3048)
			(stroke
				(width 0.1)
				(type default)
			)
			(layer "F.Fab")
		)
		(fp_line
			(start 0.12065 -0.2794)
			(end 0.12065 -0.3048)
			(stroke
				(width 0.1)
				(type default)
			)
			(layer "F.Fab")
		)
		(fp_line
			(start 0.12065 -0.3048)
			(end 0.67945 -0.3048)
			(stroke
				(width 0.1)
				(type default)
			)
			(layer "F.Fab")
		)
		(fp_line
			(start 0.120396 0.3048)
			(end 0.120396 0.2794)
			(stroke
				(width 0.1)
				(type default)
			)
			(layer "F.Fab")
		)
		(fp_line
			(start 0.120396 0.2794)
			(end -0.12065 0.2794)
			(stroke
				(width 0.1)
				(type default)
			)
			(layer "F.Fab")
		)
		(fp_line
			(start -0.12065 0.3048)
			(end -0.67945 0.3048)
			(stroke
				(width 0.1)
				(type default)
			)
			(layer "F.Fab")
		)
		(fp_line
			(start -0.12065 0.2794)
			(end -0.12065 0.3048)
			(stroke
				(width 0.1)
				(type default)
			)
			(layer "F.Fab")
		)
		(fp_line
			(start -0.12065 -0.2794)
			(end 0.12065 -0.2794)
			(stroke
				(width 0.1)
				(type default)
			)
			(layer "F.Fab")
		)
		(fp_line
			(start -0.12065 -0.305054)
			(end -0.12065 -0.2794)
			(stroke
				(width 0.1)
				(type default)
			)
			(layer "F.Fab")
		)
		(fp_line
			(start -0.67945 0.3048)
			(end -0.67945 -0.305054)
			(stroke
				(width 0.1)
				(type default)
			)
			(layer "F.Fab")
		)
		(fp_line
			(start -0.67945 -0.305054)
			(end -0.12065 -0.305054)
			(stroke
				(width 0.1)
				(type default)
			)
			(layer "F.Fab")
		)
		(pad "1" smd circle
			(at -0.40005 0 180)
			(size 0 0)
			(layers "F.Cu" "F.Mask" "F.Paste")
			(net "SMB_SML0_3V3AUX_SCL")
		)
		(pad "2" smd circle
			(at 0.40005 0 180)
			(size 0 0)
			(layers "F.Cu" "F.Mask" "F.Paste")
			(net "SMB_SML0_3V3AUX_PCH_SCL")
		)
	)
	(footprint ""
		(layer "F.Cu")
		(at 58.058558 -402.371052 -90)
		(property "Reference" "C717"
			(at 0 0 270)
			(layer "F.SilkS")
			(hide yes)
			(effects
				(font
					(size 1.27 1.27)
				)
			)
		)
		(property "Value" ""
			(at 0 0 270)
			(layer "F.Fab")
			(effects
				(font
					(size 1.27 1.27)
				)
			)
		)
		(duplicate_pad_numbers_are_jumpers no)
		(fp_line
			(start -0.299974 0.150114)
			(end -0.299974 -0.150114)
			(stroke
				(width 0.1)
				(type default)
			)
			(layer "F.Fab")
		)
		(fp_line
			(start 0.299974 0.150114)
			(end -0.299974 0.150114)
			(stroke
				(width 0.1)
				(type default)
			)
			(layer "F.Fab")
		)
		(fp_line
			(start -0.299974 -0.150114)
			(end 0.299974 -0.150114)
			(stroke
				(width 0.1)
				(type default)
			)
			(layer "F.Fab")
		)
		(fp_line
			(start 0.299974 -0.150114)
			(end 0.299974 0.150114)
			(stroke
				(width 0.1)
				(type default)
			)
			(layer "F.Fab")
		)
		(pad "1" smd rect
			(at -0.2667 0 270)
			(size 0.3048 0.381)
			(layers "F.Cu" "F.Mask" "F.Paste")
			(net "P5E_CPU1_PE0_TX_C_DP<12>")
		)
		(pad "2" smd rect
			(at 0.2667 0 270)
			(size 0.3048 0.381)
			(layers "F.Cu" "F.Mask" "F.Paste")
			(net "P5E_CPU1_PE0_TX_DP<12>")
		)
	)
	(footprint ""
		(layer "F.Cu")
		(at 105.306114 -260.36524 -90)
		(property "Reference" "C437"
			(at 0 0 270)
			(layer "F.SilkS")
			(hide yes)
			(effects
				(font
					(size 1.27 1.27)
				)
			)
		)
		(property "Value" ""
			(at 0 0 270)
			(layer "F.Fab")
			(effects
				(font
					(size 1.27 1.27)
				)
			)
		)
		(duplicate_pad_numbers_are_jumpers no)
		(fp_line
			(start -0.7874 0.4064)
			(end -0.7874 -0.4064)
			(stroke
				(width 0.1524)
				(type default)
			)
			(layer "F.SilkS")
		)
		(fp_line
			(start 0.7874 0.4064)
			(end -0.7874 0.4064)
			(stroke
				(width 0.1524)
				(type default)
			)
			(layer "F.SilkS")
		)
		(fp_line
			(start -0.7874 -0.4064)
			(end 0.7874 -0.4064)
			(stroke
				(width 0.1524)
				(type default)
			)
			(layer "F.SilkS")
		)
		(fp_line
			(start 0.7874 -0.4064)
			(end 0.7874 0.4064)
			(stroke
				(width 0.1524)
				(type default)
			)
			(layer "F.SilkS")
		)
		(fp_line
			(start -0.67945 0.3048)
			(end -0.67945 -0.305054)
			(stroke
				(width 0.1)
				(type default)
			)
			(layer "F.Fab")
		)
		(fp_line
			(start -0.12065 0.3048)
			(end -0.67945 0.3048)
			(stroke
				(width 0.1)
				(type default)
			)
			(layer "F.Fab")
		)
		(fp_line
			(start 0.120396 0.3048)
			(end 0.120396 0.2794)
			(stroke
				(width 0.1)
				(type default)
			)
			(layer "F.Fab")
		)
		(fp_line
			(start 0.67945 0.3048)
			(end 0.120396 0.3048)
			(stroke
				(width 0.1)
				(type default)
			)
			(layer "F.Fab")
		)
		(fp_line
			(start -0.12065 0.2794)
			(end -0.12065 0.3048)
			(stroke
				(width 0.1)
				(type default)
			)
			(layer "F.Fab")
		)
		(fp_line
			(start 0.120396 0.2794)
			(end -0.12065 0.2794)
			(stroke
				(width 0.1)
				(type default)
			)
			(layer "F.Fab")
		)
		(fp_line
			(start -0.12065 -0.2794)
			(end 0.12065 -0.2794)
			(stroke
				(width 0.1)
				(type default)
			)
			(layer "F.Fab")
		)
		(fp_line
			(start 0.12065 -0.2794)
			(end 0.12065 -0.3048)
			(stroke
				(width 0.1)
				(type default)
			)
			(layer "F.Fab")
		)
		(fp_line
			(start 0.12065 -0.3048)
			(end 0.67945 -0.3048)
			(stroke
				(width 0.1)
				(type default)
			)
			(layer "F.Fab")
		)
		(fp_line
			(start 0.67945 -0.3048)
			(end 0.67945 0.3048)
			(stroke
				(width 0.1)
				(type default)
			)
			(layer "F.Fab")
		)
		(fp_line
			(start -0.67945 -0.305054)
			(end -0.12065 -0.305054)
			(stroke
				(width 0.1)
				(type default)
			)
			(layer "F.Fab")
		)
		(fp_line
			(start -0.12065 -0.305054)
			(end -0.12065 -0.2794)
			(stroke
				(width 0.1)
				(type default)
			)
			(layer "F.Fab")
		)
		(pad "1" smd circle
			(at -0.40005 0 270)
			(size 0 0)
			(layers "F.Cu" "F.Mask" "F.Paste")
			(net "PVCCFA_EHV_FIVRA_CPU1")
		)
		(pad "2" smd circle
			(at 0.40005 0 270)
			(size 0 0)
			(layers "F.Cu" "F.Mask" "F.Paste")
			(net "GND")
		)
	)
	(footprint ""
		(layer "F.Cu")
		(at 31.307278 -138.01979 90)
		(property "Reference" "PR4243"
			(at 0 0 90)
			(layer "F.SilkS")
			(hide yes)
			(effects
				(font
					(size 1.27 1.27)
				)
			)
		)
		(property "Value" ""
			(at 0 0 90)
			(layer "F.Fab")
			(effects
				(font
					(size 1.27 1.27)
				)
			)
		)
		(duplicate_pad_numbers_are_jumpers no)
		(fp_line
			(start 0.7874 -0.4064)
			(end 0.7874 0.4064)
			(stroke
				(width 0.1524)
				(type default)
			)
			(layer "F.SilkS")
		)
		(fp_line
			(start -0.7874 -0.4064)
			(end 0.7874 -0.4064)
			(stroke
				(width 0.1524)
				(type default)
			)
			(layer "F.SilkS")
		)
		(fp_line
			(start 0.7874 0.4064)
			(end -0.7874 0.4064)
			(stroke
				(width 0.1524)
				(type default)
			)
			(layer "F.SilkS")
		)
		(fp_line
			(start -0.7874 0.4064)
			(end -0.7874 -0.4064)
			(stroke
				(width 0.1524)
				(type default)
			)
			(layer "F.SilkS")
		)
		(fp_line
			(start -0.12065 -0.305054)
			(end -0.12065 -0.2794)
			(stroke
				(width 0.1)
				(type default)
			)
			(layer "F.Fab")
		)
		(fp_line
			(start -0.67945 -0.305054)
			(end -0.12065 -0.305054)
			(stroke
				(width 0.1)
				(type default)
			)
			(layer "F.Fab")
		)
		(fp_line
			(start 0.67945 -0.3048)
			(end 0.67945 0.3048)
			(stroke
				(width 0.1)
				(type default)
			)
			(layer "F.Fab")
		)
		(fp_line
			(start 0.12065 -0.3048)
			(end 0.67945 -0.3048)
			(stroke
				(width 0.1)
				(type default)
			)
			(layer "F.Fab")
		)
		(fp_line
			(start 0.12065 -0.2794)
			(end 0.12065 -0.3048)
			(stroke
				(width 0.1)
				(type default)
			)
			(layer "F.Fab")
		)
		(fp_line
			(start -0.12065 -0.2794)
			(end 0.12065 -0.2794)
			(stroke
				(width 0.1)
				(type default)
			)
			(layer "F.Fab")
		)
		(fp_line
			(start 0.120396 0.2794)
			(end -0.12065 0.2794)
			(stroke
				(width 0.1)
				(type default)
			)
			(layer "F.Fab")
		)
		(fp_line
			(start -0.12065 0.2794)
			(end -0.12065 0.3048)
			(stroke
				(width 0.1)
				(type default)
			)
			(layer "F.Fab")
		)
		(fp_line
			(start 0.67945 0.3048)
			(end 0.120396 0.3048)
			(stroke
				(width 0.1)
				(type default)
			)
			(layer "F.Fab")
		)
		(fp_line
			(start 0.120396 0.3048)
			(end 0.120396 0.2794)
			(stroke
				(width 0.1)
				(type default)
			)
			(layer "F.Fab")
		)
		(fp_line
			(start -0.12065 0.3048)
			(end -0.67945 0.3048)
			(stroke
				(width 0.1)
				(type default)
			)
			(layer "F.Fab")
		)
		(fp_line
			(start -0.67945 0.3048)
			(end -0.67945 -0.305054)
			(stroke
				(width 0.1)
				(type default)
			)
			(layer "F.Fab")
		)
		(pad "1" smd circle
			(at -0.40005 0 90)
			(size 0 0)
			(layers "F.Cu" "F.Mask" "F.Paste")
			(net "NC_PVCCINFAON_CPU1_ACSP4")
		)
		(pad "2" smd circle
			(at 0.40005 0 90)
			(size 0 0)
			(layers "F.Cu" "F.Mask" "F.Paste")
			(net "GND")
		)
	)
	(footprint ""
		(layer "F.Cu")
		(at 344.764106 -389.052816)
		(property "Reference" "ME18"
			(at 0 0 0)
			(layer "F.SilkS")
			(hide yes)
			(effects
				(font
					(size 1.27 1.27)
				)
			)
		)
		(property "Value" ""
			(at 0 0 0)
			(layer "F.Fab")
			(effects
				(font
					(size 1.27 1.27)
				)
			)
		)
		(duplicate_pad_numbers_are_jumpers no)
		(fp_rect
			(start 0 0)
			(end 3.3401 -0.5842)
			(stroke
				(width 0)
				(type default)
			)
			(fill yes)
			(layer "F.SilkS")
		)
		(fp_rect
			(start 1.32715 -3.2512)
			(end 2.01295 -3.4417)
			(stroke
				(width 0)
				(type default)
			)
			(fill yes)
			(layer "F.SilkS")
		)
		(fp_poly
			(pts
				(xy 0.92075 -1.1557) (xy 0.888492 -1.51384) (xy 0.094488 -0.693928) (xy -0.070612 -0.681228) (xy -0.197612 -0.820928)
				(xy 0.852678 -1.91262) (xy 0.728472 -3.29184) (xy -0.248412 -4.300728) (xy -0.184912 -4.478528)
				(xy -0.007112 -4.503928) (xy 0.684022 -3.785616) (xy 0.65659 -4.0894) (xy 0.97155 -4.3434) (xy 1.22555 -4.3561)
				(xy 1.46685 -4.4704) (xy 2.01295 -4.4704) (xy 2.15265 -4.4069) (xy 2.44475 -4.191) (xy 2.49555 -4.191)
				(xy 2.59715 -4.2926) (xy 2.80035 -4.2672) (xy 2.88925 -4.1656) (xy 2.88925 -4.029456) (xy 3.345688 -4.503928)
				(xy 3.523488 -4.478528) (xy 3.586988 -4.300728) (xy 2.88925 -3.58013) (xy 2.88925 -3.3147) (xy 2.82575 -3.2385)
				(xy 2.67335 -3.2385) (xy 2.521966 -1.875282) (xy 2.545842 -1.85039)
				(arc
					(start 2.55905 -1.8415)
					(mid 2.648099 -1.766068)
					(end 2.717292 -1.672082)
				)
				(xy 3.536188 -0.820928) (xy 3.409188 -0.681228) (xy 3.244088 -0.693928)
				(arc
					(start 2.737612 -1.216914)
					(mid 2.31728 -0.925553)
					(end 1.86055 -1.1557)
				)
			)
			(stroke
				(width 0)
				(type default)
			)
			(fill yes)
			(layer "F.SilkS")
		)
	)
	(footprint ""
		(layer "F.Cu")
		(at 328.460608 -402.371052 -90)
		(property "Reference" "C1794"
			(at 0 0 270)
			(layer "F.SilkS")
			(hide yes)
			(effects
				(font
					(size 1.27 1.27)
				)
			)
		)
		(property "Value" ""
			(at 0 0 270)
			(layer "F.Fab")
			(effects
				(font
					(size 1.27 1.27)
				)
			)
		)
		(duplicate_pad_numbers_are_jumpers no)
		(fp_line
			(start -0.299974 0.150114)
			(end -0.299974 -0.150114)
			(stroke
				(width 0.1)
				(type default)
			)
			(layer "F.Fab")
		)
		(fp_line
			(start 0.299974 0.150114)
			(end -0.299974 0.150114)
			(stroke
				(width 0.1)
				(type default)
			)
			(layer "F.Fab")
		)
		(fp_line
			(start -0.299974 -0.150114)
			(end 0.299974 -0.150114)
			(stroke
				(width 0.1)
				(type default)
			)
			(layer "F.Fab")
		)
		(fp_line
			(start 0.299974 -0.150114)
			(end 0.299974 0.150114)
			(stroke
				(width 0.1)
				(type default)
			)
			(layer "F.Fab")
		)
		(pad "1" smd rect
			(at -0.2667 0 270)
			(size 0.3048 0.381)
			(layers "F.Cu" "F.Mask" "F.Paste")
			(net "P5E_CPU0_PE4_TX_C_DN<8>")
		)
		(pad "2" smd rect
			(at 0.2667 0 270)
			(size 0.3048 0.381)
			(layers "F.Cu" "F.Mask" "F.Paste")
			(net "P5E_CPU0_PE4_TX_DN<8>")
		)
	)
	(footprint ""
		(layer "F.Cu")
		(at 336.779108 -16.219678 -90)
		(property "Reference" "C607"
			(at 0 0 270)
			(layer "F.SilkS")
			(hide yes)
			(effects
				(font
					(size 1.27 1.27)
				)
			)
		)
		(property "Value" ""
			(at 0 0 270)
			(layer "F.Fab")
			(effects
				(font
					(size 1.27 1.27)
				)
			)
		)
		(duplicate_pad_numbers_are_jumpers no)
		(fp_line
			(start -0.7874 0.4064)
			(end -0.7874 -0.4064)
			(stroke
				(width 0.1524)
				(type default)
			)
			(layer "F.SilkS")
		)
		(fp_line
			(start 0.7874 0.4064)
			(end -0.7874 0.4064)
			(stroke
				(width 0.1524)
				(type default)
			)
			(layer "F.SilkS")
		)
		(fp_line
			(start -0.7874 -0.4064)
			(end 0.7874 -0.4064)
			(stroke
				(width 0.1524)
				(type default)
			)
			(layer "F.SilkS")
		)
		(fp_line
			(start 0.7874 -0.4064)
			(end 0.7874 0.4064)
			(stroke
				(width 0.1524)
				(type default)
			)
			(layer "F.SilkS")
		)
		(fp_line
			(start -0.67945 0.3048)
			(end -0.67945 -0.305054)
			(stroke
				(width 0.1)
				(type default)
			)
			(layer "F.Fab")
		)
		(fp_line
			(start -0.12065 0.3048)
			(end -0.67945 0.3048)
			(stroke
				(width 0.1)
				(type default)
			)
			(layer "F.Fab")
		)
		(fp_line
			(start 0.120396 0.3048)
			(end 0.120396 0.2794)
			(stroke
				(width 0.1)
				(type default)
			)
			(layer "F.Fab")
		)
		(fp_line
			(start 0.67945 0.3048)
			(end 0.120396 0.3048)
			(stroke
				(width 0.1)
				(type default)
			)
			(layer "F.Fab")
		)
		(fp_line
			(start -0.12065 0.2794)
			(end -0.12065 0.3048)
			(stroke
				(width 0.1)
				(type default)
			)
			(layer "F.Fab")
		)
		(fp_line
			(start 0.120396 0.2794)
			(end -0.12065 0.2794)
			(stroke
				(width 0.1)
				(type default)
			)
			(layer "F.Fab")
		)
		(fp_line
			(start -0.12065 -0.2794)
			(end 0.12065 -0.2794)
			(stroke
				(width 0.1)
				(type default)
			)
			(layer "F.Fab")
		)
		(fp_line
			(start 0.12065 -0.2794)
			(end 0.12065 -0.3048)
			(stroke
				(width 0.1)
				(type default)
			)
			(layer "F.Fab")
		)
		(fp_line
			(start 0.12065 -0.3048)
			(end 0.67945 -0.3048)
			(stroke
				(width 0.1)
				(type default)
			)
			(layer "F.Fab")
		)
		(fp_line
			(start 0.67945 -0.3048)
			(end 0.67945 0.3048)
			(stroke
				(width 0.1)
				(type default)
			)
			(layer "F.Fab")
		)
		(fp_line
			(start -0.67945 -0.305054)
			(end -0.12065 -0.305054)
			(stroke
				(width 0.1)
				(type default)
			)
			(layer "F.Fab")
		)
		(fp_line
			(start -0.12065 -0.305054)
			(end -0.12065 -0.2794)
			(stroke
				(width 0.1)
				(type default)
			)
			(layer "F.Fab")
		)
		(pad "1" smd circle
			(at -0.40005 0 270)
			(size 0 0)
			(layers "F.Cu" "F.Mask" "F.Paste")
			(net "PGPPA_AUX")
		)
		(pad "2" smd circle
			(at 0.40005 0 270)
			(size 0 0)
			(layers "F.Cu" "F.Mask" "F.Paste")
			(net "GND")
		)
	)
	(footprint ""
		(layer "F.Cu")
		(at 224.2312 -49.71288 180)
		(property "Reference" "R4083"
			(at 0 0 180)
			(layer "F.SilkS")
			(hide yes)
			(effects
				(font
					(size 1.27 1.27)
				)
			)
		)
		(property "Value" ""
			(at 0 0 180)
			(layer "F.Fab")
			(effects
				(font
					(size 1.27 1.27)
				)
			)
		)
		(duplicate_pad_numbers_are_jumpers no)
		(fp_line
			(start 0.7874 0.4064)
			(end -0.7874 0.4064)
			(stroke
				(width 0.1524)
				(type default)
			)
			(layer "F.SilkS")
		)
		(fp_line
			(start 0.7874 -0.4064)
			(end 0.7874 0.4064)
			(stroke
				(width 0.1524)
				(type default)
			)
			(layer "F.SilkS")
		)
		(fp_line
			(start -0.7874 0.4064)
			(end -0.7874 -0.4064)
			(stroke
				(width 0.1524)
				(type default)
			)
			(layer "F.SilkS")
		)
		(fp_line
			(start -0.7874 -0.4064)
			(end 0.7874 -0.4064)
			(stroke
				(width 0.1524)
				(type default)
			)
			(layer "F.SilkS")
		)
		(fp_line
			(start 0.67945 0.3048)
			(end 0.120396 0.3048)
			(stroke
				(width 0.1)
				(type default)
			)
			(layer "F.Fab")
		)
		(fp_line
			(start 0.67945 -0.3048)
			(end 0.67945 0.3048)
			(stroke
				(width 0.1)
				(type default)
			)
			(layer "F.Fab")
		)
		(fp_line
			(start 0.12065 -0.2794)
			(end 0.12065 -0.3048)
			(stroke
				(width 0.1)
				(type default)
			)
			(layer "F.Fab")
		)
		(fp_line
			(start 0.12065 -0.3048)
			(end 0.67945 -0.3048)
			(stroke
				(width 0.1)
				(type default)
			)
			(layer "F.Fab")
		)
		(fp_line
			(start 0.120396 0.3048)
			(end 0.120396 0.2794)
			(stroke
				(width 0.1)
				(type default)
			)
			(layer "F.Fab")
		)
		(fp_line
			(start 0.120396 0.2794)
			(end -0.12065 0.2794)
			(stroke
				(width 0.1)
				(type default)
			)
			(layer "F.Fab")
		)
		(fp_line
			(start -0.12065 0.3048)
			(end -0.67945 0.3048)
			(stroke
				(width 0.1)
				(type default)
			)
			(layer "F.Fab")
		)
		(fp_line
			(start -0.12065 0.2794)
			(end -0.12065 0.3048)
			(stroke
				(width 0.1)
				(type default)
			)
			(layer "F.Fab")
		)
		(fp_line
			(start -0.12065 -0.2794)
			(end 0.12065 -0.2794)
			(stroke
				(width 0.1)
				(type default)
			)
			(layer "F.Fab")
		)
		(fp_line
			(start -0.12065 -0.305054)
			(end -0.12065 -0.2794)
			(stroke
				(width 0.1)
				(type default)
			)
			(layer "F.Fab")
		)
		(fp_line
			(start -0.67945 0.3048)
			(end -0.67945 -0.305054)
			(stroke
				(width 0.1)
				(type default)
			)
			(layer "F.Fab")
		)
		(fp_line
			(start -0.67945 -0.305054)
			(end -0.12065 -0.305054)
			(stroke
				(width 0.1)
				(type default)
			)
			(layer "F.Fab")
		)
		(pad "1" smd circle
			(at -0.40005 0 180)
			(size 0 0)
			(layers "F.Cu" "F.Mask" "F.Paste")
			(net "E1S_0_PERST1_CLKREQ_N")
		)
		(pad "2" smd circle
			(at 0.40005 0 180)
			(size 0 0)
			(layers "F.Cu" "F.Mask" "F.Paste")
			(net "E1S_0_CLKREQ_N")
		)
	)
	(footprint ""
		(layer "F.Cu")
		(at 36.801298 -182.28564)
		(property "Reference" "PC1207"
			(at 0 0 0)
			(layer "F.SilkS")
			(hide yes)
			(effects
				(font
					(size 1.27 1.27)
				)
			)
		)
		(property "Value" ""
			(at 0 0 0)
			(layer "F.Fab")
			(effects
				(font
					(size 1.27 1.27)
				)
			)
		)
		(duplicate_pad_numbers_are_jumpers no)
		(fp_line
			(start -1.524 -0.762)
			(end 1.524 -0.762)
			(stroke
				(width 0.1524)
				(type default)
			)
			(layer "F.SilkS")
		)
		(fp_line
			(start -1.524 0.762)
			(end -1.524 -0.762)
			(stroke
				(width 0.1524)
				(type default)
			)
			(layer "F.SilkS")
		)
		(fp_line
			(start 1.524 -0.762)
			(end 1.524 0.762)
			(stroke
				(width 0.1524)
				(type default)
			)
			(layer "F.SilkS")
		)
		(fp_line
			(start 1.524 0.762)
			(end -1.524 0.762)
			(stroke
				(width 0.1524)
				(type default)
			)
			(layer "F.SilkS")
		)
		(fp_line
			(start -1.1049 -0.724916)
			(end -1.1049 0.724916)
			(stroke
				(width 0.1)
				(type default)
			)
			(layer "F.Fab")
		)
		(fp_line
			(start -1.1049 0.724916)
			(end 1.1049 0.724916)
			(stroke
				(width 0.1)
				(type default)
			)
			(layer "F.Fab")
		)
		(fp_line
			(start 1.1049 -0.724916)
			(end -1.1049 -0.724916)
			(stroke
				(width 0.1)
				(type default)
			)
			(layer "F.Fab")
		)
		(fp_line
			(start 1.1049 0.724916)
			(end 1.1049 -0.724916)
			(stroke
				(width 0.1)
				(type default)
			)
			(layer "F.Fab")
		)
		(pad "1" smd rect
			(at -0.889 0 180)
			(size 1.016 1.27)
			(layers "F.Cu" "F.Mask" "F.Paste")
			(net "PVNN_MAIN_CPU1")
		)
		(pad "2" smd rect
			(at 0.889 0 180)
			(size 1.016 1.27)
			(layers "F.Cu" "F.Mask" "F.Paste")
			(net "GND")
		)
	)
	(footprint ""
		(layer "F.Cu")
		(at 292.357302 -362.843826 -90)
		(property "Reference" "PC1176_P0_4"
			(at 0 0 270)
			(layer "F.SilkS")
			(hide yes)
			(effects
				(font
					(size 1.27 1.27)
				)
			)
		)
		(property "Value" ""
			(at 0 0 270)
			(layer "F.Fab")
			(effects
				(font
					(size 1.27 1.27)
				)
			)
		)
		(duplicate_pad_numbers_are_jumpers no)
		(fp_line
			(start -0.7874 0.4064)
			(end -0.7874 -0.4064)
			(stroke
				(width 0.1524)
				(type default)
			)
			(layer "F.SilkS")
		)
		(fp_line
			(start 0.7874 0.4064)
			(end -0.7874 0.4064)
			(stroke
				(width 0.1524)
				(type default)
			)
			(layer "F.SilkS")
		)
		(fp_line
			(start -0.7874 -0.4064)
			(end 0.7874 -0.4064)
			(stroke
				(width 0.1524)
				(type default)
			)
			(layer "F.SilkS")
		)
		(fp_line
			(start 0.7874 -0.4064)
			(end 0.7874 0.4064)
			(stroke
				(width 0.1524)
				(type default)
			)
			(layer "F.SilkS")
		)
		(fp_line
			(start -0.67945 0.3048)
			(end -0.67945 -0.305054)
			(stroke
				(width 0.1)
				(type default)
			)
			(layer "F.Fab")
		)
		(fp_line
			(start -0.12065 0.3048)
			(end -0.67945 0.3048)
			(stroke
				(width 0.1)
				(type default)
			)
			(layer "F.Fab")
		)
		(fp_line
			(start 0.120396 0.3048)
			(end 0.120396 0.2794)
			(stroke
				(width 0.1)
				(type default)
			)
			(layer "F.Fab")
		)
		(fp_line
			(start 0.67945 0.3048)
			(end 0.120396 0.3048)
			(stroke
				(width 0.1)
				(type default)
			)
			(layer "F.Fab")
		)
		(fp_line
			(start -0.12065 0.2794)
			(end -0.12065 0.3048)
			(stroke
				(width 0.1)
				(type default)
			)
			(layer "F.Fab")
		)
		(fp_line
			(start 0.120396 0.2794)
			(end -0.12065 0.2794)
			(stroke
				(width 0.1)
				(type default)
			)
			(layer "F.Fab")
		)
		(fp_line
			(start -0.12065 -0.2794)
			(end 0.12065 -0.2794)
			(stroke
				(width 0.1)
				(type default)
			)
			(layer "F.Fab")
		)
		(fp_line
			(start 0.12065 -0.2794)
			(end 0.12065 -0.3048)
			(stroke
				(width 0.1)
				(type default)
			)
			(layer "F.Fab")
		)
		(fp_line
			(start 0.12065 -0.3048)
			(end 0.67945 -0.3048)
			(stroke
				(width 0.1)
				(type default)
			)
			(layer "F.Fab")
		)
		(fp_line
			(start 0.67945 -0.3048)
			(end 0.67945 0.3048)
			(stroke
				(width 0.1)
				(type default)
			)
			(layer "F.Fab")
		)
		(fp_line
			(start -0.67945 -0.305054)
			(end -0.12065 -0.305054)
			(stroke
				(width 0.1)
				(type default)
			)
			(layer "F.Fab")
		)
		(fp_line
			(start -0.12065 -0.305054)
			(end -0.12065 -0.2794)
			(stroke
				(width 0.1)
				(type default)
			)
			(layer "F.Fab")
		)
		(pad "1" smd circle
			(at -0.40005 0 270)
			(size 0 0)
			(layers "F.Cu" "F.Mask" "F.Paste")
			(net "SW_P12V_PVCCFA_EHV_FIVRA_CPU0_L")
		)
		(pad "2" smd circle
			(at 0.40005 0 270)
			(size 0 0)
			(layers "F.Cu" "F.Mask" "F.Paste")
			(net "GND")
		)
	)
	(footprint ""
		(layer "F.Cu")
		(at 335.48574 -342.270334)
		(property "Reference" "PR138"
			(at 0 0 0)
			(layer "F.SilkS")
			(hide yes)
			(effects
				(font
					(size 1.27 1.27)
				)
			)
		)
		(property "Value" ""
			(at 0 0 0)
			(layer "F.Fab")
			(effects
				(font
					(size 1.27 1.27)
				)
			)
		)
		(duplicate_pad_numbers_are_jumpers no)
		(fp_line
			(start -0.7874 -0.4064)
			(end 0.7874 -0.4064)
			(stroke
				(width 0.1524)
				(type default)
			)
			(layer "F.SilkS")
		)
		(fp_line
			(start -0.7874 0.4064)
			(end -0.7874 -0.4064)
			(stroke
				(width 0.1524)
				(type default)
			)
			(layer "F.SilkS")
		)
		(fp_line
			(start 0.7874 -0.4064)
			(end 0.7874 0.4064)
			(stroke
				(width 0.1524)
				(type default)
			)
			(layer "F.SilkS")
		)
		(fp_line
			(start 0.7874 0.4064)
			(end -0.7874 0.4064)
			(stroke
				(width 0.1524)
				(type default)
			)
			(layer "F.SilkS")
		)
		(fp_line
			(start -0.67945 -0.305054)
			(end -0.12065 -0.305054)
			(stroke
				(width 0.1)
				(type default)
			)
			(layer "F.Fab")
		)
		(fp_line
			(start -0.67945 0.3048)
			(end -0.67945 -0.305054)
			(stroke
				(width 0.1)
				(type default)
			)
			(layer "F.Fab")
		)
		(fp_line
			(start -0.12065 -0.305054)
			(end -0.12065 -0.2794)
			(stroke
				(width 0.1)
				(type default)
			)
			(layer "F.Fab")
		)
		(fp_line
			(start -0.12065 -0.2794)
			(end 0.12065 -0.2794)
			(stroke
				(width 0.1)
				(type default)
			)
			(layer "F.Fab")
		)
		(fp_line
			(start -0.12065 0.2794)
			(end -0.12065 0.3048)
			(stroke
				(width 0.1)
				(type default)
			)
			(layer "F.Fab")
		)
		(fp_line
			(start -0.12065 0.3048)
			(end -0.67945 0.3048)
			(stroke
				(width 0.1)
				(type default)
			)
			(layer "F.Fab")
		)
		(fp_line
			(start 0.120396 0.2794)
			(end -0.12065 0.2794)
			(stroke
				(width 0.1)
				(type default)
			)
			(layer "F.Fab")
		)
		(fp_line
			(start 0.120396 0.3048)
			(end 0.120396 0.2794)
			(stroke
				(width 0.1)
				(type default)
			)
			(layer "F.Fab")
		)
		(fp_line
			(start 0.12065 -0.3048)
			(end 0.67945 -0.3048)
			(stroke
				(width 0.1)
				(type default)
			)
			(layer "F.Fab")
		)
		(fp_line
			(start 0.12065 -0.2794)
			(end 0.12065 -0.3048)
			(stroke
				(width 0.1)
				(type default)
			)
			(layer "F.Fab")
		)
		(fp_line
			(start 0.67945 -0.3048)
			(end 0.67945 0.3048)
			(stroke
				(width 0.1)
				(type default)
			)
			(layer "F.Fab")
		)
		(fp_line
			(start 0.67945 0.3048)
			(end 0.120396 0.3048)
			(stroke
				(width 0.1)
				(type default)
			)
			(layer "F.Fab")
		)
		(pad "1" smd circle
			(at -0.40005 0)
			(size 0 0)
			(layers "F.Cu" "F.Mask" "F.Paste")
			(net "PVCCIN_CPU0_LSET6")
		)
		(pad "2" smd circle
			(at 0.40005 0)
			(size 0 0)
			(layers "F.Cu" "F.Mask" "F.Paste")
			(net "GND")
		)
	)
	(footprint ""
		(layer "F.Cu")
		(at 353.235514 -255.053846 90)
		(property "Reference" "C986"
			(at 0 0 90)
			(layer "F.SilkS")
			(hide yes)
			(effects
				(font
					(size 1.27 1.27)
				)
			)
		)
		(property "Value" ""
			(at 0 0 90)
			(layer "F.Fab")
			(effects
				(font
					(size 1.27 1.27)
				)
			)
		)
		(duplicate_pad_numbers_are_jumpers no)
		(fp_line
			(start 0.7874 -0.4064)
			(end 0.7874 0.4064)
			(stroke
				(width 0.1524)
				(type default)
			)
			(layer "F.SilkS")
		)
		(fp_line
			(start -0.7874 -0.4064)
			(end 0.7874 -0.4064)
			(stroke
				(width 0.1524)
				(type default)
			)
			(layer "F.SilkS")
		)
		(fp_line
			(start 0.7874 0.4064)
			(end -0.7874 0.4064)
			(stroke
				(width 0.1524)
				(type default)
			)
			(layer "F.SilkS")
		)
		(fp_line
			(start -0.7874 0.4064)
			(end -0.7874 -0.4064)
			(stroke
				(width 0.1524)
				(type default)
			)
			(layer "F.SilkS")
		)
		(fp_line
			(start -0.12065 -0.305054)
			(end -0.12065 -0.2794)
			(stroke
				(width 0.1)
				(type default)
			)
			(layer "F.Fab")
		)
		(fp_line
			(start -0.67945 -0.305054)
			(end -0.12065 -0.305054)
			(stroke
				(width 0.1)
				(type default)
			)
			(layer "F.Fab")
		)
		(fp_line
			(start 0.67945 -0.3048)
			(end 0.67945 0.3048)
			(stroke
				(width 0.1)
				(type default)
			)
			(layer "F.Fab")
		)
		(fp_line
			(start 0.12065 -0.3048)
			(end 0.67945 -0.3048)
			(stroke
				(width 0.1)
				(type default)
			)
			(layer "F.Fab")
		)
		(fp_line
			(start 0.12065 -0.2794)
			(end 0.12065 -0.3048)
			(stroke
				(width 0.1)
				(type default)
			)
			(layer "F.Fab")
		)
		(fp_line
			(start -0.12065 -0.2794)
			(end 0.12065 -0.2794)
			(stroke
				(width 0.1)
				(type default)
			)
			(layer "F.Fab")
		)
		(fp_line
			(start 0.120396 0.2794)
			(end -0.12065 0.2794)
			(stroke
				(width 0.1)
				(type default)
			)
			(layer "F.Fab")
		)
		(fp_line
			(start -0.12065 0.2794)
			(end -0.12065 0.3048)
			(stroke
				(width 0.1)
				(type default)
			)
			(layer "F.Fab")
		)
		(fp_line
			(start 0.67945 0.3048)
			(end 0.120396 0.3048)
			(stroke
				(width 0.1)
				(type default)
			)
			(layer "F.Fab")
		)
		(fp_line
			(start 0.120396 0.3048)
			(end 0.120396 0.2794)
			(stroke
				(width 0.1)
				(type default)
			)
			(layer "F.Fab")
		)
		(fp_line
			(start -0.12065 0.3048)
			(end -0.67945 0.3048)
			(stroke
				(width 0.1)
				(type default)
			)
			(layer "F.Fab")
		)
		(fp_line
			(start -0.67945 0.3048)
			(end -0.67945 -0.305054)
			(stroke
				(width 0.1)
				(type default)
			)
			(layer "F.Fab")
		)
		(pad "1" smd circle
			(at -0.40005 0 90)
			(size 0 0)
			(layers "F.Cu" "F.Mask" "F.Paste")
			(net "PVCCIN_CPU0")
		)
		(pad "2" smd circle
			(at 0.40005 0 90)
			(size 0 0)
			(layers "F.Cu" "F.Mask" "F.Paste")
			(net "GND")
		)
	)
	(footprint ""
		(layer "F.Cu")
		(at 364.50143 -255.053846 90)
		(property "Reference" "C1000"
			(at 0 0 90)
			(layer "F.SilkS")
			(hide yes)
			(effects
				(font
					(size 1.27 1.27)
				)
			)
		)
		(property "Value" ""
			(at 0 0 90)
			(layer "F.Fab")
			(effects
				(font
					(size 1.27 1.27)
				)
			)
		)
		(duplicate_pad_numbers_are_jumpers no)
		(fp_line
			(start 0.7874 -0.4064)
			(end 0.7874 0.4064)
			(stroke
				(width 0.1524)
				(type default)
			)
			(layer "F.SilkS")
		)
		(fp_line
			(start -0.7874 -0.4064)
			(end 0.7874 -0.4064)
			(stroke
				(width 0.1524)
				(type default)
			)
			(layer "F.SilkS")
		)
		(fp_line
			(start 0.7874 0.4064)
			(end -0.7874 0.4064)
			(stroke
				(width 0.1524)
				(type default)
			)
			(layer "F.SilkS")
		)
		(fp_line
			(start -0.7874 0.4064)
			(end -0.7874 -0.4064)
			(stroke
				(width 0.1524)
				(type default)
			)
			(layer "F.SilkS")
		)
		(fp_line
			(start -0.12065 -0.305054)
			(end -0.12065 -0.2794)
			(stroke
				(width 0.1)
				(type default)
			)
			(layer "F.Fab")
		)
		(fp_line
			(start -0.67945 -0.305054)
			(end -0.12065 -0.305054)
			(stroke
				(width 0.1)
				(type default)
			)
			(layer "F.Fab")
		)
		(fp_line
			(start 0.67945 -0.3048)
			(end 0.67945 0.3048)
			(stroke
				(width 0.1)
				(type default)
			)
			(layer "F.Fab")
		)
		(fp_line
			(start 0.12065 -0.3048)
			(end 0.67945 -0.3048)
			(stroke
				(width 0.1)
				(type default)
			)
			(layer "F.Fab")
		)
		(fp_line
			(start 0.12065 -0.2794)
			(end 0.12065 -0.3048)
			(stroke
				(width 0.1)
				(type default)
			)
			(layer "F.Fab")
		)
		(fp_line
			(start -0.12065 -0.2794)
			(end 0.12065 -0.2794)
			(stroke
				(width 0.1)
				(type default)
			)
			(layer "F.Fab")
		)
		(fp_line
			(start 0.120396 0.2794)
			(end -0.12065 0.2794)
			(stroke
				(width 0.1)
				(type default)
			)
			(layer "F.Fab")
		)
		(fp_line
			(start -0.12065 0.2794)
			(end -0.12065 0.3048)
			(stroke
				(width 0.1)
				(type default)
			)
			(layer "F.Fab")
		)
		(fp_line
			(start 0.67945 0.3048)
			(end 0.120396 0.3048)
			(stroke
				(width 0.1)
				(type default)
			)
			(layer "F.Fab")
		)
		(fp_line
			(start 0.120396 0.3048)
			(end 0.120396 0.2794)
			(stroke
				(width 0.1)
				(type default)
			)
			(layer "F.Fab")
		)
		(fp_line
			(start -0.12065 0.3048)
			(end -0.67945 0.3048)
			(stroke
				(width 0.1)
				(type default)
			)
			(layer "F.Fab")
		)
		(fp_line
			(start -0.67945 0.3048)
			(end -0.67945 -0.305054)
			(stroke
				(width 0.1)
				(type default)
			)
			(layer "F.Fab")
		)
		(pad "1" smd circle
			(at -0.40005 0 90)
			(size 0 0)
			(layers "F.Cu" "F.Mask" "F.Paste")
			(net "PVCCIN_CPU0")
		)
		(pad "2" smd circle
			(at 0.40005 0 90)
			(size 0 0)
			(layers "F.Cu" "F.Mask" "F.Paste")
			(net "GND")
		)
	)
	(footprint ""
		(layer "F.Cu")
		(at 368.127788 -338.86013)
		(property "Reference" "PR144"
			(at 0 0 0)
			(layer "F.SilkS")
			(hide yes)
			(effects
				(font
					(size 1.27 1.27)
				)
			)
		)
		(property "Value" ""
			(at 0 0 0)
			(layer "F.Fab")
			(effects
				(font
					(size 1.27 1.27)
				)
			)
		)
		(duplicate_pad_numbers_are_jumpers no)
		(fp_line
			(start -0.7874 -0.4064)
			(end 0.7874 -0.4064)
			(stroke
				(width 0.1524)
				(type default)
			)
			(layer "F.SilkS")
		)
		(fp_line
			(start -0.7874 0.4064)
			(end -0.7874 -0.4064)
			(stroke
				(width 0.1524)
				(type default)
			)
			(layer "F.SilkS")
		)
		(fp_line
			(start 0.7874 -0.4064)
			(end 0.7874 0.4064)
			(stroke
				(width 0.1524)
				(type default)
			)
			(layer "F.SilkS")
		)
		(fp_line
			(start 0.7874 0.4064)
			(end -0.7874 0.4064)
			(stroke
				(width 0.1524)
				(type default)
			)
			(layer "F.SilkS")
		)
		(fp_line
			(start -0.67945 -0.305054)
			(end -0.12065 -0.305054)
			(stroke
				(width 0.1)
				(type default)
			)
			(layer "F.Fab")
		)
		(fp_line
			(start -0.67945 0.3048)
			(end -0.67945 -0.305054)
			(stroke
				(width 0.1)
				(type default)
			)
			(layer "F.Fab")
		)
		(fp_line
			(start -0.12065 -0.305054)
			(end -0.12065 -0.2794)
			(stroke
				(width 0.1)
				(type default)
			)
			(layer "F.Fab")
		)
		(fp_line
			(start -0.12065 -0.2794)
			(end 0.12065 -0.2794)
			(stroke
				(width 0.1)
				(type default)
			)
			(layer "F.Fab")
		)
		(fp_line
			(start -0.12065 0.2794)
			(end -0.12065 0.3048)
			(stroke
				(width 0.1)
				(type default)
			)
			(layer "F.Fab")
		)
		(fp_line
			(start -0.12065 0.3048)
			(end -0.67945 0.3048)
			(stroke
				(width 0.1)
				(type default)
			)
			(layer "F.Fab")
		)
		(fp_line
			(start 0.120396 0.2794)
			(end -0.12065 0.2794)
			(stroke
				(width 0.1)
				(type default)
			)
			(layer "F.Fab")
		)
		(fp_line
			(start 0.120396 0.3048)
			(end 0.120396 0.2794)
			(stroke
				(width 0.1)
				(type default)
			)
			(layer "F.Fab")
		)
		(fp_line
			(start 0.12065 -0.3048)
			(end 0.67945 -0.3048)
			(stroke
				(width 0.1)
				(type default)
			)
			(layer "F.Fab")
		)
		(fp_line
			(start 0.12065 -0.2794)
			(end 0.12065 -0.3048)
			(stroke
				(width 0.1)
				(type default)
			)
			(layer "F.Fab")
		)
		(fp_line
			(start 0.67945 -0.3048)
			(end 0.67945 0.3048)
			(stroke
				(width 0.1)
				(type default)
			)
			(layer "F.Fab")
		)
		(fp_line
			(start 0.67945 0.3048)
			(end 0.120396 0.3048)
			(stroke
				(width 0.1)
				(type default)
			)
			(layer "F.Fab")
		)
		(pad "1" smd circle
			(at -0.40005 0)
			(size 0 0)
			(layers "F.Cu" "F.Mask" "F.Paste")
			(net "PVCCIN_CPU0_LSET4")
		)
		(pad "2" smd circle
			(at 0.40005 0)
			(size 0 0)
			(layers "F.Cu" "F.Mask" "F.Paste")
			(net "GND")
		)
	)
	(footprint ""
		(layer "F.Cu")
		(at 203.1492 -95.91802 90)
		(property "Reference" "U339"
			(at -0.8382 2.13487 90)
			(unlocked yes)
			(layer "F.SilkS")
			(effects
				(font
					(size 0.7874 0.5842)
					(thickness 0.1524)
				)
			)
		)
		(property "Value" ""
			(at 0 0 90)
			(layer "F.Fab")
			(effects
				(font
					(size 1.27 1.27)
				)
			)
		)
		(duplicate_pad_numbers_are_jumpers no)
		(fp_line
			(start 2.032 -1.549908)
			(end 2.032 1.549908)
			(stroke
				(width 0.1524)
				(type default)
			)
			(layer "F.SilkS")
		)
		(fp_line
			(start 0.508 -1.549908)
			(end 2.032 -1.549908)
			(stroke
				(width 0.1524)
				(type default)
			)
			(layer "F.SilkS")
		)
		(fp_line
			(start -0.508 -1.549908)
			(end 0 -0.762)
			(stroke
				(width 0.1524)
				(type default)
			)
			(layer "F.SilkS")
		)
		(fp_line
			(start -2.032 -1.549908)
			(end -0.508 -1.549908)
			(stroke
				(width 0.1524)
				(type default)
			)
			(layer "F.SilkS")
		)
		(fp_line
			(start 0 -0.762)
			(end 0.508 -1.549908)
			(stroke
				(width 0.1524)
				(type default)
			)
			(layer "F.SilkS")
		)
		(fp_line
			(start 2.032 1.549908)
			(end -2.032 1.549908)
			(stroke
				(width 0.1524)
				(type default)
			)
			(layer "F.SilkS")
		)
		(fp_line
			(start -2.032 1.549908)
			(end -2.032 -1.549908)
			(stroke
				(width 0.1524)
				(type default)
			)
			(layer "F.SilkS")
		)
		(fp_poly
			(pts
				(xy -3.2004 -1.45796) (xy -3.2004 -0.44196) (xy -2.1844 -0.94996)
			)
			(stroke
				(width 0)
				(type default)
			)
			(fill yes)
			(layer "F.SilkS")
		)
		(fp_line
			(start 0.849884 -1.549908)
			(end 0.849884 1.549908)
			(stroke
				(width 0.1)
				(type default)
			)
			(layer "F.Fab")
		)
		(fp_line
			(start -0.849884 -1.549908)
			(end 0.849884 -1.549908)
			(stroke
				(width 0.1)
				(type default)
			)
			(layer "F.Fab")
		)
		(fp_line
			(start 0.849884 1.549908)
			(end -0.849884 1.549908)
			(stroke
				(width 0.1)
				(type default)
			)
			(layer "F.Fab")
		)
		(fp_line
			(start -0.849884 1.549908)
			(end -0.849884 -1.549908)
			(stroke
				(width 0.1)
				(type default)
			)
			(layer "F.Fab")
		)
		(fp_poly
			(pts
				(xy -3.2004 -1.45796) (xy -3.2004 -0.44196) (xy -2.1844 -0.94996)
			)
			(stroke
				(width 0)
				(type default)
			)
			(fill yes)
			(layer "F.Fab")
		)
		(pad "1" smd rect
			(at -1.35001 -0.94996)
			(size 0.6096 1.0668)
			(layers "F.Cu" "F.Mask" "F.Paste")
			(net "UV_ADR_P2V5_COMP")
		)
		(pad "2" smd rect
			(at -1.35001 0)
			(size 0.6096 1.0668)
			(layers "F.Cu" "F.Mask" "F.Paste")
			(net "GND")
		)
		(pad "3" smd rect
			(at -1.35001 0.94996)
			(size 0.6096 1.0668)
			(layers "F.Cu" "F.Mask" "F.Paste")
			(net "P12V_AUX_UV_ADR_TRIGGER")
		)
		(pad "4" smd rect
			(at 1.35001 0.94996)
			(size 0.6096 1.0668)
			(layers "F.Cu" "F.Mask" "F.Paste")
			(net "FM_UV_ADR_TRIGGER_N_R2")
		)
		(pad "5" smd rect
			(at 1.35001 -0.94996)
			(size 0.6096 1.0668)
			(layers "F.Cu" "F.Mask" "F.Paste")
			(net "P12V_AUX")
		)
	)
	(footprint ""
		(layer "F.Cu")
		(at 36.795202 -180.55336)
		(property "Reference" "PC1286"
			(at 0 0 0)
			(layer "F.SilkS")
			(hide yes)
			(effects
				(font
					(size 1.27 1.27)
				)
			)
		)
		(property "Value" ""
			(at 0 0 0)
			(layer "F.Fab")
			(effects
				(font
					(size 1.27 1.27)
				)
			)
		)
		(duplicate_pad_numbers_are_jumpers no)
		(fp_line
			(start -1.524 -0.762)
			(end 1.524 -0.762)
			(stroke
				(width 0.1524)
				(type default)
			)
			(layer "F.SilkS")
		)
		(fp_line
			(start -1.524 0.762)
			(end -1.524 -0.762)
			(stroke
				(width 0.1524)
				(type default)
			)
			(layer "F.SilkS")
		)
		(fp_line
			(start 1.524 -0.762)
			(end 1.524 0.762)
			(stroke
				(width 0.1524)
				(type default)
			)
			(layer "F.SilkS")
		)
		(fp_line
			(start 1.524 0.762)
			(end -1.524 0.762)
			(stroke
				(width 0.1524)
				(type default)
			)
			(layer "F.SilkS")
		)
		(fp_line
			(start -1.1049 -0.724916)
			(end -1.1049 0.724916)
			(stroke
				(width 0.1)
				(type default)
			)
			(layer "F.Fab")
		)
		(fp_line
			(start -1.1049 0.724916)
			(end 1.1049 0.724916)
			(stroke
				(width 0.1)
				(type default)
			)
			(layer "F.Fab")
		)
		(fp_line
			(start 1.1049 -0.724916)
			(end -1.1049 -0.724916)
			(stroke
				(width 0.1)
				(type default)
			)
			(layer "F.Fab")
		)
		(fp_line
			(start 1.1049 0.724916)
			(end 1.1049 -0.724916)
			(stroke
				(width 0.1)
				(type default)
			)
			(layer "F.Fab")
		)
		(pad "1" smd rect
			(at -0.889 0 180)
			(size 1.016 1.27)
			(layers "F.Cu" "F.Mask" "F.Paste")
			(net "PVNN_MAIN_CPU1")
		)
		(pad "2" smd rect
			(at 0.889 0 180)
			(size 1.016 1.27)
			(layers "F.Cu" "F.Mask" "F.Paste")
			(net "GND")
		)
	)
	(footprint ""
		(layer "F.Cu")
		(at 361.25658 -407.228548)
		(property "Reference" "C2341"
			(at 0 0 0)
			(layer "F.SilkS")
			(hide yes)
			(effects
				(font
					(size 1.27 1.27)
				)
			)
		)
		(property "Value" ""
			(at 0 0 0)
			(layer "F.Fab")
			(effects
				(font
					(size 1.27 1.27)
				)
			)
		)
		(duplicate_pad_numbers_are_jumpers no)
		(fp_line
			(start -0.7874 -0.4064)
			(end 0.7874 -0.4064)
			(stroke
				(width 0.1524)
				(type default)
			)
			(layer "F.SilkS")
		)
		(fp_line
			(start -0.7874 0.4064)
			(end -0.7874 -0.4064)
			(stroke
				(width 0.1524)
				(type default)
			)
			(layer "F.SilkS")
		)
		(fp_line
			(start 0.7874 -0.4064)
			(end 0.7874 0.4064)
			(stroke
				(width 0.1524)
				(type default)
			)
			(layer "F.SilkS")
		)
		(fp_line
			(start 0.7874 0.4064)
			(end -0.7874 0.4064)
			(stroke
				(width 0.1524)
				(type default)
			)
			(layer "F.SilkS")
		)
		(fp_line
			(start -0.67945 -0.305054)
			(end -0.12065 -0.305054)
			(stroke
				(width 0.1)
				(type default)
			)
			(layer "F.Fab")
		)
		(fp_line
			(start -0.67945 0.3048)
			(end -0.67945 -0.305054)
			(stroke
				(width 0.1)
				(type default)
			)
			(layer "F.Fab")
		)
		(fp_line
			(start -0.12065 -0.305054)
			(end -0.12065 -0.2794)
			(stroke
				(width 0.1)
				(type default)
			)
			(layer "F.Fab")
		)
		(fp_line
			(start -0.12065 -0.2794)
			(end 0.12065 -0.2794)
			(stroke
				(width 0.1)
				(type default)
			)
			(layer "F.Fab")
		)
		(fp_line
			(start -0.12065 0.2794)
			(end -0.12065 0.3048)
			(stroke
				(width 0.1)
				(type default)
			)
			(layer "F.Fab")
		)
		(fp_line
			(start -0.12065 0.3048)
			(end -0.67945 0.3048)
			(stroke
				(width 0.1)
				(type default)
			)
			(layer "F.Fab")
		)
		(fp_line
			(start 0.120396 0.2794)
			(end -0.12065 0.2794)
			(stroke
				(width 0.1)
				(type default)
			)
			(layer "F.Fab")
		)
		(fp_line
			(start 0.120396 0.3048)
			(end 0.120396 0.2794)
			(stroke
				(width 0.1)
				(type default)
			)
			(layer "F.Fab")
		)
		(fp_line
			(start 0.12065 -0.3048)
			(end 0.67945 -0.3048)
			(stroke
				(width 0.1)
				(type default)
			)
			(layer "F.Fab")
		)
		(fp_line
			(start 0.12065 -0.2794)
			(end 0.12065 -0.3048)
			(stroke
				(width 0.1)
				(type default)
			)
			(layer "F.Fab")
		)
		(fp_line
			(start 0.67945 -0.3048)
			(end 0.67945 0.3048)
			(stroke
				(width 0.1)
				(type default)
			)
			(layer "F.Fab")
		)
		(fp_line
			(start 0.67945 0.3048)
			(end 0.120396 0.3048)
			(stroke
				(width 0.1)
				(type default)
			)
			(layer "F.Fab")
		)
		(pad "1" smd circle
			(at -0.40005 0)
			(size 0 0)
			(layers "F.Cu" "F.Mask" "F.Paste")
			(net "P3V3_AUX")
		)
		(pad "2" smd circle
			(at 0.40005 0)
			(size 0 0)
			(layers "F.Cu" "F.Mask" "F.Paste")
			(net "GND")
		)
	)
	(footprint ""
		(layer "F.Cu")
		(at 398.133824 -185.96991)
		(property "Reference" "PR519"
			(at 0 0 0)
			(layer "F.SilkS")
			(hide yes)
			(effects
				(font
					(size 1.27 1.27)
				)
			)
		)
		(property "Value" ""
			(at 0 0 0)
			(layer "F.Fab")
			(effects
				(font
					(size 1.27 1.27)
				)
			)
		)
		(duplicate_pad_numbers_are_jumpers no)
		(fp_line
			(start -0.7874 -0.4064)
			(end 0.7874 -0.4064)
			(stroke
				(width 0.1524)
				(type default)
			)
			(layer "F.SilkS")
		)
		(fp_line
			(start -0.7874 0.4064)
			(end -0.7874 -0.4064)
			(stroke
				(width 0.1524)
				(type default)
			)
			(layer "F.SilkS")
		)
		(fp_line
			(start 0.7874 -0.4064)
			(end 0.7874 0.4064)
			(stroke
				(width 0.1524)
				(type default)
			)
			(layer "F.SilkS")
		)
		(fp_line
			(start 0.7874 0.4064)
			(end -0.7874 0.4064)
			(stroke
				(width 0.1524)
				(type default)
			)
			(layer "F.SilkS")
		)
		(fp_line
			(start -0.67945 -0.305054)
			(end -0.12065 -0.305054)
			(stroke
				(width 0.1)
				(type default)
			)
			(layer "F.Fab")
		)
		(fp_line
			(start -0.67945 0.3048)
			(end -0.67945 -0.305054)
			(stroke
				(width 0.1)
				(type default)
			)
			(layer "F.Fab")
		)
		(fp_line
			(start -0.12065 -0.305054)
			(end -0.12065 -0.2794)
			(stroke
				(width 0.1)
				(type default)
			)
			(layer "F.Fab")
		)
		(fp_line
			(start -0.12065 -0.2794)
			(end 0.12065 -0.2794)
			(stroke
				(width 0.1)
				(type default)
			)
			(layer "F.Fab")
		)
		(fp_line
			(start -0.12065 0.2794)
			(end -0.12065 0.3048)
			(stroke
				(width 0.1)
				(type default)
			)
			(layer "F.Fab")
		)
		(fp_line
			(start -0.12065 0.3048)
			(end -0.67945 0.3048)
			(stroke
				(width 0.1)
				(type default)
			)
			(layer "F.Fab")
		)
		(fp_line
			(start 0.120396 0.2794)
			(end -0.12065 0.2794)
			(stroke
				(width 0.1)
				(type default)
			)
			(layer "F.Fab")
		)
		(fp_line
			(start 0.120396 0.3048)
			(end 0.120396 0.2794)
			(stroke
				(width 0.1)
				(type default)
			)
			(layer "F.Fab")
		)
		(fp_line
			(start 0.12065 -0.3048)
			(end 0.67945 -0.3048)
			(stroke
				(width 0.1)
				(type default)
			)
			(layer "F.Fab")
		)
		(fp_line
			(start 0.12065 -0.2794)
			(end 0.12065 -0.3048)
			(stroke
				(width 0.1)
				(type default)
			)
			(layer "F.Fab")
		)
		(fp_line
			(start 0.67945 -0.3048)
			(end 0.67945 0.3048)
			(stroke
				(width 0.1)
				(type default)
			)
			(layer "F.Fab")
		)
		(fp_line
			(start 0.67945 0.3048)
			(end 0.120396 0.3048)
			(stroke
				(width 0.1)
				(type default)
			)
			(layer "F.Fab")
		)
		(pad "1" smd circle
			(at -0.40005 0)
			(size 0 0)
			(layers "F.Cu" "F.Mask" "F.Paste")
			(net "VSENSE_PVCCINFAON_CPU0_DN")
		)
		(pad "2" smd circle
			(at 0.40005 0)
			(size 0 0)
			(layers "F.Cu" "F.Mask" "F.Paste")
			(net "GND")
		)
	)
	(footprint ""
		(layer "F.Cu")
		(at 322.349622 -33.848548 -135)
		(property "Reference" "C609"
			(at 0 0 225)
			(layer "F.SilkS")
			(hide yes)
			(effects
				(font
					(size 1.27 1.27)
				)
			)
		)
		(property "Value" ""
			(at 0 0 225)
			(layer "F.Fab")
			(effects
				(font
					(size 1.27 1.27)
				)
			)
		)
		(duplicate_pad_numbers_are_jumpers no)
		(fp_line
			(start 0.787389 0.406267)
			(end -0.787389 0.406267)
			(stroke
				(width 0.1524)
				(type default)
			)
			(layer "F.SilkS")
		)
		(fp_line
			(start 0.787389 -0.406267)
			(end 0.787389 0.406267)
			(stroke
				(width 0.1524)
				(type default)
			)
			(layer "F.SilkS")
		)
		(fp_line
			(start -0.787389 0.406267)
			(end -0.787389 -0.406267)
			(stroke
				(width 0.1524)
				(type default)
			)
			(layer "F.SilkS")
		)
		(fp_line
			(start -0.787389 -0.406267)
			(end 0.787389 -0.406267)
			(stroke
				(width 0.1524)
				(type default)
			)
			(layer "F.SilkS")
		)
		(fp_line
			(start 0.679446 0.30479)
			(end 0.120515 0.30479)
			(stroke
				(width 0.1)
				(type default)
			)
			(layer "F.Fab")
		)
		(fp_line
			(start 0.120515 0.30479)
			(end 0.120335 0.279466)
			(stroke
				(width 0.1)
				(type default)
			)
			(layer "F.Fab")
		)
		(fp_line
			(start 0.120335 0.279466)
			(end -0.120695 0.279466)
			(stroke
				(width 0.1)
				(type default)
			)
			(layer "F.Fab")
		)
		(fp_line
			(start 0.679446 -0.30479)
			(end 0.679446 0.30479)
			(stroke
				(width 0.1)
				(type default)
			)
			(layer "F.Fab")
		)
		(fp_line
			(start -0.120515 0.30479)
			(end -0.679446 0.30479)
			(stroke
				(width 0.1)
				(type default)
			)
			(layer "F.Fab")
		)
		(fp_line
			(start -0.120695 0.279466)
			(end -0.120515 0.30479)
			(stroke
				(width 0.1)
				(type default)
			)
			(layer "F.Fab")
		)
		(fp_line
			(start 0.120695 -0.279466)
			(end 0.120515 -0.30479)
			(stroke
				(width 0.1)
				(type default)
			)
			(layer "F.Fab")
		)
		(fp_line
			(start 0.120515 -0.30479)
			(end 0.679446 -0.30479)
			(stroke
				(width 0.1)
				(type default)
			)
			(layer "F.Fab")
		)
		(fp_line
			(start -0.679446 0.30479)
			(end -0.679446 -0.305149)
			(stroke
				(width 0.1)
				(type default)
			)
			(layer "F.Fab")
		)
		(fp_line
			(start -0.120695 -0.279466)
			(end 0.120695 -0.279466)
			(stroke
				(width 0.1)
				(type default)
			)
			(layer "F.Fab")
		)
		(fp_line
			(start -0.120695 -0.304969)
			(end -0.120695 -0.279466)
			(stroke
				(width 0.1)
				(type default)
			)
			(layer "F.Fab")
		)
		(fp_line
			(start -0.679446 -0.305149)
			(end -0.120695 -0.304969)
			(stroke
				(width 0.1)
				(type default)
			)
			(layer "F.Fab")
		)
		(pad "1" smd circle
			(at -0.40005 0 225)
			(size 0 0)
			(layers "F.Cu" "F.Mask" "F.Paste")
			(net "RTC_EXT_CAP")
		)
		(pad "2" smd circle
			(at 0.40005 0 225)
			(size 0 0)
			(layers "F.Cu" "F.Mask" "F.Paste")
			(net "GND")
		)
	)
	(footprint ""
		(layer "F.Cu")
		(at 160.838642 -110.9091)
		(property "Reference" "R3132"
			(at 0 0 0)
			(layer "F.SilkS")
			(hide yes)
			(effects
				(font
					(size 1.27 1.27)
				)
			)
		)
		(property "Value" ""
			(at 0 0 0)
			(layer "F.Fab")
			(effects
				(font
					(size 1.27 1.27)
				)
			)
		)
		(duplicate_pad_numbers_are_jumpers no)
		(fp_line
			(start -0.7874 -0.4064)
			(end 0.7874 -0.4064)
			(stroke
				(width 0.1524)
				(type default)
			)
			(layer "F.SilkS")
		)
		(fp_line
			(start -0.7874 0.4064)
			(end -0.7874 -0.4064)
			(stroke
				(width 0.1524)
				(type default)
			)
			(layer "F.SilkS")
		)
		(fp_line
			(start 0.7874 -0.4064)
			(end 0.7874 0.4064)
			(stroke
				(width 0.1524)
				(type default)
			)
			(layer "F.SilkS")
		)
		(fp_line
			(start 0.7874 0.4064)
			(end -0.7874 0.4064)
			(stroke
				(width 0.1524)
				(type default)
			)
			(layer "F.SilkS")
		)
		(fp_line
			(start -0.67945 -0.305054)
			(end -0.12065 -0.305054)
			(stroke
				(width 0.1)
				(type default)
			)
			(layer "F.Fab")
		)
		(fp_line
			(start -0.67945 0.3048)
			(end -0.67945 -0.305054)
			(stroke
				(width 0.1)
				(type default)
			)
			(layer "F.Fab")
		)
		(fp_line
			(start -0.12065 -0.305054)
			(end -0.12065 -0.2794)
			(stroke
				(width 0.1)
				(type default)
			)
			(layer "F.Fab")
		)
		(fp_line
			(start -0.12065 -0.2794)
			(end 0.12065 -0.2794)
			(stroke
				(width 0.1)
				(type default)
			)
			(layer "F.Fab")
		)
		(fp_line
			(start -0.12065 0.2794)
			(end -0.12065 0.3048)
			(stroke
				(width 0.1)
				(type default)
			)
			(layer "F.Fab")
		)
		(fp_line
			(start -0.12065 0.3048)
			(end -0.67945 0.3048)
			(stroke
				(width 0.1)
				(type default)
			)
			(layer "F.Fab")
		)
		(fp_line
			(start 0.120396 0.2794)
			(end -0.12065 0.2794)
			(stroke
				(width 0.1)
				(type default)
			)
			(layer "F.Fab")
		)
		(fp_line
			(start 0.120396 0.3048)
			(end 0.120396 0.2794)
			(stroke
				(width 0.1)
				(type default)
			)
			(layer "F.Fab")
		)
		(fp_line
			(start 0.12065 -0.3048)
			(end 0.67945 -0.3048)
			(stroke
				(width 0.1)
				(type default)
			)
			(layer "F.Fab")
		)
		(fp_line
			(start 0.12065 -0.2794)
			(end 0.12065 -0.3048)
			(stroke
				(width 0.1)
				(type default)
			)
			(layer "F.Fab")
		)
		(fp_line
			(start 0.67945 -0.3048)
			(end 0.67945 0.3048)
			(stroke
				(width 0.1)
				(type default)
			)
			(layer "F.Fab")
		)
		(fp_line
			(start 0.67945 0.3048)
			(end 0.120396 0.3048)
			(stroke
				(width 0.1)
				(type default)
			)
			(layer "F.Fab")
		)
		(pad "1" smd circle
			(at -0.40005 0)
			(size 0 0)
			(layers "F.Cu" "F.Mask" "F.Paste")
			(net "GND")
		)
		(pad "2" smd circle
			(at 0.40005 0)
			(size 0 0)
			(layers "F.Cu" "F.Mask" "F.Paste")
			(net "FM_OCP_SFF_PWR_GOOD")
		)
	)
	(footprint ""
		(layer "F.Cu")
		(at 15.436596 -391.183876)
		(property "Reference" "R3275"
			(at 0 0 0)
			(layer "F.SilkS")
			(hide yes)
			(effects
				(font
					(size 1.27 1.27)
				)
			)
		)
		(property "Value" ""
			(at 0 0 0)
			(layer "F.Fab")
			(effects
				(font
					(size 1.27 1.27)
				)
			)
		)
		(duplicate_pad_numbers_are_jumpers no)
		(fp_line
			(start -0.7874 -0.4064)
			(end 0.7874 -0.4064)
			(stroke
				(width 0.1524)
				(type default)
			)
			(layer "F.SilkS")
		)
		(fp_line
			(start -0.7874 0.4064)
			(end -0.7874 -0.4064)
			(stroke
				(width 0.1524)
				(type default)
			)
			(layer "F.SilkS")
		)
		(fp_line
			(start 0.7874 -0.4064)
			(end 0.7874 0.4064)
			(stroke
				(width 0.1524)
				(type default)
			)
			(layer "F.SilkS")
		)
		(fp_line
			(start 0.7874 0.4064)
			(end -0.7874 0.4064)
			(stroke
				(width 0.1524)
				(type default)
			)
			(layer "F.SilkS")
		)
		(fp_line
			(start -0.67945 -0.305054)
			(end -0.12065 -0.305054)
			(stroke
				(width 0.1)
				(type default)
			)
			(layer "F.Fab")
		)
		(fp_line
			(start -0.67945 0.3048)
			(end -0.67945 -0.305054)
			(stroke
				(width 0.1)
				(type default)
			)
			(layer "F.Fab")
		)
		(fp_line
			(start -0.12065 -0.305054)
			(end -0.12065 -0.2794)
			(stroke
				(width 0.1)
				(type default)
			)
			(layer "F.Fab")
		)
		(fp_line
			(start -0.12065 -0.2794)
			(end 0.12065 -0.2794)
			(stroke
				(width 0.1)
				(type default)
			)
			(layer "F.Fab")
		)
		(fp_line
			(start -0.12065 0.2794)
			(end -0.12065 0.3048)
			(stroke
				(width 0.1)
				(type default)
			)
			(layer "F.Fab")
		)
		(fp_line
			(start -0.12065 0.3048)
			(end -0.67945 0.3048)
			(stroke
				(width 0.1)
				(type default)
			)
			(layer "F.Fab")
		)
		(fp_line
			(start 0.120396 0.2794)
			(end -0.12065 0.2794)
			(stroke
				(width 0.1)
				(type default)
			)
			(layer "F.Fab")
		)
		(fp_line
			(start 0.120396 0.3048)
			(end 0.120396 0.2794)
			(stroke
				(width 0.1)
				(type default)
			)
			(layer "F.Fab")
		)
		(fp_line
			(start 0.12065 -0.3048)
			(end 0.67945 -0.3048)
			(stroke
				(width 0.1)
				(type default)
			)
			(layer "F.Fab")
		)
		(fp_line
			(start 0.12065 -0.2794)
			(end 0.12065 -0.3048)
			(stroke
				(width 0.1)
				(type default)
			)
			(layer "F.Fab")
		)
		(fp_line
			(start 0.67945 -0.3048)
			(end 0.67945 0.3048)
			(stroke
				(width 0.1)
				(type default)
			)
			(layer "F.Fab")
		)
		(fp_line
			(start 0.67945 0.3048)
			(end 0.120396 0.3048)
			(stroke
				(width 0.1)
				(type default)
			)
			(layer "F.Fab")
		)
		(pad "1" smd circle
			(at -0.40005 0)
			(size 0 0)
			(layers "F.Cu" "F.Mask" "F.Paste")
			(net "P3V3_AUX")
		)
		(pad "2" smd circle
			(at 0.40005 0)
			(size 0 0)
			(layers "F.Cu" "F.Mask" "F.Paste")
			(net "FM_P2E_FGA")
		)
	)
	(footprint ""
		(layer "F.Cu")
		(at 423.089324 -149.239224 -90)
		(property "Reference" "PC176"
			(at 0 0 270)
			(layer "F.SilkS")
			(hide yes)
			(effects
				(font
					(size 1.27 1.27)
				)
			)
		)
		(property "Value" ""
			(at 0 0 270)
			(layer "F.Fab")
			(effects
				(font
					(size 1.27 1.27)
				)
			)
		)
		(duplicate_pad_numbers_are_jumpers no)
		(fp_line
			(start -0.7874 0.4064)
			(end -0.7874 -0.4064)
			(stroke
				(width 0.1524)
				(type default)
			)
			(layer "F.SilkS")
		)
		(fp_line
			(start 0.7874 0.4064)
			(end -0.7874 0.4064)
			(stroke
				(width 0.1524)
				(type default)
			)
			(layer "F.SilkS")
		)
		(fp_line
			(start -0.7874 -0.4064)
			(end 0.7874 -0.4064)
			(stroke
				(width 0.1524)
				(type default)
			)
			(layer "F.SilkS")
		)
		(fp_line
			(start 0.7874 -0.4064)
			(end 0.7874 0.4064)
			(stroke
				(width 0.1524)
				(type default)
			)
			(layer "F.SilkS")
		)
		(fp_line
			(start -0.67945 0.3048)
			(end -0.67945 -0.305054)
			(stroke
				(width 0.1)
				(type default)
			)
			(layer "F.Fab")
		)
		(fp_line
			(start -0.12065 0.3048)
			(end -0.67945 0.3048)
			(stroke
				(width 0.1)
				(type default)
			)
			(layer "F.Fab")
		)
		(fp_line
			(start 0.120396 0.3048)
			(end 0.120396 0.2794)
			(stroke
				(width 0.1)
				(type default)
			)
			(layer "F.Fab")
		)
		(fp_line
			(start 0.67945 0.3048)
			(end 0.120396 0.3048)
			(stroke
				(width 0.1)
				(type default)
			)
			(layer "F.Fab")
		)
		(fp_line
			(start -0.12065 0.2794)
			(end -0.12065 0.3048)
			(stroke
				(width 0.1)
				(type default)
			)
			(layer "F.Fab")
		)
		(fp_line
			(start 0.120396 0.2794)
			(end -0.12065 0.2794)
			(stroke
				(width 0.1)
				(type default)
			)
			(layer "F.Fab")
		)
		(fp_line
			(start -0.12065 -0.2794)
			(end 0.12065 -0.2794)
			(stroke
				(width 0.1)
				(type default)
			)
			(layer "F.Fab")
		)
		(fp_line
			(start 0.12065 -0.2794)
			(end 0.12065 -0.3048)
			(stroke
				(width 0.1)
				(type default)
			)
			(layer "F.Fab")
		)
		(fp_line
			(start 0.12065 -0.3048)
			(end 0.67945 -0.3048)
			(stroke
				(width 0.1)
				(type default)
			)
			(layer "F.Fab")
		)
		(fp_line
			(start 0.67945 -0.3048)
			(end 0.67945 0.3048)
			(stroke
				(width 0.1)
				(type default)
			)
			(layer "F.Fab")
		)
		(fp_line
			(start -0.67945 -0.305054)
			(end -0.12065 -0.305054)
			(stroke
				(width 0.1)
				(type default)
			)
			(layer "F.Fab")
		)
		(fp_line
			(start -0.12065 -0.305054)
			(end -0.12065 -0.2794)
			(stroke
				(width 0.1)
				(type default)
			)
			(layer "F.Fab")
		)
		(pad "1" smd circle
			(at -0.40005 0 270)
			(size 0 0)
			(layers "F.Cu" "F.Mask" "F.Paste")
			(net "SW_P12V_PVCCINFAON_CPU0_FLT")
		)
		(pad "2" smd circle
			(at 0.40005 0 270)
			(size 0 0)
			(layers "F.Cu" "F.Mask" "F.Paste")
			(net "GND")
		)
	)
	(footprint ""
		(layer "F.Cu")
		(at 69.923406 -154.36469)
		(property "Reference" "PC1596"
			(at 0 0 0)
			(layer "F.SilkS")
			(hide yes)
			(effects
				(font
					(size 1.27 1.27)
				)
			)
		)
		(property "Value" ""
			(at 0 0 0)
			(layer "F.Fab")
			(effects
				(font
					(size 1.27 1.27)
				)
			)
		)
		(duplicate_pad_numbers_are_jumpers no)
		(fp_line
			(start 2.750058 0.999998)
			(end -2.750058 0.999998)
			(stroke
				(width 0.1524)
				(type default)
			)
			(layer "F.SilkS")
		)
		(fp_circle
			(center 0 0.999998)
			(end 2.750058 0.999998)
			(stroke
				(width 0.1524)
				(type default)
			)
			(fill no)
			(layer "F.SilkS")
		)
		(fp_poly
			(pts
				(arc
					(start 2.750058 0.999998)
					(mid 0 3.750056)
					(end -2.750058 0.999998)
				)
			)
			(stroke
				(width 0)
				(type default)
			)
			(fill yes)
			(layer "F.SilkS")
		)
		(fp_circle
			(center 0 0.999998)
			(end 2.750058 0.999998)
			(stroke
				(width 0.1)
				(type default)
			)
			(fill no)
			(layer "F.Fab")
		)
		(pad "1" thru_hole rect
			(at 0 0)
			(size 1.5748 1.5748)
			(drill 1.0668)
			(layers "*.Cu" "*.Mask")
			(remove_unused_layers no)
			(net "PVCCINFAON_CPU1")
			(clearance 0)
			(padstack
				(mode front_inner_back)
				(layer "Inner"
					(shape circle)
					(size 1.5748 1.5748)
					(clearance 0)
				)
				(layer "B.Cu"
					(shape rect)
					(size 1.5748 1.5748)
					(clearance 0)
				)
			)
		)
		(pad "2" thru_hole circle
			(at 0 1.999996)
			(size 1.5748 1.5748)
			(drill 1.0668)
			(layers "*.Cu" "*.Mask")
			(remove_unused_layers no)
			(net "GND")
			(clearance 0)
		)
	)
	(footprint ""
		(layer "F.Cu")
		(at 21.913596 -390.675876 90)
		(property "Reference" "U237"
			(at -6.036056 -6.165088 0)
			(unlocked yes)
			(layer "F.SilkS")
			(effects
				(font
					(size 0.7874 0.5842)
					(thickness 0.1524)
				)
				(justify left)
			)
		)
		(property "Value" ""
			(at 0 0 90)
			(layer "F.Fab")
			(effects
				(font
					(size 1.27 1.27)
				)
			)
		)
		(duplicate_pad_numbers_are_jumpers no)
		(fp_line
			(start -0.8128 -2.6924)
			(end -0.8128 -3.5052)
			(stroke
				(width 0.1524)
				(type default)
			)
			(layer "F.SilkS")
		)
		(fp_line
			(start 1.299972 -2.29997)
			(end 1.016 -2.29997)
			(stroke
				(width 0.1524)
				(type default)
			)
			(layer "F.SilkS")
		)
		(fp_line
			(start -1.016 -2.29997)
			(end -1.299972 -2.29997)
			(stroke
				(width 0.1524)
				(type default)
			)
			(layer "F.SilkS")
		)
		(fp_line
			(start -1.299972 -2.29997)
			(end -1.299972 -2.015998)
			(stroke
				(width 0.1524)
				(type default)
			)
			(layer "F.SilkS")
		)
		(fp_line
			(start 1.299972 -2.015998)
			(end 1.299972 -2.29997)
			(stroke
				(width 0.1524)
				(type default)
			)
			(layer "F.SilkS")
		)
		(fp_line
			(start 1.6891 -1.8034)
			(end 2.0701 -1.8034)
			(stroke
				(width 0.1524)
				(type default)
			)
			(layer "F.SilkS")
		)
		(fp_line
			(start -1.6891 -0.2032)
			(end -2.0701 -0.2032)
			(stroke
				(width 0.1524)
				(type default)
			)
			(layer "F.SilkS")
		)
		(fp_line
			(start 2.5146 0.2032)
			(end 1.7018 0.2032)
			(stroke
				(width 0.1524)
				(type default)
			)
			(layer "F.SilkS")
		)
		(fp_line
			(start -1.7018 1.8034)
			(end -2.5146 1.8034)
			(stroke
				(width 0.1524)
				(type default)
			)
			(layer "F.SilkS")
		)
		(fp_line
			(start -1.299972 2.015998)
			(end -1.299972 2.29997)
			(stroke
				(width 0.1524)
				(type default)
			)
			(layer "F.SilkS")
		)
		(fp_line
			(start 1.299972 2.29997)
			(end 1.299972 2.015998)
			(stroke
				(width 0.1524)
				(type default)
			)
			(layer "F.SilkS")
		)
		(fp_line
			(start 1.016 2.29997)
			(end 1.299972 2.29997)
			(stroke
				(width 0.1524)
				(type default)
			)
			(layer "F.SilkS")
		)
		(fp_line
			(start -1.299972 2.29997)
			(end -1.016 2.29997)
			(stroke
				(width 0.1524)
				(type default)
			)
			(layer "F.SilkS")
		)
		(fp_line
			(start 0.7874 3.0861)
			(end 0.7874 2.7051)
			(stroke
				(width 0.1524)
				(type default)
			)
			(layer "F.SilkS")
		)
		(fp_poly
			(pts
				(xy -3.111246 -3.900678) (xy -3.829558 -3.182112) (xy -2.75209 -2.822956)
			)
			(stroke
				(width 0)
				(type default)
			)
			(fill yes)
			(layer "F.SilkS")
		)
		(fp_line
			(start -0.8128 -2.6924)
			(end -0.8128 -3.5052)
			(stroke
				(width 0.1)
				(type default)
			)
			(layer "F.Fab")
		)
		(fp_line
			(start 1.299972 -2.29997)
			(end -1.299972 -2.29997)
			(stroke
				(width 0.1)
				(type default)
			)
			(layer "F.Fab")
		)
		(fp_line
			(start -1.299972 -2.29997)
			(end -1.299972 2.29997)
			(stroke
				(width 0.1)
				(type default)
			)
			(layer "F.Fab")
		)
		(fp_line
			(start 1.6891 -1.8034)
			(end 2.0701 -1.8034)
			(stroke
				(width 0.1)
				(type default)
			)
			(layer "F.Fab")
		)
		(fp_line
			(start -1.6891 -0.2032)
			(end -2.0701 -0.2032)
			(stroke
				(width 0.1)
				(type default)
			)
			(layer "F.Fab")
		)
		(fp_line
			(start 2.5146 0.2032)
			(end 1.7018 0.2032)
			(stroke
				(width 0.1)
				(type default)
			)
			(layer "F.Fab")
		)
		(fp_line
			(start -1.7018 1.8034)
			(end -2.5146 1.8034)
			(stroke
				(width 0.1)
				(type default)
			)
			(layer "F.Fab")
		)
		(fp_line
			(start 1.299972 2.29997)
			(end 1.299972 -2.29997)
			(stroke
				(width 0.1)
				(type default)
			)
			(layer "F.Fab")
		)
		(fp_line
			(start -1.299972 2.29997)
			(end 1.299972 2.29997)
			(stroke
				(width 0.1)
				(type default)
			)
			(layer "F.Fab")
		)
		(fp_line
			(start 0.7874 3.0861)
			(end 0.7874 2.7051)
			(stroke
				(width 0.1)
				(type default)
			)
			(layer "F.Fab")
		)
		(fp_poly
			(pts
				(xy -2.7178 -2.308098) (xy -2.7178 -1.292098) (xy -1.7018 -1.800098)
			)
			(stroke
				(width 0)
				(type default)
			)
			(fill yes)
			(layer "F.Fab")
		)
		(fp_text user "26"
			(at 3.089402 -4.626356 0)
			(unlocked yes)
			(layer "F.SilkS")
			(effects
				(font
					(size 0.635 0.4064)
					(thickness 0.1524)
				)
			)
		)
		(fp_text user "25"
			(at 3.871468 -3.175 0)
			(unlocked yes)
			(layer "F.SilkS")
			(effects
				(font
					(size 0.635 0.4064)
					(thickness 0.1524)
				)
			)
		)
		(fp_text user "30"
			(at -2.718816 -2.527808 0)
			(unlocked yes)
			(layer "F.SilkS")
			(effects
				(font
					(size 0.635 0.4064)
					(thickness 0.1524)
				)
			)
		)
		(fp_text user "10"
			(at -4.436872 2.85496 0)
			(unlocked yes)
			(layer "F.SilkS")
			(effects
				(font
					(size 0.635 0.4064)
					(thickness 0.1524)
				)
			)
		)
		(fp_text user "16"
			(at 2.007108 2.98958 0)
			(unlocked yes)
			(layer "F.SilkS")
			(effects
				(font
					(size 0.635 0.4064)
					(thickness 0.1524)
				)
			)
		)
		(fp_text user "11"
			(at -1.746758 4.055364 0)
			(unlocked yes)
			(layer "F.SilkS")
			(effects
				(font
					(size 0.635 0.4064)
					(thickness 0.1524)
				)
			)
		)
		(fp_text user "15"
			(at 1.489964 4.071112 0)
			(unlocked yes)
			(layer "F.SilkS")
			(effects
				(font
					(size 0.635 0.4064)
					(thickness 0.1524)
				)
			)
		)
		(fp_text user "26"
			(at 1.0922 -3.071368 90)
			(unlocked yes)
			(layer "F.Fab")
			(effects
				(font
					(size 0.635 0.4064)
					(thickness 0.1524)
				)
			)
		)
		(fp_text user "30"
			(at -1.4478 -2.842768 90)
			(unlocked yes)
			(layer "F.Fab")
			(effects
				(font
					(size 0.635 0.4064)
					(thickness 0.1524)
				)
			)
		)
		(fp_text user "25"
			(at 1.979168 -2.4384 0)
			(unlocked yes)
			(layer "F.Fab")
			(effects
				(font
					(size 0.635 0.4064)
					(thickness 0.1524)
				)
			)
		)
		(fp_text user "16"
			(at 2.029968 2.0574 0)
			(unlocked yes)
			(layer "F.Fab")
			(effects
				(font
					(size 0.635 0.4064)
					(thickness 0.1524)
				)
			)
		)
		(fp_text user "10"
			(at -2.084832 2.3876 0)
			(unlocked yes)
			(layer "F.Fab")
			(effects
				(font
					(size 0.635 0.4064)
					(thickness 0.1524)
				)
			)
		)
		(fp_text user "15"
			(at 1.3716 2.948432 90)
			(unlocked yes)
			(layer "F.Fab")
			(effects
				(font
					(size 0.635 0.4064)
					(thickness 0.1524)
				)
			)
		)
		(fp_text user "11"
			(at -1.2192 3.075432 90)
			(unlocked yes)
			(layer "F.Fab")
			(effects
				(font
					(size 0.635 0.4064)
					(thickness 0.1524)
				)
			)
		)
		(pad "1" smd circle
			(at -1.249934 -1.800098)
			(size 0 0)
			(layers "F.Cu" "F.Mask" "F.Paste")
			(net "P3V3_AUX")
		)
		(pad "2" smd circle
			(at -1.249934 -1.400048)
			(size 0 0)
			(layers "F.Cu" "F.Mask" "F.Paste")
			(net "P2E_MB_BMC_TX_C_R1_DP<0>")
		)
		(pad "3" smd circle
			(at -1.249934 -0.999998)
			(size 0 0)
			(layers "F.Cu" "F.Mask" "F.Paste")
			(net "P2E_MB_BMC_TX_C_R1_DN<0>")
		)
		(pad "4" smd circle
			(at -1.249934 -0.599948)
			(size 0 0)
			(layers "F.Cu" "F.Mask" "F.Paste")
			(net "GND")
		)
		(pad "5" smd circle
			(at -1.249934 -0.199898)
			(size 0 0)
			(layers "F.Cu" "F.Mask" "F.Paste")
			(net "PU_TEST")
		)
		(pad "6" smd circle
			(at -1.249934 0.199898)
			(size 0 0)
			(layers "F.Cu" "F.Mask" "F.Paste")
			(net "GND")
		)
		(pad "7" smd circle
			(at -1.249934 0.599948)
			(size 0 0)
			(layers "F.Cu" "F.Mask" "F.Paste")
			(net "GND")
		)
		(pad "8" smd circle
			(at -1.249934 0.999998)
			(size 0 0)
			(layers "F.Cu" "F.Mask" "F.Paste")
			(net "P2E_MB_BMC_RX_BUF_C_DN<0>")
		)
		(pad "9" smd circle
			(at -1.249934 1.400048)
			(size 0 0)
			(layers "F.Cu" "F.Mask" "F.Paste")
			(net "P2E_MB_BMC_RX_BUF_C_DP<0>")
		)
		(pad "10" smd circle
			(at -1.249934 1.800098)
			(size 0 0)
			(layers "F.Cu" "F.Mask" "F.Paste")
			(net "P3V3_AUX")
		)
		(pad "11" smd circle
			(at -0.8001 2.249932 90)
			(size 0 0)
			(layers "F.Cu" "F.Mask" "F.Paste")
			(net "FM_P2E_EN_N")
		)
		(pad "12" smd circle
			(at -0.40005 2.249932 90)
			(size 0 0)
			(layers "F.Cu" "F.Mask" "F.Paste")
			(net "FM_P2E_SWB")
		)
		(pad "13" smd circle
			(at 0 2.249932 90)
			(size 0 0)
			(layers "F.Cu" "F.Mask" "F.Paste")
			(net "GND")
		)
		(pad "14" smd circle
			(at 0.40005 2.249932 90)
			(size 0 0)
			(layers "F.Cu" "F.Mask" "F.Paste")
			(net "FM_P2E_FGB")
		)
		(pad "15" smd circle
			(at 0.8001 2.249932 90)
			(size 0 0)
			(layers "F.Cu" "F.Mask" "F.Paste")
			(net "FM_P2E_EQB1")
		)
		(pad "16" smd circle
			(at 1.249934 1.800098 180)
			(size 0 0)
			(layers "F.Cu" "F.Mask" "F.Paste")
			(net "P3V3_AUX")
		)
		(pad "17" smd circle
			(at 1.249934 1.400048 180)
			(size 0 0)
			(layers "F.Cu" "F.Mask" "F.Paste")
			(net "P2E_MB_BMC_RX_R1_DP<0>")
		)
		(pad "18" smd circle
			(at 1.249934 0.999998 180)
			(size 0 0)
			(layers "F.Cu" "F.Mask" "F.Paste")
			(net "P2E_MB_BMC_RX_R1_DN<0>")
		)
		(pad "19" smd circle
			(at 1.249934 0.599948 180)
			(size 0 0)
			(layers "F.Cu" "F.Mask" "F.Paste")
			(net "GND")
		)
		(pad "20" smd circle
			(at 1.249934 0.199898 180)
			(size 0 0)
			(layers "F.Cu" "F.Mask" "F.Paste")
			(net "FM_P2E_EQB0")
		)
		(pad "21" smd circle
			(at 1.249934 -0.199898 180)
			(size 0 0)
			(layers "F.Cu" "F.Mask" "F.Paste")
			(net "FM_P2E_EQA0")
		)
		(pad "22" smd circle
			(at 1.249934 -0.599948 180)
			(size 0 0)
			(layers "F.Cu" "F.Mask" "F.Paste")
			(net "GND")
		)
		(pad "23" smd circle
			(at 1.249934 -0.999998 180)
			(size 0 0)
			(layers "F.Cu" "F.Mask" "F.Paste")
			(net "P2E_MB_BMC_TX_BUF_DN<0>")
		)
		(pad "24" smd circle
			(at 1.249934 -1.400048 180)
			(size 0 0)
			(layers "F.Cu" "F.Mask" "F.Paste")
			(net "P2E_MB_BMC_TX_BUF_DP<0>")
		)
		(pad "25" smd circle
			(at 1.249934 -1.800098 180)
			(size 0 0)
			(layers "F.Cu" "F.Mask" "F.Paste")
			(net "P3V3_AUX")
		)
		(pad "26" smd circle
			(at 0.8001 -2.249932 270)
			(size 0 0)
			(layers "F.Cu" "F.Mask" "F.Paste")
			(net "FM_P2E_EQA1")
		)
		(pad "27" smd circle
			(at 0.40005 -2.249932 270)
			(size 0 0)
			(layers "F.Cu" "F.Mask" "F.Paste")
			(net "FM_P2E_FGA")
		)
		(pad "28" smd circle
			(at 0 -2.249932 270)
			(size 0 0)
			(layers "F.Cu" "F.Mask" "F.Paste")
			(net "GND")
		)
		(pad "29" smd circle
			(at -0.40005 -2.249932 270)
			(size 0 0)
			(layers "F.Cu" "F.Mask" "F.Paste")
			(net "FM_P2E_SWA")
		)
		(pad "30" smd circle
			(at -0.8001 -2.249932 270)
			(size 0 0)
			(layers "F.Cu" "F.Mask" "F.Paste")
			(net "FM_P2E_MODE")
		)
		(pad "TH" smd rect
			(at 0 0 90)
			(size 1.2192 3.2004)
			(layers "F.Cu" "F.Mask" "F.Paste")
			(net "GND")
		)
		(zone
			(layer "F.Cu")
			(hatch none 0.5)
			(connect_pads
				(clearance 0)
			)
			(min_thickness 0.25)
			(keepout
				(tracks not_allowed)
				(vias allowed)
				(pads allowed)
				(copperpour not_allowed)
				(footprints allowed)
			)
			(placement
				(enabled no)
				(sheetname "")
			)
			(fill
				(thermal_gap 0.5)
				(thermal_bridge_width 0.5)
				(island_removal_mode 0)
			)
			(polygon
				(pts
					(xy 20.033996 -390.853676) (xy 20.262596 -390.853676) (xy 20.262596 -390.015476) (xy 23.564596 -390.015476)
					(xy 23.564596 -391.336276) (xy 20.262596 -391.336276) (xy 20.262596 -390.879076) (xy 20.033996 -390.879076)
					(xy 20.033996 -391.564876) (xy 23.793196 -391.564876) (xy 23.793196 -389.786876) (xy 20.033996 -389.786876)
				)
			)
		)
	)
	(footprint ""
		(layer "F.Cu")
		(at 73.94448 -161.107882 180)
		(property "Reference" "PR559"
			(at 0 0 180)
			(layer "F.SilkS")
			(hide yes)
			(effects
				(font
					(size 1.27 1.27)
				)
			)
		)
		(property "Value" ""
			(at 0 0 180)
			(layer "F.Fab")
			(effects
				(font
					(size 1.27 1.27)
				)
			)
		)
		(duplicate_pad_numbers_are_jumpers no)
		(fp_line
			(start 0.7874 0.4064)
			(end -0.7874 0.4064)
			(stroke
				(width 0.1524)
				(type default)
			)
			(layer "F.SilkS")
		)
		(fp_line
			(start 0.7874 -0.4064)
			(end 0.7874 0.4064)
			(stroke
				(width 0.1524)
				(type default)
			)
			(layer "F.SilkS")
		)
		(fp_line
			(start -0.7874 0.4064)
			(end -0.7874 -0.4064)
			(stroke
				(width 0.1524)
				(type default)
			)
			(layer "F.SilkS")
		)
		(fp_line
			(start -0.7874 -0.4064)
			(end 0.7874 -0.4064)
			(stroke
				(width 0.1524)
				(type default)
			)
			(layer "F.SilkS")
		)
		(fp_line
			(start 0.67945 0.3048)
			(end 0.120396 0.3048)
			(stroke
				(width 0.1)
				(type default)
			)
			(layer "F.Fab")
		)
		(fp_line
			(start 0.67945 -0.3048)
			(end 0.67945 0.3048)
			(stroke
				(width 0.1)
				(type default)
			)
			(layer "F.Fab")
		)
		(fp_line
			(start 0.12065 -0.2794)
			(end 0.12065 -0.3048)
			(stroke
				(width 0.1)
				(type default)
			)
			(layer "F.Fab")
		)
		(fp_line
			(start 0.12065 -0.3048)
			(end 0.67945 -0.3048)
			(stroke
				(width 0.1)
				(type default)
			)
			(layer "F.Fab")
		)
		(fp_line
			(start 0.120396 0.3048)
			(end 0.120396 0.2794)
			(stroke
				(width 0.1)
				(type default)
			)
			(layer "F.Fab")
		)
		(fp_line
			(start 0.120396 0.2794)
			(end -0.12065 0.2794)
			(stroke
				(width 0.1)
				(type default)
			)
			(layer "F.Fab")
		)
		(fp_line
			(start -0.12065 0.3048)
			(end -0.67945 0.3048)
			(stroke
				(width 0.1)
				(type default)
			)
			(layer "F.Fab")
		)
		(fp_line
			(start -0.12065 0.2794)
			(end -0.12065 0.3048)
			(stroke
				(width 0.1)
				(type default)
			)
			(layer "F.Fab")
		)
		(fp_line
			(start -0.12065 -0.2794)
			(end 0.12065 -0.2794)
			(stroke
				(width 0.1)
				(type default)
			)
			(layer "F.Fab")
		)
		(fp_line
			(start -0.12065 -0.305054)
			(end -0.12065 -0.2794)
			(stroke
				(width 0.1)
				(type default)
			)
			(layer "F.Fab")
		)
		(fp_line
			(start -0.67945 0.3048)
			(end -0.67945 -0.305054)
			(stroke
				(width 0.1)
				(type default)
			)
			(layer "F.Fab")
		)
		(fp_line
			(start -0.67945 -0.305054)
			(end -0.12065 -0.305054)
			(stroke
				(width 0.1)
				(type default)
			)
			(layer "F.Fab")
		)
		(pad "1" smd circle
			(at -0.40005 0 180)
			(size 0 0)
			(layers "F.Cu" "F.Mask" "F.Paste")
			(net "VSENSE_PVCCD_HV_CPU1_DP")
		)
		(pad "2" smd circle
			(at 0.40005 0 180)
			(size 0 0)
			(layers "F.Cu" "F.Mask" "F.Paste")
			(net "PVCCD_HV_CPU1")
		)
	)
	(footprint ""
		(layer "F.Cu")
		(at 119.508016 -260.36524 -90)
		(property "Reference" "C432"
			(at 0 0 270)
			(layer "F.SilkS")
			(hide yes)
			(effects
				(font
					(size 1.27 1.27)
				)
			)
		)
		(property "Value" ""
			(at 0 0 270)
			(layer "F.Fab")
			(effects
				(font
					(size 1.27 1.27)
				)
			)
		)
		(duplicate_pad_numbers_are_jumpers no)
		(fp_line
			(start -0.7874 0.4064)
			(end -0.7874 -0.4064)
			(stroke
				(width 0.1524)
				(type default)
			)
			(layer "F.SilkS")
		)
		(fp_line
			(start 0.7874 0.4064)
			(end -0.7874 0.4064)
			(stroke
				(width 0.1524)
				(type default)
			)
			(layer "F.SilkS")
		)
		(fp_line
			(start -0.7874 -0.4064)
			(end 0.7874 -0.4064)
			(stroke
				(width 0.1524)
				(type default)
			)
			(layer "F.SilkS")
		)
		(fp_line
			(start 0.7874 -0.4064)
			(end 0.7874 0.4064)
			(stroke
				(width 0.1524)
				(type default)
			)
			(layer "F.SilkS")
		)
		(fp_line
			(start -0.67945 0.3048)
			(end -0.67945 -0.305054)
			(stroke
				(width 0.1)
				(type default)
			)
			(layer "F.Fab")
		)
		(fp_line
			(start -0.12065 0.3048)
			(end -0.67945 0.3048)
			(stroke
				(width 0.1)
				(type default)
			)
			(layer "F.Fab")
		)
		(fp_line
			(start 0.120396 0.3048)
			(end 0.120396 0.2794)
			(stroke
				(width 0.1)
				(type default)
			)
			(layer "F.Fab")
		)
		(fp_line
			(start 0.67945 0.3048)
			(end 0.120396 0.3048)
			(stroke
				(width 0.1)
				(type default)
			)
			(layer "F.Fab")
		)
		(fp_line
			(start -0.12065 0.2794)
			(end -0.12065 0.3048)
			(stroke
				(width 0.1)
				(type default)
			)
			(layer "F.Fab")
		)
		(fp_line
			(start 0.120396 0.2794)
			(end -0.12065 0.2794)
			(stroke
				(width 0.1)
				(type default)
			)
			(layer "F.Fab")
		)
		(fp_line
			(start -0.12065 -0.2794)
			(end 0.12065 -0.2794)
			(stroke
				(width 0.1)
				(type default)
			)
			(layer "F.Fab")
		)
		(fp_line
			(start 0.12065 -0.2794)
			(end 0.12065 -0.3048)
			(stroke
				(width 0.1)
				(type default)
			)
			(layer "F.Fab")
		)
		(fp_line
			(start 0.12065 -0.3048)
			(end 0.67945 -0.3048)
			(stroke
				(width 0.1)
				(type default)
			)
			(layer "F.Fab")
		)
		(fp_line
			(start 0.67945 -0.3048)
			(end 0.67945 0.3048)
			(stroke
				(width 0.1)
				(type default)
			)
			(layer "F.Fab")
		)
		(fp_line
			(start -0.67945 -0.305054)
			(end -0.12065 -0.305054)
			(stroke
				(width 0.1)
				(type default)
			)
			(layer "F.Fab")
		)
		(fp_line
			(start -0.12065 -0.305054)
			(end -0.12065 -0.2794)
			(stroke
				(width 0.1)
				(type default)
			)
			(layer "F.Fab")
		)
		(pad "1" smd circle
			(at -0.40005 0 270)
			(size 0 0)
			(layers "F.Cu" "F.Mask" "F.Paste")
			(net "PVCCINFAON_CPU1")
		)
		(pad "2" smd circle
			(at 0.40005 0 270)
			(size 0 0)
			(layers "F.Cu" "F.Mask" "F.Paste")
			(net "GND")
		)
	)
	(footprint ""
		(layer "F.Cu")
		(at 40.960294 -17.623536 90)
		(property "Reference" "C824"
			(at 0 0 90)
			(layer "F.SilkS")
			(hide yes)
			(effects
				(font
					(size 1.27 1.27)
				)
			)
		)
		(property "Value" ""
			(at 0 0 90)
			(layer "F.Fab")
			(effects
				(font
					(size 1.27 1.27)
				)
			)
		)
		(duplicate_pad_numbers_are_jumpers no)
		(fp_line
			(start 0.299974 -0.150114)
			(end 0.299974 0.150114)
			(stroke
				(width 0.1)
				(type default)
			)
			(layer "F.Fab")
		)
		(fp_line
			(start -0.299974 -0.150114)
			(end 0.299974 -0.150114)
			(stroke
				(width 0.1)
				(type default)
			)
			(layer "F.Fab")
		)
		(fp_line
			(start 0.299974 0.150114)
			(end -0.299974 0.150114)
			(stroke
				(width 0.1)
				(type default)
			)
			(layer "F.Fab")
		)
		(fp_line
			(start -0.299974 0.150114)
			(end -0.299974 -0.150114)
			(stroke
				(width 0.1)
				(type default)
			)
			(layer "F.Fab")
		)
		(pad "1" smd rect
			(at -0.2667 0 90)
			(size 0.3048 0.381)
			(layers "F.Cu" "F.Mask" "F.Paste")
			(net "P5E_CPU1_PE1_TX_C_DN<6>")
		)
		(pad "2" smd rect
			(at 0.2667 0 90)
			(size 0.3048 0.381)
			(layers "F.Cu" "F.Mask" "F.Paste")
			(net "P5E_CPU1_PE1_TX_DN<6>")
		)
	)
	(footprint ""
		(layer "F.Cu")
		(at 86.059518 -408.517344 -90)
		(property "Reference" "C684"
			(at 0 0 270)
			(layer "F.SilkS")
			(hide yes)
			(effects
				(font
					(size 1.27 1.27)
				)
			)
		)
		(property "Value" ""
			(at 0 0 270)
			(layer "F.Fab")
			(effects
				(font
					(size 1.27 1.27)
				)
			)
		)
		(duplicate_pad_numbers_are_jumpers no)
		(fp_line
			(start -0.299974 0.150114)
			(end -0.299974 -0.150114)
			(stroke
				(width 0.1)
				(type default)
			)
			(layer "F.Fab")
		)
		(fp_line
			(start 0.299974 0.150114)
			(end -0.299974 0.150114)
			(stroke
				(width 0.1)
				(type default)
			)
			(layer "F.Fab")
		)
		(fp_line
			(start -0.299974 -0.150114)
			(end 0.299974 -0.150114)
			(stroke
				(width 0.1)
				(type default)
			)
			(layer "F.Fab")
		)
		(fp_line
			(start 0.299974 -0.150114)
			(end 0.299974 0.150114)
			(stroke
				(width 0.1)
				(type default)
			)
			(layer "F.Fab")
		)
		(pad "1" smd rect
			(at -0.2667 0 270)
			(size 0.3048 0.381)
			(layers "F.Cu" "F.Mask" "F.Paste")
			(net "P5E_CPU1_PE4_TX_C_DN<12>")
		)
		(pad "2" smd rect
			(at 0.2667 0 270)
			(size 0.3048 0.381)
			(layers "F.Cu" "F.Mask" "F.Paste")
			(net "P5E_CPU1_PE4_TX_DN<12>")
		)
	)
	(footprint ""
		(layer "F.Cu")
		(at 164.251894 -34.164524)
		(property "Reference" "R4449"
			(at 0 0 0)
			(layer "F.SilkS")
			(hide yes)
			(effects
				(font
					(size 1.27 1.27)
				)
			)
		)
		(property "Value" ""
			(at 0 0 0)
			(layer "F.Fab")
			(effects
				(font
					(size 1.27 1.27)
				)
			)
		)
		(duplicate_pad_numbers_are_jumpers no)
		(fp_line
			(start -0.7874 -0.4064)
			(end 0.7874 -0.4064)
			(stroke
				(width 0.1524)
				(type default)
			)
			(layer "F.SilkS")
		)
		(fp_line
			(start -0.7874 0.4064)
			(end -0.7874 -0.4064)
			(stroke
				(width 0.1524)
				(type default)
			)
			(layer "F.SilkS")
		)
		(fp_line
			(start 0.7874 -0.4064)
			(end 0.7874 0.4064)
			(stroke
				(width 0.1524)
				(type default)
			)
			(layer "F.SilkS")
		)
		(fp_line
			(start 0.7874 0.4064)
			(end -0.7874 0.4064)
			(stroke
				(width 0.1524)
				(type default)
			)
			(layer "F.SilkS")
		)
		(fp_line
			(start -0.67945 -0.305054)
			(end -0.12065 -0.305054)
			(stroke
				(width 0.1)
				(type default)
			)
			(layer "F.Fab")
		)
		(fp_line
			(start -0.67945 0.3048)
			(end -0.67945 -0.305054)
			(stroke
				(width 0.1)
				(type default)
			)
			(layer "F.Fab")
		)
		(fp_line
			(start -0.12065 -0.305054)
			(end -0.12065 -0.2794)
			(stroke
				(width 0.1)
				(type default)
			)
			(layer "F.Fab")
		)
		(fp_line
			(start -0.12065 -0.2794)
			(end 0.12065 -0.2794)
			(stroke
				(width 0.1)
				(type default)
			)
			(layer "F.Fab")
		)
		(fp_line
			(start -0.12065 0.2794)
			(end -0.12065 0.3048)
			(stroke
				(width 0.1)
				(type default)
			)
			(layer "F.Fab")
		)
		(fp_line
			(start -0.12065 0.3048)
			(end -0.67945 0.3048)
			(stroke
				(width 0.1)
				(type default)
			)
			(layer "F.Fab")
		)
		(fp_line
			(start 0.120396 0.2794)
			(end -0.12065 0.2794)
			(stroke
				(width 0.1)
				(type default)
			)
			(layer "F.Fab")
		)
		(fp_line
			(start 0.120396 0.3048)
			(end 0.120396 0.2794)
			(stroke
				(width 0.1)
				(type default)
			)
			(layer "F.Fab")
		)
		(fp_line
			(start 0.12065 -0.3048)
			(end 0.67945 -0.3048)
			(stroke
				(width 0.1)
				(type default)
			)
			(layer "F.Fab")
		)
		(fp_line
			(start 0.12065 -0.2794)
			(end 0.12065 -0.3048)
			(stroke
				(width 0.1)
				(type default)
			)
			(layer "F.Fab")
		)
		(fp_line
			(start 0.67945 -0.3048)
			(end 0.67945 0.3048)
			(stroke
				(width 0.1)
				(type default)
			)
			(layer "F.Fab")
		)
		(fp_line
			(start 0.67945 0.3048)
			(end 0.120396 0.3048)
			(stroke
				(width 0.1)
				(type default)
			)
			(layer "F.Fab")
		)
		(pad "1" smd circle
			(at -0.40005 0)
			(size 0 0)
			(layers "F.Cu" "F.Mask" "F.Paste")
			(net "USB_HUB_2_PSELF")
		)
		(pad "2" smd circle
			(at 0.40005 0)
			(size 0 0)
			(layers "F.Cu" "F.Mask" "F.Paste")
			(net "GND")
		)
	)
	(footprint ""
		(layer "F.Cu")
		(at 454.847452 -21.302218 90)
		(property "Reference" "R3799"
			(at 0 0 90)
			(layer "F.SilkS")
			(hide yes)
			(effects
				(font
					(size 1.27 1.27)
				)
			)
		)
		(property "Value" ""
			(at 0 0 90)
			(layer "F.Fab")
			(effects
				(font
					(size 1.27 1.27)
				)
			)
		)
		(duplicate_pad_numbers_are_jumpers no)
		(fp_line
			(start 0.7874 -0.4064)
			(end 0.7874 0.4064)
			(stroke
				(width 0.1524)
				(type default)
			)
			(layer "F.SilkS")
		)
		(fp_line
			(start -0.7874 -0.4064)
			(end 0.7874 -0.4064)
			(stroke
				(width 0.1524)
				(type default)
			)
			(layer "F.SilkS")
		)
		(fp_line
			(start 0.7874 0.4064)
			(end -0.7874 0.4064)
			(stroke
				(width 0.1524)
				(type default)
			)
			(layer "F.SilkS")
		)
		(fp_line
			(start -0.7874 0.4064)
			(end -0.7874 -0.4064)
			(stroke
				(width 0.1524)
				(type default)
			)
			(layer "F.SilkS")
		)
		(fp_line
			(start -0.12065 -0.305054)
			(end -0.12065 -0.2794)
			(stroke
				(width 0.1)
				(type default)
			)
			(layer "F.Fab")
		)
		(fp_line
			(start -0.67945 -0.305054)
			(end -0.12065 -0.305054)
			(stroke
				(width 0.1)
				(type default)
			)
			(layer "F.Fab")
		)
		(fp_line
			(start 0.67945 -0.3048)
			(end 0.67945 0.3048)
			(stroke
				(width 0.1)
				(type default)
			)
			(layer "F.Fab")
		)
		(fp_line
			(start 0.12065 -0.3048)
			(end 0.67945 -0.3048)
			(stroke
				(width 0.1)
				(type default)
			)
			(layer "F.Fab")
		)
		(fp_line
			(start 0.12065 -0.2794)
			(end 0.12065 -0.3048)
			(stroke
				(width 0.1)
				(type default)
			)
			(layer "F.Fab")
		)
		(fp_line
			(start -0.12065 -0.2794)
			(end 0.12065 -0.2794)
			(stroke
				(width 0.1)
				(type default)
			)
			(layer "F.Fab")
		)
		(fp_line
			(start 0.120396 0.2794)
			(end -0.12065 0.2794)
			(stroke
				(width 0.1)
				(type default)
			)
			(layer "F.Fab")
		)
		(fp_line
			(start -0.12065 0.2794)
			(end -0.12065 0.3048)
			(stroke
				(width 0.1)
				(type default)
			)
			(layer "F.Fab")
		)
		(fp_line
			(start 0.67945 0.3048)
			(end 0.120396 0.3048)
			(stroke
				(width 0.1)
				(type default)
			)
			(layer "F.Fab")
		)
		(fp_line
			(start 0.120396 0.3048)
			(end 0.120396 0.2794)
			(stroke
				(width 0.1)
				(type default)
			)
			(layer "F.Fab")
		)
		(fp_line
			(start -0.12065 0.3048)
			(end -0.67945 0.3048)
			(stroke
				(width 0.1)
				(type default)
			)
			(layer "F.Fab")
		)
		(fp_line
			(start -0.67945 0.3048)
			(end -0.67945 -0.305054)
			(stroke
				(width 0.1)
				(type default)
			)
			(layer "F.Fab")
		)
		(pad "1" smd circle
			(at -0.40005 0 90)
			(size 0 0)
			(layers "F.Cu" "F.Mask" "F.Paste")
			(net "P3V3_AUX")
		)
		(pad "2" smd circle
			(at 0.40005 0 90)
			(size 0 0)
			(layers "F.Cu" "F.Mask" "F.Paste")
			(net "P12V_OCP_FAULT_1")
		)
	)
	(footprint ""
		(layer "F.Cu")
		(at 176.17948 -427.446948)
		(property "Reference" "R2926"
			(at 0 0 0)
			(layer "F.SilkS")
			(hide yes)
			(effects
				(font
					(size 1.27 1.27)
				)
			)
		)
		(property "Value" ""
			(at 0 0 0)
			(layer "F.Fab")
			(effects
				(font
					(size 1.27 1.27)
				)
			)
		)
		(duplicate_pad_numbers_are_jumpers no)
		(fp_line
			(start -0.7874 -0.4064)
			(end 0.7874 -0.4064)
			(stroke
				(width 0.1524)
				(type default)
			)
			(layer "F.SilkS")
		)
		(fp_line
			(start -0.7874 0.4064)
			(end -0.7874 -0.4064)
			(stroke
				(width 0.1524)
				(type default)
			)
			(layer "F.SilkS")
		)
		(fp_line
			(start 0.7874 -0.4064)
			(end 0.7874 0.4064)
			(stroke
				(width 0.1524)
				(type default)
			)
			(layer "F.SilkS")
		)
		(fp_line
			(start 0.7874 0.4064)
			(end -0.7874 0.4064)
			(stroke
				(width 0.1524)
				(type default)
			)
			(layer "F.SilkS")
		)
		(fp_line
			(start -0.67945 -0.305054)
			(end -0.12065 -0.305054)
			(stroke
				(width 0.1)
				(type default)
			)
			(layer "F.Fab")
		)
		(fp_line
			(start -0.67945 0.3048)
			(end -0.67945 -0.305054)
			(stroke
				(width 0.1)
				(type default)
			)
			(layer "F.Fab")
		)
		(fp_line
			(start -0.12065 -0.305054)
			(end -0.12065 -0.2794)
			(stroke
				(width 0.1)
				(type default)
			)
			(layer "F.Fab")
		)
		(fp_line
			(start -0.12065 -0.2794)
			(end 0.12065 -0.2794)
			(stroke
				(width 0.1)
				(type default)
			)
			(layer "F.Fab")
		)
		(fp_line
			(start -0.12065 0.2794)
			(end -0.12065 0.3048)
			(stroke
				(width 0.1)
				(type default)
			)
			(layer "F.Fab")
		)
		(fp_line
			(start -0.12065 0.3048)
			(end -0.67945 0.3048)
			(stroke
				(width 0.1)
				(type default)
			)
			(layer "F.Fab")
		)
		(fp_line
			(start 0.120396 0.2794)
			(end -0.12065 0.2794)
			(stroke
				(width 0.1)
				(type default)
			)
			(layer "F.Fab")
		)
		(fp_line
			(start 0.120396 0.3048)
			(end 0.120396 0.2794)
			(stroke
				(width 0.1)
				(type default)
			)
			(layer "F.Fab")
		)
		(fp_line
			(start 0.12065 -0.3048)
			(end 0.67945 -0.3048)
			(stroke
				(width 0.1)
				(type default)
			)
			(layer "F.Fab")
		)
		(fp_line
			(start 0.12065 -0.2794)
			(end 0.12065 -0.3048)
			(stroke
				(width 0.1)
				(type default)
			)
			(layer "F.Fab")
		)
		(fp_line
			(start 0.67945 -0.3048)
			(end 0.67945 0.3048)
			(stroke
				(width 0.1)
				(type default)
			)
			(layer "F.Fab")
		)
		(fp_line
			(start 0.67945 0.3048)
			(end 0.120396 0.3048)
			(stroke
				(width 0.1)
				(type default)
			)
			(layer "F.Fab")
		)
		(pad "1" smd circle
			(at -0.40005 0)
			(size 0 0)
			(layers "F.Cu" "F.Mask" "F.Paste")
			(net "BMC_MONITER_BUF_R")
		)
		(pad "2" smd circle
			(at 0.40005 0)
			(size 0 0)
			(layers "F.Cu" "F.Mask" "F.Paste")
			(net "GND")
		)
	)
	(footprint ""
		(layer "F.Cu")
		(at 152.978612 -31.341568 90)
		(property "Reference" "R4451"
			(at 0 0 90)
			(layer "F.SilkS")
			(hide yes)
			(effects
				(font
					(size 1.27 1.27)
				)
			)
		)
		(property "Value" ""
			(at 0 0 90)
			(layer "F.Fab")
			(effects
				(font
					(size 1.27 1.27)
				)
			)
		)
		(duplicate_pad_numbers_are_jumpers no)
		(fp_line
			(start 0.7874 -0.4064)
			(end 0.7874 0.4064)
			(stroke
				(width 0.1524)
				(type default)
			)
			(layer "F.SilkS")
		)
		(fp_line
			(start -0.7874 -0.4064)
			(end 0.7874 -0.4064)
			(stroke
				(width 0.1524)
				(type default)
			)
			(layer "F.SilkS")
		)
		(fp_line
			(start 0.7874 0.4064)
			(end -0.7874 0.4064)
			(stroke
				(width 0.1524)
				(type default)
			)
			(layer "F.SilkS")
		)
		(fp_line
			(start -0.7874 0.4064)
			(end -0.7874 -0.4064)
			(stroke
				(width 0.1524)
				(type default)
			)
			(layer "F.SilkS")
		)
		(fp_line
			(start -0.12065 -0.305054)
			(end -0.12065 -0.2794)
			(stroke
				(width 0.1)
				(type default)
			)
			(layer "F.Fab")
		)
		(fp_line
			(start -0.67945 -0.305054)
			(end -0.12065 -0.305054)
			(stroke
				(width 0.1)
				(type default)
			)
			(layer "F.Fab")
		)
		(fp_line
			(start 0.67945 -0.3048)
			(end 0.67945 0.3048)
			(stroke
				(width 0.1)
				(type default)
			)
			(layer "F.Fab")
		)
		(fp_line
			(start 0.12065 -0.3048)
			(end 0.67945 -0.3048)
			(stroke
				(width 0.1)
				(type default)
			)
			(layer "F.Fab")
		)
		(fp_line
			(start 0.12065 -0.2794)
			(end 0.12065 -0.3048)
			(stroke
				(width 0.1)
				(type default)
			)
			(layer "F.Fab")
		)
		(fp_line
			(start -0.12065 -0.2794)
			(end 0.12065 -0.2794)
			(stroke
				(width 0.1)
				(type default)
			)
			(layer "F.Fab")
		)
		(fp_line
			(start 0.120396 0.2794)
			(end -0.12065 0.2794)
			(stroke
				(width 0.1)
				(type default)
			)
			(layer "F.Fab")
		)
		(fp_line
			(start -0.12065 0.2794)
			(end -0.12065 0.3048)
			(stroke
				(width 0.1)
				(type default)
			)
			(layer "F.Fab")
		)
		(fp_line
			(start 0.67945 0.3048)
			(end 0.120396 0.3048)
			(stroke
				(width 0.1)
				(type default)
			)
			(layer "F.Fab")
		)
		(fp_line
			(start 0.120396 0.3048)
			(end 0.120396 0.2794)
			(stroke
				(width 0.1)
				(type default)
			)
			(layer "F.Fab")
		)
		(fp_line
			(start -0.12065 0.3048)
			(end -0.67945 0.3048)
			(stroke
				(width 0.1)
				(type default)
			)
			(layer "F.Fab")
		)
		(fp_line
			(start -0.67945 0.3048)
			(end -0.67945 -0.305054)
			(stroke
				(width 0.1)
				(type default)
			)
			(layer "F.Fab")
		)
		(pad "1" smd circle
			(at -0.40005 0 90)
			(size 0 0)
			(layers "F.Cu" "F.Mask" "F.Paste")
			(net "RST_USB_HUB_N")
		)
		(pad "2" smd circle
			(at 0.40005 0 90)
			(size 0 0)
			(layers "F.Cu" "F.Mask" "F.Paste")
			(net "RST_USB_HUB_2_R_N")
		)
	)
	(footprint ""
		(layer "F.Cu")
		(at 198.9963 -131.694428 -90)
		(property "Reference" "R2528"
			(at 0 0 270)
			(layer "F.SilkS")
			(hide yes)
			(effects
				(font
					(size 1.27 1.27)
				)
			)
		)
		(property "Value" ""
			(at 0 0 270)
			(layer "F.Fab")
			(effects
				(font
					(size 1.27 1.27)
				)
			)
		)
		(duplicate_pad_numbers_are_jumpers no)
		(fp_line
			(start -0.7874 0.4064)
			(end -0.7874 -0.4064)
			(stroke
				(width 0.1524)
				(type default)
			)
			(layer "F.SilkS")
		)
		(fp_line
			(start 0.7874 0.4064)
			(end -0.7874 0.4064)
			(stroke
				(width 0.1524)
				(type default)
			)
			(layer "F.SilkS")
		)
		(fp_line
			(start -0.7874 -0.4064)
			(end 0.7874 -0.4064)
			(stroke
				(width 0.1524)
				(type default)
			)
			(layer "F.SilkS")
		)
		(fp_line
			(start 0.7874 -0.4064)
			(end 0.7874 0.4064)
			(stroke
				(width 0.1524)
				(type default)
			)
			(layer "F.SilkS")
		)
		(fp_line
			(start -0.67945 0.3048)
			(end -0.67945 -0.305054)
			(stroke
				(width 0.1)
				(type default)
			)
			(layer "F.Fab")
		)
		(fp_line
			(start -0.12065 0.3048)
			(end -0.67945 0.3048)
			(stroke
				(width 0.1)
				(type default)
			)
			(layer "F.Fab")
		)
		(fp_line
			(start 0.120396 0.3048)
			(end 0.120396 0.2794)
			(stroke
				(width 0.1)
				(type default)
			)
			(layer "F.Fab")
		)
		(fp_line
			(start 0.67945 0.3048)
			(end 0.120396 0.3048)
			(stroke
				(width 0.1)
				(type default)
			)
			(layer "F.Fab")
		)
		(fp_line
			(start -0.12065 0.2794)
			(end -0.12065 0.3048)
			(stroke
				(width 0.1)
				(type default)
			)
			(layer "F.Fab")
		)
		(fp_line
			(start 0.120396 0.2794)
			(end -0.12065 0.2794)
			(stroke
				(width 0.1)
				(type default)
			)
			(layer "F.Fab")
		)
		(fp_line
			(start -0.12065 -0.2794)
			(end 0.12065 -0.2794)
			(stroke
				(width 0.1)
				(type default)
			)
			(layer "F.Fab")
		)
		(fp_line
			(start 0.12065 -0.2794)
			(end 0.12065 -0.3048)
			(stroke
				(width 0.1)
				(type default)
			)
			(layer "F.Fab")
		)
		(fp_line
			(start 0.12065 -0.3048)
			(end 0.67945 -0.3048)
			(stroke
				(width 0.1)
				(type default)
			)
			(layer "F.Fab")
		)
		(fp_line
			(start 0.67945 -0.3048)
			(end 0.67945 0.3048)
			(stroke
				(width 0.1)
				(type default)
			)
			(layer "F.Fab")
		)
		(fp_line
			(start -0.67945 -0.305054)
			(end -0.12065 -0.305054)
			(stroke
				(width 0.1)
				(type default)
			)
			(layer "F.Fab")
		)
		(fp_line
			(start -0.12065 -0.305054)
			(end -0.12065 -0.2794)
			(stroke
				(width 0.1)
				(type default)
			)
			(layer "F.Fab")
		)
		(pad "1" smd circle
			(at -0.40005 0 270)
			(size 0 0)
			(layers "F.Cu" "F.Mask" "F.Paste")
			(net "P12V_AUX")
		)
		(pad "2" smd circle
			(at 0.40005 0 270)
			(size 0 0)
			(layers "F.Cu" "F.Mask" "F.Paste")
			(net "FM_P12V_HSC_EN_N")
		)
	)
	(footprint ""
		(layer "F.Cu")
		(at 88.442038 -179.267866 180)
		(property "Reference" "R4260"
			(at 0 0 180)
			(layer "F.SilkS")
			(hide yes)
			(effects
				(font
					(size 1.27 1.27)
				)
			)
		)
		(property "Value" ""
			(at 0 0 180)
			(layer "F.Fab")
			(effects
				(font
					(size 1.27 1.27)
				)
			)
		)
		(duplicate_pad_numbers_are_jumpers no)
		(fp_line
			(start 0.7874 0.4064)
			(end -0.7874 0.4064)
			(stroke
				(width 0.1524)
				(type default)
			)
			(layer "F.SilkS")
		)
		(fp_line
			(start 0.7874 -0.4064)
			(end 0.7874 0.4064)
			(stroke
				(width 0.1524)
				(type default)
			)
			(layer "F.SilkS")
		)
		(fp_line
			(start -0.7874 0.4064)
			(end -0.7874 -0.4064)
			(stroke
				(width 0.1524)
				(type default)
			)
			(layer "F.SilkS")
		)
		(fp_line
			(start -0.7874 -0.4064)
			(end 0.7874 -0.4064)
			(stroke
				(width 0.1524)
				(type default)
			)
			(layer "F.SilkS")
		)
		(fp_line
			(start 0.67945 0.3048)
			(end 0.120396 0.3048)
			(stroke
				(width 0.1)
				(type default)
			)
			(layer "F.Fab")
		)
		(fp_line
			(start 0.67945 -0.3048)
			(end 0.67945 0.3048)
			(stroke
				(width 0.1)
				(type default)
			)
			(layer "F.Fab")
		)
		(fp_line
			(start 0.12065 -0.2794)
			(end 0.12065 -0.3048)
			(stroke
				(width 0.1)
				(type default)
			)
			(layer "F.Fab")
		)
		(fp_line
			(start 0.12065 -0.3048)
			(end 0.67945 -0.3048)
			(stroke
				(width 0.1)
				(type default)
			)
			(layer "F.Fab")
		)
		(fp_line
			(start 0.120396 0.3048)
			(end 0.120396 0.2794)
			(stroke
				(width 0.1)
				(type default)
			)
			(layer "F.Fab")
		)
		(fp_line
			(start 0.120396 0.2794)
			(end -0.12065 0.2794)
			(stroke
				(width 0.1)
				(type default)
			)
			(layer "F.Fab")
		)
		(fp_line
			(start -0.12065 0.3048)
			(end -0.67945 0.3048)
			(stroke
				(width 0.1)
				(type default)
			)
			(layer "F.Fab")
		)
		(fp_line
			(start -0.12065 0.2794)
			(end -0.12065 0.3048)
			(stroke
				(width 0.1)
				(type default)
			)
			(layer "F.Fab")
		)
		(fp_line
			(start -0.12065 -0.2794)
			(end 0.12065 -0.2794)
			(stroke
				(width 0.1)
				(type default)
			)
			(layer "F.Fab")
		)
		(fp_line
			(start -0.12065 -0.305054)
			(end -0.12065 -0.2794)
			(stroke
				(width 0.1)
				(type default)
			)
			(layer "F.Fab")
		)
		(fp_line
			(start -0.67945 0.3048)
			(end -0.67945 -0.305054)
			(stroke
				(width 0.1)
				(type default)
			)
			(layer "F.Fab")
		)
		(fp_line
			(start -0.67945 -0.305054)
			(end -0.12065 -0.305054)
			(stroke
				(width 0.1)
				(type default)
			)
			(layer "F.Fab")
		)
		(pad "1" smd circle
			(at -0.40005 0 180)
			(size 0 0)
			(layers "F.Cu" "F.Mask" "F.Paste")
			(net "PVNN_TERM_CPU0")
		)
		(pad "2" smd circle
			(at 0.40005 0 180)
			(size 0 0)
			(layers "F.Cu" "F.Mask" "F.Paste")
			(net "PD_CPU1_BIST_ENABLE")
		)
	)
	(footprint ""
		(layer "F.Cu")
		(at 21.348192 -399.532094 90)
		(property "Reference" "R3278"
			(at 0 0 90)
			(layer "F.SilkS")
			(hide yes)
			(effects
				(font
					(size 1.27 1.27)
				)
			)
		)
		(property "Value" ""
			(at 0 0 90)
			(layer "F.Fab")
			(effects
				(font
					(size 1.27 1.27)
				)
			)
		)
		(duplicate_pad_numbers_are_jumpers no)
		(fp_line
			(start 0.7874 -0.4064)
			(end 0.7874 0.4064)
			(stroke
				(width 0.1524)
				(type default)
			)
			(layer "F.SilkS")
		)
		(fp_line
			(start -0.7874 -0.4064)
			(end 0.7874 -0.4064)
			(stroke
				(width 0.1524)
				(type default)
			)
			(layer "F.SilkS")
		)
		(fp_line
			(start 0.7874 0.4064)
			(end -0.7874 0.4064)
			(stroke
				(width 0.1524)
				(type default)
			)
			(layer "F.SilkS")
		)
		(fp_line
			(start -0.7874 0.4064)
			(end -0.7874 -0.4064)
			(stroke
				(width 0.1524)
				(type default)
			)
			(layer "F.SilkS")
		)
		(fp_line
			(start -0.12065 -0.305054)
			(end -0.12065 -0.2794)
			(stroke
				(width 0.1)
				(type default)
			)
			(layer "F.Fab")
		)
		(fp_line
			(start -0.67945 -0.305054)
			(end -0.12065 -0.305054)
			(stroke
				(width 0.1)
				(type default)
			)
			(layer "F.Fab")
		)
		(fp_line
			(start 0.67945 -0.3048)
			(end 0.67945 0.3048)
			(stroke
				(width 0.1)
				(type default)
			)
			(layer "F.Fab")
		)
		(fp_line
			(start 0.12065 -0.3048)
			(end 0.67945 -0.3048)
			(stroke
				(width 0.1)
				(type default)
			)
			(layer "F.Fab")
		)
		(fp_line
			(start 0.12065 -0.2794)
			(end 0.12065 -0.3048)
			(stroke
				(width 0.1)
				(type default)
			)
			(layer "F.Fab")
		)
		(fp_line
			(start -0.12065 -0.2794)
			(end 0.12065 -0.2794)
			(stroke
				(width 0.1)
				(type default)
			)
			(layer "F.Fab")
		)
		(fp_line
			(start 0.120396 0.2794)
			(end -0.12065 0.2794)
			(stroke
				(width 0.1)
				(type default)
			)
			(layer "F.Fab")
		)
		(fp_line
			(start -0.12065 0.2794)
			(end -0.12065 0.3048)
			(stroke
				(width 0.1)
				(type default)
			)
			(layer "F.Fab")
		)
		(fp_line
			(start 0.67945 0.3048)
			(end 0.120396 0.3048)
			(stroke
				(width 0.1)
				(type default)
			)
			(layer "F.Fab")
		)
		(fp_line
			(start 0.120396 0.3048)
			(end 0.120396 0.2794)
			(stroke
				(width 0.1)
				(type default)
			)
			(layer "F.Fab")
		)
		(fp_line
			(start -0.12065 0.3048)
			(end -0.67945 0.3048)
			(stroke
				(width 0.1)
				(type default)
			)
			(layer "F.Fab")
		)
		(fp_line
			(start -0.67945 0.3048)
			(end -0.67945 -0.305054)
			(stroke
				(width 0.1)
				(type default)
			)
			(layer "F.Fab")
		)
		(pad "1" smd circle
			(at -0.40005 0 90)
			(size 0 0)
			(layers "F.Cu" "F.Mask" "F.Paste")
			(net "FM_P2E_EQA0")
		)
		(pad "2" smd circle
			(at 0.40005 0 90)
			(size 0 0)
			(layers "F.Cu" "F.Mask" "F.Paste")
			(net "GND")
		)
	)
	(footprint ""
		(layer "F.Cu")
		(at 13.12672 -74.846688)
		(property "Reference" "U242"
			(at 2.69494 1.000252 0)
			(unlocked yes)
			(layer "F.SilkS")
			(effects
				(font
					(size 0.7874 0.5842)
					(thickness 0.1524)
				)
				(justify left)
			)
		)
		(property "Value" ""
			(at 0 0 0)
			(layer "F.Fab")
			(effects
				(font
					(size 1.27 1.27)
				)
			)
		)
		(duplicate_pad_numbers_are_jumpers no)
		(fp_line
			(start -1.207008 -1.549908)
			(end -1.207008 1.549908)
			(stroke
				(width 0.1524)
				(type default)
			)
			(layer "F.SilkS")
		)
		(fp_line
			(start -1.207008 1.549908)
			(end 1.207008 1.549908)
			(stroke
				(width 0.1524)
				(type default)
			)
			(layer "F.SilkS")
		)
		(fp_line
			(start -0.762508 -1.549908)
			(end -1.207008 -1.549908)
			(stroke
				(width 0.1524)
				(type default)
			)
			(layer "F.SilkS")
		)
		(fp_line
			(start 0 -0.635)
			(end -0.762508 -1.549908)
			(stroke
				(width 0.1524)
				(type default)
			)
			(layer "F.SilkS")
		)
		(fp_line
			(start 0.762508 -1.549908)
			(end 0 -0.635)
			(stroke
				(width 0.1524)
				(type default)
			)
			(layer "F.SilkS")
		)
		(fp_line
			(start 1.207008 -1.549908)
			(end 0.762508 -1.549908)
			(stroke
				(width 0.1524)
				(type default)
			)
			(layer "F.SilkS")
		)
		(fp_line
			(start 1.207008 1.549908)
			(end 1.207008 -1.549908)
			(stroke
				(width 0.1524)
				(type default)
			)
			(layer "F.SilkS")
		)
		(fp_poly
			(pts
				(xy -1.41351 -2.42062) (xy -1.92151 -1.40462) (xy -2.42951 -2.42062)
			)
			(stroke
				(width 0)
				(type default)
			)
			(fill yes)
			(layer "F.SilkS")
		)
		(fp_line
			(start -1.549908 -1.549908)
			(end -1.549908 1.549908)
			(stroke
				(width 0.1)
				(type default)
			)
			(layer "F.Fab")
		)
		(fp_line
			(start -1.549908 1.549908)
			(end 1.549908 1.549908)
			(stroke
				(width 0.1)
				(type default)
			)
			(layer "F.Fab")
		)
		(fp_line
			(start 1.549908 -1.549908)
			(end -1.549908 -1.549908)
			(stroke
				(width 0.1)
				(type default)
			)
			(layer "F.Fab")
		)
		(fp_line
			(start 1.549908 1.549908)
			(end 1.549908 -1.549908)
			(stroke
				(width 0.1)
				(type default)
			)
			(layer "F.Fab")
		)
		(fp_poly
			(pts
				(xy -3.4036 -1.53289) (xy -3.4036 -0.51689) (xy -2.3876 -1.02489)
			)
			(stroke
				(width 0)
				(type default)
			)
			(fill yes)
			(layer "F.Fab")
		)
		(pad "1" smd rect
			(at -1.774952 -1.02489 270)
			(size 0.508 0.8636)
			(layers "F.Cu" "F.Mask" "F.Paste")
			(net "OCP_SFF_PRSNT01_R_N")
		)
		(pad "2" smd rect
			(at -1.774952 -0.32512 270)
			(size 0.4064 0.8636)
			(layers "F.Cu" "F.Mask" "F.Paste")
			(net "OCP_SFF_PRSNT23_R_N")
		)
		(pad "3" smd rect
			(at -1.774952 0.32512 270)
			(size 0.4064 0.8636)
			(layers "F.Cu" "F.Mask" "F.Paste")
			(net "OCP_V3_2_PRSNT_ALL_R_N")
		)
		(pad "4" smd rect
			(at -1.774952 1.02489 270)
			(size 0.508 0.8636)
			(layers "F.Cu" "F.Mask" "F.Paste")
			(net "GND")
		)
		(pad "5" smd rect
			(at 1.774952 1.02489 270)
			(size 0.508 0.8636)
			(layers "F.Cu" "F.Mask" "F.Paste")
			(net "OCP_V3_2_PRSNT01_R_N")
		)
		(pad "6" smd rect
			(at 1.774952 0.32512 270)
			(size 0.4064 0.8636)
			(layers "F.Cu" "F.Mask" "F.Paste")
			(net "OCP_V3_2_PRSNT23_R_N")
		)
		(pad "7" smd rect
			(at 1.774952 -0.32512 270)
			(size 0.4064 0.8636)
			(layers "F.Cu" "F.Mask" "F.Paste")
			(net "OCP_SFF_PRSNT_ALL_R_N")
		)
		(pad "8" smd rect
			(at 1.774952 -1.02489 270)
			(size 0.508 0.8636)
			(layers "F.Cu" "F.Mask" "F.Paste")
			(net "P3V3_AUX")
		)
	)
	(footprint ""
		(layer "F.Cu")
		(at 380.341886 -71.126858)
		(property "Reference" "PR396"
			(at 0 0 0)
			(layer "F.SilkS")
			(hide yes)
			(effects
				(font
					(size 1.27 1.27)
				)
			)
		)
		(property "Value" ""
			(at 0 0 0)
			(layer "F.Fab")
			(effects
				(font
					(size 1.27 1.27)
				)
			)
		)
		(duplicate_pad_numbers_are_jumpers no)
		(fp_line
			(start -0.7874 -0.4064)
			(end 0.7874 -0.4064)
			(stroke
				(width 0.1524)
				(type default)
			)
			(layer "F.SilkS")
		)
		(fp_line
			(start -0.7874 0.4064)
			(end -0.7874 -0.4064)
			(stroke
				(width 0.1524)
				(type default)
			)
			(layer "F.SilkS")
		)
		(fp_line
			(start 0.7874 -0.4064)
			(end 0.7874 0.4064)
			(stroke
				(width 0.1524)
				(type default)
			)
			(layer "F.SilkS")
		)
		(fp_line
			(start 0.7874 0.4064)
			(end -0.7874 0.4064)
			(stroke
				(width 0.1524)
				(type default)
			)
			(layer "F.SilkS")
		)
		(fp_line
			(start -0.67945 -0.305054)
			(end -0.12065 -0.305054)
			(stroke
				(width 0.1)
				(type default)
			)
			(layer "F.Fab")
		)
		(fp_line
			(start -0.67945 0.3048)
			(end -0.67945 -0.305054)
			(stroke
				(width 0.1)
				(type default)
			)
			(layer "F.Fab")
		)
		(fp_line
			(start -0.12065 -0.305054)
			(end -0.12065 -0.2794)
			(stroke
				(width 0.1)
				(type default)
			)
			(layer "F.Fab")
		)
		(fp_line
			(start -0.12065 -0.2794)
			(end 0.12065 -0.2794)
			(stroke
				(width 0.1)
				(type default)
			)
			(layer "F.Fab")
		)
		(fp_line
			(start -0.12065 0.2794)
			(end -0.12065 0.3048)
			(stroke
				(width 0.1)
				(type default)
			)
			(layer "F.Fab")
		)
		(fp_line
			(start -0.12065 0.3048)
			(end -0.67945 0.3048)
			(stroke
				(width 0.1)
				(type default)
			)
			(layer "F.Fab")
		)
		(fp_line
			(start 0.120396 0.2794)
			(end -0.12065 0.2794)
			(stroke
				(width 0.1)
				(type default)
			)
			(layer "F.Fab")
		)
		(fp_line
			(start 0.120396 0.3048)
			(end 0.120396 0.2794)
			(stroke
				(width 0.1)
				(type default)
			)
			(layer "F.Fab")
		)
		(fp_line
			(start 0.12065 -0.3048)
			(end 0.67945 -0.3048)
			(stroke
				(width 0.1)
				(type default)
			)
			(layer "F.Fab")
		)
		(fp_line
			(start 0.12065 -0.2794)
			(end 0.12065 -0.3048)
			(stroke
				(width 0.1)
				(type default)
			)
			(layer "F.Fab")
		)
		(fp_line
			(start 0.67945 -0.3048)
			(end 0.67945 0.3048)
			(stroke
				(width 0.1)
				(type default)
			)
			(layer "F.Fab")
		)
		(fp_line
			(start 0.67945 0.3048)
			(end 0.120396 0.3048)
			(stroke
				(width 0.1)
				(type default)
			)
			(layer "F.Fab")
		)
		(pad "1" smd circle
			(at -0.40005 0)
			(size 0 0)
			(layers "F.Cu" "F.Mask" "F.Paste")
			(net "P5V_AUX")
		)
		(pad "2" smd circle
			(at 0.40005 0)
			(size 0 0)
			(layers "F.Cu" "F.Mask" "F.Paste")
			(net "PVCC1_AUX")
		)
	)
	(footprint ""
		(layer "F.Cu")
		(at 228.816662 -123.167902 180)
		(property "Reference" "R1273"
			(at 0 0 180)
			(layer "F.SilkS")
			(hide yes)
			(effects
				(font
					(size 1.27 1.27)
				)
			)
		)
		(property "Value" ""
			(at 0 0 180)
			(layer "F.Fab")
			(effects
				(font
					(size 1.27 1.27)
				)
			)
		)
		(duplicate_pad_numbers_are_jumpers no)
		(fp_line
			(start 0.7874 0.4064)
			(end -0.7874 0.4064)
			(stroke
				(width 0.1524)
				(type default)
			)
			(layer "F.SilkS")
		)
		(fp_line
			(start 0.7874 -0.087122)
			(end 0.7874 0.4064)
			(stroke
				(width 0.1524)
				(type default)
			)
			(layer "F.SilkS")
		)
		(fp_line
			(start -0.507238 -0.4064)
			(end 0.610362 -0.4064)
			(stroke
				(width 0.1524)
				(type default)
			)
			(layer "F.SilkS")
		)
		(fp_line
			(start -0.7874 0.4064)
			(end -0.7874 0.011938)
			(stroke
				(width 0.1524)
				(type default)
			)
			(layer "F.SilkS")
		)
		(fp_line
			(start 0.67945 0.3048)
			(end 0.120396 0.3048)
			(stroke
				(width 0.1)
				(type default)
			)
			(layer "F.Fab")
		)
		(fp_line
			(start 0.67945 -0.3048)
			(end 0.67945 0.3048)
			(stroke
				(width 0.1)
				(type default)
			)
			(layer "F.Fab")
		)
		(fp_line
			(start 0.12065 -0.2794)
			(end 0.12065 -0.3048)
			(stroke
				(width 0.1)
				(type default)
			)
			(layer "F.Fab")
		)
		(fp_line
			(start 0.12065 -0.3048)
			(end 0.67945 -0.3048)
			(stroke
				(width 0.1)
				(type default)
			)
			(layer "F.Fab")
		)
		(fp_line
			(start 0.120396 0.3048)
			(end 0.120396 0.2794)
			(stroke
				(width 0.1)
				(type default)
			)
			(layer "F.Fab")
		)
		(fp_line
			(start 0.120396 0.2794)
			(end -0.12065 0.2794)
			(stroke
				(width 0.1)
				(type default)
			)
			(layer "F.Fab")
		)
		(fp_line
			(start -0.12065 0.3048)
			(end -0.67945 0.3048)
			(stroke
				(width 0.1)
				(type default)
			)
			(layer "F.Fab")
		)
		(fp_line
			(start -0.12065 0.2794)
			(end -0.12065 0.3048)
			(stroke
				(width 0.1)
				(type default)
			)
			(layer "F.Fab")
		)
		(fp_line
			(start -0.12065 -0.2794)
			(end 0.12065 -0.2794)
			(stroke
				(width 0.1)
				(type default)
			)
			(layer "F.Fab")
		)
		(fp_line
			(start -0.12065 -0.305054)
			(end -0.12065 -0.2794)
			(stroke
				(width 0.1)
				(type default)
			)
			(layer "F.Fab")
		)
		(fp_line
			(start -0.67945 0.3048)
			(end -0.67945 -0.305054)
			(stroke
				(width 0.1)
				(type default)
			)
			(layer "F.Fab")
		)
		(fp_line
			(start -0.67945 -0.305054)
			(end -0.12065 -0.305054)
			(stroke
				(width 0.1)
				(type default)
			)
			(layer "F.Fab")
		)
		(pad "1" smd circle
			(at -0.40005 0 180)
			(size 0 0)
			(layers "F.Cu" "F.Mask" "F.Paste")
			(net "CLK_100M_OCP_SFF_2_R_DP")
		)
		(pad "2" smd circle
			(at 0.40005 0 180)
			(size 0 0)
			(layers "F.Cu" "F.Mask" "F.Paste")
			(net "CLK_100M_OCP_SFF_2_DP")
		)
	)
	(footprint ""
		(layer "F.Cu")
		(at 386.849366 -394.643356)
		(property "Reference" "ME20"
			(at 0 0 0)
			(layer "F.SilkS")
			(hide yes)
			(effects
				(font
					(size 1.27 1.27)
				)
			)
		)
		(property "Value" ""
			(at 0 0 0)
			(layer "F.Fab")
			(effects
				(font
					(size 1.27 1.27)
				)
			)
		)
		(duplicate_pad_numbers_are_jumpers no)
		(fp_line
			(start -3.1369 2.5527)
			(end -3.1115 2.5019)
			(stroke
				(width 0.1524)
				(type default)
			)
			(layer "F.SilkS")
		)
		(fp_line
			(start -3.1369 3.0861)
			(end -2.8321 3.0861)
			(stroke
				(width 0.1524)
				(type default)
			)
			(layer "F.SilkS")
		)
		(fp_line
			(start -3.1242 2.9972)
			(end -3.1369 3.0861)
			(stroke
				(width 0.1524)
				(type default)
			)
			(layer "F.SilkS")
		)
		(fp_line
			(start -3.1115 2.5019)
			(end -3.0861 2.4765)
			(stroke
				(width 0.1524)
				(type default)
			)
			(layer "F.SilkS")
		)
		(fp_line
			(start -3.0988 2.921)
			(end -3.1242 2.9972)
			(stroke
				(width 0.1524)
				(type default)
			)
			(layer "F.SilkS")
		)
		(fp_line
			(start -3.0861 2.4765)
			(end -3.048 2.4511)
			(stroke
				(width 0.1524)
				(type default)
			)
			(layer "F.SilkS")
		)
		(fp_line
			(start -3.0734 2.8829)
			(end -3.0988 2.921)
			(stroke
				(width 0.1524)
				(type default)
			)
			(layer "F.SilkS")
		)
		(fp_line
			(start -3.048 2.4511)
			(end -2.9972 2.4384)
			(stroke
				(width 0.1524)
				(type default)
			)
			(layer "F.SilkS")
		)
		(fp_line
			(start -3.048 2.8575)
			(end -3.0734 2.8829)
			(stroke
				(width 0.1524)
				(type default)
			)
			(layer "F.SilkS")
		)
		(fp_line
			(start -3.0099 2.8067)
			(end -3.048 2.8575)
			(stroke
				(width 0.1524)
				(type default)
			)
			(layer "F.SilkS")
		)
		(fp_line
			(start -2.9972 2.4384)
			(end -2.9337 2.4511)
			(stroke
				(width 0.1524)
				(type default)
			)
			(layer "F.SilkS")
		)
		(fp_line
			(start -2.9591 2.7686)
			(end -3.0099 2.8067)
			(stroke
				(width 0.1524)
				(type default)
			)
			(layer "F.SilkS")
		)
		(fp_line
			(start -2.9337 2.4511)
			(end -2.8702 2.5146)
			(stroke
				(width 0.1524)
				(type default)
			)
			(layer "F.SilkS")
		)
		(fp_line
			(start -2.921 2.7432)
			(end -2.9591 2.7686)
			(stroke
				(width 0.1524)
				(type default)
			)
			(layer "F.SilkS")
		)
		(fp_line
			(start -2.8956 2.7178)
			(end -2.921 2.7432)
			(stroke
				(width 0.1524)
				(type default)
			)
			(layer "F.SilkS")
		)
		(fp_line
			(start -2.8702 2.5146)
			(end -2.8575 2.5527)
			(stroke
				(width 0.1524)
				(type default)
			)
			(layer "F.SilkS")
		)
		(fp_line
			(start -2.8702 2.6797)
			(end -2.8956 2.7178)
			(stroke
				(width 0.1524)
				(type default)
			)
			(layer "F.SilkS")
		)
		(fp_line
			(start -2.8575 2.5527)
			(end -2.8575 2.6416)
			(stroke
				(width 0.1524)
				(type default)
			)
			(layer "F.SilkS")
		)
		(fp_line
			(start -2.8575 2.6416)
			(end -2.8702 2.6797)
			(stroke
				(width 0.1524)
				(type default)
			)
			(layer "F.SilkS")
		)
		(fp_line
			(start -2.5908 2.6543)
			(end -2.5908 3.0861)
			(stroke
				(width 0.1524)
				(type default)
			)
			(layer "F.SilkS")
		)
		(fp_line
			(start -2.5908 2.7813)
			(end -2.5654 2.7305)
			(stroke
				(width 0.1524)
				(type default)
			)
			(layer "F.SilkS")
		)
		(fp_line
			(start -2.5654 2.7305)
			(end -2.54 2.6924)
			(stroke
				(width 0.1524)
				(type default)
			)
			(layer "F.SilkS")
		)
		(fp_line
			(start -2.54 2.6924)
			(end -2.5146 2.667)
			(stroke
				(width 0.1524)
				(type default)
			)
			(layer "F.SilkS")
		)
		(fp_line
			(start -2.5146 2.667)
			(end -2.4638 2.6543)
			(stroke
				(width 0.1524)
				(type default)
			)
			(layer "F.SilkS")
		)
		(fp_line
			(start -2.4638 2.6543)
			(end -2.4257 2.6543)
			(stroke
				(width 0.1524)
				(type default)
			)
			(layer "F.SilkS")
		)
		(fp_line
			(start -2.4257 2.6543)
			(end -2.3749 2.667)
			(stroke
				(width 0.1524)
				(type default)
			)
			(layer "F.SilkS")
		)
		(fp_line
			(start -2.3749 2.667)
			(end -2.3368 2.7178)
			(stroke
				(width 0.1524)
				(type default)
			)
			(layer "F.SilkS")
		)
		(fp_line
			(start -2.3368 2.7178)
			(end -2.3114 2.7686)
			(stroke
				(width 0.1524)
				(type default)
			)
			(layer "F.SilkS")
		)
		(fp_line
			(start -2.3114 2.7686)
			(end -2.3114 3.0861)
			(stroke
				(width 0.1524)
				(type default)
			)
			(layer "F.SilkS")
		)
		(fp_line
			(start -2.0701 2.8575)
			(end -2.0701 2.9083)
			(stroke
				(width 0.1524)
				(type default)
			)
			(layer "F.SilkS")
		)
		(fp_line
			(start -2.0701 2.9083)
			(end -2.0574 2.9718)
			(stroke
				(width 0.1524)
				(type default)
			)
			(layer "F.SilkS")
		)
		(fp_line
			(start -2.0574 2.8194)
			(end -2.0701 2.8575)
			(stroke
				(width 0.1524)
				(type default)
			)
			(layer "F.SilkS")
		)
		(fp_line
			(start -2.0574 2.9718)
			(end -2.032 3.0099)
			(stroke
				(width 0.1524)
				(type default)
			)
			(layer "F.SilkS")
		)
		(fp_line
			(start -2.0447 2.794)
			(end -2.0574 2.8194)
			(stroke
				(width 0.1524)
				(type default)
			)
			(layer "F.SilkS")
		)
		(fp_line
			(start -2.032 3.0099)
			(end -2.0066 3.0353)
			(stroke
				(width 0.1524)
				(type default)
			)
			(layer "F.SilkS")
		)
		(fp_line
			(start -2.0066 2.7559)
			(end -2.0447 2.794)
			(stroke
				(width 0.1524)
				(type default)
			)
			(layer "F.SilkS")
		)
		(fp_line
			(start -2.0066 3.0353)
			(end -1.9685 3.0607)
			(stroke
				(width 0.1524)
				(type default)
			)
			(layer "F.SilkS")
		)
		(fp_line
			(start -1.9685 2.7305)
			(end -2.0066 2.7559)
			(stroke
				(width 0.1524)
				(type default)
			)
			(layer "F.SilkS")
		)
		(fp_line
			(start -1.9685 3.0607)
			(end -1.9304 3.0734)
			(stroke
				(width 0.1524)
				(type default)
			)
			(layer "F.SilkS")
		)
		(fp_line
			(start -1.9304 3.0734)
			(end -1.8796 3.0734)
			(stroke
				(width 0.1524)
				(type default)
			)
			(layer "F.SilkS")
		)
		(fp_line
			(start -1.9177 2.7178)
			(end -1.9685 2.7305)
			(stroke
				(width 0.1524)
				(type default)
			)
			(layer "F.SilkS")
		)
		(fp_line
			(start -1.8796 3.0734)
			(end -1.8161 3.0607)
			(stroke
				(width 0.1524)
				(type default)
			)
			(layer "F.SilkS")
		)
		(fp_line
			(start -1.8542 2.7178)
			(end -1.9177 2.7178)
			(stroke
				(width 0.1524)
				(type default)
			)
			(layer "F.SilkS")
		)
		(fp_line
			(start -1.8161 2.7305)
			(end -1.8542 2.7178)
			(stroke
				(width 0.1524)
				(type default)
			)
			(layer "F.SilkS")
		)
		(fp_line
			(start -1.8161 3.0607)
			(end -1.778 3.0353)
			(stroke
				(width 0.1524)
				(type default)
			)
			(layer "F.SilkS")
		)
		(fp_line
			(start -1.778 2.7559)
			(end -1.8161 2.7305)
			(stroke
				(width 0.1524)
				(type default)
			)
			(layer "F.SilkS")
		)
		(fp_line
			(start -1.778 3.0353)
			(end -1.7526 3.0099)
			(stroke
				(width 0.1524)
				(type default)
			)
			(layer "F.SilkS")
		)
		(fp_line
			(start -1.7526 2.4384)
			(end -1.7526 3.0861)
			(stroke
				(width 0.1524)
				(type default)
			)
			(layer "F.SilkS")
		)
		(fp_line
			(start -1.7526 2.7813)
			(end -1.778 2.7559)
			(stroke
				(width 0.1524)
				(type default)
			)
			(layer "F.SilkS")
		)
		(fp_line
			(start -1.3208 -1.524)
			(end 1.4732 1.397)
			(stroke
				(width 0.1524)
				(type default)
			)
			(layer "F.SilkS")
		)
		(fp_line
			(start -1.1938 -1.27)
			(end -1.1938 1.2954)
			(stroke
				(width 0.254)
				(type default)
			)
			(layer "F.SilkS")
		)
		(fp_line
			(start -1.1938 -1.27)
			(end -0.5588 -1.27)
			(stroke
				(width 0.254)
				(type default)
			)
			(layer "F.SilkS")
		)
		(fp_line
			(start -1.1557 2.4257)
			(end -1.1557 3.0861)
			(stroke
				(width 0.1524)
				(type default)
			)
			(layer "F.SilkS")
		)
		(fp_line
			(start -1.016 4.7498)
			(end -1.016 4.826)
			(stroke
				(width 0.254)
				(type default)
			)
			(layer "F.SilkS")
		)
		(fp_line
			(start -1.016 4.7752)
			(end 0.3048 4.7752)
			(stroke
				(width 0.254)
				(type default)
			)
			(layer "F.SilkS")
		)
		(fp_line
			(start -1.016 4.826)
			(end -0.9906 4.953)
			(stroke
				(width 0.254)
				(type default)
			)
			(layer "F.SilkS")
		)
		(fp_line
			(start -0.9906 4.5974)
			(end -1.016 4.7498)
			(stroke
				(width 0.254)
				(type default)
			)
			(layer "F.SilkS")
		)
		(fp_line
			(start -0.9906 4.953)
			(end -0.9652 5.0292)
			(stroke
				(width 0.254)
				(type default)
			)
			(layer "F.SilkS")
		)
		(fp_line
			(start -0.9652 4.5212)
			(end -0.9906 4.5974)
			(stroke
				(width 0.254)
				(type default)
			)
			(layer "F.SilkS")
		)
		(fp_line
			(start -0.9652 5.0292)
			(end -0.9144 5.1308)
			(stroke
				(width 0.254)
				(type default)
			)
			(layer "F.SilkS")
		)
		(fp_line
			(start -0.9144 4.4196)
			(end -0.9652 4.5212)
			(stroke
				(width 0.254)
				(type default)
			)
			(layer "F.SilkS")
		)
		(fp_line
			(start -0.9144 5.1308)
			(end -0.8382 5.2324)
			(stroke
				(width 0.254)
				(type default)
			)
			(layer "F.SilkS")
		)
		(fp_line
			(start -0.8382 4.318)
			(end -0.9144 4.4196)
			(stroke
				(width 0.254)
				(type default)
			)
			(layer "F.SilkS")
		)
		(fp_line
			(start -0.8382 5.2324)
			(end -0.7112 5.334)
			(stroke
				(width 0.254)
				(type default)
			)
			(layer "F.SilkS")
		)
		(fp_line
			(start -0.8128 4.2926)
			(end -0.8382 4.318)
			(stroke
				(width 0.254)
				(type default)
			)
			(layer "F.SilkS")
		)
		(fp_line
			(start -0.7747 2.6543)
			(end -0.5969 3.0861)
			(stroke
				(width 0.1524)
				(type default)
			)
			(layer "F.SilkS")
		)
		(fp_line
			(start -0.7112 4.2164)
			(end -0.8128 4.2926)
			(stroke
				(width 0.254)
				(type default)
			)
			(layer "F.SilkS")
		)
		(fp_line
			(start -0.7112 5.334)
			(end -0.6096 5.3848)
			(stroke
				(width 0.254)
				(type default)
			)
			(layer "F.SilkS")
		)
		(fp_line
			(start -0.6096 4.1656)
			(end -0.7112 4.2164)
			(stroke
				(width 0.254)
				(type default)
			)
			(layer "F.SilkS")
		)
		(fp_line
			(start -0.6096 5.3848)
			(end -0.5334 5.4102)
			(stroke
				(width 0.254)
				(type default)
			)
			(layer "F.SilkS")
		)
		(fp_line
			(start -0.5969 3.0861)
			(end -0.4191 2.6543)
			(stroke
				(width 0.1524)
				(type default)
			)
			(layer "F.SilkS")
		)
		(fp_line
			(start -0.5588 0)
			(end -1.1938 0)
			(stroke
				(width 0.254)
				(type default)
			)
			(layer "F.SilkS")
		)
		(fp_line
			(start -0.5334 4.1402)
			(end -0.6096 4.1656)
			(stroke
				(width 0.254)
				(type default)
			)
			(layer "F.SilkS")
		)
		(fp_line
			(start -0.5334 5.4102)
			(end -0.381 5.4356)
			(stroke
				(width 0.254)
				(type default)
			)
			(layer "F.SilkS")
		)
		(fp_line
			(start -0.4064 4.1148)
			(end -0.5334 4.1402)
			(stroke
				(width 0.254)
				(type default)
			)
			(layer "F.SilkS")
		)
		(fp_line
			(start -0.381 5.4356)
			(end -0.3556 5.4356)
			(stroke
				(width 0.254)
				(type default)
			)
			(layer "F.SilkS")
		)
		(fp_line
			(start -0.3556 5.4356)
			(end -0.1778 5.4102)
			(stroke
				(width 0.254)
				(type default)
			)
			(layer "F.SilkS")
		)
		(fp_line
			(start -0.3048 4.1148)
			(end -0.4064 4.1148)
			(stroke
				(width 0.254)
				(type default)
			)
			(layer "F.SilkS")
		)
		(fp_line
			(start -0.1778 4.1402)
			(end -0.3048 4.1148)
			(stroke
				(width 0.254)
				(type default)
			)
			(layer "F.SilkS")
		)
		(fp_line
			(start -0.1778 5.4102)
			(end -0.1016 5.3848)
			(stroke
				(width 0.254)
				(type default)
			)
			(layer "F.SilkS")
		)
		(fp_line
			(start -0.1016 4.1656)
			(end -0.1778 4.1402)
			(stroke
				(width 0.254)
				(type default)
			)
			(layer "F.SilkS")
		)
		(fp_line
			(start -0.1016 5.3848)
			(end -0.0508 5.3594)
			(stroke
				(width 0.254)
				(type default)
			)
			(layer "F.SilkS")
		)
		(fp_line
			(start -0.0508 5.3594)
			(end 0.1016 5.2578)
			(stroke
				(width 0.254)
				(type default)
			)
			(layer "F.SilkS")
		)
		(fp_line
			(start -0.0381 2.4257)
			(end -0.0381 3.0861)
			(stroke
				(width 0.1524)
				(type default)
			)
			(layer "F.SilkS")
		)
		(fp_line
			(start 0 4.2164)
			(end -0.1016 4.1656)
			(stroke
				(width 0.254)
				(type default)
			)
			(layer "F.SilkS")
		)
		(fp_line
			(start 0.1016 5.2578)
			(end 0.2032 5.1308)
			(stroke
				(width 0.254)
				(type default)
			)
			(layer "F.SilkS")
		)
		(fp_line
			(start 0.127 4.318)
			(end 0 4.2164)
			(stroke
				(width 0.254)
				(type default)
			)
			(layer "F.SilkS")
		)
		(fp_line
			(start 0.2032 4.4196)
			(end 0.127 4.318)
			(stroke
				(width 0.254)
				(type default)
			)
			(layer "F.SilkS")
		)
		(fp_line
			(start 0.254 4.5212)
			(end 0.2032 4.4196)
			(stroke
				(width 0.254)
				(type default)
			)
			(layer "F.SilkS")
		)
		(fp_line
			(start 0.2794 4.5974)
			(end 0.254 4.5212)
			(stroke
				(width 0.254)
				(type default)
			)
			(layer "F.SilkS")
		)
		(fp_line
			(start 0.3048 4.7752)
			(end 0.2794 4.5974)
			(stroke
				(width 0.254)
				(type default)
			)
			(layer "F.SilkS")
		)
		(fp_line
			(start 0.3556 -1.27)
			(end 0.3556 1.2954)
			(stroke
				(width 0.254)
				(type default)
			)
			(layer "F.SilkS")
		)
		(fp_line
			(start 0.635 4.3434)
			(end 0.9144 4.191)
			(stroke
				(width 0.254)
				(type default)
			)
			(layer "F.SilkS")
		)
		(fp_line
			(start 0.6731 2.3495)
			(end 0.6731 2.3749)
			(stroke
				(width 0.1524)
				(type default)
			)
			(layer "F.SilkS")
		)
		(fp_line
			(start 0.6731 2.3749)
			(end 0.6985 2.4003)
			(stroke
				(width 0.1524)
				(type default)
			)
			(layer "F.SilkS")
		)
		(fp_line
			(start 0.6985 2.3241)
			(end 0.6731 2.3495)
			(stroke
				(width 0.1524)
				(type default)
			)
			(layer "F.SilkS")
		)
		(fp_line
			(start 0.6985 2.4003)
			(end 0.7239 2.3749)
			(stroke
				(width 0.1524)
				(type default)
			)
			(layer "F.SilkS")
		)
		(fp_line
			(start 0.6985 2.6416)
			(end 0.6985 3.0861)
			(stroke
				(width 0.1524)
				(type default)
			)
			(layer "F.SilkS")
		)
		(fp_line
			(start 0.7239 2.3495)
			(end 0.6985 2.3241)
			(stroke
				(width 0.1524)
				(type default)
			)
			(layer "F.SilkS")
		)
		(fp_line
			(start 0.7239 2.3749)
			(end 0.7239 2.3495)
			(stroke
				(width 0.1524)
				(type default)
			)
			(layer "F.SilkS")
		)
		(fp_line
			(start 0.9144 4.191)
			(end 0.9144 5.461)
			(stroke
				(width 0.254)
				(type default)
			)
			(layer "F.SilkS")
		)
		(fp_line
			(start 1.143 2.6543)
			(end 1.143 3.0861)
			(stroke
				(width 0.1524)
				(type default)
			)
			(layer "F.SilkS")
		)
		(fp_line
			(start 1.143 2.7813)
			(end 1.1684 2.7305)
			(stroke
				(width 0.1524)
				(type default)
			)
			(layer "F.SilkS")
		)
		(fp_line
			(start 1.1684 2.7305)
			(end 1.1938 2.6924)
			(stroke
				(width 0.1524)
				(type default)
			)
			(layer "F.SilkS")
		)
		(fp_line
			(start 1.1938 2.6924)
			(end 1.2192 2.667)
			(stroke
				(width 0.1524)
				(type default)
			)
			(layer "F.SilkS")
		)
		(fp_line
			(start 1.2192 2.667)
			(end 1.27 2.6543)
			(stroke
				(width 0.1524)
				(type default)
			)
			(layer "F.SilkS")
		)
		(fp_line
			(start 1.27 2.6543)
			(end 1.3081 2.6543)
			(stroke
				(width 0.1524)
				(type default)
			)
			(layer "F.SilkS")
		)
		(fp_line
			(start 1.3081 2.6543)
			(end 1.3589 2.667)
			(stroke
				(width 0.1524)
				(type default)
			)
			(layer "F.SilkS")
		)
		(fp_line
			(start 1.3589 2.667)
			(end 1.397 2.7178)
			(stroke
				(width 0.1524)
				(type default)
			)
			(layer "F.SilkS")
		)
		(fp_line
			(start 1.397 2.7178)
			(end 1.4224 2.7686)
			(stroke
				(width 0.1524)
				(type default)
			)
			(layer "F.SilkS")
		)
		(fp_line
			(start 1.4224 2.7686)
			(end 1.4224 3.0861)
			(stroke
				(width 0.1524)
				(type default)
			)
			(layer "F.SilkS")
		)
		(fp_line
			(start 1.7018 2.667)
			(end 1.9304 2.667)
			(stroke
				(width 0.1524)
				(type default)
			)
			(layer "F.SilkS")
		)
		(fp_line
			(start 1.8161 2.4511)
			(end 1.8161 3.0861)
			(stroke
				(width 0.1524)
				(type default)
			)
			(layer "F.SilkS")
		)
		(fp_line
			(start 1.8161 3.0861)
			(end 1.9939 3.0734)
			(stroke
				(width 0.1524)
				(type default)
			)
			(layer "F.SilkS")
		)
		(fp_line
			(start 2.1844 2.8575)
			(end 2.1844 2.8956)
			(stroke
				(width 0.1524)
				(type default)
			)
			(layer "F.SilkS")
		)
		(fp_line
			(start 2.1844 2.8956)
			(end 2.1971 2.9464)
			(stroke
				(width 0.1524)
				(type default)
			)
			(layer "F.SilkS")
		)
		(fp_line
			(start 2.1971 2.794)
			(end 2.1844 2.8575)
			(stroke
				(width 0.1524)
				(type default)
			)
			(layer "F.SilkS")
		)
		(fp_line
			(start 2.1971 2.9464)
			(end 2.2098 2.9718)
			(stroke
				(width 0.1524)
				(type default)
			)
			(layer "F.SilkS")
		)
		(fp_line
			(start 2.2098 2.7686)
			(end 2.1971 2.794)
			(stroke
				(width 0.1524)
				(type default)
			)
			(layer "F.SilkS")
		)
		(fp_line
			(start 2.2098 2.9718)
			(end 2.2352 3.0099)
			(stroke
				(width 0.1524)
				(type default)
			)
			(layer "F.SilkS")
		)
		(fp_line
			(start 2.2352 2.7305)
			(end 2.2098 2.7686)
			(stroke
				(width 0.1524)
				(type default)
			)
			(layer "F.SilkS")
		)
		(fp_line
			(start 2.2352 3.0099)
			(end 2.2606 3.0353)
			(stroke
				(width 0.1524)
				(type default)
			)
			(layer "F.SilkS")
		)
		(fp_line
			(start 2.2606 2.7051)
			(end 2.2352 2.7305)
			(stroke
				(width 0.1524)
				(type default)
			)
			(layer "F.SilkS")
		)
		(fp_line
			(start 2.2606 3.0353)
			(end 2.2987 3.0607)
			(stroke
				(width 0.1524)
				(type default)
			)
			(layer "F.SilkS")
		)
		(fp_line
			(start 2.2987 2.6797)
			(end 2.2606 2.7051)
			(stroke
				(width 0.1524)
				(type default)
			)
			(layer "F.SilkS")
		)
		(fp_line
			(start 2.2987 3.0607)
			(end 2.3241 3.0734)
			(stroke
				(width 0.1524)
				(type default)
			)
			(layer "F.SilkS")
		)
		(fp_line
			(start 2.3241 2.667)
			(end 2.2987 2.6797)
			(stroke
				(width 0.1524)
				(type default)
			)
			(layer "F.SilkS")
		)
		(fp_line
			(start 2.3241 3.0734)
			(end 2.3876 3.0861)
			(stroke
				(width 0.1524)
				(type default)
			)
			(layer "F.SilkS")
		)
		(fp_line
			(start 2.3749 2.6543)
			(end 2.3241 2.667)
			(stroke
				(width 0.1524)
				(type default)
			)
			(layer "F.SilkS")
		)
		(fp_line
			(start 2.3876 3.0861)
			(end 2.4384 3.0861)
			(stroke
				(width 0.1524)
				(type default)
			)
			(layer "F.SilkS")
		)
		(fp_line
			(start 2.413 2.6543)
			(end 2.3749 2.6543)
			(stroke
				(width 0.1524)
				(type default)
			)
			(layer "F.SilkS")
		)
		(fp_line
			(start 2.4384 3.0861)
			(end 2.5019 3.0607)
			(stroke
				(width 0.1524)
				(type default)
			)
			(layer "F.SilkS")
		)
		(fp_line
			(start 2.4638 2.667)
			(end 2.413 2.6543)
			(stroke
				(width 0.1524)
				(type default)
			)
			(layer "F.SilkS")
		)
		(fp_line
			(start 2.5019 2.6797)
			(end 2.4638 2.667)
			(stroke
				(width 0.1524)
				(type default)
			)
			(layer "F.SilkS")
		)
		(fp_line
			(start 2.8194 2.667)
			(end 3.048 2.667)
			(stroke
				(width 0.1524)
				(type default)
			)
			(layer "F.SilkS")
		)
		(fp_line
			(start 2.9337 2.4511)
			(end 2.9337 3.0861)
			(stroke
				(width 0.1524)
				(type default)
			)
			(layer "F.SilkS")
		)
		(fp_line
			(start 2.9337 3.0861)
			(end 3.1115 3.0734)
			(stroke
				(width 0.1524)
				(type default)
			)
			(layer "F.SilkS")
		)
		(fp_arc
			(start -1.5748 4.826)
			(mid -0.985634 3.828381)
			(end 0.127 3.5052)
			(stroke
				(width 0.1524)
				(type default)
			)
			(layer "F.SilkS")
		)
		(fp_arc
			(start -0.5588 -1.27)
			(mid 0.0762 -0.635)
			(end -0.5588 0)
			(stroke
				(width 0.254)
				(type default)
			)
			(layer "F.SilkS")
		)
		(fp_arc
			(start -0.127 3.5052)
			(mid 0.985653 3.828369)
			(end 1.5748 4.826)
			(stroke
				(width 0.1524)
				(type default)
			)
			(layer "F.SilkS")
		)
		(fp_arc
			(start 0.1524 6.096)
			(mid -0.964585 5.805588)
			(end -1.5748 4.826)
			(stroke
				(width 0.1524)
				(type default)
			)
			(layer "F.SilkS")
		)
		(fp_arc
			(start 1.5748 4.826)
			(mid 0.964538 5.805581)
			(end -0.1524 6.096)
			(stroke
				(width 0.1524)
				(type default)
			)
			(layer "F.SilkS")
		)
		(fp_circle
			(center -1.8923 2.8956)
			(end -1.71196 2.8956)
			(stroke
				(width 0.1524)
				(type default)
			)
			(fill no)
			(layer "F.SilkS")
		)
		(fp_circle
			(center 0 0)
			(end 2.03454 0)
			(stroke
				(width 0.1524)
				(type default)
			)
			(fill no)
			(layer "F.SilkS")
		)
		(fp_circle
			(center 0.9652 0.6858)
			(end 1.57734 0.6858)
			(stroke
				(width 0.254)
				(type default)
			)
			(fill no)
			(layer "F.SilkS")
		)
	)
	(footprint ""
		(layer "F.Cu")
		(at 230.960422 -117.710712 -90)
		(property "Reference" "R1275"
			(at 0 0 270)
			(layer "F.SilkS")
			(hide yes)
			(effects
				(font
					(size 1.27 1.27)
				)
			)
		)
		(property "Value" ""
			(at 0 0 270)
			(layer "F.Fab")
			(effects
				(font
					(size 1.27 1.27)
				)
			)
		)
		(duplicate_pad_numbers_are_jumpers no)
		(fp_line
			(start -0.7874 0.4064)
			(end -0.7874 0.000762)
			(stroke
				(width 0.1524)
				(type default)
			)
			(layer "F.SilkS")
		)
		(fp_line
			(start 0.7874 0.4064)
			(end -0.7874 0.4064)
			(stroke
				(width 0.1524)
				(type default)
			)
			(layer "F.SilkS")
		)
		(fp_line
			(start 0.7874 -0.095758)
			(end 0.7874 0.4064)
			(stroke
				(width 0.1524)
				(type default)
			)
			(layer "F.SilkS")
		)
		(fp_line
			(start -0.373888 -0.4064)
			(end 0.418592 -0.4064)
			(stroke
				(width 0.1524)
				(type default)
			)
			(layer "F.SilkS")
		)
		(fp_line
			(start -0.67945 0.3048)
			(end -0.67945 -0.305054)
			(stroke
				(width 0.1)
				(type default)
			)
			(layer "F.Fab")
		)
		(fp_line
			(start -0.12065 0.3048)
			(end -0.67945 0.3048)
			(stroke
				(width 0.1)
				(type default)
			)
			(layer "F.Fab")
		)
		(fp_line
			(start 0.120396 0.3048)
			(end 0.120396 0.2794)
			(stroke
				(width 0.1)
				(type default)
			)
			(layer "F.Fab")
		)
		(fp_line
			(start 0.67945 0.3048)
			(end 0.120396 0.3048)
			(stroke
				(width 0.1)
				(type default)
			)
			(layer "F.Fab")
		)
		(fp_line
			(start -0.12065 0.2794)
			(end -0.12065 0.3048)
			(stroke
				(width 0.1)
				(type default)
			)
			(layer "F.Fab")
		)
		(fp_line
			(start 0.120396 0.2794)
			(end -0.12065 0.2794)
			(stroke
				(width 0.1)
				(type default)
			)
			(layer "F.Fab")
		)
		(fp_line
			(start -0.12065 -0.2794)
			(end 0.12065 -0.2794)
			(stroke
				(width 0.1)
				(type default)
			)
			(layer "F.Fab")
		)
		(fp_line
			(start 0.12065 -0.2794)
			(end 0.12065 -0.3048)
			(stroke
				(width 0.1)
				(type default)
			)
			(layer "F.Fab")
		)
		(fp_line
			(start 0.12065 -0.3048)
			(end 0.67945 -0.3048)
			(stroke
				(width 0.1)
				(type default)
			)
			(layer "F.Fab")
		)
		(fp_line
			(start 0.67945 -0.3048)
			(end 0.67945 0.3048)
			(stroke
				(width 0.1)
				(type default)
			)
			(layer "F.Fab")
		)
		(fp_line
			(start -0.67945 -0.305054)
			(end -0.12065 -0.305054)
			(stroke
				(width 0.1)
				(type default)
			)
			(layer "F.Fab")
		)
		(fp_line
			(start -0.12065 -0.305054)
			(end -0.12065 -0.2794)
			(stroke
				(width 0.1)
				(type default)
			)
			(layer "F.Fab")
		)
		(pad "1" smd circle
			(at -0.40005 0 270)
			(size 0 0)
			(layers "F.Cu" "F.Mask" "F.Paste")
			(net "CLK_100M_OCP_SFF_3_R_DP")
		)
		(pad "2" smd circle
			(at 0.40005 0 270)
			(size 0 0)
			(layers "F.Cu" "F.Mask" "F.Paste")
			(net "CLK_100M_OCP_SFF_3_DP")
		)
	)
	(footprint ""
		(layer "F.Cu")
		(at 433.83962 -175.197008 90)
		(property "Reference" "PC1420"
			(at 0 0 90)
			(layer "F.SilkS")
			(hide yes)
			(effects
				(font
					(size 1.27 1.27)
				)
			)
		)
		(property "Value" ""
			(at 0 0 90)
			(layer "F.Fab")
			(effects
				(font
					(size 1.27 1.27)
				)
			)
		)
		(duplicate_pad_numbers_are_jumpers no)
		(fp_line
			(start 0.7874 -0.4064)
			(end 0.7874 0.4064)
			(stroke
				(width 0.1524)
				(type default)
			)
			(layer "F.SilkS")
		)
		(fp_line
			(start -0.7874 -0.4064)
			(end 0.7874 -0.4064)
			(stroke
				(width 0.1524)
				(type default)
			)
			(layer "F.SilkS")
		)
		(fp_line
			(start 0.7874 0.4064)
			(end -0.7874 0.4064)
			(stroke
				(width 0.1524)
				(type default)
			)
			(layer "F.SilkS")
		)
		(fp_line
			(start -0.7874 0.4064)
			(end -0.7874 -0.4064)
			(stroke
				(width 0.1524)
				(type default)
			)
			(layer "F.SilkS")
		)
		(fp_line
			(start -0.12065 -0.305054)
			(end -0.12065 -0.2794)
			(stroke
				(width 0.1)
				(type default)
			)
			(layer "F.Fab")
		)
		(fp_line
			(start -0.67945 -0.305054)
			(end -0.12065 -0.305054)
			(stroke
				(width 0.1)
				(type default)
			)
			(layer "F.Fab")
		)
		(fp_line
			(start 0.67945 -0.3048)
			(end 0.67945 0.3048)
			(stroke
				(width 0.1)
				(type default)
			)
			(layer "F.Fab")
		)
		(fp_line
			(start 0.12065 -0.3048)
			(end 0.67945 -0.3048)
			(stroke
				(width 0.1)
				(type default)
			)
			(layer "F.Fab")
		)
		(fp_line
			(start 0.12065 -0.2794)
			(end 0.12065 -0.3048)
			(stroke
				(width 0.1)
				(type default)
			)
			(layer "F.Fab")
		)
		(fp_line
			(start -0.12065 -0.2794)
			(end 0.12065 -0.2794)
			(stroke
				(width 0.1)
				(type default)
			)
			(layer "F.Fab")
		)
		(fp_line
			(start 0.120396 0.2794)
			(end -0.12065 0.2794)
			(stroke
				(width 0.1)
				(type default)
			)
			(layer "F.Fab")
		)
		(fp_line
			(start -0.12065 0.2794)
			(end -0.12065 0.3048)
			(stroke
				(width 0.1)
				(type default)
			)
			(layer "F.Fab")
		)
		(fp_line
			(start 0.67945 0.3048)
			(end 0.120396 0.3048)
			(stroke
				(width 0.1)
				(type default)
			)
			(layer "F.Fab")
		)
		(fp_line
			(start 0.120396 0.3048)
			(end 0.120396 0.2794)
			(stroke
				(width 0.1)
				(type default)
			)
			(layer "F.Fab")
		)
		(fp_line
			(start -0.12065 0.3048)
			(end -0.67945 0.3048)
			(stroke
				(width 0.1)
				(type default)
			)
			(layer "F.Fab")
		)
		(fp_line
			(start -0.67945 0.3048)
			(end -0.67945 -0.305054)
			(stroke
				(width 0.1)
				(type default)
			)
			(layer "F.Fab")
		)
		(pad "1" smd circle
			(at -0.40005 0 90)
			(size 0 0)
			(layers "F.Cu" "F.Mask" "F.Paste")
			(net "PVNN_MAIN_CPU0_FB_RC")
		)
		(pad "2" smd circle
			(at 0.40005 0 90)
			(size 0 0)
			(layers "F.Cu" "F.Mask" "F.Paste")
			(net "GND")
		)
	)
	(footprint ""
		(layer "F.Cu")
		(at 240.854484 -55.612792 180)
		(property "Reference" "C1992"
			(at 0 0 180)
			(layer "F.SilkS")
			(hide yes)
			(effects
				(font
					(size 1.27 1.27)
				)
			)
		)
		(property "Value" ""
			(at 0 0 180)
			(layer "F.Fab")
			(effects
				(font
					(size 1.27 1.27)
				)
			)
		)
		(duplicate_pad_numbers_are_jumpers no)
		(fp_line
			(start 0.299974 0.150114)
			(end -0.299974 0.150114)
			(stroke
				(width 0.1)
				(type default)
			)
			(layer "F.Fab")
		)
		(fp_line
			(start 0.299974 -0.150114)
			(end 0.299974 0.150114)
			(stroke
				(width 0.1)
				(type default)
			)
			(layer "F.Fab")
		)
		(fp_line
			(start -0.299974 0.150114)
			(end -0.299974 -0.150114)
			(stroke
				(width 0.1)
				(type default)
			)
			(layer "F.Fab")
		)
		(fp_line
			(start -0.299974 -0.150114)
			(end 0.299974 -0.150114)
			(stroke
				(width 0.1)
				(type default)
			)
			(layer "F.Fab")
		)
		(pad "1" smd rect
			(at -0.2667 0 180)
			(size 0.3048 0.381)
			(layers "F.Cu" "F.Mask" "F.Paste")
			(net "P3E_PCH_E1S_TX_DN<2>")
		)
		(pad "2" smd rect
			(at 0.2667 0 180)
			(size 0.3048 0.381)
			(layers "F.Cu" "F.Mask" "F.Paste")
			(net "P3E_PCH_E1S_TX_C_DN<2>")
		)
		(zone
			(layer "In1.Cu")
			(hatch none 0.5)
			(connect_pads
				(clearance 0)
			)
			(min_thickness 0.25)
			(keepout
				(tracks not_allowed)
				(vias allowed)
				(pads allowed)
				(copperpour not_allowed)
				(footprints allowed)
			)
			(placement
				(enabled no)
				(sheetname "")
			)
			(fill
				(thermal_gap 0.5)
				(thermal_bridge_width 0.5)
				(island_removal_mode 0)
			)
			(polygon
				(pts
					(arc
						(start 240.714784 -55.853076)
						(mid 240.768666 -55.830758)
						(end 240.790984 -55.776876)
					)
					(arc
						(start 240.790984 -55.446676)
						(mid 240.768666 -55.392794)
						(end 240.714784 -55.370476)
					)
					(arc
						(start 240.460784 -55.370476)
						(mid 240.406902 -55.392794)
						(end 240.384584 -55.446676)
					)
					(arc
						(start 240.384584 -55.776876)
						(mid 240.406902 -55.830758)
						(end 240.460784 -55.853076)
					)
				)
			)
		)
		(zone
			(layer "In1.Cu")
			(hatch none 0.5)
			(connect_pads
				(clearance 0)
			)
			(min_thickness 0.25)
			(keepout
				(tracks not_allowed)
				(vias allowed)
				(pads allowed)
				(copperpour not_allowed)
				(footprints allowed)
			)
			(placement
				(enabled no)
				(sheetname "")
			)
			(fill
				(thermal_gap 0.5)
				(thermal_bridge_width 0.5)
				(island_removal_mode 0)
			)
			(polygon
				(pts
					(arc
						(start 241.248184 -55.853076)
						(mid 241.302066 -55.830758)
						(end 241.324384 -55.776876)
					)
					(arc
						(start 241.324384 -55.446676)
						(mid 241.302066 -55.392794)
						(end 241.248184 -55.370476)
					)
					(arc
						(start 240.994184 -55.370476)
						(mid 240.940302 -55.392794)
						(end 240.917984 -55.446676)
					)
					(arc
						(start 240.917984 -55.776876)
						(mid 240.940302 -55.830758)
						(end 240.994184 -55.853076)
					)
				)
			)
		)
	)
	(footprint ""
		(layer "F.Cu")
		(at 126.385828 -350.780858)
		(property "Reference" "PC1261"
			(at 0 0 0)
			(layer "F.SilkS")
			(hide yes)
			(effects
				(font
					(size 1.27 1.27)
				)
			)
		)
		(property "Value" ""
			(at 0 0 0)
			(layer "F.Fab")
			(effects
				(font
					(size 1.27 1.27)
				)
			)
		)
		(duplicate_pad_numbers_are_jumpers no)
		(fp_line
			(start -1.524 -0.762)
			(end 1.524 -0.762)
			(stroke
				(width 0.1524)
				(type default)
			)
			(layer "F.SilkS")
		)
		(fp_line
			(start -1.524 0.762)
			(end -1.524 -0.762)
			(stroke
				(width 0.1524)
				(type default)
			)
			(layer "F.SilkS")
		)
		(fp_line
			(start 1.524 -0.762)
			(end 1.524 0.762)
			(stroke
				(width 0.1524)
				(type default)
			)
			(layer "F.SilkS")
		)
		(fp_line
			(start 1.524 0.762)
			(end -1.524 0.762)
			(stroke
				(width 0.1524)
				(type default)
			)
			(layer "F.SilkS")
		)
		(fp_line
			(start -1.1049 -0.724916)
			(end -1.1049 0.724916)
			(stroke
				(width 0.1)
				(type default)
			)
			(layer "F.Fab")
		)
		(fp_line
			(start -1.1049 0.724916)
			(end 1.1049 0.724916)
			(stroke
				(width 0.1)
				(type default)
			)
			(layer "F.Fab")
		)
		(fp_line
			(start 1.1049 -0.724916)
			(end -1.1049 -0.724916)
			(stroke
				(width 0.1)
				(type default)
			)
			(layer "F.Fab")
		)
		(fp_line
			(start 1.1049 0.724916)
			(end 1.1049 -0.724916)
			(stroke
				(width 0.1)
				(type default)
			)
			(layer "F.Fab")
		)
		(pad "1" smd rect
			(at -0.889 0 180)
			(size 1.016 1.27)
			(layers "F.Cu" "F.Mask" "F.Paste")
			(net "SW_P12V_PVCCIN_CPU1_FLT")
		)
		(pad "2" smd rect
			(at 0.889 0 180)
			(size 1.016 1.27)
			(layers "F.Cu" "F.Mask" "F.Paste")
			(net "GND")
		)
	)
	(footprint ""
		(layer "F.Cu")
		(at 143.764 -26.126948 180)
		(property "Reference" "R4627"
			(at 0 0 180)
			(layer "F.SilkS")
			(hide yes)
			(effects
				(font
					(size 1.27 1.27)
				)
			)
		)
		(property "Value" ""
			(at 0 0 180)
			(layer "F.Fab")
			(effects
				(font
					(size 1.27 1.27)
				)
			)
		)
		(duplicate_pad_numbers_are_jumpers no)
		(fp_line
			(start 0.7874 0.4064)
			(end -0.7874 0.4064)
			(stroke
				(width 0.1524)
				(type default)
			)
			(layer "F.SilkS")
		)
		(fp_line
			(start 0.7874 -0.4064)
			(end 0.7874 0.4064)
			(stroke
				(width 0.1524)
				(type default)
			)
			(layer "F.SilkS")
		)
		(fp_line
			(start -0.7874 0.4064)
			(end -0.7874 -0.4064)
			(stroke
				(width 0.1524)
				(type default)
			)
			(layer "F.SilkS")
		)
		(fp_line
			(start -0.7874 -0.4064)
			(end 0.7874 -0.4064)
			(stroke
				(width 0.1524)
				(type default)
			)
			(layer "F.SilkS")
		)
		(fp_line
			(start 0.67945 0.3048)
			(end 0.120396 0.3048)
			(stroke
				(width 0.1)
				(type default)
			)
			(layer "F.Fab")
		)
		(fp_line
			(start 0.67945 -0.3048)
			(end 0.67945 0.3048)
			(stroke
				(width 0.1)
				(type default)
			)
			(layer "F.Fab")
		)
		(fp_line
			(start 0.12065 -0.2794)
			(end 0.12065 -0.3048)
			(stroke
				(width 0.1)
				(type default)
			)
			(layer "F.Fab")
		)
		(fp_line
			(start 0.12065 -0.3048)
			(end 0.67945 -0.3048)
			(stroke
				(width 0.1)
				(type default)
			)
			(layer "F.Fab")
		)
		(fp_line
			(start 0.120396 0.3048)
			(end 0.120396 0.2794)
			(stroke
				(width 0.1)
				(type default)
			)
			(layer "F.Fab")
		)
		(fp_line
			(start 0.120396 0.2794)
			(end -0.12065 0.2794)
			(stroke
				(width 0.1)
				(type default)
			)
			(layer "F.Fab")
		)
		(fp_line
			(start -0.12065 0.3048)
			(end -0.67945 0.3048)
			(stroke
				(width 0.1)
				(type default)
			)
			(layer "F.Fab")
		)
		(fp_line
			(start -0.12065 0.2794)
			(end -0.12065 0.3048)
			(stroke
				(width 0.1)
				(type default)
			)
			(layer "F.Fab")
		)
		(fp_line
			(start -0.12065 -0.2794)
			(end 0.12065 -0.2794)
			(stroke
				(width 0.1)
				(type default)
			)
			(layer "F.Fab")
		)
		(fp_line
			(start -0.12065 -0.305054)
			(end -0.12065 -0.2794)
			(stroke
				(width 0.1)
				(type default)
			)
			(layer "F.Fab")
		)
		(fp_line
			(start -0.67945 0.3048)
			(end -0.67945 -0.305054)
			(stroke
				(width 0.1)
				(type default)
			)
			(layer "F.Fab")
		)
		(fp_line
			(start -0.67945 -0.305054)
			(end -0.12065 -0.305054)
			(stroke
				(width 0.1)
				(type default)
			)
			(layer "F.Fab")
		)
		(pad "1" smd circle
			(at -0.40005 0 180)
			(size 0 0)
			(layers "F.Cu" "F.Mask" "F.Paste")
			(net "JTAG_BMC_TDI")
		)
		(pad "2" smd circle
			(at 0.40005 0 180)
			(size 0 0)
			(layers "F.Cu" "F.Mask" "F.Paste")
			(net "JTAG_BMC_TDI_R")
		)
	)
	(footprint ""
		(layer "F.Cu")
		(at 115.95608 -122.132598 90)
		(property "Reference" "R936"
			(at 0 0 90)
			(layer "F.SilkS")
			(hide yes)
			(effects
				(font
					(size 1.27 1.27)
				)
			)
		)
		(property "Value" ""
			(at 0 0 90)
			(layer "F.Fab")
			(effects
				(font
					(size 1.27 1.27)
				)
			)
		)
		(duplicate_pad_numbers_are_jumpers no)
		(fp_line
			(start 0.7874 -0.4064)
			(end 0.7874 0.4064)
			(stroke
				(width 0.1524)
				(type default)
			)
			(layer "F.SilkS")
		)
		(fp_line
			(start -0.7874 -0.4064)
			(end 0.7874 -0.4064)
			(stroke
				(width 0.1524)
				(type default)
			)
			(layer "F.SilkS")
		)
		(fp_line
			(start 0.7874 0.4064)
			(end -0.7874 0.4064)
			(stroke
				(width 0.1524)
				(type default)
			)
			(layer "F.SilkS")
		)
		(fp_line
			(start -0.7874 0.4064)
			(end -0.7874 -0.4064)
			(stroke
				(width 0.1524)
				(type default)
			)
			(layer "F.SilkS")
		)
		(fp_line
			(start -0.12065 -0.305054)
			(end -0.12065 -0.2794)
			(stroke
				(width 0.1)
				(type default)
			)
			(layer "F.Fab")
		)
		(fp_line
			(start -0.67945 -0.305054)
			(end -0.12065 -0.305054)
			(stroke
				(width 0.1)
				(type default)
			)
			(layer "F.Fab")
		)
		(fp_line
			(start 0.67945 -0.3048)
			(end 0.67945 0.3048)
			(stroke
				(width 0.1)
				(type default)
			)
			(layer "F.Fab")
		)
		(fp_line
			(start 0.12065 -0.3048)
			(end 0.67945 -0.3048)
			(stroke
				(width 0.1)
				(type default)
			)
			(layer "F.Fab")
		)
		(fp_line
			(start 0.12065 -0.2794)
			(end 0.12065 -0.3048)
			(stroke
				(width 0.1)
				(type default)
			)
			(layer "F.Fab")
		)
		(fp_line
			(start -0.12065 -0.2794)
			(end 0.12065 -0.2794)
			(stroke
				(width 0.1)
				(type default)
			)
			(layer "F.Fab")
		)
		(fp_line
			(start 0.120396 0.2794)
			(end -0.12065 0.2794)
			(stroke
				(width 0.1)
				(type default)
			)
			(layer "F.Fab")
		)
		(fp_line
			(start -0.12065 0.2794)
			(end -0.12065 0.3048)
			(stroke
				(width 0.1)
				(type default)
			)
			(layer "F.Fab")
		)
		(fp_line
			(start 0.67945 0.3048)
			(end 0.120396 0.3048)
			(stroke
				(width 0.1)
				(type default)
			)
			(layer "F.Fab")
		)
		(fp_line
			(start 0.120396 0.3048)
			(end 0.120396 0.2794)
			(stroke
				(width 0.1)
				(type default)
			)
			(layer "F.Fab")
		)
		(fp_line
			(start -0.12065 0.3048)
			(end -0.67945 0.3048)
			(stroke
				(width 0.1)
				(type default)
			)
			(layer "F.Fab")
		)
		(fp_line
			(start -0.67945 0.3048)
			(end -0.67945 -0.305054)
			(stroke
				(width 0.1)
				(type default)
			)
			(layer "F.Fab")
		)
		(pad "1" smd circle
			(at -0.40005 0 90)
			(size 0 0)
			(layers "F.Cu" "F.Mask" "F.Paste")
			(net "RST_CPU0_DRAM_EF_N")
		)
		(pad "2" smd circle
			(at 0.40005 0 90)
			(size 0 0)
			(layers "F.Cu" "F.Mask" "F.Paste")
			(net "GND")
		)
	)
	(footprint ""
		(layer "F.Cu")
		(at 309.522622 -40.122348 180)
		(property "Reference" "R1451"
			(at 0 0 180)
			(layer "F.SilkS")
			(hide yes)
			(effects
				(font
					(size 1.27 1.27)
				)
			)
		)
		(property "Value" ""
			(at 0 0 180)
			(layer "F.Fab")
			(effects
				(font
					(size 1.27 1.27)
				)
			)
		)
		(duplicate_pad_numbers_are_jumpers no)
		(fp_line
			(start 0.7874 0.4064)
			(end -0.7874 0.4064)
			(stroke
				(width 0.1524)
				(type default)
			)
			(layer "F.SilkS")
		)
		(fp_line
			(start 0.7874 -0.4064)
			(end 0.7874 0.4064)
			(stroke
				(width 0.1524)
				(type default)
			)
			(layer "F.SilkS")
		)
		(fp_line
			(start -0.7874 0.4064)
			(end -0.7874 -0.4064)
			(stroke
				(width 0.1524)
				(type default)
			)
			(layer "F.SilkS")
		)
		(fp_line
			(start -0.7874 -0.4064)
			(end 0.7874 -0.4064)
			(stroke
				(width 0.1524)
				(type default)
			)
			(layer "F.SilkS")
		)
		(fp_line
			(start 0.67945 0.3048)
			(end 0.120396 0.3048)
			(stroke
				(width 0.1)
				(type default)
			)
			(layer "F.Fab")
		)
		(fp_line
			(start 0.67945 -0.3048)
			(end 0.67945 0.3048)
			(stroke
				(width 0.1)
				(type default)
			)
			(layer "F.Fab")
		)
		(fp_line
			(start 0.12065 -0.2794)
			(end 0.12065 -0.3048)
			(stroke
				(width 0.1)
				(type default)
			)
			(layer "F.Fab")
		)
		(fp_line
			(start 0.12065 -0.3048)
			(end 0.67945 -0.3048)
			(stroke
				(width 0.1)
				(type default)
			)
			(layer "F.Fab")
		)
		(fp_line
			(start 0.120396 0.3048)
			(end 0.120396 0.2794)
			(stroke
				(width 0.1)
				(type default)
			)
			(layer "F.Fab")
		)
		(fp_line
			(start 0.120396 0.2794)
			(end -0.12065 0.2794)
			(stroke
				(width 0.1)
				(type default)
			)
			(layer "F.Fab")
		)
		(fp_line
			(start -0.12065 0.3048)
			(end -0.67945 0.3048)
			(stroke
				(width 0.1)
				(type default)
			)
			(layer "F.Fab")
		)
		(fp_line
			(start -0.12065 0.2794)
			(end -0.12065 0.3048)
			(stroke
				(width 0.1)
				(type default)
			)
			(layer "F.Fab")
		)
		(fp_line
			(start -0.12065 -0.2794)
			(end 0.12065 -0.2794)
			(stroke
				(width 0.1)
				(type default)
			)
			(layer "F.Fab")
		)
		(fp_line
			(start -0.12065 -0.305054)
			(end -0.12065 -0.2794)
			(stroke
				(width 0.1)
				(type default)
			)
			(layer "F.Fab")
		)
		(fp_line
			(start -0.67945 0.3048)
			(end -0.67945 -0.305054)
			(stroke
				(width 0.1)
				(type default)
			)
			(layer "F.Fab")
		)
		(fp_line
			(start -0.67945 -0.305054)
			(end -0.12065 -0.305054)
			(stroke
				(width 0.1)
				(type default)
			)
			(layer "F.Fab")
		)
		(pad "1" smd circle
			(at -0.40005 0 180)
			(size 0 0)
			(layers "F.Cu" "F.Mask" "F.Paste")
			(net "PU_SMB_SML3_3V3AUX_PCH_SCL")
		)
		(pad "2" smd circle
			(at 0.40005 0 180)
			(size 0 0)
			(layers "F.Cu" "F.Mask" "F.Paste")
			(net "P3V3_AUX")
		)
	)
	(footprint ""
		(layer "F.Cu")
		(at 298.16552 -408.7114)
		(property "Reference" "R4895"
			(at 0 0 0)
			(layer "F.SilkS")
			(hide yes)
			(effects
				(font
					(size 1.27 1.27)
				)
			)
		)
		(property "Value" ""
			(at 0 0 0)
			(layer "F.Fab")
			(effects
				(font
					(size 1.27 1.27)
				)
			)
		)
		(duplicate_pad_numbers_are_jumpers no)
		(fp_line
			(start -0.7874 -0.4064)
			(end 0.7874 -0.4064)
			(stroke
				(width 0.1524)
				(type default)
			)
			(layer "F.SilkS")
		)
		(fp_line
			(start -0.7874 0.4064)
			(end -0.7874 -0.4064)
			(stroke
				(width 0.1524)
				(type default)
			)
			(layer "F.SilkS")
		)
		(fp_line
			(start 0.7874 -0.4064)
			(end 0.7874 0.4064)
			(stroke
				(width 0.1524)
				(type default)
			)
			(layer "F.SilkS")
		)
		(fp_line
			(start 0.7874 0.4064)
			(end -0.7874 0.4064)
			(stroke
				(width 0.1524)
				(type default)
			)
			(layer "F.SilkS")
		)
		(fp_line
			(start -0.67945 -0.305054)
			(end -0.12065 -0.305054)
			(stroke
				(width 0.1)
				(type default)
			)
			(layer "F.Fab")
		)
		(fp_line
			(start -0.67945 0.3048)
			(end -0.67945 -0.305054)
			(stroke
				(width 0.1)
				(type default)
			)
			(layer "F.Fab")
		)
		(fp_line
			(start -0.12065 -0.305054)
			(end -0.12065 -0.2794)
			(stroke
				(width 0.1)
				(type default)
			)
			(layer "F.Fab")
		)
		(fp_line
			(start -0.12065 -0.2794)
			(end 0.12065 -0.2794)
			(stroke
				(width 0.1)
				(type default)
			)
			(layer "F.Fab")
		)
		(fp_line
			(start -0.12065 0.2794)
			(end -0.12065 0.3048)
			(stroke
				(width 0.1)
				(type default)
			)
			(layer "F.Fab")
		)
		(fp_line
			(start -0.12065 0.3048)
			(end -0.67945 0.3048)
			(stroke
				(width 0.1)
				(type default)
			)
			(layer "F.Fab")
		)
		(fp_line
			(start 0.120396 0.2794)
			(end -0.12065 0.2794)
			(stroke
				(width 0.1)
				(type default)
			)
			(layer "F.Fab")
		)
		(fp_line
			(start 0.120396 0.3048)
			(end 0.120396 0.2794)
			(stroke
				(width 0.1)
				(type default)
			)
			(layer "F.Fab")
		)
		(fp_line
			(start 0.12065 -0.3048)
			(end 0.67945 -0.3048)
			(stroke
				(width 0.1)
				(type default)
			)
			(layer "F.Fab")
		)
		(fp_line
			(start 0.12065 -0.2794)
			(end 0.12065 -0.3048)
			(stroke
				(width 0.1)
				(type default)
			)
			(layer "F.Fab")
		)
		(fp_line
			(start 0.67945 -0.3048)
			(end 0.67945 0.3048)
			(stroke
				(width 0.1)
				(type default)
			)
			(layer "F.Fab")
		)
		(fp_line
			(start 0.67945 0.3048)
			(end 0.120396 0.3048)
			(stroke
				(width 0.1)
				(type default)
			)
			(layer "F.Fab")
		)
		(pad "1" smd circle
			(at -0.40005 0)
			(size 0 0)
			(layers "F.Cu" "F.Mask" "F.Paste")
			(net "P12V_HSC_TEMP_SDA")
		)
		(pad "2" smd circle
			(at 0.40005 0)
			(size 0 0)
			(layers "F.Cu" "F.Mask" "F.Paste")
			(net "SMB_LM75_0_3V3AUX_SDA")
		)
	)
	(footprint ""
		(layer "F.Cu")
		(at 36.930584 -112.619282)
		(property "Reference" "C2046"
			(at 0 0 0)
			(layer "F.SilkS")
			(hide yes)
			(effects
				(font
					(size 1.27 1.27)
				)
			)
		)
		(property "Value" ""
			(at 0 0 0)
			(layer "F.Fab")
			(effects
				(font
					(size 1.27 1.27)
				)
			)
		)
		(duplicate_pad_numbers_are_jumpers no)
		(fp_line
			(start -0.7874 -0.4064)
			(end 0.7874 -0.4064)
			(stroke
				(width 0.1524)
				(type default)
			)
			(layer "F.SilkS")
		)
		(fp_line
			(start -0.7874 0.4064)
			(end -0.7874 -0.4064)
			(stroke
				(width 0.1524)
				(type default)
			)
			(layer "F.SilkS")
		)
		(fp_line
			(start 0.7874 -0.4064)
			(end 0.7874 0.4064)
			(stroke
				(width 0.1524)
				(type default)
			)
			(layer "F.SilkS")
		)
		(fp_line
			(start 0.7874 0.4064)
			(end -0.7874 0.4064)
			(stroke
				(width 0.1524)
				(type default)
			)
			(layer "F.SilkS")
		)
		(fp_line
			(start -0.67945 -0.305054)
			(end -0.12065 -0.305054)
			(stroke
				(width 0.1)
				(type default)
			)
			(layer "F.Fab")
		)
		(fp_line
			(start -0.67945 0.3048)
			(end -0.67945 -0.305054)
			(stroke
				(width 0.1)
				(type default)
			)
			(layer "F.Fab")
		)
		(fp_line
			(start -0.12065 -0.305054)
			(end -0.12065 -0.2794)
			(stroke
				(width 0.1)
				(type default)
			)
			(layer "F.Fab")
		)
		(fp_line
			(start -0.12065 -0.2794)
			(end 0.12065 -0.2794)
			(stroke
				(width 0.1)
				(type default)
			)
			(layer "F.Fab")
		)
		(fp_line
			(start -0.12065 0.2794)
			(end -0.12065 0.3048)
			(stroke
				(width 0.1)
				(type default)
			)
			(layer "F.Fab")
		)
		(fp_line
			(start -0.12065 0.3048)
			(end -0.67945 0.3048)
			(stroke
				(width 0.1)
				(type default)
			)
			(layer "F.Fab")
		)
		(fp_line
			(start 0.120396 0.2794)
			(end -0.12065 0.2794)
			(stroke
				(width 0.1)
				(type default)
			)
			(layer "F.Fab")
		)
		(fp_line
			(start 0.120396 0.3048)
			(end 0.120396 0.2794)
			(stroke
				(width 0.1)
				(type default)
			)
			(layer "F.Fab")
		)
		(fp_line
			(start 0.12065 -0.3048)
			(end 0.67945 -0.3048)
			(stroke
				(width 0.1)
				(type default)
			)
			(layer "F.Fab")
		)
		(fp_line
			(start 0.12065 -0.2794)
			(end 0.12065 -0.3048)
			(stroke
				(width 0.1)
				(type default)
			)
			(layer "F.Fab")
		)
		(fp_line
			(start 0.67945 -0.3048)
			(end 0.67945 0.3048)
			(stroke
				(width 0.1)
				(type default)
			)
			(layer "F.Fab")
		)
		(fp_line
			(start 0.67945 0.3048)
			(end 0.120396 0.3048)
			(stroke
				(width 0.1)
				(type default)
			)
			(layer "F.Fab")
		)
		(pad "1" smd circle
			(at -0.40005 0)
			(size 0 0)
			(layers "F.Cu" "F.Mask" "F.Paste")
			(net "P12V_AUX_ADC_TIC")
		)
		(pad "2" smd circle
			(at 0.40005 0)
			(size 0 0)
			(layers "F.Cu" "F.Mask" "F.Paste")
			(net "GND")
		)
	)
	(footprint ""
		(layer "F.Cu")
		(at 197.19036 -116.804948 180)
		(property "Reference" "R1811"
			(at 0 0 180)
			(layer "F.SilkS")
			(hide yes)
			(effects
				(font
					(size 1.27 1.27)
				)
			)
		)
		(property "Value" ""
			(at 0 0 180)
			(layer "F.Fab")
			(effects
				(font
					(size 1.27 1.27)
				)
			)
		)
		(duplicate_pad_numbers_are_jumpers no)
		(fp_line
			(start 0.7874 0.4064)
			(end -0.7874 0.4064)
			(stroke
				(width 0.1524)
				(type default)
			)
			(layer "F.SilkS")
		)
		(fp_line
			(start 0.7874 -0.4064)
			(end 0.7874 0.4064)
			(stroke
				(width 0.1524)
				(type default)
			)
			(layer "F.SilkS")
		)
		(fp_line
			(start -0.7874 0.4064)
			(end -0.7874 -0.4064)
			(stroke
				(width 0.1524)
				(type default)
			)
			(layer "F.SilkS")
		)
		(fp_line
			(start -0.7874 -0.4064)
			(end 0.7874 -0.4064)
			(stroke
				(width 0.1524)
				(type default)
			)
			(layer "F.SilkS")
		)
		(fp_line
			(start 0.67945 0.3048)
			(end 0.120396 0.3048)
			(stroke
				(width 0.1)
				(type default)
			)
			(layer "F.Fab")
		)
		(fp_line
			(start 0.67945 -0.3048)
			(end 0.67945 0.3048)
			(stroke
				(width 0.1)
				(type default)
			)
			(layer "F.Fab")
		)
		(fp_line
			(start 0.12065 -0.2794)
			(end 0.12065 -0.3048)
			(stroke
				(width 0.1)
				(type default)
			)
			(layer "F.Fab")
		)
		(fp_line
			(start 0.12065 -0.3048)
			(end 0.67945 -0.3048)
			(stroke
				(width 0.1)
				(type default)
			)
			(layer "F.Fab")
		)
		(fp_line
			(start 0.120396 0.3048)
			(end 0.120396 0.2794)
			(stroke
				(width 0.1)
				(type default)
			)
			(layer "F.Fab")
		)
		(fp_line
			(start 0.120396 0.2794)
			(end -0.12065 0.2794)
			(stroke
				(width 0.1)
				(type default)
			)
			(layer "F.Fab")
		)
		(fp_line
			(start -0.12065 0.3048)
			(end -0.67945 0.3048)
			(stroke
				(width 0.1)
				(type default)
			)
			(layer "F.Fab")
		)
		(fp_line
			(start -0.12065 0.2794)
			(end -0.12065 0.3048)
			(stroke
				(width 0.1)
				(type default)
			)
			(layer "F.Fab")
		)
		(fp_line
			(start -0.12065 -0.2794)
			(end 0.12065 -0.2794)
			(stroke
				(width 0.1)
				(type default)
			)
			(layer "F.Fab")
		)
		(fp_line
			(start -0.12065 -0.305054)
			(end -0.12065 -0.2794)
			(stroke
				(width 0.1)
				(type default)
			)
			(layer "F.Fab")
		)
		(fp_line
			(start -0.67945 0.3048)
			(end -0.67945 -0.305054)
			(stroke
				(width 0.1)
				(type default)
			)
			(layer "F.Fab")
		)
		(fp_line
			(start -0.67945 -0.305054)
			(end -0.12065 -0.305054)
			(stroke
				(width 0.1)
				(type default)
			)
			(layer "F.Fab")
		)
		(pad "1" smd circle
			(at -0.40005 0 180)
			(size 0 0)
			(layers "F.Cu" "F.Mask" "F.Paste")
			(net "RST_SGPIO_RESET_N")
		)
		(pad "2" smd circle
			(at 0.40005 0 180)
			(size 0 0)
			(layers "F.Cu" "F.Mask" "F.Paste")
			(net "RST_SGPIO_RESET_N_R")
		)
	)
	(footprint ""
		(layer "F.Cu")
		(at 136.360154 -402.371052 -90)
		(property "Reference" "C752"
			(at 0 0 270)
			(layer "F.SilkS")
			(hide yes)
			(effects
				(font
					(size 1.27 1.27)
				)
			)
		)
		(property "Value" ""
			(at 0 0 270)
			(layer "F.Fab")
			(effects
				(font
					(size 1.27 1.27)
				)
			)
		)
		(duplicate_pad_numbers_are_jumpers no)
		(fp_line
			(start -0.299974 0.150114)
			(end -0.299974 -0.150114)
			(stroke
				(width 0.1)
				(type default)
			)
			(layer "F.Fab")
		)
		(fp_line
			(start 0.299974 0.150114)
			(end -0.299974 0.150114)
			(stroke
				(width 0.1)
				(type default)
			)
			(layer "F.Fab")
		)
		(fp_line
			(start -0.299974 -0.150114)
			(end 0.299974 -0.150114)
			(stroke
				(width 0.1)
				(type default)
			)
			(layer "F.Fab")
		)
		(fp_line
			(start 0.299974 -0.150114)
			(end 0.299974 0.150114)
			(stroke
				(width 0.1)
				(type default)
			)
			(layer "F.Fab")
		)
		(pad "1" smd rect
			(at -0.2667 0 270)
			(size 0.3048 0.381)
			(layers "F.Cu" "F.Mask" "F.Paste")
			(net "P5E_CPU1_PE2_TX_C_DN<10>")
		)
		(pad "2" smd rect
			(at 0.2667 0 270)
			(size 0.3048 0.381)
			(layers "F.Cu" "F.Mask" "F.Paste")
			(net "P5E_CPU1_PE2_TX_DN<10>")
		)
	)
	(footprint ""
		(layer "F.Cu")
		(at 213.19744 -30.246828 90)
		(property "Reference" "R4091"
			(at 0 0 90)
			(layer "F.SilkS")
			(hide yes)
			(effects
				(font
					(size 1.27 1.27)
				)
			)
		)
		(property "Value" ""
			(at 0 0 90)
			(layer "F.Fab")
			(effects
				(font
					(size 1.27 1.27)
				)
			)
		)
		(duplicate_pad_numbers_are_jumpers no)
		(fp_line
			(start 0.7874 -0.4064)
			(end 0.7874 0.4064)
			(stroke
				(width 0.1524)
				(type default)
			)
			(layer "F.SilkS")
		)
		(fp_line
			(start -0.7874 -0.4064)
			(end 0.7874 -0.4064)
			(stroke
				(width 0.1524)
				(type default)
			)
			(layer "F.SilkS")
		)
		(fp_line
			(start 0.7874 0.4064)
			(end -0.7874 0.4064)
			(stroke
				(width 0.1524)
				(type default)
			)
			(layer "F.SilkS")
		)
		(fp_line
			(start -0.7874 0.4064)
			(end -0.7874 -0.4064)
			(stroke
				(width 0.1524)
				(type default)
			)
			(layer "F.SilkS")
		)
		(fp_line
			(start -0.12065 -0.305054)
			(end -0.12065 -0.2794)
			(stroke
				(width 0.1)
				(type default)
			)
			(layer "F.Fab")
		)
		(fp_line
			(start -0.67945 -0.305054)
			(end -0.12065 -0.305054)
			(stroke
				(width 0.1)
				(type default)
			)
			(layer "F.Fab")
		)
		(fp_line
			(start 0.67945 -0.3048)
			(end 0.67945 0.3048)
			(stroke
				(width 0.1)
				(type default)
			)
			(layer "F.Fab")
		)
		(fp_line
			(start 0.12065 -0.3048)
			(end 0.67945 -0.3048)
			(stroke
				(width 0.1)
				(type default)
			)
			(layer "F.Fab")
		)
		(fp_line
			(start 0.12065 -0.2794)
			(end 0.12065 -0.3048)
			(stroke
				(width 0.1)
				(type default)
			)
			(layer "F.Fab")
		)
		(fp_line
			(start -0.12065 -0.2794)
			(end 0.12065 -0.2794)
			(stroke
				(width 0.1)
				(type default)
			)
			(layer "F.Fab")
		)
		(fp_line
			(start 0.120396 0.2794)
			(end -0.12065 0.2794)
			(stroke
				(width 0.1)
				(type default)
			)
			(layer "F.Fab")
		)
		(fp_line
			(start -0.12065 0.2794)
			(end -0.12065 0.3048)
			(stroke
				(width 0.1)
				(type default)
			)
			(layer "F.Fab")
		)
		(fp_line
			(start 0.67945 0.3048)
			(end 0.120396 0.3048)
			(stroke
				(width 0.1)
				(type default)
			)
			(layer "F.Fab")
		)
		(fp_line
			(start 0.120396 0.3048)
			(end 0.120396 0.2794)
			(stroke
				(width 0.1)
				(type default)
			)
			(layer "F.Fab")
		)
		(fp_line
			(start -0.12065 0.3048)
			(end -0.67945 0.3048)
			(stroke
				(width 0.1)
				(type default)
			)
			(layer "F.Fab")
		)
		(fp_line
			(start -0.67945 0.3048)
			(end -0.67945 -0.305054)
			(stroke
				(width 0.1)
				(type default)
			)
			(layer "F.Fab")
		)
		(pad "1" smd circle
			(at -0.40005 0 90)
			(size 0 0)
			(layers "F.Cu" "F.Mask" "F.Paste")
			(net "P3V3_AUX")
		)
		(pad "2" smd circle
			(at 0.40005 0 90)
			(size 0 0)
			(layers "F.Cu" "F.Mask" "F.Paste")
			(net "P12V_SCM_ADC_ALERT_R")
		)
	)
	(footprint ""
		(layer "F.Cu")
		(at 366.48263 -247.715024 90)
		(property "Reference" "C993"
			(at 0 0 90)
			(layer "F.SilkS")
			(hide yes)
			(effects
				(font
					(size 1.27 1.27)
				)
			)
		)
		(property "Value" ""
			(at 0 0 90)
			(layer "F.Fab")
			(effects
				(font
					(size 1.27 1.27)
				)
			)
		)
		(duplicate_pad_numbers_are_jumpers no)
		(fp_line
			(start 0.7874 -0.4064)
			(end 0.7874 0.4064)
			(stroke
				(width 0.1524)
				(type default)
			)
			(layer "F.SilkS")
		)
		(fp_line
			(start -0.7874 -0.4064)
			(end 0.7874 -0.4064)
			(stroke
				(width 0.1524)
				(type default)
			)
			(layer "F.SilkS")
		)
		(fp_line
			(start 0.7874 0.4064)
			(end -0.7874 0.4064)
			(stroke
				(width 0.1524)
				(type default)
			)
			(layer "F.SilkS")
		)
		(fp_line
			(start -0.7874 0.4064)
			(end -0.7874 -0.4064)
			(stroke
				(width 0.1524)
				(type default)
			)
			(layer "F.SilkS")
		)
		(fp_line
			(start -0.12065 -0.305054)
			(end -0.12065 -0.2794)
			(stroke
				(width 0.1)
				(type default)
			)
			(layer "F.Fab")
		)
		(fp_line
			(start -0.67945 -0.305054)
			(end -0.12065 -0.305054)
			(stroke
				(width 0.1)
				(type default)
			)
			(layer "F.Fab")
		)
		(fp_line
			(start 0.67945 -0.3048)
			(end 0.67945 0.3048)
			(stroke
				(width 0.1)
				(type default)
			)
			(layer "F.Fab")
		)
		(fp_line
			(start 0.12065 -0.3048)
			(end 0.67945 -0.3048)
			(stroke
				(width 0.1)
				(type default)
			)
			(layer "F.Fab")
		)
		(fp_line
			(start 0.12065 -0.2794)
			(end 0.12065 -0.3048)
			(stroke
				(width 0.1)
				(type default)
			)
			(layer "F.Fab")
		)
		(fp_line
			(start -0.12065 -0.2794)
			(end 0.12065 -0.2794)
			(stroke
				(width 0.1)
				(type default)
			)
			(layer "F.Fab")
		)
		(fp_line
			(start 0.120396 0.2794)
			(end -0.12065 0.2794)
			(stroke
				(width 0.1)
				(type default)
			)
			(layer "F.Fab")
		)
		(fp_line
			(start -0.12065 0.2794)
			(end -0.12065 0.3048)
			(stroke
				(width 0.1)
				(type default)
			)
			(layer "F.Fab")
		)
		(fp_line
			(start 0.67945 0.3048)
			(end 0.120396 0.3048)
			(stroke
				(width 0.1)
				(type default)
			)
			(layer "F.Fab")
		)
		(fp_line
			(start 0.120396 0.3048)
			(end 0.120396 0.2794)
			(stroke
				(width 0.1)
				(type default)
			)
			(layer "F.Fab")
		)
		(fp_line
			(start -0.12065 0.3048)
			(end -0.67945 0.3048)
			(stroke
				(width 0.1)
				(type default)
			)
			(layer "F.Fab")
		)
		(fp_line
			(start -0.67945 0.3048)
			(end -0.67945 -0.305054)
			(stroke
				(width 0.1)
				(type default)
			)
			(layer "F.Fab")
		)
		(pad "1" smd circle
			(at -0.40005 0 90)
			(size 0 0)
			(layers "F.Cu" "F.Mask" "F.Paste")
			(net "PVCCIN_CPU0")
		)
		(pad "2" smd circle
			(at 0.40005 0 90)
			(size 0 0)
			(layers "F.Cu" "F.Mask" "F.Paste")
			(net "GND")
		)
	)
	(footprint ""
		(layer "F.Cu")
		(at 98.1329 -413.273748)
		(property "Reference" "R4544"
			(at 0 0 0)
			(layer "F.SilkS")
			(hide yes)
			(effects
				(font
					(size 1.27 1.27)
				)
			)
		)
		(property "Value" ""
			(at 0 0 0)
			(layer "F.Fab")
			(effects
				(font
					(size 1.27 1.27)
				)
			)
		)
		(duplicate_pad_numbers_are_jumpers no)
		(fp_line
			(start -0.7874 -0.4064)
			(end 0.7874 -0.4064)
			(stroke
				(width 0.1524)
				(type default)
			)
			(layer "F.SilkS")
		)
		(fp_line
			(start -0.7874 0.4064)
			(end -0.7874 -0.4064)
			(stroke
				(width 0.1524)
				(type default)
			)
			(layer "F.SilkS")
		)
		(fp_line
			(start 0.7874 -0.4064)
			(end 0.7874 0.4064)
			(stroke
				(width 0.1524)
				(type default)
			)
			(layer "F.SilkS")
		)
		(fp_line
			(start 0.7874 0.4064)
			(end -0.7874 0.4064)
			(stroke
				(width 0.1524)
				(type default)
			)
			(layer "F.SilkS")
		)
		(fp_line
			(start -0.67945 -0.305054)
			(end -0.12065 -0.305054)
			(stroke
				(width 0.1)
				(type default)
			)
			(layer "F.Fab")
		)
		(fp_line
			(start -0.67945 0.3048)
			(end -0.67945 -0.305054)
			(stroke
				(width 0.1)
				(type default)
			)
			(layer "F.Fab")
		)
		(fp_line
			(start -0.12065 -0.305054)
			(end -0.12065 -0.2794)
			(stroke
				(width 0.1)
				(type default)
			)
			(layer "F.Fab")
		)
		(fp_line
			(start -0.12065 -0.2794)
			(end 0.12065 -0.2794)
			(stroke
				(width 0.1)
				(type default)
			)
			(layer "F.Fab")
		)
		(fp_line
			(start -0.12065 0.2794)
			(end -0.12065 0.3048)
			(stroke
				(width 0.1)
				(type default)
			)
			(layer "F.Fab")
		)
		(fp_line
			(start -0.12065 0.3048)
			(end -0.67945 0.3048)
			(stroke
				(width 0.1)
				(type default)
			)
			(layer "F.Fab")
		)
		(fp_line
			(start 0.120396 0.2794)
			(end -0.12065 0.2794)
			(stroke
				(width 0.1)
				(type default)
			)
			(layer "F.Fab")
		)
		(fp_line
			(start 0.120396 0.3048)
			(end 0.120396 0.2794)
			(stroke
				(width 0.1)
				(type default)
			)
			(layer "F.Fab")
		)
		(fp_line
			(start 0.12065 -0.3048)
			(end 0.67945 -0.3048)
			(stroke
				(width 0.1)
				(type default)
			)
			(layer "F.Fab")
		)
		(fp_line
			(start 0.12065 -0.2794)
			(end 0.12065 -0.3048)
			(stroke
				(width 0.1)
				(type default)
			)
			(layer "F.Fab")
		)
		(fp_line
			(start 0.67945 -0.3048)
			(end 0.67945 0.3048)
			(stroke
				(width 0.1)
				(type default)
			)
			(layer "F.Fab")
		)
		(fp_line
			(start 0.67945 0.3048)
			(end 0.120396 0.3048)
			(stroke
				(width 0.1)
				(type default)
			)
			(layer "F.Fab")
		)
		(pad "1" smd circle
			(at -0.40005 0)
			(size 0 0)
			(layers "F.Cu" "F.Mask" "F.Paste")
			(net "HGX_DETECT_N")
		)
		(pad "2" smd circle
			(at 0.40005 0)
			(size 0 0)
			(layers "F.Cu" "F.Mask" "F.Paste")
			(net "GND")
		)
	)
	(footprint ""
		(layer "F.Cu")
		(at 77.780896 -70.78599)
		(property "Reference" "D66"
			(at -40.319706 50.178462 90)
			(unlocked yes)
			(layer "F.SilkS")
			(effects
				(font
					(size 0.635 0.4064)
					(thickness 0.1524)
				)
				(justify left)
			)
		)
		(property "Value" ""
			(at 0 0 0)
			(layer "F.Fab")
			(effects
				(font
					(size 1.27 1.27)
				)
			)
		)
		(duplicate_pad_numbers_are_jumpers no)
		(fp_line
			(start -0.90678 0.4826)
			(end -0.90678 -0.4699)
			(stroke
				(width 0.1524)
				(type default)
			)
			(layer "F.SilkS")
		)
		(fp_line
			(start -0.89408 -0.4826)
			(end 0.90678 -0.4826)
			(stroke
				(width 0.1524)
				(type default)
			)
			(layer "F.SilkS")
		)
		(fp_line
			(start -0.79248 -0.4826)
			(end 1.03378 -0.4826)
			(stroke
				(width 0.1524)
				(type default)
			)
			(layer "F.SilkS")
		)
		(fp_line
			(start -0.64008 -0.4826)
			(end 1.16078 -0.4826)
			(stroke
				(width 0.1524)
				(type default)
			)
			(layer "F.SilkS")
		)
		(fp_line
			(start 0.90678 -0.4826)
			(end 0.90678 0.4826)
			(stroke
				(width 0.1524)
				(type default)
			)
			(layer "F.SilkS")
		)
		(fp_line
			(start 0.90678 0.4826)
			(end -0.90678 0.4826)
			(stroke
				(width 0.1524)
				(type default)
			)
			(layer "F.SilkS")
		)
		(fp_line
			(start 1.03378 -0.4826)
			(end 1.03378 0.4826)
			(stroke
				(width 0.1524)
				(type default)
			)
			(layer "F.SilkS")
		)
		(fp_line
			(start 1.03378 0.4826)
			(end -0.79248 0.4826)
			(stroke
				(width 0.1524)
				(type default)
			)
			(layer "F.SilkS")
		)
		(fp_line
			(start 1.16078 -0.4826)
			(end 1.16078 0.4826)
			(stroke
				(width 0.1524)
				(type default)
			)
			(layer "F.SilkS")
		)
		(fp_line
			(start 1.16078 0.4826)
			(end -0.64008 0.4826)
			(stroke
				(width 0.1524)
				(type default)
			)
			(layer "F.SilkS")
		)
		(fp_line
			(start -0.499872 -0.249936)
			(end 0.499872 -0.249936)
			(stroke
				(width 0.1)
				(type default)
			)
			(layer "F.Fab")
		)
		(fp_line
			(start -0.499872 0.249936)
			(end -0.499872 -0.249936)
			(stroke
				(width 0.1)
				(type default)
			)
			(layer "F.Fab")
		)
		(fp_line
			(start 0.499872 -0.249936)
			(end 0.499872 0.249936)
			(stroke
				(width 0.1)
				(type default)
			)
			(layer "F.Fab")
		)
		(fp_line
			(start 0.499872 0.249936)
			(end -0.499872 0.249936)
			(stroke
				(width 0.1)
				(type default)
			)
			(layer "F.Fab")
		)
		(pad "A" smd rect
			(at -0.47498 0)
			(size 0.6096 0.7112)
			(layers "F.Cu" "F.Mask" "F.Paste")
			(net "LED_RST_PLD_CPU0_DRAM_CD_N")
		)
		(pad "C" smd rect
			(at 0.47498 0)
			(size 0.6096 0.7112)
			(layers "F.Cu" "F.Mask" "F.Paste")
			(net "LED_RST_PLD_CPU0_DRAM_CD_N_D")
		)
	)
	(footprint ""
		(layer "F.Cu")
		(at 369.292632 -397.519398)
		(property "Reference" "R2725"
			(at 0 0 0)
			(layer "F.SilkS")
			(hide yes)
			(effects
				(font
					(size 1.27 1.27)
				)
			)
		)
		(property "Value" ""
			(at 0 0 0)
			(layer "F.Fab")
			(effects
				(font
					(size 1.27 1.27)
				)
			)
		)
		(duplicate_pad_numbers_are_jumpers no)
		(fp_line
			(start -0.7874 -0.4064)
			(end 0.7874 -0.4064)
			(stroke
				(width 0.1524)
				(type default)
			)
			(layer "F.SilkS")
		)
		(fp_line
			(start -0.7874 0.4064)
			(end -0.7874 -0.4064)
			(stroke
				(width 0.1524)
				(type default)
			)
			(layer "F.SilkS")
		)
		(fp_line
			(start 0.7874 -0.4064)
			(end 0.7874 0.4064)
			(stroke
				(width 0.1524)
				(type default)
			)
			(layer "F.SilkS")
		)
		(fp_line
			(start 0.7874 0.4064)
			(end -0.7874 0.4064)
			(stroke
				(width 0.1524)
				(type default)
			)
			(layer "F.SilkS")
		)
		(fp_line
			(start -0.67945 -0.305054)
			(end -0.12065 -0.305054)
			(stroke
				(width 0.1)
				(type default)
			)
			(layer "F.Fab")
		)
		(fp_line
			(start -0.67945 0.3048)
			(end -0.67945 -0.305054)
			(stroke
				(width 0.1)
				(type default)
			)
			(layer "F.Fab")
		)
		(fp_line
			(start -0.12065 -0.305054)
			(end -0.12065 -0.2794)
			(stroke
				(width 0.1)
				(type default)
			)
			(layer "F.Fab")
		)
		(fp_line
			(start -0.12065 -0.2794)
			(end 0.12065 -0.2794)
			(stroke
				(width 0.1)
				(type default)
			)
			(layer "F.Fab")
		)
		(fp_line
			(start -0.12065 0.2794)
			(end -0.12065 0.3048)
			(stroke
				(width 0.1)
				(type default)
			)
			(layer "F.Fab")
		)
		(fp_line
			(start -0.12065 0.3048)
			(end -0.67945 0.3048)
			(stroke
				(width 0.1)
				(type default)
			)
			(layer "F.Fab")
		)
		(fp_line
			(start 0.120396 0.2794)
			(end -0.12065 0.2794)
			(stroke
				(width 0.1)
				(type default)
			)
			(layer "F.Fab")
		)
		(fp_line
			(start 0.120396 0.3048)
			(end 0.120396 0.2794)
			(stroke
				(width 0.1)
				(type default)
			)
			(layer "F.Fab")
		)
		(fp_line
			(start 0.12065 -0.3048)
			(end 0.67945 -0.3048)
			(stroke
				(width 0.1)
				(type default)
			)
			(layer "F.Fab")
		)
		(fp_line
			(start 0.12065 -0.2794)
			(end 0.12065 -0.3048)
			(stroke
				(width 0.1)
				(type default)
			)
			(layer "F.Fab")
		)
		(fp_line
			(start 0.67945 -0.3048)
			(end 0.67945 0.3048)
			(stroke
				(width 0.1)
				(type default)
			)
			(layer "F.Fab")
		)
		(fp_line
			(start 0.67945 0.3048)
			(end 0.120396 0.3048)
			(stroke
				(width 0.1)
				(type default)
			)
			(layer "F.Fab")
		)
		(pad "1" smd circle
			(at -0.40005 0)
			(size 0 0)
			(layers "F.Cu" "F.Mask" "F.Paste")
			(net "I3C_BMC_SWB_R_SCL")
		)
		(pad "2" smd circle
			(at 0.40005 0)
			(size 0 0)
			(layers "F.Cu" "F.Mask" "F.Paste")
			(net "I3C_BMC_SWB_BUF_R_SCL")
		)
	)
	(footprint ""
		(layer "F.Cu")
		(at 24.046942 -417.159948)
		(property "Reference" "R3512"
			(at 0 0 0)
			(layer "F.SilkS")
			(hide yes)
			(effects
				(font
					(size 1.27 1.27)
				)
			)
		)
		(property "Value" ""
			(at 0 0 0)
			(layer "F.Fab")
			(effects
				(font
					(size 1.27 1.27)
				)
			)
		)
		(duplicate_pad_numbers_are_jumpers no)
		(fp_line
			(start -0.7874 -0.4064)
			(end 0.7874 -0.4064)
			(stroke
				(width 0.1524)
				(type default)
			)
			(layer "F.SilkS")
		)
		(fp_line
			(start -0.7874 0.4064)
			(end -0.7874 -0.4064)
			(stroke
				(width 0.1524)
				(type default)
			)
			(layer "F.SilkS")
		)
		(fp_line
			(start 0.7874 -0.4064)
			(end 0.7874 0.4064)
			(stroke
				(width 0.1524)
				(type default)
			)
			(layer "F.SilkS")
		)
		(fp_line
			(start 0.7874 0.4064)
			(end -0.7874 0.4064)
			(stroke
				(width 0.1524)
				(type default)
			)
			(layer "F.SilkS")
		)
		(fp_line
			(start -0.67945 -0.305054)
			(end -0.12065 -0.305054)
			(stroke
				(width 0.1)
				(type default)
			)
			(layer "F.Fab")
		)
		(fp_line
			(start -0.67945 0.3048)
			(end -0.67945 -0.305054)
			(stroke
				(width 0.1)
				(type default)
			)
			(layer "F.Fab")
		)
		(fp_line
			(start -0.12065 -0.305054)
			(end -0.12065 -0.2794)
			(stroke
				(width 0.1)
				(type default)
			)
			(layer "F.Fab")
		)
		(fp_line
			(start -0.12065 -0.2794)
			(end 0.12065 -0.2794)
			(stroke
				(width 0.1)
				(type default)
			)
			(layer "F.Fab")
		)
		(fp_line
			(start -0.12065 0.2794)
			(end -0.12065 0.3048)
			(stroke
				(width 0.1)
				(type default)
			)
			(layer "F.Fab")
		)
		(fp_line
			(start -0.12065 0.3048)
			(end -0.67945 0.3048)
			(stroke
				(width 0.1)
				(type default)
			)
			(layer "F.Fab")
		)
		(fp_line
			(start 0.120396 0.2794)
			(end -0.12065 0.2794)
			(stroke
				(width 0.1)
				(type default)
			)
			(layer "F.Fab")
		)
		(fp_line
			(start 0.120396 0.3048)
			(end 0.120396 0.2794)
			(stroke
				(width 0.1)
				(type default)
			)
			(layer "F.Fab")
		)
		(fp_line
			(start 0.12065 -0.3048)
			(end 0.67945 -0.3048)
			(stroke
				(width 0.1)
				(type default)
			)
			(layer "F.Fab")
		)
		(fp_line
			(start 0.12065 -0.2794)
			(end 0.12065 -0.3048)
			(stroke
				(width 0.1)
				(type default)
			)
			(layer "F.Fab")
		)
		(fp_line
			(start 0.67945 -0.3048)
			(end 0.67945 0.3048)
			(stroke
				(width 0.1)
				(type default)
			)
			(layer "F.Fab")
		)
		(fp_line
			(start 0.67945 0.3048)
			(end 0.120396 0.3048)
			(stroke
				(width 0.1)
				(type default)
			)
			(layer "F.Fab")
		)
		(pad "1" smd circle
			(at -0.40005 0)
			(size 0 0)
			(layers "F.Cu" "F.Mask" "F.Paste")
			(net "P3V3_AUX")
		)
		(pad "2" smd circle
			(at 0.40005 0)
			(size 0 0)
			(layers "F.Cu" "F.Mask" "F.Paste")
			(net "FM_GPU_PWRGD")
		)
	)
	(footprint ""
		(layer "F.Cu")
		(at 432.974496 -109.13745 90)
		(property "Reference" "PR5481"
			(at 0 0 90)
			(layer "F.SilkS")
			(hide yes)
			(effects
				(font
					(size 1.27 1.27)
				)
			)
		)
		(property "Value" ""
			(at 0 0 90)
			(layer "F.Fab")
			(effects
				(font
					(size 1.27 1.27)
				)
			)
		)
		(duplicate_pad_numbers_are_jumpers no)
		(fp_line
			(start 0.7874 -0.4064)
			(end 0.7874 0.4064)
			(stroke
				(width 0.1524)
				(type default)
			)
			(layer "F.SilkS")
		)
		(fp_line
			(start -0.7874 -0.4064)
			(end 0.7874 -0.4064)
			(stroke
				(width 0.1524)
				(type default)
			)
			(layer "F.SilkS")
		)
		(fp_line
			(start 0.7874 0.4064)
			(end -0.7874 0.4064)
			(stroke
				(width 0.1524)
				(type default)
			)
			(layer "F.SilkS")
		)
		(fp_line
			(start -0.7874 0.4064)
			(end -0.7874 -0.4064)
			(stroke
				(width 0.1524)
				(type default)
			)
			(layer "F.SilkS")
		)
		(fp_line
			(start -0.12065 -0.305054)
			(end -0.12065 -0.2794)
			(stroke
				(width 0.1)
				(type default)
			)
			(layer "F.Fab")
		)
		(fp_line
			(start -0.67945 -0.305054)
			(end -0.12065 -0.305054)
			(stroke
				(width 0.1)
				(type default)
			)
			(layer "F.Fab")
		)
		(fp_line
			(start 0.67945 -0.3048)
			(end 0.67945 0.3048)
			(stroke
				(width 0.1)
				(type default)
			)
			(layer "F.Fab")
		)
		(fp_line
			(start 0.12065 -0.3048)
			(end 0.67945 -0.3048)
			(stroke
				(width 0.1)
				(type default)
			)
			(layer "F.Fab")
		)
		(fp_line
			(start 0.12065 -0.2794)
			(end 0.12065 -0.3048)
			(stroke
				(width 0.1)
				(type default)
			)
			(layer "F.Fab")
		)
		(fp_line
			(start -0.12065 -0.2794)
			(end 0.12065 -0.2794)
			(stroke
				(width 0.1)
				(type default)
			)
			(layer "F.Fab")
		)
		(fp_line
			(start 0.120396 0.2794)
			(end -0.12065 0.2794)
			(stroke
				(width 0.1)
				(type default)
			)
			(layer "F.Fab")
		)
		(fp_line
			(start -0.12065 0.2794)
			(end -0.12065 0.3048)
			(stroke
				(width 0.1)
				(type default)
			)
			(layer "F.Fab")
		)
		(fp_line
			(start 0.67945 0.3048)
			(end 0.120396 0.3048)
			(stroke
				(width 0.1)
				(type default)
			)
			(layer "F.Fab")
		)
		(fp_line
			(start 0.120396 0.3048)
			(end 0.120396 0.2794)
			(stroke
				(width 0.1)
				(type default)
			)
			(layer "F.Fab")
		)
		(fp_line
			(start -0.12065 0.3048)
			(end -0.67945 0.3048)
			(stroke
				(width 0.1)
				(type default)
			)
			(layer "F.Fab")
		)
		(fp_line
			(start -0.67945 0.3048)
			(end -0.67945 -0.305054)
			(stroke
				(width 0.1)
				(type default)
			)
			(layer "F.Fab")
		)
		(pad "1" smd circle
			(at -0.40005 0 90)
			(size 0 0)
			(layers "F.Cu" "F.Mask" "F.Paste")
			(net "P3V3_OCP_SENSE_1")
		)
		(pad "2" smd circle
			(at 0.40005 0 90)
			(size 0 0)
			(layers "F.Cu" "F.Mask" "F.Paste")
			(net "GND")
		)
	)
	(footprint ""
		(layer "F.Cu")
		(at 445.760602 -77.829918 90)
		(property "Reference" "PR834"
			(at 0 0 90)
			(layer "F.SilkS")
			(hide yes)
			(effects
				(font
					(size 1.27 1.27)
				)
			)
		)
		(property "Value" ""
			(at 0 0 90)
			(layer "F.Fab")
			(effects
				(font
					(size 1.27 1.27)
				)
			)
		)
		(duplicate_pad_numbers_are_jumpers no)
		(fp_line
			(start 0.7874 -0.4064)
			(end 0.7874 0.4064)
			(stroke
				(width 0.1524)
				(type default)
			)
			(layer "F.SilkS")
		)
		(fp_line
			(start -0.7874 -0.4064)
			(end 0.7874 -0.4064)
			(stroke
				(width 0.1524)
				(type default)
			)
			(layer "F.SilkS")
		)
		(fp_line
			(start 0.7874 0.4064)
			(end -0.7874 0.4064)
			(stroke
				(width 0.1524)
				(type default)
			)
			(layer "F.SilkS")
		)
		(fp_line
			(start -0.7874 0.4064)
			(end -0.7874 -0.4064)
			(stroke
				(width 0.1524)
				(type default)
			)
			(layer "F.SilkS")
		)
		(fp_line
			(start -0.12065 -0.305054)
			(end -0.12065 -0.2794)
			(stroke
				(width 0.1)
				(type default)
			)
			(layer "F.Fab")
		)
		(fp_line
			(start -0.67945 -0.305054)
			(end -0.12065 -0.305054)
			(stroke
				(width 0.1)
				(type default)
			)
			(layer "F.Fab")
		)
		(fp_line
			(start 0.67945 -0.3048)
			(end 0.67945 0.3048)
			(stroke
				(width 0.1)
				(type default)
			)
			(layer "F.Fab")
		)
		(fp_line
			(start 0.12065 -0.3048)
			(end 0.67945 -0.3048)
			(stroke
				(width 0.1)
				(type default)
			)
			(layer "F.Fab")
		)
		(fp_line
			(start 0.12065 -0.2794)
			(end 0.12065 -0.3048)
			(stroke
				(width 0.1)
				(type default)
			)
			(layer "F.Fab")
		)
		(fp_line
			(start -0.12065 -0.2794)
			(end 0.12065 -0.2794)
			(stroke
				(width 0.1)
				(type default)
			)
			(layer "F.Fab")
		)
		(fp_line
			(start 0.120396 0.2794)
			(end -0.12065 0.2794)
			(stroke
				(width 0.1)
				(type default)
			)
			(layer "F.Fab")
		)
		(fp_line
			(start -0.12065 0.2794)
			(end -0.12065 0.3048)
			(stroke
				(width 0.1)
				(type default)
			)
			(layer "F.Fab")
		)
		(fp_line
			(start 0.67945 0.3048)
			(end 0.120396 0.3048)
			(stroke
				(width 0.1)
				(type default)
			)
			(layer "F.Fab")
		)
		(fp_line
			(start 0.120396 0.3048)
			(end 0.120396 0.2794)
			(stroke
				(width 0.1)
				(type default)
			)
			(layer "F.Fab")
		)
		(fp_line
			(start -0.12065 0.3048)
			(end -0.67945 0.3048)
			(stroke
				(width 0.1)
				(type default)
			)
			(layer "F.Fab")
		)
		(fp_line
			(start -0.67945 0.3048)
			(end -0.67945 -0.305054)
			(stroke
				(width 0.1)
				(type default)
			)
			(layer "F.Fab")
		)
		(pad "1" smd circle
			(at -0.40005 0 90)
			(size 0 0)
			(layers "F.Cu" "F.Mask" "F.Paste")
			(net "P3V3_AUX_ILIM")
		)
		(pad "2" smd circle
			(at 0.40005 0 90)
			(size 0 0)
			(layers "F.Cu" "F.Mask" "F.Paste")
			(net "GND")
		)
	)
	(footprint ""
		(layer "F.Cu")
		(at 32.191452 -166.777162)
		(property "Reference" "PC390"
			(at 0 0 0)
			(layer "F.SilkS")
			(hide yes)
			(effects
				(font
					(size 1.27 1.27)
				)
			)
		)
		(property "Value" ""
			(at 0 0 0)
			(layer "F.Fab")
			(effects
				(font
					(size 1.27 1.27)
				)
			)
		)
		(duplicate_pad_numbers_are_jumpers no)
		(fp_line
			(start -0.7874 -0.4064)
			(end 0.7874 -0.4064)
			(stroke
				(width 0.1524)
				(type default)
			)
			(layer "F.SilkS")
		)
		(fp_line
			(start -0.7874 0.4064)
			(end -0.7874 -0.4064)
			(stroke
				(width 0.1524)
				(type default)
			)
			(layer "F.SilkS")
		)
		(fp_line
			(start 0.7874 -0.4064)
			(end 0.7874 0.4064)
			(stroke
				(width 0.1524)
				(type default)
			)
			(layer "F.SilkS")
		)
		(fp_line
			(start 0.7874 0.4064)
			(end -0.7874 0.4064)
			(stroke
				(width 0.1524)
				(type default)
			)
			(layer "F.SilkS")
		)
		(fp_line
			(start -0.67945 -0.305054)
			(end -0.12065 -0.305054)
			(stroke
				(width 0.1)
				(type default)
			)
			(layer "F.Fab")
		)
		(fp_line
			(start -0.67945 0.3048)
			(end -0.67945 -0.305054)
			(stroke
				(width 0.1)
				(type default)
			)
			(layer "F.Fab")
		)
		(fp_line
			(start -0.12065 -0.305054)
			(end -0.12065 -0.2794)
			(stroke
				(width 0.1)
				(type default)
			)
			(layer "F.Fab")
		)
		(fp_line
			(start -0.12065 -0.2794)
			(end 0.12065 -0.2794)
			(stroke
				(width 0.1)
				(type default)
			)
			(layer "F.Fab")
		)
		(fp_line
			(start -0.12065 0.2794)
			(end -0.12065 0.3048)
			(stroke
				(width 0.1)
				(type default)
			)
			(layer "F.Fab")
		)
		(fp_line
			(start -0.12065 0.3048)
			(end -0.67945 0.3048)
			(stroke
				(width 0.1)
				(type default)
			)
			(layer "F.Fab")
		)
		(fp_line
			(start 0.120396 0.2794)
			(end -0.12065 0.2794)
			(stroke
				(width 0.1)
				(type default)
			)
			(layer "F.Fab")
		)
		(fp_line
			(start 0.120396 0.3048)
			(end 0.120396 0.2794)
			(stroke
				(width 0.1)
				(type default)
			)
			(layer "F.Fab")
		)
		(fp_line
			(start 0.12065 -0.3048)
			(end 0.67945 -0.3048)
			(stroke
				(width 0.1)
				(type default)
			)
			(layer "F.Fab")
		)
		(fp_line
			(start 0.12065 -0.2794)
			(end 0.12065 -0.3048)
			(stroke
				(width 0.1)
				(type default)
			)
			(layer "F.Fab")
		)
		(fp_line
			(start 0.67945 -0.3048)
			(end 0.67945 0.3048)
			(stroke
				(width 0.1)
				(type default)
			)
			(layer "F.Fab")
		)
		(fp_line
			(start 0.67945 0.3048)
			(end 0.120396 0.3048)
			(stroke
				(width 0.1)
				(type default)
			)
			(layer "F.Fab")
		)
		(pad "1" smd circle
			(at -0.40005 0)
			(size 0 0)
			(layers "F.Cu" "F.Mask" "F.Paste")
			(net "PVCCD_HV_CPU1_ISENSE_N")
		)
		(pad "2" smd circle
			(at 0.40005 0)
			(size 0 0)
			(layers "F.Cu" "F.Mask" "F.Paste")
			(net "GND")
		)
	)
	(footprint ""
		(layer "F.Cu")
		(at 393.115038 -31.185612 90)
		(property "Reference" "R1595"
			(at 0 0 90)
			(layer "F.SilkS")
			(hide yes)
			(effects
				(font
					(size 1.27 1.27)
				)
			)
		)
		(property "Value" ""
			(at 0 0 90)
			(layer "F.Fab")
			(effects
				(font
					(size 1.27 1.27)
				)
			)
		)
		(duplicate_pad_numbers_are_jumpers no)
		(fp_line
			(start 0.7874 -0.4064)
			(end 0.7874 0.4064)
			(stroke
				(width 0.1524)
				(type default)
			)
			(layer "F.SilkS")
		)
		(fp_line
			(start -0.7874 -0.4064)
			(end 0.7874 -0.4064)
			(stroke
				(width 0.1524)
				(type default)
			)
			(layer "F.SilkS")
		)
		(fp_line
			(start 0.7874 0.4064)
			(end -0.7874 0.4064)
			(stroke
				(width 0.1524)
				(type default)
			)
			(layer "F.SilkS")
		)
		(fp_line
			(start -0.7874 0.4064)
			(end -0.7874 -0.4064)
			(stroke
				(width 0.1524)
				(type default)
			)
			(layer "F.SilkS")
		)
		(fp_line
			(start -0.12065 -0.305054)
			(end -0.12065 -0.2794)
			(stroke
				(width 0.1)
				(type default)
			)
			(layer "F.Fab")
		)
		(fp_line
			(start -0.67945 -0.305054)
			(end -0.12065 -0.305054)
			(stroke
				(width 0.1)
				(type default)
			)
			(layer "F.Fab")
		)
		(fp_line
			(start 0.67945 -0.3048)
			(end 0.67945 0.3048)
			(stroke
				(width 0.1)
				(type default)
			)
			(layer "F.Fab")
		)
		(fp_line
			(start 0.12065 -0.3048)
			(end 0.67945 -0.3048)
			(stroke
				(width 0.1)
				(type default)
			)
			(layer "F.Fab")
		)
		(fp_line
			(start 0.12065 -0.2794)
			(end 0.12065 -0.3048)
			(stroke
				(width 0.1)
				(type default)
			)
			(layer "F.Fab")
		)
		(fp_line
			(start -0.12065 -0.2794)
			(end 0.12065 -0.2794)
			(stroke
				(width 0.1)
				(type default)
			)
			(layer "F.Fab")
		)
		(fp_line
			(start 0.120396 0.2794)
			(end -0.12065 0.2794)
			(stroke
				(width 0.1)
				(type default)
			)
			(layer "F.Fab")
		)
		(fp_line
			(start -0.12065 0.2794)
			(end -0.12065 0.3048)
			(stroke
				(width 0.1)
				(type default)
			)
			(layer "F.Fab")
		)
		(fp_line
			(start 0.67945 0.3048)
			(end 0.120396 0.3048)
			(stroke
				(width 0.1)
				(type default)
			)
			(layer "F.Fab")
		)
		(fp_line
			(start 0.120396 0.3048)
			(end 0.120396 0.2794)
			(stroke
				(width 0.1)
				(type default)
			)
			(layer "F.Fab")
		)
		(fp_line
			(start -0.12065 0.3048)
			(end -0.67945 0.3048)
			(stroke
				(width 0.1)
				(type default)
			)
			(layer "F.Fab")
		)
		(fp_line
			(start -0.67945 0.3048)
			(end -0.67945 -0.305054)
			(stroke
				(width 0.1)
				(type default)
			)
			(layer "F.Fab")
		)
		(pad "1" smd circle
			(at -0.40005 0 90)
			(size 0 0)
			(layers "F.Cu" "F.Mask" "F.Paste")
			(net "OCP_SFF_PWRBRK_BUFF_N")
		)
		(pad "2" smd circle
			(at 0.40005 0 90)
			(size 0 0)
			(layers "F.Cu" "F.Mask" "F.Paste")
			(net "OCP_SFF_PWRBRK_N")
		)
	)
	(footprint ""
		(layer "F.Cu")
		(at 359.71988 -294.01008 180)
		(property "Reference" "C215"
			(at 0 0 180)
			(layer "F.SilkS")
			(hide yes)
			(effects
				(font
					(size 1.27 1.27)
				)
			)
		)
		(property "Value" ""
			(at 0 0 180)
			(layer "F.Fab")
			(effects
				(font
					(size 1.27 1.27)
				)
			)
		)
		(duplicate_pad_numbers_are_jumpers no)
		(fp_line
			(start 1.524 0.762)
			(end -1.524 0.762)
			(stroke
				(width 0.1524)
				(type default)
			)
			(layer "F.SilkS")
		)
		(fp_line
			(start 1.524 -0.762)
			(end 1.524 0.762)
			(stroke
				(width 0.1524)
				(type default)
			)
			(layer "F.SilkS")
		)
		(fp_line
			(start -1.524 0.762)
			(end -1.524 -0.762)
			(stroke
				(width 0.1524)
				(type default)
			)
			(layer "F.SilkS")
		)
		(fp_line
			(start -1.524 -0.762)
			(end 1.524 -0.762)
			(stroke
				(width 0.1524)
				(type default)
			)
			(layer "F.SilkS")
		)
		(fp_line
			(start 1.1049 0.724916)
			(end 1.1049 -0.724916)
			(stroke
				(width 0.1)
				(type default)
			)
			(layer "F.Fab")
		)
		(fp_line
			(start 1.1049 -0.724916)
			(end -1.1049 -0.724916)
			(stroke
				(width 0.1)
				(type default)
			)
			(layer "F.Fab")
		)
		(fp_line
			(start -1.1049 0.724916)
			(end 1.1049 0.724916)
			(stroke
				(width 0.1)
				(type default)
			)
			(layer "F.Fab")
		)
		(fp_line
			(start -1.1049 -0.724916)
			(end -1.1049 0.724916)
			(stroke
				(width 0.1)
				(type default)
			)
			(layer "F.Fab")
		)
		(pad "1" smd rect
			(at -0.889 0)
			(size 1.016 1.27)
			(layers "F.Cu" "F.Mask" "F.Paste")
			(net "PVCCIN_CPU0")
		)
		(pad "2" smd rect
			(at 0.889 0)
			(size 1.016 1.27)
			(layers "F.Cu" "F.Mask" "F.Paste")
			(net "GND")
		)
	)
	(footprint ""
		(layer "F.Cu")
		(at 183.198008 -398.651222 180)
		(property "Reference" "PC2190"
			(at 0 0 180)
			(layer "F.SilkS")
			(hide yes)
			(effects
				(font
					(size 1.27 1.27)
				)
			)
		)
		(property "Value" ""
			(at 0 0 180)
			(layer "F.Fab")
			(effects
				(font
					(size 1.27 1.27)
				)
			)
		)
		(duplicate_pad_numbers_are_jumpers no)
		(fp_line
			(start 0.7874 0.4064)
			(end -0.7874 0.4064)
			(stroke
				(width 0.1524)
				(type default)
			)
			(layer "F.SilkS")
		)
		(fp_line
			(start 0.7874 -0.4064)
			(end 0.7874 0.4064)
			(stroke
				(width 0.1524)
				(type default)
			)
			(layer "F.SilkS")
		)
		(fp_line
			(start -0.7874 0.4064)
			(end -0.7874 -0.4064)
			(stroke
				(width 0.1524)
				(type default)
			)
			(layer "F.SilkS")
		)
		(fp_line
			(start -0.7874 -0.4064)
			(end 0.7874 -0.4064)
			(stroke
				(width 0.1524)
				(type default)
			)
			(layer "F.SilkS")
		)
		(fp_line
			(start 0.67945 0.3048)
			(end 0.120396 0.3048)
			(stroke
				(width 0.1)
				(type default)
			)
			(layer "F.Fab")
		)
		(fp_line
			(start 0.67945 -0.3048)
			(end 0.67945 0.3048)
			(stroke
				(width 0.1)
				(type default)
			)
			(layer "F.Fab")
		)
		(fp_line
			(start 0.12065 -0.2794)
			(end 0.12065 -0.3048)
			(stroke
				(width 0.1)
				(type default)
			)
			(layer "F.Fab")
		)
		(fp_line
			(start 0.12065 -0.3048)
			(end 0.67945 -0.3048)
			(stroke
				(width 0.1)
				(type default)
			)
			(layer "F.Fab")
		)
		(fp_line
			(start 0.120396 0.3048)
			(end 0.120396 0.2794)
			(stroke
				(width 0.1)
				(type default)
			)
			(layer "F.Fab")
		)
		(fp_line
			(start 0.120396 0.2794)
			(end -0.12065 0.2794)
			(stroke
				(width 0.1)
				(type default)
			)
			(layer "F.Fab")
		)
		(fp_line
			(start -0.12065 0.3048)
			(end -0.67945 0.3048)
			(stroke
				(width 0.1)
				(type default)
			)
			(layer "F.Fab")
		)
		(fp_line
			(start -0.12065 0.2794)
			(end -0.12065 0.3048)
			(stroke
				(width 0.1)
				(type default)
			)
			(layer "F.Fab")
		)
		(fp_line
			(start -0.12065 -0.2794)
			(end 0.12065 -0.2794)
			(stroke
				(width 0.1)
				(type default)
			)
			(layer "F.Fab")
		)
		(fp_line
			(start -0.12065 -0.305054)
			(end -0.12065 -0.2794)
			(stroke
				(width 0.1)
				(type default)
			)
			(layer "F.Fab")
		)
		(fp_line
			(start -0.67945 0.3048)
			(end -0.67945 -0.305054)
			(stroke
				(width 0.1)
				(type default)
			)
			(layer "F.Fab")
		)
		(fp_line
			(start -0.67945 -0.305054)
			(end -0.12065 -0.305054)
			(stroke
				(width 0.1)
				(type default)
			)
			(layer "F.Fab")
		)
		(pad "1" smd circle
			(at -0.40005 0 180)
			(size 0 0)
			(layers "F.Cu" "F.Mask" "F.Paste")
			(net "HSC_VOSEN")
		)
		(pad "2" smd circle
			(at 0.40005 0 180)
			(size 0 0)
			(layers "F.Cu" "F.Mask" "F.Paste")
			(net "AGND_HSC")
		)
	)
	(footprint ""
		(layer "F.Cu")
		(at 364.940342 -390.48817)
		(property "Reference" "Q137"
			(at 2.02692 0.708152 0)
			(unlocked yes)
			(layer "F.SilkS")
			(effects
				(font
					(size 0.7874 0.5842)
					(thickness 0.1524)
				)
				(justify left)
			)
		)
		(property "Value" ""
			(at 0 0 0)
			(layer "F.Fab")
			(effects
				(font
					(size 1.27 1.27)
				)
			)
		)
		(duplicate_pad_numbers_are_jumpers no)
		(fp_line
			(start -1.332738 -1.100074)
			(end -0.4826 -1.100074)
			(stroke
				(width 0.1524)
				(type default)
			)
			(layer "F.SilkS")
		)
		(fp_line
			(start -1.332738 1.100074)
			(end -1.332738 -1.100074)
			(stroke
				(width 0.1524)
				(type default)
			)
			(layer "F.SilkS")
		)
		(fp_line
			(start -0.4826 -1.100074)
			(end 0 -0.541274)
			(stroke
				(width 0.1524)
				(type default)
			)
			(layer "F.SilkS")
		)
		(fp_line
			(start 0 -0.541274)
			(end 0.4826 -1.100074)
			(stroke
				(width 0.1524)
				(type default)
			)
			(layer "F.SilkS")
		)
		(fp_line
			(start 0.4826 -1.100074)
			(end 1.332738 -1.100074)
			(stroke
				(width 0.1524)
				(type default)
			)
			(layer "F.SilkS")
		)
		(fp_line
			(start 1.332738 -1.100074)
			(end 1.332738 1.100074)
			(stroke
				(width 0.1524)
				(type default)
			)
			(layer "F.SilkS")
		)
		(fp_line
			(start 1.332738 1.100074)
			(end -1.332738 1.100074)
			(stroke
				(width 0.1524)
				(type default)
			)
			(layer "F.SilkS")
		)
		(fp_poly
			(pts
				(xy -2.2352 -1.001014) (xy -1.533144 -0.649986) (xy -2.2352 -0.298958)
			)
			(stroke
				(width 0)
				(type default)
			)
			(fill yes)
			(layer "F.SilkS")
		)
		(fp_line
			(start -0.674878 -1.100074)
			(end 0.674878 -1.100074)
			(stroke
				(width 0.1)
				(type default)
			)
			(layer "F.Fab")
		)
		(fp_line
			(start -0.674878 1.100074)
			(end -0.674878 -1.100074)
			(stroke
				(width 0.1)
				(type default)
			)
			(layer "F.Fab")
		)
		(fp_line
			(start 0.674878 -1.100074)
			(end 0.674878 1.100074)
			(stroke
				(width 0.1)
				(type default)
			)
			(layer "F.Fab")
		)
		(fp_line
			(start 0.674878 1.100074)
			(end -0.674878 1.100074)
			(stroke
				(width 0.1)
				(type default)
			)
			(layer "F.Fab")
		)
		(fp_poly
			(pts
				(xy -2.2352 -0.298958) (xy -2.2352 -1.001014) (xy -1.533144 -0.649986)
			)
			(stroke
				(width 0)
				(type default)
			)
			(fill yes)
			(layer "F.Fab")
		)
		(pad "1" smd rect
			(at -0.94996 -0.649986 90)
			(size 0.4318 0.508)
			(layers "F.Cu" "F.Mask" "F.Paste")
			(net "GND")
		)
		(pad "2" smd rect
			(at -0.94996 0 90)
			(size 0.4318 0.508)
			(layers "F.Cu" "F.Mask" "F.Paste")
			(net "GPU_3V3IO_RSVD3")
		)
		(pad "3" smd rect
			(at -0.94996 0.649986 90)
			(size 0.4318 0.508)
			(layers "F.Cu" "F.Mask" "F.Paste")
			(net "GPU_3V3IO_RSVD3_ISO")
		)
		(pad "4" smd rect
			(at 0.94996 0.649986 90)
			(size 0.4318 0.508)
			(layers "F.Cu" "F.Mask" "F.Paste")
			(net "GND")
		)
		(pad "5" smd rect
			(at 0.94996 0 90)
			(size 0.4318 0.508)
			(layers "F.Cu" "F.Mask" "F.Paste")
			(net "GPU_3V3IO_RSVD3_N")
		)
		(pad "6" smd rect
			(at 0.94996 -0.649986 90)
			(size 0.4318 0.508)
			(layers "F.Cu" "F.Mask" "F.Paste")
			(net "GPU_3V3IO_RSVD3_N")
		)
	)
	(footprint ""
		(layer "F.Cu")
		(at 16.422878 -16.099536 90)
		(property "Reference" "C806"
			(at 0 0 90)
			(layer "F.SilkS")
			(hide yes)
			(effects
				(font
					(size 1.27 1.27)
				)
			)
		)
		(property "Value" ""
			(at 0 0 90)
			(layer "F.Fab")
			(effects
				(font
					(size 1.27 1.27)
				)
			)
		)
		(duplicate_pad_numbers_are_jumpers no)
		(fp_line
			(start 0.299974 -0.150114)
			(end 0.299974 0.150114)
			(stroke
				(width 0.1)
				(type default)
			)
			(layer "F.Fab")
		)
		(fp_line
			(start -0.299974 -0.150114)
			(end 0.299974 -0.150114)
			(stroke
				(width 0.1)
				(type default)
			)
			(layer "F.Fab")
		)
		(fp_line
			(start 0.299974 0.150114)
			(end -0.299974 0.150114)
			(stroke
				(width 0.1)
				(type default)
			)
			(layer "F.Fab")
		)
		(fp_line
			(start -0.299974 0.150114)
			(end -0.299974 -0.150114)
			(stroke
				(width 0.1)
				(type default)
			)
			(layer "F.Fab")
		)
		(pad "1" smd rect
			(at -0.2667 0 90)
			(size 0.3048 0.381)
			(layers "F.Cu" "F.Mask" "F.Paste")
			(net "P5E_CPU1_PE1_TX_C_DN<15>")
		)
		(pad "2" smd rect
			(at 0.2667 0 90)
			(size 0.3048 0.381)
			(layers "F.Cu" "F.Mask" "F.Paste")
			(net "P5E_CPU1_PE1_TX_DN<15>")
		)
	)
	(footprint ""
		(layer "F.Cu")
		(at 40.506396 -337.471258)
		(property "Reference" "PC414"
			(at 0 0 0)
			(layer "F.SilkS")
			(hide yes)
			(effects
				(font
					(size 1.27 1.27)
				)
			)
		)
		(property "Value" ""
			(at 0 0 0)
			(layer "F.Fab")
			(effects
				(font
					(size 1.27 1.27)
				)
			)
		)
		(duplicate_pad_numbers_are_jumpers no)
		(fp_line
			(start 2.750058 0.999998)
			(end -2.750058 0.999998)
			(stroke
				(width 0.1524)
				(type default)
			)
			(layer "F.SilkS")
		)
		(fp_circle
			(center 0 0.999998)
			(end 2.750058 0.999998)
			(stroke
				(width 0.1524)
				(type default)
			)
			(fill no)
			(layer "F.SilkS")
		)
		(fp_poly
			(pts
				(arc
					(start 2.750058 0.999998)
					(mid 0 3.750056)
					(end -2.750058 0.999998)
				)
			)
			(stroke
				(width 0)
				(type default)
			)
			(fill yes)
			(layer "F.SilkS")
		)
		(fp_circle
			(center 0 0.999998)
			(end 2.750058 0.999998)
			(stroke
				(width 0.1)
				(type default)
			)
			(fill no)
			(layer "F.Fab")
		)
		(pad "1" thru_hole rect
			(at 0 0)
			(size 1.5748 1.5748)
			(drill 1.0668)
			(layers "*.Cu" "*.Mask")
			(remove_unused_layers no)
			(net "PVCCFA_EHV_FIVRA_CPU1")
			(clearance 0)
			(padstack
				(mode front_inner_back)
				(layer "Inner"
					(shape circle)
					(size 1.5748 1.5748)
					(clearance 0)
				)
				(layer "B.Cu"
					(shape rect)
					(size 1.5748 1.5748)
					(clearance 0)
				)
			)
		)
		(pad "2" thru_hole circle
			(at 0 1.999996)
			(size 1.5748 1.5748)
			(drill 1.0668)
			(layers "*.Cu" "*.Mask")
			(remove_unused_layers no)
			(net "GND")
			(clearance 0)
		)
	)
	(footprint ""
		(layer "F.Cu")
		(at 455.439526 -99.124008)
		(property "Reference" "R1719"
			(at 0 0 0)
			(layer "F.SilkS")
			(hide yes)
			(effects
				(font
					(size 1.27 1.27)
				)
			)
		)
		(property "Value" ""
			(at 0 0 0)
			(layer "F.Fab")
			(effects
				(font
					(size 1.27 1.27)
				)
			)
		)
		(duplicate_pad_numbers_are_jumpers no)
		(fp_line
			(start -0.7874 -0.4064)
			(end 0.7874 -0.4064)
			(stroke
				(width 0.1524)
				(type default)
			)
			(layer "F.SilkS")
		)
		(fp_line
			(start -0.7874 0.4064)
			(end -0.7874 -0.4064)
			(stroke
				(width 0.1524)
				(type default)
			)
			(layer "F.SilkS")
		)
		(fp_line
			(start 0.7874 -0.4064)
			(end 0.7874 0.4064)
			(stroke
				(width 0.1524)
				(type default)
			)
			(layer "F.SilkS")
		)
		(fp_line
			(start 0.7874 0.4064)
			(end -0.7874 0.4064)
			(stroke
				(width 0.1524)
				(type default)
			)
			(layer "F.SilkS")
		)
		(fp_line
			(start -0.67945 -0.305054)
			(end -0.12065 -0.305054)
			(stroke
				(width 0.1)
				(type default)
			)
			(layer "F.Fab")
		)
		(fp_line
			(start -0.67945 0.3048)
			(end -0.67945 -0.305054)
			(stroke
				(width 0.1)
				(type default)
			)
			(layer "F.Fab")
		)
		(fp_line
			(start -0.12065 -0.305054)
			(end -0.12065 -0.2794)
			(stroke
				(width 0.1)
				(type default)
			)
			(layer "F.Fab")
		)
		(fp_line
			(start -0.12065 -0.2794)
			(end 0.12065 -0.2794)
			(stroke
				(width 0.1)
				(type default)
			)
			(layer "F.Fab")
		)
		(fp_line
			(start -0.12065 0.2794)
			(end -0.12065 0.3048)
			(stroke
				(width 0.1)
				(type default)
			)
			(layer "F.Fab")
		)
		(fp_line
			(start -0.12065 0.3048)
			(end -0.67945 0.3048)
			(stroke
				(width 0.1)
				(type default)
			)
			(layer "F.Fab")
		)
		(fp_line
			(start 0.120396 0.2794)
			(end -0.12065 0.2794)
			(stroke
				(width 0.1)
				(type default)
			)
			(layer "F.Fab")
		)
		(fp_line
			(start 0.120396 0.3048)
			(end 0.120396 0.2794)
			(stroke
				(width 0.1)
				(type default)
			)
			(layer "F.Fab")
		)
		(fp_line
			(start 0.12065 -0.3048)
			(end 0.67945 -0.3048)
			(stroke
				(width 0.1)
				(type default)
			)
			(layer "F.Fab")
		)
		(fp_line
			(start 0.12065 -0.2794)
			(end 0.12065 -0.3048)
			(stroke
				(width 0.1)
				(type default)
			)
			(layer "F.Fab")
		)
		(fp_line
			(start 0.67945 -0.3048)
			(end 0.67945 0.3048)
			(stroke
				(width 0.1)
				(type default)
			)
			(layer "F.Fab")
		)
		(fp_line
			(start 0.67945 0.3048)
			(end 0.120396 0.3048)
			(stroke
				(width 0.1)
				(type default)
			)
			(layer "F.Fab")
		)
		(pad "1" smd circle
			(at -0.40005 0)
			(size 0 0)
			(layers "F.Cu" "F.Mask" "F.Paste")
			(net "OCP_SFF_AUX_PWR_EN")
		)
		(pad "2" smd circle
			(at 0.40005 0)
			(size 0 0)
			(layers "F.Cu" "F.Mask" "F.Paste")
			(net "OCP_SFF_AUX_PWR_EN_R1")
		)
	)
	(footprint ""
		(layer "F.Cu")
		(at 437.425846 -383.51968 180)
		(property "Reference" "PC1855"
			(at 0 0 180)
			(layer "F.SilkS")
			(hide yes)
			(effects
				(font
					(size 1.27 1.27)
				)
			)
		)
		(property "Value" ""
			(at 0 0 180)
			(layer "F.Fab")
			(effects
				(font
					(size 1.27 1.27)
				)
			)
		)
		(duplicate_pad_numbers_are_jumpers no)
		(fp_line
			(start 1.524 0.762)
			(end -1.524 0.762)
			(stroke
				(width 0.1524)
				(type default)
			)
			(layer "F.SilkS")
		)
		(fp_line
			(start 1.524 -0.762)
			(end 1.524 0.762)
			(stroke
				(width 0.1524)
				(type default)
			)
			(layer "F.SilkS")
		)
		(fp_line
			(start -1.524 0.762)
			(end -1.524 -0.762)
			(stroke
				(width 0.1524)
				(type default)
			)
			(layer "F.SilkS")
		)
		(fp_line
			(start -1.524 -0.762)
			(end 1.524 -0.762)
			(stroke
				(width 0.1524)
				(type default)
			)
			(layer "F.SilkS")
		)
		(fp_line
			(start 1.1049 0.724916)
			(end 1.1049 -0.724916)
			(stroke
				(width 0.1)
				(type default)
			)
			(layer "F.Fab")
		)
		(fp_line
			(start 1.1049 -0.724916)
			(end -1.1049 -0.724916)
			(stroke
				(width 0.1)
				(type default)
			)
			(layer "F.Fab")
		)
		(fp_line
			(start -1.1049 0.724916)
			(end 1.1049 0.724916)
			(stroke
				(width 0.1)
				(type default)
			)
			(layer "F.Fab")
		)
		(fp_line
			(start -1.1049 -0.724916)
			(end -1.1049 0.724916)
			(stroke
				(width 0.1)
				(type default)
			)
			(layer "F.Fab")
		)
		(pad "1" smd rect
			(at -0.889 0)
			(size 1.016 1.27)
			(layers "F.Cu" "F.Mask" "F.Paste")
			(net "P5V_AUX")
		)
		(pad "2" smd rect
			(at 0.889 0)
			(size 1.016 1.27)
			(layers "F.Cu" "F.Mask" "F.Paste")
			(net "GND")
		)
	)
	(footprint ""
		(layer "F.Cu")
		(at 406.00757 -402.371052 -90)
		(property "Reference" "C956"
			(at 0 0 270)
			(layer "F.SilkS")
			(hide yes)
			(effects
				(font
					(size 1.27 1.27)
				)
			)
		)
		(property "Value" ""
			(at 0 0 270)
			(layer "F.Fab")
			(effects
				(font
					(size 1.27 1.27)
				)
			)
		)
		(duplicate_pad_numbers_are_jumpers no)
		(fp_line
			(start -0.299974 0.150114)
			(end -0.299974 -0.150114)
			(stroke
				(width 0.1)
				(type default)
			)
			(layer "F.Fab")
		)
		(fp_line
			(start 0.299974 0.150114)
			(end -0.299974 0.150114)
			(stroke
				(width 0.1)
				(type default)
			)
			(layer "F.Fab")
		)
		(fp_line
			(start -0.299974 -0.150114)
			(end 0.299974 -0.150114)
			(stroke
				(width 0.1)
				(type default)
			)
			(layer "F.Fab")
		)
		(fp_line
			(start 0.299974 -0.150114)
			(end 0.299974 0.150114)
			(stroke
				(width 0.1)
				(type default)
			)
			(layer "F.Fab")
		)
		(pad "1" smd rect
			(at -0.2667 0 270)
			(size 0.3048 0.381)
			(layers "F.Cu" "F.Mask" "F.Paste")
			(net "P5E_CPU0_PE2_TX_C_DN<4>")
		)
		(pad "2" smd rect
			(at 0.2667 0 270)
			(size 0.3048 0.381)
			(layers "F.Cu" "F.Mask" "F.Paste")
			(net "P5E_CPU0_PE2_TX_DN<4>")
		)
	)
	(footprint ""
		(layer "F.Cu")
		(at 109.744002 -336.192368 90)
		(property "Reference" "PC524"
			(at 0 0 90)
			(layer "F.SilkS")
			(hide yes)
			(effects
				(font
					(size 1.27 1.27)
				)
			)
		)
		(property "Value" ""
			(at 0 0 90)
			(layer "F.Fab")
			(effects
				(font
					(size 1.27 1.27)
				)
			)
		)
		(duplicate_pad_numbers_are_jumpers no)
		(fp_line
			(start 0.7874 -0.4064)
			(end 0.7874 0.4064)
			(stroke
				(width 0.1524)
				(type default)
			)
			(layer "F.SilkS")
		)
		(fp_line
			(start -0.7874 -0.4064)
			(end 0.7874 -0.4064)
			(stroke
				(width 0.1524)
				(type default)
			)
			(layer "F.SilkS")
		)
		(fp_line
			(start 0.7874 0.4064)
			(end -0.7874 0.4064)
			(stroke
				(width 0.1524)
				(type default)
			)
			(layer "F.SilkS")
		)
		(fp_line
			(start -0.7874 0.4064)
			(end -0.7874 -0.4064)
			(stroke
				(width 0.1524)
				(type default)
			)
			(layer "F.SilkS")
		)
		(fp_line
			(start -0.12065 -0.305054)
			(end -0.12065 -0.2794)
			(stroke
				(width 0.1)
				(type default)
			)
			(layer "F.Fab")
		)
		(fp_line
			(start -0.67945 -0.305054)
			(end -0.12065 -0.305054)
			(stroke
				(width 0.1)
				(type default)
			)
			(layer "F.Fab")
		)
		(fp_line
			(start 0.67945 -0.3048)
			(end 0.67945 0.3048)
			(stroke
				(width 0.1)
				(type default)
			)
			(layer "F.Fab")
		)
		(fp_line
			(start 0.12065 -0.3048)
			(end 0.67945 -0.3048)
			(stroke
				(width 0.1)
				(type default)
			)
			(layer "F.Fab")
		)
		(fp_line
			(start 0.12065 -0.2794)
			(end 0.12065 -0.3048)
			(stroke
				(width 0.1)
				(type default)
			)
			(layer "F.Fab")
		)
		(fp_line
			(start -0.12065 -0.2794)
			(end 0.12065 -0.2794)
			(stroke
				(width 0.1)
				(type default)
			)
			(layer "F.Fab")
		)
		(fp_line
			(start 0.120396 0.2794)
			(end -0.12065 0.2794)
			(stroke
				(width 0.1)
				(type default)
			)
			(layer "F.Fab")
		)
		(fp_line
			(start -0.12065 0.2794)
			(end -0.12065 0.3048)
			(stroke
				(width 0.1)
				(type default)
			)
			(layer "F.Fab")
		)
		(fp_line
			(start 0.67945 0.3048)
			(end 0.120396 0.3048)
			(stroke
				(width 0.1)
				(type default)
			)
			(layer "F.Fab")
		)
		(fp_line
			(start 0.120396 0.3048)
			(end 0.120396 0.2794)
			(stroke
				(width 0.1)
				(type default)
			)
			(layer "F.Fab")
		)
		(fp_line
			(start -0.12065 0.3048)
			(end -0.67945 0.3048)
			(stroke
				(width 0.1)
				(type default)
			)
			(layer "F.Fab")
		)
		(fp_line
			(start -0.67945 0.3048)
			(end -0.67945 -0.305054)
			(stroke
				(width 0.1)
				(type default)
			)
			(layer "F.Fab")
		)
		(pad "1" smd circle
			(at -0.40005 0 90)
			(size 0 0)
			(layers "F.Cu" "F.Mask" "F.Paste")
			(net "PVCCIN_CPU1_VDD3")
		)
		(pad "2" smd circle
			(at 0.40005 0 90)
			(size 0 0)
			(layers "F.Cu" "F.Mask" "F.Paste")
			(net "GND")
		)
	)
	(footprint ""
		(layer "F.Cu")
		(at 161.297874 -408.517344 -90)
		(property "Reference" "C1542"
			(at 0 0 270)
			(layer "F.SilkS")
			(hide yes)
			(effects
				(font
					(size 1.27 1.27)
				)
			)
		)
		(property "Value" ""
			(at 0 0 270)
			(layer "F.Fab")
			(effects
				(font
					(size 1.27 1.27)
				)
			)
		)
		(duplicate_pad_numbers_are_jumpers no)
		(fp_line
			(start -0.299974 0.150114)
			(end -0.299974 -0.150114)
			(stroke
				(width 0.1)
				(type default)
			)
			(layer "F.Fab")
		)
		(fp_line
			(start 0.299974 0.150114)
			(end -0.299974 0.150114)
			(stroke
				(width 0.1)
				(type default)
			)
			(layer "F.Fab")
		)
		(fp_line
			(start -0.299974 -0.150114)
			(end 0.299974 -0.150114)
			(stroke
				(width 0.1)
				(type default)
			)
			(layer "F.Fab")
		)
		(fp_line
			(start 0.299974 -0.150114)
			(end 0.299974 0.150114)
			(stroke
				(width 0.1)
				(type default)
			)
			(layer "F.Fab")
		)
		(pad "1" smd rect
			(at -0.2667 0 270)
			(size 0.3048 0.381)
			(layers "F.Cu" "F.Mask" "F.Paste")
			(net "P5E_CPU1_PE3_TX_C_DN<2>")
		)
		(pad "2" smd rect
			(at 0.2667 0 270)
			(size 0.3048 0.381)
			(layers "F.Cu" "F.Mask" "F.Paste")
			(net "P5E_CPU1_PE3_TX_DN<2>")
		)
	)
	(footprint ""
		(layer "F.Cu")
		(at 136.61136 -25.189688 180)
		(property "Reference" "R4275"
			(at 0 0 180)
			(layer "F.SilkS")
			(hide yes)
			(effects
				(font
					(size 1.27 1.27)
				)
			)
		)
		(property "Value" ""
			(at 0 0 180)
			(layer "F.Fab")
			(effects
				(font
					(size 1.27 1.27)
				)
			)
		)
		(duplicate_pad_numbers_are_jumpers no)
		(fp_line
			(start 0.7874 0.4064)
			(end -0.7874 0.4064)
			(stroke
				(width 0.1524)
				(type default)
			)
			(layer "F.SilkS")
		)
		(fp_line
			(start 0.7874 -0.4064)
			(end 0.7874 0.4064)
			(stroke
				(width 0.1524)
				(type default)
			)
			(layer "F.SilkS")
		)
		(fp_line
			(start -0.7874 0.4064)
			(end -0.7874 -0.4064)
			(stroke
				(width 0.1524)
				(type default)
			)
			(layer "F.SilkS")
		)
		(fp_line
			(start -0.7874 -0.4064)
			(end 0.7874 -0.4064)
			(stroke
				(width 0.1524)
				(type default)
			)
			(layer "F.SilkS")
		)
		(fp_line
			(start 0.67945 0.3048)
			(end 0.120396 0.3048)
			(stroke
				(width 0.1)
				(type default)
			)
			(layer "F.Fab")
		)
		(fp_line
			(start 0.67945 -0.3048)
			(end 0.67945 0.3048)
			(stroke
				(width 0.1)
				(type default)
			)
			(layer "F.Fab")
		)
		(fp_line
			(start 0.12065 -0.2794)
			(end 0.12065 -0.3048)
			(stroke
				(width 0.1)
				(type default)
			)
			(layer "F.Fab")
		)
		(fp_line
			(start 0.12065 -0.3048)
			(end 0.67945 -0.3048)
			(stroke
				(width 0.1)
				(type default)
			)
			(layer "F.Fab")
		)
		(fp_line
			(start 0.120396 0.3048)
			(end 0.120396 0.2794)
			(stroke
				(width 0.1)
				(type default)
			)
			(layer "F.Fab")
		)
		(fp_line
			(start 0.120396 0.2794)
			(end -0.12065 0.2794)
			(stroke
				(width 0.1)
				(type default)
			)
			(layer "F.Fab")
		)
		(fp_line
			(start -0.12065 0.3048)
			(end -0.67945 0.3048)
			(stroke
				(width 0.1)
				(type default)
			)
			(layer "F.Fab")
		)
		(fp_line
			(start -0.12065 0.2794)
			(end -0.12065 0.3048)
			(stroke
				(width 0.1)
				(type default)
			)
			(layer "F.Fab")
		)
		(fp_line
			(start -0.12065 -0.2794)
			(end 0.12065 -0.2794)
			(stroke
				(width 0.1)
				(type default)
			)
			(layer "F.Fab")
		)
		(fp_line
			(start -0.12065 -0.305054)
			(end -0.12065 -0.2794)
			(stroke
				(width 0.1)
				(type default)
			)
			(layer "F.Fab")
		)
		(fp_line
			(start -0.67945 0.3048)
			(end -0.67945 -0.305054)
			(stroke
				(width 0.1)
				(type default)
			)
			(layer "F.Fab")
		)
		(fp_line
			(start -0.67945 -0.305054)
			(end -0.12065 -0.305054)
			(stroke
				(width 0.1)
				(type default)
			)
			(layer "F.Fab")
		)
		(pad "1" smd circle
			(at -0.40005 0 180)
			(size 0 0)
			(layers "F.Cu" "F.Mask" "F.Paste")
			(net "P3V3_AUX")
		)
		(pad "2" smd circle
			(at 0.40005 0 180)
			(size 0 0)
			(layers "F.Cu" "F.Mask" "F.Paste")
			(net "FM_USB3_1_EQA")
		)
	)
	(footprint ""
		(layer "F.Cu")
		(at 366.413542 -420.108126 -90)
		(property "Reference" "R4212"
			(at 0 0 270)
			(layer "F.SilkS")
			(hide yes)
			(effects
				(font
					(size 1.27 1.27)
				)
			)
		)
		(property "Value" ""
			(at 0 0 270)
			(layer "F.Fab")
			(effects
				(font
					(size 1.27 1.27)
				)
			)
		)
		(duplicate_pad_numbers_are_jumpers no)
		(fp_line
			(start -0.7874 0.4064)
			(end -0.7874 -0.4064)
			(stroke
				(width 0.1524)
				(type default)
			)
			(layer "F.SilkS")
		)
		(fp_line
			(start 0.7874 0.4064)
			(end -0.7874 0.4064)
			(stroke
				(width 0.1524)
				(type default)
			)
			(layer "F.SilkS")
		)
		(fp_line
			(start -0.7874 -0.4064)
			(end 0.7874 -0.4064)
			(stroke
				(width 0.1524)
				(type default)
			)
			(layer "F.SilkS")
		)
		(fp_line
			(start 0.7874 -0.4064)
			(end 0.7874 0.4064)
			(stroke
				(width 0.1524)
				(type default)
			)
			(layer "F.SilkS")
		)
		(fp_line
			(start -0.67945 0.3048)
			(end -0.67945 -0.305054)
			(stroke
				(width 0.1)
				(type default)
			)
			(layer "F.Fab")
		)
		(fp_line
			(start -0.12065 0.3048)
			(end -0.67945 0.3048)
			(stroke
				(width 0.1)
				(type default)
			)
			(layer "F.Fab")
		)
		(fp_line
			(start 0.120396 0.3048)
			(end 0.120396 0.2794)
			(stroke
				(width 0.1)
				(type default)
			)
			(layer "F.Fab")
		)
		(fp_line
			(start 0.67945 0.3048)
			(end 0.120396 0.3048)
			(stroke
				(width 0.1)
				(type default)
			)
			(layer "F.Fab")
		)
		(fp_line
			(start -0.12065 0.2794)
			(end -0.12065 0.3048)
			(stroke
				(width 0.1)
				(type default)
			)
			(layer "F.Fab")
		)
		(fp_line
			(start 0.120396 0.2794)
			(end -0.12065 0.2794)
			(stroke
				(width 0.1)
				(type default)
			)
			(layer "F.Fab")
		)
		(fp_line
			(start -0.12065 -0.2794)
			(end 0.12065 -0.2794)
			(stroke
				(width 0.1)
				(type default)
			)
			(layer "F.Fab")
		)
		(fp_line
			(start 0.12065 -0.2794)
			(end 0.12065 -0.3048)
			(stroke
				(width 0.1)
				(type default)
			)
			(layer "F.Fab")
		)
		(fp_line
			(start 0.12065 -0.3048)
			(end 0.67945 -0.3048)
			(stroke
				(width 0.1)
				(type default)
			)
			(layer "F.Fab")
		)
		(fp_line
			(start 0.67945 -0.3048)
			(end 0.67945 0.3048)
			(stroke
				(width 0.1)
				(type default)
			)
			(layer "F.Fab")
		)
		(fp_line
			(start -0.67945 -0.305054)
			(end -0.12065 -0.305054)
			(stroke
				(width 0.1)
				(type default)
			)
			(layer "F.Fab")
		)
		(fp_line
			(start -0.12065 -0.305054)
			(end -0.12065 -0.2794)
			(stroke
				(width 0.1)
				(type default)
			)
			(layer "F.Fab")
		)
		(pad "1" smd circle
			(at -0.40005 0 270)
			(size 0 0)
			(layers "F.Cu" "F.Mask" "F.Paste")
			(net "FM_THERMAL_ALERT_N")
		)
		(pad "2" smd circle
			(at 0.40005 0 270)
			(size 0 0)
			(layers "F.Cu" "F.Mask" "F.Paste")
			(net "FM_LM75_3_ALERT_N")
		)
	)
	(footprint ""
		(layer "F.Cu")
		(at 346.037408 -408.517344 -90)
		(property "Reference" "C929"
			(at 0 0 270)
			(layer "F.SilkS")
			(hide yes)
			(effects
				(font
					(size 1.27 1.27)
				)
			)
		)
		(property "Value" ""
			(at 0 0 270)
			(layer "F.Fab")
			(effects
				(font
					(size 1.27 1.27)
				)
			)
		)
		(duplicate_pad_numbers_are_jumpers no)
		(fp_line
			(start -0.299974 0.150114)
			(end -0.299974 -0.150114)
			(stroke
				(width 0.1)
				(type default)
			)
			(layer "F.Fab")
		)
		(fp_line
			(start 0.299974 0.150114)
			(end -0.299974 0.150114)
			(stroke
				(width 0.1)
				(type default)
			)
			(layer "F.Fab")
		)
		(fp_line
			(start -0.299974 -0.150114)
			(end 0.299974 -0.150114)
			(stroke
				(width 0.1)
				(type default)
			)
			(layer "F.Fab")
		)
		(fp_line
			(start 0.299974 -0.150114)
			(end 0.299974 0.150114)
			(stroke
				(width 0.1)
				(type default)
			)
			(layer "F.Fab")
		)
		(pad "1" smd rect
			(at -0.2667 0 270)
			(size 0.3048 0.381)
			(layers "F.Cu" "F.Mask" "F.Paste")
			(net "P5E_CPU0_PE0_TX_C_DP<2>")
		)
		(pad "2" smd rect
			(at 0.2667 0 270)
			(size 0.3048 0.381)
			(layers "F.Cu" "F.Mask" "F.Paste")
			(net "P5E_CPU0_PE0_TX_DP<2>")
		)
	)
	(footprint ""
		(layer "F.Cu")
		(at 75.705462 -38.532562)
		(property "Reference" "C2012"
			(at 0 0 0)
			(layer "F.SilkS")
			(hide yes)
			(effects
				(font
					(size 1.27 1.27)
				)
			)
		)
		(property "Value" ""
			(at 0 0 0)
			(layer "F.Fab")
			(effects
				(font
					(size 1.27 1.27)
				)
			)
		)
		(duplicate_pad_numbers_are_jumpers no)
		(fp_line
			(start -0.7874 -0.4064)
			(end 0.7874 -0.4064)
			(stroke
				(width 0.1524)
				(type default)
			)
			(layer "F.SilkS")
		)
		(fp_line
			(start -0.7874 0.4064)
			(end -0.7874 -0.4064)
			(stroke
				(width 0.1524)
				(type default)
			)
			(layer "F.SilkS")
		)
		(fp_line
			(start 0.7874 -0.4064)
			(end 0.7874 0.4064)
			(stroke
				(width 0.1524)
				(type default)
			)
			(layer "F.SilkS")
		)
		(fp_line
			(start 0.7874 0.4064)
			(end -0.7874 0.4064)
			(stroke
				(width 0.1524)
				(type default)
			)
			(layer "F.SilkS")
		)
		(fp_line
			(start -0.67945 -0.305054)
			(end -0.12065 -0.305054)
			(stroke
				(width 0.1)
				(type default)
			)
			(layer "F.Fab")
		)
		(fp_line
			(start -0.67945 0.3048)
			(end -0.67945 -0.305054)
			(stroke
				(width 0.1)
				(type default)
			)
			(layer "F.Fab")
		)
		(fp_line
			(start -0.12065 -0.305054)
			(end -0.12065 -0.2794)
			(stroke
				(width 0.1)
				(type default)
			)
			(layer "F.Fab")
		)
		(fp_line
			(start -0.12065 -0.2794)
			(end 0.12065 -0.2794)
			(stroke
				(width 0.1)
				(type default)
			)
			(layer "F.Fab")
		)
		(fp_line
			(start -0.12065 0.2794)
			(end -0.12065 0.3048)
			(stroke
				(width 0.1)
				(type default)
			)
			(layer "F.Fab")
		)
		(fp_line
			(start -0.12065 0.3048)
			(end -0.67945 0.3048)
			(stroke
				(width 0.1)
				(type default)
			)
			(layer "F.Fab")
		)
		(fp_line
			(start 0.120396 0.2794)
			(end -0.12065 0.2794)
			(stroke
				(width 0.1)
				(type default)
			)
			(layer "F.Fab")
		)
		(fp_line
			(start 0.120396 0.3048)
			(end 0.120396 0.2794)
			(stroke
				(width 0.1)
				(type default)
			)
			(layer "F.Fab")
		)
		(fp_line
			(start 0.12065 -0.3048)
			(end 0.67945 -0.3048)
			(stroke
				(width 0.1)
				(type default)
			)
			(layer "F.Fab")
		)
		(fp_line
			(start 0.12065 -0.2794)
			(end 0.12065 -0.3048)
			(stroke
				(width 0.1)
				(type default)
			)
			(layer "F.Fab")
		)
		(fp_line
			(start 0.67945 -0.3048)
			(end 0.67945 0.3048)
			(stroke
				(width 0.1)
				(type default)
			)
			(layer "F.Fab")
		)
		(fp_line
			(start 0.67945 0.3048)
			(end 0.120396 0.3048)
			(stroke
				(width 0.1)
				(type default)
			)
			(layer "F.Fab")
		)
		(pad "1" smd circle
			(at -0.40005 0)
			(size 0 0)
			(layers "F.Cu" "F.Mask" "F.Paste")
			(net "P3V3_AUX")
		)
		(pad "2" smd circle
			(at 0.40005 0)
			(size 0 0)
			(layers "F.Cu" "F.Mask" "F.Paste")
			(net "GND")
		)
	)
	(footprint ""
		(layer "F.Cu")
		(at 271.966436 -398.78 90)
		(property "Reference" "PPQ8"
			(at -8.118348 -1.949196 0)
			(unlocked yes)
			(layer "F.SilkS")
			(effects
				(font
					(size 0.7874 0.5842)
					(thickness 0.1524)
				)
				(justify left)
			)
		)
		(property "Value" ""
			(at 0 0 90)
			(layer "F.Fab")
			(effects
				(font
					(size 1.27 1.27)
				)
			)
		)
		(duplicate_pad_numbers_are_jumpers no)
		(fp_line
			(start 2.350008 -2.649982)
			(end 2.350008 -2.4892)
			(stroke
				(width 0.1524)
				(type default)
			)
			(layer "F.SilkS")
		)
		(fp_line
			(start -2.350008 -2.649982)
			(end 2.350008 -2.649982)
			(stroke
				(width 0.1524)
				(type default)
			)
			(layer "F.SilkS")
		)
		(fp_line
			(start -2.350008 -2.4384)
			(end -2.350008 -2.649982)
			(stroke
				(width 0.1524)
				(type default)
			)
			(layer "F.SilkS")
		)
		(fp_line
			(start 2.350008 2.4892)
			(end 2.350008 2.649982)
			(stroke
				(width 0.1524)
				(type default)
			)
			(layer "F.SilkS")
		)
		(fp_line
			(start 2.350008 2.649982)
			(end -2.350008 2.649982)
			(stroke
				(width 0.1524)
				(type default)
			)
			(layer "F.SilkS")
		)
		(fp_line
			(start -2.350008 2.649982)
			(end -2.350008 2.413)
			(stroke
				(width 0.1524)
				(type default)
			)
			(layer "F.SilkS")
		)
		(fp_poly
			(pts
				(xy -3.717544 -1.905) (xy -4.758944 -2.3241) (xy -4.758944 -1.524)
			)
			(stroke
				(width 0)
				(type default)
			)
			(fill yes)
			(layer "F.SilkS")
		)
		(fp_line
			(start 2.350008 -2.649982)
			(end 2.350008 2.649982)
			(stroke
				(width 0.1)
				(type default)
			)
			(layer "F.Fab")
		)
		(fp_line
			(start -2.350008 -2.649982)
			(end 2.350008 -2.649982)
			(stroke
				(width 0.1)
				(type default)
			)
			(layer "F.Fab")
		)
		(fp_line
			(start 2.350008 2.649982)
			(end -2.350008 2.649982)
			(stroke
				(width 0.1)
				(type default)
			)
			(layer "F.Fab")
		)
		(fp_line
			(start -2.350008 2.649982)
			(end -2.350008 -2.649982)
			(stroke
				(width 0.1)
				(type default)
			)
			(layer "F.Fab")
		)
		(fp_poly
			(pts
				(xy -3.717544 -1.905) (xy -4.758944 -2.3241) (xy -4.758944 -1.524)
			)
			(stroke
				(width 0)
				(type default)
			)
			(fill yes)
			(layer "F.Fab")
		)
		(pad "1" smd rect
			(at -2.999994 -1.905)
			(size 0.7112 1.1684)
			(layers "F.Cu" "F.Mask" "F.Paste")
			(net "P12V_AUX")
		)
		(pad "2" smd rect
			(at -2.999994 -0.635)
			(size 0.7112 1.1684)
			(layers "F.Cu" "F.Mask" "F.Paste")
			(net "P12V_AUX")
		)
		(pad "3" smd rect
			(at -2.999994 0.635)
			(size 0.7112 1.1684)
			(layers "F.Cu" "F.Mask" "F.Paste")
			(net "P12V_AUX")
		)
		(pad "4" smd rect
			(at -2.999994 1.905)
			(size 0.7112 1.1684)
			(layers "F.Cu" "F.Mask" "F.Paste")
			(net "P12V_HSC_GATE_G4")
		)
		(pad "5" smd circle
			(at 0.925068 0)
			(size 0 0)
			(layers "F.Cu" "F.Mask" "F.Paste")
			(net "P12V_MAIN_R")
		)
		(zone
			(layer "F.Cu")
			(hatch none 0.5)
			(connect_pads
				(clearance 0)
			)
			(min_thickness 0.25)
			(keepout
				(tracks not_allowed)
				(vias allowed)
				(pads allowed)
				(copperpour not_allowed)
				(footprints allowed)
			)
			(placement
				(enabled no)
				(sheetname "")
			)
			(fill
				(thermal_gap 0.5)
				(thermal_bridge_width 0.5)
				(island_removal_mode 0)
			)
			(polygon
				(pts
					(xy 269.807436 -397.3322) (xy 274.125436 -397.3322) (xy 274.608036 -397.3322) (xy 274.608036 -396.4305)
					(xy 269.324836 -396.4305) (xy 269.324836 -397.3322)
				)
			)
		)
	)
	(footprint ""
		(layer "F.Cu")
		(at 424.204892 -391.632948 180)
		(property "Reference" "R2833"
			(at 0 0 180)
			(layer "F.SilkS")
			(hide yes)
			(effects
				(font
					(size 1.27 1.27)
				)
			)
		)
		(property "Value" ""
			(at 0 0 180)
			(layer "F.Fab")
			(effects
				(font
					(size 1.27 1.27)
				)
			)
		)
		(duplicate_pad_numbers_are_jumpers no)
		(fp_line
			(start 0.7874 0.4064)
			(end -0.7874 0.4064)
			(stroke
				(width 0.1524)
				(type default)
			)
			(layer "F.SilkS")
		)
		(fp_line
			(start 0.7874 -0.4064)
			(end 0.7874 0.4064)
			(stroke
				(width 0.1524)
				(type default)
			)
			(layer "F.SilkS")
		)
		(fp_line
			(start -0.7874 0.4064)
			(end -0.7874 -0.4064)
			(stroke
				(width 0.1524)
				(type default)
			)
			(layer "F.SilkS")
		)
		(fp_line
			(start -0.7874 -0.4064)
			(end 0.7874 -0.4064)
			(stroke
				(width 0.1524)
				(type default)
			)
			(layer "F.SilkS")
		)
		(fp_line
			(start 0.67945 0.3048)
			(end 0.120396 0.3048)
			(stroke
				(width 0.1)
				(type default)
			)
			(layer "F.Fab")
		)
		(fp_line
			(start 0.67945 -0.3048)
			(end 0.67945 0.3048)
			(stroke
				(width 0.1)
				(type default)
			)
			(layer "F.Fab")
		)
		(fp_line
			(start 0.12065 -0.2794)
			(end 0.12065 -0.3048)
			(stroke
				(width 0.1)
				(type default)
			)
			(layer "F.Fab")
		)
		(fp_line
			(start 0.12065 -0.3048)
			(end 0.67945 -0.3048)
			(stroke
				(width 0.1)
				(type default)
			)
			(layer "F.Fab")
		)
		(fp_line
			(start 0.120396 0.3048)
			(end 0.120396 0.2794)
			(stroke
				(width 0.1)
				(type default)
			)
			(layer "F.Fab")
		)
		(fp_line
			(start 0.120396 0.2794)
			(end -0.12065 0.2794)
			(stroke
				(width 0.1)
				(type default)
			)
			(layer "F.Fab")
		)
		(fp_line
			(start -0.12065 0.3048)
			(end -0.67945 0.3048)
			(stroke
				(width 0.1)
				(type default)
			)
			(layer "F.Fab")
		)
		(fp_line
			(start -0.12065 0.2794)
			(end -0.12065 0.3048)
			(stroke
				(width 0.1)
				(type default)
			)
			(layer "F.Fab")
		)
		(fp_line
			(start -0.12065 -0.2794)
			(end 0.12065 -0.2794)
			(stroke
				(width 0.1)
				(type default)
			)
			(layer "F.Fab")
		)
		(fp_line
			(start -0.12065 -0.305054)
			(end -0.12065 -0.2794)
			(stroke
				(width 0.1)
				(type default)
			)
			(layer "F.Fab")
		)
		(fp_line
			(start -0.67945 0.3048)
			(end -0.67945 -0.305054)
			(stroke
				(width 0.1)
				(type default)
			)
			(layer "F.Fab")
		)
		(fp_line
			(start -0.67945 -0.305054)
			(end -0.12065 -0.305054)
			(stroke
				(width 0.1)
				(type default)
			)
			(layer "F.Fab")
		)
		(pad "1" smd circle
			(at -0.40005 0 180)
			(size 0 0)
			(layers "F.Cu" "F.Mask" "F.Paste")
			(net "FM_SWB_BIC_READY_N")
		)
		(pad "2" smd circle
			(at 0.40005 0 180)
			(size 0 0)
			(layers "F.Cu" "F.Mask" "F.Paste")
			(net "GND")
		)
	)
	(footprint ""
		(layer "F.Cu")
		(at 131.466844 -137.114026 180)
		(property "Reference" "R536"
			(at 0 0 180)
			(layer "F.SilkS")
			(hide yes)
			(effects
				(font
					(size 1.27 1.27)
				)
			)
		)
		(property "Value" ""
			(at 0 0 180)
			(layer "F.Fab")
			(effects
				(font
					(size 1.27 1.27)
				)
			)
		)
		(duplicate_pad_numbers_are_jumpers no)
		(fp_line
			(start 0.7874 0.4064)
			(end -0.7874 0.4064)
			(stroke
				(width 0.1524)
				(type default)
			)
			(layer "F.SilkS")
		)
		(fp_line
			(start 0.7874 -0.4064)
			(end 0.7874 0.4064)
			(stroke
				(width 0.1524)
				(type default)
			)
			(layer "F.SilkS")
		)
		(fp_line
			(start -0.7874 0.4064)
			(end -0.7874 -0.4064)
			(stroke
				(width 0.1524)
				(type default)
			)
			(layer "F.SilkS")
		)
		(fp_line
			(start -0.7874 -0.4064)
			(end 0.7874 -0.4064)
			(stroke
				(width 0.1524)
				(type default)
			)
			(layer "F.SilkS")
		)
		(fp_line
			(start 0.67945 0.3048)
			(end 0.120396 0.3048)
			(stroke
				(width 0.1)
				(type default)
			)
			(layer "F.Fab")
		)
		(fp_line
			(start 0.67945 -0.3048)
			(end 0.67945 0.3048)
			(stroke
				(width 0.1)
				(type default)
			)
			(layer "F.Fab")
		)
		(fp_line
			(start 0.12065 -0.2794)
			(end 0.12065 -0.3048)
			(stroke
				(width 0.1)
				(type default)
			)
			(layer "F.Fab")
		)
		(fp_line
			(start 0.12065 -0.3048)
			(end 0.67945 -0.3048)
			(stroke
				(width 0.1)
				(type default)
			)
			(layer "F.Fab")
		)
		(fp_line
			(start 0.120396 0.3048)
			(end 0.120396 0.2794)
			(stroke
				(width 0.1)
				(type default)
			)
			(layer "F.Fab")
		)
		(fp_line
			(start 0.120396 0.2794)
			(end -0.12065 0.2794)
			(stroke
				(width 0.1)
				(type default)
			)
			(layer "F.Fab")
		)
		(fp_line
			(start -0.12065 0.3048)
			(end -0.67945 0.3048)
			(stroke
				(width 0.1)
				(type default)
			)
			(layer "F.Fab")
		)
		(fp_line
			(start -0.12065 0.2794)
			(end -0.12065 0.3048)
			(stroke
				(width 0.1)
				(type default)
			)
			(layer "F.Fab")
		)
		(fp_line
			(start -0.12065 -0.2794)
			(end 0.12065 -0.2794)
			(stroke
				(width 0.1)
				(type default)
			)
			(layer "F.Fab")
		)
		(fp_line
			(start -0.12065 -0.305054)
			(end -0.12065 -0.2794)
			(stroke
				(width 0.1)
				(type default)
			)
			(layer "F.Fab")
		)
		(fp_line
			(start -0.67945 0.3048)
			(end -0.67945 -0.305054)
			(stroke
				(width 0.1)
				(type default)
			)
			(layer "F.Fab")
		)
		(fp_line
			(start -0.67945 -0.305054)
			(end -0.12065 -0.305054)
			(stroke
				(width 0.1)
				(type default)
			)
			(layer "F.Fab")
		)
		(pad "1" smd circle
			(at -0.40005 0 180)
			(size 0 0)
			(layers "F.Cu" "F.Mask" "F.Paste")
			(net "P3V3_AUX")
		)
		(pad "2" smd circle
			(at 0.40005 0 180)
			(size 0 0)
			(layers "F.Cu" "F.Mask" "F.Paste")
			(net "PCA9548_PCIE3_ADDR2")
		)
	)
	(footprint ""
		(layer "F.Cu")
		(at 31.29788 -430.875948 180)
		(property "Reference" "R2914"
			(at 0 0 180)
			(layer "F.SilkS")
			(hide yes)
			(effects
				(font
					(size 1.27 1.27)
				)
			)
		)
		(property "Value" ""
			(at 0 0 180)
			(layer "F.Fab")
			(effects
				(font
					(size 1.27 1.27)
				)
			)
		)
		(duplicate_pad_numbers_are_jumpers no)
		(fp_line
			(start 0.7874 0.4064)
			(end -0.7874 0.4064)
			(stroke
				(width 0.1524)
				(type default)
			)
			(layer "F.SilkS")
		)
		(fp_line
			(start 0.7874 -0.4064)
			(end 0.7874 0.4064)
			(stroke
				(width 0.1524)
				(type default)
			)
			(layer "F.SilkS")
		)
		(fp_line
			(start -0.7874 0.4064)
			(end -0.7874 -0.4064)
			(stroke
				(width 0.1524)
				(type default)
			)
			(layer "F.SilkS")
		)
		(fp_line
			(start -0.7874 -0.4064)
			(end 0.7874 -0.4064)
			(stroke
				(width 0.1524)
				(type default)
			)
			(layer "F.SilkS")
		)
		(fp_line
			(start 0.67945 0.3048)
			(end 0.120396 0.3048)
			(stroke
				(width 0.1)
				(type default)
			)
			(layer "F.Fab")
		)
		(fp_line
			(start 0.67945 -0.3048)
			(end 0.67945 0.3048)
			(stroke
				(width 0.1)
				(type default)
			)
			(layer "F.Fab")
		)
		(fp_line
			(start 0.12065 -0.2794)
			(end 0.12065 -0.3048)
			(stroke
				(width 0.1)
				(type default)
			)
			(layer "F.Fab")
		)
		(fp_line
			(start 0.12065 -0.3048)
			(end 0.67945 -0.3048)
			(stroke
				(width 0.1)
				(type default)
			)
			(layer "F.Fab")
		)
		(fp_line
			(start 0.120396 0.3048)
			(end 0.120396 0.2794)
			(stroke
				(width 0.1)
				(type default)
			)
			(layer "F.Fab")
		)
		(fp_line
			(start 0.120396 0.2794)
			(end -0.12065 0.2794)
			(stroke
				(width 0.1)
				(type default)
			)
			(layer "F.Fab")
		)
		(fp_line
			(start -0.12065 0.3048)
			(end -0.67945 0.3048)
			(stroke
				(width 0.1)
				(type default)
			)
			(layer "F.Fab")
		)
		(fp_line
			(start -0.12065 0.2794)
			(end -0.12065 0.3048)
			(stroke
				(width 0.1)
				(type default)
			)
			(layer "F.Fab")
		)
		(fp_line
			(start -0.12065 -0.2794)
			(end 0.12065 -0.2794)
			(stroke
				(width 0.1)
				(type default)
			)
			(layer "F.Fab")
		)
		(fp_line
			(start -0.12065 -0.305054)
			(end -0.12065 -0.2794)
			(stroke
				(width 0.1)
				(type default)
			)
			(layer "F.Fab")
		)
		(fp_line
			(start -0.67945 0.3048)
			(end -0.67945 -0.305054)
			(stroke
				(width 0.1)
				(type default)
			)
			(layer "F.Fab")
		)
		(fp_line
			(start -0.67945 -0.305054)
			(end -0.12065 -0.305054)
			(stroke
				(width 0.1)
				(type default)
			)
			(layer "F.Fab")
		)
		(pad "1" smd circle
			(at -0.40005 0 180)
			(size 0 0)
			(layers "F.Cu" "F.Mask" "F.Paste")
			(net "P3V3_AUX")
		)
		(pad "2" smd circle
			(at 0.40005 0 180)
			(size 0 0)
			(layers "F.Cu" "F.Mask" "F.Paste")
			(net "FM_SWB_PWR_EN_R1_BUF")
		)
	)
	(footprint ""
		(layer "F.Cu")
		(at 358.425496 -338.298028 -90)
		(property "Reference" "PC1341"
			(at 0 0 270)
			(layer "F.SilkS")
			(hide yes)
			(effects
				(font
					(size 1.27 1.27)
				)
			)
		)
		(property "Value" ""
			(at 0 0 270)
			(layer "F.Fab")
			(effects
				(font
					(size 1.27 1.27)
				)
			)
		)
		(duplicate_pad_numbers_are_jumpers no)
		(fp_line
			(start -0.7874 0.4064)
			(end -0.7874 -0.4064)
			(stroke
				(width 0.1524)
				(type default)
			)
			(layer "F.SilkS")
		)
		(fp_line
			(start 0.7874 0.4064)
			(end -0.7874 0.4064)
			(stroke
				(width 0.1524)
				(type default)
			)
			(layer "F.SilkS")
		)
		(fp_line
			(start -0.7874 -0.4064)
			(end 0.7874 -0.4064)
			(stroke
				(width 0.1524)
				(type default)
			)
			(layer "F.SilkS")
		)
		(fp_line
			(start 0.7874 -0.4064)
			(end 0.7874 0.4064)
			(stroke
				(width 0.1524)
				(type default)
			)
			(layer "F.SilkS")
		)
		(fp_line
			(start -0.67945 0.3048)
			(end -0.67945 -0.305054)
			(stroke
				(width 0.1)
				(type default)
			)
			(layer "F.Fab")
		)
		(fp_line
			(start -0.12065 0.3048)
			(end -0.67945 0.3048)
			(stroke
				(width 0.1)
				(type default)
			)
			(layer "F.Fab")
		)
		(fp_line
			(start 0.120396 0.3048)
			(end 0.120396 0.2794)
			(stroke
				(width 0.1)
				(type default)
			)
			(layer "F.Fab")
		)
		(fp_line
			(start 0.67945 0.3048)
			(end 0.120396 0.3048)
			(stroke
				(width 0.1)
				(type default)
			)
			(layer "F.Fab")
		)
		(fp_line
			(start -0.12065 0.2794)
			(end -0.12065 0.3048)
			(stroke
				(width 0.1)
				(type default)
			)
			(layer "F.Fab")
		)
		(fp_line
			(start 0.120396 0.2794)
			(end -0.12065 0.2794)
			(stroke
				(width 0.1)
				(type default)
			)
			(layer "F.Fab")
		)
		(fp_line
			(start -0.12065 -0.2794)
			(end 0.12065 -0.2794)
			(stroke
				(width 0.1)
				(type default)
			)
			(layer "F.Fab")
		)
		(fp_line
			(start 0.12065 -0.2794)
			(end 0.12065 -0.3048)
			(stroke
				(width 0.1)
				(type default)
			)
			(layer "F.Fab")
		)
		(fp_line
			(start 0.12065 -0.3048)
			(end 0.67945 -0.3048)
			(stroke
				(width 0.1)
				(type default)
			)
			(layer "F.Fab")
		)
		(fp_line
			(start 0.67945 -0.3048)
			(end 0.67945 0.3048)
			(stroke
				(width 0.1)
				(type default)
			)
			(layer "F.Fab")
		)
		(fp_line
			(start -0.67945 -0.305054)
			(end -0.12065 -0.305054)
			(stroke
				(width 0.1)
				(type default)
			)
			(layer "F.Fab")
		)
		(fp_line
			(start -0.12065 -0.305054)
			(end -0.12065 -0.2794)
			(stroke
				(width 0.1)
				(type default)
			)
			(layer "F.Fab")
		)
		(pad "1" smd circle
			(at -0.40005 0 270)
			(size 0 0)
			(layers "F.Cu" "F.Mask" "F.Paste")
			(net "GND")
		)
		(pad "2" smd circle
			(at 0.40005 0 270)
			(size 0 0)
			(layers "F.Cu" "F.Mask" "F.Paste")
			(net "PVCCIN_CPU0_VREF")
		)
	)
	(footprint ""
		(layer "F.Cu")
		(at 355.8286 -404.876 180)
		(property "Reference" "R4731"
			(at 0 0 180)
			(layer "F.SilkS")
			(hide yes)
			(effects
				(font
					(size 1.27 1.27)
				)
			)
		)
		(property "Value" ""
			(at 0 0 180)
			(layer "F.Fab")
			(effects
				(font
					(size 1.27 1.27)
				)
			)
		)
		(duplicate_pad_numbers_are_jumpers no)
		(fp_line
			(start 0.7874 0.4064)
			(end -0.7874 0.4064)
			(stroke
				(width 0.1524)
				(type default)
			)
			(layer "F.SilkS")
		)
		(fp_line
			(start 0.7874 -0.4064)
			(end 0.7874 0.4064)
			(stroke
				(width 0.1524)
				(type default)
			)
			(layer "F.SilkS")
		)
		(fp_line
			(start -0.7874 0.4064)
			(end -0.7874 -0.4064)
			(stroke
				(width 0.1524)
				(type default)
			)
			(layer "F.SilkS")
		)
		(fp_line
			(start -0.7874 -0.4064)
			(end 0.7874 -0.4064)
			(stroke
				(width 0.1524)
				(type default)
			)
			(layer "F.SilkS")
		)
		(fp_line
			(start 0.67945 0.3048)
			(end 0.120396 0.3048)
			(stroke
				(width 0.1)
				(type default)
			)
			(layer "F.Fab")
		)
		(fp_line
			(start 0.67945 -0.3048)
			(end 0.67945 0.3048)
			(stroke
				(width 0.1)
				(type default)
			)
			(layer "F.Fab")
		)
		(fp_line
			(start 0.12065 -0.2794)
			(end 0.12065 -0.3048)
			(stroke
				(width 0.1)
				(type default)
			)
			(layer "F.Fab")
		)
		(fp_line
			(start 0.12065 -0.3048)
			(end 0.67945 -0.3048)
			(stroke
				(width 0.1)
				(type default)
			)
			(layer "F.Fab")
		)
		(fp_line
			(start 0.120396 0.3048)
			(end 0.120396 0.2794)
			(stroke
				(width 0.1)
				(type default)
			)
			(layer "F.Fab")
		)
		(fp_line
			(start 0.120396 0.2794)
			(end -0.12065 0.2794)
			(stroke
				(width 0.1)
				(type default)
			)
			(layer "F.Fab")
		)
		(fp_line
			(start -0.12065 0.3048)
			(end -0.67945 0.3048)
			(stroke
				(width 0.1)
				(type default)
			)
			(layer "F.Fab")
		)
		(fp_line
			(start -0.12065 0.2794)
			(end -0.12065 0.3048)
			(stroke
				(width 0.1)
				(type default)
			)
			(layer "F.Fab")
		)
		(fp_line
			(start -0.12065 -0.2794)
			(end 0.12065 -0.2794)
			(stroke
				(width 0.1)
				(type default)
			)
			(layer "F.Fab")
		)
		(fp_line
			(start -0.12065 -0.305054)
			(end -0.12065 -0.2794)
			(stroke
				(width 0.1)
				(type default)
			)
			(layer "F.Fab")
		)
		(fp_line
			(start -0.67945 0.3048)
			(end -0.67945 -0.305054)
			(stroke
				(width 0.1)
				(type default)
			)
			(layer "F.Fab")
		)
		(fp_line
			(start -0.67945 -0.305054)
			(end -0.12065 -0.305054)
			(stroke
				(width 0.1)
				(type default)
			)
			(layer "F.Fab")
		)
		(pad "1" smd circle
			(at -0.40005 0 180)
			(size 0 0)
			(layers "F.Cu" "F.Mask" "F.Paste")
			(net "PRSNT_CABLE_SWB_B2_N")
		)
		(pad "2" smd circle
			(at 0.40005 0 180)
			(size 0 0)
			(layers "F.Cu" "F.Mask" "F.Paste")
			(net "GND")
		)
	)
	(footprint ""
		(layer "F.Cu")
		(at 207.074008 -402.994622 90)
		(property "Reference" "PC2181"
			(at 0 0 90)
			(layer "F.SilkS")
			(hide yes)
			(effects
				(font
					(size 1.27 1.27)
				)
			)
		)
		(property "Value" ""
			(at 0 0 90)
			(layer "F.Fab")
			(effects
				(font
					(size 1.27 1.27)
				)
			)
		)
		(duplicate_pad_numbers_are_jumpers no)
		(fp_line
			(start 0.7874 -0.4064)
			(end 0.7874 0.4064)
			(stroke
				(width 0.1524)
				(type default)
			)
			(layer "F.SilkS")
		)
		(fp_line
			(start -0.7874 -0.4064)
			(end 0.7874 -0.4064)
			(stroke
				(width 0.1524)
				(type default)
			)
			(layer "F.SilkS")
		)
		(fp_line
			(start 0.7874 0.4064)
			(end -0.7874 0.4064)
			(stroke
				(width 0.1524)
				(type default)
			)
			(layer "F.SilkS")
		)
		(fp_line
			(start -0.7874 0.4064)
			(end -0.7874 -0.4064)
			(stroke
				(width 0.1524)
				(type default)
			)
			(layer "F.SilkS")
		)
		(fp_line
			(start -0.12065 -0.305054)
			(end -0.12065 -0.2794)
			(stroke
				(width 0.1)
				(type default)
			)
			(layer "F.Fab")
		)
		(fp_line
			(start -0.67945 -0.305054)
			(end -0.12065 -0.305054)
			(stroke
				(width 0.1)
				(type default)
			)
			(layer "F.Fab")
		)
		(fp_line
			(start 0.67945 -0.3048)
			(end 0.67945 0.3048)
			(stroke
				(width 0.1)
				(type default)
			)
			(layer "F.Fab")
		)
		(fp_line
			(start 0.12065 -0.3048)
			(end 0.67945 -0.3048)
			(stroke
				(width 0.1)
				(type default)
			)
			(layer "F.Fab")
		)
		(fp_line
			(start 0.12065 -0.2794)
			(end 0.12065 -0.3048)
			(stroke
				(width 0.1)
				(type default)
			)
			(layer "F.Fab")
		)
		(fp_line
			(start -0.12065 -0.2794)
			(end 0.12065 -0.2794)
			(stroke
				(width 0.1)
				(type default)
			)
			(layer "F.Fab")
		)
		(fp_line
			(start 0.120396 0.2794)
			(end -0.12065 0.2794)
			(stroke
				(width 0.1)
				(type default)
			)
			(layer "F.Fab")
		)
		(fp_line
			(start -0.12065 0.2794)
			(end -0.12065 0.3048)
			(stroke
				(width 0.1)
				(type default)
			)
			(layer "F.Fab")
		)
		(fp_line
			(start 0.67945 0.3048)
			(end 0.120396 0.3048)
			(stroke
				(width 0.1)
				(type default)
			)
			(layer "F.Fab")
		)
		(fp_line
			(start 0.120396 0.3048)
			(end 0.120396 0.2794)
			(stroke
				(width 0.1)
				(type default)
			)
			(layer "F.Fab")
		)
		(fp_line
			(start -0.12065 0.3048)
			(end -0.67945 0.3048)
			(stroke
				(width 0.1)
				(type default)
			)
			(layer "F.Fab")
		)
		(fp_line
			(start -0.67945 0.3048)
			(end -0.67945 -0.305054)
			(stroke
				(width 0.1)
				(type default)
			)
			(layer "F.Fab")
		)
		(pad "1" smd circle
			(at -0.40005 0 90)
			(size 0 0)
			(layers "F.Cu" "F.Mask" "F.Paste")
			(net "HSC_VDD_R_2")
		)
		(pad "2" smd circle
			(at 0.40005 0 90)
			(size 0 0)
			(layers "F.Cu" "F.Mask" "F.Paste")
			(net "AGND_HSC")
		)
	)
	(footprint ""
		(layer "F.Cu")
		(at 373.736616 -366.581944 90)
		(property "Reference" "PL118"
			(at 4.647438 -1.728724 0)
			(unlocked yes)
			(layer "F.SilkS")
			(effects
				(font
					(size 0.7874 0.5842)
					(thickness 0.1524)
				)
				(justify left)
			)
		)
		(property "Value" ""
			(at 0 0 90)
			(layer "F.Fab")
			(effects
				(font
					(size 1.27 1.27)
				)
			)
		)
		(duplicate_pad_numbers_are_jumpers no)
		(fp_line
			(start 3.64998 -3.350006)
			(end 3.64998 -1.8034)
			(stroke
				(width 0.1524)
				(type default)
			)
			(layer "F.SilkS")
		)
		(fp_line
			(start -3.6576 -3.350006)
			(end 3.64998 -3.350006)
			(stroke
				(width 0.1524)
				(type default)
			)
			(layer "F.SilkS")
		)
		(fp_line
			(start -3.64998 -1.8034)
			(end -3.64998 -3.350006)
			(stroke
				(width 0.1524)
				(type default)
			)
			(layer "F.SilkS")
		)
		(fp_line
			(start 3.64998 1.8034)
			(end 3.64998 3.350006)
			(stroke
				(width 0.1524)
				(type default)
			)
			(layer "F.SilkS")
		)
		(fp_line
			(start 3.64998 3.350006)
			(end -3.64998 3.350006)
			(stroke
				(width 0.1524)
				(type default)
			)
			(layer "F.SilkS")
		)
		(fp_line
			(start -3.64998 3.350006)
			(end -3.64998 1.8288)
			(stroke
				(width 0.1524)
				(type default)
			)
			(layer "F.SilkS")
		)
		(fp_line
			(start 3.64998 -3.350006)
			(end 3.64998 3.350006)
			(stroke
				(width 0.1)
				(type default)
			)
			(layer "F.Fab")
		)
		(fp_line
			(start -3.64998 -3.350006)
			(end 3.64998 -3.350006)
			(stroke
				(width 0.1)
				(type default)
			)
			(layer "F.Fab")
		)
		(fp_line
			(start 3.64998 3.350006)
			(end -3.64998 3.350006)
			(stroke
				(width 0.1)
				(type default)
			)
			(layer "F.Fab")
		)
		(fp_line
			(start -3.64998 3.350006)
			(end -3.64998 -3.350006)
			(stroke
				(width 0.1)
				(type default)
			)
			(layer "F.Fab")
		)
		(pad "1" smd rect
			(at -2.92481 0 90)
			(size 2.15392 3.302)
			(layers "F.Cu" "F.Mask" "F.Paste")
			(net "SW_PVPP_HBM_CPU0_SW")
		)
		(pad "2" smd rect
			(at 2.92481 0 90)
			(size 2.15392 3.302)
			(layers "F.Cu" "F.Mask" "F.Paste")
			(net "PVPP_HBM_CPU0")
		)
	)
	(footprint ""
		(layer "F.Cu")
		(at 162.179 -20.665948 -90)
		(property "Reference" "R4508"
			(at 0 0 270)
			(layer "F.SilkS")
			(hide yes)
			(effects
				(font
					(size 1.27 1.27)
				)
			)
		)
		(property "Value" ""
			(at 0 0 270)
			(layer "F.Fab")
			(effects
				(font
					(size 1.27 1.27)
				)
			)
		)
		(duplicate_pad_numbers_are_jumpers no)
		(fp_line
			(start -0.7874 0.4064)
			(end -0.7874 -0.4064)
			(stroke
				(width 0.1524)
				(type default)
			)
			(layer "F.SilkS")
		)
		(fp_line
			(start 0.7874 0.4064)
			(end -0.7874 0.4064)
			(stroke
				(width 0.1524)
				(type default)
			)
			(layer "F.SilkS")
		)
		(fp_line
			(start -0.7874 -0.4064)
			(end 0.7874 -0.4064)
			(stroke
				(width 0.1524)
				(type default)
			)
			(layer "F.SilkS")
		)
		(fp_line
			(start 0.7874 -0.4064)
			(end 0.7874 0.4064)
			(stroke
				(width 0.1524)
				(type default)
			)
			(layer "F.SilkS")
		)
		(fp_line
			(start -0.67945 0.3048)
			(end -0.67945 -0.305054)
			(stroke
				(width 0.1)
				(type default)
			)
			(layer "F.Fab")
		)
		(fp_line
			(start -0.12065 0.3048)
			(end -0.67945 0.3048)
			(stroke
				(width 0.1)
				(type default)
			)
			(layer "F.Fab")
		)
		(fp_line
			(start 0.120396 0.3048)
			(end 0.120396 0.2794)
			(stroke
				(width 0.1)
				(type default)
			)
			(layer "F.Fab")
		)
		(fp_line
			(start 0.67945 0.3048)
			(end 0.120396 0.3048)
			(stroke
				(width 0.1)
				(type default)
			)
			(layer "F.Fab")
		)
		(fp_line
			(start -0.12065 0.2794)
			(end -0.12065 0.3048)
			(stroke
				(width 0.1)
				(type default)
			)
			(layer "F.Fab")
		)
		(fp_line
			(start 0.120396 0.2794)
			(end -0.12065 0.2794)
			(stroke
				(width 0.1)
				(type default)
			)
			(layer "F.Fab")
		)
		(fp_line
			(start -0.12065 -0.2794)
			(end 0.12065 -0.2794)
			(stroke
				(width 0.1)
				(type default)
			)
			(layer "F.Fab")
		)
		(fp_line
			(start 0.12065 -0.2794)
			(end 0.12065 -0.3048)
			(stroke
				(width 0.1)
				(type default)
			)
			(layer "F.Fab")
		)
		(fp_line
			(start 0.12065 -0.3048)
			(end 0.67945 -0.3048)
			(stroke
				(width 0.1)
				(type default)
			)
			(layer "F.Fab")
		)
		(fp_line
			(start 0.67945 -0.3048)
			(end 0.67945 0.3048)
			(stroke
				(width 0.1)
				(type default)
			)
			(layer "F.Fab")
		)
		(fp_line
			(start -0.67945 -0.305054)
			(end -0.12065 -0.305054)
			(stroke
				(width 0.1)
				(type default)
			)
			(layer "F.Fab")
		)
		(fp_line
			(start -0.12065 -0.305054)
			(end -0.12065 -0.2794)
			(stroke
				(width 0.1)
				(type default)
			)
			(layer "F.Fab")
		)
		(pad "1" smd circle
			(at -0.40005 0 270)
			(size 0 0)
			(layers "F.Cu" "F.Mask" "F.Paste")
			(net "SMB_1_PLD_3V3AUX_SCL")
		)
		(pad "2" smd circle
			(at 0.40005 0 270)
			(size 0 0)
			(layers "F.Cu" "F.Mask" "F.Paste")
			(net "SMB_1_PLD_3V3AUX_SCL_R3")
		)
	)
	(footprint ""
		(layer "F.Cu")
		(at 466.68309 -46.408848)
		(property "Reference" "C1175"
			(at 0 0 0)
			(layer "F.SilkS")
			(hide yes)
			(effects
				(font
					(size 1.27 1.27)
				)
			)
		)
		(property "Value" ""
			(at 0 0 0)
			(layer "F.Fab")
			(effects
				(font
					(size 1.27 1.27)
				)
			)
		)
		(duplicate_pad_numbers_are_jumpers no)
		(fp_line
			(start -0.7874 -0.4064)
			(end 0.7874 -0.4064)
			(stroke
				(width 0.1524)
				(type default)
			)
			(layer "F.SilkS")
		)
		(fp_line
			(start -0.7874 0.4064)
			(end -0.7874 -0.4064)
			(stroke
				(width 0.1524)
				(type default)
			)
			(layer "F.SilkS")
		)
		(fp_line
			(start 0.7874 -0.4064)
			(end 0.7874 0.4064)
			(stroke
				(width 0.1524)
				(type default)
			)
			(layer "F.SilkS")
		)
		(fp_line
			(start 0.7874 0.4064)
			(end -0.7874 0.4064)
			(stroke
				(width 0.1524)
				(type default)
			)
			(layer "F.SilkS")
		)
		(fp_line
			(start -0.67945 -0.305054)
			(end -0.12065 -0.305054)
			(stroke
				(width 0.1)
				(type default)
			)
			(layer "F.Fab")
		)
		(fp_line
			(start -0.67945 0.3048)
			(end -0.67945 -0.305054)
			(stroke
				(width 0.1)
				(type default)
			)
			(layer "F.Fab")
		)
		(fp_line
			(start -0.12065 -0.305054)
			(end -0.12065 -0.2794)
			(stroke
				(width 0.1)
				(type default)
			)
			(layer "F.Fab")
		)
		(fp_line
			(start -0.12065 -0.2794)
			(end 0.12065 -0.2794)
			(stroke
				(width 0.1)
				(type default)
			)
			(layer "F.Fab")
		)
		(fp_line
			(start -0.12065 0.2794)
			(end -0.12065 0.3048)
			(stroke
				(width 0.1)
				(type default)
			)
			(layer "F.Fab")
		)
		(fp_line
			(start -0.12065 0.3048)
			(end -0.67945 0.3048)
			(stroke
				(width 0.1)
				(type default)
			)
			(layer "F.Fab")
		)
		(fp_line
			(start 0.120396 0.2794)
			(end -0.12065 0.2794)
			(stroke
				(width 0.1)
				(type default)
			)
			(layer "F.Fab")
		)
		(fp_line
			(start 0.120396 0.3048)
			(end 0.120396 0.2794)
			(stroke
				(width 0.1)
				(type default)
			)
			(layer "F.Fab")
		)
		(fp_line
			(start 0.12065 -0.3048)
			(end 0.67945 -0.3048)
			(stroke
				(width 0.1)
				(type default)
			)
			(layer "F.Fab")
		)
		(fp_line
			(start 0.12065 -0.2794)
			(end 0.12065 -0.3048)
			(stroke
				(width 0.1)
				(type default)
			)
			(layer "F.Fab")
		)
		(fp_line
			(start 0.67945 -0.3048)
			(end 0.67945 0.3048)
			(stroke
				(width 0.1)
				(type default)
			)
			(layer "F.Fab")
		)
		(fp_line
			(start 0.67945 0.3048)
			(end 0.120396 0.3048)
			(stroke
				(width 0.1)
				(type default)
			)
			(layer "F.Fab")
		)
		(pad "1" smd circle
			(at -0.40005 0)
			(size 0 0)
			(layers "F.Cu" "F.Mask" "F.Paste")
			(net "P3V3_AUX")
		)
		(pad "2" smd circle
			(at 0.40005 0)
			(size 0 0)
			(layers "F.Cu" "F.Mask" "F.Paste")
			(net "GND")
		)
	)
	(footprint ""
		(layer "F.Cu")
		(at 374.336056 -354.844858)
		(property "Reference" "PC831"
			(at 0 0 0)
			(layer "F.SilkS")
			(hide yes)
			(effects
				(font
					(size 1.27 1.27)
				)
			)
		)
		(property "Value" ""
			(at 0 0 0)
			(layer "F.Fab")
			(effects
				(font
					(size 1.27 1.27)
				)
			)
		)
		(duplicate_pad_numbers_are_jumpers no)
		(fp_line
			(start -1.524 -0.762)
			(end 1.524 -0.762)
			(stroke
				(width 0.1524)
				(type default)
			)
			(layer "F.SilkS")
		)
		(fp_line
			(start -1.524 0.762)
			(end -1.524 -0.762)
			(stroke
				(width 0.1524)
				(type default)
			)
			(layer "F.SilkS")
		)
		(fp_line
			(start 1.524 -0.762)
			(end 1.524 0.762)
			(stroke
				(width 0.1524)
				(type default)
			)
			(layer "F.SilkS")
		)
		(fp_line
			(start 1.524 0.762)
			(end -1.524 0.762)
			(stroke
				(width 0.1524)
				(type default)
			)
			(layer "F.SilkS")
		)
		(fp_line
			(start -1.1049 -0.724916)
			(end -1.1049 0.724916)
			(stroke
				(width 0.1)
				(type default)
			)
			(layer "F.Fab")
		)
		(fp_line
			(start -1.1049 0.724916)
			(end 1.1049 0.724916)
			(stroke
				(width 0.1)
				(type default)
			)
			(layer "F.Fab")
		)
		(fp_line
			(start 1.1049 -0.724916)
			(end -1.1049 -0.724916)
			(stroke
				(width 0.1)
				(type default)
			)
			(layer "F.Fab")
		)
		(fp_line
			(start 1.1049 0.724916)
			(end 1.1049 -0.724916)
			(stroke
				(width 0.1)
				(type default)
			)
			(layer "F.Fab")
		)
		(pad "1" smd rect
			(at -0.889 0 180)
			(size 1.016 1.27)
			(layers "F.Cu" "F.Mask" "F.Paste")
			(net "SW_P12V_PVCCIN_CPU0_FLT")
		)
		(pad "2" smd rect
			(at 0.889 0 180)
			(size 1.016 1.27)
			(layers "F.Cu" "F.Mask" "F.Paste")
			(net "GND")
		)
	)
	(footprint ""
		(layer "F.Cu")
		(at 225.525838 -220.815916 90)
		(property "Reference" "R995"
			(at 0 0 90)
			(layer "F.SilkS")
			(hide yes)
			(effects
				(font
					(size 1.27 1.27)
				)
			)
		)
		(property "Value" ""
			(at 0 0 90)
			(layer "F.Fab")
			(effects
				(font
					(size 1.27 1.27)
				)
			)
		)
		(duplicate_pad_numbers_are_jumpers no)
		(fp_line
			(start 0.7874 -0.4064)
			(end 0.7874 0.4064)
			(stroke
				(width 0.1524)
				(type default)
			)
			(layer "F.SilkS")
		)
		(fp_line
			(start -0.7874 -0.4064)
			(end 0.7874 -0.4064)
			(stroke
				(width 0.1524)
				(type default)
			)
			(layer "F.SilkS")
		)
		(fp_line
			(start 0.7874 0.4064)
			(end -0.7874 0.4064)
			(stroke
				(width 0.1524)
				(type default)
			)
			(layer "F.SilkS")
		)
		(fp_line
			(start -0.7874 0.4064)
			(end -0.7874 -0.4064)
			(stroke
				(width 0.1524)
				(type default)
			)
			(layer "F.SilkS")
		)
		(fp_line
			(start -0.12065 -0.305054)
			(end -0.12065 -0.2794)
			(stroke
				(width 0.1)
				(type default)
			)
			(layer "F.Fab")
		)
		(fp_line
			(start -0.67945 -0.305054)
			(end -0.12065 -0.305054)
			(stroke
				(width 0.1)
				(type default)
			)
			(layer "F.Fab")
		)
		(fp_line
			(start 0.67945 -0.3048)
			(end 0.67945 0.3048)
			(stroke
				(width 0.1)
				(type default)
			)
			(layer "F.Fab")
		)
		(fp_line
			(start 0.12065 -0.3048)
			(end 0.67945 -0.3048)
			(stroke
				(width 0.1)
				(type default)
			)
			(layer "F.Fab")
		)
		(fp_line
			(start 0.12065 -0.2794)
			(end 0.12065 -0.3048)
			(stroke
				(width 0.1)
				(type default)
			)
			(layer "F.Fab")
		)
		(fp_line
			(start -0.12065 -0.2794)
			(end 0.12065 -0.2794)
			(stroke
				(width 0.1)
				(type default)
			)
			(layer "F.Fab")
		)
		(fp_line
			(start 0.120396 0.2794)
			(end -0.12065 0.2794)
			(stroke
				(width 0.1)
				(type default)
			)
			(layer "F.Fab")
		)
		(fp_line
			(start -0.12065 0.2794)
			(end -0.12065 0.3048)
			(stroke
				(width 0.1)
				(type default)
			)
			(layer "F.Fab")
		)
		(fp_line
			(start 0.67945 0.3048)
			(end 0.120396 0.3048)
			(stroke
				(width 0.1)
				(type default)
			)
			(layer "F.Fab")
		)
		(fp_line
			(start 0.120396 0.3048)
			(end 0.120396 0.2794)
			(stroke
				(width 0.1)
				(type default)
			)
			(layer "F.Fab")
		)
		(fp_line
			(start -0.12065 0.3048)
			(end -0.67945 0.3048)
			(stroke
				(width 0.1)
				(type default)
			)
			(layer "F.Fab")
		)
		(fp_line
			(start -0.67945 0.3048)
			(end -0.67945 -0.305054)
			(stroke
				(width 0.1)
				(type default)
			)
			(layer "F.Fab")
		)
		(pad "1" smd circle
			(at -0.40005 0 90)
			(size 0 0)
			(layers "F.Cu" "F.Mask" "F.Paste")
			(net "SMB_S3M_CPU1_SCL")
		)
		(pad "2" smd circle
			(at 0.40005 0 90)
			(size 0 0)
			(layers "F.Cu" "F.Mask" "F.Paste")
			(net "SMB_S3M_CPU1_R_SCL")
		)
	)
	(footprint ""
		(layer "F.Cu")
		(at 204.99578 -113.0554 180)
		(property "Reference" "R4723"
			(at 0 0 180)
			(layer "F.SilkS")
			(hide yes)
			(effects
				(font
					(size 1.27 1.27)
				)
			)
		)
		(property "Value" ""
			(at 0 0 180)
			(layer "F.Fab")
			(effects
				(font
					(size 1.27 1.27)
				)
			)
		)
		(duplicate_pad_numbers_are_jumpers no)
		(fp_line
			(start 0.7874 0.4064)
			(end -0.7874 0.4064)
			(stroke
				(width 0.1524)
				(type default)
			)
			(layer "F.SilkS")
		)
		(fp_line
			(start 0.7874 -0.4064)
			(end 0.7874 0.4064)
			(stroke
				(width 0.1524)
				(type default)
			)
			(layer "F.SilkS")
		)
		(fp_line
			(start -0.7874 0.4064)
			(end -0.7874 -0.4064)
			(stroke
				(width 0.1524)
				(type default)
			)
			(layer "F.SilkS")
		)
		(fp_line
			(start -0.7874 -0.4064)
			(end 0.7874 -0.4064)
			(stroke
				(width 0.1524)
				(type default)
			)
			(layer "F.SilkS")
		)
		(fp_line
			(start 0.67945 0.3048)
			(end 0.120396 0.3048)
			(stroke
				(width 0.1)
				(type default)
			)
			(layer "F.Fab")
		)
		(fp_line
			(start 0.67945 -0.3048)
			(end 0.67945 0.3048)
			(stroke
				(width 0.1)
				(type default)
			)
			(layer "F.Fab")
		)
		(fp_line
			(start 0.12065 -0.2794)
			(end 0.12065 -0.3048)
			(stroke
				(width 0.1)
				(type default)
			)
			(layer "F.Fab")
		)
		(fp_line
			(start 0.12065 -0.3048)
			(end 0.67945 -0.3048)
			(stroke
				(width 0.1)
				(type default)
			)
			(layer "F.Fab")
		)
		(fp_line
			(start 0.120396 0.3048)
			(end 0.120396 0.2794)
			(stroke
				(width 0.1)
				(type default)
			)
			(layer "F.Fab")
		)
		(fp_line
			(start 0.120396 0.2794)
			(end -0.12065 0.2794)
			(stroke
				(width 0.1)
				(type default)
			)
			(layer "F.Fab")
		)
		(fp_line
			(start -0.12065 0.3048)
			(end -0.67945 0.3048)
			(stroke
				(width 0.1)
				(type default)
			)
			(layer "F.Fab")
		)
		(fp_line
			(start -0.12065 0.2794)
			(end -0.12065 0.3048)
			(stroke
				(width 0.1)
				(type default)
			)
			(layer "F.Fab")
		)
		(fp_line
			(start -0.12065 -0.2794)
			(end 0.12065 -0.2794)
			(stroke
				(width 0.1)
				(type default)
			)
			(layer "F.Fab")
		)
		(fp_line
			(start -0.12065 -0.305054)
			(end -0.12065 -0.2794)
			(stroke
				(width 0.1)
				(type default)
			)
			(layer "F.Fab")
		)
		(fp_line
			(start -0.67945 0.3048)
			(end -0.67945 -0.305054)
			(stroke
				(width 0.1)
				(type default)
			)
			(layer "F.Fab")
		)
		(fp_line
			(start -0.67945 -0.305054)
			(end -0.12065 -0.305054)
			(stroke
				(width 0.1)
				(type default)
			)
			(layer "F.Fab")
		)
		(pad "1" smd circle
			(at -0.40005 0 180)
			(size 0 0)
			(layers "F.Cu" "F.Mask" "F.Paste")
			(net "FM_PCH_BMC_RST_R_N")
		)
		(pad "2" smd circle
			(at 0.40005 0 180)
			(size 0 0)
			(layers "F.Cu" "F.Mask" "F.Paste")
			(net "FM_PCH_BMC_RST_N")
		)
	)
	(footprint ""
		(layer "F.Cu")
		(at 166.34333 -131.976876 -90)
		(property "Reference" "R1607"
			(at 0 0 270)
			(layer "F.SilkS")
			(hide yes)
			(effects
				(font
					(size 1.27 1.27)
				)
			)
		)
		(property "Value" ""
			(at 0 0 270)
			(layer "F.Fab")
			(effects
				(font
					(size 1.27 1.27)
				)
			)
		)
		(duplicate_pad_numbers_are_jumpers no)
		(fp_line
			(start -0.7874 0.4064)
			(end -0.7874 -0.4064)
			(stroke
				(width 0.1524)
				(type default)
			)
			(layer "F.SilkS")
		)
		(fp_line
			(start 0.7874 0.4064)
			(end -0.7874 0.4064)
			(stroke
				(width 0.1524)
				(type default)
			)
			(layer "F.SilkS")
		)
		(fp_line
			(start -0.7874 -0.4064)
			(end 0.7874 -0.4064)
			(stroke
				(width 0.1524)
				(type default)
			)
			(layer "F.SilkS")
		)
		(fp_line
			(start 0.7874 -0.4064)
			(end 0.7874 0.4064)
			(stroke
				(width 0.1524)
				(type default)
			)
			(layer "F.SilkS")
		)
		(fp_line
			(start -0.67945 0.3048)
			(end -0.67945 -0.305054)
			(stroke
				(width 0.1)
				(type default)
			)
			(layer "F.Fab")
		)
		(fp_line
			(start -0.12065 0.3048)
			(end -0.67945 0.3048)
			(stroke
				(width 0.1)
				(type default)
			)
			(layer "F.Fab")
		)
		(fp_line
			(start 0.120396 0.3048)
			(end 0.120396 0.2794)
			(stroke
				(width 0.1)
				(type default)
			)
			(layer "F.Fab")
		)
		(fp_line
			(start 0.67945 0.3048)
			(end 0.120396 0.3048)
			(stroke
				(width 0.1)
				(type default)
			)
			(layer "F.Fab")
		)
		(fp_line
			(start -0.12065 0.2794)
			(end -0.12065 0.3048)
			(stroke
				(width 0.1)
				(type default)
			)
			(layer "F.Fab")
		)
		(fp_line
			(start 0.120396 0.2794)
			(end -0.12065 0.2794)
			(stroke
				(width 0.1)
				(type default)
			)
			(layer "F.Fab")
		)
		(fp_line
			(start -0.12065 -0.2794)
			(end 0.12065 -0.2794)
			(stroke
				(width 0.1)
				(type default)
			)
			(layer "F.Fab")
		)
		(fp_line
			(start 0.12065 -0.2794)
			(end 0.12065 -0.3048)
			(stroke
				(width 0.1)
				(type default)
			)
			(layer "F.Fab")
		)
		(fp_line
			(start 0.12065 -0.3048)
			(end 0.67945 -0.3048)
			(stroke
				(width 0.1)
				(type default)
			)
			(layer "F.Fab")
		)
		(fp_line
			(start 0.67945 -0.3048)
			(end 0.67945 0.3048)
			(stroke
				(width 0.1)
				(type default)
			)
			(layer "F.Fab")
		)
		(fp_line
			(start -0.67945 -0.305054)
			(end -0.12065 -0.305054)
			(stroke
				(width 0.1)
				(type default)
			)
			(layer "F.Fab")
		)
		(fp_line
			(start -0.12065 -0.305054)
			(end -0.12065 -0.2794)
			(stroke
				(width 0.1)
				(type default)
			)
			(layer "F.Fab")
		)
		(pad "1" smd circle
			(at -0.40005 0 270)
			(size 0 0)
			(layers "F.Cu" "F.Mask" "F.Paste")
			(net "FM_PS_EN_PLD_R")
		)
		(pad "2" smd circle
			(at 0.40005 0 270)
			(size 0 0)
			(layers "F.Cu" "F.Mask" "F.Paste")
			(net "VR_P5V_EN")
		)
	)
	(footprint ""
		(layer "F.Cu")
		(at 117.526816 -255.0541 90)
		(property "Reference" "C301"
			(at 0 0 90)
			(layer "F.SilkS")
			(hide yes)
			(effects
				(font
					(size 1.27 1.27)
				)
			)
		)
		(property "Value" ""
			(at 0 0 90)
			(layer "F.Fab")
			(effects
				(font
					(size 1.27 1.27)
				)
			)
		)
		(duplicate_pad_numbers_are_jumpers no)
		(fp_line
			(start 0.7874 -0.4064)
			(end 0.7874 0.4064)
			(stroke
				(width 0.1524)
				(type default)
			)
			(layer "F.SilkS")
		)
		(fp_line
			(start -0.7874 -0.4064)
			(end 0.7874 -0.4064)
			(stroke
				(width 0.1524)
				(type default)
			)
			(layer "F.SilkS")
		)
		(fp_line
			(start 0.7874 0.4064)
			(end -0.7874 0.4064)
			(stroke
				(width 0.1524)
				(type default)
			)
			(layer "F.SilkS")
		)
		(fp_line
			(start -0.7874 0.4064)
			(end -0.7874 -0.4064)
			(stroke
				(width 0.1524)
				(type default)
			)
			(layer "F.SilkS")
		)
		(fp_line
			(start -0.12065 -0.305054)
			(end -0.12065 -0.2794)
			(stroke
				(width 0.1)
				(type default)
			)
			(layer "F.Fab")
		)
		(fp_line
			(start -0.67945 -0.305054)
			(end -0.12065 -0.305054)
			(stroke
				(width 0.1)
				(type default)
			)
			(layer "F.Fab")
		)
		(fp_line
			(start 0.67945 -0.3048)
			(end 0.67945 0.3048)
			(stroke
				(width 0.1)
				(type default)
			)
			(layer "F.Fab")
		)
		(fp_line
			(start 0.12065 -0.3048)
			(end 0.67945 -0.3048)
			(stroke
				(width 0.1)
				(type default)
			)
			(layer "F.Fab")
		)
		(fp_line
			(start 0.12065 -0.2794)
			(end 0.12065 -0.3048)
			(stroke
				(width 0.1)
				(type default)
			)
			(layer "F.Fab")
		)
		(fp_line
			(start -0.12065 -0.2794)
			(end 0.12065 -0.2794)
			(stroke
				(width 0.1)
				(type default)
			)
			(layer "F.Fab")
		)
		(fp_line
			(start 0.120396 0.2794)
			(end -0.12065 0.2794)
			(stroke
				(width 0.1)
				(type default)
			)
			(layer "F.Fab")
		)
		(fp_line
			(start -0.12065 0.2794)
			(end -0.12065 0.3048)
			(stroke
				(width 0.1)
				(type default)
			)
			(layer "F.Fab")
		)
		(fp_line
			(start 0.67945 0.3048)
			(end 0.120396 0.3048)
			(stroke
				(width 0.1)
				(type default)
			)
			(layer "F.Fab")
		)
		(fp_line
			(start 0.120396 0.3048)
			(end 0.120396 0.2794)
			(stroke
				(width 0.1)
				(type default)
			)
			(layer "F.Fab")
		)
		(fp_line
			(start -0.12065 0.3048)
			(end -0.67945 0.3048)
			(stroke
				(width 0.1)
				(type default)
			)
			(layer "F.Fab")
		)
		(fp_line
			(start -0.67945 0.3048)
			(end -0.67945 -0.305054)
			(stroke
				(width 0.1)
				(type default)
			)
			(layer "F.Fab")
		)
		(pad "1" smd circle
			(at -0.40005 0 90)
			(size 0 0)
			(layers "F.Cu" "F.Mask" "F.Paste")
			(net "PVCCIN_CPU1")
		)
		(pad "2" smd circle
			(at 0.40005 0 90)
			(size 0 0)
			(layers "F.Cu" "F.Mask" "F.Paste")
			(net "GND")
		)
	)
	(footprint ""
		(layer "F.Cu")
		(at 331.224636 -17.414748 180)
		(property "Reference" "R2451"
			(at 0 0 180)
			(layer "F.SilkS")
			(hide yes)
			(effects
				(font
					(size 1.27 1.27)
				)
			)
		)
		(property "Value" ""
			(at 0 0 180)
			(layer "F.Fab")
			(effects
				(font
					(size 1.27 1.27)
				)
			)
		)
		(duplicate_pad_numbers_are_jumpers no)
		(fp_line
			(start 0.7874 0.4064)
			(end -0.7874 0.4064)
			(stroke
				(width 0.1524)
				(type default)
			)
			(layer "F.SilkS")
		)
		(fp_line
			(start 0.7874 -0.4064)
			(end 0.7874 0.4064)
			(stroke
				(width 0.1524)
				(type default)
			)
			(layer "F.SilkS")
		)
		(fp_line
			(start -0.7874 0.4064)
			(end -0.7874 -0.4064)
			(stroke
				(width 0.1524)
				(type default)
			)
			(layer "F.SilkS")
		)
		(fp_line
			(start -0.7874 -0.4064)
			(end 0.7874 -0.4064)
			(stroke
				(width 0.1524)
				(type default)
			)
			(layer "F.SilkS")
		)
		(fp_line
			(start 0.67945 0.3048)
			(end 0.120396 0.3048)
			(stroke
				(width 0.1)
				(type default)
			)
			(layer "F.Fab")
		)
		(fp_line
			(start 0.67945 -0.3048)
			(end 0.67945 0.3048)
			(stroke
				(width 0.1)
				(type default)
			)
			(layer "F.Fab")
		)
		(fp_line
			(start 0.12065 -0.2794)
			(end 0.12065 -0.3048)
			(stroke
				(width 0.1)
				(type default)
			)
			(layer "F.Fab")
		)
		(fp_line
			(start 0.12065 -0.3048)
			(end 0.67945 -0.3048)
			(stroke
				(width 0.1)
				(type default)
			)
			(layer "F.Fab")
		)
		(fp_line
			(start 0.120396 0.3048)
			(end 0.120396 0.2794)
			(stroke
				(width 0.1)
				(type default)
			)
			(layer "F.Fab")
		)
		(fp_line
			(start 0.120396 0.2794)
			(end -0.12065 0.2794)
			(stroke
				(width 0.1)
				(type default)
			)
			(layer "F.Fab")
		)
		(fp_line
			(start -0.12065 0.3048)
			(end -0.67945 0.3048)
			(stroke
				(width 0.1)
				(type default)
			)
			(layer "F.Fab")
		)
		(fp_line
			(start -0.12065 0.2794)
			(end -0.12065 0.3048)
			(stroke
				(width 0.1)
				(type default)
			)
			(layer "F.Fab")
		)
		(fp_line
			(start -0.12065 -0.2794)
			(end 0.12065 -0.2794)
			(stroke
				(width 0.1)
				(type default)
			)
			(layer "F.Fab")
		)
		(fp_line
			(start -0.12065 -0.305054)
			(end -0.12065 -0.2794)
			(stroke
				(width 0.1)
				(type default)
			)
			(layer "F.Fab")
		)
		(fp_line
			(start -0.67945 0.3048)
			(end -0.67945 -0.305054)
			(stroke
				(width 0.1)
				(type default)
			)
			(layer "F.Fab")
		)
		(fp_line
			(start -0.67945 -0.305054)
			(end -0.12065 -0.305054)
			(stroke
				(width 0.1)
				(type default)
			)
			(layer "F.Fab")
		)
		(pad "1" smd circle
			(at -0.40005 0 180)
			(size 0 0)
			(layers "F.Cu" "F.Mask" "F.Paste")
			(net "P3V3_AUX")
		)
		(pad "2" smd circle
			(at 0.40005 0 180)
			(size 0 0)
			(layers "F.Cu" "F.Mask" "F.Paste")
			(net "FM_ESPI_PLD_R1_EN")
		)
	)
	(footprint ""
		(layer "F.Cu")
		(at 359.967276 -338.86013)
		(property "Reference" "PR145"
			(at 0 0 0)
			(layer "F.SilkS")
			(hide yes)
			(effects
				(font
					(size 1.27 1.27)
				)
			)
		)
		(property "Value" ""
			(at 0 0 0)
			(layer "F.Fab")
			(effects
				(font
					(size 1.27 1.27)
				)
			)
		)
		(duplicate_pad_numbers_are_jumpers no)
		(fp_line
			(start -0.7874 -0.4064)
			(end 0.7874 -0.4064)
			(stroke
				(width 0.1524)
				(type default)
			)
			(layer "F.SilkS")
		)
		(fp_line
			(start -0.7874 0.4064)
			(end -0.7874 -0.4064)
			(stroke
				(width 0.1524)
				(type default)
			)
			(layer "F.SilkS")
		)
		(fp_line
			(start 0.7874 -0.4064)
			(end 0.7874 0.4064)
			(stroke
				(width 0.1524)
				(type default)
			)
			(layer "F.SilkS")
		)
		(fp_line
			(start 0.7874 0.4064)
			(end -0.7874 0.4064)
			(stroke
				(width 0.1524)
				(type default)
			)
			(layer "F.SilkS")
		)
		(fp_line
			(start -0.67945 -0.305054)
			(end -0.12065 -0.305054)
			(stroke
				(width 0.1)
				(type default)
			)
			(layer "F.Fab")
		)
		(fp_line
			(start -0.67945 0.3048)
			(end -0.67945 -0.305054)
			(stroke
				(width 0.1)
				(type default)
			)
			(layer "F.Fab")
		)
		(fp_line
			(start -0.12065 -0.305054)
			(end -0.12065 -0.2794)
			(stroke
				(width 0.1)
				(type default)
			)
			(layer "F.Fab")
		)
		(fp_line
			(start -0.12065 -0.2794)
			(end 0.12065 -0.2794)
			(stroke
				(width 0.1)
				(type default)
			)
			(layer "F.Fab")
		)
		(fp_line
			(start -0.12065 0.2794)
			(end -0.12065 0.3048)
			(stroke
				(width 0.1)
				(type default)
			)
			(layer "F.Fab")
		)
		(fp_line
			(start -0.12065 0.3048)
			(end -0.67945 0.3048)
			(stroke
				(width 0.1)
				(type default)
			)
			(layer "F.Fab")
		)
		(fp_line
			(start 0.120396 0.2794)
			(end -0.12065 0.2794)
			(stroke
				(width 0.1)
				(type default)
			)
			(layer "F.Fab")
		)
		(fp_line
			(start 0.120396 0.3048)
			(end 0.120396 0.2794)
			(stroke
				(width 0.1)
				(type default)
			)
			(layer "F.Fab")
		)
		(fp_line
			(start 0.12065 -0.3048)
			(end 0.67945 -0.3048)
			(stroke
				(width 0.1)
				(type default)
			)
			(layer "F.Fab")
		)
		(fp_line
			(start 0.12065 -0.2794)
			(end 0.12065 -0.3048)
			(stroke
				(width 0.1)
				(type default)
			)
			(layer "F.Fab")
		)
		(fp_line
			(start 0.67945 -0.3048)
			(end 0.67945 0.3048)
			(stroke
				(width 0.1)
				(type default)
			)
			(layer "F.Fab")
		)
		(fp_line
			(start 0.67945 0.3048)
			(end 0.120396 0.3048)
			(stroke
				(width 0.1)
				(type default)
			)
			(layer "F.Fab")
		)
		(pad "1" smd circle
			(at -0.40005 0)
			(size 0 0)
			(layers "F.Cu" "F.Mask" "F.Paste")
			(net "PVCCIN_CPU0_LSET3")
		)
		(pad "2" smd circle
			(at 0.40005 0)
			(size 0 0)
			(layers "F.Cu" "F.Mask" "F.Paste")
			(net "GND")
		)
	)
	(footprint ""
		(layer "F.Cu")
		(at 371.796818 -417.17341 90)
		(property "Reference" "R4206"
			(at 0 0 90)
			(layer "F.SilkS")
			(hide yes)
			(effects
				(font
					(size 1.27 1.27)
				)
			)
		)
		(property "Value" ""
			(at 0 0 90)
			(layer "F.Fab")
			(effects
				(font
					(size 1.27 1.27)
				)
			)
		)
		(duplicate_pad_numbers_are_jumpers no)
		(fp_line
			(start 0.7874 -0.4064)
			(end 0.7874 0.4064)
			(stroke
				(width 0.1524)
				(type default)
			)
			(layer "F.SilkS")
		)
		(fp_line
			(start -0.7874 -0.4064)
			(end 0.7874 -0.4064)
			(stroke
				(width 0.1524)
				(type default)
			)
			(layer "F.SilkS")
		)
		(fp_line
			(start 0.7874 0.4064)
			(end -0.7874 0.4064)
			(stroke
				(width 0.1524)
				(type default)
			)
			(layer "F.SilkS")
		)
		(fp_line
			(start -0.7874 0.4064)
			(end -0.7874 -0.4064)
			(stroke
				(width 0.1524)
				(type default)
			)
			(layer "F.SilkS")
		)
		(fp_line
			(start -0.12065 -0.305054)
			(end -0.12065 -0.2794)
			(stroke
				(width 0.1)
				(type default)
			)
			(layer "F.Fab")
		)
		(fp_line
			(start -0.67945 -0.305054)
			(end -0.12065 -0.305054)
			(stroke
				(width 0.1)
				(type default)
			)
			(layer "F.Fab")
		)
		(fp_line
			(start 0.67945 -0.3048)
			(end 0.67945 0.3048)
			(stroke
				(width 0.1)
				(type default)
			)
			(layer "F.Fab")
		)
		(fp_line
			(start 0.12065 -0.3048)
			(end 0.67945 -0.3048)
			(stroke
				(width 0.1)
				(type default)
			)
			(layer "F.Fab")
		)
		(fp_line
			(start 0.12065 -0.2794)
			(end 0.12065 -0.3048)
			(stroke
				(width 0.1)
				(type default)
			)
			(layer "F.Fab")
		)
		(fp_line
			(start -0.12065 -0.2794)
			(end 0.12065 -0.2794)
			(stroke
				(width 0.1)
				(type default)
			)
			(layer "F.Fab")
		)
		(fp_line
			(start 0.120396 0.2794)
			(end -0.12065 0.2794)
			(stroke
				(width 0.1)
				(type default)
			)
			(layer "F.Fab")
		)
		(fp_line
			(start -0.12065 0.2794)
			(end -0.12065 0.3048)
			(stroke
				(width 0.1)
				(type default)
			)
			(layer "F.Fab")
		)
		(fp_line
			(start 0.67945 0.3048)
			(end 0.120396 0.3048)
			(stroke
				(width 0.1)
				(type default)
			)
			(layer "F.Fab")
		)
		(fp_line
			(start 0.120396 0.3048)
			(end 0.120396 0.2794)
			(stroke
				(width 0.1)
				(type default)
			)
			(layer "F.Fab")
		)
		(fp_line
			(start -0.12065 0.3048)
			(end -0.67945 0.3048)
			(stroke
				(width 0.1)
				(type default)
			)
			(layer "F.Fab")
		)
		(fp_line
			(start -0.67945 0.3048)
			(end -0.67945 -0.305054)
			(stroke
				(width 0.1)
				(type default)
			)
			(layer "F.Fab")
		)
		(pad "1" smd circle
			(at -0.40005 0 90)
			(size 0 0)
			(layers "F.Cu" "F.Mask" "F.Paste")
			(net "P3V3_AUX")
		)
		(pad "2" smd circle
			(at 0.40005 0 90)
			(size 0 0)
			(layers "F.Cu" "F.Mask" "F.Paste")
			(net "U270_0_ADD0")
		)
	)
	(footprint ""
		(layer "F.Cu")
		(at 84.5058 -35.651948 90)
		(property "Reference" "R4616"
			(at 0 0 90)
			(layer "F.SilkS")
			(hide yes)
			(effects
				(font
					(size 1.27 1.27)
				)
			)
		)
		(property "Value" ""
			(at 0 0 90)
			(layer "F.Fab")
			(effects
				(font
					(size 1.27 1.27)
				)
			)
		)
		(duplicate_pad_numbers_are_jumpers no)
		(fp_line
			(start 0.7874 -0.4064)
			(end 0.7874 0.4064)
			(stroke
				(width 0.1524)
				(type default)
			)
			(layer "F.SilkS")
		)
		(fp_line
			(start -0.7874 -0.4064)
			(end 0.7874 -0.4064)
			(stroke
				(width 0.1524)
				(type default)
			)
			(layer "F.SilkS")
		)
		(fp_line
			(start 0.7874 0.4064)
			(end -0.7874 0.4064)
			(stroke
				(width 0.1524)
				(type default)
			)
			(layer "F.SilkS")
		)
		(fp_line
			(start -0.7874 0.4064)
			(end -0.7874 -0.4064)
			(stroke
				(width 0.1524)
				(type default)
			)
			(layer "F.SilkS")
		)
		(fp_line
			(start -0.12065 -0.305054)
			(end -0.12065 -0.2794)
			(stroke
				(width 0.1)
				(type default)
			)
			(layer "F.Fab")
		)
		(fp_line
			(start -0.67945 -0.305054)
			(end -0.12065 -0.305054)
			(stroke
				(width 0.1)
				(type default)
			)
			(layer "F.Fab")
		)
		(fp_line
			(start 0.67945 -0.3048)
			(end 0.67945 0.3048)
			(stroke
				(width 0.1)
				(type default)
			)
			(layer "F.Fab")
		)
		(fp_line
			(start 0.12065 -0.3048)
			(end 0.67945 -0.3048)
			(stroke
				(width 0.1)
				(type default)
			)
			(layer "F.Fab")
		)
		(fp_line
			(start 0.12065 -0.2794)
			(end 0.12065 -0.3048)
			(stroke
				(width 0.1)
				(type default)
			)
			(layer "F.Fab")
		)
		(fp_line
			(start -0.12065 -0.2794)
			(end 0.12065 -0.2794)
			(stroke
				(width 0.1)
				(type default)
			)
			(layer "F.Fab")
		)
		(fp_line
			(start 0.120396 0.2794)
			(end -0.12065 0.2794)
			(stroke
				(width 0.1)
				(type default)
			)
			(layer "F.Fab")
		)
		(fp_line
			(start -0.12065 0.2794)
			(end -0.12065 0.3048)
			(stroke
				(width 0.1)
				(type default)
			)
			(layer "F.Fab")
		)
		(fp_line
			(start 0.67945 0.3048)
			(end 0.120396 0.3048)
			(stroke
				(width 0.1)
				(type default)
			)
			(layer "F.Fab")
		)
		(fp_line
			(start 0.120396 0.3048)
			(end 0.120396 0.2794)
			(stroke
				(width 0.1)
				(type default)
			)
			(layer "F.Fab")
		)
		(fp_line
			(start -0.12065 0.3048)
			(end -0.67945 0.3048)
			(stroke
				(width 0.1)
				(type default)
			)
			(layer "F.Fab")
		)
		(fp_line
			(start -0.67945 0.3048)
			(end -0.67945 -0.305054)
			(stroke
				(width 0.1)
				(type default)
			)
			(layer "F.Fab")
		)
		(pad "1" smd circle
			(at -0.40005 0 90)
			(size 0 0)
			(layers "F.Cu" "F.Mask" "F.Paste")
			(net "HP_OCP_V3_2_RST")
		)
		(pad "2" smd circle
			(at 0.40005 0 90)
			(size 0 0)
			(layers "F.Cu" "F.Mask" "F.Paste")
			(net "HP_OCP_V3_2_RST_R")
		)
	)
	(footprint ""
		(layer "F.Cu")
		(at 104.8258 -408.2796)
		(property "Reference" "R4726"
			(at 0 0 0)
			(layer "F.SilkS")
			(hide yes)
			(effects
				(font
					(size 1.27 1.27)
				)
			)
		)
		(property "Value" ""
			(at 0 0 0)
			(layer "F.Fab")
			(effects
				(font
					(size 1.27 1.27)
				)
			)
		)
		(duplicate_pad_numbers_are_jumpers no)
		(fp_line
			(start -0.7874 -0.4064)
			(end 0.7874 -0.4064)
			(stroke
				(width 0.1524)
				(type default)
			)
			(layer "F.SilkS")
		)
		(fp_line
			(start -0.7874 0.4064)
			(end -0.7874 -0.4064)
			(stroke
				(width 0.1524)
				(type default)
			)
			(layer "F.SilkS")
		)
		(fp_line
			(start 0.7874 -0.4064)
			(end 0.7874 0.4064)
			(stroke
				(width 0.1524)
				(type default)
			)
			(layer "F.SilkS")
		)
		(fp_line
			(start 0.7874 0.4064)
			(end -0.7874 0.4064)
			(stroke
				(width 0.1524)
				(type default)
			)
			(layer "F.SilkS")
		)
		(fp_line
			(start -0.67945 -0.305054)
			(end -0.12065 -0.305054)
			(stroke
				(width 0.1)
				(type default)
			)
			(layer "F.Fab")
		)
		(fp_line
			(start -0.67945 0.3048)
			(end -0.67945 -0.305054)
			(stroke
				(width 0.1)
				(type default)
			)
			(layer "F.Fab")
		)
		(fp_line
			(start -0.12065 -0.305054)
			(end -0.12065 -0.2794)
			(stroke
				(width 0.1)
				(type default)
			)
			(layer "F.Fab")
		)
		(fp_line
			(start -0.12065 -0.2794)
			(end 0.12065 -0.2794)
			(stroke
				(width 0.1)
				(type default)
			)
			(layer "F.Fab")
		)
		(fp_line
			(start -0.12065 0.2794)
			(end -0.12065 0.3048)
			(stroke
				(width 0.1)
				(type default)
			)
			(layer "F.Fab")
		)
		(fp_line
			(start -0.12065 0.3048)
			(end -0.67945 0.3048)
			(stroke
				(width 0.1)
				(type default)
			)
			(layer "F.Fab")
		)
		(fp_line
			(start 0.120396 0.2794)
			(end -0.12065 0.2794)
			(stroke
				(width 0.1)
				(type default)
			)
			(layer "F.Fab")
		)
		(fp_line
			(start 0.120396 0.3048)
			(end 0.120396 0.2794)
			(stroke
				(width 0.1)
				(type default)
			)
			(layer "F.Fab")
		)
		(fp_line
			(start 0.12065 -0.3048)
			(end 0.67945 -0.3048)
			(stroke
				(width 0.1)
				(type default)
			)
			(layer "F.Fab")
		)
		(fp_line
			(start 0.12065 -0.2794)
			(end 0.12065 -0.3048)
			(stroke
				(width 0.1)
				(type default)
			)
			(layer "F.Fab")
		)
		(fp_line
			(start 0.67945 -0.3048)
			(end 0.67945 0.3048)
			(stroke
				(width 0.1)
				(type default)
			)
			(layer "F.Fab")
		)
		(fp_line
			(start 0.67945 0.3048)
			(end 0.120396 0.3048)
			(stroke
				(width 0.1)
				(type default)
			)
			(layer "F.Fab")
		)
		(pad "1" smd circle
			(at -0.40005 0)
			(size 0 0)
			(layers "F.Cu" "F.Mask" "F.Paste")
			(net "P3V3_AUX")
		)
		(pad "2" smd circle
			(at 0.40005 0)
			(size 0 0)
			(layers "F.Cu" "F.Mask" "F.Paste")
			(net "PRSNT_SWB_ISO_N")
		)
	)
	(footprint ""
		(layer "F.Cu")
		(at 196.708014 -78.42377 180)
		(property "Reference" "R1352"
			(at 0 0 180)
			(layer "F.SilkS")
			(hide yes)
			(effects
				(font
					(size 1.27 1.27)
				)
			)
		)
		(property "Value" ""
			(at 0 0 180)
			(layer "F.Fab")
			(effects
				(font
					(size 1.27 1.27)
				)
			)
		)
		(duplicate_pad_numbers_are_jumpers no)
		(fp_line
			(start 0.7874 0.4064)
			(end -0.7874 0.4064)
			(stroke
				(width 0.1524)
				(type default)
			)
			(layer "F.SilkS")
		)
		(fp_line
			(start 0.7874 -0.4064)
			(end 0.7874 0.4064)
			(stroke
				(width 0.1524)
				(type default)
			)
			(layer "F.SilkS")
		)
		(fp_line
			(start -0.7874 0.4064)
			(end -0.7874 -0.4064)
			(stroke
				(width 0.1524)
				(type default)
			)
			(layer "F.SilkS")
		)
		(fp_line
			(start -0.7874 -0.4064)
			(end 0.7874 -0.4064)
			(stroke
				(width 0.1524)
				(type default)
			)
			(layer "F.SilkS")
		)
		(fp_line
			(start 0.67945 0.3048)
			(end 0.120396 0.3048)
			(stroke
				(width 0.1)
				(type default)
			)
			(layer "F.Fab")
		)
		(fp_line
			(start 0.67945 -0.3048)
			(end 0.67945 0.3048)
			(stroke
				(width 0.1)
				(type default)
			)
			(layer "F.Fab")
		)
		(fp_line
			(start 0.12065 -0.2794)
			(end 0.12065 -0.3048)
			(stroke
				(width 0.1)
				(type default)
			)
			(layer "F.Fab")
		)
		(fp_line
			(start 0.12065 -0.3048)
			(end 0.67945 -0.3048)
			(stroke
				(width 0.1)
				(type default)
			)
			(layer "F.Fab")
		)
		(fp_line
			(start 0.120396 0.3048)
			(end 0.120396 0.2794)
			(stroke
				(width 0.1)
				(type default)
			)
			(layer "F.Fab")
		)
		(fp_line
			(start 0.120396 0.2794)
			(end -0.12065 0.2794)
			(stroke
				(width 0.1)
				(type default)
			)
			(layer "F.Fab")
		)
		(fp_line
			(start -0.12065 0.3048)
			(end -0.67945 0.3048)
			(stroke
				(width 0.1)
				(type default)
			)
			(layer "F.Fab")
		)
		(fp_line
			(start -0.12065 0.2794)
			(end -0.12065 0.3048)
			(stroke
				(width 0.1)
				(type default)
			)
			(layer "F.Fab")
		)
		(fp_line
			(start -0.12065 -0.2794)
			(end 0.12065 -0.2794)
			(stroke
				(width 0.1)
				(type default)
			)
			(layer "F.Fab")
		)
		(fp_line
			(start -0.12065 -0.305054)
			(end -0.12065 -0.2794)
			(stroke
				(width 0.1)
				(type default)
			)
			(layer "F.Fab")
		)
		(fp_line
			(start -0.67945 0.3048)
			(end -0.67945 -0.305054)
			(stroke
				(width 0.1)
				(type default)
			)
			(layer "F.Fab")
		)
		(fp_line
			(start -0.67945 -0.305054)
			(end -0.12065 -0.305054)
			(stroke
				(width 0.1)
				(type default)
			)
			(layer "F.Fab")
		)
		(pad "1" smd circle
			(at -0.40005 0 180)
			(size 0 0)
			(layers "F.Cu" "F.Mask" "F.Paste")
			(net "RMII_OCP_BMC_RXD_1")
		)
		(pad "2" smd circle
			(at 0.40005 0 180)
			(size 0 0)
			(layers "F.Cu" "F.Mask" "F.Paste")
			(net "GND")
		)
	)
	(footprint ""
		(layer "F.Cu")
		(at 220.100652 -103.330248)
		(property "Reference" "R2330"
			(at 0 0 0)
			(layer "F.SilkS")
			(hide yes)
			(effects
				(font
					(size 1.27 1.27)
				)
			)
		)
		(property "Value" ""
			(at 0 0 0)
			(layer "F.Fab")
			(effects
				(font
					(size 1.27 1.27)
				)
			)
		)
		(duplicate_pad_numbers_are_jumpers no)
		(fp_line
			(start -0.7874 -0.4064)
			(end 0.7874 -0.4064)
			(stroke
				(width 0.1524)
				(type default)
			)
			(layer "F.SilkS")
		)
		(fp_line
			(start -0.7874 0.4064)
			(end -0.7874 -0.4064)
			(stroke
				(width 0.1524)
				(type default)
			)
			(layer "F.SilkS")
		)
		(fp_line
			(start 0.7874 -0.4064)
			(end 0.7874 0.4064)
			(stroke
				(width 0.1524)
				(type default)
			)
			(layer "F.SilkS")
		)
		(fp_line
			(start 0.7874 0.4064)
			(end -0.7874 0.4064)
			(stroke
				(width 0.1524)
				(type default)
			)
			(layer "F.SilkS")
		)
		(fp_line
			(start -0.67945 -0.305054)
			(end -0.12065 -0.305054)
			(stroke
				(width 0.1)
				(type default)
			)
			(layer "F.Fab")
		)
		(fp_line
			(start -0.67945 0.3048)
			(end -0.67945 -0.305054)
			(stroke
				(width 0.1)
				(type default)
			)
			(layer "F.Fab")
		)
		(fp_line
			(start -0.12065 -0.305054)
			(end -0.12065 -0.2794)
			(stroke
				(width 0.1)
				(type default)
			)
			(layer "F.Fab")
		)
		(fp_line
			(start -0.12065 -0.2794)
			(end 0.12065 -0.2794)
			(stroke
				(width 0.1)
				(type default)
			)
			(layer "F.Fab")
		)
		(fp_line
			(start -0.12065 0.2794)
			(end -0.12065 0.3048)
			(stroke
				(width 0.1)
				(type default)
			)
			(layer "F.Fab")
		)
		(fp_line
			(start -0.12065 0.3048)
			(end -0.67945 0.3048)
			(stroke
				(width 0.1)
				(type default)
			)
			(layer "F.Fab")
		)
		(fp_line
			(start 0.120396 0.2794)
			(end -0.12065 0.2794)
			(stroke
				(width 0.1)
				(type default)
			)
			(layer "F.Fab")
		)
		(fp_line
			(start 0.120396 0.3048)
			(end 0.120396 0.2794)
			(stroke
				(width 0.1)
				(type default)
			)
			(layer "F.Fab")
		)
		(fp_line
			(start 0.12065 -0.3048)
			(end 0.67945 -0.3048)
			(stroke
				(width 0.1)
				(type default)
			)
			(layer "F.Fab")
		)
		(fp_line
			(start 0.12065 -0.2794)
			(end 0.12065 -0.3048)
			(stroke
				(width 0.1)
				(type default)
			)
			(layer "F.Fab")
		)
		(fp_line
			(start 0.67945 -0.3048)
			(end 0.67945 0.3048)
			(stroke
				(width 0.1)
				(type default)
			)
			(layer "F.Fab")
		)
		(fp_line
			(start 0.67945 0.3048)
			(end 0.120396 0.3048)
			(stroke
				(width 0.1)
				(type default)
			)
			(layer "F.Fab")
		)
		(pad "1" smd circle
			(at -0.40005 0)
			(size 0 0)
			(layers "F.Cu" "F.Mask" "F.Paste")
			(net "PWRGD_DSW_PWROK_R4")
		)
		(pad "2" smd circle
			(at 0.40005 0)
			(size 0 0)
			(layers "F.Cu" "F.Mask" "F.Paste")
			(net "PWRGD_DSW_PWROK")
		)
	)
	(footprint ""
		(layer "F.Cu")
		(at 367.920778 -417.15055 90)
		(property "Reference" "R4208"
			(at 0 0 90)
			(layer "F.SilkS")
			(hide yes)
			(effects
				(font
					(size 1.27 1.27)
				)
			)
		)
		(property "Value" ""
			(at 0 0 90)
			(layer "F.Fab")
			(effects
				(font
					(size 1.27 1.27)
				)
			)
		)
		(duplicate_pad_numbers_are_jumpers no)
		(fp_line
			(start 0.7874 -0.4064)
			(end 0.7874 0.4064)
			(stroke
				(width 0.1524)
				(type default)
			)
			(layer "F.SilkS")
		)
		(fp_line
			(start -0.7874 -0.4064)
			(end 0.7874 -0.4064)
			(stroke
				(width 0.1524)
				(type default)
			)
			(layer "F.SilkS")
		)
		(fp_line
			(start 0.7874 0.4064)
			(end -0.7874 0.4064)
			(stroke
				(width 0.1524)
				(type default)
			)
			(layer "F.SilkS")
		)
		(fp_line
			(start -0.7874 0.4064)
			(end -0.7874 -0.4064)
			(stroke
				(width 0.1524)
				(type default)
			)
			(layer "F.SilkS")
		)
		(fp_line
			(start -0.12065 -0.305054)
			(end -0.12065 -0.2794)
			(stroke
				(width 0.1)
				(type default)
			)
			(layer "F.Fab")
		)
		(fp_line
			(start -0.67945 -0.305054)
			(end -0.12065 -0.305054)
			(stroke
				(width 0.1)
				(type default)
			)
			(layer "F.Fab")
		)
		(fp_line
			(start 0.67945 -0.3048)
			(end 0.67945 0.3048)
			(stroke
				(width 0.1)
				(type default)
			)
			(layer "F.Fab")
		)
		(fp_line
			(start 0.12065 -0.3048)
			(end 0.67945 -0.3048)
			(stroke
				(width 0.1)
				(type default)
			)
			(layer "F.Fab")
		)
		(fp_line
			(start 0.12065 -0.2794)
			(end 0.12065 -0.3048)
			(stroke
				(width 0.1)
				(type default)
			)
			(layer "F.Fab")
		)
		(fp_line
			(start -0.12065 -0.2794)
			(end 0.12065 -0.2794)
			(stroke
				(width 0.1)
				(type default)
			)
			(layer "F.Fab")
		)
		(fp_line
			(start 0.120396 0.2794)
			(end -0.12065 0.2794)
			(stroke
				(width 0.1)
				(type default)
			)
			(layer "F.Fab")
		)
		(fp_line
			(start -0.12065 0.2794)
			(end -0.12065 0.3048)
			(stroke
				(width 0.1)
				(type default)
			)
			(layer "F.Fab")
		)
		(fp_line
			(start 0.67945 0.3048)
			(end 0.120396 0.3048)
			(stroke
				(width 0.1)
				(type default)
			)
			(layer "F.Fab")
		)
		(fp_line
			(start 0.120396 0.3048)
			(end 0.120396 0.2794)
			(stroke
				(width 0.1)
				(type default)
			)
			(layer "F.Fab")
		)
		(fp_line
			(start -0.12065 0.3048)
			(end -0.67945 0.3048)
			(stroke
				(width 0.1)
				(type default)
			)
			(layer "F.Fab")
		)
		(fp_line
			(start -0.67945 0.3048)
			(end -0.67945 -0.305054)
			(stroke
				(width 0.1)
				(type default)
			)
			(layer "F.Fab")
		)
		(pad "1" smd circle
			(at -0.40005 0 90)
			(size 0 0)
			(layers "F.Cu" "F.Mask" "F.Paste")
			(net "P3V3_AUX")
		)
		(pad "2" smd circle
			(at 0.40005 0 90)
			(size 0 0)
			(layers "F.Cu" "F.Mask" "F.Paste")
			(net "FM_THERMAL_ALERT_N")
		)
	)
	(footprint ""
		(layer "F.Cu")
		(at 131.579874 -408.517344 -90)
		(property "Reference" "C1523"
			(at 0 0 270)
			(layer "F.SilkS")
			(hide yes)
			(effects
				(font
					(size 1.27 1.27)
				)
			)
		)
		(property "Value" ""
			(at 0 0 270)
			(layer "F.Fab")
			(effects
				(font
					(size 1.27 1.27)
				)
			)
		)
		(duplicate_pad_numbers_are_jumpers no)
		(fp_line
			(start -0.299974 0.150114)
			(end -0.299974 -0.150114)
			(stroke
				(width 0.1)
				(type default)
			)
			(layer "F.Fab")
		)
		(fp_line
			(start 0.299974 0.150114)
			(end -0.299974 0.150114)
			(stroke
				(width 0.1)
				(type default)
			)
			(layer "F.Fab")
		)
		(fp_line
			(start -0.299974 -0.150114)
			(end 0.299974 -0.150114)
			(stroke
				(width 0.1)
				(type default)
			)
			(layer "F.Fab")
		)
		(fp_line
			(start 0.299974 -0.150114)
			(end 0.299974 0.150114)
			(stroke
				(width 0.1)
				(type default)
			)
			(layer "F.Fab")
		)
		(pad "1" smd rect
			(at -0.2667 0 270)
			(size 0.3048 0.381)
			(layers "F.Cu" "F.Mask" "F.Paste")
			(net "P5E_CPU1_PE3_TX_C_DP<12>")
		)
		(pad "2" smd rect
			(at 0.2667 0 270)
			(size 0.3048 0.381)
			(layers "F.Cu" "F.Mask" "F.Paste")
			(net "P5E_CPU1_PE3_TX_DP<12>")
		)
	)
	(footprint ""
		(layer "F.Cu")
		(at 448.799966 -435.59984)
		(property "Reference" "H90"
			(at -3.91922 -2.705608 0)
			(unlocked yes)
			(layer "F.SilkS")
			(effects
				(font
					(size 0.7874 0.5842)
					(thickness 0.1524)
				)
				(justify left)
			)
		)
		(property "Value" ""
			(at 0 0 0)
			(layer "F.Fab")
			(effects
				(font
					(size 1.27 1.27)
				)
			)
		)
		(duplicate_pad_numbers_are_jumpers no)
		(fp_circle
			(center 0 0)
			(end 2.6289 0)
			(stroke
				(width 0.1524)
				(type default)
			)
			(fill no)
			(layer "F.SilkS")
		)
		(fp_circle
			(center 0 0)
			(end 2.6289 0)
			(stroke
				(width 0.1524)
				(type default)
			)
			(fill no)
			(layer "B.SilkS")
		)
		(fp_circle
			(center 0 0)
			(end 2.6289 0)
			(stroke
				(width 0.1)
				(type default)
			)
			(fill no)
			(layer "B.Fab")
		)
		(fp_circle
			(center 0 0)
			(end 2.6289 0)
			(stroke
				(width 0.1)
				(type default)
			)
			(fill no)
			(layer "F.Fab")
		)
		(pad "" np_thru_hole circle
			(at 0 0)
			(size 3.0988 3.0988)
			(drill 3.0988)
			(layers "*.Cu" "*.Mask")
			(clearance 0.254)
			(thermal_gap 0.254)
		)
	)
	(footprint ""
		(layer "F.Cu")
		(at 76.437998 -402.371052 -90)
		(property "Reference" "C729"
			(at 0 0 270)
			(layer "F.SilkS")
			(hide yes)
			(effects
				(font
					(size 1.27 1.27)
				)
			)
		)
		(property "Value" ""
			(at 0 0 270)
			(layer "F.Fab")
			(effects
				(font
					(size 1.27 1.27)
				)
			)
		)
		(duplicate_pad_numbers_are_jumpers no)
		(fp_line
			(start -0.299974 0.150114)
			(end -0.299974 -0.150114)
			(stroke
				(width 0.1)
				(type default)
			)
			(layer "F.Fab")
		)
		(fp_line
			(start 0.299974 0.150114)
			(end -0.299974 0.150114)
			(stroke
				(width 0.1)
				(type default)
			)
			(layer "F.Fab")
		)
		(fp_line
			(start -0.299974 -0.150114)
			(end 0.299974 -0.150114)
			(stroke
				(width 0.1)
				(type default)
			)
			(layer "F.Fab")
		)
		(fp_line
			(start 0.299974 -0.150114)
			(end 0.299974 0.150114)
			(stroke
				(width 0.1)
				(type default)
			)
			(layer "F.Fab")
		)
		(pad "1" smd rect
			(at -0.2667 0 270)
			(size 0.3048 0.381)
			(layers "F.Cu" "F.Mask" "F.Paste")
			(net "P5E_CPU1_PE0_TX_C_DP<6>")
		)
		(pad "2" smd rect
			(at 0.2667 0 270)
			(size 0.3048 0.381)
			(layers "F.Cu" "F.Mask" "F.Paste")
			(net "P5E_CPU1_PE0_TX_DP<6>")
		)
	)
	(footprint ""
		(layer "F.Cu")
		(at 366.48263 -240.276888 90)
		(property "Reference" "C415"
			(at 0 0 90)
			(layer "F.SilkS")
			(hide yes)
			(effects
				(font
					(size 1.27 1.27)
				)
			)
		)
		(property "Value" ""
			(at 0 0 90)
			(layer "F.Fab")
			(effects
				(font
					(size 1.27 1.27)
				)
			)
		)
		(duplicate_pad_numbers_are_jumpers no)
		(fp_line
			(start 0.7874 -0.4064)
			(end 0.7874 0.4064)
			(stroke
				(width 0.1524)
				(type default)
			)
			(layer "F.SilkS")
		)
		(fp_line
			(start -0.7874 -0.4064)
			(end 0.7874 -0.4064)
			(stroke
				(width 0.1524)
				(type default)
			)
			(layer "F.SilkS")
		)
		(fp_line
			(start 0.7874 0.4064)
			(end -0.7874 0.4064)
			(stroke
				(width 0.1524)
				(type default)
			)
			(layer "F.SilkS")
		)
		(fp_line
			(start -0.7874 0.4064)
			(end -0.7874 -0.4064)
			(stroke
				(width 0.1524)
				(type default)
			)
			(layer "F.SilkS")
		)
		(fp_line
			(start -0.12065 -0.305054)
			(end -0.12065 -0.2794)
			(stroke
				(width 0.1)
				(type default)
			)
			(layer "F.Fab")
		)
		(fp_line
			(start -0.67945 -0.305054)
			(end -0.12065 -0.305054)
			(stroke
				(width 0.1)
				(type default)
			)
			(layer "F.Fab")
		)
		(fp_line
			(start 0.67945 -0.3048)
			(end 0.67945 0.3048)
			(stroke
				(width 0.1)
				(type default)
			)
			(layer "F.Fab")
		)
		(fp_line
			(start 0.12065 -0.3048)
			(end 0.67945 -0.3048)
			(stroke
				(width 0.1)
				(type default)
			)
			(layer "F.Fab")
		)
		(fp_line
			(start 0.12065 -0.2794)
			(end 0.12065 -0.3048)
			(stroke
				(width 0.1)
				(type default)
			)
			(layer "F.Fab")
		)
		(fp_line
			(start -0.12065 -0.2794)
			(end 0.12065 -0.2794)
			(stroke
				(width 0.1)
				(type default)
			)
			(layer "F.Fab")
		)
		(fp_line
			(start 0.120396 0.2794)
			(end -0.12065 0.2794)
			(stroke
				(width 0.1)
				(type default)
			)
			(layer "F.Fab")
		)
		(fp_line
			(start -0.12065 0.2794)
			(end -0.12065 0.3048)
			(stroke
				(width 0.1)
				(type default)
			)
			(layer "F.Fab")
		)
		(fp_line
			(start 0.67945 0.3048)
			(end 0.120396 0.3048)
			(stroke
				(width 0.1)
				(type default)
			)
			(layer "F.Fab")
		)
		(fp_line
			(start 0.120396 0.3048)
			(end 0.120396 0.2794)
			(stroke
				(width 0.1)
				(type default)
			)
			(layer "F.Fab")
		)
		(fp_line
			(start -0.12065 0.3048)
			(end -0.67945 0.3048)
			(stroke
				(width 0.1)
				(type default)
			)
			(layer "F.Fab")
		)
		(fp_line
			(start -0.67945 0.3048)
			(end -0.67945 -0.305054)
			(stroke
				(width 0.1)
				(type default)
			)
			(layer "F.Fab")
		)
		(pad "1" smd circle
			(at -0.40005 0 90)
			(size 0 0)
			(layers "F.Cu" "F.Mask" "F.Paste")
			(net "PVCCFA_EHV_FIVRA_CPU0")
		)
		(pad "2" smd circle
			(at 0.40005 0 90)
			(size 0 0)
			(layers "F.Cu" "F.Mask" "F.Paste")
			(net "GND")
		)
	)
	(footprint ""
		(layer "F.Cu")
		(at 105.696004 -393.711684 180)
		(property "Reference" "U255"
			(at 1.799844 -3.027426 0)
			(unlocked yes)
			(layer "F.SilkS")
			(effects
				(font
					(size 0.7874 0.5842)
					(thickness 0.1524)
				)
				(justify left)
			)
		)
		(property "Value" ""
			(at 0 0 180)
			(layer "F.Fab")
			(effects
				(font
					(size 1.27 1.27)
				)
			)
		)
		(duplicate_pad_numbers_are_jumpers no)
		(fp_line
			(start 1.38176 1.100074)
			(end 1.38176 -1.100074)
			(stroke
				(width 0.1524)
				(type default)
			)
			(layer "F.SilkS")
		)
		(fp_line
			(start 1.38176 -1.100074)
			(end 0.592074 -1.100074)
			(stroke
				(width 0.1524)
				(type default)
			)
			(layer "F.SilkS")
		)
		(fp_line
			(start 0.456184 1.100074)
			(end 1.38176 1.100074)
			(stroke
				(width 0.1524)
				(type default)
			)
			(layer "F.SilkS")
		)
		(fp_line
			(start -0.592074 -1.100074)
			(end -1.38176 -1.100074)
			(stroke
				(width 0.1524)
				(type default)
			)
			(layer "F.SilkS")
		)
		(fp_line
			(start -1.38176 1.100074)
			(end -0.305816 1.100074)
			(stroke
				(width 0.1524)
				(type default)
			)
			(layer "F.SilkS")
		)
		(fp_line
			(start -1.38176 -1.100074)
			(end -1.38176 1.100074)
			(stroke
				(width 0.1524)
				(type default)
			)
			(layer "F.SilkS")
		)
		(fp_poly
			(pts
				(xy -1.260856 -1.255014) (xy -1.728216 -1.410716) (xy -1.416812 -1.722374)
			)
			(stroke
				(width 0)
				(type default)
			)
			(fill yes)
			(layer "F.SilkS")
		)
		(fp_line
			(start 0.674878 1.100074)
			(end 0.674878 -1.100074)
			(stroke
				(width 0.1)
				(type default)
			)
			(layer "F.Fab")
		)
		(fp_line
			(start 0.674878 -1.100074)
			(end -0.674878 -1.100074)
			(stroke
				(width 0.1)
				(type default)
			)
			(layer "F.Fab")
		)
		(fp_line
			(start -0.674878 1.100074)
			(end 0.674878 1.100074)
			(stroke
				(width 0.1)
				(type default)
			)
			(layer "F.Fab")
		)
		(fp_line
			(start -0.674878 -1.100074)
			(end -0.674878 1.100074)
			(stroke
				(width 0.1)
				(type default)
			)
			(layer "F.Fab")
		)
		(fp_poly
			(pts
				(xy -1.9431 -0.870204) (xy -1.50241 -0.649986) (xy -1.9431 -0.429768)
			)
			(stroke
				(width 0)
				(type default)
			)
			(fill yes)
			(layer "F.Fab")
		)
		(pad "1" smd rect
			(at -0.94996 -0.649986 90)
			(size 0.4318 0.6096)
			(layers "F.Cu" "F.Mask" "F.Paste")
			(net "GPU_NVS_PWR_BRAKE_N")
		)
		(pad "2" smd rect
			(at -0.94996 0 90)
			(size 0.4318 0.6096)
			(layers "F.Cu" "F.Mask" "F.Paste")
			(net "GND")
		)
		(pad "3" smd rect
			(at -0.94996 0.649986 90)
			(size 0.4318 0.6096)
			(layers "F.Cu" "F.Mask" "F.Paste")
			(net "GPU_FPGA_EROT_RST_N")
		)
		(pad "4" smd rect
			(at 0.94996 0.649986 90)
			(size 0.4318 0.6096)
			(layers "F.Cu" "F.Mask" "F.Paste")
			(net "GPU_FPGA_EROT_RST_BUF_R_N")
		)
		(pad "5" smd rect
			(at 0.94996 0 90)
			(size 0.4318 0.6096)
			(layers "F.Cu" "F.Mask" "F.Paste")
			(net "P3V3_AUX")
		)
		(pad "6" smd rect
			(at 0.94996 -0.649986 90)
			(size 0.4318 0.6096)
			(layers "F.Cu" "F.Mask" "F.Paste")
			(net "GPU_NVS_PWR_BRAKE_N_R")
		)
	)
	(footprint ""
		(layer "F.Cu")
		(at 506.259338 -427.45025 180)
		(property "Reference" "DB3"
			(at -2.693924 -0.263398 90)
			(unlocked yes)
			(layer "F.SilkS")
			(effects
				(font
					(size 0.7874 0.5842)
					(thickness 0.1524)
				)
				(justify left)
			)
		)
		(property "Value" ""
			(at 0 0 180)
			(layer "F.Fab")
			(effects
				(font
					(size 1.27 1.27)
				)
			)
		)
		(duplicate_pad_numbers_are_jumpers no)
		(fp_line
			(start 3.330702 -4.771136)
			(end 0 4.011168)
			(stroke
				(width 0.1524)
				(type default)
			)
			(layer "F.SilkS")
		)
		(fp_line
			(start 0 4.011168)
			(end -3.330702 -4.771136)
			(stroke
				(width 0.1524)
				(type default)
			)
			(layer "F.SilkS")
		)
		(fp_line
			(start -3.330702 -4.771136)
			(end 3.330702 -4.771136)
			(stroke
				(width 0.1524)
				(type default)
			)
			(layer "F.SilkS")
		)
		(fp_line
			(start 3.330702 -4.771136)
			(end 0 4.011168)
			(stroke
				(width 0.1)
				(type default)
			)
			(layer "F.Fab")
		)
		(fp_line
			(start 0 4.011168)
			(end -3.330702 -4.771136)
			(stroke
				(width 0.1)
				(type default)
			)
			(layer "F.Fab")
		)
		(fp_line
			(start -3.330702 -4.771136)
			(end 3.330702 -4.771136)
			(stroke
				(width 0.1)
				(type default)
			)
			(layer "F.Fab")
		)
		(pad "1" thru_hole circle
			(at 0 0 180)
			(size 2.159 2.159)
			(drill 1.7018)
			(layers "*.Cu" "*.Mask")
			(remove_unused_layers no)
			(net "T1_GND")
			(clearance 0.0254)
			(thermal_gap 0.0254)
		)
		(pad "2" thru_hole circle
			(at -1.27 -3.348736 180)
			(size 2.159 2.159)
			(drill 1.7018)
			(layers "*.Cu" "*.Mask")
			(remove_unused_layers no)
			(net "TDR_SE_40_OHM_IN2")
			(clearance 0.0254)
			(thermal_gap 0.0254)
		)
		(pad "3" thru_hole circle
			(at 1.27 -3.348736 180)
			(size 2.159 2.159)
			(drill 1.7018)
			(layers "*.Cu" "*.Mask")
			(remove_unused_layers no)
			(net "TDR_SE_40_OHM_IN2")
			(clearance 0.0254)
			(thermal_gap 0.0254)
		)
	)
	(footprint ""
		(layer "F.Cu")
		(at 50.43551 -157.172914 180)
		(property "Reference" "PR1794"
			(at 0 0 180)
			(layer "F.SilkS")
			(hide yes)
			(effects
				(font
					(size 1.27 1.27)
				)
			)
		)
		(property "Value" ""
			(at 0 0 180)
			(layer "F.Fab")
			(effects
				(font
					(size 1.27 1.27)
				)
			)
		)
		(duplicate_pad_numbers_are_jumpers no)
		(fp_line
			(start 0.7874 0.4064)
			(end -0.7874 0.4064)
			(stroke
				(width 0.1524)
				(type default)
			)
			(layer "F.SilkS")
		)
		(fp_line
			(start 0.7874 -0.4064)
			(end 0.7874 0.4064)
			(stroke
				(width 0.1524)
				(type default)
			)
			(layer "F.SilkS")
		)
		(fp_line
			(start -0.7874 0.4064)
			(end -0.7874 -0.4064)
			(stroke
				(width 0.1524)
				(type default)
			)
			(layer "F.SilkS")
		)
		(fp_line
			(start -0.7874 -0.4064)
			(end 0.7874 -0.4064)
			(stroke
				(width 0.1524)
				(type default)
			)
			(layer "F.SilkS")
		)
		(fp_line
			(start 0.67945 0.3048)
			(end 0.120396 0.3048)
			(stroke
				(width 0.1)
				(type default)
			)
			(layer "F.Fab")
		)
		(fp_line
			(start 0.67945 -0.3048)
			(end 0.67945 0.3048)
			(stroke
				(width 0.1)
				(type default)
			)
			(layer "F.Fab")
		)
		(fp_line
			(start 0.12065 -0.2794)
			(end 0.12065 -0.3048)
			(stroke
				(width 0.1)
				(type default)
			)
			(layer "F.Fab")
		)
		(fp_line
			(start 0.12065 -0.3048)
			(end 0.67945 -0.3048)
			(stroke
				(width 0.1)
				(type default)
			)
			(layer "F.Fab")
		)
		(fp_line
			(start 0.120396 0.3048)
			(end 0.120396 0.2794)
			(stroke
				(width 0.1)
				(type default)
			)
			(layer "F.Fab")
		)
		(fp_line
			(start 0.120396 0.2794)
			(end -0.12065 0.2794)
			(stroke
				(width 0.1)
				(type default)
			)
			(layer "F.Fab")
		)
		(fp_line
			(start -0.12065 0.3048)
			(end -0.67945 0.3048)
			(stroke
				(width 0.1)
				(type default)
			)
			(layer "F.Fab")
		)
		(fp_line
			(start -0.12065 0.2794)
			(end -0.12065 0.3048)
			(stroke
				(width 0.1)
				(type default)
			)
			(layer "F.Fab")
		)
		(fp_line
			(start -0.12065 -0.2794)
			(end 0.12065 -0.2794)
			(stroke
				(width 0.1)
				(type default)
			)
			(layer "F.Fab")
		)
		(fp_line
			(start -0.12065 -0.305054)
			(end -0.12065 -0.2794)
			(stroke
				(width 0.1)
				(type default)
			)
			(layer "F.Fab")
		)
		(fp_line
			(start -0.67945 0.3048)
			(end -0.67945 -0.305054)
			(stroke
				(width 0.1)
				(type default)
			)
			(layer "F.Fab")
		)
		(fp_line
			(start -0.67945 -0.305054)
			(end -0.12065 -0.305054)
			(stroke
				(width 0.1)
				(type default)
			)
			(layer "F.Fab")
		)
		(pad "1" smd circle
			(at -0.40005 0 180)
			(size 0 0)
			(layers "F.Cu" "F.Mask" "F.Paste")
			(net "SW_PVCCINFAON_CPU1_BOOT1")
		)
		(pad "2" smd circle
			(at 0.40005 0 180)
			(size 0 0)
			(layers "F.Cu" "F.Mask" "F.Paste")
			(net "SW_PVCCINFAON_CPU1_BOOT1_R")
		)
	)
	(footprint ""
		(layer "F.Cu")
		(at 368.7318 -74.3458 -90)
		(property "Reference" "R4704"
			(at 0 0 270)
			(layer "F.SilkS")
			(hide yes)
			(effects
				(font
					(size 1.27 1.27)
				)
			)
		)
		(property "Value" ""
			(at 0 0 270)
			(layer "F.Fab")
			(effects
				(font
					(size 1.27 1.27)
				)
			)
		)
		(duplicate_pad_numbers_are_jumpers no)
		(fp_line
			(start -0.7874 0.4064)
			(end -0.7874 -0.4064)
			(stroke
				(width 0.1524)
				(type default)
			)
			(layer "F.SilkS")
		)
		(fp_line
			(start 0.7874 0.4064)
			(end -0.7874 0.4064)
			(stroke
				(width 0.1524)
				(type default)
			)
			(layer "F.SilkS")
		)
		(fp_line
			(start -0.7874 -0.4064)
			(end 0.7874 -0.4064)
			(stroke
				(width 0.1524)
				(type default)
			)
			(layer "F.SilkS")
		)
		(fp_line
			(start 0.7874 -0.4064)
			(end 0.7874 0.4064)
			(stroke
				(width 0.1524)
				(type default)
			)
			(layer "F.SilkS")
		)
		(fp_line
			(start -0.67945 0.3048)
			(end -0.67945 -0.305054)
			(stroke
				(width 0.1)
				(type default)
			)
			(layer "F.Fab")
		)
		(fp_line
			(start -0.12065 0.3048)
			(end -0.67945 0.3048)
			(stroke
				(width 0.1)
				(type default)
			)
			(layer "F.Fab")
		)
		(fp_line
			(start 0.120396 0.3048)
			(end 0.120396 0.2794)
			(stroke
				(width 0.1)
				(type default)
			)
			(layer "F.Fab")
		)
		(fp_line
			(start 0.67945 0.3048)
			(end 0.120396 0.3048)
			(stroke
				(width 0.1)
				(type default)
			)
			(layer "F.Fab")
		)
		(fp_line
			(start -0.12065 0.2794)
			(end -0.12065 0.3048)
			(stroke
				(width 0.1)
				(type default)
			)
			(layer "F.Fab")
		)
		(fp_line
			(start 0.120396 0.2794)
			(end -0.12065 0.2794)
			(stroke
				(width 0.1)
				(type default)
			)
			(layer "F.Fab")
		)
		(fp_line
			(start -0.12065 -0.2794)
			(end 0.12065 -0.2794)
			(stroke
				(width 0.1)
				(type default)
			)
			(layer "F.Fab")
		)
		(fp_line
			(start 0.12065 -0.2794)
			(end 0.12065 -0.3048)
			(stroke
				(width 0.1)
				(type default)
			)
			(layer "F.Fab")
		)
		(fp_line
			(start 0.12065 -0.3048)
			(end 0.67945 -0.3048)
			(stroke
				(width 0.1)
				(type default)
			)
			(layer "F.Fab")
		)
		(fp_line
			(start 0.67945 -0.3048)
			(end 0.67945 0.3048)
			(stroke
				(width 0.1)
				(type default)
			)
			(layer "F.Fab")
		)
		(fp_line
			(start -0.67945 -0.305054)
			(end -0.12065 -0.305054)
			(stroke
				(width 0.1)
				(type default)
			)
			(layer "F.Fab")
		)
		(fp_line
			(start -0.12065 -0.305054)
			(end -0.12065 -0.2794)
			(stroke
				(width 0.1)
				(type default)
			)
			(layer "F.Fab")
		)
		(pad "1" smd circle
			(at -0.40005 0 270)
			(size 0 0)
			(layers "F.Cu" "F.Mask" "F.Paste")
			(net "LED_P12V_AUX_R2")
		)
		(pad "2" smd circle
			(at 0.40005 0 270)
			(size 0 0)
			(layers "F.Cu" "F.Mask" "F.Paste")
			(net "LED_P12V_AUX_R3")
		)
	)
	(footprint ""
		(layer "F.Cu")
		(at 155.98013 -70.26402 90)
		(property "Reference" "R2310"
			(at 0 0 90)
			(layer "F.SilkS")
			(hide yes)
			(effects
				(font
					(size 1.27 1.27)
				)
			)
		)
		(property "Value" ""
			(at 0 0 90)
			(layer "F.Fab")
			(effects
				(font
					(size 1.27 1.27)
				)
			)
		)
		(duplicate_pad_numbers_are_jumpers no)
		(fp_line
			(start 0.7874 -0.4064)
			(end 0.7874 0.4064)
			(stroke
				(width 0.1524)
				(type default)
			)
			(layer "F.SilkS")
		)
		(fp_line
			(start -0.7874 -0.4064)
			(end 0.7874 -0.4064)
			(stroke
				(width 0.1524)
				(type default)
			)
			(layer "F.SilkS")
		)
		(fp_line
			(start 0.7874 0.4064)
			(end -0.7874 0.4064)
			(stroke
				(width 0.1524)
				(type default)
			)
			(layer "F.SilkS")
		)
		(fp_line
			(start -0.7874 0.4064)
			(end -0.7874 -0.4064)
			(stroke
				(width 0.1524)
				(type default)
			)
			(layer "F.SilkS")
		)
		(fp_line
			(start -0.12065 -0.305054)
			(end -0.12065 -0.2794)
			(stroke
				(width 0.1)
				(type default)
			)
			(layer "F.Fab")
		)
		(fp_line
			(start -0.67945 -0.305054)
			(end -0.12065 -0.305054)
			(stroke
				(width 0.1)
				(type default)
			)
			(layer "F.Fab")
		)
		(fp_line
			(start 0.67945 -0.3048)
			(end 0.67945 0.3048)
			(stroke
				(width 0.1)
				(type default)
			)
			(layer "F.Fab")
		)
		(fp_line
			(start 0.12065 -0.3048)
			(end 0.67945 -0.3048)
			(stroke
				(width 0.1)
				(type default)
			)
			(layer "F.Fab")
		)
		(fp_line
			(start 0.12065 -0.2794)
			(end 0.12065 -0.3048)
			(stroke
				(width 0.1)
				(type default)
			)
			(layer "F.Fab")
		)
		(fp_line
			(start -0.12065 -0.2794)
			(end 0.12065 -0.2794)
			(stroke
				(width 0.1)
				(type default)
			)
			(layer "F.Fab")
		)
		(fp_line
			(start 0.120396 0.2794)
			(end -0.12065 0.2794)
			(stroke
				(width 0.1)
				(type default)
			)
			(layer "F.Fab")
		)
		(fp_line
			(start -0.12065 0.2794)
			(end -0.12065 0.3048)
			(stroke
				(width 0.1)
				(type default)
			)
			(layer "F.Fab")
		)
		(fp_line
			(start 0.67945 0.3048)
			(end 0.120396 0.3048)
			(stroke
				(width 0.1)
				(type default)
			)
			(layer "F.Fab")
		)
		(fp_line
			(start 0.120396 0.3048)
			(end 0.120396 0.2794)
			(stroke
				(width 0.1)
				(type default)
			)
			(layer "F.Fab")
		)
		(fp_line
			(start -0.12065 0.3048)
			(end -0.67945 0.3048)
			(stroke
				(width 0.1)
				(type default)
			)
			(layer "F.Fab")
		)
		(fp_line
			(start -0.67945 0.3048)
			(end -0.67945 -0.305054)
			(stroke
				(width 0.1)
				(type default)
			)
			(layer "F.Fab")
		)
		(pad "1" smd circle
			(at -0.40005 0 90)
			(size 0 0)
			(layers "F.Cu" "F.Mask" "F.Paste")
			(net "P3V3_AUX")
		)
		(pad "2" smd circle
			(at 0.40005 0 90)
			(size 0 0)
			(layers "F.Cu" "F.Mask" "F.Paste")
			(net "PCA9543_S3M_ADDR0")
		)
	)
	(footprint ""
		(layer "F.Cu")
		(at 68.081144 -106.319066)
		(property "Reference" "R3732"
			(at 0 0 0)
			(layer "F.SilkS")
			(hide yes)
			(effects
				(font
					(size 1.27 1.27)
				)
			)
		)
		(property "Value" ""
			(at 0 0 0)
			(layer "F.Fab")
			(effects
				(font
					(size 1.27 1.27)
				)
			)
		)
		(duplicate_pad_numbers_are_jumpers no)
		(fp_line
			(start -0.7874 -0.4064)
			(end 0.7874 -0.4064)
			(stroke
				(width 0.1524)
				(type default)
			)
			(layer "F.SilkS")
		)
		(fp_line
			(start -0.7874 0.4064)
			(end -0.7874 -0.4064)
			(stroke
				(width 0.1524)
				(type default)
			)
			(layer "F.SilkS")
		)
		(fp_line
			(start 0.7874 -0.4064)
			(end 0.7874 0.4064)
			(stroke
				(width 0.1524)
				(type default)
			)
			(layer "F.SilkS")
		)
		(fp_line
			(start 0.7874 0.4064)
			(end -0.7874 0.4064)
			(stroke
				(width 0.1524)
				(type default)
			)
			(layer "F.SilkS")
		)
		(fp_line
			(start -0.67945 -0.305054)
			(end -0.12065 -0.305054)
			(stroke
				(width 0.1)
				(type default)
			)
			(layer "F.Fab")
		)
		(fp_line
			(start -0.67945 0.3048)
			(end -0.67945 -0.305054)
			(stroke
				(width 0.1)
				(type default)
			)
			(layer "F.Fab")
		)
		(fp_line
			(start -0.12065 -0.305054)
			(end -0.12065 -0.2794)
			(stroke
				(width 0.1)
				(type default)
			)
			(layer "F.Fab")
		)
		(fp_line
			(start -0.12065 -0.2794)
			(end 0.12065 -0.2794)
			(stroke
				(width 0.1)
				(type default)
			)
			(layer "F.Fab")
		)
		(fp_line
			(start -0.12065 0.2794)
			(end -0.12065 0.3048)
			(stroke
				(width 0.1)
				(type default)
			)
			(layer "F.Fab")
		)
		(fp_line
			(start -0.12065 0.3048)
			(end -0.67945 0.3048)
			(stroke
				(width 0.1)
				(type default)
			)
			(layer "F.Fab")
		)
		(fp_line
			(start 0.120396 0.2794)
			(end -0.12065 0.2794)
			(stroke
				(width 0.1)
				(type default)
			)
			(layer "F.Fab")
		)
		(fp_line
			(start 0.120396 0.3048)
			(end 0.120396 0.2794)
			(stroke
				(width 0.1)
				(type default)
			)
			(layer "F.Fab")
		)
		(fp_line
			(start 0.12065 -0.3048)
			(end 0.67945 -0.3048)
			(stroke
				(width 0.1)
				(type default)
			)
			(layer "F.Fab")
		)
		(fp_line
			(start 0.12065 -0.2794)
			(end 0.12065 -0.3048)
			(stroke
				(width 0.1)
				(type default)
			)
			(layer "F.Fab")
		)
		(fp_line
			(start 0.67945 -0.3048)
			(end 0.67945 0.3048)
			(stroke
				(width 0.1)
				(type default)
			)
			(layer "F.Fab")
		)
		(fp_line
			(start 0.67945 0.3048)
			(end 0.120396 0.3048)
			(stroke
				(width 0.1)
				(type default)
			)
			(layer "F.Fab")
		)
		(pad "1" smd circle
			(at -0.40005 0)
			(size 0 0)
			(layers "F.Cu" "F.Mask" "F.Paste")
			(net "P3V3_AUX")
		)
		(pad "2" smd circle
			(at 0.40005 0)
			(size 0 0)
			(layers "F.Cu" "F.Mask" "F.Paste")
			(net "SMB_LM75_3_3V3AUX_SDA")
		)
	)
	(footprint ""
		(layer "F.Cu")
		(at 142.750032 -440.489848)
		(property "Reference" "J109"
			(at 1.4859 23.131272 0)
			(unlocked yes)
			(layer "F.SilkS")
			(effects
				(font
					(size 0.7874 0.5842)
					(thickness 0.1524)
				)
				(justify left)
			)
		)
		(property "Value" ""
			(at 0 0 0)
			(layer "F.Fab")
			(effects
				(font
					(size 1.27 1.27)
				)
			)
		)
		(duplicate_pad_numbers_are_jumpers no)
		(fp_line
			(start -4.249928 -11.999976)
			(end 18.64995 -11.999976)
			(stroke
				(width 0.1524)
				(type default)
			)
			(layer "F.SilkS")
		)
		(fp_line
			(start -4.249928 22.400006)
			(end -4.249928 -11.999976)
			(stroke
				(width 0.1524)
				(type default)
			)
			(layer "F.SilkS")
		)
		(fp_line
			(start -1.249934 -8.999982)
			(end -1.249934 19.400012)
			(stroke
				(width 0.1524)
				(type default)
			)
			(layer "F.SilkS")
		)
		(fp_line
			(start -1.249934 -1.500124)
			(end 15.649956 -1.500124)
			(stroke
				(width 0.1524)
				(type default)
			)
			(layer "F.SilkS")
		)
		(fp_line
			(start -1.249934 19.400012)
			(end 15.649956 19.400012)
			(stroke
				(width 0.1524)
				(type default)
			)
			(layer "F.SilkS")
		)
		(fp_line
			(start 0.0254 -0.9144)
			(end 1.0414 -0.9144)
			(stroke
				(width 0.1524)
				(type default)
			)
			(layer "F.SilkS")
		)
		(fp_line
			(start 0.5334 -1.4224)
			(end 0.0254 -0.9144)
			(stroke
				(width 0.1524)
				(type default)
			)
			(layer "F.SilkS")
		)
		(fp_line
			(start 0.5334 -1.4224)
			(end 0.5334 -0.5588)
			(stroke
				(width 0.1524)
				(type default)
			)
			(layer "F.SilkS")
		)
		(fp_line
			(start 0.5334 -0.5588)
			(end 1.8034 -0.5588)
			(stroke
				(width 0.1524)
				(type default)
			)
			(layer "F.SilkS")
		)
		(fp_line
			(start 1.0414 -0.9144)
			(end 0.5334 -1.4224)
			(stroke
				(width 0.1524)
				(type default)
			)
			(layer "F.SilkS")
		)
		(fp_line
			(start 1.8034 -0.5588)
			(end 2.032 -0.7874)
			(stroke
				(width 0.1524)
				(type default)
			)
			(layer "F.SilkS")
		)
		(fp_line
			(start 15.649956 -8.999982)
			(end -1.249934 -8.999982)
			(stroke
				(width 0.1524)
				(type default)
			)
			(layer "F.SilkS")
		)
		(fp_line
			(start 15.649956 19.400012)
			(end 15.649956 -8.999982)
			(stroke
				(width 0.1524)
				(type default)
			)
			(layer "F.SilkS")
		)
		(fp_line
			(start 18.64995 -11.999976)
			(end 18.64995 22.400006)
			(stroke
				(width 0.1524)
				(type default)
			)
			(layer "F.SilkS")
		)
		(fp_line
			(start 18.64995 22.400006)
			(end -4.249928 22.400006)
			(stroke
				(width 0.1524)
				(type default)
			)
			(layer "F.SilkS")
		)
		(fp_poly
			(pts
				(xy -1.539748 0.11684) (xy -2.249932 0.471932) (xy -2.249932 -0.238252)
			)
			(stroke
				(width 0)
				(type default)
			)
			(fill yes)
			(layer "F.SilkS")
		)
		(fp_line
			(start -4.249928 -11.999976)
			(end 18.64995 -11.999976)
			(stroke
				(width 0.1524)
				(type default)
			)
			(layer "B.SilkS")
		)
		(fp_line
			(start -4.249928 22.400006)
			(end -4.249928 -11.999976)
			(stroke
				(width 0.1524)
				(type default)
			)
			(layer "B.SilkS")
		)
		(fp_line
			(start 18.64995 -11.999976)
			(end 18.64995 5.240528)
			(stroke
				(width 0.1524)
				(type default)
			)
			(layer "B.SilkS")
		)
		(fp_line
			(start 18.64995 6.617208)
			(end 18.64995 16.096488)
			(stroke
				(width 0.1524)
				(type default)
			)
			(layer "B.SilkS")
		)
		(fp_line
			(start 18.64995 18.654268)
			(end 18.64995 22.400006)
			(stroke
				(width 0.1524)
				(type default)
			)
			(layer "B.SilkS")
		)
		(fp_line
			(start 18.64995 22.400006)
			(end -4.249928 22.400006)
			(stroke
				(width 0.1524)
				(type default)
			)
			(layer "B.SilkS")
		)
		(fp_line
			(start -4.249928 -11.999976)
			(end 18.64995 -11.999976)
			(stroke
				(width 0.1)
				(type default)
			)
			(layer "B.Fab")
		)
		(fp_line
			(start -4.249928 22.400006)
			(end -4.249928 -11.999976)
			(stroke
				(width 0.1)
				(type default)
			)
			(layer "B.Fab")
		)
		(fp_line
			(start 18.64995 -11.999976)
			(end 18.64995 22.400006)
			(stroke
				(width 0.1)
				(type default)
			)
			(layer "B.Fab")
		)
		(fp_line
			(start 18.64995 22.400006)
			(end -4.249928 22.400006)
			(stroke
				(width 0.1)
				(type default)
			)
			(layer "B.Fab")
		)
		(fp_line
			(start -1.249934 -8.999982)
			(end -1.249934 19.400012)
			(stroke
				(width 0.1)
				(type default)
			)
			(layer "F.Fab")
		)
		(fp_line
			(start -1.249934 19.400012)
			(end 15.649956 19.400012)
			(stroke
				(width 0.1)
				(type default)
			)
			(layer "F.Fab")
		)
		(fp_line
			(start 15.649956 -8.999982)
			(end -1.249934 -8.999982)
			(stroke
				(width 0.1)
				(type default)
			)
			(layer "F.Fab")
		)
		(fp_line
			(start 15.649956 19.400012)
			(end 15.649956 -8.999982)
			(stroke
				(width 0.1)
				(type default)
			)
			(layer "F.Fab")
		)
		(fp_poly
			(pts
				(xy -2.670048 -0.508) (xy -2.670048 0.508) (xy -1.654048 0)
			)
			(stroke
				(width 0)
				(type default)
			)
			(fill yes)
			(layer "F.Fab")
		)
		(fp_text user "B"
			(at -1.835912 1.472946 0)
			(unlocked yes)
			(layer "F.SilkS")
			(effects
				(font
					(size 0.7874 0.5842)
					(thickness 0.1524)
				)
			)
		)
		(fp_text user "C"
			(at -1.835912 2.673096 0)
			(unlocked yes)
			(layer "F.SilkS")
			(effects
				(font
					(size 0.7874 0.5842)
					(thickness 0.1524)
				)
			)
		)
		(fp_text user "D"
			(at -1.835912 3.872992 0)
			(unlocked yes)
			(layer "F.SilkS")
			(effects
				(font
					(size 0.7874 0.5842)
					(thickness 0.1524)
				)
			)
		)
		(fp_text user "E"
			(at -1.835912 5.073142 0)
			(unlocked yes)
			(layer "F.SilkS")
			(effects
				(font
					(size 0.7874 0.5842)
					(thickness 0.1524)
				)
			)
		)
		(fp_text user "F"
			(at -1.835912 6.273038 0)
			(unlocked yes)
			(layer "F.SilkS")
			(effects
				(font
					(size 0.7874 0.5842)
					(thickness 0.1524)
				)
			)
		)
		(fp_text user "G"
			(at -1.835912 7.472934 0)
			(unlocked yes)
			(layer "F.SilkS")
			(effects
				(font
					(size 0.7874 0.5842)
					(thickness 0.1524)
				)
			)
		)
		(fp_text user "H"
			(at -1.835912 8.673084 0)
			(unlocked yes)
			(layer "F.SilkS")
			(effects
				(font
					(size 0.7874 0.5842)
					(thickness 0.1524)
				)
			)
		)
		(fp_text user "I"
			(at -1.835912 9.87298 0)
			(unlocked yes)
			(layer "F.SilkS")
			(effects
				(font
					(size 0.7874 0.5842)
					(thickness 0.1524)
				)
			)
		)
		(fp_text user "J"
			(at -1.835912 11.07313 0)
			(unlocked yes)
			(layer "F.SilkS")
			(effects
				(font
					(size 0.7874 0.5842)
					(thickness 0.1524)
				)
			)
		)
		(fp_text user "K"
			(at -1.835912 12.273026 0)
			(unlocked yes)
			(layer "F.SilkS")
			(effects
				(font
					(size 0.7874 0.5842)
					(thickness 0.1524)
				)
			)
		)
		(fp_text user "L"
			(at -1.835912 13.473176 0)
			(unlocked yes)
			(layer "F.SilkS")
			(effects
				(font
					(size 0.7874 0.5842)
					(thickness 0.1524)
				)
			)
		)
		(fp_text user "M"
			(at -1.835912 14.673072 0)
			(unlocked yes)
			(layer "F.SilkS")
			(effects
				(font
					(size 0.7874 0.5842)
					(thickness 0.1524)
				)
			)
		)
		(fp_text user "N"
			(at -1.835912 15.872968 0)
			(unlocked yes)
			(layer "F.SilkS")
			(effects
				(font
					(size 0.7874 0.5842)
					(thickness 0.1524)
				)
			)
		)
		(fp_text user "1"
			(at 0.224028 20.12569 0)
			(unlocked yes)
			(layer "F.SilkS")
			(effects
				(font
					(size 0.7874 0.5842)
					(thickness 0.1524)
				)
			)
		)
		(fp_text user "2"
			(at 2.215388 20.06219 0)
			(unlocked yes)
			(layer "F.SilkS")
			(effects
				(font
					(size 0.7874 0.5842)
					(thickness 0.1524)
				)
			)
		)
		(fp_text user "EDGE OF DAUGHTER CARD"
			(at 2.2479 -0.899668 0)
			(unlocked yes)
			(layer "F.SilkS")
			(effects
				(font
					(size 0.635 0.4064)
					(thickness 0.1524)
				)
				(justify left)
			)
		)
		(fp_text user "3"
			(at 3.625088 20.08251 0)
			(unlocked yes)
			(layer "F.SilkS")
			(effects
				(font
					(size 0.7874 0.5842)
					(thickness 0.1524)
				)
			)
		)
		(fp_text user "4"
			(at 5.11683 20.09013 0)
			(unlocked yes)
			(layer "F.SilkS")
			(effects
				(font
					(size 0.7874 0.5842)
					(thickness 0.1524)
				)
			)
		)
		(fp_text user "5"
			(at 7.116826 20.09013 0)
			(unlocked yes)
			(layer "F.SilkS")
			(effects
				(font
					(size 0.7874 0.5842)
					(thickness 0.1524)
				)
			)
		)
		(fp_text user "6"
			(at 9.116822 20.09013 0)
			(unlocked yes)
			(layer "F.SilkS")
			(effects
				(font
					(size 0.7874 0.5842)
					(thickness 0.1524)
				)
			)
		)
		(fp_text user "7"
			(at 11.116818 20.09013 0)
			(unlocked yes)
			(layer "F.SilkS")
			(effects
				(font
					(size 0.7874 0.5842)
					(thickness 0.1524)
				)
			)
		)
		(fp_text user "8"
			(at 13.116814 20.09013 0)
			(unlocked yes)
			(layer "F.SilkS")
			(effects
				(font
					(size 0.7874 0.5842)
					(thickness 0.1524)
				)
			)
		)
		(fp_text user "PRESS-FIT"
			(at 17.240758 16.521684 90)
			(unlocked yes)
			(layer "F.SilkS")
			(effects
				(font
					(size 1.905 1.4224)
					(thickness 0.1524)
				)
				(justify left)
			)
		)
		(fp_text user "A"
			(at -1.225804 0.10287 0)
			(unlocked yes)
			(layer "B.SilkS")
			(effects
				(font
					(size 0.7874 0.5842)
					(thickness 0.1524)
				)
				(justify mirror)
			)
		)
		(fp_text user "G"
			(at -1.200404 7.51967 0)
			(unlocked yes)
			(layer "B.SilkS")
			(effects
				(font
					(size 0.7874 0.5842)
					(thickness 0.1524)
				)
				(justify mirror)
			)
		)
		(fp_text user "H"
			(at -1.175004 8.73887 0)
			(unlocked yes)
			(layer "B.SilkS")
			(effects
				(font
					(size 0.7874 0.5842)
					(thickness 0.1524)
				)
				(justify mirror)
			)
		)
		(fp_text user "B"
			(at -1.17348 1.429766 0)
			(unlocked yes)
			(layer "B.SilkS")
			(effects
				(font
					(size 0.7874 0.5842)
					(thickness 0.1524)
				)
				(justify mirror)
			)
		)
		(fp_text user "C"
			(at -1.17348 2.629916 0)
			(unlocked yes)
			(layer "B.SilkS")
			(effects
				(font
					(size 0.7874 0.5842)
					(thickness 0.1524)
				)
				(justify mirror)
			)
		)
		(fp_text user "D"
			(at -1.17348 3.829812 0)
			(unlocked yes)
			(layer "B.SilkS")
			(effects
				(font
					(size 0.7874 0.5842)
					(thickness 0.1524)
				)
				(justify mirror)
			)
		)
		(fp_text user "E"
			(at -1.17348 5.029962 0)
			(unlocked yes)
			(layer "B.SilkS")
			(effects
				(font
					(size 0.7874 0.5842)
					(thickness 0.1524)
				)
				(justify mirror)
			)
		)
		(fp_text user "F"
			(at -1.17348 6.229858 0)
			(unlocked yes)
			(layer "B.SilkS")
			(effects
				(font
					(size 0.7874 0.5842)
					(thickness 0.1524)
				)
				(justify mirror)
			)
		)
		(fp_text user "I"
			(at -1.17348 9.8298 0)
			(unlocked yes)
			(layer "B.SilkS")
			(effects
				(font
					(size 0.7874 0.5842)
					(thickness 0.1524)
				)
				(justify mirror)
			)
		)
		(fp_text user "J"
			(at -1.17348 11.02995 0)
			(unlocked yes)
			(layer "B.SilkS")
			(effects
				(font
					(size 0.7874 0.5842)
					(thickness 0.1524)
				)
				(justify mirror)
			)
		)
		(fp_text user "K"
			(at -1.17348 12.229846 0)
			(unlocked yes)
			(layer "B.SilkS")
			(effects
				(font
					(size 0.7874 0.5842)
					(thickness 0.1524)
				)
				(justify mirror)
			)
		)
		(fp_text user "L"
			(at -1.17348 13.429996 0)
			(unlocked yes)
			(layer "B.SilkS")
			(effects
				(font
					(size 0.7874 0.5842)
					(thickness 0.1524)
				)
				(justify mirror)
			)
		)
		(fp_text user "M"
			(at -1.17348 14.629892 0)
			(unlocked yes)
			(layer "B.SilkS")
			(effects
				(font
					(size 0.7874 0.5842)
					(thickness 0.1524)
				)
				(justify mirror)
			)
		)
		(fp_text user "N"
			(at -1.17348 15.829788 0)
			(unlocked yes)
			(layer "B.SilkS")
			(effects
				(font
					(size 0.7874 0.5842)
					(thickness 0.1524)
				)
				(justify mirror)
			)
		)
		(fp_text user "1"
			(at -0.083058 16.98371 0)
			(unlocked yes)
			(layer "B.SilkS")
			(effects
				(font
					(size 0.7874 0.5842)
					(thickness 0.1524)
				)
				(justify mirror)
			)
		)
		(fp_text user "2"
			(at 1.916938 16.98371 0)
			(unlocked yes)
			(layer "B.SilkS")
			(effects
				(font
					(size 0.7874 0.5842)
					(thickness 0.1524)
				)
				(justify mirror)
			)
		)
		(fp_text user "3"
			(at 3.916934 16.98371 0)
			(unlocked yes)
			(layer "B.SilkS")
			(effects
				(font
					(size 0.7874 0.5842)
					(thickness 0.1524)
				)
				(justify mirror)
			)
		)
		(fp_text user "4"
			(at 5.91693 16.98371 0)
			(unlocked yes)
			(layer "B.SilkS")
			(effects
				(font
					(size 0.7874 0.5842)
					(thickness 0.1524)
				)
				(justify mirror)
			)
		)
		(fp_text user "5"
			(at 7.916926 16.98371 0)
			(unlocked yes)
			(layer "B.SilkS")
			(effects
				(font
					(size 0.7874 0.5842)
					(thickness 0.1524)
				)
				(justify mirror)
			)
		)
		(fp_text user "6"
			(at 9.916922 16.98371 0)
			(unlocked yes)
			(layer "B.SilkS")
			(effects
				(font
					(size 0.7874 0.5842)
					(thickness 0.1524)
				)
				(justify mirror)
			)
		)
		(fp_text user "7"
			(at 11.916918 16.98371 0)
			(unlocked yes)
			(layer "B.SilkS")
			(effects
				(font
					(size 0.7874 0.5842)
					(thickness 0.1524)
				)
				(justify mirror)
			)
		)
		(fp_text user "8"
			(at 13.916914 16.98371 0)
			(unlocked yes)
			(layer "B.SilkS")
			(effects
				(font
					(size 0.7874 0.5842)
					(thickness 0.1524)
				)
				(justify mirror)
			)
		)
		(fp_text user "PRESS-FIT"
			(at 18.430748 19.85137 0)
			(unlocked yes)
			(layer "B.SilkS")
			(effects
				(font
					(size 1.905 1.4224)
					(thickness 0.1524)
				)
				(justify left mirror)
			)
		)
		(fp_text user "A"
			(at -1.199134 0 90)
			(unlocked yes)
			(layer "B.Fab")
			(effects
				(font
					(size 0.7874 0.5842)
					(thickness 0.1524)
				)
				(justify mirror)
			)
		)
		(fp_text user "G"
			(at -1.173734 7.4168 90)
			(unlocked yes)
			(layer "B.Fab")
			(effects
				(font
					(size 0.7874 0.5842)
					(thickness 0.1524)
				)
				(justify mirror)
			)
		)
		(fp_text user "H"
			(at -1.148334 8.636 90)
			(unlocked yes)
			(layer "B.Fab")
			(effects
				(font
					(size 0.7874 0.5842)
					(thickness 0.1524)
				)
				(justify mirror)
			)
		)
		(fp_text user "B"
			(at -1.14681 1.326896 90)
			(unlocked yes)
			(layer "B.Fab")
			(effects
				(font
					(size 0.7874 0.5842)
					(thickness 0.1524)
				)
				(justify mirror)
			)
		)
		(fp_text user "C"
			(at -1.14681 2.527046 90)
			(unlocked yes)
			(layer "B.Fab")
			(effects
				(font
					(size 0.7874 0.5842)
					(thickness 0.1524)
				)
				(justify mirror)
			)
		)
		(fp_text user "D"
			(at -1.14681 3.726942 90)
			(unlocked yes)
			(layer "B.Fab")
			(effects
				(font
					(size 0.7874 0.5842)
					(thickness 0.1524)
				)
				(justify mirror)
			)
		)
		(fp_text user "E"
			(at -1.14681 4.927092 90)
			(unlocked yes)
			(layer "B.Fab")
			(effects
				(font
					(size 0.7874 0.5842)
					(thickness 0.1524)
				)
				(justify mirror)
			)
		)
		(fp_text user "F"
			(at -1.14681 6.126988 90)
			(unlocked yes)
			(layer "B.Fab")
			(effects
				(font
					(size 0.7874 0.5842)
					(thickness 0.1524)
				)
				(justify mirror)
			)
		)
		(fp_text user "I"
			(at -1.14681 9.72693 90)
			(unlocked yes)
			(layer "B.Fab")
			(effects
				(font
					(size 0.7874 0.5842)
					(thickness 0.1524)
				)
				(justify mirror)
			)
		)
		(fp_text user "J"
			(at -1.14681 10.92708 90)
			(unlocked yes)
			(layer "B.Fab")
			(effects
				(font
					(size 0.7874 0.5842)
					(thickness 0.1524)
				)
				(justify mirror)
			)
		)
		(fp_text user "K"
			(at -1.14681 12.126976 90)
			(unlocked yes)
			(layer "B.Fab")
			(effects
				(font
					(size 0.7874 0.5842)
					(thickness 0.1524)
				)
				(justify mirror)
			)
		)
		(fp_text user "L"
			(at -1.14681 13.327126 90)
			(unlocked yes)
			(layer "B.Fab")
			(effects
				(font
					(size 0.7874 0.5842)
					(thickness 0.1524)
				)
				(justify mirror)
			)
		)
		(fp_text user "M"
			(at -1.14681 14.527022 90)
			(unlocked yes)
			(layer "B.Fab")
			(effects
				(font
					(size 0.7874 0.5842)
					(thickness 0.1524)
				)
				(justify mirror)
			)
		)
		(fp_text user "N"
			(at -1.14681 15.726918 90)
			(unlocked yes)
			(layer "B.Fab")
			(effects
				(font
					(size 0.7874 0.5842)
					(thickness 0.1524)
				)
				(justify mirror)
			)
		)
		(fp_text user "1"
			(at 0.060452 16.764 90)
			(unlocked yes)
			(layer "B.Fab")
			(effects
				(font
					(size 0.7874 0.5842)
					(thickness 0.1524)
				)
				(justify mirror)
			)
		)
		(fp_text user "2"
			(at 2.060448 16.764 90)
			(unlocked yes)
			(layer "B.Fab")
			(effects
				(font
					(size 0.7874 0.5842)
					(thickness 0.1524)
				)
				(justify mirror)
			)
		)
		(fp_text user "3"
			(at 4.060444 16.764 90)
			(unlocked yes)
			(layer "B.Fab")
			(effects
				(font
					(size 0.7874 0.5842)
					(thickness 0.1524)
				)
				(justify mirror)
			)
		)
		(fp_text user "4"
			(at 6.06044 16.764 90)
			(unlocked yes)
			(layer "B.Fab")
			(effects
				(font
					(size 0.7874 0.5842)
					(thickness 0.1524)
				)
				(justify mirror)
			)
		)
		(fp_text user "5"
			(at 8.060436 16.764 90)
			(unlocked yes)
			(layer "B.Fab")
			(effects
				(font
					(size 0.7874 0.5842)
					(thickness 0.1524)
				)
				(justify mirror)
			)
		)
		(fp_text user "6"
			(at 10.060432 16.764 90)
			(unlocked yes)
			(layer "B.Fab")
			(effects
				(font
					(size 0.7874 0.5842)
					(thickness 0.1524)
				)
				(justify mirror)
			)
		)
		(fp_text user "7"
			(at 12.060428 16.764 90)
			(unlocked yes)
			(layer "B.Fab")
			(effects
				(font
					(size 0.7874 0.5842)
					(thickness 0.1524)
				)
				(justify mirror)
			)
		)
		(fp_text user "8"
			(at 14.060424 16.764 90)
			(unlocked yes)
			(layer "B.Fab")
			(effects
				(font
					(size 0.7874 0.5842)
					(thickness 0.1524)
				)
				(justify mirror)
			)
		)
		(fp_text user "PRESS-FIT"
			(at 17.23771 -0.0762 90)
			(unlocked yes)
			(layer "B.Fab")
			(effects
				(font
					(size 1.905 1.4224)
					(thickness 0.1524)
				)
				(justify left mirror)
			)
		)
		(fp_text user "B"
			(at -2.253742 1.199896 90)
			(unlocked yes)
			(layer "F.Fab")
			(effects
				(font
					(size 0.7874 0.5842)
					(thickness 0.1524)
				)
			)
		)
		(fp_text user "C"
			(at -2.253742 2.400046 90)
			(unlocked yes)
			(layer "F.Fab")
			(effects
				(font
					(size 0.7874 0.5842)
					(thickness 0.1524)
				)
			)
		)
		(fp_text user "D"
			(at -2.253742 3.599942 90)
			(unlocked yes)
			(layer "F.Fab")
			(effects
				(font
					(size 0.7874 0.5842)
					(thickness 0.1524)
				)
			)
		)
		(fp_text user "E"
			(at -2.253742 4.800092 90)
			(unlocked yes)
			(layer "F.Fab")
			(effects
				(font
					(size 0.7874 0.5842)
					(thickness 0.1524)
				)
			)
		)
		(fp_text user "F"
			(at -2.253742 5.999988 90)
			(unlocked yes)
			(layer "F.Fab")
			(effects
				(font
					(size 0.7874 0.5842)
					(thickness 0.1524)
				)
			)
		)
		(fp_text user "G"
			(at -2.253742 7.199884 90)
			(unlocked yes)
			(layer "F.Fab")
			(effects
				(font
					(size 0.7874 0.5842)
					(thickness 0.1524)
				)
			)
		)
		(fp_text user "H"
			(at -2.253742 8.400034 90)
			(unlocked yes)
			(layer "F.Fab")
			(effects
				(font
					(size 0.7874 0.5842)
					(thickness 0.1524)
				)
			)
		)
		(fp_text user "I"
			(at -2.253742 9.59993 90)
			(unlocked yes)
			(layer "F.Fab")
			(effects
				(font
					(size 0.7874 0.5842)
					(thickness 0.1524)
				)
			)
		)
		(fp_text user "J"
			(at -2.253742 10.80008 90)
			(unlocked yes)
			(layer "F.Fab")
			(effects
				(font
					(size 0.7874 0.5842)
					(thickness 0.1524)
				)
			)
		)
		(fp_text user "K"
			(at -2.253742 11.999976 90)
			(unlocked yes)
			(layer "F.Fab")
			(effects
				(font
					(size 0.7874 0.5842)
					(thickness 0.1524)
				)
			)
		)
		(fp_text user "L"
			(at -2.253742 13.200126 90)
			(unlocked yes)
			(layer "F.Fab")
			(effects
				(font
					(size 0.7874 0.5842)
					(thickness 0.1524)
				)
			)
		)
		(fp_text user "M"
			(at -2.253742 14.400022 90)
			(unlocked yes)
			(layer "F.Fab")
			(effects
				(font
					(size 0.7874 0.5842)
					(thickness 0.1524)
				)
			)
		)
		(fp_text user "N"
			(at -2.253742 15.599918 90)
			(unlocked yes)
			(layer "F.Fab")
			(effects
				(font
					(size 0.7874 0.5842)
					(thickness 0.1524)
				)
			)
		)
		(fp_text user "1"
			(at 0.111252 19.8628 90)
			(unlocked yes)
			(layer "F.Fab")
			(effects
				(font
					(size 0.7874 0.5842)
					(thickness 0.1524)
				)
			)
		)
		(fp_text user "2"
			(at 2.111248 19.8628 90)
			(unlocked yes)
			(layer "F.Fab")
			(effects
				(font
					(size 0.7874 0.5842)
					(thickness 0.1524)
				)
			)
		)
		(fp_text user "3"
			(at 4.111244 19.8628 90)
			(unlocked yes)
			(layer "F.Fab")
			(effects
				(font
					(size 0.7874 0.5842)
					(thickness 0.1524)
				)
			)
		)
		(fp_text user "4"
			(at 6.11124 19.8628 90)
			(unlocked yes)
			(layer "F.Fab")
			(effects
				(font
					(size 0.7874 0.5842)
					(thickness 0.1524)
				)
			)
		)
		(fp_text user "5"
			(at 8.111236 19.8628 90)
			(unlocked yes)
			(layer "F.Fab")
			(effects
				(font
					(size 0.7874 0.5842)
					(thickness 0.1524)
				)
			)
		)
		(fp_text user "6"
			(at 10.111232 19.8628 90)
			(unlocked yes)
			(layer "F.Fab")
			(effects
				(font
					(size 0.7874 0.5842)
					(thickness 0.1524)
				)
			)
		)
		(fp_text user "7"
			(at 12.111228 19.8628 90)
			(unlocked yes)
			(layer "F.Fab")
			(effects
				(font
					(size 0.7874 0.5842)
					(thickness 0.1524)
				)
			)
		)
		(fp_text user "8"
			(at 14.111224 19.8628 90)
			(unlocked yes)
			(layer "F.Fab")
			(effects
				(font
					(size 0.7874 0.5842)
					(thickness 0.1524)
				)
			)
		)
		(fp_text user "PRESS-FIT"
			(at 17.240758 16.521684 90)
			(unlocked yes)
			(layer "F.Fab")
			(effects
				(font
					(size 1.905 1.4224)
					(thickness 0.1524)
				)
				(justify left)
			)
		)
		(pad "A1" thru_hole rect
			(at 0 0 180)
			(size 0.766318 0.766318)
			(drill 0.359918)
			(layers "*.Cu" "*.Mask")
			(remove_unused_layers no)
			(net "BMC_MONITER_BUF")
			(clearance 0.0508)
			(thermal_gap 0.0508)
			(padstack
				(mode front_inner_back)
				(layer "Inner"
					(shape circle)
					(size 0.766318 0.766318)
					(clearance 0.0508)
				)
				(layer "B.Cu"
					(shape rect)
					(size 0.766318 0.766318)
					(clearance 0.0508)
				)
			)
		)
		(pad "A2" thru_hole circle
			(at 1.999996 0.199898 180)
			(size 0.906272 0.906272)
			(drill 0.499872)
			(layers "*.Cu" "*.Mask")
			(remove_unused_layers no)
			(net "GND")
			(clearance 0.0508)
			(thermal_gap 0.0508)
		)
		(pad "A3" thru_hole circle
			(at 3.999992 0 180)
			(size 0.766318 0.766318)
			(drill 0.359918)
			(layers "*.Cu" "*.Mask")
			(remove_unused_layers no)
			(net "BIC_MONITER")
			(clearance 0.0508)
			(thermal_gap 0.0508)
		)
		(pad "A4" thru_hole circle
			(at 5.999988 0.199898 180)
			(size 0.906272 0.906272)
			(drill 0.499872)
			(layers "*.Cu" "*.Mask")
			(remove_unused_layers no)
			(net "GND")
			(clearance 0.0508)
			(thermal_gap 0.0508)
		)
		(pad "A5" thru_hole circle
			(at 7.999984 0 180)
			(size 0.766318 0.766318)
			(drill 0.359918)
			(layers "*.Cu" "*.Mask")
			(remove_unused_layers no)
			(net "SMB_BMC_SWB_BUF_SCL")
			(clearance 0.0508)
			(thermal_gap 0.0508)
		)
		(pad "A6" thru_hole circle
			(at 9.99998 0.199898 180)
			(size 0.906272 0.906272)
			(drill 0.499872)
			(layers "*.Cu" "*.Mask")
			(remove_unused_layers no)
			(net "GND")
			(clearance 0.0508)
			(thermal_gap 0.0508)
		)
		(pad "A7" thru_hole circle
			(at 11.999976 0 180)
			(size 0.766318 0.766318)
			(drill 0.359918)
			(layers "*.Cu" "*.Mask")
			(remove_unused_layers no)
			(net "SMB_BMC_SWB_BUF_SDA")
			(clearance 0.0508)
			(thermal_gap 0.0508)
		)
		(pad "A8" thru_hole circle
			(at 13.999972 0.199898 180)
			(size 0.906272 0.906272)
			(drill 0.499872)
			(layers "*.Cu" "*.Mask")
			(remove_unused_layers no)
			(net "GND")
			(clearance 0.0508)
			(thermal_gap 0.0508)
		)
		(pad "B1" thru_hole circle
			(at 0 1.199896 180)
			(size 0.906272 0.906272)
			(drill 0.499872)
			(layers "*.Cu" "*.Mask")
			(remove_unused_layers no)
			(net "GND")
			(clearance 0.0508)
			(thermal_gap 0.0508)
		)
		(pad "B3" thru_hole circle
			(at 3.999992 1.199896 180)
			(size 0.906272 0.906272)
			(drill 0.499872)
			(layers "*.Cu" "*.Mask")
			(remove_unused_layers no)
			(net "GND")
			(clearance 0.0508)
			(thermal_gap 0.0508)
		)
		(pad "B5" thru_hole circle
			(at 7.999984 1.199896 180)
			(size 0.906272 0.906272)
			(drill 0.499872)
			(layers "*.Cu" "*.Mask")
			(remove_unused_layers no)
			(net "GND")
			(clearance 0.0508)
			(thermal_gap 0.0508)
		)
		(pad "B7" thru_hole circle
			(at 11.999976 1.199896 180)
			(size 0.906272 0.906272)
			(drill 0.499872)
			(layers "*.Cu" "*.Mask")
			(remove_unused_layers no)
			(net "GND")
			(clearance 0.0508)
			(thermal_gap 0.0508)
		)
		(pad "D2" thru_hole circle
			(at 1.999996 3.800094 180)
			(size 0.906272 0.906272)
			(drill 0.499872)
			(layers "*.Cu" "*.Mask")
			(remove_unused_layers no)
			(net "GND")
			(clearance 0.0508)
			(thermal_gap 0.0508)
		)
		(pad "D4" thru_hole circle
			(at 5.999988 3.800094 180)
			(size 0.906272 0.906272)
			(drill 0.499872)
			(layers "*.Cu" "*.Mask")
			(remove_unused_layers no)
			(net "GND")
			(clearance 0.0508)
			(thermal_gap 0.0508)
		)
		(pad "D6" thru_hole circle
			(at 9.99998 3.800094 180)
			(size 0.906272 0.906272)
			(drill 0.499872)
			(layers "*.Cu" "*.Mask")
			(remove_unused_layers no)
			(net "GND")
			(clearance 0.0508)
			(thermal_gap 0.0508)
		)
		(pad "D8" thru_hole circle
			(at 13.999972 3.800094 180)
			(size 0.906272 0.906272)
			(drill 0.499872)
			(layers "*.Cu" "*.Mask")
			(remove_unused_layers no)
			(net "GND")
			(clearance 0.0508)
			(thermal_gap 0.0508)
		)
		(pad "E1" thru_hole circle
			(at 0 4.800092 180)
			(size 0.906272 0.906272)
			(drill 0.499872)
			(layers "*.Cu" "*.Mask")
			(remove_unused_layers no)
			(net "GND")
			(clearance 0.0508)
			(thermal_gap 0.0508)
		)
		(pad "E3" thru_hole circle
			(at 3.999992 4.800092 180)
			(size 0.906272 0.906272)
			(drill 0.499872)
			(layers "*.Cu" "*.Mask")
			(remove_unused_layers no)
			(net "GND")
			(clearance 0.0508)
			(thermal_gap 0.0508)
		)
		(pad "E5" thru_hole circle
			(at 7.999984 4.800092 180)
			(size 0.906272 0.906272)
			(drill 0.499872)
			(layers "*.Cu" "*.Mask")
			(remove_unused_layers no)
			(net "GND")
			(clearance 0.0508)
			(thermal_gap 0.0508)
		)
		(pad "E7" thru_hole circle
			(at 11.999976 4.800092 180)
			(size 0.906272 0.906272)
			(drill 0.499872)
			(layers "*.Cu" "*.Mask")
			(remove_unused_layers no)
			(net "GND")
			(clearance 0.0508)
			(thermal_gap 0.0508)
		)
		(pad "G2" thru_hole circle
			(at 1.999996 7.400036 180)
			(size 0.906272 0.906272)
			(drill 0.499872)
			(layers "*.Cu" "*.Mask")
			(remove_unused_layers no)
			(net "GND")
			(clearance 0.0508)
			(thermal_gap 0.0508)
		)
		(pad "G4" thru_hole circle
			(at 5.999988 7.400036 180)
			(size 0.906272 0.906272)
			(drill 0.499872)
			(layers "*.Cu" "*.Mask")
			(remove_unused_layers no)
			(net "GND")
			(clearance 0.0508)
			(thermal_gap 0.0508)
		)
		(pad "G6" thru_hole circle
			(at 9.99998 7.400036 180)
			(size 0.906272 0.906272)
			(drill 0.499872)
			(layers "*.Cu" "*.Mask")
			(remove_unused_layers no)
			(net "GND")
			(clearance 0.0508)
			(thermal_gap 0.0508)
		)
		(pad "G8" thru_hole circle
			(at 13.999972 7.400036 180)
			(size 0.906272 0.906272)
			(drill 0.499872)
			(layers "*.Cu" "*.Mask")
			(remove_unused_layers no)
			(net "GND")
			(clearance 0.0508)
			(thermal_gap 0.0508)
		)
		(pad "H1" thru_hole circle
			(at 0 8.400034 180)
			(size 0.906272 0.906272)
			(drill 0.499872)
			(layers "*.Cu" "*.Mask")
			(remove_unused_layers no)
			(net "GND")
			(clearance 0.0508)
			(thermal_gap 0.0508)
		)
		(pad "H3" thru_hole circle
			(at 3.999992 8.400034 180)
			(size 0.906272 0.906272)
			(drill 0.499872)
			(layers "*.Cu" "*.Mask")
			(remove_unused_layers no)
			(net "GND")
			(clearance 0.0508)
			(thermal_gap 0.0508)
		)
		(pad "H5" thru_hole circle
			(at 7.999984 8.400034 180)
			(size 0.906272 0.906272)
			(drill 0.499872)
			(layers "*.Cu" "*.Mask")
			(remove_unused_layers no)
			(net "GND")
			(clearance 0.0508)
			(thermal_gap 0.0508)
		)
		(pad "H7" thru_hole circle
			(at 11.999976 8.400034 180)
			(size 0.906272 0.906272)
			(drill 0.499872)
			(layers "*.Cu" "*.Mask")
			(remove_unused_layers no)
			(net "GND")
			(clearance 0.0508)
			(thermal_gap 0.0508)
		)
		(pad "J2" thru_hole circle
			(at 1.999996 10.999978 180)
			(size 0.906272 0.906272)
			(drill 0.499872)
			(layers "*.Cu" "*.Mask")
			(remove_unused_layers no)
			(net "GND")
			(clearance 0.0508)
			(thermal_gap 0.0508)
		)
		(pad "J4" thru_hole circle
			(at 5.999988 10.999978 180)
			(size 0.906272 0.906272)
			(drill 0.499872)
			(layers "*.Cu" "*.Mask")
			(remove_unused_layers no)
			(net "GND")
			(clearance 0.0508)
			(thermal_gap 0.0508)
		)
		(pad "J6" thru_hole circle
			(at 9.99998 10.999978 180)
			(size 0.906272 0.906272)
			(drill 0.499872)
			(layers "*.Cu" "*.Mask")
			(remove_unused_layers no)
			(net "GND")
			(clearance 0.0508)
			(thermal_gap 0.0508)
		)
		(pad "J8" thru_hole circle
			(at 13.999972 10.999978 180)
			(size 0.906272 0.906272)
			(drill 0.499872)
			(layers "*.Cu" "*.Mask")
			(remove_unused_layers no)
			(net "GND")
			(clearance 0.0508)
			(thermal_gap 0.0508)
		)
		(pad "K1" thru_hole circle
			(at 0 11.999976 180)
			(size 0.906272 0.906272)
			(drill 0.499872)
			(layers "*.Cu" "*.Mask")
			(remove_unused_layers no)
			(net "GND")
			(clearance 0.0508)
			(thermal_gap 0.0508)
		)
		(pad "K3" thru_hole circle
			(at 3.999992 11.999976 180)
			(size 0.906272 0.906272)
			(drill 0.499872)
			(layers "*.Cu" "*.Mask")
			(remove_unused_layers no)
			(net "GND")
			(clearance 0.0508)
			(thermal_gap 0.0508)
		)
		(pad "K5" thru_hole circle
			(at 7.999984 11.999976 180)
			(size 0.906272 0.906272)
			(drill 0.499872)
			(layers "*.Cu" "*.Mask")
			(remove_unused_layers no)
			(net "GND")
			(clearance 0.0508)
			(thermal_gap 0.0508)
		)
		(pad "K7" thru_hole circle
			(at 11.999976 11.999976 180)
			(size 0.906272 0.906272)
			(drill 0.499872)
			(layers "*.Cu" "*.Mask")
			(remove_unused_layers no)
			(net "GND")
			(clearance 0.0508)
			(thermal_gap 0.0508)
		)
		(pad "M2" thru_hole circle
			(at 1.999996 14.59992 180)
			(size 0.906272 0.906272)
			(drill 0.499872)
			(layers "*.Cu" "*.Mask")
			(remove_unused_layers no)
			(net "GND")
			(clearance 0.0508)
			(thermal_gap 0.0508)
		)
		(pad "M4" thru_hole circle
			(at 5.999988 14.59992 180)
			(size 0.906272 0.906272)
			(drill 0.499872)
			(layers "*.Cu" "*.Mask")
			(remove_unused_layers no)
			(net "GND")
			(clearance 0.0508)
			(thermal_gap 0.0508)
		)
		(pad "M6" thru_hole circle
			(at 9.99998 14.59992 180)
			(size 0.906272 0.906272)
			(drill 0.499872)
			(layers "*.Cu" "*.Mask")
			(remove_unused_layers no)
			(net "GND")
			(clearance 0.0508)
			(thermal_gap 0.0508)
		)
		(pad "M8" thru_hole circle
			(at 13.999972 14.59992 180)
			(size 0.906272 0.906272)
			(drill 0.499872)
			(layers "*.Cu" "*.Mask")
			(remove_unused_layers no)
			(net "GND")
			(clearance 0.0508)
			(thermal_gap 0.0508)
		)
		(pad "N1" thru_hole circle
			(at 0 15.599918 180)
			(size 0.906272 0.906272)
			(drill 0.499872)
			(layers "*.Cu" "*.Mask")
			(remove_unused_layers no)
			(net "GND")
			(clearance 0.0508)
			(thermal_gap 0.0508)
		)
		(pad "N2" thru_hole circle
			(at 1.999996 15.80007 180)
			(size 0.766318 0.766318)
			(drill 0.359918)
			(layers "*.Cu" "*.Mask")
			(remove_unused_layers no)
			(net "GPU_FPGA_EROT_FATALERR_N")
			(clearance 0.0508)
			(thermal_gap 0.0508)
		)
		(pad "N3" thru_hole circle
			(at 3.999992 15.599918 180)
			(size 0.906272 0.906272)
			(drill 0.499872)
			(layers "*.Cu" "*.Mask")
			(remove_unused_layers no)
			(net "GND")
			(clearance 0.0508)
			(thermal_gap 0.0508)
		)
		(pad "N4" thru_hole circle
			(at 5.999988 15.80007 180)
			(size 0.766318 0.766318)
			(drill 0.359918)
			(layers "*.Cu" "*.Mask")
			(remove_unused_layers no)
			(net "GPU_3V3IO_RSVD0_FFU")
			(clearance 0.0508)
			(thermal_gap 0.0508)
		)
		(pad "N5" thru_hole circle
			(at 7.999984 15.599918 180)
			(size 0.906272 0.906272)
			(drill 0.499872)
			(layers "*.Cu" "*.Mask")
			(remove_unused_layers no)
			(net "GND")
			(clearance 0.0508)
			(thermal_gap 0.0508)
		)
		(pad "N6" thru_hole circle
			(at 9.99998 15.80007 180)
			(size 0.766318 0.766318)
			(drill 0.359918)
			(layers "*.Cu" "*.Mask")
			(remove_unused_layers no)
			(net "GPU_3V3IO_RSVD1_FFU")
			(clearance 0.0508)
			(thermal_gap 0.0508)
		)
		(pad "N7" thru_hole circle
			(at 11.999976 15.599918 180)
			(size 0.906272 0.906272)
			(drill 0.499872)
			(layers "*.Cu" "*.Mask")
			(remove_unused_layers no)
			(net "GND")
			(clearance 0.0508)
			(thermal_gap 0.0508)
		)
		(pad "N8" thru_hole circle
			(at 13.999972 15.80007 180)
			(size 0.766318 0.766318)
			(drill 0.359918)
			(layers "*.Cu" "*.Mask")
			(remove_unused_layers no)
			(net "PRSNT_CABLE_GPU_B3_N")
			(clearance 0.0508)
			(thermal_gap 0.0508)
		)
	)
	(footprint ""
		(layer "F.Cu")
		(at 366.48263 -245.634002 -90)
		(property "Reference" "C1005"
			(at 0 0 270)
			(layer "F.SilkS")
			(hide yes)
			(effects
				(font
					(size 1.27 1.27)
				)
			)
		)
		(property "Value" ""
			(at 0 0 270)
			(layer "F.Fab")
			(effects
				(font
					(size 1.27 1.27)
				)
			)
		)
		(duplicate_pad_numbers_are_jumpers no)
		(fp_line
			(start -0.7874 0.4064)
			(end -0.7874 -0.4064)
			(stroke
				(width 0.1524)
				(type default)
			)
			(layer "F.SilkS")
		)
		(fp_line
			(start 0.7874 0.4064)
			(end -0.7874 0.4064)
			(stroke
				(width 0.1524)
				(type default)
			)
			(layer "F.SilkS")
		)
		(fp_line
			(start -0.7874 -0.4064)
			(end 0.7874 -0.4064)
			(stroke
				(width 0.1524)
				(type default)
			)
			(layer "F.SilkS")
		)
		(fp_line
			(start 0.7874 -0.4064)
			(end 0.7874 0.4064)
			(stroke
				(width 0.1524)
				(type default)
			)
			(layer "F.SilkS")
		)
		(fp_line
			(start -0.67945 0.3048)
			(end -0.67945 -0.305054)
			(stroke
				(width 0.1)
				(type default)
			)
			(layer "F.Fab")
		)
		(fp_line
			(start -0.12065 0.3048)
			(end -0.67945 0.3048)
			(stroke
				(width 0.1)
				(type default)
			)
			(layer "F.Fab")
		)
		(fp_line
			(start 0.120396 0.3048)
			(end 0.120396 0.2794)
			(stroke
				(width 0.1)
				(type default)
			)
			(layer "F.Fab")
		)
		(fp_line
			(start 0.67945 0.3048)
			(end 0.120396 0.3048)
			(stroke
				(width 0.1)
				(type default)
			)
			(layer "F.Fab")
		)
		(fp_line
			(start -0.12065 0.2794)
			(end -0.12065 0.3048)
			(stroke
				(width 0.1)
				(type default)
			)
			(layer "F.Fab")
		)
		(fp_line
			(start 0.120396 0.2794)
			(end -0.12065 0.2794)
			(stroke
				(width 0.1)
				(type default)
			)
			(layer "F.Fab")
		)
		(fp_line
			(start -0.12065 -0.2794)
			(end 0.12065 -0.2794)
			(stroke
				(width 0.1)
				(type default)
			)
			(layer "F.Fab")
		)
		(fp_line
			(start 0.12065 -0.2794)
			(end 0.12065 -0.3048)
			(stroke
				(width 0.1)
				(type default)
			)
			(layer "F.Fab")
		)
		(fp_line
			(start 0.12065 -0.3048)
			(end 0.67945 -0.3048)
			(stroke
				(width 0.1)
				(type default)
			)
			(layer "F.Fab")
		)
		(fp_line
			(start 0.67945 -0.3048)
			(end 0.67945 0.3048)
			(stroke
				(width 0.1)
				(type default)
			)
			(layer "F.Fab")
		)
		(fp_line
			(start -0.67945 -0.305054)
			(end -0.12065 -0.305054)
			(stroke
				(width 0.1)
				(type default)
			)
			(layer "F.Fab")
		)
		(fp_line
			(start -0.12065 -0.305054)
			(end -0.12065 -0.2794)
			(stroke
				(width 0.1)
				(type default)
			)
			(layer "F.Fab")
		)
		(pad "1" smd circle
			(at -0.40005 0 270)
			(size 0 0)
			(layers "F.Cu" "F.Mask" "F.Paste")
			(net "PVCCIN_CPU0")
		)
		(pad "2" smd circle
			(at 0.40005 0 270)
			(size 0 0)
			(layers "F.Cu" "F.Mask" "F.Paste")
			(net "GND")
		)
	)
	(footprint ""
		(layer "F.Cu")
		(at 333.335884 -343.496138 -90)
		(property "Reference" "PC231_P0_7"
			(at 0 0 270)
			(layer "F.SilkS")
			(hide yes)
			(effects
				(font
					(size 1.27 1.27)
				)
			)
		)
		(property "Value" ""
			(at 0 0 270)
			(layer "F.Fab")
			(effects
				(font
					(size 1.27 1.27)
				)
			)
		)
		(duplicate_pad_numbers_are_jumpers no)
		(fp_line
			(start -0.7874 0.4064)
			(end -0.7874 -0.4064)
			(stroke
				(width 0.1524)
				(type default)
			)
			(layer "F.SilkS")
		)
		(fp_line
			(start 0.7874 0.4064)
			(end -0.7874 0.4064)
			(stroke
				(width 0.1524)
				(type default)
			)
			(layer "F.SilkS")
		)
		(fp_line
			(start -0.7874 -0.4064)
			(end 0.7874 -0.4064)
			(stroke
				(width 0.1524)
				(type default)
			)
			(layer "F.SilkS")
		)
		(fp_line
			(start 0.7874 -0.4064)
			(end 0.7874 0.4064)
			(stroke
				(width 0.1524)
				(type default)
			)
			(layer "F.SilkS")
		)
		(fp_line
			(start -0.67945 0.3048)
			(end -0.67945 -0.305054)
			(stroke
				(width 0.1)
				(type default)
			)
			(layer "F.Fab")
		)
		(fp_line
			(start -0.12065 0.3048)
			(end -0.67945 0.3048)
			(stroke
				(width 0.1)
				(type default)
			)
			(layer "F.Fab")
		)
		(fp_line
			(start 0.120396 0.3048)
			(end 0.120396 0.2794)
			(stroke
				(width 0.1)
				(type default)
			)
			(layer "F.Fab")
		)
		(fp_line
			(start 0.67945 0.3048)
			(end 0.120396 0.3048)
			(stroke
				(width 0.1)
				(type default)
			)
			(layer "F.Fab")
		)
		(fp_line
			(start -0.12065 0.2794)
			(end -0.12065 0.3048)
			(stroke
				(width 0.1)
				(type default)
			)
			(layer "F.Fab")
		)
		(fp_line
			(start 0.120396 0.2794)
			(end -0.12065 0.2794)
			(stroke
				(width 0.1)
				(type default)
			)
			(layer "F.Fab")
		)
		(fp_line
			(start -0.12065 -0.2794)
			(end 0.12065 -0.2794)
			(stroke
				(width 0.1)
				(type default)
			)
			(layer "F.Fab")
		)
		(fp_line
			(start 0.12065 -0.2794)
			(end 0.12065 -0.3048)
			(stroke
				(width 0.1)
				(type default)
			)
			(layer "F.Fab")
		)
		(fp_line
			(start 0.12065 -0.3048)
			(end 0.67945 -0.3048)
			(stroke
				(width 0.1)
				(type default)
			)
			(layer "F.Fab")
		)
		(fp_line
			(start 0.67945 -0.3048)
			(end 0.67945 0.3048)
			(stroke
				(width 0.1)
				(type default)
			)
			(layer "F.Fab")
		)
		(fp_line
			(start -0.67945 -0.305054)
			(end -0.12065 -0.305054)
			(stroke
				(width 0.1)
				(type default)
			)
			(layer "F.Fab")
		)
		(fp_line
			(start -0.12065 -0.305054)
			(end -0.12065 -0.2794)
			(stroke
				(width 0.1)
				(type default)
			)
			(layer "F.Fab")
		)
		(pad "1" smd circle
			(at -0.40005 0 270)
			(size 0 0)
			(layers "F.Cu" "F.Mask" "F.Paste")
			(net "SW_P12V_PVCCIN_CPU0_FLT")
		)
		(pad "2" smd circle
			(at 0.40005 0 270)
			(size 0 0)
			(layers "F.Cu" "F.Mask" "F.Paste")
			(net "GND")
		)
	)
	(footprint ""
		(layer "F.Cu")
		(at 81.435956 -347.520514 90)
		(property "Reference" "PR1793"
			(at 0 0 90)
			(layer "F.SilkS")
			(hide yes)
			(effects
				(font
					(size 1.27 1.27)
				)
			)
		)
		(property "Value" ""
			(at 0 0 90)
			(layer "F.Fab")
			(effects
				(font
					(size 1.27 1.27)
				)
			)
		)
		(duplicate_pad_numbers_are_jumpers no)
		(fp_line
			(start 0.7874 -0.4064)
			(end 0.7874 0.4064)
			(stroke
				(width 0.1524)
				(type default)
			)
			(layer "F.SilkS")
		)
		(fp_line
			(start -0.7874 -0.4064)
			(end 0.7874 -0.4064)
			(stroke
				(width 0.1524)
				(type default)
			)
			(layer "F.SilkS")
		)
		(fp_line
			(start 0.7874 0.4064)
			(end -0.7874 0.4064)
			(stroke
				(width 0.1524)
				(type default)
			)
			(layer "F.SilkS")
		)
		(fp_line
			(start -0.7874 0.4064)
			(end -0.7874 -0.4064)
			(stroke
				(width 0.1524)
				(type default)
			)
			(layer "F.SilkS")
		)
		(fp_line
			(start -0.12065 -0.305054)
			(end -0.12065 -0.2794)
			(stroke
				(width 0.1)
				(type default)
			)
			(layer "F.Fab")
		)
		(fp_line
			(start -0.67945 -0.305054)
			(end -0.12065 -0.305054)
			(stroke
				(width 0.1)
				(type default)
			)
			(layer "F.Fab")
		)
		(fp_line
			(start 0.67945 -0.3048)
			(end 0.67945 0.3048)
			(stroke
				(width 0.1)
				(type default)
			)
			(layer "F.Fab")
		)
		(fp_line
			(start 0.12065 -0.3048)
			(end 0.67945 -0.3048)
			(stroke
				(width 0.1)
				(type default)
			)
			(layer "F.Fab")
		)
		(fp_line
			(start 0.12065 -0.2794)
			(end 0.12065 -0.3048)
			(stroke
				(width 0.1)
				(type default)
			)
			(layer "F.Fab")
		)
		(fp_line
			(start -0.12065 -0.2794)
			(end 0.12065 -0.2794)
			(stroke
				(width 0.1)
				(type default)
			)
			(layer "F.Fab")
		)
		(fp_line
			(start 0.120396 0.2794)
			(end -0.12065 0.2794)
			(stroke
				(width 0.1)
				(type default)
			)
			(layer "F.Fab")
		)
		(fp_line
			(start -0.12065 0.2794)
			(end -0.12065 0.3048)
			(stroke
				(width 0.1)
				(type default)
			)
			(layer "F.Fab")
		)
		(fp_line
			(start 0.67945 0.3048)
			(end 0.120396 0.3048)
			(stroke
				(width 0.1)
				(type default)
			)
			(layer "F.Fab")
		)
		(fp_line
			(start 0.120396 0.3048)
			(end 0.120396 0.2794)
			(stroke
				(width 0.1)
				(type default)
			)
			(layer "F.Fab")
		)
		(fp_line
			(start -0.12065 0.3048)
			(end -0.67945 0.3048)
			(stroke
				(width 0.1)
				(type default)
			)
			(layer "F.Fab")
		)
		(fp_line
			(start -0.67945 0.3048)
			(end -0.67945 -0.305054)
			(stroke
				(width 0.1)
				(type default)
			)
			(layer "F.Fab")
		)
		(pad "1" smd circle
			(at -0.40005 0 90)
			(size 0 0)
			(layers "F.Cu" "F.Mask" "F.Paste")
			(net "SW_PVCCIN_CPU1_BOOT7")
		)
		(pad "2" smd circle
			(at 0.40005 0 90)
			(size 0 0)
			(layers "F.Cu" "F.Mask" "F.Paste")
			(net "SW_PVCCIN_CPU1_BOOT7_R")
		)
	)
	(footprint ""
		(layer "F.Cu")
		(at 359.870248 -251.76988 90)
		(property "Reference" "U2"
			(at -74.416158 -44.488608 0)
			(unlocked yes)
			(layer "F.SilkS")
			(effects
				(font
					(size 1.6002 1.1938)
					(thickness 0.1524)
				)
				(justify left)
			)
		)
		(property "Value" ""
			(at 0 0 90)
			(layer "F.Fab")
			(effects
				(font
					(size 1.27 1.27)
				)
			)
		)
		(duplicate_pad_numbers_are_jumpers no)
		(fp_line
			(start 39.499794 -32.250126)
			(end 39.499794 -31.000192)
			(stroke
				(width 0.1524)
				(type default)
			)
			(layer "F.SilkS")
		)
		(fp_line
			(start 39.499794 -32.250126)
			(end 39.499794 -30.995874)
			(stroke
				(width 0.1524)
				(type default)
			)
			(layer "F.SilkS")
		)
		(fp_line
			(start 39.299896 -32.250126)
			(end 39.499794 -32.250126)
			(stroke
				(width 0.1524)
				(type default)
			)
			(layer "F.SilkS")
		)
		(fp_line
			(start 37.69995 -32.250126)
			(end 39.299896 -32.250126)
			(stroke
				(width 0.1524)
				(type default)
			)
			(layer "F.SilkS")
		)
		(fp_line
			(start 37.499798 -32.250126)
			(end 39.499794 -32.250126)
			(stroke
				(width 0.1524)
				(type default)
			)
			(layer "F.SilkS")
		)
		(fp_line
			(start 37.499798 -32.250126)
			(end 37.69995 -32.250126)
			(stroke
				(width 0.1524)
				(type default)
			)
			(layer "F.SilkS")
		)
		(fp_line
			(start -30.80004 -32.250126)
			(end -34.99993 -32.250126)
			(stroke
				(width 0.1524)
				(type default)
			)
			(layer "F.SilkS")
		)
		(fp_line
			(start -34.99993 -32.250126)
			(end -34.99993 -31.000192)
			(stroke
				(width 0.1524)
				(type default)
			)
			(layer "F.SilkS")
		)
		(fp_line
			(start -35.000184 -32.250126)
			(end -32.999934 -32.250126)
			(stroke
				(width 0.1524)
				(type default)
			)
			(layer "F.SilkS")
		)
		(fp_line
			(start 39.499794 -32.249872)
			(end 39.499794 -30.999938)
			(stroke
				(width 0.1524)
				(type default)
			)
			(layer "F.SilkS")
		)
		(fp_line
			(start 39.299896 -32.249872)
			(end 39.499794 -32.249872)
			(stroke
				(width 0.1524)
				(type default)
			)
			(layer "F.SilkS")
		)
		(fp_line
			(start 37.69995 -32.249872)
			(end 39.299896 -32.249872)
			(stroke
				(width 0.1524)
				(type default)
			)
			(layer "F.SilkS")
		)
		(fp_line
			(start 37.499798 -32.249872)
			(end 37.69995 -32.249872)
			(stroke
				(width 0.1524)
				(type default)
			)
			(layer "F.SilkS")
		)
		(fp_line
			(start -33.000188 -32.249872)
			(end -35.000184 -32.249872)
			(stroke
				(width 0.1524)
				(type default)
			)
			(layer "F.SilkS")
		)
		(fp_line
			(start -35.000184 -32.249872)
			(end -35.000184 -30.999938)
			(stroke
				(width 0.1524)
				(type default)
			)
			(layer "F.SilkS")
		)
		(fp_line
			(start 37.499798 -31.000192)
			(end 37.499798 -32.250126)
			(stroke
				(width 0.1524)
				(type default)
			)
			(layer "F.SilkS")
		)
		(fp_line
			(start 37.499798 -31.000192)
			(end 37.499798 -32.250126)
			(stroke
				(width 0.1524)
				(type default)
			)
			(layer "F.SilkS")
		)
		(fp_line
			(start -35.000184 -31.000192)
			(end -35.000184 -32.250126)
			(stroke
				(width 0.1524)
				(type default)
			)
			(layer "F.SilkS")
		)
		(fp_line
			(start 37.499798 -30.999938)
			(end 37.499798 -32.249872)
			(stroke
				(width 0.1524)
				(type default)
			)
			(layer "F.SilkS")
		)
		(fp_line
			(start 41.000172 -30.500066)
			(end 40.000174 -30.500066)
			(stroke
				(width 0.1524)
				(type default)
			)
			(layer "F.SilkS")
		)
		(fp_line
			(start 40.999918 -30.500066)
			(end 40.999918 30.500066)
			(stroke
				(width 0.1524)
				(type default)
			)
			(layer "F.SilkS")
		)
		(fp_line
			(start 39.998396 -30.500066)
			(end 40.999918 -30.500066)
			(stroke
				(width 0.1524)
				(type default)
			)
			(layer "F.SilkS")
		)
		(fp_line
			(start 37.00018 -30.500066)
			(end 35.81019 -30.500066)
			(stroke
				(width 0.1524)
				(type default)
			)
			(layer "F.SilkS")
		)
		(fp_line
			(start 35.81019 -30.500066)
			(end 35.81019 -29.500068)
			(stroke
				(width 0.1524)
				(type default)
			)
			(layer "F.SilkS")
		)
		(fp_line
			(start 31.809944 -30.500066)
			(end 30.209998 -30.500066)
			(stroke
				(width 0.1524)
				(type default)
			)
			(layer "F.SilkS")
		)
		(fp_line
			(start 30.209998 -30.500066)
			(end 30.209998 -29.500068)
			(stroke
				(width 0.1524)
				(type default)
			)
			(layer "F.SilkS")
		)
		(fp_line
			(start -30.80004 -30.500066)
			(end -30.80004 -32.250126)
			(stroke
				(width 0.1524)
				(type default)
			)
			(layer "F.SilkS")
		)
		(fp_line
			(start -32.999934 -30.500066)
			(end 37.001704 -30.500066)
			(stroke
				(width 0.1524)
				(type default)
			)
			(layer "F.SilkS")
		)
		(fp_line
			(start -35.809936 -30.500066)
			(end -35.500056 -30.500066)
			(stroke
				(width 0.1524)
				(type default)
			)
			(layer "F.SilkS")
		)
		(fp_line
			(start -39.500048 -30.500066)
			(end -35.49523 -30.500066)
			(stroke
				(width 0.1524)
				(type default)
			)
			(layer "F.SilkS")
		)
		(fp_line
			(start -39.500048 -30.500066)
			(end -35.809936 -30.500066)
			(stroke
				(width 0.1524)
				(type default)
			)
			(layer "F.SilkS")
		)
		(fp_line
			(start 40.999918 -30.499812)
			(end 39.99992 -30.499812)
			(stroke
				(width 0.1524)
				(type default)
			)
			(layer "F.SilkS")
		)
		(fp_line
			(start 36.999926 -30.499812)
			(end 35.809936 -30.499812)
			(stroke
				(width 0.1524)
				(type default)
			)
			(layer "F.SilkS")
		)
		(fp_line
			(start 35.809936 -30.499812)
			(end 35.809936 -29.499814)
			(stroke
				(width 0.1524)
				(type default)
			)
			(layer "F.SilkS")
		)
		(fp_line
			(start 31.809944 -30.499812)
			(end 30.209998 -30.499812)
			(stroke
				(width 0.1524)
				(type default)
			)
			(layer "F.SilkS")
		)
		(fp_line
			(start 30.209998 -30.499812)
			(end 30.209998 -29.499814)
			(stroke
				(width 0.1524)
				(type default)
			)
			(layer "F.SilkS")
		)
		(fp_line
			(start -35.81019 -30.499812)
			(end -35.500056 -30.499812)
			(stroke
				(width 0.1524)
				(type default)
			)
			(layer "F.SilkS")
		)
		(fp_line
			(start -39.500048 -30.499812)
			(end -35.81019 -30.499812)
			(stroke
				(width 0.1524)
				(type default)
			)
			(layer "F.SilkS")
		)
		(fp_line
			(start 35.81019 -29.800042)
			(end 35.81019 -28.999942)
			(stroke
				(width 0.1524)
				(type default)
			)
			(layer "F.SilkS")
		)
		(fp_line
			(start 35.809936 -29.799788)
			(end 35.809936 -28.999942)
			(stroke
				(width 0.1524)
				(type default)
			)
			(layer "F.SilkS")
		)
		(fp_line
			(start 35.81019 -29.500068)
			(end 31.809944 -29.500068)
			(stroke
				(width 0.1524)
				(type default)
			)
			(layer "F.SilkS")
		)
		(fp_line
			(start 31.809944 -29.500068)
			(end 31.809944 -30.500066)
			(stroke
				(width 0.1524)
				(type default)
			)
			(layer "F.SilkS")
		)
		(fp_line
			(start 31.809944 -29.500068)
			(end 31.809944 -28.450032)
			(stroke
				(width 0.1524)
				(type default)
			)
			(layer "F.SilkS")
		)
		(fp_line
			(start 30.209998 -29.500068)
			(end 2.999994 -29.500068)
			(stroke
				(width 0.1524)
				(type default)
			)
			(layer "F.SilkS")
		)
		(fp_line
			(start 2.999994 -29.500068)
			(end 1.299972 -27.450034)
			(stroke
				(width 0.1524)
				(type default)
			)
			(layer "F.SilkS")
		)
		(fp_line
			(start -2.99974 -29.500068)
			(end -32.999934 -29.500068)
			(stroke
				(width 0.1524)
				(type default)
			)
			(layer "F.SilkS")
		)
		(fp_line
			(start -32.999934 -29.500068)
			(end -32.999934 -28.999942)
			(stroke
				(width 0.1524)
				(type default)
			)
			(layer "F.SilkS")
		)
		(fp_line
			(start 35.809936 -29.499814)
			(end 31.809944 -29.499814)
			(stroke
				(width 0.1524)
				(type default)
			)
			(layer "F.SilkS")
		)
		(fp_line
			(start 31.809944 -29.499814)
			(end 31.809944 -30.499812)
			(stroke
				(width 0.1524)
				(type default)
			)
			(layer "F.SilkS")
		)
		(fp_line
			(start 31.809944 -29.499814)
			(end 31.809944 -28.450032)
			(stroke
				(width 0.1524)
				(type default)
			)
			(layer "F.SilkS")
		)
		(fp_line
			(start 30.209998 -29.499814)
			(end 2.999994 -29.499814)
			(stroke
				(width 0.1524)
				(type default)
			)
			(layer "F.SilkS")
		)
		(fp_line
			(start 2.999994 -29.499814)
			(end 1.299972 -27.44978)
			(stroke
				(width 0.1524)
				(type default)
			)
			(layer "F.SilkS")
		)
		(fp_line
			(start -2.999994 -29.499814)
			(end -33.000188 -29.499814)
			(stroke
				(width 0.1524)
				(type default)
			)
			(layer "F.SilkS")
		)
		(fp_line
			(start -33.000188 -29.499814)
			(end -32.999934 -30.500066)
			(stroke
				(width 0.1524)
				(type default)
			)
			(layer "F.SilkS")
		)
		(fp_line
			(start -33.000188 -29.499814)
			(end -33.000188 -28.999942)
			(stroke
				(width 0.1524)
				(type default)
			)
			(layer "F.SilkS")
		)
		(fp_line
			(start 37.810186 -29.009848)
			(end 38.759892 -29.009848)
			(stroke
				(width 0.1524)
				(type default)
			)
			(layer "F.SilkS")
		)
		(fp_line
			(start 37.809932 -29.009848)
			(end 38.759892 -29.009848)
			(stroke
				(width 0.1524)
				(type default)
			)
			(layer "F.SilkS")
		)
		(fp_line
			(start -38.760146 -29.009848)
			(end -37.809932 -29.009848)
			(stroke
				(width 0.1524)
				(type default)
			)
			(layer "F.SilkS")
		)
		(fp_line
			(start -38.760146 -29.009848)
			(end -37.810186 -29.009848)
			(stroke
				(width 0.1524)
				(type default)
			)
			(layer "F.SilkS")
		)
		(fp_line
			(start -40.999918 -29.000196)
			(end -39.500048 -30.500066)
			(stroke
				(width 0.1524)
				(type default)
			)
			(layer "F.SilkS")
		)
		(fp_line
			(start 37.810186 -28.999942)
			(end 37.810186 -28.300172)
			(stroke
				(width 0.1524)
				(type default)
			)
			(layer "F.SilkS")
		)
		(fp_line
			(start 37.809932 -28.999942)
			(end 37.809932 -28.299918)
			(stroke
				(width 0.1524)
				(type default)
			)
			(layer "F.SilkS")
		)
		(fp_line
			(start -32.999934 -28.999942)
			(end -33.199832 -28.999942)
			(stroke
				(width 0.1524)
				(type default)
			)
			(layer "F.SilkS")
		)
		(fp_line
			(start -33.000188 -28.999942)
			(end -33.200086 -28.999942)
			(stroke
				(width 0.1524)
				(type default)
			)
			(layer "F.SilkS")
		)
		(fp_line
			(start -33.199832 -28.999942)
			(end -35.809936 -28.999942)
			(stroke
				(width 0.1524)
				(type default)
			)
			(layer "F.SilkS")
		)
		(fp_line
			(start -33.200086 -28.999942)
			(end -35.81019 -28.999942)
			(stroke
				(width 0.1524)
				(type default)
			)
			(layer "F.SilkS")
		)
		(fp_line
			(start -35.809936 -28.999942)
			(end -35.809936 -28.300172)
			(stroke
				(width 0.1524)
				(type default)
			)
			(layer "F.SilkS")
		)
		(fp_line
			(start -35.81019 -28.999942)
			(end -35.81019 -28.299918)
			(stroke
				(width 0.1524)
				(type default)
			)
			(layer "F.SilkS")
		)
		(fp_line
			(start -40.999918 -28.999942)
			(end -39.500048 -30.500066)
			(stroke
				(width 0.1524)
				(type default)
			)
			(layer "F.SilkS")
		)
		(fp_line
			(start -40.999918 -28.999942)
			(end -40.999918 -12.499848)
			(stroke
				(width 0.1524)
				(type default)
			)
			(layer "F.SilkS")
		)
		(fp_line
			(start -41.000172 -28.999942)
			(end -39.500048 -30.499812)
			(stroke
				(width 0.1524)
				(type default)
			)
			(layer "F.SilkS")
		)
		(fp_line
			(start -41.000172 -28.999942)
			(end -41.000172 -12.499848)
			(stroke
				(width 0.1524)
				(type default)
			)
			(layer "F.SilkS")
		)
		(fp_line
			(start 30.209998 -28.450032)
			(end 30.209998 -30.500066)
			(stroke
				(width 0.1524)
				(type default)
			)
			(layer "F.SilkS")
		)
		(fp_line
			(start 30.209998 -28.450032)
			(end 30.209998 -30.499812)
			(stroke
				(width 0.1524)
				(type default)
			)
			(layer "F.SilkS")
		)
		(fp_line
			(start 37.810186 -28.300172)
			(end 37.810186 -29.009848)
			(stroke
				(width 0.1524)
				(type default)
			)
			(layer "F.SilkS")
		)
		(fp_line
			(start 35.81019 -28.300172)
			(end 35.81019 -28.999942)
			(stroke
				(width 0.1524)
				(type default)
			)
			(layer "F.SilkS")
		)
		(fp_line
			(start 35.81019 -28.300172)
			(end 37.810186 -28.300172)
			(stroke
				(width 0.1524)
				(type default)
			)
			(layer "F.SilkS")
		)
		(fp_line
			(start -35.809936 -28.300172)
			(end -37.809932 -28.300172)
			(stroke
				(width 0.1524)
				(type default)
			)
			(layer "F.SilkS")
		)
		(fp_line
			(start -37.809932 -28.300172)
			(end -37.809932 -28.999942)
			(stroke
				(width 0.1524)
				(type default)
			)
			(layer "F.SilkS")
		)
		(fp_line
			(start 38.800024 -28.299918)
			(end -38.800024 -28.299918)
			(stroke
				(width 0.1524)
				(type default)
			)
			(layer "F.SilkS")
		)
		(fp_line
			(start 37.809932 -28.299918)
			(end 37.809932 -29.009848)
			(stroke
				(width 0.1524)
				(type default)
			)
			(layer "F.SilkS")
		)
		(fp_line
			(start 35.809936 -28.299918)
			(end 35.809936 -28.999942)
			(stroke
				(width 0.1524)
				(type default)
			)
			(layer "F.SilkS")
		)
		(fp_line
			(start 35.809936 -28.299918)
			(end 37.809932 -28.299918)
			(stroke
				(width 0.1524)
				(type default)
			)
			(layer "F.SilkS")
		)
		(fp_line
			(start -35.81019 -28.299918)
			(end -37.810186 -28.299918)
			(stroke
				(width 0.1524)
				(type default)
			)
			(layer "F.SilkS")
		)
		(fp_line
			(start -37.810186 -28.299918)
			(end -37.810186 -28.999942)
			(stroke
				(width 0.1524)
				(type default)
			)
			(layer "F.SilkS")
		)
		(fp_line
			(start -38.800024 -28.299918)
			(end -38.800024 28.299918)
			(stroke
				(width 0.1524)
				(type default)
			)
			(layer "F.SilkS")
		)
		(fp_line
			(start 39.509954 -28.26004)
			(end 39.509954 -27.31008)
			(stroke
				(width 0.1524)
				(type default)
			)
			(layer "F.SilkS")
		)
		(fp_line
			(start 39.509954 -28.259786)
			(end 39.509954 -27.309826)
			(stroke
				(width 0.1524)
				(type default)
			)
			(layer "F.SilkS")
		)
		(fp_line
			(start 1.299972 -27.450034)
			(end -1.299718 -27.450034)
			(stroke
				(width 0.1524)
				(type default)
			)
			(layer "F.SilkS")
		)
		(fp_line
			(start -1.299718 -27.450034)
			(end -2.99974 -29.500068)
			(stroke
				(width 0.1524)
				(type default)
			)
			(layer "F.SilkS")
		)
		(fp_line
			(start 1.299972 -27.44978)
			(end -1.299972 -27.44978)
			(stroke
				(width 0.1524)
				(type default)
			)
			(layer "F.SilkS")
		)
		(fp_line
			(start -1.299972 -27.44978)
			(end -2.999994 -29.499814)
			(stroke
				(width 0.1524)
				(type default)
			)
			(layer "F.SilkS")
		)
		(fp_line
			(start -38.800024 -27.31008)
			(end -38.800024 -25.310084)
			(stroke
				(width 0.1524)
				(type default)
			)
			(layer "F.SilkS")
		)
		(fp_line
			(start -39.500048 -27.31008)
			(end -38.800024 -27.31008)
			(stroke
				(width 0.1524)
				(type default)
			)
			(layer "F.SilkS")
		)
		(fp_line
			(start -39.500048 -27.31008)
			(end -39.510208 -27.31008)
			(stroke
				(width 0.1524)
				(type default)
			)
			(layer "F.SilkS")
		)
		(fp_line
			(start -39.510208 -27.31008)
			(end -39.510208 -28.26004)
			(stroke
				(width 0.1524)
				(type default)
			)
			(layer "F.SilkS")
		)
		(fp_line
			(start 39.509954 -27.309826)
			(end 39.499794 -27.309826)
			(stroke
				(width 0.1524)
				(type default)
			)
			(layer "F.SilkS")
		)
		(fp_line
			(start 38.800024 -27.309826)
			(end 39.499794 -27.309826)
			(stroke
				(width 0.1524)
				(type default)
			)
			(layer "F.SilkS")
		)
		(fp_line
			(start -38.800024 -27.309826)
			(end -38.800024 -25.30983)
			(stroke
				(width 0.1524)
				(type default)
			)
			(layer "F.SilkS")
		)
		(fp_line
			(start -39.500048 -27.309826)
			(end -38.800024 -27.309826)
			(stroke
				(width 0.1524)
				(type default)
			)
			(layer "F.SilkS")
		)
		(fp_line
			(start -39.500048 -27.309826)
			(end -39.510208 -27.309826)
			(stroke
				(width 0.1524)
				(type default)
			)
			(layer "F.SilkS")
		)
		(fp_line
			(start -39.510208 -27.309826)
			(end -39.510208 -28.259786)
			(stroke
				(width 0.1524)
				(type default)
			)
			(layer "F.SilkS")
		)
		(fp_line
			(start 40.046402 -25.310084)
			(end 41.000172 -25.310084)
			(stroke
				(width 0.1524)
				(type default)
			)
			(layer "F.SilkS")
		)
		(fp_line
			(start 38.800278 -25.310084)
			(end 40.046402 -25.310084)
			(stroke
				(width 0.1524)
				(type default)
			)
			(layer "F.SilkS")
		)
		(fp_line
			(start -40.046656 -25.310084)
			(end -38.800024 -25.310084)
			(stroke
				(width 0.1524)
				(type default)
			)
			(layer "F.SilkS")
		)
		(fp_line
			(start -40.999918 -25.310084)
			(end -40.046656 -25.310084)
			(stroke
				(width 0.1524)
				(type default)
			)
			(layer "F.SilkS")
		)
		(fp_line
			(start 40.046402 -25.30983)
			(end 40.999918 -25.30983)
			(stroke
				(width 0.1524)
				(type default)
			)
			(layer "F.SilkS")
		)
		(fp_line
			(start 38.800024 -25.30983)
			(end 38.800024 -27.309826)
			(stroke
				(width 0.1524)
				(type default)
			)
			(layer "F.SilkS")
		)
		(fp_line
			(start 38.800024 -25.30983)
			(end 40.046402 -25.30983)
			(stroke
				(width 0.1524)
				(type default)
			)
			(layer "F.SilkS")
		)
		(fp_line
			(start -40.046656 -25.30983)
			(end -38.800024 -25.30983)
			(stroke
				(width 0.1524)
				(type default)
			)
			(layer "F.SilkS")
		)
		(fp_line
			(start -41.000172 -25.30983)
			(end -40.046656 -25.30983)
			(stroke
				(width 0.1524)
				(type default)
			)
			(layer "F.SilkS")
		)
		(fp_line
			(start 41.000172 -12.499848)
			(end 41.000172 -30.500066)
			(stroke
				(width 0.1524)
				(type default)
			)
			(layer "F.SilkS")
		)
		(fp_line
			(start 40.999918 -12.499848)
			(end 40.999918 -30.499812)
			(stroke
				(width 0.1524)
				(type default)
			)
			(layer "F.SilkS")
		)
		(fp_line
			(start -40.999918 -12.499848)
			(end -39.99992 -8.000238)
			(stroke
				(width 0.1524)
				(type default)
			)
			(layer "F.SilkS")
		)
		(fp_line
			(start -41.000172 -12.499848)
			(end -40.000174 -7.999984)
			(stroke
				(width 0.1524)
				(type default)
			)
			(layer "F.SilkS")
		)
		(fp_line
			(start 10.363454 -8.419846)
			(end -15.24635 -8.419846)
			(stroke
				(width 0.1524)
				(type default)
			)
			(layer "F.SilkS")
		)
		(fp_line
			(start 10.363454 -8.419846)
			(end 10.363454 -3.797808)
			(stroke
				(width 0.1524)
				(type default)
			)
			(layer "F.SilkS")
		)
		(fp_line
			(start 40.000174 -8.000238)
			(end 41.000172 -12.499848)
			(stroke
				(width 0.1524)
				(type default)
			)
			(layer "F.SilkS")
		)
		(fp_line
			(start -39.99992 -8.000238)
			(end -39.99992 -2.62509)
			(stroke
				(width 0.1524)
				(type default)
			)
			(layer "F.SilkS")
		)
		(fp_line
			(start 39.99992 -7.999984)
			(end 40.999918 -12.499848)
			(stroke
				(width 0.1524)
				(type default)
			)
			(layer "F.SilkS")
		)
		(fp_line
			(start -40.000174 -7.999984)
			(end -40.000174 -2.624836)
			(stroke
				(width 0.1524)
				(type default)
			)
			(layer "F.SilkS")
		)
		(fp_line
			(start -15.24635 -3.797808)
			(end -15.24635 -8.419846)
			(stroke
				(width 0.1524)
				(type default)
			)
			(layer "F.SilkS")
		)
		(fp_line
			(start -15.24635 -3.797808)
			(end 10.363454 -3.797808)
			(stroke
				(width 0.1524)
				(type default)
			)
			(layer "F.SilkS")
		)
		(fp_line
			(start 40.000174 -2.62509)
			(end 40.000174 -8.000238)
			(stroke
				(width 0.1524)
				(type default)
			)
			(layer "F.SilkS")
		)
		(fp_line
			(start -39.99992 -2.62509)
			(end -37.999924 -1.550162)
			(stroke
				(width 0.1524)
				(type default)
			)
			(layer "F.SilkS")
		)
		(fp_line
			(start 39.99992 -2.624836)
			(end 39.99992 -7.999984)
			(stroke
				(width 0.1524)
				(type default)
			)
			(layer "F.SilkS")
		)
		(fp_line
			(start -40.000174 -2.624836)
			(end -38.000178 -1.549908)
			(stroke
				(width 0.1524)
				(type default)
			)
			(layer "F.SilkS")
		)
		(fp_line
			(start 38.000178 -1.550162)
			(end 40.000174 -2.62509)
			(stroke
				(width 0.1524)
				(type default)
			)
			(layer "F.SilkS")
		)
		(fp_line
			(start -37.999924 -1.550162)
			(end -37.999924 1.549908)
			(stroke
				(width 0.1524)
				(type default)
			)
			(layer "F.SilkS")
		)
		(fp_line
			(start 37.999924 -1.549908)
			(end 39.99992 -2.624836)
			(stroke
				(width 0.1524)
				(type default)
			)
			(layer "F.SilkS")
		)
		(fp_line
			(start -38.000178 -1.549908)
			(end -38.000178 1.550162)
			(stroke
				(width 0.1524)
				(type default)
			)
			(layer "F.SilkS")
		)
		(fp_line
			(start 38.000178 1.549908)
			(end 38.000178 -1.550162)
			(stroke
				(width 0.1524)
				(type default)
			)
			(layer "F.SilkS")
		)
		(fp_line
			(start -37.999924 1.549908)
			(end -39.99992 2.624836)
			(stroke
				(width 0.1524)
				(type default)
			)
			(layer "F.SilkS")
		)
		(fp_line
			(start 37.999924 1.550162)
			(end 37.999924 -1.549908)
			(stroke
				(width 0.1524)
				(type default)
			)
			(layer "F.SilkS")
		)
		(fp_line
			(start -38.000178 1.550162)
			(end -40.000174 2.62509)
			(stroke
				(width 0.1524)
				(type default)
			)
			(layer "F.SilkS")
		)
		(fp_line
			(start 40.000174 2.624836)
			(end 38.000178 1.549908)
			(stroke
				(width 0.1524)
				(type default)
			)
			(layer "F.SilkS")
		)
		(fp_line
			(start -39.99992 2.624836)
			(end -39.99992 7.99973)
			(stroke
				(width 0.1524)
				(type default)
			)
			(layer "F.SilkS")
		)
		(fp_line
			(start 39.99992 2.62509)
			(end 37.999924 1.550162)
			(stroke
				(width 0.1524)
				(type default)
			)
			(layer "F.SilkS")
		)
		(fp_line
			(start -40.000174 2.62509)
			(end -40.000174 7.999984)
			(stroke
				(width 0.1524)
				(type default)
			)
			(layer "F.SilkS")
		)
		(fp_line
			(start 10.363454 3.797554)
			(end -15.24635 3.797554)
			(stroke
				(width 0.1524)
				(type default)
			)
			(layer "F.SilkS")
		)
		(fp_line
			(start 10.363454 3.797554)
			(end 10.363454 8.419592)
			(stroke
				(width 0.1524)
				(type default)
			)
			(layer "F.SilkS")
		)
		(fp_line
			(start 40.000174 7.99973)
			(end 40.000174 2.624836)
			(stroke
				(width 0.1524)
				(type default)
			)
			(layer "F.SilkS")
		)
		(fp_line
			(start -39.99992 7.99973)
			(end -40.999918 12.499848)
			(stroke
				(width 0.1524)
				(type default)
			)
			(layer "F.SilkS")
		)
		(fp_line
			(start 39.99992 7.999984)
			(end 39.99992 2.62509)
			(stroke
				(width 0.1524)
				(type default)
			)
			(layer "F.SilkS")
		)
		(fp_line
			(start -40.000174 7.999984)
			(end -41.000172 12.500102)
			(stroke
				(width 0.1524)
				(type default)
			)
			(layer "F.SilkS")
		)
		(fp_line
			(start -15.24635 8.419592)
			(end -15.24635 3.797554)
			(stroke
				(width 0.1524)
				(type default)
			)
			(layer "F.SilkS")
		)
		(fp_line
			(start -15.24635 8.419592)
			(end 10.363454 8.419592)
			(stroke
				(width 0.1524)
				(type default)
			)
			(layer "F.SilkS")
		)
		(fp_line
			(start 41.000172 12.499848)
			(end 40.000174 7.99973)
			(stroke
				(width 0.1524)
				(type default)
			)
			(layer "F.SilkS")
		)
		(fp_line
			(start -40.999918 12.499848)
			(end -40.999918 30.499812)
			(stroke
				(width 0.1524)
				(type default)
			)
			(layer "F.SilkS")
		)
		(fp_line
			(start 40.999918 12.500102)
			(end 39.99992 7.999984)
			(stroke
				(width 0.1524)
				(type default)
			)
			(layer "F.SilkS")
		)
		(fp_line
			(start -41.000172 12.500102)
			(end -41.000172 30.500066)
			(stroke
				(width 0.1524)
				(type default)
			)
			(layer "F.SilkS")
		)
		(fp_line
			(start 41.000172 25.30983)
			(end 38.800278 25.30983)
			(stroke
				(width 0.1524)
				(type default)
			)
			(layer "F.SilkS")
		)
		(fp_line
			(start 38.800278 25.30983)
			(end 38.800278 27.309826)
			(stroke
				(width 0.1524)
				(type default)
			)
			(layer "F.SilkS")
		)
		(fp_line
			(start -39.500048 25.30983)
			(end -38.800024 25.30983)
			(stroke
				(width 0.1524)
				(type default)
			)
			(layer "F.SilkS")
		)
		(fp_line
			(start -39.500048 25.30983)
			(end -40.300148 25.30983)
			(stroke
				(width 0.1524)
				(type default)
			)
			(layer "F.SilkS")
		)
		(fp_line
			(start -40.046656 25.30983)
			(end -40.999918 25.30983)
			(stroke
				(width 0.1524)
				(type default)
			)
			(layer "F.SilkS")
		)
		(fp_line
			(start -40.999918 25.30983)
			(end -40.300148 25.30983)
			(stroke
				(width 0.1524)
				(type default)
			)
			(layer "F.SilkS")
		)
		(fp_line
			(start 40.999918 25.310084)
			(end 38.800024 25.310084)
			(stroke
				(width 0.1524)
				(type default)
			)
			(layer "F.SilkS")
		)
		(fp_line
			(start 38.800024 25.310084)
			(end 38.800024 27.31008)
			(stroke
				(width 0.1524)
				(type default)
			)
			(layer "F.SilkS")
		)
		(fp_line
			(start -39.500048 25.310084)
			(end -38.800024 25.310084)
			(stroke
				(width 0.1524)
				(type default)
			)
			(layer "F.SilkS")
		)
		(fp_line
			(start -39.500048 25.310084)
			(end -40.300148 25.310084)
			(stroke
				(width 0.1524)
				(type default)
			)
			(layer "F.SilkS")
		)
		(fp_line
			(start -40.046656 25.310084)
			(end -41.000172 25.310084)
			(stroke
				(width 0.1524)
				(type default)
			)
			(layer "F.SilkS")
		)
		(fp_line
			(start -41.000172 25.310084)
			(end -40.300148 25.310084)
			(stroke
				(width 0.1524)
				(type default)
			)
			(layer "F.SilkS")
		)
		(fp_line
			(start 38.800278 27.309826)
			(end 39.509954 27.309826)
			(stroke
				(width 0.1524)
				(type default)
			)
			(layer "F.SilkS")
		)
		(fp_line
			(start -38.800024 27.309826)
			(end -38.800024 25.30983)
			(stroke
				(width 0.1524)
				(type default)
			)
			(layer "F.SilkS")
		)
		(fp_line
			(start -39.510208 27.309826)
			(end -38.800024 27.309826)
			(stroke
				(width 0.1524)
				(type default)
			)
			(layer "F.SilkS")
		)
		(fp_line
			(start 38.800024 27.31008)
			(end 39.509954 27.31008)
			(stroke
				(width 0.1524)
				(type default)
			)
			(layer "F.SilkS")
		)
		(fp_line
			(start -38.800024 27.31008)
			(end -38.800024 25.310084)
			(stroke
				(width 0.1524)
				(type default)
			)
			(layer "F.SilkS")
		)
		(fp_line
			(start -39.510208 27.31008)
			(end -38.800024 27.31008)
			(stroke
				(width 0.1524)
				(type default)
			)
			(layer "F.SilkS")
		)
		(fp_line
			(start 1.299972 27.44978)
			(end 2.999994 29.499814)
			(stroke
				(width 0.1524)
				(type default)
			)
			(layer "F.SilkS")
		)
		(fp_line
			(start 1.299972 27.44978)
			(end 2.999994 29.500068)
			(stroke
				(width 0.1524)
				(type default)
			)
			(layer "F.SilkS")
		)
		(fp_line
			(start -1.299718 27.44978)
			(end 1.299972 27.44978)
			(stroke
				(width 0.1524)
				(type default)
			)
			(layer "F.SilkS")
		)
		(fp_line
			(start -1.299972 27.44978)
			(end 1.299972 27.44978)
			(stroke
				(width 0.1524)
				(type default)
			)
			(layer "F.SilkS")
		)
		(fp_line
			(start 39.509954 28.259786)
			(end 39.509954 27.309826)
			(stroke
				(width 0.1524)
				(type default)
			)
			(layer "F.SilkS")
		)
		(fp_line
			(start 39.509954 28.259786)
			(end 39.509954 27.31008)
			(stroke
				(width 0.1524)
				(type default)
			)
			(layer "F.SilkS")
		)
		(fp_line
			(start -39.510208 28.259786)
			(end -39.510208 27.309826)
			(stroke
				(width 0.1524)
				(type default)
			)
			(layer "F.SilkS")
		)
		(fp_line
			(start -39.510208 28.259786)
			(end -39.510208 27.31008)
			(stroke
				(width 0.1524)
				(type default)
			)
			(layer "F.SilkS")
		)
		(fp_line
			(start 38.800024 28.299918)
			(end 38.800024 -28.299918)
			(stroke
				(width 0.1524)
				(type default)
			)
			(layer "F.SilkS")
		)
		(fp_line
			(start 37.810186 28.299918)
			(end 35.81019 28.299918)
			(stroke
				(width 0.1524)
				(type default)
			)
			(layer "F.SilkS")
		)
		(fp_line
			(start 35.81019 28.299918)
			(end 35.81019 29.499814)
			(stroke
				(width 0.1524)
				(type default)
			)
			(layer "F.SilkS")
		)
		(fp_line
			(start -35.809936 28.299918)
			(end -37.809932 28.299918)
			(stroke
				(width 0.1524)
				(type default)
			)
			(layer "F.SilkS")
		)
		(fp_line
			(start -37.809932 28.299918)
			(end -37.809932 29.009848)
			(stroke
				(width 0.1524)
				(type default)
			)
			(layer "F.SilkS")
		)
		(fp_line
			(start -38.800024 28.299918)
			(end 38.800024 28.299918)
			(stroke
				(width 0.1524)
				(type default)
			)
			(layer "F.SilkS")
		)
		(fp_line
			(start 37.809932 28.300172)
			(end 35.809936 28.300172)
			(stroke
				(width 0.1524)
				(type default)
			)
			(layer "F.SilkS")
		)
		(fp_line
			(start 35.809936 28.300172)
			(end 35.809936 29.500068)
			(stroke
				(width 0.1524)
				(type default)
			)
			(layer "F.SilkS")
		)
		(fp_line
			(start -35.81019 28.300172)
			(end -37.810186 28.300172)
			(stroke
				(width 0.1524)
				(type default)
			)
			(layer "F.SilkS")
		)
		(fp_line
			(start -37.810186 28.300172)
			(end -37.810186 29.010102)
			(stroke
				(width 0.1524)
				(type default)
			)
			(layer "F.SilkS")
		)
		(fp_line
			(start 31.809944 28.449778)
			(end 31.809944 30.499812)
			(stroke
				(width 0.1524)
				(type default)
			)
			(layer "F.SilkS")
		)
		(fp_line
			(start 31.809944 28.450032)
			(end 31.809944 30.500066)
			(stroke
				(width 0.1524)
				(type default)
			)
			(layer "F.SilkS")
		)
		(fp_line
			(start -32.999934 28.999942)
			(end -32.999934 29.499814)
			(stroke
				(width 0.1524)
				(type default)
			)
			(layer "F.SilkS")
		)
		(fp_line
			(start -33.199832 28.999942)
			(end -32.999934 28.999942)
			(stroke
				(width 0.1524)
				(type default)
			)
			(layer "F.SilkS")
		)
		(fp_line
			(start -35.809936 28.999942)
			(end -35.809936 28.299918)
			(stroke
				(width 0.1524)
				(type default)
			)
			(layer "F.SilkS")
		)
		(fp_line
			(start -35.809936 28.999942)
			(end -33.199832 28.999942)
			(stroke
				(width 0.1524)
				(type default)
			)
			(layer "F.SilkS")
		)
		(fp_line
			(start -37.809932 28.999942)
			(end -37.809932 29.009848)
			(stroke
				(width 0.1524)
				(type default)
			)
			(layer "F.SilkS")
		)
		(fp_line
			(start -33.000188 29.000196)
			(end -33.000188 29.500068)
			(stroke
				(width 0.1524)
				(type default)
			)
			(layer "F.SilkS")
		)
		(fp_line
			(start -33.200086 29.000196)
			(end -33.000188 29.000196)
			(stroke
				(width 0.1524)
				(type default)
			)
			(layer "F.SilkS")
		)
		(fp_line
			(start -35.81019 29.000196)
			(end -35.81019 28.300172)
			(stroke
				(width 0.1524)
				(type default)
			)
			(layer "F.SilkS")
		)
		(fp_line
			(start -35.81019 29.000196)
			(end -33.200086 29.000196)
			(stroke
				(width 0.1524)
				(type default)
			)
			(layer "F.SilkS")
		)
		(fp_line
			(start -37.810186 29.000196)
			(end -37.810186 29.010102)
			(stroke
				(width 0.1524)
				(type default)
			)
			(layer "F.SilkS")
		)
		(fp_line
			(start 38.759892 29.009848)
			(end 37.810186 29.009848)
			(stroke
				(width 0.1524)
				(type default)
			)
			(layer "F.SilkS")
		)
		(fp_line
			(start 37.810186 29.009848)
			(end 37.810186 28.299918)
			(stroke
				(width 0.1524)
				(type default)
			)
			(layer "F.SilkS")
		)
		(fp_line
			(start -37.809932 29.009848)
			(end -38.760146 29.009848)
			(stroke
				(width 0.1524)
				(type default)
			)
			(layer "F.SilkS")
		)
		(fp_line
			(start 38.759892 29.010102)
			(end 37.809932 29.010102)
			(stroke
				(width 0.1524)
				(type default)
			)
			(layer "F.SilkS")
		)
		(fp_line
			(start 37.809932 29.010102)
			(end 37.809932 28.300172)
			(stroke
				(width 0.1524)
				(type default)
			)
			(layer "F.SilkS")
		)
		(fp_line
			(start -37.810186 29.010102)
			(end -38.760146 29.010102)
			(stroke
				(width 0.1524)
				(type default)
			)
			(layer "F.SilkS")
		)
		(fp_line
			(start 35.81019 29.499814)
			(end 35.81019 30.499812)
			(stroke
				(width 0.1524)
				(type default)
			)
			(layer "F.SilkS")
		)
		(fp_line
			(start 31.809944 29.499814)
			(end 35.81019 29.499814)
			(stroke
				(width 0.1524)
				(type default)
			)
			(layer "F.SilkS")
		)
		(fp_line
			(start 30.209998 29.499814)
			(end 30.209998 28.449778)
			(stroke
				(width 0.1524)
				(type default)
			)
			(layer "F.SilkS")
		)
		(fp_line
			(start 30.209998 29.499814)
			(end 30.209998 30.499812)
			(stroke
				(width 0.1524)
				(type default)
			)
			(layer "F.SilkS")
		)
		(fp_line
			(start 2.999994 29.499814)
			(end 30.209998 29.499814)
			(stroke
				(width 0.1524)
				(type default)
			)
			(layer "F.SilkS")
		)
		(fp_line
			(start -2.99974 29.499814)
			(end -1.299718 27.44978)
			(stroke
				(width 0.1524)
				(type default)
			)
			(layer "F.SilkS")
		)
		(fp_line
			(start -32.999934 29.499814)
			(end -2.99974 29.499814)
			(stroke
				(width 0.1524)
				(type default)
			)
			(layer "F.SilkS")
		)
		(fp_line
			(start 35.809936 29.500068)
			(end 35.809936 30.500066)
			(stroke
				(width 0.1524)
				(type default)
			)
			(layer "F.SilkS")
		)
		(fp_line
			(start 31.809944 29.500068)
			(end 35.809936 29.500068)
			(stroke
				(width 0.1524)
				(type default)
			)
			(layer "F.SilkS")
		)
		(fp_line
			(start 30.209998 29.500068)
			(end 30.209998 28.450032)
			(stroke
				(width 0.1524)
				(type default)
			)
			(layer "F.SilkS")
		)
		(fp_line
			(start 30.209998 29.500068)
			(end 30.209998 30.500066)
			(stroke
				(width 0.1524)
				(type default)
			)
			(layer "F.SilkS")
		)
		(fp_line
			(start 2.999994 29.500068)
			(end 30.209998 29.500068)
			(stroke
				(width 0.1524)
				(type default)
			)
			(layer "F.SilkS")
		)
		(fp_line
			(start -2.999994 29.500068)
			(end -1.299972 27.44978)
			(stroke
				(width 0.1524)
				(type default)
			)
			(layer "F.SilkS")
		)
		(fp_line
			(start -33.000188 29.500068)
			(end -2.999994 29.500068)
			(stroke
				(width 0.1524)
				(type default)
			)
			(layer "F.SilkS")
		)
		(fp_line
			(start 41.000172 30.499812)
			(end 41.000172 12.499848)
			(stroke
				(width 0.1524)
				(type default)
			)
			(layer "F.SilkS")
		)
		(fp_line
			(start 41.000172 30.499812)
			(end 40.000174 30.499812)
			(stroke
				(width 0.1524)
				(type default)
			)
			(layer "F.SilkS")
		)
		(fp_line
			(start 37.00018 30.499812)
			(end 35.81019 30.499812)
			(stroke
				(width 0.1524)
				(type default)
			)
			(layer "F.SilkS")
		)
		(fp_line
			(start 31.809944 30.499812)
			(end 31.809944 29.499814)
			(stroke
				(width 0.1524)
				(type default)
			)
			(layer "F.SilkS")
		)
		(fp_line
			(start 30.209998 30.499812)
			(end 31.809944 30.499812)
			(stroke
				(width 0.1524)
				(type default)
			)
			(layer "F.SilkS")
		)
		(fp_line
			(start -35.500056 30.499812)
			(end -35.809936 30.499812)
			(stroke
				(width 0.1524)
				(type default)
			)
			(layer "F.SilkS")
		)
		(fp_line
			(start -40.999918 30.499812)
			(end -35.809936 30.499812)
			(stroke
				(width 0.1524)
				(type default)
			)
			(layer "F.SilkS")
		)
		(fp_line
			(start 40.999918 30.500066)
			(end 40.999918 12.500102)
			(stroke
				(width 0.1524)
				(type default)
			)
			(layer "F.SilkS")
		)
		(fp_line
			(start 40.999918 30.500066)
			(end 39.99992 30.500066)
			(stroke
				(width 0.1524)
				(type default)
			)
			(layer "F.SilkS")
		)
		(fp_line
			(start 40.999918 30.500066)
			(end 39.997888 30.500066)
			(stroke
				(width 0.1524)
				(type default)
			)
			(layer "F.SilkS")
		)
		(fp_line
			(start 37.00145 30.500066)
			(end -32.999934 30.500066)
			(stroke
				(width 0.1524)
				(type default)
			)
			(layer "F.SilkS")
		)
		(fp_line
			(start 36.999926 30.500066)
			(end 35.809936 30.500066)
			(stroke
				(width 0.1524)
				(type default)
			)
			(layer "F.SilkS")
		)
		(fp_line
			(start 31.809944 30.500066)
			(end 31.809944 29.500068)
			(stroke
				(width 0.1524)
				(type default)
			)
			(layer "F.SilkS")
		)
		(fp_line
			(start 30.209998 30.500066)
			(end 31.809944 30.500066)
			(stroke
				(width 0.1524)
				(type default)
			)
			(layer "F.SilkS")
		)
		(fp_line
			(start -32.999934 30.500066)
			(end -33.000188 29.500068)
			(stroke
				(width 0.1524)
				(type default)
			)
			(layer "F.SilkS")
		)
		(fp_line
			(start -35.485832 30.500066)
			(end -40.999918 30.500066)
			(stroke
				(width 0.1524)
				(type default)
			)
			(layer "F.SilkS")
		)
		(fp_line
			(start -35.500056 30.500066)
			(end -35.81019 30.500066)
			(stroke
				(width 0.1524)
				(type default)
			)
			(layer "F.SilkS")
		)
		(fp_line
			(start -40.999918 30.500066)
			(end -40.999918 -29.000196)
			(stroke
				(width 0.1524)
				(type default)
			)
			(layer "F.SilkS")
		)
		(fp_line
			(start -41.000172 30.500066)
			(end -35.81019 30.500066)
			(stroke
				(width 0.1524)
				(type default)
			)
			(layer "F.SilkS")
		)
		(fp_line
			(start 39.499794 30.995112)
			(end 39.499794 32.250126)
			(stroke
				(width 0.1524)
				(type default)
			)
			(layer "F.SilkS")
		)
		(fp_line
			(start 39.499794 30.999938)
			(end 39.499794 32.249872)
			(stroke
				(width 0.1524)
				(type default)
			)
			(layer "F.SilkS")
		)
		(fp_line
			(start 39.499794 31.000192)
			(end 39.499794 32.249872)
			(stroke
				(width 0.1524)
				(type default)
			)
			(layer "F.SilkS")
		)
		(fp_line
			(start 39.499794 32.249872)
			(end 39.299896 32.249872)
			(stroke
				(width 0.1524)
				(type default)
			)
			(layer "F.SilkS")
		)
		(fp_line
			(start 39.499794 32.249872)
			(end 39.299896 32.249872)
			(stroke
				(width 0.1524)
				(type default)
			)
			(layer "F.SilkS")
		)
		(fp_line
			(start 39.299896 32.249872)
			(end 37.69995 32.249872)
			(stroke
				(width 0.1524)
				(type default)
			)
			(layer "F.SilkS")
		)
		(fp_line
			(start 39.299896 32.249872)
			(end 37.69995 32.249872)
			(stroke
				(width 0.1524)
				(type default)
			)
			(layer "F.SilkS")
		)
		(fp_line
			(start 37.69995 32.249872)
			(end 37.499798 32.249872)
			(stroke
				(width 0.1524)
				(type default)
			)
			(layer "F.SilkS")
		)
		(fp_line
			(start 37.69995 32.249872)
			(end 37.499798 32.249872)
			(stroke
				(width 0.1524)
				(type default)
			)
			(layer "F.SilkS")
		)
		(fp_line
			(start 37.499798 32.249872)
			(end 37.499798 30.999938)
			(stroke
				(width 0.1524)
				(type default)
			)
			(layer "F.SilkS")
		)
		(fp_line
			(start 37.499798 32.249872)
			(end 37.499798 31.000192)
			(stroke
				(width 0.1524)
				(type default)
			)
			(layer "F.SilkS")
		)
		(fp_line
			(start -30.80004 32.249872)
			(end -30.80004 30.500066)
			(stroke
				(width 0.1524)
				(type default)
			)
			(layer "F.SilkS")
		)
		(fp_line
			(start -30.80004 32.249872)
			(end -33.199832 32.249872)
			(stroke
				(width 0.1524)
				(type default)
			)
			(layer "F.SilkS")
		)
		(fp_line
			(start -32.999934 32.249872)
			(end -35.000184 32.249872)
			(stroke
				(width 0.1524)
				(type default)
			)
			(layer "F.SilkS")
		)
		(fp_line
			(start -33.000188 32.249872)
			(end -33.200086 32.249872)
			(stroke
				(width 0.1524)
				(type default)
			)
			(layer "F.SilkS")
		)
		(fp_line
			(start -33.199832 32.249872)
			(end -34.800032 32.249872)
			(stroke
				(width 0.1524)
				(type default)
			)
			(layer "F.SilkS")
		)
		(fp_line
			(start -33.200086 32.249872)
			(end -34.800032 32.249872)
			(stroke
				(width 0.1524)
				(type default)
			)
			(layer "F.SilkS")
		)
		(fp_line
			(start -34.800032 32.249872)
			(end -34.99993 32.249872)
			(stroke
				(width 0.1524)
				(type default)
			)
			(layer "F.SilkS")
		)
		(fp_line
			(start -34.800032 32.249872)
			(end -35.000184 32.249872)
			(stroke
				(width 0.1524)
				(type default)
			)
			(layer "F.SilkS")
		)
		(fp_line
			(start -34.99993 32.249872)
			(end -34.99993 30.999938)
			(stroke
				(width 0.1524)
				(type default)
			)
			(layer "F.SilkS")
		)
		(fp_line
			(start -35.000184 32.249872)
			(end -35.000184 30.994858)
			(stroke
				(width 0.1524)
				(type default)
			)
			(layer "F.SilkS")
		)
		(fp_line
			(start -35.000184 32.249872)
			(end -35.000184 31.000192)
			(stroke
				(width 0.1524)
				(type default)
			)
			(layer "F.SilkS")
		)
		(fp_line
			(start 39.499794 32.250126)
			(end 37.499798 32.250126)
			(stroke
				(width 0.1524)
				(type default)
			)
			(layer "F.SilkS")
		)
		(fp_line
			(start 37.499798 32.250126)
			(end 37.499798 30.995874)
			(stroke
				(width 0.1524)
				(type default)
			)
			(layer "F.SilkS")
		)
		(fp_arc
			(start 37.499798 -31.000192)
			(mid 37.354103 -30.647199)
			(end 37.001704 -30.500066)
			(stroke
				(width 0.1524)
				(type default)
			)
			(layer "F.SilkS")
		)
		(fp_arc
			(start 37.499798 -31.000192)
			(mid 37.353565 -30.646659)
			(end 37.00018 -30.500066)
			(stroke
				(width 0.1524)
				(type default)
			)
			(layer "F.SilkS")
		)
		(fp_arc
			(start -34.99993 -31.000192)
			(mid -35.146397 -30.646513)
			(end -35.500056 -30.500066)
			(stroke
				(width 0.1524)
				(type default)
			)
			(layer "F.SilkS")
		)
		(fp_arc
			(start -35.000184 -31.000192)
			(mid -35.144768 -30.64821)
			(end -35.49523 -30.500066)
			(stroke
				(width 0.1524)
				(type default)
			)
			(layer "F.SilkS")
		)
		(fp_arc
			(start 37.499798 -30.999938)
			(mid 37.353398 -30.646409)
			(end 36.999926 -30.499812)
			(stroke
				(width 0.1524)
				(type default)
			)
			(layer "F.SilkS")
		)
		(fp_arc
			(start -35.000184 -30.999938)
			(mid -35.146583 -30.646402)
			(end -35.500056 -30.499812)
			(stroke
				(width 0.1524)
				(type default)
			)
			(layer "F.SilkS")
		)
		(fp_arc
			(start 40.000174 -30.500066)
			(mid 39.646383 -30.646462)
			(end 39.499794 -31.000192)
			(stroke
				(width 0.1524)
				(type default)
			)
			(layer "F.SilkS")
		)
		(fp_arc
			(start 39.998396 -30.500066)
			(mid 39.64728 -30.645564)
			(end 39.499794 -30.995874)
			(stroke
				(width 0.1524)
				(type default)
			)
			(layer "F.SilkS")
		)
		(fp_arc
			(start 39.99992 -30.499812)
			(mid 39.646274 -30.646295)
			(end 39.499794 -30.999938)
			(stroke
				(width 0.1524)
				(type default)
			)
			(layer "F.SilkS")
		)
		(fp_arc
			(start 38.759892 -29.009848)
			(mid 39.290231 -28.790314)
			(end 39.509954 -28.26004)
			(stroke
				(width 0.1524)
				(type default)
			)
			(layer "F.SilkS")
		)
		(fp_arc
			(start 38.759892 -29.009848)
			(mid 39.290297 -28.790172)
			(end 39.509954 -28.259786)
			(stroke
				(width 0.1524)
				(type default)
			)
			(layer "F.SilkS")
		)
		(fp_arc
			(start 31.809944 -28.450032)
			(mid 31.01002 -27.650024)
			(end 30.209998 -28.450032)
			(stroke
				(width 0.1524)
				(type default)
			)
			(layer "F.SilkS")
		)
		(fp_arc
			(start 31.809944 -28.450032)
			(mid 31.01002 -27.650024)
			(end 30.209998 -28.450032)
			(stroke
				(width 0.1524)
				(type default)
			)
			(layer "F.SilkS")
		)
		(fp_arc
			(start -39.510208 -28.26004)
			(mid -39.290415 -28.790213)
			(end -38.760146 -29.009848)
			(stroke
				(width 0.1524)
				(type default)
			)
			(layer "F.SilkS")
		)
		(fp_arc
			(start -39.510208 -28.259786)
			(mid -39.290504 -28.790123)
			(end -38.760146 -29.009848)
			(stroke
				(width 0.1524)
				(type default)
			)
			(layer "F.SilkS")
		)
		(fp_arc
			(start 39.509954 28.259786)
			(mid 39.290346 28.790251)
			(end 38.759892 29.009848)
			(stroke
				(width 0.1524)
				(type default)
			)
			(layer "F.SilkS")
		)
		(fp_arc
			(start 39.509954 28.259786)
			(mid 39.290358 28.790322)
			(end 38.759892 29.010102)
			(stroke
				(width 0.1524)
				(type default)
			)
			(layer "F.SilkS")
		)
		(fp_arc
			(start 30.209998 28.449778)
			(mid 31.01002 27.64993)
			(end 31.809944 28.449778)
			(stroke
				(width 0.1524)
				(type default)
			)
			(layer "F.SilkS")
		)
		(fp_arc
			(start 30.209998 28.450032)
			(mid 31.01002 27.65013)
			(end 31.809944 28.450032)
			(stroke
				(width 0.1524)
				(type default)
			)
			(layer "F.SilkS")
		)
		(fp_arc
			(start -38.760146 29.009848)
			(mid -39.290554 28.790174)
			(end -39.510208 28.259786)
			(stroke
				(width 0.1524)
				(type default)
			)
			(layer "F.SilkS")
		)
		(fp_arc
			(start -38.760146 29.010102)
			(mid -39.290627 28.790335)
			(end -39.510208 28.259786)
			(stroke
				(width 0.1524)
				(type default)
			)
			(layer "F.SilkS")
		)
		(fp_arc
			(start 37.00018 30.499812)
			(mid 37.353553 30.646405)
			(end 37.499798 30.999938)
			(stroke
				(width 0.1524)
				(type default)
			)
			(layer "F.SilkS")
		)
		(fp_arc
			(start -35.500056 30.499812)
			(mid -35.146424 30.646303)
			(end -34.99993 30.999938)
			(stroke
				(width 0.1524)
				(type default)
			)
			(layer "F.SilkS")
		)
		(fp_arc
			(start 37.00145 30.500066)
			(mid 37.352434 30.645636)
			(end 37.499798 30.995874)
			(stroke
				(width 0.1524)
				(type default)
			)
			(layer "F.SilkS")
		)
		(fp_arc
			(start 36.999926 30.500066)
			(mid 37.35348 30.646566)
			(end 37.499798 31.000192)
			(stroke
				(width 0.1524)
				(type default)
			)
			(layer "F.SilkS")
		)
		(fp_arc
			(start -35.485832 30.500066)
			(mid -35.143203 30.649491)
			(end -35.000184 30.994858)
			(stroke
				(width 0.1524)
				(type default)
			)
			(layer "F.SilkS")
		)
		(fp_arc
			(start -35.500056 30.500066)
			(mid -35.146514 30.646573)
			(end -35.000184 31.000192)
			(stroke
				(width 0.1524)
				(type default)
			)
			(layer "F.SilkS")
		)
		(fp_arc
			(start 39.499794 30.995112)
			(mid 39.647216 30.645351)
			(end 39.997888 30.500066)
			(stroke
				(width 0.1524)
				(type default)
			)
			(layer "F.SilkS")
		)
		(fp_arc
			(start 39.499794 30.999938)
			(mid 39.646372 30.646215)
			(end 40.000174 30.499812)
			(stroke
				(width 0.1524)
				(type default)
			)
			(layer "F.SilkS")
		)
		(fp_arc
			(start 39.499794 31.000192)
			(mid 39.646263 30.646524)
			(end 39.99992 30.500066)
			(stroke
				(width 0.1524)
				(type default)
			)
			(layer "F.SilkS")
		)
		(fp_line
			(start 39.499794 -32.250126)
			(end 39.499794 -31.000192)
			(stroke
				(width 0.1)
				(type default)
			)
			(layer "F.Fab")
		)
		(fp_line
			(start 39.499794 -32.250126)
			(end 39.499794 -30.995874)
			(stroke
				(width 0.1)
				(type default)
			)
			(layer "F.Fab")
		)
		(fp_line
			(start 39.299896 -32.250126)
			(end 39.499794 -32.250126)
			(stroke
				(width 0.1)
				(type default)
			)
			(layer "F.Fab")
		)
		(fp_line
			(start 37.69995 -32.250126)
			(end 39.299896 -32.250126)
			(stroke
				(width 0.1)
				(type default)
			)
			(layer "F.Fab")
		)
		(fp_line
			(start 37.499798 -32.250126)
			(end 39.499794 -32.250126)
			(stroke
				(width 0.1)
				(type default)
			)
			(layer "F.Fab")
		)
		(fp_line
			(start 37.499798 -32.250126)
			(end 37.69995 -32.250126)
			(stroke
				(width 0.1)
				(type default)
			)
			(layer "F.Fab")
		)
		(fp_line
			(start -30.80004 -32.250126)
			(end -35.000184 -32.249872)
			(stroke
				(width 0.1)
				(type default)
			)
			(layer "F.Fab")
		)
		(fp_line
			(start -30.80004 -32.250126)
			(end -30.80004 -30.500066)
			(stroke
				(width 0.1)
				(type default)
			)
			(layer "F.Fab")
		)
		(fp_line
			(start -32.999934 -32.250126)
			(end -34.99993 -32.250126)
			(stroke
				(width 0.1)
				(type default)
			)
			(layer "F.Fab")
		)
		(fp_line
			(start -34.99993 -32.250126)
			(end -34.99993 -31.000192)
			(stroke
				(width 0.1)
				(type default)
			)
			(layer "F.Fab")
		)
		(fp_line
			(start -35.000184 -32.250126)
			(end -32.999934 -32.250126)
			(stroke
				(width 0.1)
				(type default)
			)
			(layer "F.Fab")
		)
		(fp_line
			(start 39.499794 -32.249872)
			(end 39.499794 -30.999938)
			(stroke
				(width 0.1)
				(type default)
			)
			(layer "F.Fab")
		)
		(fp_line
			(start 39.299896 -32.249872)
			(end 39.499794 -32.249872)
			(stroke
				(width 0.1)
				(type default)
			)
			(layer "F.Fab")
		)
		(fp_line
			(start 37.69995 -32.249872)
			(end 39.299896 -32.249872)
			(stroke
				(width 0.1)
				(type default)
			)
			(layer "F.Fab")
		)
		(fp_line
			(start 37.499798 -32.249872)
			(end 37.69995 -32.249872)
			(stroke
				(width 0.1)
				(type default)
			)
			(layer "F.Fab")
		)
		(fp_line
			(start -35.000184 -32.249872)
			(end -35.000184 -30.999938)
			(stroke
				(width 0.1)
				(type default)
			)
			(layer "F.Fab")
		)
		(fp_line
			(start 37.499798 -31.000192)
			(end 37.499798 -32.250126)
			(stroke
				(width 0.1)
				(type default)
			)
			(layer "F.Fab")
		)
		(fp_line
			(start 37.499798 -31.000192)
			(end 37.499798 -32.250126)
			(stroke
				(width 0.1)
				(type default)
			)
			(layer "F.Fab")
		)
		(fp_line
			(start -35.000184 -31.000192)
			(end -35.000184 -32.250126)
			(stroke
				(width 0.1)
				(type default)
			)
			(layer "F.Fab")
		)
		(fp_line
			(start 37.499798 -30.999938)
			(end 37.499798 -32.249872)
			(stroke
				(width 0.1)
				(type default)
			)
			(layer "F.Fab")
		)
		(fp_line
			(start 41.000172 -30.500066)
			(end 40.000174 -30.500066)
			(stroke
				(width 0.1)
				(type default)
			)
			(layer "F.Fab")
		)
		(fp_line
			(start 40.999918 -30.500066)
			(end 40.999918 30.500066)
			(stroke
				(width 0.1)
				(type default)
			)
			(layer "F.Fab")
		)
		(fp_line
			(start 39.998396 -30.500066)
			(end 40.999918 -30.500066)
			(stroke
				(width 0.1)
				(type default)
			)
			(layer "F.Fab")
		)
		(fp_line
			(start 37.00018 -30.500066)
			(end 35.81019 -30.500066)
			(stroke
				(width 0.1)
				(type default)
			)
			(layer "F.Fab")
		)
		(fp_line
			(start 35.81019 -30.500066)
			(end 35.81019 -29.500068)
			(stroke
				(width 0.1)
				(type default)
			)
			(layer "F.Fab")
		)
		(fp_line
			(start 31.809944 -30.500066)
			(end 30.209998 -30.500066)
			(stroke
				(width 0.1)
				(type default)
			)
			(layer "F.Fab")
		)
		(fp_line
			(start 30.209998 -30.500066)
			(end 30.209998 -29.500068)
			(stroke
				(width 0.1)
				(type default)
			)
			(layer "F.Fab")
		)
		(fp_line
			(start -32.999934 -30.500066)
			(end 37.001704 -30.500066)
			(stroke
				(width 0.1)
				(type default)
			)
			(layer "F.Fab")
		)
		(fp_line
			(start -35.809936 -30.500066)
			(end -35.500056 -30.500066)
			(stroke
				(width 0.1)
				(type default)
			)
			(layer "F.Fab")
		)
		(fp_line
			(start -39.500048 -30.500066)
			(end -35.49523 -30.500066)
			(stroke
				(width 0.1)
				(type default)
			)
			(layer "F.Fab")
		)
		(fp_line
			(start -39.500048 -30.500066)
			(end -35.809936 -30.500066)
			(stroke
				(width 0.1)
				(type default)
			)
			(layer "F.Fab")
		)
		(fp_line
			(start 40.999918 -30.499812)
			(end 39.99992 -30.499812)
			(stroke
				(width 0.1)
				(type default)
			)
			(layer "F.Fab")
		)
		(fp_line
			(start 36.999926 -30.499812)
			(end 35.809936 -30.499812)
			(stroke
				(width 0.1)
				(type default)
			)
			(layer "F.Fab")
		)
		(fp_line
			(start 35.809936 -30.499812)
			(end 35.809936 -29.499814)
			(stroke
				(width 0.1)
				(type default)
			)
			(layer "F.Fab")
		)
		(fp_line
			(start 31.809944 -30.499812)
			(end 30.209998 -30.499812)
			(stroke
				(width 0.1)
				(type default)
			)
			(layer "F.Fab")
		)
		(fp_line
			(start 30.209998 -30.499812)
			(end 30.209998 -29.499814)
			(stroke
				(width 0.1)
				(type default)
			)
			(layer "F.Fab")
		)
		(fp_line
			(start -35.81019 -30.499812)
			(end -35.500056 -30.499812)
			(stroke
				(width 0.1)
				(type default)
			)
			(layer "F.Fab")
		)
		(fp_line
			(start -39.500048 -30.499812)
			(end -35.81019 -30.499812)
			(stroke
				(width 0.1)
				(type default)
			)
			(layer "F.Fab")
		)
		(fp_line
			(start 35.81019 -29.800042)
			(end 35.81019 -28.999942)
			(stroke
				(width 0.1)
				(type default)
			)
			(layer "F.Fab")
		)
		(fp_line
			(start 35.809936 -29.799788)
			(end 35.809936 -28.999942)
			(stroke
				(width 0.1)
				(type default)
			)
			(layer "F.Fab")
		)
		(fp_line
			(start 35.81019 -29.500068)
			(end 31.809944 -29.500068)
			(stroke
				(width 0.1)
				(type default)
			)
			(layer "F.Fab")
		)
		(fp_line
			(start 31.809944 -29.500068)
			(end 31.809944 -30.500066)
			(stroke
				(width 0.1)
				(type default)
			)
			(layer "F.Fab")
		)
		(fp_line
			(start 31.809944 -29.500068)
			(end 31.809944 -28.450032)
			(stroke
				(width 0.1)
				(type default)
			)
			(layer "F.Fab")
		)
		(fp_line
			(start 30.209998 -29.500068)
			(end 2.999994 -29.500068)
			(stroke
				(width 0.1)
				(type default)
			)
			(layer "F.Fab")
		)
		(fp_line
			(start 2.999994 -29.500068)
			(end 1.299972 -27.450034)
			(stroke
				(width 0.1)
				(type default)
			)
			(layer "F.Fab")
		)
		(fp_line
			(start -2.99974 -29.500068)
			(end -32.999934 -29.500068)
			(stroke
				(width 0.1)
				(type default)
			)
			(layer "F.Fab")
		)
		(fp_line
			(start -32.999934 -29.500068)
			(end -32.999934 -30.500066)
			(stroke
				(width 0.1)
				(type default)
			)
			(layer "F.Fab")
		)
		(fp_line
			(start -32.999934 -29.500068)
			(end -32.999934 -28.999942)
			(stroke
				(width 0.1)
				(type default)
			)
			(layer "F.Fab")
		)
		(fp_line
			(start 35.809936 -29.499814)
			(end 31.809944 -29.499814)
			(stroke
				(width 0.1)
				(type default)
			)
			(layer "F.Fab")
		)
		(fp_line
			(start 31.809944 -29.499814)
			(end 31.809944 -30.499812)
			(stroke
				(width 0.1)
				(type default)
			)
			(layer "F.Fab")
		)
		(fp_line
			(start 31.809944 -29.499814)
			(end 31.809944 -28.450032)
			(stroke
				(width 0.1)
				(type default)
			)
			(layer "F.Fab")
		)
		(fp_line
			(start 30.209998 -29.499814)
			(end 2.999994 -29.499814)
			(stroke
				(width 0.1)
				(type default)
			)
			(layer "F.Fab")
		)
		(fp_line
			(start 2.999994 -29.499814)
			(end 1.299972 -27.44978)
			(stroke
				(width 0.1)
				(type default)
			)
			(layer "F.Fab")
		)
		(fp_line
			(start -2.999994 -29.499814)
			(end -33.000188 -29.499814)
			(stroke
				(width 0.1)
				(type default)
			)
			(layer "F.Fab")
		)
		(fp_line
			(start -33.000188 -29.499814)
			(end -33.000188 -28.999942)
			(stroke
				(width 0.1)
				(type default)
			)
			(layer "F.Fab")
		)
		(fp_line
			(start 37.810186 -29.009848)
			(end 38.759892 -29.009848)
			(stroke
				(width 0.1)
				(type default)
			)
			(layer "F.Fab")
		)
		(fp_line
			(start 37.809932 -29.009848)
			(end 38.759892 -29.009848)
			(stroke
				(width 0.1)
				(type default)
			)
			(layer "F.Fab")
		)
		(fp_line
			(start -38.760146 -29.009848)
			(end -37.809932 -29.009848)
			(stroke
				(width 0.1)
				(type default)
			)
			(layer "F.Fab")
		)
		(fp_line
			(start -38.760146 -29.009848)
			(end -37.810186 -29.009848)
			(stroke
				(width 0.1)
				(type default)
			)
			(layer "F.Fab")
		)
		(fp_line
			(start -40.999918 -29.000196)
			(end -39.500048 -30.500066)
			(stroke
				(width 0.1)
				(type default)
			)
			(layer "F.Fab")
		)
		(fp_line
			(start 37.810186 -28.999942)
			(end 37.810186 -28.300172)
			(stroke
				(width 0.1)
				(type default)
			)
			(layer "F.Fab")
		)
		(fp_line
			(start 37.809932 -28.999942)
			(end 37.809932 -28.299918)
			(stroke
				(width 0.1)
				(type default)
			)
			(layer "F.Fab")
		)
		(fp_line
			(start -32.999934 -28.999942)
			(end -33.199832 -28.999942)
			(stroke
				(width 0.1)
				(type default)
			)
			(layer "F.Fab")
		)
		(fp_line
			(start -33.000188 -28.999942)
			(end -33.200086 -28.999942)
			(stroke
				(width 0.1)
				(type default)
			)
			(layer "F.Fab")
		)
		(fp_line
			(start -33.199832 -28.999942)
			(end -35.809936 -28.999942)
			(stroke
				(width 0.1)
				(type default)
			)
			(layer "F.Fab")
		)
		(fp_line
			(start -33.200086 -28.999942)
			(end -35.81019 -28.999942)
			(stroke
				(width 0.1)
				(type default)
			)
			(layer "F.Fab")
		)
		(fp_line
			(start -35.809936 -28.999942)
			(end -35.809936 -28.300172)
			(stroke
				(width 0.1)
				(type default)
			)
			(layer "F.Fab")
		)
		(fp_line
			(start -35.81019 -28.999942)
			(end -35.81019 -28.299918)
			(stroke
				(width 0.1)
				(type default)
			)
			(layer "F.Fab")
		)
		(fp_line
			(start -40.999918 -28.999942)
			(end -39.500048 -30.500066)
			(stroke
				(width 0.1)
				(type default)
			)
			(layer "F.Fab")
		)
		(fp_line
			(start -40.999918 -28.999942)
			(end -40.999918 -12.499848)
			(stroke
				(width 0.1)
				(type default)
			)
			(layer "F.Fab")
		)
		(fp_line
			(start -41.000172 -28.999942)
			(end -39.500048 -30.499812)
			(stroke
				(width 0.1)
				(type default)
			)
			(layer "F.Fab")
		)
		(fp_line
			(start -41.000172 -28.999942)
			(end -41.000172 -12.499848)
			(stroke
				(width 0.1)
				(type default)
			)
			(layer "F.Fab")
		)
		(fp_line
			(start 30.209998 -28.450032)
			(end 30.209998 -30.500066)
			(stroke
				(width 0.1)
				(type default)
			)
			(layer "F.Fab")
		)
		(fp_line
			(start 30.209998 -28.450032)
			(end 30.209998 -30.499812)
			(stroke
				(width 0.1)
				(type default)
			)
			(layer "F.Fab")
		)
		(fp_line
			(start 37.810186 -28.300172)
			(end 37.810186 -29.009848)
			(stroke
				(width 0.1)
				(type default)
			)
			(layer "F.Fab")
		)
		(fp_line
			(start 35.81019 -28.300172)
			(end 35.81019 -28.999942)
			(stroke
				(width 0.1)
				(type default)
			)
			(layer "F.Fab")
		)
		(fp_line
			(start 35.81019 -28.300172)
			(end 37.810186 -28.300172)
			(stroke
				(width 0.1)
				(type default)
			)
			(layer "F.Fab")
		)
		(fp_line
			(start -35.809936 -28.300172)
			(end -37.809932 -28.300172)
			(stroke
				(width 0.1)
				(type default)
			)
			(layer "F.Fab")
		)
		(fp_line
			(start -37.809932 -28.300172)
			(end -37.809932 -28.999942)
			(stroke
				(width 0.1)
				(type default)
			)
			(layer "F.Fab")
		)
		(fp_line
			(start 38.800024 -28.299918)
			(end -38.800024 -28.299918)
			(stroke
				(width 0.1)
				(type default)
			)
			(layer "F.Fab")
		)
		(fp_line
			(start 37.809932 -28.299918)
			(end 37.809932 -29.009848)
			(stroke
				(width 0.1)
				(type default)
			)
			(layer "F.Fab")
		)
		(fp_line
			(start 35.809936 -28.299918)
			(end 35.809936 -28.999942)
			(stroke
				(width 0.1)
				(type default)
			)
			(layer "F.Fab")
		)
		(fp_line
			(start 35.809936 -28.299918)
			(end 37.809932 -28.299918)
			(stroke
				(width 0.1)
				(type default)
			)
			(layer "F.Fab")
		)
		(fp_line
			(start -35.81019 -28.299918)
			(end -37.810186 -28.299918)
			(stroke
				(width 0.1)
				(type default)
			)
			(layer "F.Fab")
		)
		(fp_line
			(start -37.810186 -28.299918)
			(end -37.810186 -28.999942)
			(stroke
				(width 0.1)
				(type default)
			)
			(layer "F.Fab")
		)
		(fp_line
			(start -38.800024 -28.299918)
			(end -38.800024 28.299918)
			(stroke
				(width 0.1)
				(type default)
			)
			(layer "F.Fab")
		)
		(fp_line
			(start 39.509954 -28.26004)
			(end 39.509954 -27.31008)
			(stroke
				(width 0.1)
				(type default)
			)
			(layer "F.Fab")
		)
		(fp_line
			(start 39.509954 -28.259786)
			(end 39.509954 -27.309826)
			(stroke
				(width 0.1)
				(type default)
			)
			(layer "F.Fab")
		)
		(fp_line
			(start 1.299972 -27.450034)
			(end -1.299718 -27.450034)
			(stroke
				(width 0.1)
				(type default)
			)
			(layer "F.Fab")
		)
		(fp_line
			(start -1.299718 -27.450034)
			(end -2.99974 -29.500068)
			(stroke
				(width 0.1)
				(type default)
			)
			(layer "F.Fab")
		)
		(fp_line
			(start 1.299972 -27.44978)
			(end -1.299972 -27.44978)
			(stroke
				(width 0.1)
				(type default)
			)
			(layer "F.Fab")
		)
		(fp_line
			(start -1.299972 -27.44978)
			(end -2.999994 -29.499814)
			(stroke
				(width 0.1)
				(type default)
			)
			(layer "F.Fab")
		)
		(fp_line
			(start -38.800024 -27.31008)
			(end -38.800024 -25.310084)
			(stroke
				(width 0.1)
				(type default)
			)
			(layer "F.Fab")
		)
		(fp_line
			(start -39.500048 -27.31008)
			(end -38.800024 -27.31008)
			(stroke
				(width 0.1)
				(type default)
			)
			(layer "F.Fab")
		)
		(fp_line
			(start -39.500048 -27.31008)
			(end -39.510208 -27.31008)
			(stroke
				(width 0.1)
				(type default)
			)
			(layer "F.Fab")
		)
		(fp_line
			(start -39.510208 -27.31008)
			(end -39.510208 -28.26004)
			(stroke
				(width 0.1)
				(type default)
			)
			(layer "F.Fab")
		)
		(fp_line
			(start 39.509954 -27.309826)
			(end 39.499794 -27.309826)
			(stroke
				(width 0.1)
				(type default)
			)
			(layer "F.Fab")
		)
		(fp_line
			(start 38.800024 -27.309826)
			(end 39.499794 -27.309826)
			(stroke
				(width 0.1)
				(type default)
			)
			(layer "F.Fab")
		)
		(fp_line
			(start -38.800024 -27.309826)
			(end -38.800024 -25.30983)
			(stroke
				(width 0.1)
				(type default)
			)
			(layer "F.Fab")
		)
		(fp_line
			(start -39.500048 -27.309826)
			(end -38.800024 -27.309826)
			(stroke
				(width 0.1)
				(type default)
			)
			(layer "F.Fab")
		)
		(fp_line
			(start -39.500048 -27.309826)
			(end -39.510208 -27.309826)
			(stroke
				(width 0.1)
				(type default)
			)
			(layer "F.Fab")
		)
		(fp_line
			(start -39.510208 -27.309826)
			(end -39.510208 -28.259786)
			(stroke
				(width 0.1)
				(type default)
			)
			(layer "F.Fab")
		)
		(fp_line
			(start 40.046402 -25.310084)
			(end 41.000172 -25.310084)
			(stroke
				(width 0.1)
				(type default)
			)
			(layer "F.Fab")
		)
		(fp_line
			(start 38.800278 -25.310084)
			(end 40.046402 -25.310084)
			(stroke
				(width 0.1)
				(type default)
			)
			(layer "F.Fab")
		)
		(fp_line
			(start -40.046656 -25.310084)
			(end -38.800024 -25.310084)
			(stroke
				(width 0.1)
				(type default)
			)
			(layer "F.Fab")
		)
		(fp_line
			(start -40.999918 -25.310084)
			(end -40.046656 -25.310084)
			(stroke
				(width 0.1)
				(type default)
			)
			(layer "F.Fab")
		)
		(fp_line
			(start 40.046402 -25.30983)
			(end 40.999918 -25.30983)
			(stroke
				(width 0.1)
				(type default)
			)
			(layer "F.Fab")
		)
		(fp_line
			(start 38.800024 -25.30983)
			(end 38.800024 -27.309826)
			(stroke
				(width 0.1)
				(type default)
			)
			(layer "F.Fab")
		)
		(fp_line
			(start 38.800024 -25.30983)
			(end 40.046402 -25.30983)
			(stroke
				(width 0.1)
				(type default)
			)
			(layer "F.Fab")
		)
		(fp_line
			(start -40.046656 -25.30983)
			(end -38.800024 -25.30983)
			(stroke
				(width 0.1)
				(type default)
			)
			(layer "F.Fab")
		)
		(fp_line
			(start -41.000172 -25.30983)
			(end -40.046656 -25.30983)
			(stroke
				(width 0.1)
				(type default)
			)
			(layer "F.Fab")
		)
		(fp_line
			(start 41.000172 -12.499848)
			(end 41.000172 -30.500066)
			(stroke
				(width 0.1)
				(type default)
			)
			(layer "F.Fab")
		)
		(fp_line
			(start 40.999918 -12.499848)
			(end 40.999918 -30.499812)
			(stroke
				(width 0.1)
				(type default)
			)
			(layer "F.Fab")
		)
		(fp_line
			(start -40.999918 -12.499848)
			(end -39.99992 -8.000238)
			(stroke
				(width 0.1)
				(type default)
			)
			(layer "F.Fab")
		)
		(fp_line
			(start -41.000172 -12.499848)
			(end -40.000174 -7.999984)
			(stroke
				(width 0.1)
				(type default)
			)
			(layer "F.Fab")
		)
		(fp_line
			(start 10.363454 -8.419846)
			(end -15.24635 -8.419846)
			(stroke
				(width 0.1)
				(type default)
			)
			(layer "F.Fab")
		)
		(fp_line
			(start 10.363454 -8.419846)
			(end 10.363454 -3.797808)
			(stroke
				(width 0.1)
				(type default)
			)
			(layer "F.Fab")
		)
		(fp_line
			(start 40.000174 -8.000238)
			(end 41.000172 -12.499848)
			(stroke
				(width 0.1)
				(type default)
			)
			(layer "F.Fab")
		)
		(fp_line
			(start -39.99992 -8.000238)
			(end -39.99992 -2.62509)
			(stroke
				(width 0.1)
				(type default)
			)
			(layer "F.Fab")
		)
		(fp_line
			(start 39.99992 -7.999984)
			(end 40.999918 -12.499848)
			(stroke
				(width 0.1)
				(type default)
			)
			(layer "F.Fab")
		)
		(fp_line
			(start -40.000174 -7.999984)
			(end -40.000174 -2.624836)
			(stroke
				(width 0.1)
				(type default)
			)
			(layer "F.Fab")
		)
		(fp_line
			(start -15.24635 -3.797808)
			(end -15.24635 -8.419846)
			(stroke
				(width 0.1)
				(type default)
			)
			(layer "F.Fab")
		)
		(fp_line
			(start -15.24635 -3.797808)
			(end 10.363454 -3.797808)
			(stroke
				(width 0.1)
				(type default)
			)
			(layer "F.Fab")
		)
		(fp_line
			(start 40.000174 -2.62509)
			(end 40.000174 -8.000238)
			(stroke
				(width 0.1)
				(type default)
			)
			(layer "F.Fab")
		)
		(fp_line
			(start -39.99992 -2.62509)
			(end -37.999924 -1.550162)
			(stroke
				(width 0.1)
				(type default)
			)
			(layer "F.Fab")
		)
		(fp_line
			(start 39.99992 -2.624836)
			(end 39.99992 -7.999984)
			(stroke
				(width 0.1)
				(type default)
			)
			(layer "F.Fab")
		)
		(fp_line
			(start -40.000174 -2.624836)
			(end -38.000178 -1.549908)
			(stroke
				(width 0.1)
				(type default)
			)
			(layer "F.Fab")
		)
		(fp_line
			(start 38.000178 -1.550162)
			(end 40.000174 -2.62509)
			(stroke
				(width 0.1)
				(type default)
			)
			(layer "F.Fab")
		)
		(fp_line
			(start -37.999924 -1.550162)
			(end -37.999924 1.549908)
			(stroke
				(width 0.1)
				(type default)
			)
			(layer "F.Fab")
		)
		(fp_line
			(start 37.999924 -1.549908)
			(end 39.99992 -2.624836)
			(stroke
				(width 0.1)
				(type default)
			)
			(layer "F.Fab")
		)
		(fp_line
			(start -38.000178 -1.549908)
			(end -38.000178 1.550162)
			(stroke
				(width 0.1)
				(type default)
			)
			(layer "F.Fab")
		)
		(fp_line
			(start 38.000178 1.549908)
			(end 38.000178 -1.550162)
			(stroke
				(width 0.1)
				(type default)
			)
			(layer "F.Fab")
		)
		(fp_line
			(start -37.999924 1.549908)
			(end -39.99992 2.624836)
			(stroke
				(width 0.1)
				(type default)
			)
			(layer "F.Fab")
		)
		(fp_line
			(start 37.999924 1.550162)
			(end 37.999924 -1.549908)
			(stroke
				(width 0.1)
				(type default)
			)
			(layer "F.Fab")
		)
		(fp_line
			(start -38.000178 1.550162)
			(end -40.000174 2.62509)
			(stroke
				(width 0.1)
				(type default)
			)
			(layer "F.Fab")
		)
		(fp_line
			(start 40.000174 2.624836)
			(end 38.000178 1.549908)
			(stroke
				(width 0.1)
				(type default)
			)
			(layer "F.Fab")
		)
		(fp_line
			(start -39.99992 2.624836)
			(end -39.99992 7.99973)
			(stroke
				(width 0.1)
				(type default)
			)
			(layer "F.Fab")
		)
		(fp_line
			(start 39.99992 2.62509)
			(end 37.999924 1.550162)
			(stroke
				(width 0.1)
				(type default)
			)
			(layer "F.Fab")
		)
		(fp_line
			(start -40.000174 2.62509)
			(end -40.000174 7.999984)
			(stroke
				(width 0.1)
				(type default)
			)
			(layer "F.Fab")
		)
		(fp_line
			(start 10.363454 3.797554)
			(end -15.24635 3.797554)
			(stroke
				(width 0.1)
				(type default)
			)
			(layer "F.Fab")
		)
		(fp_line
			(start 10.363454 3.797554)
			(end 10.363454 8.419592)
			(stroke
				(width 0.1)
				(type default)
			)
			(layer "F.Fab")
		)
		(fp_line
			(start 40.000174 7.99973)
			(end 40.000174 2.624836)
			(stroke
				(width 0.1)
				(type default)
			)
			(layer "F.Fab")
		)
		(fp_line
			(start -39.99992 7.99973)
			(end -40.999918 12.499848)
			(stroke
				(width 0.1)
				(type default)
			)
			(layer "F.Fab")
		)
		(fp_line
			(start 39.99992 7.999984)
			(end 39.99992 2.62509)
			(stroke
				(width 0.1)
				(type default)
			)
			(layer "F.Fab")
		)
		(fp_line
			(start -40.000174 7.999984)
			(end -41.000172 12.500102)
			(stroke
				(width 0.1)
				(type default)
			)
			(layer "F.Fab")
		)
		(fp_line
			(start -15.24635 8.419592)
			(end -15.24635 3.797554)
			(stroke
				(width 0.1)
				(type default)
			)
			(layer "F.Fab")
		)
		(fp_line
			(start -15.24635 8.419592)
			(end 10.363454 8.419592)
			(stroke
				(width 0.1)
				(type default)
			)
			(layer "F.Fab")
		)
		(fp_line
			(start 41.000172 12.499848)
			(end 40.000174 7.99973)
			(stroke
				(width 0.1)
				(type default)
			)
			(layer "F.Fab")
		)
		(fp_line
			(start -40.999918 12.499848)
			(end -40.999918 30.499812)
			(stroke
				(width 0.1)
				(type default)
			)
			(layer "F.Fab")
		)
		(fp_line
			(start 40.999918 12.500102)
			(end 39.99992 7.999984)
			(stroke
				(width 0.1)
				(type default)
			)
			(layer "F.Fab")
		)
		(fp_line
			(start -41.000172 12.500102)
			(end -41.000172 30.500066)
			(stroke
				(width 0.1)
				(type default)
			)
			(layer "F.Fab")
		)
		(fp_line
			(start 41.000172 25.30983)
			(end 38.800278 25.30983)
			(stroke
				(width 0.1)
				(type default)
			)
			(layer "F.Fab")
		)
		(fp_line
			(start 38.800278 25.30983)
			(end 38.800278 27.309826)
			(stroke
				(width 0.1)
				(type default)
			)
			(layer "F.Fab")
		)
		(fp_line
			(start -39.500048 25.30983)
			(end -38.800024 25.30983)
			(stroke
				(width 0.1)
				(type default)
			)
			(layer "F.Fab")
		)
		(fp_line
			(start -39.500048 25.30983)
			(end -40.300148 25.30983)
			(stroke
				(width 0.1)
				(type default)
			)
			(layer "F.Fab")
		)
		(fp_line
			(start -40.046656 25.30983)
			(end -40.999918 25.30983)
			(stroke
				(width 0.1)
				(type default)
			)
			(layer "F.Fab")
		)
		(fp_line
			(start -40.999918 25.30983)
			(end -40.300148 25.30983)
			(stroke
				(width 0.1)
				(type default)
			)
			(layer "F.Fab")
		)
		(fp_line
			(start 40.999918 25.310084)
			(end 38.800024 25.310084)
			(stroke
				(width 0.1)
				(type default)
			)
			(layer "F.Fab")
		)
		(fp_line
			(start 38.800024 25.310084)
			(end 38.800024 27.31008)
			(stroke
				(width 0.1)
				(type default)
			)
			(layer "F.Fab")
		)
		(fp_line
			(start -39.500048 25.310084)
			(end -38.800024 25.310084)
			(stroke
				(width 0.1)
				(type default)
			)
			(layer "F.Fab")
		)
		(fp_line
			(start -39.500048 25.310084)
			(end -40.300148 25.310084)
			(stroke
				(width 0.1)
				(type default)
			)
			(layer "F.Fab")
		)
		(fp_line
			(start -40.046656 25.310084)
			(end -41.000172 25.310084)
			(stroke
				(width 0.1)
				(type default)
			)
			(layer "F.Fab")
		)
		(fp_line
			(start -41.000172 25.310084)
			(end -40.300148 25.310084)
			(stroke
				(width 0.1)
				(type default)
			)
			(layer "F.Fab")
		)
		(fp_line
			(start 38.800278 27.309826)
			(end 39.509954 27.309826)
			(stroke
				(width 0.1)
				(type default)
			)
			(layer "F.Fab")
		)
		(fp_line
			(start -38.800024 27.309826)
			(end -38.800024 25.30983)
			(stroke
				(width 0.1)
				(type default)
			)
			(layer "F.Fab")
		)
		(fp_line
			(start -39.510208 27.309826)
			(end -38.800024 27.309826)
			(stroke
				(width 0.1)
				(type default)
			)
			(layer "F.Fab")
		)
		(fp_line
			(start 38.800024 27.31008)
			(end 39.509954 27.31008)
			(stroke
				(width 0.1)
				(type default)
			)
			(layer "F.Fab")
		)
		(fp_line
			(start -38.800024 27.31008)
			(end -38.800024 25.310084)
			(stroke
				(width 0.1)
				(type default)
			)
			(layer "F.Fab")
		)
		(fp_line
			(start -39.510208 27.31008)
			(end -38.800024 27.31008)
			(stroke
				(width 0.1)
				(type default)
			)
			(layer "F.Fab")
		)
		(fp_line
			(start 1.299972 27.44978)
			(end 2.999994 29.499814)
			(stroke
				(width 0.1)
				(type default)
			)
			(layer "F.Fab")
		)
		(fp_line
			(start 1.299972 27.44978)
			(end 2.999994 29.500068)
			(stroke
				(width 0.1)
				(type default)
			)
			(layer "F.Fab")
		)
		(fp_line
			(start -1.299718 27.44978)
			(end 1.299972 27.44978)
			(stroke
				(width 0.1)
				(type default)
			)
			(layer "F.Fab")
		)
		(fp_line
			(start -1.299972 27.44978)
			(end 1.299972 27.44978)
			(stroke
				(width 0.1)
				(type default)
			)
			(layer "F.Fab")
		)
		(fp_line
			(start 39.509954 28.259786)
			(end 39.509954 27.309826)
			(stroke
				(width 0.1)
				(type default)
			)
			(layer "F.Fab")
		)
		(fp_line
			(start 39.509954 28.259786)
			(end 39.509954 27.31008)
			(stroke
				(width 0.1)
				(type default)
			)
			(layer "F.Fab")
		)
		(fp_line
			(start -39.510208 28.259786)
			(end -39.510208 27.309826)
			(stroke
				(width 0.1)
				(type default)
			)
			(layer "F.Fab")
		)
		(fp_line
			(start -39.510208 28.259786)
			(end -39.510208 27.31008)
			(stroke
				(width 0.1)
				(type default)
			)
			(layer "F.Fab")
		)
		(fp_line
			(start 38.800024 28.299918)
			(end 38.800024 -28.299918)
			(stroke
				(width 0.1)
				(type default)
			)
			(layer "F.Fab")
		)
		(fp_line
			(start 37.810186 28.299918)
			(end 35.81019 28.299918)
			(stroke
				(width 0.1)
				(type default)
			)
			(layer "F.Fab")
		)
		(fp_line
			(start 35.81019 28.299918)
			(end 35.81019 29.499814)
			(stroke
				(width 0.1)
				(type default)
			)
			(layer "F.Fab")
		)
		(fp_line
			(start -35.809936 28.299918)
			(end -37.809932 28.299918)
			(stroke
				(width 0.1)
				(type default)
			)
			(layer "F.Fab")
		)
		(fp_line
			(start -37.809932 28.299918)
			(end -37.809932 29.009848)
			(stroke
				(width 0.1)
				(type default)
			)
			(layer "F.Fab")
		)
		(fp_line
			(start -38.800024 28.299918)
			(end 38.800024 28.299918)
			(stroke
				(width 0.1)
				(type default)
			)
			(layer "F.Fab")
		)
		(fp_line
			(start 37.809932 28.300172)
			(end 35.809936 28.300172)
			(stroke
				(width 0.1)
				(type default)
			)
			(layer "F.Fab")
		)
		(fp_line
			(start 35.809936 28.300172)
			(end 35.809936 29.500068)
			(stroke
				(width 0.1)
				(type default)
			)
			(layer "F.Fab")
		)
		(fp_line
			(start -35.81019 28.300172)
			(end -37.810186 28.300172)
			(stroke
				(width 0.1)
				(type default)
			)
			(layer "F.Fab")
		)
		(fp_line
			(start -37.810186 28.300172)
			(end -37.810186 29.010102)
			(stroke
				(width 0.1)
				(type default)
			)
			(layer "F.Fab")
		)
		(fp_line
			(start 31.809944 28.449778)
			(end 31.809944 30.499812)
			(stroke
				(width 0.1)
				(type default)
			)
			(layer "F.Fab")
		)
		(fp_line
			(start 31.809944 28.450032)
			(end 31.809944 30.500066)
			(stroke
				(width 0.1)
				(type default)
			)
			(layer "F.Fab")
		)
		(fp_line
			(start -32.999934 28.999942)
			(end -32.999934 29.499814)
			(stroke
				(width 0.1)
				(type default)
			)
			(layer "F.Fab")
		)
		(fp_line
			(start -33.199832 28.999942)
			(end -32.999934 28.999942)
			(stroke
				(width 0.1)
				(type default)
			)
			(layer "F.Fab")
		)
		(fp_line
			(start -35.809936 28.999942)
			(end -35.809936 28.299918)
			(stroke
				(width 0.1)
				(type default)
			)
			(layer "F.Fab")
		)
		(fp_line
			(start -35.809936 28.999942)
			(end -33.199832 28.999942)
			(stroke
				(width 0.1)
				(type default)
			)
			(layer "F.Fab")
		)
		(fp_line
			(start -37.809932 28.999942)
			(end -37.809932 29.009848)
			(stroke
				(width 0.1)
				(type default)
			)
			(layer "F.Fab")
		)
		(fp_line
			(start -33.200086 29.000196)
			(end -33.000188 29.000196)
			(stroke
				(width 0.1)
				(type default)
			)
			(layer "F.Fab")
		)
		(fp_line
			(start -35.81019 29.000196)
			(end -35.81019 28.300172)
			(stroke
				(width 0.1)
				(type default)
			)
			(layer "F.Fab")
		)
		(fp_line
			(start -35.81019 29.000196)
			(end -33.200086 29.000196)
			(stroke
				(width 0.1)
				(type default)
			)
			(layer "F.Fab")
		)
		(fp_line
			(start -37.810186 29.000196)
			(end -37.810186 29.010102)
			(stroke
				(width 0.1)
				(type default)
			)
			(layer "F.Fab")
		)
		(fp_line
			(start 38.759892 29.009848)
			(end 37.810186 29.009848)
			(stroke
				(width 0.1)
				(type default)
			)
			(layer "F.Fab")
		)
		(fp_line
			(start 37.810186 29.009848)
			(end 37.810186 28.299918)
			(stroke
				(width 0.1)
				(type default)
			)
			(layer "F.Fab")
		)
		(fp_line
			(start -37.809932 29.009848)
			(end -38.760146 29.009848)
			(stroke
				(width 0.1)
				(type default)
			)
			(layer "F.Fab")
		)
		(fp_line
			(start 38.759892 29.010102)
			(end 37.809932 29.010102)
			(stroke
				(width 0.1)
				(type default)
			)
			(layer "F.Fab")
		)
		(fp_line
			(start 37.809932 29.010102)
			(end 37.809932 28.300172)
			(stroke
				(width 0.1)
				(type default)
			)
			(layer "F.Fab")
		)
		(fp_line
			(start -37.810186 29.010102)
			(end -38.760146 29.010102)
			(stroke
				(width 0.1)
				(type default)
			)
			(layer "F.Fab")
		)
		(fp_line
			(start 35.81019 29.499814)
			(end 35.81019 30.499812)
			(stroke
				(width 0.1)
				(type default)
			)
			(layer "F.Fab")
		)
		(fp_line
			(start 31.809944 29.499814)
			(end 35.81019 29.499814)
			(stroke
				(width 0.1)
				(type default)
			)
			(layer "F.Fab")
		)
		(fp_line
			(start 30.209998 29.499814)
			(end 30.209998 28.449778)
			(stroke
				(width 0.1)
				(type default)
			)
			(layer "F.Fab")
		)
		(fp_line
			(start 30.209998 29.499814)
			(end 30.209998 30.499812)
			(stroke
				(width 0.1)
				(type default)
			)
			(layer "F.Fab")
		)
		(fp_line
			(start 2.999994 29.499814)
			(end 30.209998 29.499814)
			(stroke
				(width 0.1)
				(type default)
			)
			(layer "F.Fab")
		)
		(fp_line
			(start -2.99974 29.499814)
			(end -1.299718 27.44978)
			(stroke
				(width 0.1)
				(type default)
			)
			(layer "F.Fab")
		)
		(fp_line
			(start -32.999934 29.499814)
			(end -2.99974 29.499814)
			(stroke
				(width 0.1)
				(type default)
			)
			(layer "F.Fab")
		)
		(fp_line
			(start 35.809936 29.500068)
			(end 35.809936 30.500066)
			(stroke
				(width 0.1)
				(type default)
			)
			(layer "F.Fab")
		)
		(fp_line
			(start 31.809944 29.500068)
			(end 35.809936 29.500068)
			(stroke
				(width 0.1)
				(type default)
			)
			(layer "F.Fab")
		)
		(fp_line
			(start 30.209998 29.500068)
			(end 30.209998 28.450032)
			(stroke
				(width 0.1)
				(type default)
			)
			(layer "F.Fab")
		)
		(fp_line
			(start 30.209998 29.500068)
			(end 30.209998 30.500066)
			(stroke
				(width 0.1)
				(type default)
			)
			(layer "F.Fab")
		)
		(fp_line
			(start 2.999994 29.500068)
			(end 30.209998 29.500068)
			(stroke
				(width 0.1)
				(type default)
			)
			(layer "F.Fab")
		)
		(fp_line
			(start -2.999994 29.500068)
			(end -1.299972 27.44978)
			(stroke
				(width 0.1)
				(type default)
			)
			(layer "F.Fab")
		)
		(fp_line
			(start -33.000188 29.500068)
			(end -2.999994 29.500068)
			(stroke
				(width 0.1)
				(type default)
			)
			(layer "F.Fab")
		)
		(fp_line
			(start 41.000172 30.499812)
			(end 41.000172 12.499848)
			(stroke
				(width 0.1)
				(type default)
			)
			(layer "F.Fab")
		)
		(fp_line
			(start 41.000172 30.499812)
			(end 40.000174 30.499812)
			(stroke
				(width 0.1)
				(type default)
			)
			(layer "F.Fab")
		)
		(fp_line
			(start 37.00018 30.499812)
			(end 35.81019 30.499812)
			(stroke
				(width 0.1)
				(type default)
			)
			(layer "F.Fab")
		)
		(fp_line
			(start 31.809944 30.499812)
			(end 31.809944 29.499814)
			(stroke
				(width 0.1)
				(type default)
			)
			(layer "F.Fab")
		)
		(fp_line
			(start 30.209998 30.499812)
			(end 31.809944 30.499812)
			(stroke
				(width 0.1)
				(type default)
			)
			(layer "F.Fab")
		)
		(fp_line
			(start -35.500056 30.499812)
			(end -35.809936 30.499812)
			(stroke
				(width 0.1)
				(type default)
			)
			(layer "F.Fab")
		)
		(fp_line
			(start -40.999918 30.499812)
			(end -35.809936 30.499812)
			(stroke
				(width 0.1)
				(type default)
			)
			(layer "F.Fab")
		)
		(fp_line
			(start 40.999918 30.500066)
			(end 40.999918 12.500102)
			(stroke
				(width 0.1)
				(type default)
			)
			(layer "F.Fab")
		)
		(fp_line
			(start 40.999918 30.500066)
			(end 39.99992 30.500066)
			(stroke
				(width 0.1)
				(type default)
			)
			(layer "F.Fab")
		)
		(fp_line
			(start 40.999918 30.500066)
			(end 39.997888 30.500066)
			(stroke
				(width 0.1)
				(type default)
			)
			(layer "F.Fab")
		)
		(fp_line
			(start 37.00145 30.500066)
			(end -30.80004 30.500066)
			(stroke
				(width 0.1)
				(type default)
			)
			(layer "F.Fab")
		)
		(fp_line
			(start 36.999926 30.500066)
			(end 35.809936 30.500066)
			(stroke
				(width 0.1)
				(type default)
			)
			(layer "F.Fab")
		)
		(fp_line
			(start 31.809944 30.500066)
			(end 31.809944 29.500068)
			(stroke
				(width 0.1)
				(type default)
			)
			(layer "F.Fab")
		)
		(fp_line
			(start 30.209998 30.500066)
			(end 31.809944 30.500066)
			(stroke
				(width 0.1)
				(type default)
			)
			(layer "F.Fab")
		)
		(fp_line
			(start -30.80004 30.500066)
			(end -33.000188 30.500066)
			(stroke
				(width 0.1)
				(type default)
			)
			(layer "F.Fab")
		)
		(fp_line
			(start -30.80004 30.500066)
			(end -30.80004 32.249872)
			(stroke
				(width 0.1)
				(type default)
			)
			(layer "F.Fab")
		)
		(fp_line
			(start -33.000188 30.500066)
			(end -33.000188 29.000196)
			(stroke
				(width 0.1)
				(type default)
			)
			(layer "F.Fab")
		)
		(fp_line
			(start -35.485832 30.500066)
			(end -40.999918 30.500066)
			(stroke
				(width 0.1)
				(type default)
			)
			(layer "F.Fab")
		)
		(fp_line
			(start -35.500056 30.500066)
			(end -35.81019 30.500066)
			(stroke
				(width 0.1)
				(type default)
			)
			(layer "F.Fab")
		)
		(fp_line
			(start -40.999918 30.500066)
			(end -40.999918 -29.000196)
			(stroke
				(width 0.1)
				(type default)
			)
			(layer "F.Fab")
		)
		(fp_line
			(start -41.000172 30.500066)
			(end -35.81019 30.500066)
			(stroke
				(width 0.1)
				(type default)
			)
			(layer "F.Fab")
		)
		(fp_line
			(start 39.499794 30.995112)
			(end 39.499794 32.250126)
			(stroke
				(width 0.1)
				(type default)
			)
			(layer "F.Fab")
		)
		(fp_line
			(start 39.499794 30.999938)
			(end 39.499794 32.249872)
			(stroke
				(width 0.1)
				(type default)
			)
			(layer "F.Fab")
		)
		(fp_line
			(start 39.499794 31.000192)
			(end 39.499794 32.249872)
			(stroke
				(width 0.1)
				(type default)
			)
			(layer "F.Fab")
		)
		(fp_line
			(start 39.499794 32.249872)
			(end 39.299896 32.249872)
			(stroke
				(width 0.1)
				(type default)
			)
			(layer "F.Fab")
		)
		(fp_line
			(start 39.499794 32.249872)
			(end 39.299896 32.249872)
			(stroke
				(width 0.1)
				(type default)
			)
			(layer "F.Fab")
		)
		(fp_line
			(start 39.299896 32.249872)
			(end 37.69995 32.249872)
			(stroke
				(width 0.1)
				(type default)
			)
			(layer "F.Fab")
		)
		(fp_line
			(start 39.299896 32.249872)
			(end 37.69995 32.249872)
			(stroke
				(width 0.1)
				(type default)
			)
			(layer "F.Fab")
		)
		(fp_line
			(start 37.69995 32.249872)
			(end 37.499798 32.249872)
			(stroke
				(width 0.1)
				(type default)
			)
			(layer "F.Fab")
		)
		(fp_line
			(start 37.69995 32.249872)
			(end 37.499798 32.249872)
			(stroke
				(width 0.1)
				(type default)
			)
			(layer "F.Fab")
		)
		(fp_line
			(start 37.499798 32.249872)
			(end 37.499798 30.999938)
			(stroke
				(width 0.1)
				(type default)
			)
			(layer "F.Fab")
		)
		(fp_line
			(start 37.499798 32.249872)
			(end 37.499798 31.000192)
			(stroke
				(width 0.1)
				(type default)
			)
			(layer "F.Fab")
		)
		(fp_line
			(start -30.80004 32.249872)
			(end -35.000184 32.249872)
			(stroke
				(width 0.1)
				(type default)
			)
			(layer "F.Fab")
		)
		(fp_line
			(start -32.999934 32.249872)
			(end -33.199832 32.249872)
			(stroke
				(width 0.1)
				(type default)
			)
			(layer "F.Fab")
		)
		(fp_line
			(start -33.000188 32.249872)
			(end -33.200086 32.249872)
			(stroke
				(width 0.1)
				(type default)
			)
			(layer "F.Fab")
		)
		(fp_line
			(start -33.199832 32.249872)
			(end -34.800032 32.249872)
			(stroke
				(width 0.1)
				(type default)
			)
			(layer "F.Fab")
		)
		(fp_line
			(start -33.200086 32.249872)
			(end -34.800032 32.249872)
			(stroke
				(width 0.1)
				(type default)
			)
			(layer "F.Fab")
		)
		(fp_line
			(start -34.800032 32.249872)
			(end -34.99993 32.249872)
			(stroke
				(width 0.1)
				(type default)
			)
			(layer "F.Fab")
		)
		(fp_line
			(start -34.800032 32.249872)
			(end -35.000184 32.249872)
			(stroke
				(width 0.1)
				(type default)
			)
			(layer "F.Fab")
		)
		(fp_line
			(start -34.99993 32.249872)
			(end -34.99993 30.999938)
			(stroke
				(width 0.1)
				(type default)
			)
			(layer "F.Fab")
		)
		(fp_line
			(start -35.000184 32.249872)
			(end -35.000184 30.994858)
			(stroke
				(width 0.1)
				(type default)
			)
			(layer "F.Fab")
		)
		(fp_line
			(start -35.000184 32.249872)
			(end -35.000184 31.000192)
			(stroke
				(width 0.1)
				(type default)
			)
			(layer "F.Fab")
		)
		(fp_line
			(start 39.499794 32.250126)
			(end 37.499798 32.250126)
			(stroke
				(width 0.1)
				(type default)
			)
			(layer "F.Fab")
		)
		(fp_line
			(start 37.499798 32.250126)
			(end 37.499798 30.995874)
			(stroke
				(width 0.1)
				(type default)
			)
			(layer "F.Fab")
		)
		(fp_arc
			(start 37.499798 -31.000192)
			(mid 37.354103 -30.647199)
			(end 37.001704 -30.500066)
			(stroke
				(width 0.1)
				(type default)
			)
			(layer "F.Fab")
		)
		(fp_arc
			(start 37.499798 -31.000192)
			(mid 37.353565 -30.646659)
			(end 37.00018 -30.500066)
			(stroke
				(width 0.1)
				(type default)
			)
			(layer "F.Fab")
		)
		(fp_arc
			(start -34.99993 -31.000192)
			(mid -35.146397 -30.646513)
			(end -35.500056 -30.500066)
			(stroke
				(width 0.1)
				(type default)
			)
			(layer "F.Fab")
		)
		(fp_arc
			(start -35.000184 -31.000192)
			(mid -35.144768 -30.64821)
			(end -35.49523 -30.500066)
			(stroke
				(width 0.1)
				(type default)
			)
			(layer "F.Fab")
		)
		(fp_arc
			(start 37.499798 -30.999938)
			(mid 37.353398 -30.646409)
			(end 36.999926 -30.499812)
			(stroke
				(width 0.1)
				(type default)
			)
			(layer "F.Fab")
		)
		(fp_arc
			(start -35.000184 -30.999938)
			(mid -35.146583 -30.646402)
			(end -35.500056 -30.499812)
			(stroke
				(width 0.1)
				(type default)
			)
			(layer "F.Fab")
		)
		(fp_arc
			(start 40.000174 -30.500066)
			(mid 39.646383 -30.646462)
			(end 39.499794 -31.000192)
			(stroke
				(width 0.1)
				(type default)
			)
			(layer "F.Fab")
		)
		(fp_arc
			(start 39.998396 -30.500066)
			(mid 39.64728 -30.645564)
			(end 39.499794 -30.995874)
			(stroke
				(width 0.1)
				(type default)
			)
			(layer "F.Fab")
		)
		(fp_arc
			(start 39.99992 -30.499812)
			(mid 39.646274 -30.646295)
			(end 39.499794 -30.999938)
			(stroke
				(width 0.1)
				(type default)
			)
			(layer "F.Fab")
		)
		(fp_arc
			(start 38.759892 -29.009848)
			(mid 39.290231 -28.790314)
			(end 39.509954 -28.26004)
			(stroke
				(width 0.1)
				(type default)
			)
			(layer "F.Fab")
		)
		(fp_arc
			(start 38.759892 -29.009848)
			(mid 39.290297 -28.790172)
			(end 39.509954 -28.259786)
			(stroke
				(width 0.1)
				(type default)
			)
			(layer "F.Fab")
		)
		(fp_arc
			(start 31.809944 -28.450032)
			(mid 31.01002 -27.650024)
			(end 30.209998 -28.450032)
			(stroke
				(width 0.1)
				(type default)
			)
			(layer "F.Fab")
		)
		(fp_arc
			(start 31.809944 -28.450032)
			(mid 31.01002 -27.650024)
			(end 30.209998 -28.450032)
			(stroke
				(width 0.1)
				(type default)
			)
			(layer "F.Fab")
		)
		(fp_arc
			(start -39.510208 -28.26004)
			(mid -39.290415 -28.790213)
			(end -38.760146 -29.009848)
			(stroke
				(width 0.1)
				(type default)
			)
			(layer "F.Fab")
		)
		(fp_arc
			(start -39.510208 -28.259786)
			(mid -39.290504 -28.790123)
			(end -38.760146 -29.009848)
			(stroke
				(width 0.1)
				(type default)
			)
			(layer "F.Fab")
		)
		(fp_arc
			(start 39.509954 28.259786)
			(mid 39.290346 28.790251)
			(end 38.759892 29.009848)
			(stroke
				(width 0.1)
				(type default)
			)
			(layer "F.Fab")
		)
		(fp_arc
			(start 39.509954 28.259786)
			(mid 39.290358 28.790322)
			(end 38.759892 29.010102)
			(stroke
				(width 0.1)
				(type default)
			)
			(layer "F.Fab")
		)
		(fp_arc
			(start 30.209998 28.449778)
			(mid 31.01002 27.64993)
			(end 31.809944 28.449778)
			(stroke
				(width 0.1)
				(type default)
			)
			(layer "F.Fab")
		)
		(fp_arc
			(start 30.209998 28.450032)
			(mid 31.01002 27.65013)
			(end 31.809944 28.450032)
			(stroke
				(width 0.1)
				(type default)
			)
			(layer "F.Fab")
		)
		(fp_arc
			(start -38.760146 29.009848)
			(mid -39.290554 28.790174)
			(end -39.510208 28.259786)
			(stroke
				(width 0.1)
				(type default)
			)
			(layer "F.Fab")
		)
		(fp_arc
			(start -38.760146 29.010102)
			(mid -39.290627 28.790335)
			(end -39.510208 28.259786)
			(stroke
				(width 0.1)
				(type default)
			)
			(layer "F.Fab")
		)
		(fp_arc
			(start 37.00018 30.499812)
			(mid 37.353553 30.646405)
			(end 37.499798 30.999938)
			(stroke
				(width 0.1)
				(type default)
			)
			(layer "F.Fab")
		)
		(fp_arc
			(start -35.500056 30.499812)
			(mid -35.146424 30.646303)
			(end -34.99993 30.999938)
			(stroke
				(width 0.1)
				(type default)
			)
			(layer "F.Fab")
		)
		(fp_arc
			(start 37.00145 30.500066)
			(mid 37.352434 30.645636)
			(end 37.499798 30.995874)
			(stroke
				(width 0.1)
				(type default)
			)
			(layer "F.Fab")
		)
		(fp_arc
			(start 36.999926 30.500066)
			(mid 37.35348 30.646566)
			(end 37.499798 31.000192)
			(stroke
				(width 0.1)
				(type default)
			)
			(layer "F.Fab")
		)
		(fp_arc
			(start -35.485832 30.500066)
			(mid -35.143203 30.649491)
			(end -35.000184 30.994858)
			(stroke
				(width 0.1)
				(type default)
			)
			(layer "F.Fab")
		)
		(fp_arc
			(start -35.500056 30.500066)
			(mid -35.146514 30.646573)
			(end -35.000184 31.000192)
			(stroke
				(width 0.1)
				(type default)
			)
			(layer "F.Fab")
		)
		(fp_arc
			(start 39.499794 30.995112)
			(mid 39.647216 30.645351)
			(end 39.997888 30.500066)
			(stroke
				(width 0.1)
				(type default)
			)
			(layer "F.Fab")
		)
		(fp_arc
			(start 39.499794 30.999938)
			(mid 39.646372 30.646215)
			(end 40.000174 30.499812)
			(stroke
				(width 0.1)
				(type default)
			)
			(layer "F.Fab")
		)
		(fp_arc
			(start 39.499794 31.000192)
			(mid 39.646263 30.646524)
			(end 39.99992 30.500066)
			(stroke
				(width 0.1)
				(type default)
			)
			(layer "F.Fab")
		)
		(pad "A9" smd oval
			(at -30.914086 -27.074114 135)
			(size 0.381 0.4826)
			(drill
				(offset 0 -0.0508)
			)
			(layers "F.Cu" "F.Mask" "F.Paste")
			(net "M_A_CPU0_SB_DQS_DN<3>")
		)
		(pad "A11" smd oval
			(at -29.2862 -27.074114 90)
			(size 0.381 0.4826)
			(drill
				(offset 0 -0.0508)
			)
			(layers "F.Cu" "F.Mask" "F.Paste")
			(net "GND")
		)
		(pad "A13" smd oval
			(at -27.658314 -27.074114 90)
			(size 0.381 0.4826)
			(drill
				(offset 0 -0.0508)
			)
			(layers "F.Cu" "F.Mask" "F.Paste")
			(net "GND")
		)
		(pad "A15" smd oval
			(at -26.030682 -27.074114 90)
			(size 0.381 0.4826)
			(drill
				(offset 0 -0.0508)
			)
			(layers "F.Cu" "F.Mask" "F.Paste")
			(net "M_B_CPU0_SB_DQS_DN<3>")
		)
		(pad "A17" smd oval
			(at -24.402796 -27.074114 90)
			(size 0.381 0.4826)
			(drill
				(offset 0 -0.0508)
			)
			(layers "F.Cu" "F.Mask" "F.Paste")
			(net "GND")
		)
		(pad "A19" smd oval
			(at -22.77491 -27.074114 90)
			(size 0.381 0.4826)
			(drill
				(offset 0 -0.0508)
			)
			(layers "F.Cu" "F.Mask" "F.Paste")
			(net "GND")
		)
		(pad "A21" smd oval
			(at -21.147278 -27.074114 90)
			(size 0.381 0.4826)
			(drill
				(offset 0 -0.0508)
			)
			(layers "F.Cu" "F.Mask" "F.Paste")
			(net "M_A_CPU0_SB_DQS_DN<2>")
		)
		(pad "A23" smd oval
			(at -19.519392 -27.074114 90)
			(size 0.381 0.4826)
			(drill
				(offset 0 -0.0508)
			)
			(layers "F.Cu" "F.Mask" "F.Paste")
			(net "GND")
		)
		(pad "A25" smd oval
			(at -17.89176 -27.074114 90)
			(size 0.381 0.4826)
			(drill
				(offset 0 -0.0508)
			)
			(layers "F.Cu" "F.Mask" "F.Paste")
			(net "GND")
		)
		(pad "A27" smd oval
			(at -16.263874 -27.074114 90)
			(size 0.381 0.4826)
			(drill
				(offset 0 -0.0508)
			)
			(layers "F.Cu" "F.Mask" "F.Paste")
			(net "M_A_CPU0_SB_DQS_DN<1>")
		)
		(pad "A29" smd oval
			(at -14.635988 -27.074114 90)
			(size 0.381 0.4826)
			(drill
				(offset 0 -0.0508)
			)
			(layers "F.Cu" "F.Mask" "F.Paste")
			(net "GND")
		)
		(pad "A31" smd oval
			(at -13.008356 -27.074114 90)
			(size 0.381 0.4826)
			(drill
				(offset 0 -0.0508)
			)
			(layers "F.Cu" "F.Mask" "F.Paste")
			(net "GND")
		)
		(pad "A33" smd oval
			(at -11.380724 -27.074114 90)
			(size 0.381 0.4826)
			(drill
				(offset 0 -0.0508)
			)
			(layers "F.Cu" "F.Mask" "F.Paste")
			(net "M_A_CPU0_SB_DQS_DN<9>")
		)
		(pad "A35" smd oval
			(at -9.752838 -27.074114 90)
			(size 0.381 0.4826)
			(drill
				(offset 0 -0.0508)
			)
			(layers "F.Cu" "F.Mask" "F.Paste")
			(net "GND")
		)
		(pad "A37" smd oval
			(at -8.124952 -27.074114 90)
			(size 0.381 0.4826)
			(drill
				(offset 0 -0.0508)
			)
			(layers "F.Cu" "F.Mask" "F.Paste")
			(net "GND")
		)
		(pad "A39" smd oval
			(at -6.49732 -27.074114 90)
			(size 0.381 0.4826)
			(drill
				(offset 0 -0.0508)
			)
			(layers "F.Cu" "F.Mask" "F.Paste")
			(net "M_A_CPU0_SB_CA<6>")
		)
		(pad "A41" smd oval
			(at -4.869434 -27.074114 90)
			(size 0.381 0.4826)
			(drill
				(offset 0 -0.0508)
			)
			(layers "F.Cu" "F.Mask" "F.Paste")
			(net "GND")
		)
		(pad "A43" smd oval
			(at -3.241802 -27.074114 90)
			(size 0.381 0.4826)
			(drill
				(offset 0 -0.0508)
			)
			(layers "F.Cu" "F.Mask" "F.Paste")
			(net "PWRGD_DRAMPWRGD_CPU0_AB_LVC1_R")
		)
		(pad "A50" smd oval
			(at 4.055618 -26.964132 90)
			(size 0.381 0.4826)
			(drill
				(offset 0 -0.0508)
			)
			(layers "F.Cu" "F.Mask" "F.Paste")
			(net "GND")
		)
		(pad "A52" smd oval
			(at 5.68325 -26.964132 90)
			(size 0.381 0.4826)
			(drill
				(offset 0 -0.0508)
			)
			(layers "F.Cu" "F.Mask" "F.Paste")
			(net "M_A_CPU0_SA_CA<0>")
		)
		(pad "A54" smd oval
			(at 7.311136 -26.964132 90)
			(size 0.381 0.4826)
			(drill
				(offset 0 -0.0508)
			)
			(layers "F.Cu" "F.Mask" "F.Paste")
			(net "GND")
		)
		(pad "A56" smd oval
			(at 8.939022 -26.964132 90)
			(size 0.381 0.4826)
			(drill
				(offset 0 -0.0508)
			)
			(layers "F.Cu" "F.Mask" "F.Paste")
			(net "GND")
		)
		(pad "A58" smd oval
			(at 10.566654 -26.964132 90)
			(size 0.381 0.4826)
			(drill
				(offset 0 -0.0508)
			)
			(layers "F.Cu" "F.Mask" "F.Paste")
			(net "M_A_CPU0_SA_DQS_DN<4>")
		)
		(pad "A60" smd oval
			(at 12.19454 -26.964132 90)
			(size 0.381 0.4826)
			(drill
				(offset 0 -0.0508)
			)
			(layers "F.Cu" "F.Mask" "F.Paste")
			(net "GND")
		)
		(pad "A62" smd oval
			(at 13.822426 -26.964132 90)
			(size 0.381 0.4826)
			(drill
				(offset 0 -0.0508)
			)
			(layers "F.Cu" "F.Mask" "F.Paste")
			(net "GND")
		)
		(pad "A64" smd oval
			(at 15.450058 -26.964132 90)
			(size 0.381 0.4826)
			(drill
				(offset 0 -0.0508)
			)
			(layers "F.Cu" "F.Mask" "F.Paste")
			(net "M_A_CPU0_SA_DQS_DN<3>")
		)
		(pad "AA1" smd oval
			(at -37.425122 -17.676114 180)
			(size 0.381 0.4826)
			(drill
				(offset 0 -0.0508)
			)
			(layers "F.Cu" "F.Mask" "F.Paste")
			(net "UPI_CPU0_CPU1_P0P1_DN<6>")
		)
		(pad "AA3" smd circle
			(at -35.797236 -17.676114 270)
			(size 0.4318 0.4318)
			(layers "F.Cu" "F.Mask" "F.Paste")
			(net "PVCCFA_EHV_CPU0")
		)
		(pad "AA5" smd circle
			(at -34.169604 -17.676114 270)
			(size 0.4318 0.4318)
			(layers "F.Cu" "F.Mask" "F.Paste")
			(net "UPI_CPU1_CPU0_P1P0_DP<5>")
		)
		(pad "AA7" smd circle
			(at -32.541718 -17.676114 270)
			(size 0.4318 0.4318)
			(layers "F.Cu" "F.Mask" "F.Paste")
			(net "PVCCFA_EHV_FIVRA_CPU0")
		)
		(pad "AA9" smd circle
			(at -30.914086 -17.676114 270)
			(size 0.4318 0.4318)
			(layers "F.Cu" "F.Mask" "F.Paste")
			(net "P5E_CPU0_PE0_RX_DN<5>")
		)
		(pad "AA11" smd circle
			(at -29.2862 -17.676114 270)
			(size 0.4318 0.4318)
			(layers "F.Cu" "F.Mask" "F.Paste")
			(net "PVCCFA_EHV_FIVRA_CPU0")
		)
		(pad "AA13" smd circle
			(at -27.658314 -17.676114 270)
			(size 0.4318 0.4318)
			(layers "F.Cu" "F.Mask" "F.Paste")
			(net "P5E_CPU0_PE0_TX_DN<4>")
		)
		(pad "AA15" smd circle
			(at -26.030682 -17.676114 270)
			(size 0.4318 0.4318)
			(layers "F.Cu" "F.Mask" "F.Paste")
			(net "PVCCFA_EHV_FIVRA_CPU0")
		)
		(pad "AA17" smd circle
			(at -24.402796 -17.676114 270)
			(size 0.4318 0.4318)
			(layers "F.Cu" "F.Mask" "F.Paste")
			(net "M_C_CPU0_SB_DQ<28>")
		)
		(pad "AA19" smd circle
			(at -22.77491 -17.676114 270)
			(size 0.4318 0.4318)
			(layers "F.Cu" "F.Mask" "F.Paste")
			(net "GND")
		)
		(pad "AA21" smd circle
			(at -21.147278 -17.676114 270)
			(size 0.4318 0.4318)
			(layers "F.Cu" "F.Mask" "F.Paste")
			(net "M_C_CPU0_SB_DQS_DP<7>")
		)
		(pad "AA23" smd circle
			(at -19.519392 -17.676114 270)
			(size 0.4318 0.4318)
			(layers "F.Cu" "F.Mask" "F.Paste")
			(net "GND")
		)
		(pad "AA25" smd circle
			(at -17.89176 -17.676114 270)
			(size 0.4318 0.4318)
			(layers "F.Cu" "F.Mask" "F.Paste")
			(net "GND")
		)
		(pad "AA27" smd circle
			(at -16.263874 -17.676114 270)
			(size 0.4318 0.4318)
			(layers "F.Cu" "F.Mask" "F.Paste")
			(net "M_B_CPU0_SB_DQS_DP<5>")
		)
		(pad "AA29" smd circle
			(at -14.635988 -17.676114 270)
			(size 0.4318 0.4318)
			(layers "F.Cu" "F.Mask" "F.Paste")
			(net "GND")
		)
		(pad "AA31" smd circle
			(at -13.008356 -17.676114 270)
			(size 0.4318 0.4318)
			(layers "F.Cu" "F.Mask" "F.Paste")
			(net "GND")
		)
		(pad "AA33" smd circle
			(at -11.380724 -17.676114 270)
			(size 0.4318 0.4318)
			(layers "F.Cu" "F.Mask" "F.Paste")
			(net "M_C_CPU0_SB_DQS_DP<4>")
		)
		(pad "AA35" smd circle
			(at -9.752838 -17.676114 270)
			(size 0.4318 0.4318)
			(layers "F.Cu" "F.Mask" "F.Paste")
			(net "GND")
		)
		(pad "AA37" smd circle
			(at -8.124952 -17.676114 270)
			(size 0.4318 0.4318)
			(layers "F.Cu" "F.Mask" "F.Paste")
			(net "GND")
		)
		(pad "AA39" smd circle
			(at -6.49732 -17.676114 270)
			(size 0.4318 0.4318)
			(layers "F.Cu" "F.Mask" "F.Paste")
			(net "M_C_CPU0_SB_PAR")
		)
		(pad "AA41" smd circle
			(at -4.869434 -17.676114 270)
			(size 0.4318 0.4318)
			(layers "F.Cu" "F.Mask" "F.Paste")
			(net "GND")
		)
		(pad "AA43" smd circle
			(at -3.241802 -17.676114 270)
			(size 0.4318 0.4318)
			(layers "F.Cu" "F.Mask" "F.Paste")
			(net "GND")
		)
		(pad "AA45" smd circle
			(at -1.613916 -17.676114 270)
			(size 0.4318 0.4318)
			(layers "F.Cu" "F.Mask" "F.Paste")
			(net "M_B_CPU0_CLK_DP<1>")
		)
		(pad "AA48" smd circle
			(at 2.427732 -17.566132 270)
			(size 0.4318 0.4318)
			(layers "F.Cu" "F.Mask" "F.Paste")
			(net "GND")
		)
		(pad "AA50" smd circle
			(at 4.055618 -17.566132 270)
			(size 0.4318 0.4318)
			(layers "F.Cu" "F.Mask" "F.Paste")
			(net "GND")
		)
		(pad "AA52" smd circle
			(at 5.68325 -17.566132 270)
			(size 0.4318 0.4318)
			(layers "F.Cu" "F.Mask" "F.Paste")
			(net "M_C_CPU0_SA_CA<1>")
		)
		(pad "AA54" smd circle
			(at 7.311136 -17.566132 270)
			(size 0.4318 0.4318)
			(layers "F.Cu" "F.Mask" "F.Paste")
			(net "GND")
		)
		(pad "AA56" smd circle
			(at 8.939022 -17.566132 270)
			(size 0.4318 0.4318)
			(layers "F.Cu" "F.Mask" "F.Paste")
			(net "GND")
		)
		(pad "AA58" smd circle
			(at 10.566654 -17.566132 270)
			(size 0.4318 0.4318)
			(layers "F.Cu" "F.Mask" "F.Paste")
			(net "M_B_CPU0_SA_DQS_DN<8>")
		)
		(pad "AA60" smd circle
			(at 12.19454 -17.566132 270)
			(size 0.4318 0.4318)
			(layers "F.Cu" "F.Mask" "F.Paste")
			(net "GND")
		)
		(pad "AA62" smd circle
			(at 13.822426 -17.566132 270)
			(size 0.4318 0.4318)
			(layers "F.Cu" "F.Mask" "F.Paste")
			(net "GND")
		)
		(pad "AA64" smd circle
			(at 15.450058 -17.566132 270)
			(size 0.4318 0.4318)
			(layers "F.Cu" "F.Mask" "F.Paste")
			(net "M_C_CPU0_SA_DQS_DN<7>")
		)
		(pad "AA66" smd circle
			(at 17.07769 -17.566132 270)
			(size 0.4318 0.4318)
			(layers "F.Cu" "F.Mask" "F.Paste")
			(net "GND")
		)
		(pad "AA68" smd circle
			(at 18.705576 -17.566132 270)
			(size 0.4318 0.4318)
			(layers "F.Cu" "F.Mask" "F.Paste")
			(net "GND")
		)
		(pad "AA70" smd circle
			(at 20.333462 -17.566132 270)
			(size 0.4318 0.4318)
			(layers "F.Cu" "F.Mask" "F.Paste")
			(net "M_B_CPU0_SA_DQS_DN<6>")
		)
		(pad "AA72" smd circle
			(at 21.961094 -17.566132 270)
			(size 0.4318 0.4318)
			(layers "F.Cu" "F.Mask" "F.Paste")
			(net "GND")
		)
		(pad "AA74" smd circle
			(at 23.58898 -17.566132 270)
			(size 0.4318 0.4318)
			(layers "F.Cu" "F.Mask" "F.Paste")
			(net "GND")
		)
		(pad "AA76" smd circle
			(at 25.216612 -17.566132 270)
			(size 0.4318 0.4318)
			(layers "F.Cu" "F.Mask" "F.Paste")
			(net "M_C_CPU0_SA_DQS_DP<5>")
		)
		(pad "AA78" smd circle
			(at 26.844498 -17.566132 270)
			(size 0.4318 0.4318)
			(layers "F.Cu" "F.Mask" "F.Paste")
			(net "GND")
		)
		(pad "AA80" smd circle
			(at 28.472384 -17.566132 270)
			(size 0.4318 0.4318)
			(layers "F.Cu" "F.Mask" "F.Paste")
			(net "GND")
		)
		(pad "AA82" smd circle
			(at 30.100016 -17.566132 270)
			(size 0.4318 0.4318)
			(layers "F.Cu" "F.Mask" "F.Paste")
			(net "GND")
		)
		(pad "AA84" smd circle
			(at 31.727902 -17.566132 270)
			(size 0.4318 0.4318)
			(layers "F.Cu" "F.Mask" "F.Paste")
			(net "GND")
		)
		(pad "AA86" smd circle
			(at 33.355534 -17.566132 270)
			(size 0.4318 0.4318)
			(layers "F.Cu" "F.Mask" "F.Paste")
			(net "P5E_CPU0_PE4_TX_DN<5>")
		)
		(pad "AA88" smd circle
			(at 34.98342 -17.566132 270)
			(size 0.4318 0.4318)
			(layers "F.Cu" "F.Mask" "F.Paste")
			(net "GND")
		)
		(pad "AA90" smd circle
			(at 36.611306 -17.566132 270)
			(size 0.4318 0.4318)
			(layers "F.Cu" "F.Mask" "F.Paste")
			(net "P5E_CPU0_PE4_RX_DP<5>")
		)
		(pad "AB2" smd circle
			(at -36.611306 -17.206468 270)
			(size 0.4318 0.4318)
			(layers "F.Cu" "F.Mask" "F.Paste")
			(net "UPI_CPU0_CPU1_P0P1_DP<6>")
		)
		(pad "AB4" smd circle
			(at -34.98342 -17.206468 270)
			(size 0.4318 0.4318)
			(layers "F.Cu" "F.Mask" "F.Paste")
			(net "GND")
		)
		(pad "AB6" smd circle
			(at -33.355534 -17.206468 270)
			(size 0.4318 0.4318)
			(layers "F.Cu" "F.Mask" "F.Paste")
			(net "UPI_CPU1_CPU0_P1P0_DN<6>")
		)
		(pad "AB8" smd circle
			(at -31.727902 -17.206468 270)
			(size 0.4318 0.4318)
			(layers "F.Cu" "F.Mask" "F.Paste")
			(net "GND")
		)
		(pad "AB10" smd circle
			(at -30.100016 -17.206468 270)
			(size 0.4318 0.4318)
			(layers "F.Cu" "F.Mask" "F.Paste")
			(net "P5E_CPU0_PE0_RX_DN<6>")
		)
		(pad "AB12" smd circle
			(at -28.472384 -17.206468 270)
			(size 0.4318 0.4318)
			(layers "F.Cu" "F.Mask" "F.Paste")
			(net "GND")
		)
		(pad "AB14" smd circle
			(at -26.844498 -17.206468 270)
			(size 0.4318 0.4318)
			(layers "F.Cu" "F.Mask" "F.Paste")
			(net "P5E_CPU0_PE0_TX_DN<5>")
		)
		(pad "AB16" smd circle
			(at -25.216612 -17.206468 270)
			(size 0.4318 0.4318)
			(layers "F.Cu" "F.Mask" "F.Paste")
			(net "GND")
		)
		(pad "AB18" smd circle
			(at -23.58898 -17.206468 270)
			(size 0.4318 0.4318)
			(layers "F.Cu" "F.Mask" "F.Paste")
			(net "M_C_CPU0_SB_DQS_DN<3>")
		)
		(pad "AB20" smd circle
			(at -21.961094 -17.206468 270)
			(size 0.4318 0.4318)
			(layers "F.Cu" "F.Mask" "F.Paste")
			(net "GND")
		)
		(pad "AB22" smd circle
			(at -20.333462 -17.206468 270)
			(size 0.4318 0.4318)
			(layers "F.Cu" "F.Mask" "F.Paste")
			(net "GND")
		)
		(pad "AB24" smd circle
			(at -18.705576 -17.206468 270)
			(size 0.4318 0.4318)
			(layers "F.Cu" "F.Mask" "F.Paste")
			(net "M_D_CPU0_SB_DQS_DN<2>")
		)
		(pad "AB26" smd circle
			(at -17.07769 -17.206468 270)
			(size 0.4318 0.4318)
			(layers "F.Cu" "F.Mask" "F.Paste")
			(net "GND")
		)
		(pad "AB28" smd circle
			(at -15.450058 -17.206468 270)
			(size 0.4318 0.4318)
			(layers "F.Cu" "F.Mask" "F.Paste")
			(net "GND")
		)
		(pad "AB30" smd circle
			(at -13.822426 -17.206468 270)
			(size 0.4318 0.4318)
			(layers "F.Cu" "F.Mask" "F.Paste")
			(net "M_C_CPU0_SB_DQS_DN<1>")
		)
		(pad "AB32" smd circle
			(at -12.19454 -17.206468 270)
			(size 0.4318 0.4318)
			(layers "F.Cu" "F.Mask" "F.Paste")
			(net "GND")
		)
		(pad "AB34" smd circle
			(at -10.566654 -17.206468 270)
			(size 0.4318 0.4318)
			(layers "F.Cu" "F.Mask" "F.Paste")
			(net "GND")
		)
		(pad "AB36" smd circle
			(at -8.939022 -17.206468 270)
			(size 0.4318 0.4318)
			(layers "F.Cu" "F.Mask" "F.Paste")
			(net "M_C_CPU0_SB_DQS_DN<0>")
		)
		(pad "AB38" smd circle
			(at -7.311136 -17.206468 270)
			(size 0.4318 0.4318)
			(layers "F.Cu" "F.Mask" "F.Paste")
			(net "GND")
		)
		(pad "AB40" smd circle
			(at -5.68325 -17.206468 270)
			(size 0.4318 0.4318)
			(layers "F.Cu" "F.Mask" "F.Paste")
			(net "GND")
		)
		(pad "AB42" smd circle
			(at -4.055618 -17.206468 270)
			(size 0.4318 0.4318)
			(layers "F.Cu" "F.Mask" "F.Paste")
			(net "M_D_CPU0_SB_CA<6>")
		)
		(pad "AB44" smd circle
			(at -2.427732 -17.206468 270)
			(size 0.4318 0.4318)
			(layers "F.Cu" "F.Mask" "F.Paste")
			(net "GND")
		)
		(pad "AB47" smd circle
			(at 1.613916 -17.096486 270)
			(size 0.4318 0.4318)
			(layers "F.Cu" "F.Mask" "F.Paste")
			(net "GND")
		)
		(pad "AB49" smd circle
			(at 3.241802 -17.096486 270)
			(size 0.4318 0.4318)
			(layers "F.Cu" "F.Mask" "F.Paste")
			(net "M_C_CPU0_CLK_DN<0>")
		)
		(pad "AB51" smd circle
			(at 4.869434 -17.096486 270)
			(size 0.4318 0.4318)
			(layers "F.Cu" "F.Mask" "F.Paste")
			(net "GND")
		)
		(pad "AB53" smd circle
			(at 6.49732 -17.096486 270)
			(size 0.4318 0.4318)
			(layers "F.Cu" "F.Mask" "F.Paste")
			(net "GND")
		)
		(pad "AB55" smd circle
			(at 8.124952 -17.096486 270)
			(size 0.4318 0.4318)
			(layers "F.Cu" "F.Mask" "F.Paste")
			(net "M_C_CPU0_SA_DQS_DP<4>")
		)
		(pad "AB57" smd circle
			(at 9.752838 -17.096486 270)
			(size 0.4318 0.4318)
			(layers "F.Cu" "F.Mask" "F.Paste")
			(net "GND")
		)
		(pad "AB59" smd circle
			(at 11.380724 -17.096486 270)
			(size 0.4318 0.4318)
			(layers "F.Cu" "F.Mask" "F.Paste")
			(net "GND")
		)
		(pad "AB61" smd circle
			(at 13.008356 -17.096486 270)
			(size 0.4318 0.4318)
			(layers "F.Cu" "F.Mask" "F.Paste")
			(net "M_C_CPU0_SA_DQS_DN<3>")
		)
		(pad "AB63" smd circle
			(at 14.635988 -17.096486 270)
			(size 0.4318 0.4318)
			(layers "F.Cu" "F.Mask" "F.Paste")
			(net "GND")
		)
		(pad "AB65" smd circle
			(at 16.263874 -17.096486 270)
			(size 0.4318 0.4318)
			(layers "F.Cu" "F.Mask" "F.Paste")
			(net "GND")
		)
		(pad "AB67" smd circle
			(at 17.89176 -17.096486 270)
			(size 0.4318 0.4318)
			(layers "F.Cu" "F.Mask" "F.Paste")
			(net "M_C_CPU0_SA_DQS_DN<1>")
		)
		(pad "AB69" smd circle
			(at 19.519392 -17.096486 270)
			(size 0.4318 0.4318)
			(layers "F.Cu" "F.Mask" "F.Paste")
			(net "GND")
		)
		(pad "AB71" smd circle
			(at 21.147278 -17.096486 270)
			(size 0.4318 0.4318)
			(layers "F.Cu" "F.Mask" "F.Paste")
			(net "GND")
		)
		(pad "AB73" smd circle
			(at 22.77491 -17.096486 270)
			(size 0.4318 0.4318)
			(layers "F.Cu" "F.Mask" "F.Paste")
			(net "M_D_CPU0_SA_DQS_DN<0>")
		)
		(pad "AB75" smd circle
			(at 24.402796 -17.096486 270)
			(size 0.4318 0.4318)
			(layers "F.Cu" "F.Mask" "F.Paste")
			(net "GND")
		)
		(pad "AB77" smd circle
			(at 26.030682 -17.096486 270)
			(size 0.4318 0.4318)
			(layers "F.Cu" "F.Mask" "F.Paste")
			(net "GND")
		)
		(pad "AB79" smd circle
			(at 27.658314 -17.096486 270)
			(size 0.4318 0.4318)
			(layers "F.Cu" "F.Mask" "F.Paste")
			(net "GND")
		)
		(pad "AB81" smd circle
			(at 29.2862 -17.096486 270)
			(size 0.4318 0.4318)
			(layers "F.Cu" "F.Mask" "F.Paste")
			(net "GND")
		)
		(pad "AB83" smd circle
			(at 30.914086 -17.096486 270)
			(size 0.4318 0.4318)
			(layers "F.Cu" "F.Mask" "F.Paste")
			(net "GND")
		)
		(pad "AB85" smd circle
			(at 32.541718 -17.096486 270)
			(size 0.4318 0.4318)
			(layers "F.Cu" "F.Mask" "F.Paste")
			(net "P5E_CPU0_PE4_TX_DP<5>")
		)
		(pad "AB87" smd circle
			(at 34.169604 -17.096486 270)
			(size 0.4318 0.4318)
			(layers "F.Cu" "F.Mask" "F.Paste")
			(net "GND")
		)
		(pad "AB89" smd circle
			(at 35.797236 -17.096486 270)
			(size 0.4318 0.4318)
			(layers "F.Cu" "F.Mask" "F.Paste")
			(net "P5E_CPU0_PE4_RX_DN<5>")
		)
		(pad "AB91" smd oval
			(at 37.425122 -17.096486)
			(size 0.381 0.4826)
			(drill
				(offset 0 -0.0508)
			)
			(layers "F.Cu" "F.Mask" "F.Paste")
			(net "GND")
		)
		(pad "AC1" smd oval
			(at -37.425122 -16.736314 180)
			(size 0.381 0.4826)
			(drill
				(offset 0 -0.0508)
			)
			(layers "F.Cu" "F.Mask" "F.Paste")
			(net "GND")
		)
		(pad "AC3" smd circle
			(at -35.797236 -16.736314 270)
			(size 0.4318 0.4318)
			(layers "F.Cu" "F.Mask" "F.Paste")
			(net "UPI_CPU0_CPU1_P0P1_DP<7>")
		)
		(pad "AC5" smd circle
			(at -34.169604 -16.736314 270)
			(size 0.4318 0.4318)
			(layers "F.Cu" "F.Mask" "F.Paste")
			(net "GND")
		)
		(pad "AC7" smd circle
			(at -32.541718 -16.736314 270)
			(size 0.4318 0.4318)
			(layers "F.Cu" "F.Mask" "F.Paste")
			(net "UPI_CPU1_CPU0_P1P0_DP<6>")
		)
		(pad "AC9" smd circle
			(at -30.914086 -16.736314 270)
			(size 0.4318 0.4318)
			(layers "F.Cu" "F.Mask" "F.Paste")
			(net "GND")
		)
		(pad "AC11" smd circle
			(at -29.2862 -16.736314 270)
			(size 0.4318 0.4318)
			(layers "F.Cu" "F.Mask" "F.Paste")
			(net "P5E_CPU0_PE0_RX_DP<6>")
		)
		(pad "AC13" smd circle
			(at -27.658314 -16.736314 270)
			(size 0.4318 0.4318)
			(layers "F.Cu" "F.Mask" "F.Paste")
			(net "GND")
		)
		(pad "AC15" smd circle
			(at -26.030682 -16.736314 270)
			(size 0.4318 0.4318)
			(layers "F.Cu" "F.Mask" "F.Paste")
			(net "P5E_CPU0_PE0_TX_DP<5>")
		)
		(pad "AC17" smd circle
			(at -24.402796 -16.736314 270)
			(size 0.4318 0.4318)
			(layers "F.Cu" "F.Mask" "F.Paste")
			(net "M_C_CPU0_SB_DQ<30>")
		)
		(pad "AC19" smd circle
			(at -22.77491 -16.736314 270)
			(size 0.4318 0.4318)
			(layers "F.Cu" "F.Mask" "F.Paste")
			(net "M_C_CPU0_SB_DQ<25>")
		)
		(pad "AC21" smd circle
			(at -21.147278 -16.736314 270)
			(size 0.4318 0.4318)
			(layers "F.Cu" "F.Mask" "F.Paste")
			(net "GND")
		)
		(pad "AC23" smd circle
			(at -19.519392 -16.736314 270)
			(size 0.4318 0.4318)
			(layers "F.Cu" "F.Mask" "F.Paste")
			(net "M_D_CPU0_SB_DQ<20>")
		)
		(pad "AC25" smd circle
			(at -17.89176 -16.736314 270)
			(size 0.4318 0.4318)
			(layers "F.Cu" "F.Mask" "F.Paste")
			(net "M_D_CPU0_SB_DQ<17>")
		)
		(pad "AC27" smd circle
			(at -16.263874 -16.736314 270)
			(size 0.4318 0.4318)
			(layers "F.Cu" "F.Mask" "F.Paste")
			(net "GND")
		)
		(pad "AC29" smd circle
			(at -14.635988 -16.736314 270)
			(size 0.4318 0.4318)
			(layers "F.Cu" "F.Mask" "F.Paste")
			(net "M_C_CPU0_SB_DQ<12>")
		)
		(pad "AC31" smd circle
			(at -13.008356 -16.736314 270)
			(size 0.4318 0.4318)
			(layers "F.Cu" "F.Mask" "F.Paste")
			(net "M_C_CPU0_SB_DQ<9>")
		)
		(pad "AC33" smd circle
			(at -11.380724 -16.736314 270)
			(size 0.4318 0.4318)
			(layers "F.Cu" "F.Mask" "F.Paste")
			(net "GND")
		)
		(pad "AC35" smd circle
			(at -9.752838 -16.736314 270)
			(size 0.4318 0.4318)
			(layers "F.Cu" "F.Mask" "F.Paste")
			(net "M_C_CPU0_SB_DQ<4>")
		)
		(pad "AC37" smd circle
			(at -8.124952 -16.736314 270)
			(size 0.4318 0.4318)
			(layers "F.Cu" "F.Mask" "F.Paste")
			(net "M_C_CPU0_SB_DQ<1>")
		)
		(pad "AC39" smd circle
			(at -6.49732 -16.736314 270)
			(size 0.4318 0.4318)
			(layers "F.Cu" "F.Mask" "F.Paste")
			(net "GND")
		)
		(pad "AC41" smd circle
			(at -4.869434 -16.736314 270)
			(size 0.4318 0.4318)
			(layers "F.Cu" "F.Mask" "F.Paste")
			(net "M_D_CPU0_SB_CS_N<0>")
		)
		(pad "AC43" smd circle
			(at -3.241802 -16.736314 270)
			(size 0.4318 0.4318)
			(layers "F.Cu" "F.Mask" "F.Paste")
			(net "M_D_CPU0_SB_CA<4>")
		)
		(pad "AC45" smd circle
			(at -1.613916 -16.736314 270)
			(size 0.4318 0.4318)
			(layers "F.Cu" "F.Mask" "F.Paste")
			(net "GND")
		)
		(pad "AC48" smd circle
			(at 2.427732 -16.626332 270)
			(size 0.4318 0.4318)
			(layers "F.Cu" "F.Mask" "F.Paste")
			(net "M_C_CPU0_SA_RSP<0>")
		)
		(pad "AC50" smd circle
			(at 4.055618 -16.626332 270)
			(size 0.4318 0.4318)
			(layers "F.Cu" "F.Mask" "F.Paste")
			(net "M_D_CPU0_SA_RSP<1>")
		)
		(pad "AC52" smd circle
			(at 5.68325 -16.626332 270)
			(size 0.4318 0.4318)
			(layers "F.Cu" "F.Mask" "F.Paste")
			(net "GND")
		)
		(pad "AC54" smd circle
			(at 7.311136 -16.626332 270)
			(size 0.4318 0.4318)
			(layers "F.Cu" "F.Mask" "F.Paste")
			(net "M_C_CPU0_SA_CB<4>")
		)
		(pad "AC56" smd circle
			(at 8.939022 -16.626332 270)
			(size 0.4318 0.4318)
			(layers "F.Cu" "F.Mask" "F.Paste")
			(net "M_C_CPU0_SA_CB<1>")
		)
		(pad "AC58" smd circle
			(at 10.566654 -16.626332 270)
			(size 0.4318 0.4318)
			(layers "F.Cu" "F.Mask" "F.Paste")
			(net "GND")
		)
		(pad "AC60" smd circle
			(at 12.19454 -16.626332 270)
			(size 0.4318 0.4318)
			(layers "F.Cu" "F.Mask" "F.Paste")
			(net "M_C_CPU0_SA_DQ<28>")
		)
		(pad "AC62" smd circle
			(at 13.822426 -16.626332 270)
			(size 0.4318 0.4318)
			(layers "F.Cu" "F.Mask" "F.Paste")
			(net "M_C_CPU0_SA_DQ<25>")
		)
		(pad "AC64" smd circle
			(at 15.450058 -16.626332 270)
			(size 0.4318 0.4318)
			(layers "F.Cu" "F.Mask" "F.Paste")
			(net "GND")
		)
		(pad "AC66" smd circle
			(at 17.07769 -16.626332 270)
			(size 0.4318 0.4318)
			(layers "F.Cu" "F.Mask" "F.Paste")
			(net "M_C_CPU0_SA_DQ<12>")
		)
		(pad "AC68" smd circle
			(at 18.705576 -16.626332 270)
			(size 0.4318 0.4318)
			(layers "F.Cu" "F.Mask" "F.Paste")
			(net "M_C_CPU0_SA_DQ<9>")
		)
		(pad "AC70" smd circle
			(at 20.333462 -16.626332 270)
			(size 0.4318 0.4318)
			(layers "F.Cu" "F.Mask" "F.Paste")
			(net "GND")
		)
		(pad "AC72" smd circle
			(at 21.961094 -16.626332 270)
			(size 0.4318 0.4318)
			(layers "F.Cu" "F.Mask" "F.Paste")
			(net "M_D_CPU0_SA_DQ<4>")
		)
		(pad "AC74" smd circle
			(at 23.58898 -16.626332 270)
			(size 0.4318 0.4318)
			(layers "F.Cu" "F.Mask" "F.Paste")
			(net "M_D_CPU0_SA_DQ<1>")
		)
		(pad "AC76" smd circle
			(at 25.216612 -16.626332 270)
			(size 0.4318 0.4318)
			(layers "F.Cu" "F.Mask" "F.Paste")
			(net "GND")
		)
		(pad "AC78" smd circle
			(at 26.844498 -16.626332 270)
			(size 0.4318 0.4318)
			(layers "F.Cu" "F.Mask" "F.Paste")
			(net "NC_CPU0_HBM2_VIEWDIG0")
		)
		(pad "AC80" smd circle
			(at 28.472384 -16.626332 270)
			(size 0.4318 0.4318)
			(layers "F.Cu" "F.Mask" "F.Paste")
			(net "UPI_CPU1_CPU0_P2P2_DN<17>")
		)
		(pad "AC82" smd circle
			(at 30.100016 -16.626332 270)
			(size 0.4318 0.4318)
			(layers "F.Cu" "F.Mask" "F.Paste")
			(net "UPI_CPU1_CPU0_P2P2_DN<16>")
		)
		(pad "AC84" smd circle
			(at 31.727902 -16.626332 270)
			(size 0.4318 0.4318)
			(layers "F.Cu" "F.Mask" "F.Paste")
			(net "GND")
		)
		(pad "AC86" smd circle
			(at 33.355534 -16.626332 270)
			(size 0.4318 0.4318)
			(layers "F.Cu" "F.Mask" "F.Paste")
			(net "P5E_CPU0_PE4_TX_DN<6>")
		)
		(pad "AC88" smd circle
			(at 34.98342 -16.626332 270)
			(size 0.4318 0.4318)
			(layers "F.Cu" "F.Mask" "F.Paste")
			(net "GND")
		)
		(pad "AC90" smd circle
			(at 36.611306 -16.626332 270)
			(size 0.4318 0.4318)
			(layers "F.Cu" "F.Mask" "F.Paste")
			(net "P5E_CPU0_PE4_RX_DP<6>")
		)
		(pad "AD2" smd circle
			(at -36.611306 -16.266668 270)
			(size 0.4318 0.4318)
			(layers "F.Cu" "F.Mask" "F.Paste")
			(net "UPI_CPU0_CPU1_P0P1_DN<7>")
		)
		(pad "AD4" smd circle
			(at -34.98342 -16.266668 270)
			(size 0.4318 0.4318)
			(layers "F.Cu" "F.Mask" "F.Paste")
			(net "GND")
		)
		(pad "AD6" smd circle
			(at -33.355534 -16.266668 270)
			(size 0.4318 0.4318)
			(layers "F.Cu" "F.Mask" "F.Paste")
			(net "UPI_CPU1_CPU0_P1P0_DP<7>")
		)
		(pad "AD8" smd circle
			(at -31.727902 -16.266668 270)
			(size 0.4318 0.4318)
			(layers "F.Cu" "F.Mask" "F.Paste")
			(net "GND")
		)
		(pad "AD10" smd circle
			(at -30.100016 -16.266668 270)
			(size 0.4318 0.4318)
			(layers "F.Cu" "F.Mask" "F.Paste")
			(net "P5E_CPU0_PE0_RX_DP<7>")
		)
		(pad "AD12" smd circle
			(at -28.472384 -16.266668 270)
			(size 0.4318 0.4318)
			(layers "F.Cu" "F.Mask" "F.Paste")
			(net "GND")
		)
		(pad "AD14" smd circle
			(at -26.844498 -16.266668 270)
			(size 0.4318 0.4318)
			(layers "F.Cu" "F.Mask" "F.Paste")
			(net "P5E_CPU0_PE0_TX_DP<6>")
		)
		(pad "AD16" smd circle
			(at -25.216612 -16.266668 270)
			(size 0.4318 0.4318)
			(layers "F.Cu" "F.Mask" "F.Paste")
			(net "GND")
		)
		(pad "AD18" smd circle
			(at -23.58898 -16.266668 270)
			(size 0.4318 0.4318)
			(layers "F.Cu" "F.Mask" "F.Paste")
			(net "M_C_CPU0_SB_DQS_DP<3>")
		)
		(pad "AD20" smd circle
			(at -21.961094 -16.266668 270)
			(size 0.4318 0.4318)
			(layers "F.Cu" "F.Mask" "F.Paste")
			(net "M_C_CPU0_SB_DQ<24>")
		)
		(pad "AD22" smd circle
			(at -20.333462 -16.266668 270)
			(size 0.4318 0.4318)
			(layers "F.Cu" "F.Mask" "F.Paste")
			(net "M_D_CPU0_SB_DQ<21>")
		)
		(pad "AD24" smd circle
			(at -18.705576 -16.266668 270)
			(size 0.4318 0.4318)
			(layers "F.Cu" "F.Mask" "F.Paste")
			(net "M_D_CPU0_SB_DQS_DP<2>")
		)
		(pad "AD26" smd circle
			(at -17.07769 -16.266668 270)
			(size 0.4318 0.4318)
			(layers "F.Cu" "F.Mask" "F.Paste")
			(net "M_D_CPU0_SB_DQ<16>")
		)
		(pad "AD28" smd circle
			(at -15.450058 -16.266668 270)
			(size 0.4318 0.4318)
			(layers "F.Cu" "F.Mask" "F.Paste")
			(net "M_C_CPU0_SB_DQ<13>")
		)
		(pad "AD30" smd circle
			(at -13.822426 -16.266668 270)
			(size 0.4318 0.4318)
			(layers "F.Cu" "F.Mask" "F.Paste")
			(net "M_C_CPU0_SB_DQS_DP<1>")
		)
		(pad "AD32" smd circle
			(at -12.19454 -16.266668 270)
			(size 0.4318 0.4318)
			(layers "F.Cu" "F.Mask" "F.Paste")
			(net "M_C_CPU0_SB_DQ<8>")
		)
		(pad "AD34" smd circle
			(at -10.566654 -16.266668 270)
			(size 0.4318 0.4318)
			(layers "F.Cu" "F.Mask" "F.Paste")
			(net "M_C_CPU0_SB_DQ<5>")
		)
		(pad "AD36" smd circle
			(at -8.939022 -16.266668 270)
			(size 0.4318 0.4318)
			(layers "F.Cu" "F.Mask" "F.Paste")
			(net "M_C_CPU0_SB_DQS_DP<0>")
		)
		(pad "AD38" smd circle
			(at -7.311136 -16.266668 270)
			(size 0.4318 0.4318)
			(layers "F.Cu" "F.Mask" "F.Paste")
			(net "M_C_CPU0_SB_DQ<0>")
		)
		(pad "AD40" smd circle
			(at -5.68325 -16.266668 270)
			(size 0.4318 0.4318)
			(layers "F.Cu" "F.Mask" "F.Paste")
			(net "M_D_CPU0_SB_CS_N<3>")
		)
		(pad "AD42" smd circle
			(at -4.055618 -16.266668 270)
			(size 0.4318 0.4318)
			(layers "F.Cu" "F.Mask" "F.Paste")
			(net "GND")
		)
		(pad "AD44" smd circle
			(at -2.427732 -16.266668 270)
			(size 0.4318 0.4318)
			(layers "F.Cu" "F.Mask" "F.Paste")
			(net "M_D_CPU0_SB_CA<2>")
		)
		(pad "AD47" smd circle
			(at 1.613916 -16.156686 270)
			(size 0.4318 0.4318)
			(layers "F.Cu" "F.Mask" "F.Paste")
			(net "M_C_CPU0_SA_RSP<1>")
		)
		(pad "AD49" smd circle
			(at 3.241802 -16.156686 270)
			(size 0.4318 0.4318)
			(layers "F.Cu" "F.Mask" "F.Paste")
			(net "M_C_CPU0_CLK_DP<0>")
		)
		(pad "AD51" smd circle
			(at 4.869434 -16.156686 270)
			(size 0.4318 0.4318)
			(layers "F.Cu" "F.Mask" "F.Paste")
			(net "M_D_CPU0_SA_RSP<0>")
		)
		(pad "AD53" smd circle
			(at 6.49732 -16.156686 270)
			(size 0.4318 0.4318)
			(layers "F.Cu" "F.Mask" "F.Paste")
			(net "M_C_CPU0_SA_CB<5>")
		)
		(pad "AD55" smd circle
			(at 8.124952 -16.156686 270)
			(size 0.4318 0.4318)
			(layers "F.Cu" "F.Mask" "F.Paste")
			(net "M_C_CPU0_SA_DQS_DN<4>")
		)
		(pad "AD57" smd circle
			(at 9.752838 -16.156686 270)
			(size 0.4318 0.4318)
			(layers "F.Cu" "F.Mask" "F.Paste")
			(net "M_C_CPU0_SA_CB<0>")
		)
		(pad "AD59" smd circle
			(at 11.380724 -16.156686 270)
			(size 0.4318 0.4318)
			(layers "F.Cu" "F.Mask" "F.Paste")
			(net "M_C_CPU0_SA_DQ<29>")
		)
		(pad "AD61" smd circle
			(at 13.008356 -16.156686 270)
			(size 0.4318 0.4318)
			(layers "F.Cu" "F.Mask" "F.Paste")
			(net "M_C_CPU0_SA_DQS_DP<3>")
		)
		(pad "AD63" smd circle
			(at 14.635988 -16.156686 270)
			(size 0.4318 0.4318)
			(layers "F.Cu" "F.Mask" "F.Paste")
			(net "M_C_CPU0_SA_DQ<24>")
		)
		(pad "AD65" smd circle
			(at 16.263874 -16.156686 270)
			(size 0.4318 0.4318)
			(layers "F.Cu" "F.Mask" "F.Paste")
			(net "M_C_CPU0_SA_DQ<13>")
		)
		(pad "AD67" smd circle
			(at 17.89176 -16.156686 270)
			(size 0.4318 0.4318)
			(layers "F.Cu" "F.Mask" "F.Paste")
			(net "M_C_CPU0_SA_DQS_DP<1>")
		)
		(pad "AD69" smd circle
			(at 19.519392 -16.156686 270)
			(size 0.4318 0.4318)
			(layers "F.Cu" "F.Mask" "F.Paste")
			(net "M_C_CPU0_SA_DQ<8>")
		)
		(pad "AD71" smd circle
			(at 21.147278 -16.156686 270)
			(size 0.4318 0.4318)
			(layers "F.Cu" "F.Mask" "F.Paste")
			(net "M_D_CPU0_SA_DQ<5>")
		)
		(pad "AD73" smd circle
			(at 22.77491 -16.156686 270)
			(size 0.4318 0.4318)
			(layers "F.Cu" "F.Mask" "F.Paste")
			(net "M_D_CPU0_SA_DQS_DP<0>")
		)
		(pad "AD75" smd circle
			(at 24.402796 -16.156686 270)
			(size 0.4318 0.4318)
			(layers "F.Cu" "F.Mask" "F.Paste")
			(net "M_D_CPU0_SA_DQ<0>")
		)
		(pad "AD77" smd circle
			(at 26.030682 -16.156686 270)
			(size 0.4318 0.4318)
			(layers "F.Cu" "F.Mask" "F.Paste")
			(net "NC_CPU0_HBM2_VIEWDIG1")
		)
		(pad "AD79" smd circle
			(at 27.658314 -16.156686 270)
			(size 0.4318 0.4318)
			(layers "F.Cu" "F.Mask" "F.Paste")
			(net "GND")
		)
		(pad "AD81" smd circle
			(at 29.2862 -16.156686 270)
			(size 0.4318 0.4318)
			(layers "F.Cu" "F.Mask" "F.Paste")
			(net "UPI_CPU1_CPU0_P2P2_DP<16>")
		)
		(pad "AD83" smd circle
			(at 30.914086 -16.156686 270)
			(size 0.4318 0.4318)
			(layers "F.Cu" "F.Mask" "F.Paste")
			(net "GND")
		)
		(pad "AD85" smd circle
			(at 32.541718 -16.156686 270)
			(size 0.4318 0.4318)
			(layers "F.Cu" "F.Mask" "F.Paste")
			(net "PVCCFA_EHV_FIVRA_CPU0")
		)
		(pad "AD87" smd circle
			(at 34.169604 -16.156686 270)
			(size 0.4318 0.4318)
			(layers "F.Cu" "F.Mask" "F.Paste")
			(net "P5E_CPU0_PE4_TX_DP<6>")
		)
		(pad "AD89" smd circle
			(at 35.797236 -16.156686 270)
			(size 0.4318 0.4318)
			(layers "F.Cu" "F.Mask" "F.Paste")
			(net "PVCCFA_EHV_FIVRA_CPU0")
		)
		(pad "AD91" smd oval
			(at 37.425122 -16.156686)
			(size 0.381 0.4826)
			(drill
				(offset 0 -0.0508)
			)
			(layers "F.Cu" "F.Mask" "F.Paste")
			(net "P5E_CPU0_PE4_RX_DN<6>")
		)
		(pad "AE1" smd oval
			(at -37.425122 -15.796514 180)
			(size 0.381 0.4826)
			(drill
				(offset 0 -0.0508)
			)
			(layers "F.Cu" "F.Mask" "F.Paste")
			(net "UPI_CPU0_CPU1_P0P1_DP<8>")
		)
		(pad "AE3" smd circle
			(at -35.797236 -15.796514 270)
			(size 0.4318 0.4318)
			(layers "F.Cu" "F.Mask" "F.Paste")
			(net "PVCCFA_EHV_CPU0")
		)
		(pad "AE5" smd circle
			(at -34.169604 -15.796514 270)
			(size 0.4318 0.4318)
			(layers "F.Cu" "F.Mask" "F.Paste")
			(net "UPI_CPU1_CPU0_P1P0_DN<7>")
		)
		(pad "AE7" smd circle
			(at -32.541718 -15.796514 270)
			(size 0.4318 0.4318)
			(layers "F.Cu" "F.Mask" "F.Paste")
			(net "PVCCFA_EHV_FIVRA_CPU0")
		)
		(pad "AE9" smd circle
			(at -30.914086 -15.796514 270)
			(size 0.4318 0.4318)
			(layers "F.Cu" "F.Mask" "F.Paste")
			(net "P5E_CPU0_PE0_RX_DN<7>")
		)
		(pad "AE11" smd circle
			(at -29.2862 -15.796514 270)
			(size 0.4318 0.4318)
			(layers "F.Cu" "F.Mask" "F.Paste")
			(net "PVCCFA_EHV_FIVRA_CPU0")
		)
		(pad "AE13" smd circle
			(at -27.658314 -15.796514 270)
			(size 0.4318 0.4318)
			(layers "F.Cu" "F.Mask" "F.Paste")
			(net "P5E_CPU0_PE0_TX_DN<6>")
		)
		(pad "AE15" smd circle
			(at -26.030682 -15.796514 270)
			(size 0.4318 0.4318)
			(layers "F.Cu" "F.Mask" "F.Paste")
			(net "PVCCFA_EHV_FIVRA_CPU0")
		)
		(pad "AE17" smd circle
			(at -24.402796 -15.796514 270)
			(size 0.4318 0.4318)
			(layers "F.Cu" "F.Mask" "F.Paste")
			(net "GND")
		)
		(pad "AE19" smd circle
			(at -22.77491 -15.796514 270)
			(size 0.4318 0.4318)
			(layers "F.Cu" "F.Mask" "F.Paste")
			(net "GND")
		)
		(pad "AE21" smd circle
			(at -21.147278 -15.796514 270)
			(size 0.4318 0.4318)
			(layers "F.Cu" "F.Mask" "F.Paste")
			(net "GND")
		)
		(pad "AE23" smd circle
			(at -19.519392 -15.796514 270)
			(size 0.4318 0.4318)
			(layers "F.Cu" "F.Mask" "F.Paste")
			(net "GND")
		)
		(pad "AE25" smd circle
			(at -17.89176 -15.796514 270)
			(size 0.4318 0.4318)
			(layers "F.Cu" "F.Mask" "F.Paste")
			(net "GND")
		)
		(pad "AE27" smd circle
			(at -16.263874 -15.796514 270)
			(size 0.4318 0.4318)
			(layers "F.Cu" "F.Mask" "F.Paste")
			(net "GND")
		)
		(pad "AE29" smd circle
			(at -14.635988 -15.796514 270)
			(size 0.4318 0.4318)
			(layers "F.Cu" "F.Mask" "F.Paste")
			(net "GND")
		)
		(pad "AE31" smd circle
			(at -13.008356 -15.796514 270)
			(size 0.4318 0.4318)
			(layers "F.Cu" "F.Mask" "F.Paste")
			(net "GND")
		)
		(pad "AE33" smd circle
			(at -11.380724 -15.796514 270)
			(size 0.4318 0.4318)
			(layers "F.Cu" "F.Mask" "F.Paste")
			(net "GND")
		)
		(pad "AE35" smd circle
			(at -9.752838 -15.796514 270)
			(size 0.4318 0.4318)
			(layers "F.Cu" "F.Mask" "F.Paste")
			(net "GND")
		)
		(pad "AE37" smd circle
			(at -8.124952 -15.796514 270)
			(size 0.4318 0.4318)
			(layers "F.Cu" "F.Mask" "F.Paste")
			(net "GND")
		)
		(pad "AE39" smd circle
			(at -6.49732 -15.796514 270)
			(size 0.4318 0.4318)
			(layers "F.Cu" "F.Mask" "F.Paste")
			(net "GND")
		)
		(pad "AE41" smd circle
			(at -4.869434 -15.796514 270)
			(size 0.4318 0.4318)
			(layers "F.Cu" "F.Mask" "F.Paste")
			(net "GND")
		)
		(pad "AE43" smd circle
			(at -3.241802 -15.796514 270)
			(size 0.4318 0.4318)
			(layers "F.Cu" "F.Mask" "F.Paste")
			(net "GND")
		)
		(pad "AE45" smd circle
			(at -1.613916 -15.796514 270)
			(size 0.4318 0.4318)
			(layers "F.Cu" "F.Mask" "F.Paste")
			(net "GND")
		)
		(pad "AE48" smd circle
			(at 2.427732 -15.686532 270)
			(size 0.4318 0.4318)
			(layers "F.Cu" "F.Mask" "F.Paste")
			(net "GND")
		)
		(pad "AE50" smd circle
			(at 4.055618 -15.686532 270)
			(size 0.4318 0.4318)
			(layers "F.Cu" "F.Mask" "F.Paste")
			(net "GND")
		)
		(pad "AE52" smd circle
			(at 5.68325 -15.686532 270)
			(size 0.4318 0.4318)
			(layers "F.Cu" "F.Mask" "F.Paste")
			(net "GND")
		)
		(pad "AE54" smd circle
			(at 7.311136 -15.686532 270)
			(size 0.4318 0.4318)
			(layers "F.Cu" "F.Mask" "F.Paste")
			(net "GND")
		)
		(pad "AE56" smd circle
			(at 8.939022 -15.686532 270)
			(size 0.4318 0.4318)
			(layers "F.Cu" "F.Mask" "F.Paste")
			(net "GND")
		)
		(pad "AE58" smd circle
			(at 10.566654 -15.686532 270)
			(size 0.4318 0.4318)
			(layers "F.Cu" "F.Mask" "F.Paste")
			(net "GND")
		)
		(pad "AE60" smd circle
			(at 12.19454 -15.686532 270)
			(size 0.4318 0.4318)
			(layers "F.Cu" "F.Mask" "F.Paste")
			(net "GND")
		)
		(pad "AE62" smd circle
			(at 13.822426 -15.686532 270)
			(size 0.4318 0.4318)
			(layers "F.Cu" "F.Mask" "F.Paste")
			(net "GND")
		)
		(pad "AE64" smd circle
			(at 15.450058 -15.686532 270)
			(size 0.4318 0.4318)
			(layers "F.Cu" "F.Mask" "F.Paste")
			(net "GND")
		)
		(pad "AE66" smd circle
			(at 17.07769 -15.686532 270)
			(size 0.4318 0.4318)
			(layers "F.Cu" "F.Mask" "F.Paste")
			(net "GND")
		)
		(pad "AE68" smd circle
			(at 18.705576 -15.686532 270)
			(size 0.4318 0.4318)
			(layers "F.Cu" "F.Mask" "F.Paste")
			(net "GND")
		)
		(pad "AE70" smd circle
			(at 20.333462 -15.686532 270)
			(size 0.4318 0.4318)
			(layers "F.Cu" "F.Mask" "F.Paste")
			(net "GND")
		)
		(pad "AE72" smd circle
			(at 21.961094 -15.686532 270)
			(size 0.4318 0.4318)
			(layers "F.Cu" "F.Mask" "F.Paste")
			(net "GND")
		)
		(pad "AE74" smd circle
			(at 23.58898 -15.686532 270)
			(size 0.4318 0.4318)
			(layers "F.Cu" "F.Mask" "F.Paste")
			(net "GND")
		)
		(pad "AE76" smd circle
			(at 25.216612 -15.686532 270)
			(size 0.4318 0.4318)
			(layers "F.Cu" "F.Mask" "F.Paste")
			(net "GND")
		)
		(pad "AE78" smd circle
			(at 26.844498 -15.686532 270)
			(size 0.4318 0.4318)
			(layers "F.Cu" "F.Mask" "F.Paste")
			(net "GND")
		)
		(pad "AE80" smd circle
			(at 28.472384 -15.686532 270)
			(size 0.4318 0.4318)
			(layers "F.Cu" "F.Mask" "F.Paste")
			(net "UPI_CPU1_CPU0_P2P2_DP<17>")
		)
		(pad "AE82" smd circle
			(at 30.100016 -15.686532 270)
			(size 0.4318 0.4318)
			(layers "F.Cu" "F.Mask" "F.Paste")
			(net "UPI_CPU1_CPU0_P2P2_DP<14>")
		)
		(pad "AE84" smd circle
			(at 31.727902 -15.686532 270)
			(size 0.4318 0.4318)
			(layers "F.Cu" "F.Mask" "F.Paste")
			(net "GND")
		)
		(pad "AE86" smd circle
			(at 33.355534 -15.686532 270)
			(size 0.4318 0.4318)
			(layers "F.Cu" "F.Mask" "F.Paste")
			(net "P5E_CPU0_PE4_TX_DN<7>")
		)
		(pad "AE88" smd circle
			(at 34.98342 -15.686532 270)
			(size 0.4318 0.4318)
			(layers "F.Cu" "F.Mask" "F.Paste")
			(net "GND")
		)
		(pad "AE90" smd circle
			(at 36.611306 -15.686532 270)
			(size 0.4318 0.4318)
			(layers "F.Cu" "F.Mask" "F.Paste")
			(net "P5E_CPU0_PE4_RX_DP<7>")
		)
		(pad "AF2" smd circle
			(at -36.611306 -15.326868 270)
			(size 0.4318 0.4318)
			(layers "F.Cu" "F.Mask" "F.Paste")
			(net "UPI_CPU0_CPU1_P0P1_DN<8>")
		)
		(pad "AF4" smd circle
			(at -34.98342 -15.326868 270)
			(size 0.4318 0.4318)
			(layers "F.Cu" "F.Mask" "F.Paste")
			(net "GND")
		)
		(pad "AF6" smd circle
			(at -33.355534 -15.326868 270)
			(size 0.4318 0.4318)
			(layers "F.Cu" "F.Mask" "F.Paste")
			(net "UPI_CPU1_CPU0_P1P0_DN<8>")
		)
		(pad "AF8" smd circle
			(at -31.727902 -15.326868 270)
			(size 0.4318 0.4318)
			(layers "F.Cu" "F.Mask" "F.Paste")
			(net "GND")
		)
		(pad "AF10" smd circle
			(at -30.100016 -15.326868 270)
			(size 0.4318 0.4318)
			(layers "F.Cu" "F.Mask" "F.Paste")
			(net "P5E_CPU0_PE0_RX_DN<8>")
		)
		(pad "AF12" smd circle
			(at -28.472384 -15.326868 270)
			(size 0.4318 0.4318)
			(layers "F.Cu" "F.Mask" "F.Paste")
			(net "GND")
		)
		(pad "AF14" smd circle
			(at -26.844498 -15.326868 270)
			(size 0.4318 0.4318)
			(layers "F.Cu" "F.Mask" "F.Paste")
			(net "P5E_CPU0_PE0_TX_DN<7>")
		)
		(pad "AF16" smd circle
			(at -25.216612 -15.326868 270)
			(size 0.4318 0.4318)
			(layers "F.Cu" "F.Mask" "F.Paste")
			(net "GND")
		)
		(pad "AF18" smd circle
			(at -23.58898 -15.326868 270)
			(size 0.4318 0.4318)
			(layers "F.Cu" "F.Mask" "F.Paste")
			(net "M_C_CPU0_SB_DQS_DN<8>")
		)
		(pad "AF20" smd circle
			(at -21.961094 -15.326868 270)
			(size 0.4318 0.4318)
			(layers "F.Cu" "F.Mask" "F.Paste")
			(net "M_C_CPU0_SB_DQ<26>")
		)
		(pad "AF22" smd circle
			(at -20.333462 -15.326868 270)
			(size 0.4318 0.4318)
			(layers "F.Cu" "F.Mask" "F.Paste")
			(net "M_D_CPU0_SB_DQ<23>")
		)
		(pad "AF24" smd circle
			(at -18.705576 -15.326868 270)
			(size 0.4318 0.4318)
			(layers "F.Cu" "F.Mask" "F.Paste")
			(net "M_D_CPU0_SB_DQS_DN<7>")
		)
		(pad "AF26" smd circle
			(at -17.07769 -15.326868 270)
			(size 0.4318 0.4318)
			(layers "F.Cu" "F.Mask" "F.Paste")
			(net "M_D_CPU0_SB_DQ<18>")
		)
		(pad "AF28" smd circle
			(at -15.450058 -15.326868 270)
			(size 0.4318 0.4318)
			(layers "F.Cu" "F.Mask" "F.Paste")
			(net "M_C_CPU0_SB_DQ<15>")
		)
		(pad "AF30" smd circle
			(at -13.822426 -15.326868 270)
			(size 0.4318 0.4318)
			(layers "F.Cu" "F.Mask" "F.Paste")
			(net "M_C_CPU0_SB_DQS_DN<6>")
		)
		(pad "AF32" smd circle
			(at -12.19454 -15.326868 270)
			(size 0.4318 0.4318)
			(layers "F.Cu" "F.Mask" "F.Paste")
			(net "M_C_CPU0_SB_DQ<10>")
		)
		(pad "AF34" smd circle
			(at -10.566654 -15.326868 270)
			(size 0.4318 0.4318)
			(layers "F.Cu" "F.Mask" "F.Paste")
			(net "M_C_CPU0_SB_DQ<7>")
		)
		(pad "AF36" smd circle
			(at -8.939022 -15.326868 270)
			(size 0.4318 0.4318)
			(layers "F.Cu" "F.Mask" "F.Paste")
			(net "M_C_CPU0_SB_DQS_DN<5>")
		)
		(pad "AF38" smd circle
			(at -7.311136 -15.326868 270)
			(size 0.4318 0.4318)
			(layers "F.Cu" "F.Mask" "F.Paste")
			(net "M_C_CPU0_SB_DQ<2>")
		)
		(pad "AF40" smd circle
			(at -5.68325 -15.326868 270)
			(size 0.4318 0.4318)
			(layers "F.Cu" "F.Mask" "F.Paste")
			(net "M_D_CPU0_SB_CS_N<2>")
		)
		(pad "AF42" smd circle
			(at -4.055618 -15.326868 270)
			(size 0.4318 0.4318)
			(layers "F.Cu" "F.Mask" "F.Paste")
			(net "GND")
		)
		(pad "AF44" smd circle
			(at -2.427732 -15.326868 270)
			(size 0.4318 0.4318)
			(layers "F.Cu" "F.Mask" "F.Paste")
			(net "M_D_CPU0_SB_CA<3>")
		)
		(pad "AF47" smd circle
			(at 1.613916 -15.216886 270)
			(size 0.4318 0.4318)
			(layers "F.Cu" "F.Mask" "F.Paste")
			(net "M_C_CPU0_SB_RSP<1>")
		)
		(pad "AF49" smd circle
			(at 3.241802 -15.216886 270)
			(size 0.4318 0.4318)
			(layers "F.Cu" "F.Mask" "F.Paste")
			(net "M_C_CPU0_CLK_DN<1>")
		)
		(pad "AF51" smd circle
			(at 4.869434 -15.216886 270)
			(size 0.4318 0.4318)
			(layers "F.Cu" "F.Mask" "F.Paste")
			(net "M_D_CPU0_SB_RSP<0>")
		)
		(pad "AF53" smd circle
			(at 6.49732 -15.216886 270)
			(size 0.4318 0.4318)
			(layers "F.Cu" "F.Mask" "F.Paste")
			(net "M_C_CPU0_SA_CB<7>")
		)
		(pad "AF55" smd circle
			(at 8.124952 -15.216886 270)
			(size 0.4318 0.4318)
			(layers "F.Cu" "F.Mask" "F.Paste")
			(net "M_C_CPU0_SA_DQS_DP<9>")
		)
		(pad "AF57" smd circle
			(at 9.752838 -15.216886 270)
			(size 0.4318 0.4318)
			(layers "F.Cu" "F.Mask" "F.Paste")
			(net "M_C_CPU0_SA_CB<2>")
		)
		(pad "AF59" smd circle
			(at 11.380724 -15.216886 270)
			(size 0.4318 0.4318)
			(layers "F.Cu" "F.Mask" "F.Paste")
			(net "M_C_CPU0_SA_DQ<31>")
		)
		(pad "AF61" smd circle
			(at 13.008356 -15.216886 270)
			(size 0.4318 0.4318)
			(layers "F.Cu" "F.Mask" "F.Paste")
			(net "M_C_CPU0_SA_DQS_DN<8>")
		)
		(pad "AF63" smd circle
			(at 14.635988 -15.216886 270)
			(size 0.4318 0.4318)
			(layers "F.Cu" "F.Mask" "F.Paste")
			(net "M_C_CPU0_SA_DQ<26>")
		)
		(pad "AF65" smd circle
			(at 16.263874 -15.216886 270)
			(size 0.4318 0.4318)
			(layers "F.Cu" "F.Mask" "F.Paste")
			(net "M_C_CPU0_SA_DQ<15>")
		)
		(pad "AF67" smd circle
			(at 17.89176 -15.216886 270)
			(size 0.4318 0.4318)
			(layers "F.Cu" "F.Mask" "F.Paste")
			(net "M_C_CPU0_SA_DQS_DP<6>")
		)
		(pad "AF69" smd circle
			(at 19.519392 -15.216886 270)
			(size 0.4318 0.4318)
			(layers "F.Cu" "F.Mask" "F.Paste")
			(net "M_C_CPU0_SA_DQ<10>")
		)
		(pad "AF71" smd circle
			(at 21.147278 -15.216886 270)
			(size 0.4318 0.4318)
			(layers "F.Cu" "F.Mask" "F.Paste")
			(net "M_D_CPU0_SA_DQ<7>")
		)
		(pad "AF73" smd circle
			(at 22.77491 -15.216886 270)
			(size 0.4318 0.4318)
			(layers "F.Cu" "F.Mask" "F.Paste")
			(net "M_D_CPU0_SA_DQS_DP<5>")
		)
		(pad "AF75" smd circle
			(at 24.402796 -15.216886 270)
			(size 0.4318 0.4318)
			(layers "F.Cu" "F.Mask" "F.Paste")
			(net "M_D_CPU0_SA_DQ<2>")
		)
		(pad "AF77" smd circle
			(at 26.030682 -15.216886 270)
			(size 0.4318 0.4318)
			(layers "F.Cu" "F.Mask" "F.Paste")
			(net "PVCCFA_EHV_FIVRA_CPU0")
		)
		(pad "AF79" smd circle
			(at 27.658314 -15.216886 270)
			(size 0.4318 0.4318)
			(layers "F.Cu" "F.Mask" "F.Paste")
			(net "UPI_CPU1_CPU0_P2P2_DP<15>")
		)
		(pad "AF81" smd circle
			(at 29.2862 -15.216886 270)
			(size 0.4318 0.4318)
			(layers "F.Cu" "F.Mask" "F.Paste")
			(net "GND")
		)
		(pad "AF83" smd circle
			(at 30.914086 -15.216886 270)
			(size 0.4318 0.4318)
			(layers "F.Cu" "F.Mask" "F.Paste")
			(net "UPI_CPU1_CPU0_P2P2_DN<14>")
		)
		(pad "AF85" smd circle
			(at 32.541718 -15.216886 270)
			(size 0.4318 0.4318)
			(layers "F.Cu" "F.Mask" "F.Paste")
			(net "P5E_CPU0_PE4_TX_DP<7>")
		)
		(pad "AF87" smd circle
			(at 34.169604 -15.216886 270)
			(size 0.4318 0.4318)
			(layers "F.Cu" "F.Mask" "F.Paste")
			(net "GND")
		)
		(pad "AF89" smd circle
			(at 35.797236 -15.216886 270)
			(size 0.4318 0.4318)
			(layers "F.Cu" "F.Mask" "F.Paste")
			(net "P5E_CPU0_PE4_RX_DN<7>")
		)
		(pad "AF91" smd oval
			(at 37.425122 -15.216886)
			(size 0.381 0.4826)
			(drill
				(offset 0 -0.0508)
			)
			(layers "F.Cu" "F.Mask" "F.Paste")
			(net "GND")
		)
		(pad "AG1" smd oval
			(at -37.425122 -14.856714 180)
			(size 0.381 0.4826)
			(drill
				(offset 0 -0.0508)
			)
			(layers "F.Cu" "F.Mask" "F.Paste")
			(net "GND")
		)
		(pad "AG3" smd circle
			(at -35.797236 -14.856714 270)
			(size 0.4318 0.4318)
			(layers "F.Cu" "F.Mask" "F.Paste")
			(net "UPI_CPU0_CPU1_P0P1_DP<9>")
		)
		(pad "AG5" smd circle
			(at -34.169604 -14.856714 270)
			(size 0.4318 0.4318)
			(layers "F.Cu" "F.Mask" "F.Paste")
			(net "GND")
		)
		(pad "AG7" smd circle
			(at -32.541718 -14.856714 270)
			(size 0.4318 0.4318)
			(layers "F.Cu" "F.Mask" "F.Paste")
			(net "UPI_CPU1_CPU0_P1P0_DP<8>")
		)
		(pad "AG9" smd circle
			(at -30.914086 -14.856714 270)
			(size 0.4318 0.4318)
			(layers "F.Cu" "F.Mask" "F.Paste")
			(net "GND")
		)
		(pad "AG11" smd circle
			(at -29.2862 -14.856714 270)
			(size 0.4318 0.4318)
			(layers "F.Cu" "F.Mask" "F.Paste")
			(net "P5E_CPU0_PE0_RX_DP<8>")
		)
		(pad "AG13" smd circle
			(at -27.658314 -14.856714 270)
			(size 0.4318 0.4318)
			(layers "F.Cu" "F.Mask" "F.Paste")
			(net "GND")
		)
		(pad "AG15" smd circle
			(at -26.030682 -14.856714 270)
			(size 0.4318 0.4318)
			(layers "F.Cu" "F.Mask" "F.Paste")
			(net "P5E_CPU0_PE0_TX_DP<7>")
		)
		(pad "AG17" smd circle
			(at -24.402796 -14.856714 270)
			(size 0.4318 0.4318)
			(layers "F.Cu" "F.Mask" "F.Paste")
			(net "M_C_CPU0_SB_DQ<29>")
		)
		(pad "AG19" smd circle
			(at -22.77491 -14.856714 270)
			(size 0.4318 0.4318)
			(layers "F.Cu" "F.Mask" "F.Paste")
			(net "M_C_CPU0_SB_DQ<27>")
		)
		(pad "AG21" smd circle
			(at -21.147278 -14.856714 270)
			(size 0.4318 0.4318)
			(layers "F.Cu" "F.Mask" "F.Paste")
			(net "GND")
		)
		(pad "AG23" smd circle
			(at -19.519392 -14.856714 270)
			(size 0.4318 0.4318)
			(layers "F.Cu" "F.Mask" "F.Paste")
			(net "M_D_CPU0_SB_DQ<22>")
		)
		(pad "AG25" smd circle
			(at -17.89176 -14.856714 270)
			(size 0.4318 0.4318)
			(layers "F.Cu" "F.Mask" "F.Paste")
			(net "M_D_CPU0_SB_DQ<19>")
		)
		(pad "AG27" smd circle
			(at -16.263874 -14.856714 270)
			(size 0.4318 0.4318)
			(layers "F.Cu" "F.Mask" "F.Paste")
			(net "GND")
		)
		(pad "AG29" smd circle
			(at -14.635988 -14.856714 270)
			(size 0.4318 0.4318)
			(layers "F.Cu" "F.Mask" "F.Paste")
			(net "M_C_CPU0_SB_DQ<14>")
		)
		(pad "AG31" smd circle
			(at -13.008356 -14.856714 270)
			(size 0.4318 0.4318)
			(layers "F.Cu" "F.Mask" "F.Paste")
			(net "M_C_CPU0_SB_DQ<11>")
		)
		(pad "AG33" smd circle
			(at -11.380724 -14.856714 270)
			(size 0.4318 0.4318)
			(layers "F.Cu" "F.Mask" "F.Paste")
			(net "GND")
		)
		(pad "AG35" smd circle
			(at -9.752838 -14.856714 270)
			(size 0.4318 0.4318)
			(layers "F.Cu" "F.Mask" "F.Paste")
			(net "M_C_CPU0_SB_DQ<6>")
		)
		(pad "AG37" smd circle
			(at -8.124952 -14.856714 270)
			(size 0.4318 0.4318)
			(layers "F.Cu" "F.Mask" "F.Paste")
			(net "M_C_CPU0_SB_DQ<3>")
		)
		(pad "AG39" smd circle
			(at -6.49732 -14.856714 270)
			(size 0.4318 0.4318)
			(layers "F.Cu" "F.Mask" "F.Paste")
			(net "GND")
		)
		(pad "AG41" smd circle
			(at -4.869434 -14.856714 270)
			(size 0.4318 0.4318)
			(layers "F.Cu" "F.Mask" "F.Paste")
			(net "M_D_CPU0_SB_CS_N<1>")
		)
		(pad "AG43" smd circle
			(at -3.241802 -14.856714 270)
			(size 0.4318 0.4318)
			(layers "F.Cu" "F.Mask" "F.Paste")
			(net "M_D_CPU0_SB_CA<5>")
		)
		(pad "AG45" smd circle
			(at -1.613916 -14.856714 270)
			(size 0.4318 0.4318)
			(layers "F.Cu" "F.Mask" "F.Paste")
			(net "GND")
		)
		(pad "AG48" smd circle
			(at 2.427732 -14.746732 270)
			(size 0.4318 0.4318)
			(layers "F.Cu" "F.Mask" "F.Paste")
			(net "M_C_CPU0_SB_RSP<0>")
		)
		(pad "AG50" smd circle
			(at 4.055618 -14.746732 270)
			(size 0.4318 0.4318)
			(layers "F.Cu" "F.Mask" "F.Paste")
			(net "M_D_CPU0_SB_RSP<1>")
		)
		(pad "AG52" smd circle
			(at 5.68325 -14.746732 270)
			(size 0.4318 0.4318)
			(layers "F.Cu" "F.Mask" "F.Paste")
			(net "GND")
		)
		(pad "AG54" smd circle
			(at 7.311136 -14.746732 270)
			(size 0.4318 0.4318)
			(layers "F.Cu" "F.Mask" "F.Paste")
			(net "M_C_CPU0_SA_CB<6>")
		)
		(pad "AG56" smd circle
			(at 8.939022 -14.746732 270)
			(size 0.4318 0.4318)
			(layers "F.Cu" "F.Mask" "F.Paste")
			(net "M_C_CPU0_SA_CB<3>")
		)
		(pad "AG58" smd circle
			(at 10.566654 -14.746732 270)
			(size 0.4318 0.4318)
			(layers "F.Cu" "F.Mask" "F.Paste")
			(net "GND")
		)
		(pad "AG60" smd circle
			(at 12.19454 -14.746732 270)
			(size 0.4318 0.4318)
			(layers "F.Cu" "F.Mask" "F.Paste")
			(net "M_C_CPU0_SA_DQ<30>")
		)
		(pad "AG62" smd circle
			(at 13.822426 -14.746732 270)
			(size 0.4318 0.4318)
			(layers "F.Cu" "F.Mask" "F.Paste")
			(net "M_C_CPU0_SA_DQ<27>")
		)
		(pad "AG64" smd circle
			(at 15.450058 -14.746732 270)
			(size 0.4318 0.4318)
			(layers "F.Cu" "F.Mask" "F.Paste")
			(net "GND")
		)
		(pad "AG66" smd circle
			(at 17.07769 -14.746732 270)
			(size 0.4318 0.4318)
			(layers "F.Cu" "F.Mask" "F.Paste")
			(net "M_C_CPU0_SA_DQ<14>")
		)
		(pad "AG68" smd circle
			(at 18.705576 -14.746732 270)
			(size 0.4318 0.4318)
			(layers "F.Cu" "F.Mask" "F.Paste")
			(net "M_C_CPU0_SA_DQ<11>")
		)
		(pad "AG70" smd circle
			(at 20.333462 -14.746732 270)
			(size 0.4318 0.4318)
			(layers "F.Cu" "F.Mask" "F.Paste")
			(net "GND")
		)
		(pad "AG72" smd circle
			(at 21.961094 -14.746732 270)
			(size 0.4318 0.4318)
			(layers "F.Cu" "F.Mask" "F.Paste")
			(net "M_D_CPU0_SA_DQ<6>")
		)
		(pad "AG74" smd circle
			(at 23.58898 -14.746732 270)
			(size 0.4318 0.4318)
			(layers "F.Cu" "F.Mask" "F.Paste")
			(net "M_D_CPU0_SA_DQ<3>")
		)
		(pad "AG76" smd circle
			(at 25.216612 -14.746732 270)
			(size 0.4318 0.4318)
			(layers "F.Cu" "F.Mask" "F.Paste")
			(net "GND")
		)
		(pad "AG78" smd circle
			(at 26.844498 -14.746732 270)
			(size 0.4318 0.4318)
			(layers "F.Cu" "F.Mask" "F.Paste")
			(net "PVCCFA_EHV_FIVRA_CPU0")
		)
		(pad "AG80" smd circle
			(at 28.472384 -14.746732 270)
			(size 0.4318 0.4318)
			(layers "F.Cu" "F.Mask" "F.Paste")
			(net "UPI_CPU1_CPU0_P2P2_DN<15>")
		)
		(pad "AG82" smd circle
			(at 30.100016 -14.746732 270)
			(size 0.4318 0.4318)
			(layers "F.Cu" "F.Mask" "F.Paste")
			(net "UPI_CPU1_CPU0_P2P2_DP<12>")
		)
		(pad "AG84" smd circle
			(at 31.727902 -14.746732 270)
			(size 0.4318 0.4318)
			(layers "F.Cu" "F.Mask" "F.Paste")
			(net "GND")
		)
		(pad "AG86" smd circle
			(at 33.355534 -14.746732 270)
			(size 0.4318 0.4318)
			(layers "F.Cu" "F.Mask" "F.Paste")
			(net "P5E_CPU0_PE4_TX_DN<8>")
		)
		(pad "AG88" smd circle
			(at 34.98342 -14.746732 270)
			(size 0.4318 0.4318)
			(layers "F.Cu" "F.Mask" "F.Paste")
			(net "GND")
		)
		(pad "AG90" smd circle
			(at 36.611306 -14.746732 270)
			(size 0.4318 0.4318)
			(layers "F.Cu" "F.Mask" "F.Paste")
			(net "P5E_CPU0_PE4_RX_DP<8>")
		)
		(pad "AH2" smd circle
			(at -36.611306 -14.387068 270)
			(size 0.4318 0.4318)
			(layers "F.Cu" "F.Mask" "F.Paste")
			(net "UPI_CPU0_CPU1_P0P1_DN<9>")
		)
		(pad "AH4" smd circle
			(at -34.98342 -14.387068 270)
			(size 0.4318 0.4318)
			(layers "F.Cu" "F.Mask" "F.Paste")
			(net "GND")
		)
		(pad "AH6" smd circle
			(at -33.355534 -14.387068 270)
			(size 0.4318 0.4318)
			(layers "F.Cu" "F.Mask" "F.Paste")
			(net "UPI_CPU1_CPU0_P1P0_DN<9>")
		)
		(pad "AH8" smd circle
			(at -31.727902 -14.387068 270)
			(size 0.4318 0.4318)
			(layers "F.Cu" "F.Mask" "F.Paste")
			(net "GND")
		)
		(pad "AH10" smd circle
			(at -30.100016 -14.387068 270)
			(size 0.4318 0.4318)
			(layers "F.Cu" "F.Mask" "F.Paste")
			(net "P5E_CPU0_PE0_RX_DP<9>")
		)
		(pad "AH12" smd circle
			(at -28.472384 -14.387068 270)
			(size 0.4318 0.4318)
			(layers "F.Cu" "F.Mask" "F.Paste")
			(net "GND")
		)
		(pad "AH14" smd circle
			(at -26.844498 -14.387068 270)
			(size 0.4318 0.4318)
			(layers "F.Cu" "F.Mask" "F.Paste")
			(net "P5E_CPU0_PE0_TX_DP<8>")
		)
		(pad "AH16" smd circle
			(at -25.216612 -14.387068 270)
			(size 0.4318 0.4318)
			(layers "F.Cu" "F.Mask" "F.Paste")
			(net "GND")
		)
		(pad "AH18" smd circle
			(at -23.58898 -14.387068 270)
			(size 0.4318 0.4318)
			(layers "F.Cu" "F.Mask" "F.Paste")
			(net "M_C_CPU0_SB_DQS_DP<8>")
		)
		(pad "AH20" smd circle
			(at -21.961094 -14.387068 270)
			(size 0.4318 0.4318)
			(layers "F.Cu" "F.Mask" "F.Paste")
			(net "GND")
		)
		(pad "AH22" smd circle
			(at -20.333462 -14.387068 270)
			(size 0.4318 0.4318)
			(layers "F.Cu" "F.Mask" "F.Paste")
			(net "GND")
		)
		(pad "AH24" smd circle
			(at -18.705576 -14.387068 270)
			(size 0.4318 0.4318)
			(layers "F.Cu" "F.Mask" "F.Paste")
			(net "M_D_CPU0_SB_DQS_DP<7>")
		)
		(pad "AH26" smd circle
			(at -17.07769 -14.387068 270)
			(size 0.4318 0.4318)
			(layers "F.Cu" "F.Mask" "F.Paste")
			(net "GND")
		)
		(pad "AH28" smd circle
			(at -15.450058 -14.387068 270)
			(size 0.4318 0.4318)
			(layers "F.Cu" "F.Mask" "F.Paste")
			(net "GND")
		)
		(pad "AH30" smd circle
			(at -13.822426 -14.387068 270)
			(size 0.4318 0.4318)
			(layers "F.Cu" "F.Mask" "F.Paste")
			(net "M_C_CPU0_SB_DQS_DP<6>")
		)
		(pad "AH32" smd circle
			(at -12.19454 -14.387068 270)
			(size 0.4318 0.4318)
			(layers "F.Cu" "F.Mask" "F.Paste")
			(net "GND")
		)
		(pad "AH34" smd circle
			(at -10.566654 -14.387068 270)
			(size 0.4318 0.4318)
			(layers "F.Cu" "F.Mask" "F.Paste")
			(net "GND")
		)
		(pad "AH36" smd circle
			(at -8.939022 -14.387068 270)
			(size 0.4318 0.4318)
			(layers "F.Cu" "F.Mask" "F.Paste")
			(net "M_C_CPU0_SB_DQS_DP<5>")
		)
		(pad "AH38" smd circle
			(at -7.311136 -14.387068 270)
			(size 0.4318 0.4318)
			(layers "F.Cu" "F.Mask" "F.Paste")
			(net "GND")
		)
		(pad "AH40" smd circle
			(at -5.68325 -14.387068 270)
			(size 0.4318 0.4318)
			(layers "F.Cu" "F.Mask" "F.Paste")
			(net "GND")
		)
		(pad "AH42" smd circle
			(at -4.055618 -14.387068 270)
			(size 0.4318 0.4318)
			(layers "F.Cu" "F.Mask" "F.Paste")
			(net "M_D_CPU0_SB_PAR")
		)
		(pad "AH44" smd circle
			(at -2.427732 -14.387068 270)
			(size 0.4318 0.4318)
			(layers "F.Cu" "F.Mask" "F.Paste")
			(net "GND")
		)
		(pad "AH47" smd circle
			(at 1.613916 -14.277086 270)
			(size 0.4318 0.4318)
			(layers "F.Cu" "F.Mask" "F.Paste")
			(net "GND")
		)
		(pad "AH49" smd circle
			(at 3.241802 -14.277086 270)
			(size 0.4318 0.4318)
			(layers "F.Cu" "F.Mask" "F.Paste")
			(net "M_C_CPU0_CLK_DP<1>")
		)
		(pad "AH51" smd circle
			(at 4.869434 -14.277086 270)
			(size 0.4318 0.4318)
			(layers "F.Cu" "F.Mask" "F.Paste")
			(net "GND")
		)
		(pad "AH53" smd circle
			(at 6.49732 -14.277086 270)
			(size 0.4318 0.4318)
			(layers "F.Cu" "F.Mask" "F.Paste")
			(net "GND")
		)
		(pad "AH55" smd circle
			(at 8.124952 -14.277086 270)
			(size 0.4318 0.4318)
			(layers "F.Cu" "F.Mask" "F.Paste")
			(net "M_C_CPU0_SA_DQS_DN<9>")
		)
		(pad "AH57" smd circle
			(at 9.752838 -14.277086 270)
			(size 0.4318 0.4318)
			(layers "F.Cu" "F.Mask" "F.Paste")
			(net "GND")
		)
		(pad "AH59" smd circle
			(at 11.380724 -14.277086 270)
			(size 0.4318 0.4318)
			(layers "F.Cu" "F.Mask" "F.Paste")
			(net "GND")
		)
		(pad "AH61" smd circle
			(at 13.008356 -14.277086 270)
			(size 0.4318 0.4318)
			(layers "F.Cu" "F.Mask" "F.Paste")
			(net "M_C_CPU0_SA_DQS_DP<8>")
		)
		(pad "AH63" smd circle
			(at 14.635988 -14.277086 270)
			(size 0.4318 0.4318)
			(layers "F.Cu" "F.Mask" "F.Paste")
			(net "GND")
		)
		(pad "AH65" smd circle
			(at 16.263874 -14.277086 270)
			(size 0.4318 0.4318)
			(layers "F.Cu" "F.Mask" "F.Paste")
			(net "GND")
		)
		(pad "AH67" smd circle
			(at 17.89176 -14.277086 270)
			(size 0.4318 0.4318)
			(layers "F.Cu" "F.Mask" "F.Paste")
			(net "M_C_CPU0_SA_DQS_DN<6>")
		)
		(pad "AH69" smd circle
			(at 19.519392 -14.277086 270)
			(size 0.4318 0.4318)
			(layers "F.Cu" "F.Mask" "F.Paste")
			(net "GND")
		)
		(pad "AH71" smd circle
			(at 21.147278 -14.277086 270)
			(size 0.4318 0.4318)
			(layers "F.Cu" "F.Mask" "F.Paste")
			(net "GND")
		)
		(pad "AH73" smd circle
			(at 22.77491 -14.277086 270)
			(size 0.4318 0.4318)
			(layers "F.Cu" "F.Mask" "F.Paste")
			(net "M_D_CPU0_SA_DQS_DN<5>")
		)
		(pad "AH75" smd circle
			(at 24.402796 -14.277086 270)
			(size 0.4318 0.4318)
			(layers "F.Cu" "F.Mask" "F.Paste")
			(net "GND")
		)
		(pad "AH77" smd circle
			(at 26.030682 -14.277086 270)
			(size 0.4318 0.4318)
			(layers "F.Cu" "F.Mask" "F.Paste")
			(net "GND")
		)
		(pad "AH79" smd circle
			(at 27.658314 -14.277086 270)
			(size 0.4318 0.4318)
			(layers "F.Cu" "F.Mask" "F.Paste")
			(net "GND")
		)
		(pad "AH81" smd circle
			(at 29.2862 -14.277086 270)
			(size 0.4318 0.4318)
			(layers "F.Cu" "F.Mask" "F.Paste")
			(net "UPI_CPU1_CPU0_P2P2_DP<13>")
		)
		(pad "AH83" smd circle
			(at 30.914086 -14.277086 270)
			(size 0.4318 0.4318)
			(layers "F.Cu" "F.Mask" "F.Paste")
			(net "GND")
		)
		(pad "AH85" smd circle
			(at 32.541718 -14.277086 270)
			(size 0.4318 0.4318)
			(layers "F.Cu" "F.Mask" "F.Paste")
			(net "PVCCFA_EHV_FIVRA_CPU0")
		)
		(pad "AH87" smd circle
			(at 34.169604 -14.277086 270)
			(size 0.4318 0.4318)
			(layers "F.Cu" "F.Mask" "F.Paste")
			(net "P5E_CPU0_PE4_TX_DP<8>")
		)
		(pad "AH89" smd circle
			(at 35.797236 -14.277086 270)
			(size 0.4318 0.4318)
			(layers "F.Cu" "F.Mask" "F.Paste")
			(net "PVCCFA_EHV_FIVRA_CPU0")
		)
		(pad "AH91" smd oval
			(at 37.425122 -14.277086)
			(size 0.381 0.4826)
			(drill
				(offset 0 -0.0508)
			)
			(layers "F.Cu" "F.Mask" "F.Paste")
			(net "P5E_CPU0_PE4_RX_DN<8>")
		)
		(pad "AJ1" smd oval
			(at -37.425122 -13.916914 180)
			(size 0.381 0.4826)
			(drill
				(offset 0 -0.0508)
			)
			(layers "F.Cu" "F.Mask" "F.Paste")
			(net "UPI_CPU0_CPU1_P0P1_DP<10>")
		)
		(pad "AJ3" smd circle
			(at -35.797236 -13.916914 270)
			(size 0.4318 0.4318)
			(layers "F.Cu" "F.Mask" "F.Paste")
			(net "PVCCFA_EHV_CPU0")
		)
		(pad "AJ5" smd circle
			(at -34.169604 -13.916914 270)
			(size 0.4318 0.4318)
			(layers "F.Cu" "F.Mask" "F.Paste")
			(net "UPI_CPU1_CPU0_P1P0_DP<9>")
		)
		(pad "AJ7" smd circle
			(at -32.541718 -13.916914 270)
			(size 0.4318 0.4318)
			(layers "F.Cu" "F.Mask" "F.Paste")
			(net "PVCCFA_EHV_FIVRA_CPU0")
		)
		(pad "AJ9" smd circle
			(at -30.914086 -13.916914 270)
			(size 0.4318 0.4318)
			(layers "F.Cu" "F.Mask" "F.Paste")
			(net "P5E_CPU0_PE0_RX_DN<9>")
		)
		(pad "AJ11" smd circle
			(at -29.2862 -13.916914 270)
			(size 0.4318 0.4318)
			(layers "F.Cu" "F.Mask" "F.Paste")
			(net "PVCCFA_EHV_FIVRA_CPU0")
		)
		(pad "AJ13" smd circle
			(at -27.658314 -13.916914 270)
			(size 0.4318 0.4318)
			(layers "F.Cu" "F.Mask" "F.Paste")
			(net "P5E_CPU0_PE0_TX_DN<8>")
		)
		(pad "AJ15" smd circle
			(at -26.030682 -13.916914 270)
			(size 0.4318 0.4318)
			(layers "F.Cu" "F.Mask" "F.Paste")
			(net "PVCCFA_EHV_FIVRA_CPU0")
		)
		(pad "AJ17" smd circle
			(at -24.402796 -13.916914 270)
			(size 0.4318 0.4318)
			(layers "F.Cu" "F.Mask" "F.Paste")
			(net "M_C_CPU0_SB_DQ<31>")
		)
		(pad "AJ19" smd circle
			(at -22.77491 -13.916914 270)
			(size 0.4318 0.4318)
			(layers "F.Cu" "F.Mask" "F.Paste")
			(net "GND")
		)
		(pad "AJ21" smd circle
			(at -21.147278 -13.916914 270)
			(size 0.4318 0.4318)
			(layers "F.Cu" "F.Mask" "F.Paste")
			(net "M_D_CPU0_SB_DQS_DN<3>")
		)
		(pad "AJ23" smd circle
			(at -19.519392 -13.916914 270)
			(size 0.4318 0.4318)
			(layers "F.Cu" "F.Mask" "F.Paste")
			(net "GND")
		)
		(pad "AJ25" smd circle
			(at -17.89176 -13.916914 270)
			(size 0.4318 0.4318)
			(layers "F.Cu" "F.Mask" "F.Paste")
			(net "GND")
		)
		(pad "AJ27" smd circle
			(at -16.263874 -13.916914 270)
			(size 0.4318 0.4318)
			(layers "F.Cu" "F.Mask" "F.Paste")
			(net "M_D_CPU0_SB_DQS_DN<1>")
		)
		(pad "AJ29" smd circle
			(at -14.635988 -13.916914 270)
			(size 0.4318 0.4318)
			(layers "F.Cu" "F.Mask" "F.Paste")
			(net "GND")
		)
		(pad "AJ31" smd circle
			(at -13.008356 -13.916914 270)
			(size 0.4318 0.4318)
			(layers "F.Cu" "F.Mask" "F.Paste")
			(net "GND")
		)
		(pad "AJ33" smd circle
			(at -11.380724 -13.916914 270)
			(size 0.4318 0.4318)
			(layers "F.Cu" "F.Mask" "F.Paste")
			(net "M_D_CPU0_SB_DQS_DN<0>")
		)
		(pad "AJ35" smd circle
			(at -9.752838 -13.916914 270)
			(size 0.4318 0.4318)
			(layers "F.Cu" "F.Mask" "F.Paste")
			(net "GND")
		)
		(pad "AJ37" smd circle
			(at -8.124952 -13.916914 270)
			(size 0.4318 0.4318)
			(layers "F.Cu" "F.Mask" "F.Paste")
			(net "GND")
		)
		(pad "AJ39" smd circle
			(at -6.49732 -13.916914 270)
			(size 0.4318 0.4318)
			(layers "F.Cu" "F.Mask" "F.Paste")
			(net "M_D_CPU0_SB_DQS_DN<9>")
		)
		(pad "AJ41" smd circle
			(at -4.869434 -13.916914 270)
			(size 0.4318 0.4318)
			(layers "F.Cu" "F.Mask" "F.Paste")
			(net "GND")
		)
		(pad "AJ43" smd circle
			(at -3.241802 -13.916914 270)
			(size 0.4318 0.4318)
			(layers "F.Cu" "F.Mask" "F.Paste")
			(net "GND")
		)
		(pad "AJ45" smd circle
			(at -1.613916 -13.916914 270)
			(size 0.4318 0.4318)
			(layers "F.Cu" "F.Mask" "F.Paste")
			(net "M_D_CPU0_CLK_DN<0>")
		)
		(pad "AJ48" smd circle
			(at 2.427732 -13.806932 270)
			(size 0.4318 0.4318)
			(layers "F.Cu" "F.Mask" "F.Paste")
			(net "GND")
		)
		(pad "AJ50" smd circle
			(at 4.055618 -13.806932 270)
			(size 0.4318 0.4318)
			(layers "F.Cu" "F.Mask" "F.Paste")
			(net "GND")
		)
		(pad "AJ52" smd circle
			(at 5.68325 -13.806932 270)
			(size 0.4318 0.4318)
			(layers "F.Cu" "F.Mask" "F.Paste")
			(net "M_D_CPU0_SA_CA<0>")
		)
		(pad "AJ54" smd circle
			(at 7.311136 -13.806932 270)
			(size 0.4318 0.4318)
			(layers "F.Cu" "F.Mask" "F.Paste")
			(net "GND")
		)
		(pad "AJ56" smd circle
			(at 8.939022 -13.806932 270)
			(size 0.4318 0.4318)
			(layers "F.Cu" "F.Mask" "F.Paste")
			(net "GND")
		)
		(pad "AJ58" smd circle
			(at 10.566654 -13.806932 270)
			(size 0.4318 0.4318)
			(layers "F.Cu" "F.Mask" "F.Paste")
			(net "M_D_CPU0_SA_DQS_DN<4>")
		)
		(pad "AJ60" smd circle
			(at 12.19454 -13.806932 270)
			(size 0.4318 0.4318)
			(layers "F.Cu" "F.Mask" "F.Paste")
			(net "GND")
		)
		(pad "AJ62" smd circle
			(at 13.822426 -13.806932 270)
			(size 0.4318 0.4318)
			(layers "F.Cu" "F.Mask" "F.Paste")
			(net "GND")
		)
		(pad "AJ64" smd circle
			(at 15.450058 -13.806932 270)
			(size 0.4318 0.4318)
			(layers "F.Cu" "F.Mask" "F.Paste")
			(net "M_D_CPU0_SA_DQS_DN<3>")
		)
		(pad "AJ66" smd circle
			(at 17.07769 -13.806932 270)
			(size 0.4318 0.4318)
			(layers "F.Cu" "F.Mask" "F.Paste")
			(net "GND")
		)
		(pad "AJ68" smd circle
			(at 18.705576 -13.806932 270)
			(size 0.4318 0.4318)
			(layers "F.Cu" "F.Mask" "F.Paste")
			(net "GND")
		)
		(pad "AJ70" smd circle
			(at 20.333462 -13.806932 270)
			(size 0.4318 0.4318)
			(layers "F.Cu" "F.Mask" "F.Paste")
			(net "M_D_CPU0_SA_DQS_DN<2>")
		)
		(pad "AJ72" smd circle
			(at 21.961094 -13.806932 270)
			(size 0.4318 0.4318)
			(layers "F.Cu" "F.Mask" "F.Paste")
			(net "GND")
		)
		(pad "AJ74" smd circle
			(at 23.58898 -13.806932 270)
			(size 0.4318 0.4318)
			(layers "F.Cu" "F.Mask" "F.Paste")
			(net "GND")
		)
		(pad "AJ76" smd circle
			(at 25.216612 -13.806932 270)
			(size 0.4318 0.4318)
			(layers "F.Cu" "F.Mask" "F.Paste")
			(net "M_D_CPU0_SA_DQS_DN<1>")
		)
		(pad "AJ78" smd circle
			(at 26.844498 -13.806932 270)
			(size 0.4318 0.4318)
			(layers "F.Cu" "F.Mask" "F.Paste")
			(net "GND")
		)
		(pad "AJ80" smd circle
			(at 28.472384 -13.806932 270)
			(size 0.4318 0.4318)
			(layers "F.Cu" "F.Mask" "F.Paste")
			(net "UPI_CPU1_CPU0_P2P2_DN<13>")
		)
		(pad "AJ82" smd circle
			(at 30.100016 -13.806932 270)
			(size 0.4318 0.4318)
			(layers "F.Cu" "F.Mask" "F.Paste")
			(net "UPI_CPU1_CPU0_P2P2_DN<12>")
		)
		(pad "AJ84" smd circle
			(at 31.727902 -13.806932 270)
			(size 0.4318 0.4318)
			(layers "F.Cu" "F.Mask" "F.Paste")
			(net "GND")
		)
		(pad "AJ86" smd circle
			(at 33.355534 -13.806932 270)
			(size 0.4318 0.4318)
			(layers "F.Cu" "F.Mask" "F.Paste")
			(net "P5E_CPU0_PE4_TX_DN<9>")
		)
		(pad "AJ88" smd circle
			(at 34.98342 -13.806932 270)
			(size 0.4318 0.4318)
			(layers "F.Cu" "F.Mask" "F.Paste")
			(net "GND")
		)
		(pad "AJ90" smd circle
			(at 36.611306 -13.806932 270)
			(size 0.4318 0.4318)
			(layers "F.Cu" "F.Mask" "F.Paste")
			(net "P5E_CPU0_PE4_RX_DP<9>")
		)
		(pad "AK2" smd circle
			(at -36.611306 -13.447268 270)
			(size 0.4318 0.4318)
			(layers "F.Cu" "F.Mask" "F.Paste")
			(net "UPI_CPU0_CPU1_P0P1_DN<10>")
		)
		(pad "AK4" smd circle
			(at -34.98342 -13.447268 270)
			(size 0.4318 0.4318)
			(layers "F.Cu" "F.Mask" "F.Paste")
			(net "GND")
		)
		(pad "AK6" smd circle
			(at -33.355534 -13.447268 270)
			(size 0.4318 0.4318)
			(layers "F.Cu" "F.Mask" "F.Paste")
			(net "UPI_CPU1_CPU0_P1P0_DP<10>")
		)
		(pad "AK8" smd circle
			(at -31.727902 -13.447268 270)
			(size 0.4318 0.4318)
			(layers "F.Cu" "F.Mask" "F.Paste")
			(net "GND")
		)
		(pad "AK10" smd circle
			(at -30.100016 -13.447268 270)
			(size 0.4318 0.4318)
			(layers "F.Cu" "F.Mask" "F.Paste")
			(net "P5E_CPU0_PE0_RX_DN<10>")
		)
		(pad "AK12" smd circle
			(at -28.472384 -13.447268 270)
			(size 0.4318 0.4318)
			(layers "F.Cu" "F.Mask" "F.Paste")
			(net "GND")
		)
		(pad "AK14" smd circle
			(at -26.844498 -13.447268 270)
			(size 0.4318 0.4318)
			(layers "F.Cu" "F.Mask" "F.Paste")
			(net "P5E_CPU0_PE0_TX_DN<9>")
		)
		(pad "AK16" smd circle
			(at -25.216612 -13.447268 270)
			(size 0.4318 0.4318)
			(layers "F.Cu" "F.Mask" "F.Paste")
			(net "GND")
		)
		(pad "AK18" smd circle
			(at -23.58898 -13.447268 270)
			(size 0.4318 0.4318)
			(layers "F.Cu" "F.Mask" "F.Paste")
			(net "GND")
		)
		(pad "AK20" smd circle
			(at -21.961094 -13.447268 270)
			(size 0.4318 0.4318)
			(layers "F.Cu" "F.Mask" "F.Paste")
			(net "M_D_CPU0_SB_DQ<28>")
		)
		(pad "AK22" smd circle
			(at -20.333462 -13.447268 270)
			(size 0.4318 0.4318)
			(layers "F.Cu" "F.Mask" "F.Paste")
			(net "M_D_CPU0_SB_DQ<25>")
		)
		(pad "AK24" smd circle
			(at -18.705576 -13.447268 270)
			(size 0.4318 0.4318)
			(layers "F.Cu" "F.Mask" "F.Paste")
			(net "GND")
		)
		(pad "AK26" smd circle
			(at -17.07769 -13.447268 270)
			(size 0.4318 0.4318)
			(layers "F.Cu" "F.Mask" "F.Paste")
			(net "M_D_CPU0_SB_DQ<12>")
		)
		(pad "AK28" smd circle
			(at -15.450058 -13.447268 270)
			(size 0.4318 0.4318)
			(layers "F.Cu" "F.Mask" "F.Paste")
			(net "M_D_CPU0_SB_DQ<9>")
		)
		(pad "AK30" smd circle
			(at -13.822426 -13.447268 270)
			(size 0.4318 0.4318)
			(layers "F.Cu" "F.Mask" "F.Paste")
			(net "GND")
		)
		(pad "AK32" smd circle
			(at -12.19454 -13.447268 270)
			(size 0.4318 0.4318)
			(layers "F.Cu" "F.Mask" "F.Paste")
			(net "M_D_CPU0_SB_DQ<4>")
		)
		(pad "AK34" smd circle
			(at -10.566654 -13.447268 270)
			(size 0.4318 0.4318)
			(layers "F.Cu" "F.Mask" "F.Paste")
			(net "M_D_CPU0_SB_DQ<1>")
		)
		(pad "AK36" smd circle
			(at -8.939022 -13.447268 270)
			(size 0.4318 0.4318)
			(layers "F.Cu" "F.Mask" "F.Paste")
			(net "GND")
		)
		(pad "AK38" smd circle
			(at -7.311136 -13.447268 270)
			(size 0.4318 0.4318)
			(layers "F.Cu" "F.Mask" "F.Paste")
			(net "M_D_CPU0_SB_CB<0>")
		)
		(pad "AK40" smd circle
			(at -5.68325 -13.447268 270)
			(size 0.4318 0.4318)
			(layers "F.Cu" "F.Mask" "F.Paste")
			(net "M_D_CPU0_SB_CB<5>")
		)
		(pad "AK42" smd circle
			(at -4.055618 -13.447268 270)
			(size 0.4318 0.4318)
			(layers "F.Cu" "F.Mask" "F.Paste")
			(net "GND")
		)
		(pad "AK44" smd circle
			(at -2.427732 -13.447268 270)
			(size 0.4318 0.4318)
			(layers "F.Cu" "F.Mask" "F.Paste")
			(net "M_D_CPU0_SB_CA<0>")
		)
		(pad "AK47" smd circle
			(at 1.613916 -13.337286 270)
			(size 0.4318 0.4318)
			(layers "F.Cu" "F.Mask" "F.Paste")
			(net "M_B_CPU0_SA_RSP<1>")
		)
		(pad "AK49" smd circle
			(at 3.241802 -13.337286 270)
			(size 0.4318 0.4318)
			(layers "F.Cu" "F.Mask" "F.Paste")
			(net "GND")
		)
		(pad "AK51" smd circle
			(at 4.869434 -13.337286 270)
			(size 0.4318 0.4318)
			(layers "F.Cu" "F.Mask" "F.Paste")
			(net "M_D_CPU0_SA_CA<2>")
		)
		(pad "AK53" smd circle
			(at 6.49732 -13.337286 270)
			(size 0.4318 0.4318)
			(layers "F.Cu" "F.Mask" "F.Paste")
			(net "M_D_CPU0_SA_CS_N<1>")
		)
		(pad "AK55" smd circle
			(at 8.124952 -13.337286 270)
			(size 0.4318 0.4318)
			(layers "F.Cu" "F.Mask" "F.Paste")
			(net "GND")
		)
		(pad "AK57" smd circle
			(at 9.752838 -13.337286 270)
			(size 0.4318 0.4318)
			(layers "F.Cu" "F.Mask" "F.Paste")
			(net "M_D_CPU0_SA_CB<4>")
		)
		(pad "AK59" smd circle
			(at 11.380724 -13.337286 270)
			(size 0.4318 0.4318)
			(layers "F.Cu" "F.Mask" "F.Paste")
			(net "M_D_CPU0_SA_CB<1>")
		)
		(pad "AK61" smd circle
			(at 13.008356 -13.337286 270)
			(size 0.4318 0.4318)
			(layers "F.Cu" "F.Mask" "F.Paste")
			(net "GND")
		)
		(pad "AK63" smd circle
			(at 14.635988 -13.337286 270)
			(size 0.4318 0.4318)
			(layers "F.Cu" "F.Mask" "F.Paste")
			(net "M_D_CPU0_SA_DQ<28>")
		)
		(pad "AK65" smd circle
			(at 16.263874 -13.337286 270)
			(size 0.4318 0.4318)
			(layers "F.Cu" "F.Mask" "F.Paste")
			(net "M_D_CPU0_SA_DQ<25>")
		)
		(pad "AK67" smd circle
			(at 17.89176 -13.337286 270)
			(size 0.4318 0.4318)
			(layers "F.Cu" "F.Mask" "F.Paste")
			(net "GND")
		)
		(pad "AK69" smd circle
			(at 19.519392 -13.337286 270)
			(size 0.4318 0.4318)
			(layers "F.Cu" "F.Mask" "F.Paste")
			(net "M_D_CPU0_SA_DQ<20>")
		)
		(pad "AK71" smd circle
			(at 21.147278 -13.337286 270)
			(size 0.4318 0.4318)
			(layers "F.Cu" "F.Mask" "F.Paste")
			(net "M_D_CPU0_SA_DQ<17>")
		)
		(pad "AK73" smd circle
			(at 22.77491 -13.337286 270)
			(size 0.4318 0.4318)
			(layers "F.Cu" "F.Mask" "F.Paste")
			(net "GND")
		)
		(pad "AK75" smd circle
			(at 24.402796 -13.337286 270)
			(size 0.4318 0.4318)
			(layers "F.Cu" "F.Mask" "F.Paste")
			(net "M_D_CPU0_SA_DQ<12>")
		)
		(pad "AK77" smd circle
			(at 26.030682 -13.337286 270)
			(size 0.4318 0.4318)
			(layers "F.Cu" "F.Mask" "F.Paste")
			(net "M_D_CPU0_SA_DQ<9>")
		)
		(pad "AK79" smd circle
			(at 27.658314 -13.337286 270)
			(size 0.4318 0.4318)
			(layers "F.Cu" "F.Mask" "F.Paste")
			(net "GND")
		)
		(pad "AK81" smd circle
			(at 29.2862 -13.337286 270)
			(size 0.4318 0.4318)
			(layers "F.Cu" "F.Mask" "F.Paste")
			(net "GND")
		)
		(pad "AK83" smd circle
			(at 30.914086 -13.337286 270)
			(size 0.4318 0.4318)
			(layers "F.Cu" "F.Mask" "F.Paste")
			(net "GND")
		)
		(pad "AK85" smd circle
			(at 32.541718 -13.337286 270)
			(size 0.4318 0.4318)
			(layers "F.Cu" "F.Mask" "F.Paste")
			(net "P5E_CPU0_PE4_TX_DP<9>")
		)
		(pad "AK87" smd circle
			(at 34.169604 -13.337286 270)
			(size 0.4318 0.4318)
			(layers "F.Cu" "F.Mask" "F.Paste")
			(net "GND")
		)
		(pad "AK89" smd circle
			(at 35.797236 -13.337286 270)
			(size 0.4318 0.4318)
			(layers "F.Cu" "F.Mask" "F.Paste")
			(net "P5E_CPU0_PE4_RX_DN<9>")
		)
		(pad "AK91" smd oval
			(at 37.425122 -13.337286)
			(size 0.381 0.4826)
			(drill
				(offset 0 -0.0508)
			)
			(layers "F.Cu" "F.Mask" "F.Paste")
			(net "GND")
		)
		(pad "AL1" smd oval
			(at -37.425122 -12.977114 180)
			(size 0.381 0.4826)
			(drill
				(offset 0 -0.0508)
			)
			(layers "F.Cu" "F.Mask" "F.Paste")
			(net "GND")
		)
		(pad "AL3" smd circle
			(at -35.797236 -12.977114 270)
			(size 0.4318 0.4318)
			(layers "F.Cu" "F.Mask" "F.Paste")
			(net "UPI_CPU0_CPU1_P0P1_DP<11>")
		)
		(pad "AL5" smd circle
			(at -34.169604 -12.977114 270)
			(size 0.4318 0.4318)
			(layers "F.Cu" "F.Mask" "F.Paste")
			(net "GND")
		)
		(pad "AL7" smd circle
			(at -32.541718 -12.977114 270)
			(size 0.4318 0.4318)
			(layers "F.Cu" "F.Mask" "F.Paste")
			(net "UPI_CPU1_CPU0_P1P0_DN<10>")
		)
		(pad "AL9" smd circle
			(at -30.914086 -12.977114 270)
			(size 0.4318 0.4318)
			(layers "F.Cu" "F.Mask" "F.Paste")
			(net "GND")
		)
		(pad "AL11" smd circle
			(at -29.2862 -12.977114 270)
			(size 0.4318 0.4318)
			(layers "F.Cu" "F.Mask" "F.Paste")
			(net "P5E_CPU0_PE0_RX_DP<10>")
		)
		(pad "AL13" smd circle
			(at -27.658314 -12.977114 270)
			(size 0.4318 0.4318)
			(layers "F.Cu" "F.Mask" "F.Paste")
			(net "GND")
		)
		(pad "AL15" smd circle
			(at -26.030682 -12.977114 270)
			(size 0.4318 0.4318)
			(layers "F.Cu" "F.Mask" "F.Paste")
			(net "P5E_CPU0_PE0_TX_DP<9>")
		)
		(pad "AL17" smd circle
			(at -24.402796 -12.977114 270)
			(size 0.4318 0.4318)
			(layers "F.Cu" "F.Mask" "F.Paste")
			(net "GND")
		)
		(pad "AL19" smd circle
			(at -22.77491 -12.977114 270)
			(size 0.4318 0.4318)
			(layers "F.Cu" "F.Mask" "F.Paste")
			(net "M_D_CPU0_SB_DQ<29>")
		)
		(pad "AL21" smd circle
			(at -21.147278 -12.977114 270)
			(size 0.4318 0.4318)
			(layers "F.Cu" "F.Mask" "F.Paste")
			(net "M_D_CPU0_SB_DQS_DP<3>")
		)
		(pad "AL23" smd circle
			(at -19.519392 -12.977114 270)
			(size 0.4318 0.4318)
			(layers "F.Cu" "F.Mask" "F.Paste")
			(net "M_D_CPU0_SB_DQ<24>")
		)
		(pad "AL25" smd circle
			(at -17.89176 -12.977114 270)
			(size 0.4318 0.4318)
			(layers "F.Cu" "F.Mask" "F.Paste")
			(net "M_D_CPU0_SB_DQ<13>")
		)
		(pad "AL27" smd circle
			(at -16.263874 -12.977114 270)
			(size 0.4318 0.4318)
			(layers "F.Cu" "F.Mask" "F.Paste")
			(net "M_D_CPU0_SB_DQS_DP<1>")
		)
		(pad "AL29" smd circle
			(at -14.635988 -12.977114 270)
			(size 0.4318 0.4318)
			(layers "F.Cu" "F.Mask" "F.Paste")
			(net "M_D_CPU0_SB_DQ<8>")
		)
		(pad "AL31" smd circle
			(at -13.008356 -12.977114 270)
			(size 0.4318 0.4318)
			(layers "F.Cu" "F.Mask" "F.Paste")
			(net "M_D_CPU0_SB_DQ<5>")
		)
		(pad "AL33" smd circle
			(at -11.380724 -12.977114 270)
			(size 0.4318 0.4318)
			(layers "F.Cu" "F.Mask" "F.Paste")
			(net "M_D_CPU0_SB_DQS_DP<0>")
		)
		(pad "AL35" smd circle
			(at -9.752838 -12.977114 270)
			(size 0.4318 0.4318)
			(layers "F.Cu" "F.Mask" "F.Paste")
			(net "M_D_CPU0_SB_DQ<0>")
		)
		(pad "AL37" smd circle
			(at -8.124952 -12.977114 270)
			(size 0.4318 0.4318)
			(layers "F.Cu" "F.Mask" "F.Paste")
			(net "M_D_CPU0_SB_CB<1>")
		)
		(pad "AL39" smd circle
			(at -6.49732 -12.977114 270)
			(size 0.4318 0.4318)
			(layers "F.Cu" "F.Mask" "F.Paste")
			(net "M_D_CPU0_SB_DQS_DP<9>")
		)
		(pad "AL41" smd circle
			(at -4.869434 -12.977114 270)
			(size 0.4318 0.4318)
			(layers "F.Cu" "F.Mask" "F.Paste")
			(net "M_D_CPU0_SB_CB<4>")
		)
		(pad "AL43" smd circle
			(at -3.241802 -12.977114 270)
			(size 0.4318 0.4318)
			(layers "F.Cu" "F.Mask" "F.Paste")
			(net "M_D_CPU0_SB_CA<1>")
		)
		(pad "AL45" smd circle
			(at -1.613916 -12.977114 270)
			(size 0.4318 0.4318)
			(layers "F.Cu" "F.Mask" "F.Paste")
			(net "M_D_CPU0_CLK_DP<0>")
		)
		(pad "AL48" smd circle
			(at 2.427732 -12.867132 270)
			(size 0.4318 0.4318)
			(layers "F.Cu" "F.Mask" "F.Paste")
			(net "M_B_CPU0_SA_RSP<0>")
		)
		(pad "AL50" smd circle
			(at 4.055618 -12.867132 270)
			(size 0.4318 0.4318)
			(layers "F.Cu" "F.Mask" "F.Paste")
			(net "M_D_CPU0_SA_CA<4>")
		)
		(pad "AL52" smd circle
			(at 5.68325 -12.867132 270)
			(size 0.4318 0.4318)
			(layers "F.Cu" "F.Mask" "F.Paste")
			(net "GND")
		)
		(pad "AL54" smd circle
			(at 7.311136 -12.867132 270)
			(size 0.4318 0.4318)
			(layers "F.Cu" "F.Mask" "F.Paste")
			(net "M_D_CPU0_SA_CS_N<0>")
		)
		(pad "AL56" smd circle
			(at 8.939022 -12.867132 270)
			(size 0.4318 0.4318)
			(layers "F.Cu" "F.Mask" "F.Paste")
			(net "M_D_CPU0_SA_CB<5>")
		)
		(pad "AL58" smd circle
			(at 10.566654 -12.867132 270)
			(size 0.4318 0.4318)
			(layers "F.Cu" "F.Mask" "F.Paste")
			(net "M_D_CPU0_SA_DQS_DP<4>")
		)
		(pad "AL60" smd circle
			(at 12.19454 -12.867132 270)
			(size 0.4318 0.4318)
			(layers "F.Cu" "F.Mask" "F.Paste")
			(net "M_D_CPU0_SA_CB<0>")
		)
		(pad "AL62" smd circle
			(at 13.822426 -12.867132 270)
			(size 0.4318 0.4318)
			(layers "F.Cu" "F.Mask" "F.Paste")
			(net "M_D_CPU0_SA_DQ<29>")
		)
		(pad "AL64" smd circle
			(at 15.450058 -12.867132 270)
			(size 0.4318 0.4318)
			(layers "F.Cu" "F.Mask" "F.Paste")
			(net "M_D_CPU0_SA_DQS_DP<3>")
		)
		(pad "AL66" smd circle
			(at 17.07769 -12.867132 270)
			(size 0.4318 0.4318)
			(layers "F.Cu" "F.Mask" "F.Paste")
			(net "M_D_CPU0_SA_DQ<24>")
		)
		(pad "AL68" smd circle
			(at 18.705576 -12.867132 270)
			(size 0.4318 0.4318)
			(layers "F.Cu" "F.Mask" "F.Paste")
			(net "M_D_CPU0_SA_DQ<21>")
		)
		(pad "AL70" smd circle
			(at 20.333462 -12.867132 270)
			(size 0.4318 0.4318)
			(layers "F.Cu" "F.Mask" "F.Paste")
			(net "M_D_CPU0_SA_DQS_DP<2>")
		)
		(pad "AL72" smd circle
			(at 21.961094 -12.867132 270)
			(size 0.4318 0.4318)
			(layers "F.Cu" "F.Mask" "F.Paste")
			(net "M_D_CPU0_SA_DQ<16>")
		)
		(pad "AL74" smd circle
			(at 23.58898 -12.867132 270)
			(size 0.4318 0.4318)
			(layers "F.Cu" "F.Mask" "F.Paste")
			(net "M_D_CPU0_SA_DQ<13>")
		)
		(pad "AL76" smd circle
			(at 25.216612 -12.867132 270)
			(size 0.4318 0.4318)
			(layers "F.Cu" "F.Mask" "F.Paste")
			(net "M_D_CPU0_SA_DQS_DP<1>")
		)
		(pad "AL78" smd circle
			(at 26.844498 -12.867132 270)
			(size 0.4318 0.4318)
			(layers "F.Cu" "F.Mask" "F.Paste")
			(net "M_D_CPU0_SA_DQ<8>")
		)
		(pad "AL80" smd circle
			(at 28.472384 -12.867132 270)
			(size 0.4318 0.4318)
			(layers "F.Cu" "F.Mask" "F.Paste")
			(net "GND")
		)
		(pad "AL82" smd circle
			(at 30.100016 -12.867132 270)
			(size 0.4318 0.4318)
			(layers "F.Cu" "F.Mask" "F.Paste")
			(net "GND")
		)
		(pad "AL84" smd circle
			(at 31.727902 -12.867132 270)
			(size 0.4318 0.4318)
			(layers "F.Cu" "F.Mask" "F.Paste")
			(net "GND")
		)
		(pad "AL86" smd circle
			(at 33.355534 -12.867132 270)
			(size 0.4318 0.4318)
			(layers "F.Cu" "F.Mask" "F.Paste")
			(net "P5E_CPU0_PE4_TX_DN<10>")
		)
		(pad "AL88" smd circle
			(at 34.98342 -12.867132 270)
			(size 0.4318 0.4318)
			(layers "F.Cu" "F.Mask" "F.Paste")
			(net "GND")
		)
		(pad "AL90" smd circle
			(at 36.611306 -12.867132 270)
			(size 0.4318 0.4318)
			(layers "F.Cu" "F.Mask" "F.Paste")
			(net "P5E_CPU0_PE4_RX_DP<10>")
		)
		(pad "AM2" smd circle
			(at -36.611306 -12.507468 270)
			(size 0.4318 0.4318)
			(layers "F.Cu" "F.Mask" "F.Paste")
			(net "UPI_CPU0_CPU1_P0P1_DN<11>")
		)
		(pad "AM4" smd circle
			(at -34.98342 -12.507468 270)
			(size 0.4318 0.4318)
			(layers "F.Cu" "F.Mask" "F.Paste")
			(net "GND")
		)
		(pad "AM6" smd circle
			(at -33.355534 -12.507468 270)
			(size 0.4318 0.4318)
			(layers "F.Cu" "F.Mask" "F.Paste")
			(net "UPI_CPU1_CPU0_P1P0_DN<11>")
		)
		(pad "AM8" smd circle
			(at -31.727902 -12.507468 270)
			(size 0.4318 0.4318)
			(layers "F.Cu" "F.Mask" "F.Paste")
			(net "GND")
		)
		(pad "AM10" smd circle
			(at -30.100016 -12.507468 270)
			(size 0.4318 0.4318)
			(layers "F.Cu" "F.Mask" "F.Paste")
			(net "P5E_CPU0_PE0_RX_DN<11>")
		)
		(pad "AM12" smd circle
			(at -28.472384 -12.507468 270)
			(size 0.4318 0.4318)
			(layers "F.Cu" "F.Mask" "F.Paste")
			(net "GND")
		)
		(pad "AM14" smd circle
			(at -26.844498 -12.507468 270)
			(size 0.4318 0.4318)
			(layers "F.Cu" "F.Mask" "F.Paste")
			(net "P5E_CPU0_PE0_TX_DP<10>")
		)
		(pad "AM16" smd circle
			(at -25.216612 -12.507468 270)
			(size 0.4318 0.4318)
			(layers "F.Cu" "F.Mask" "F.Paste")
			(net "GND")
		)
		(pad "AM18" smd circle
			(at -23.58898 -12.507468 270)
			(size 0.4318 0.4318)
			(layers "F.Cu" "F.Mask" "F.Paste")
			(net "GND")
		)
		(pad "AM20" smd circle
			(at -21.961094 -12.507468 270)
			(size 0.4318 0.4318)
			(layers "F.Cu" "F.Mask" "F.Paste")
			(net "GND")
		)
		(pad "AM22" smd circle
			(at -20.333462 -12.507468 270)
			(size 0.4318 0.4318)
			(layers "F.Cu" "F.Mask" "F.Paste")
			(net "GND")
		)
		(pad "AM24" smd circle
			(at -18.705576 -12.507468 270)
			(size 0.4318 0.4318)
			(layers "F.Cu" "F.Mask" "F.Paste")
			(net "GND")
		)
		(pad "AM26" smd circle
			(at -17.07769 -12.507468 270)
			(size 0.4318 0.4318)
			(layers "F.Cu" "F.Mask" "F.Paste")
			(net "GND")
		)
		(pad "AM28" smd circle
			(at -15.450058 -12.507468 270)
			(size 0.4318 0.4318)
			(layers "F.Cu" "F.Mask" "F.Paste")
			(net "GND")
		)
		(pad "AM30" smd circle
			(at -13.822426 -12.507468 270)
			(size 0.4318 0.4318)
			(layers "F.Cu" "F.Mask" "F.Paste")
			(net "GND")
		)
		(pad "AM32" smd circle
			(at -12.19454 -12.507468 270)
			(size 0.4318 0.4318)
			(layers "F.Cu" "F.Mask" "F.Paste")
			(net "GND")
		)
		(pad "AM34" smd circle
			(at -10.566654 -12.507468 270)
			(size 0.4318 0.4318)
			(layers "F.Cu" "F.Mask" "F.Paste")
			(net "GND")
		)
		(pad "AM36" smd circle
			(at -8.939022 -12.507468 270)
			(size 0.4318 0.4318)
			(layers "F.Cu" "F.Mask" "F.Paste")
			(net "GND")
		)
		(pad "AM38" smd circle
			(at -7.311136 -12.507468 270)
			(size 0.4318 0.4318)
			(layers "F.Cu" "F.Mask" "F.Paste")
			(net "GND")
		)
		(pad "AM40" smd circle
			(at -5.68325 -12.507468 270)
			(size 0.4318 0.4318)
			(layers "F.Cu" "F.Mask" "F.Paste")
			(net "GND")
		)
		(pad "AM42" smd circle
			(at -4.055618 -12.507468 270)
			(size 0.4318 0.4318)
			(layers "F.Cu" "F.Mask" "F.Paste")
			(net "GND")
		)
		(pad "AM44" smd circle
			(at -2.427732 -12.507468 270)
			(size 0.4318 0.4318)
			(layers "F.Cu" "F.Mask" "F.Paste")
			(net "GND")
		)
		(pad "AM47" smd circle
			(at 1.613916 -12.397486 270)
			(size 0.4318 0.4318)
			(layers "F.Cu" "F.Mask" "F.Paste")
			(net "GND")
		)
		(pad "AM49" smd circle
			(at 3.241802 -12.397486 270)
			(size 0.4318 0.4318)
			(layers "F.Cu" "F.Mask" "F.Paste")
			(net "GND")
		)
		(pad "AM51" smd circle
			(at 4.869434 -12.397486 270)
			(size 0.4318 0.4318)
			(layers "F.Cu" "F.Mask" "F.Paste")
			(net "GND")
		)
		(pad "AM53" smd circle
			(at 6.49732 -12.397486 270)
			(size 0.4318 0.4318)
			(layers "F.Cu" "F.Mask" "F.Paste")
			(net "GND")
		)
		(pad "AM55" smd circle
			(at 8.124952 -12.397486 270)
			(size 0.4318 0.4318)
			(layers "F.Cu" "F.Mask" "F.Paste")
			(net "GND")
		)
		(pad "AM57" smd circle
			(at 9.752838 -12.397486 270)
			(size 0.4318 0.4318)
			(layers "F.Cu" "F.Mask" "F.Paste")
			(net "GND")
		)
		(pad "AM59" smd circle
			(at 11.380724 -12.397486 270)
			(size 0.4318 0.4318)
			(layers "F.Cu" "F.Mask" "F.Paste")
			(net "GND")
		)
		(pad "AM61" smd circle
			(at 13.008356 -12.397486 270)
			(size 0.4318 0.4318)
			(layers "F.Cu" "F.Mask" "F.Paste")
			(net "GND")
		)
		(pad "AM63" smd circle
			(at 14.635988 -12.397486 270)
			(size 0.4318 0.4318)
			(layers "F.Cu" "F.Mask" "F.Paste")
			(net "GND")
		)
		(pad "AM65" smd circle
			(at 16.263874 -12.397486 270)
			(size 0.4318 0.4318)
			(layers "F.Cu" "F.Mask" "F.Paste")
			(net "GND")
		)
		(pad "AM67" smd circle
			(at 17.89176 -12.397486 270)
			(size 0.4318 0.4318)
			(layers "F.Cu" "F.Mask" "F.Paste")
			(net "GND")
		)
		(pad "AM69" smd circle
			(at 19.519392 -12.397486 270)
			(size 0.4318 0.4318)
			(layers "F.Cu" "F.Mask" "F.Paste")
			(net "GND")
		)
		(pad "AM71" smd circle
			(at 21.147278 -12.397486 270)
			(size 0.4318 0.4318)
			(layers "F.Cu" "F.Mask" "F.Paste")
			(net "GND")
		)
		(pad "AM73" smd circle
			(at 22.77491 -12.397486 270)
			(size 0.4318 0.4318)
			(layers "F.Cu" "F.Mask" "F.Paste")
			(net "GND")
		)
		(pad "AM75" smd circle
			(at 24.402796 -12.397486 270)
			(size 0.4318 0.4318)
			(layers "F.Cu" "F.Mask" "F.Paste")
			(net "GND")
		)
		(pad "AM77" smd circle
			(at 26.030682 -12.397486 270)
			(size 0.4318 0.4318)
			(layers "F.Cu" "F.Mask" "F.Paste")
			(net "GND")
		)
		(pad "AM79" smd circle
			(at 27.658314 -12.397486 270)
			(size 0.4318 0.4318)
			(layers "F.Cu" "F.Mask" "F.Paste")
			(net "PVCCFA_EHV_FIVRA_CPU0")
		)
		(pad "AM81" smd circle
			(at 29.2862 -12.397486 270)
			(size 0.4318 0.4318)
			(layers "F.Cu" "F.Mask" "F.Paste")
			(net "UPI_CPU0_CPU1_P2P2_DN<11>")
		)
		(pad "AM83" smd circle
			(at 30.914086 -12.397486 270)
			(size 0.4318 0.4318)
			(layers "F.Cu" "F.Mask" "F.Paste")
			(net "UPI_CPU0_CPU1_P2P2_DP<10>")
		)
		(pad "AM85" smd circle
			(at 32.541718 -12.397486 270)
			(size 0.4318 0.4318)
			(layers "F.Cu" "F.Mask" "F.Paste")
			(net "PVCCFA_EHV_FIVRA_CPU0")
		)
		(pad "AM87" smd circle
			(at 34.169604 -12.397486 270)
			(size 0.4318 0.4318)
			(layers "F.Cu" "F.Mask" "F.Paste")
			(net "P5E_CPU0_PE4_TX_DP<10>")
		)
		(pad "AM89" smd circle
			(at 35.797236 -12.397486 270)
			(size 0.4318 0.4318)
			(layers "F.Cu" "F.Mask" "F.Paste")
			(net "PVCCFA_EHV_FIVRA_CPU0")
		)
		(pad "AM91" smd oval
			(at 37.425122 -12.397486)
			(size 0.381 0.4826)
			(drill
				(offset 0 -0.0508)
			)
			(layers "F.Cu" "F.Mask" "F.Paste")
			(net "P5E_CPU0_PE4_RX_DN<10>")
		)
		(pad "AN1" smd oval
			(at -37.425122 -12.037314 180)
			(size 0.381 0.4826)
			(drill
				(offset 0 -0.0508)
			)
			(layers "F.Cu" "F.Mask" "F.Paste")
			(net "UPI_CPU0_CPU1_P0P1_DN<12>")
		)
		(pad "AN3" smd circle
			(at -35.797236 -12.037314 270)
			(size 0.4318 0.4318)
			(layers "F.Cu" "F.Mask" "F.Paste")
			(net "PVCCFA_EHV_CPU0")
		)
		(pad "AN5" smd circle
			(at -34.169604 -12.037314 270)
			(size 0.4318 0.4318)
			(layers "F.Cu" "F.Mask" "F.Paste")
			(net "UPI_CPU1_CPU0_P1P0_DP<11>")
		)
		(pad "AN7" smd circle
			(at -32.541718 -12.037314 270)
			(size 0.4318 0.4318)
			(layers "F.Cu" "F.Mask" "F.Paste")
			(net "PVCCFA_EHV_FIVRA_CPU0")
		)
		(pad "AN9" smd circle
			(at -30.914086 -12.037314 270)
			(size 0.4318 0.4318)
			(layers "F.Cu" "F.Mask" "F.Paste")
			(net "P5E_CPU0_PE0_RX_DP<11>")
		)
		(pad "AN11" smd circle
			(at -29.2862 -12.037314 270)
			(size 0.4318 0.4318)
			(layers "F.Cu" "F.Mask" "F.Paste")
			(net "PVCCFA_EHV_FIVRA_CPU0")
		)
		(pad "AN13" smd circle
			(at -27.658314 -12.037314 270)
			(size 0.4318 0.4318)
			(layers "F.Cu" "F.Mask" "F.Paste")
			(net "P5E_CPU0_PE0_TX_DN<10>")
		)
		(pad "AN15" smd circle
			(at -26.030682 -12.037314 270)
			(size 0.4318 0.4318)
			(layers "F.Cu" "F.Mask" "F.Paste")
			(net "PVCCFA_EHV_FIVRA_CPU0")
		)
		(pad "AN17" smd circle
			(at -24.402796 -12.037314 270)
			(size 0.4318 0.4318)
			(layers "F.Cu" "F.Mask" "F.Paste")
			(net "NC_CPU0_UPI0_APROBE<0>")
		)
		(pad "AN19" smd circle
			(at -22.77491 -12.037314 270)
			(size 0.4318 0.4318)
			(layers "F.Cu" "F.Mask" "F.Paste")
			(net "M_D_CPU0_SB_DQ<31>")
		)
		(pad "AN21" smd circle
			(at -21.147278 -12.037314 270)
			(size 0.4318 0.4318)
			(layers "F.Cu" "F.Mask" "F.Paste")
			(net "M_D_CPU0_SB_DQS_DN<8>")
		)
		(pad "AN23" smd circle
			(at -19.519392 -12.037314 270)
			(size 0.4318 0.4318)
			(layers "F.Cu" "F.Mask" "F.Paste")
			(net "M_D_CPU0_SB_DQ<26>")
		)
		(pad "AN25" smd circle
			(at -17.89176 -12.037314 270)
			(size 0.4318 0.4318)
			(layers "F.Cu" "F.Mask" "F.Paste")
			(net "M_D_CPU0_SB_DQ<15>")
		)
		(pad "AN27" smd circle
			(at -16.263874 -12.037314 270)
			(size 0.4318 0.4318)
			(layers "F.Cu" "F.Mask" "F.Paste")
			(net "M_D_CPU0_SB_DQS_DN<6>")
		)
		(pad "AN29" smd circle
			(at -14.635988 -12.037314 270)
			(size 0.4318 0.4318)
			(layers "F.Cu" "F.Mask" "F.Paste")
			(net "M_D_CPU0_SB_DQ<10>")
		)
		(pad "AN31" smd circle
			(at -13.008356 -12.037314 270)
			(size 0.4318 0.4318)
			(layers "F.Cu" "F.Mask" "F.Paste")
			(net "M_D_CPU0_SB_DQ<7>")
		)
		(pad "AN33" smd circle
			(at -11.380724 -12.037314 270)
			(size 0.4318 0.4318)
			(layers "F.Cu" "F.Mask" "F.Paste")
			(net "M_D_CPU0_SB_DQS_DN<5>")
		)
		(pad "AN35" smd circle
			(at -9.752838 -12.037314 270)
			(size 0.4318 0.4318)
			(layers "F.Cu" "F.Mask" "F.Paste")
			(net "M_D_CPU0_SB_DQ<2>")
		)
		(pad "AN37" smd circle
			(at -8.124952 -12.037314 270)
			(size 0.4318 0.4318)
			(layers "F.Cu" "F.Mask" "F.Paste")
			(net "M_D_CPU0_SB_CB<3>")
		)
		(pad "AN39" smd circle
			(at -6.49732 -12.037314 270)
			(size 0.4318 0.4318)
			(layers "F.Cu" "F.Mask" "F.Paste")
			(net "M_D_CPU0_SB_DQS_DP<4>")
		)
		(pad "AN41" smd circle
			(at -4.869434 -12.037314 270)
			(size 0.4318 0.4318)
			(layers "F.Cu" "F.Mask" "F.Paste")
			(net "M_D_CPU0_SB_CB<6>")
		)
		(pad "AN43" smd circle
			(at -3.241802 -12.037314 270)
			(size 0.4318 0.4318)
			(layers "F.Cu" "F.Mask" "F.Paste")
			(net "M_D_CPU0_SA_CA<6>")
		)
		(pad "AN45" smd circle
			(at -1.613916 -12.037314 270)
			(size 0.4318 0.4318)
			(layers "F.Cu" "F.Mask" "F.Paste")
			(net "M_D_CPU0_CLK_DN<1>")
		)
		(pad "AN48" smd circle
			(at 2.427732 -11.927332 270)
			(size 0.4318 0.4318)
			(layers "F.Cu" "F.Mask" "F.Paste")
			(net "M_B_CPU0_SB_RSP<0>")
		)
		(pad "AN50" smd circle
			(at 4.055618 -11.927332 270)
			(size 0.4318 0.4318)
			(layers "F.Cu" "F.Mask" "F.Paste")
			(net "M_D_CPU0_SA_CA<5>")
		)
		(pad "AN52" smd circle
			(at 5.68325 -11.927332 270)
			(size 0.4318 0.4318)
			(layers "F.Cu" "F.Mask" "F.Paste")
			(net "GND")
		)
		(pad "AN54" smd circle
			(at 7.311136 -11.927332 270)
			(size 0.4318 0.4318)
			(layers "F.Cu" "F.Mask" "F.Paste")
			(net "M_D_CPU0_SA_CS_N<2>")
		)
		(pad "AN56" smd circle
			(at 8.939022 -11.927332 270)
			(size 0.4318 0.4318)
			(layers "F.Cu" "F.Mask" "F.Paste")
			(net "M_D_CPU0_SA_CB<7>")
		)
		(pad "AN58" smd circle
			(at 10.566654 -11.927332 270)
			(size 0.4318 0.4318)
			(layers "F.Cu" "F.Mask" "F.Paste")
			(net "M_D_CPU0_SA_DQS_DN<9>")
		)
		(pad "AN60" smd circle
			(at 12.19454 -11.927332 270)
			(size 0.4318 0.4318)
			(layers "F.Cu" "F.Mask" "F.Paste")
			(net "M_D_CPU0_SA_CB<2>")
		)
		(pad "AN62" smd circle
			(at 13.822426 -11.927332 270)
			(size 0.4318 0.4318)
			(layers "F.Cu" "F.Mask" "F.Paste")
			(net "M_D_CPU0_SA_DQ<31>")
		)
		(pad "AN64" smd circle
			(at 15.450058 -11.927332 270)
			(size 0.4318 0.4318)
			(layers "F.Cu" "F.Mask" "F.Paste")
			(net "M_D_CPU0_SA_DQS_DN<8>")
		)
		(pad "AN66" smd circle
			(at 17.07769 -11.927332 270)
			(size 0.4318 0.4318)
			(layers "F.Cu" "F.Mask" "F.Paste")
			(net "M_D_CPU0_SA_DQ<26>")
		)
		(pad "AN68" smd circle
			(at 18.705576 -11.927332 270)
			(size 0.4318 0.4318)
			(layers "F.Cu" "F.Mask" "F.Paste")
			(net "M_D_CPU0_SA_DQ<23>")
		)
		(pad "AN70" smd circle
			(at 20.333462 -11.927332 270)
			(size 0.4318 0.4318)
			(layers "F.Cu" "F.Mask" "F.Paste")
			(net "M_D_CPU0_SA_DQS_DN<7>")
		)
		(pad "AN72" smd circle
			(at 21.961094 -11.927332 270)
			(size 0.4318 0.4318)
			(layers "F.Cu" "F.Mask" "F.Paste")
			(net "M_D_CPU0_SA_DQ<18>")
		)
		(pad "AN74" smd circle
			(at 23.58898 -11.927332 270)
			(size 0.4318 0.4318)
			(layers "F.Cu" "F.Mask" "F.Paste")
			(net "M_D_CPU0_SA_DQ<15>")
		)
		(pad "AN76" smd circle
			(at 25.216612 -11.927332 270)
			(size 0.4318 0.4318)
			(layers "F.Cu" "F.Mask" "F.Paste")
			(net "M_D_CPU0_SA_DQS_DN<6>")
		)
		(pad "AN78" smd circle
			(at 26.844498 -11.927332 270)
			(size 0.4318 0.4318)
			(layers "F.Cu" "F.Mask" "F.Paste")
			(net "M_D_CPU0_SA_DQ<10>")
		)
		(pad "AN80" smd circle
			(at 28.472384 -11.927332 270)
			(size 0.4318 0.4318)
			(layers "F.Cu" "F.Mask" "F.Paste")
			(net "PVCCFA_EHV_FIVRA_CPU0")
		)
		(pad "AN82" smd circle
			(at 30.100016 -11.927332 270)
			(size 0.4318 0.4318)
			(layers "F.Cu" "F.Mask" "F.Paste")
			(net "UPI_CPU0_CPU1_P2P2_DN<10>")
		)
		(pad "AN84" smd circle
			(at 31.727902 -11.927332 270)
			(size 0.4318 0.4318)
			(layers "F.Cu" "F.Mask" "F.Paste")
			(net "GND")
		)
		(pad "AN86" smd circle
			(at 33.355534 -11.927332 270)
			(size 0.4318 0.4318)
			(layers "F.Cu" "F.Mask" "F.Paste")
			(net "P5E_CPU0_PE4_TX_DP<11>")
		)
		(pad "AN88" smd circle
			(at 34.98342 -11.927332 270)
			(size 0.4318 0.4318)
			(layers "F.Cu" "F.Mask" "F.Paste")
			(net "GND")
		)
		(pad "AN90" smd circle
			(at 36.611306 -11.927332 270)
			(size 0.4318 0.4318)
			(layers "F.Cu" "F.Mask" "F.Paste")
			(net "P5E_CPU0_PE4_RX_DP<11>")
		)
		(pad "AP2" smd circle
			(at -36.611306 -11.567668 270)
			(size 0.4318 0.4318)
			(layers "F.Cu" "F.Mask" "F.Paste")
			(net "UPI_CPU0_CPU1_P0P1_DP<12>")
		)
		(pad "AP4" smd circle
			(at -34.98342 -11.567668 270)
			(size 0.4318 0.4318)
			(layers "F.Cu" "F.Mask" "F.Paste")
			(net "GND")
		)
		(pad "AP6" smd circle
			(at -33.355534 -11.567668 270)
			(size 0.4318 0.4318)
			(layers "F.Cu" "F.Mask" "F.Paste")
			(net "UPI_CPU1_CPU0_P1P0_DP<12>")
		)
		(pad "AP8" smd circle
			(at -31.727902 -11.567668 270)
			(size 0.4318 0.4318)
			(layers "F.Cu" "F.Mask" "F.Paste")
			(net "GND")
		)
		(pad "AP10" smd circle
			(at -30.100016 -11.567668 270)
			(size 0.4318 0.4318)
			(layers "F.Cu" "F.Mask" "F.Paste")
			(net "P5E_CPU0_PE0_RX_DN<12>")
		)
		(pad "AP12" smd circle
			(at -28.472384 -11.567668 270)
			(size 0.4318 0.4318)
			(layers "F.Cu" "F.Mask" "F.Paste")
			(net "GND")
		)
		(pad "AP14" smd circle
			(at -26.844498 -11.567668 270)
			(size 0.4318 0.4318)
			(layers "F.Cu" "F.Mask" "F.Paste")
			(net "P5E_CPU0_PE0_TX_DN<11>")
		)
		(pad "AP16" smd circle
			(at -25.216612 -11.567668 270)
			(size 0.4318 0.4318)
			(layers "F.Cu" "F.Mask" "F.Paste")
			(net "GND")
		)
		(pad "AP18" smd circle
			(at -23.58898 -11.567668 270)
			(size 0.4318 0.4318)
			(layers "F.Cu" "F.Mask" "F.Paste")
			(net "GND")
		)
		(pad "AP20" smd circle
			(at -21.961094 -11.567668 270)
			(size 0.4318 0.4318)
			(layers "F.Cu" "F.Mask" "F.Paste")
			(net "M_D_CPU0_SB_DQ<30>")
		)
		(pad "AP22" smd circle
			(at -20.333462 -11.567668 270)
			(size 0.4318 0.4318)
			(layers "F.Cu" "F.Mask" "F.Paste")
			(net "M_D_CPU0_SB_DQ<27>")
		)
		(pad "AP24" smd circle
			(at -18.705576 -11.567668 270)
			(size 0.4318 0.4318)
			(layers "F.Cu" "F.Mask" "F.Paste")
			(net "GND")
		)
		(pad "AP26" smd circle
			(at -17.07769 -11.567668 270)
			(size 0.4318 0.4318)
			(layers "F.Cu" "F.Mask" "F.Paste")
			(net "M_D_CPU0_SB_DQ<14>")
		)
		(pad "AP28" smd circle
			(at -15.450058 -11.567668 270)
			(size 0.4318 0.4318)
			(layers "F.Cu" "F.Mask" "F.Paste")
			(net "M_D_CPU0_SB_DQ<11>")
		)
		(pad "AP30" smd circle
			(at -13.822426 -11.567668 270)
			(size 0.4318 0.4318)
			(layers "F.Cu" "F.Mask" "F.Paste")
			(net "GND")
		)
		(pad "AP32" smd circle
			(at -12.19454 -11.567668 270)
			(size 0.4318 0.4318)
			(layers "F.Cu" "F.Mask" "F.Paste")
			(net "M_D_CPU0_SB_DQ<6>")
		)
		(pad "AP34" smd circle
			(at -10.566654 -11.567668 270)
			(size 0.4318 0.4318)
			(layers "F.Cu" "F.Mask" "F.Paste")
			(net "M_D_CPU0_SB_DQ<3>")
		)
		(pad "AP36" smd circle
			(at -8.939022 -11.567668 270)
			(size 0.4318 0.4318)
			(layers "F.Cu" "F.Mask" "F.Paste")
			(net "GND")
		)
		(pad "AP38" smd circle
			(at -7.311136 -11.567668 270)
			(size 0.4318 0.4318)
			(layers "F.Cu" "F.Mask" "F.Paste")
			(net "M_D_CPU0_SB_CB<2>")
		)
		(pad "AP40" smd circle
			(at -5.68325 -11.567668 270)
			(size 0.4318 0.4318)
			(layers "F.Cu" "F.Mask" "F.Paste")
			(net "M_D_CPU0_SB_CB<7>")
		)
		(pad "AP42" smd circle
			(at -4.055618 -11.567668 270)
			(size 0.4318 0.4318)
			(layers "F.Cu" "F.Mask" "F.Paste")
			(net "GND")
		)
		(pad "AP44" smd circle
			(at -2.427732 -11.567668 270)
			(size 0.4318 0.4318)
			(layers "F.Cu" "F.Mask" "F.Paste")
			(net "M_D_CPU0_SA_PAR")
		)
		(pad "AP47" smd circle
			(at 1.613916 -11.457686 270)
			(size 0.4318 0.4318)
			(layers "F.Cu" "F.Mask" "F.Paste")
			(net "M_B_CPU0_SB_RSP<1>")
		)
		(pad "AP49" smd circle
			(at 3.241802 -11.457686 270)
			(size 0.4318 0.4318)
			(layers "F.Cu" "F.Mask" "F.Paste")
			(net "GND")
		)
		(pad "AP51" smd circle
			(at 4.869434 -11.457686 270)
			(size 0.4318 0.4318)
			(layers "F.Cu" "F.Mask" "F.Paste")
			(net "M_D_CPU0_SA_CA<3>")
		)
		(pad "AP53" smd circle
			(at 6.49732 -11.457686 270)
			(size 0.4318 0.4318)
			(layers "F.Cu" "F.Mask" "F.Paste")
			(net "M_D_CPU0_SA_CS_N<3>")
		)
		(pad "AP55" smd circle
			(at 8.124952 -11.457686 270)
			(size 0.4318 0.4318)
			(layers "F.Cu" "F.Mask" "F.Paste")
			(net "GND")
		)
		(pad "AP57" smd circle
			(at 9.752838 -11.457686 270)
			(size 0.4318 0.4318)
			(layers "F.Cu" "F.Mask" "F.Paste")
			(net "M_D_CPU0_SA_CB<6>")
		)
		(pad "AP59" smd circle
			(at 11.380724 -11.457686 270)
			(size 0.4318 0.4318)
			(layers "F.Cu" "F.Mask" "F.Paste")
			(net "M_D_CPU0_SA_CB<3>")
		)
		(pad "AP61" smd circle
			(at 13.008356 -11.457686 270)
			(size 0.4318 0.4318)
			(layers "F.Cu" "F.Mask" "F.Paste")
			(net "GND")
		)
		(pad "AP63" smd circle
			(at 14.635988 -11.457686 270)
			(size 0.4318 0.4318)
			(layers "F.Cu" "F.Mask" "F.Paste")
			(net "M_D_CPU0_SA_DQ<30>")
		)
		(pad "AP65" smd circle
			(at 16.263874 -11.457686 270)
			(size 0.4318 0.4318)
			(layers "F.Cu" "F.Mask" "F.Paste")
			(net "M_D_CPU0_SA_DQ<27>")
		)
		(pad "AP67" smd circle
			(at 17.89176 -11.457686 270)
			(size 0.4318 0.4318)
			(layers "F.Cu" "F.Mask" "F.Paste")
			(net "GND")
		)
		(pad "AP69" smd circle
			(at 19.519392 -11.457686 270)
			(size 0.4318 0.4318)
			(layers "F.Cu" "F.Mask" "F.Paste")
			(net "M_D_CPU0_SA_DQ<22>")
		)
		(pad "AP71" smd circle
			(at 21.147278 -11.457686 270)
			(size 0.4318 0.4318)
			(layers "F.Cu" "F.Mask" "F.Paste")
			(net "M_D_CPU0_SA_DQ<19>")
		)
		(pad "AP73" smd circle
			(at 22.77491 -11.457686 270)
			(size 0.4318 0.4318)
			(layers "F.Cu" "F.Mask" "F.Paste")
			(net "GND")
		)
		(pad "AP75" smd circle
			(at 24.402796 -11.457686 270)
			(size 0.4318 0.4318)
			(layers "F.Cu" "F.Mask" "F.Paste")
			(net "M_D_CPU0_SA_DQ<14>")
		)
		(pad "AP77" smd circle
			(at 26.030682 -11.457686 270)
			(size 0.4318 0.4318)
			(layers "F.Cu" "F.Mask" "F.Paste")
			(net "M_D_CPU0_SA_DQ<11>")
		)
		(pad "AP79" smd circle
			(at 27.658314 -11.457686 270)
			(size 0.4318 0.4318)
			(layers "F.Cu" "F.Mask" "F.Paste")
			(net "GND")
		)
		(pad "AP81" smd circle
			(at 29.2862 -11.457686 270)
			(size 0.4318 0.4318)
			(layers "F.Cu" "F.Mask" "F.Paste")
			(net "UPI_CPU0_CPU1_P2P2_DP<11>")
		)
		(pad "AP83" smd circle
			(at 30.914086 -11.457686 270)
			(size 0.4318 0.4318)
			(layers "F.Cu" "F.Mask" "F.Paste")
			(net "GND")
		)
		(pad "AP85" smd circle
			(at 32.541718 -11.457686 270)
			(size 0.4318 0.4318)
			(layers "F.Cu" "F.Mask" "F.Paste")
			(net "P5E_CPU0_PE4_TX_DN<11>")
		)
		(pad "AP87" smd circle
			(at 34.169604 -11.457686 270)
			(size 0.4318 0.4318)
			(layers "F.Cu" "F.Mask" "F.Paste")
			(net "GND")
		)
		(pad "AP89" smd circle
			(at 35.797236 -11.457686 270)
			(size 0.4318 0.4318)
			(layers "F.Cu" "F.Mask" "F.Paste")
			(net "P5E_CPU0_PE4_RX_DN<11>")
		)
		(pad "AP91" smd oval
			(at 37.425122 -11.457686)
			(size 0.381 0.4826)
			(drill
				(offset 0 -0.0508)
			)
			(layers "F.Cu" "F.Mask" "F.Paste")
			(net "GND")
		)
		(pad "AR1" smd oval
			(at -37.425122 -11.097514 180)
			(size 0.381 0.4826)
			(drill
				(offset 0 -0.0508)
			)
			(layers "F.Cu" "F.Mask" "F.Paste")
			(net "GND")
		)
		(pad "AR3" smd circle
			(at -35.797236 -11.097514 270)
			(size 0.4318 0.4318)
			(layers "F.Cu" "F.Mask" "F.Paste")
			(net "UPI_CPU0_CPU1_P0P1_DN<13>")
		)
		(pad "AR5" smd circle
			(at -34.169604 -11.097514 270)
			(size 0.4318 0.4318)
			(layers "F.Cu" "F.Mask" "F.Paste")
			(net "GND")
		)
		(pad "AR7" smd circle
			(at -32.541718 -11.097514 270)
			(size 0.4318 0.4318)
			(layers "F.Cu" "F.Mask" "F.Paste")
			(net "UPI_CPU1_CPU0_P1P0_DN<12>")
		)
		(pad "AR9" smd circle
			(at -30.914086 -11.097514 270)
			(size 0.4318 0.4318)
			(layers "F.Cu" "F.Mask" "F.Paste")
			(net "GND")
		)
		(pad "AR11" smd circle
			(at -29.2862 -11.097514 270)
			(size 0.4318 0.4318)
			(layers "F.Cu" "F.Mask" "F.Paste")
			(net "P5E_CPU0_PE0_RX_DP<12>")
		)
		(pad "AR13" smd circle
			(at -27.658314 -11.097514 270)
			(size 0.4318 0.4318)
			(layers "F.Cu" "F.Mask" "F.Paste")
			(net "GND")
		)
		(pad "AR15" smd circle
			(at -26.030682 -11.097514 270)
			(size 0.4318 0.4318)
			(layers "F.Cu" "F.Mask" "F.Paste")
			(net "P5E_CPU0_PE0_TX_DP<11>")
		)
		(pad "AR17" smd circle
			(at -24.402796 -11.097514 270)
			(size 0.4318 0.4318)
			(layers "F.Cu" "F.Mask" "F.Paste")
			(net "NC_CPU0_UPI0_APROBE<1>")
		)
		(pad "AR19" smd circle
			(at -22.77491 -11.097514 270)
			(size 0.4318 0.4318)
			(layers "F.Cu" "F.Mask" "F.Paste")
			(net "GND")
		)
		(pad "AR21" smd circle
			(at -21.147278 -11.097514 270)
			(size 0.4318 0.4318)
			(layers "F.Cu" "F.Mask" "F.Paste")
			(net "M_D_CPU0_SB_DQS_DP<8>")
		)
		(pad "AR23" smd circle
			(at -19.519392 -11.097514 270)
			(size 0.4318 0.4318)
			(layers "F.Cu" "F.Mask" "F.Paste")
			(net "GND")
		)
		(pad "AR25" smd circle
			(at -17.89176 -11.097514 270)
			(size 0.4318 0.4318)
			(layers "F.Cu" "F.Mask" "F.Paste")
			(net "GND")
		)
		(pad "AR27" smd circle
			(at -16.263874 -11.097514 270)
			(size 0.4318 0.4318)
			(layers "F.Cu" "F.Mask" "F.Paste")
			(net "M_D_CPU0_SB_DQS_DP<6>")
		)
		(pad "AR29" smd circle
			(at -14.635988 -11.097514 270)
			(size 0.4318 0.4318)
			(layers "F.Cu" "F.Mask" "F.Paste")
			(net "GND")
		)
		(pad "AR31" smd circle
			(at -13.008356 -11.097514 270)
			(size 0.4318 0.4318)
			(layers "F.Cu" "F.Mask" "F.Paste")
			(net "GND")
		)
		(pad "AR33" smd circle
			(at -11.380724 -11.097514 270)
			(size 0.4318 0.4318)
			(layers "F.Cu" "F.Mask" "F.Paste")
			(net "M_D_CPU0_SB_DQS_DP<5>")
		)
		(pad "AR35" smd circle
			(at -9.752838 -11.097514 270)
			(size 0.4318 0.4318)
			(layers "F.Cu" "F.Mask" "F.Paste")
			(net "GND")
		)
		(pad "AR37" smd circle
			(at -8.124952 -11.097514 270)
			(size 0.4318 0.4318)
			(layers "F.Cu" "F.Mask" "F.Paste")
			(net "GND")
		)
		(pad "AR39" smd circle
			(at -6.49732 -11.097514 270)
			(size 0.4318 0.4318)
			(layers "F.Cu" "F.Mask" "F.Paste")
			(net "M_D_CPU0_SB_DQS_DN<4>")
		)
		(pad "AR41" smd circle
			(at -4.869434 -11.097514 270)
			(size 0.4318 0.4318)
			(layers "F.Cu" "F.Mask" "F.Paste")
			(net "GND")
		)
		(pad "AR43" smd circle
			(at -3.241802 -11.097514 270)
			(size 0.4318 0.4318)
			(layers "F.Cu" "F.Mask" "F.Paste")
			(net "GND")
		)
		(pad "AR45" smd circle
			(at -1.613916 -11.097514 270)
			(size 0.4318 0.4318)
			(layers "F.Cu" "F.Mask" "F.Paste")
			(net "M_D_CPU0_CLK_DP<1>")
		)
		(pad "AR48" smd circle
			(at 2.427732 -10.987532 270)
			(size 0.4318 0.4318)
			(layers "F.Cu" "F.Mask" "F.Paste")
			(net "GND")
		)
		(pad "AR50" smd circle
			(at 4.055618 -10.987532 270)
			(size 0.4318 0.4318)
			(layers "F.Cu" "F.Mask" "F.Paste")
			(net "GND")
		)
		(pad "AR52" smd circle
			(at 5.68325 -10.987532 270)
			(size 0.4318 0.4318)
			(layers "F.Cu" "F.Mask" "F.Paste")
			(net "M_D_CPU0_SA_CA<1>")
		)
		(pad "AR54" smd circle
			(at 7.311136 -10.987532 270)
			(size 0.4318 0.4318)
			(layers "F.Cu" "F.Mask" "F.Paste")
			(net "GND")
		)
		(pad "AR56" smd circle
			(at 8.939022 -10.987532 270)
			(size 0.4318 0.4318)
			(layers "F.Cu" "F.Mask" "F.Paste")
			(net "GND")
		)
		(pad "AR58" smd circle
			(at 10.566654 -10.987532 270)
			(size 0.4318 0.4318)
			(layers "F.Cu" "F.Mask" "F.Paste")
			(net "M_D_CPU0_SA_DQS_DP<9>")
		)
		(pad "AR60" smd circle
			(at 12.19454 -10.987532 270)
			(size 0.4318 0.4318)
			(layers "F.Cu" "F.Mask" "F.Paste")
			(net "GND")
		)
		(pad "AR62" smd circle
			(at 13.822426 -10.987532 270)
			(size 0.4318 0.4318)
			(layers "F.Cu" "F.Mask" "F.Paste")
			(net "GND")
		)
		(pad "AR64" smd circle
			(at 15.450058 -10.987532 270)
			(size 0.4318 0.4318)
			(layers "F.Cu" "F.Mask" "F.Paste")
			(net "M_D_CPU0_SA_DQS_DP<8>")
		)
		(pad "AR66" smd circle
			(at 17.07769 -10.987532 270)
			(size 0.4318 0.4318)
			(layers "F.Cu" "F.Mask" "F.Paste")
			(net "GND")
		)
		(pad "AR68" smd circle
			(at 18.705576 -10.987532 270)
			(size 0.4318 0.4318)
			(layers "F.Cu" "F.Mask" "F.Paste")
			(net "GND")
		)
		(pad "AR70" smd circle
			(at 20.333462 -10.987532 270)
			(size 0.4318 0.4318)
			(layers "F.Cu" "F.Mask" "F.Paste")
			(net "M_D_CPU0_SA_DQS_DP<7>")
		)
		(pad "AR72" smd circle
			(at 21.961094 -10.987532 270)
			(size 0.4318 0.4318)
			(layers "F.Cu" "F.Mask" "F.Paste")
			(net "GND")
		)
		(pad "AR74" smd circle
			(at 23.58898 -10.987532 270)
			(size 0.4318 0.4318)
			(layers "F.Cu" "F.Mask" "F.Paste")
			(net "GND")
		)
		(pad "AR76" smd circle
			(at 25.216612 -10.987532 270)
			(size 0.4318 0.4318)
			(layers "F.Cu" "F.Mask" "F.Paste")
			(net "M_D_CPU0_SA_DQS_DP<6>")
		)
		(pad "AR78" smd circle
			(at 26.844498 -10.987532 270)
			(size 0.4318 0.4318)
			(layers "F.Cu" "F.Mask" "F.Paste")
			(net "GND")
		)
		(pad "AR80" smd circle
			(at 28.472384 -10.987532 270)
			(size 0.4318 0.4318)
			(layers "F.Cu" "F.Mask" "F.Paste")
			(net "UPI_CPU0_CPU1_P2P2_DN<9>")
		)
		(pad "AR82" smd circle
			(at 30.100016 -10.987532 270)
			(size 0.4318 0.4318)
			(layers "F.Cu" "F.Mask" "F.Paste")
			(net "GND")
		)
		(pad "AR84" smd circle
			(at 31.727902 -10.987532 270)
			(size 0.4318 0.4318)
			(layers "F.Cu" "F.Mask" "F.Paste")
			(net "GND")
		)
		(pad "AR86" smd circle
			(at 33.355534 -10.987532 270)
			(size 0.4318 0.4318)
			(layers "F.Cu" "F.Mask" "F.Paste")
			(net "P5E_CPU0_PE4_TX_DN<12>")
		)
		(pad "AR88" smd circle
			(at 34.98342 -10.987532 270)
			(size 0.4318 0.4318)
			(layers "F.Cu" "F.Mask" "F.Paste")
			(net "GND")
		)
		(pad "AR90" smd circle
			(at 36.611306 -10.987532 270)
			(size 0.4318 0.4318)
			(layers "F.Cu" "F.Mask" "F.Paste")
			(net "P5E_CPU0_PE4_RX_DP<12>")
		)
		(pad "AT2" smd circle
			(at -36.611306 -10.627868 270)
			(size 0.4318 0.4318)
			(layers "F.Cu" "F.Mask" "F.Paste")
			(net "UPI_CPU0_CPU1_P0P1_DP<13>")
		)
		(pad "AT4" smd circle
			(at -34.98342 -10.627868 270)
			(size 0.4318 0.4318)
			(layers "F.Cu" "F.Mask" "F.Paste")
			(net "GND")
		)
		(pad "AT6" smd circle
			(at -33.355534 -10.627868 270)
			(size 0.4318 0.4318)
			(layers "F.Cu" "F.Mask" "F.Paste")
			(net "UPI_CPU1_CPU0_P1P0_DN<13>")
		)
		(pad "AT8" smd circle
			(at -31.727902 -10.627868 270)
			(size 0.4318 0.4318)
			(layers "F.Cu" "F.Mask" "F.Paste")
			(net "GND")
		)
		(pad "AT10" smd circle
			(at -30.100016 -10.627868 270)
			(size 0.4318 0.4318)
			(layers "F.Cu" "F.Mask" "F.Paste")
			(net "P5E_CPU0_PE0_RX_DP<13>")
		)
		(pad "AT12" smd circle
			(at -28.472384 -10.627868 270)
			(size 0.4318 0.4318)
			(layers "F.Cu" "F.Mask" "F.Paste")
			(net "GND")
		)
		(pad "AT14" smd circle
			(at -26.844498 -10.627868 270)
			(size 0.4318 0.4318)
			(layers "F.Cu" "F.Mask" "F.Paste")
			(net "P5E_CPU0_PE0_TX_DP<12>")
		)
		(pad "AT16" smd circle
			(at -25.216612 -10.627868 270)
			(size 0.4318 0.4318)
			(layers "F.Cu" "F.Mask" "F.Paste")
			(net "GND")
		)
		(pad "AT18" smd circle
			(at -23.58898 -10.627868 270)
			(size 0.4318 0.4318)
			(layers "F.Cu" "F.Mask" "F.Paste")
			(net "PD_CPU0_BIST_ENABLE")
		)
		(pad "AT20" smd circle
			(at -21.961094 -10.627868 270)
			(size 0.4318 0.4318)
			(layers "F.Cu" "F.Mask" "F.Paste")
			(net "GND")
		)
		(pad "AT22" smd circle
			(at -20.333462 -10.627868 270)
			(size 0.4318 0.4318)
			(layers "F.Cu" "F.Mask" "F.Paste")
			(net "GND")
		)
		(pad "AT24" smd circle
			(at -18.705576 -10.627868 270)
			(size 0.4318 0.4318)
			(layers "F.Cu" "F.Mask" "F.Paste")
			(net "NC_CPU0_VIEWPIN_DIE00<1>")
		)
		(pad "AT26" smd circle
			(at -17.07769 -10.627868 270)
			(size 0.4318 0.4318)
			(layers "F.Cu" "F.Mask" "F.Paste")
			(net "GND")
		)
		(pad "AT28" smd circle
			(at -15.450058 -10.627868 270)
			(size 0.4318 0.4318)
			(layers "F.Cu" "F.Mask" "F.Paste")
			(net "GND")
		)
		(pad "AT30" smd circle
			(at -13.822426 -10.627868 270)
			(size 0.4318 0.4318)
			(layers "F.Cu" "F.Mask" "F.Paste")
			(net "CLK_100M_DB2000_CPU0_BCLK0_DN")
		)
		(pad "AT32" smd circle
			(at -12.19454 -10.627868 270)
			(size 0.4318 0.4318)
			(layers "F.Cu" "F.Mask" "F.Paste")
			(net "GND")
		)
		(pad "AT34" smd circle
			(at -10.566654 -10.627868 270)
			(size 0.4318 0.4318)
			(layers "F.Cu" "F.Mask" "F.Paste")
			(net "GND")
		)
		(pad "AT36" smd circle
			(at -8.939022 -10.627868 270)
			(size 0.4318 0.4318)
			(layers "F.Cu" "F.Mask" "F.Paste")
			(net "PVCCD_HV_CPU0")
		)
		(pad "AT38" smd circle
			(at -7.311136 -10.627868 270)
			(size 0.4318 0.4318)
			(layers "F.Cu" "F.Mask" "F.Paste")
			(net "GND")
		)
		(pad "AT40" smd circle
			(at -5.68325 -10.627868 270)
			(size 0.4318 0.4318)
			(layers "F.Cu" "F.Mask" "F.Paste")
			(net "GND")
		)
		(pad "AT42" smd circle
			(at -4.055618 -10.627868 270)
			(size 0.4318 0.4318)
			(layers "F.Cu" "F.Mask" "F.Paste")
			(net "M_A_CPU0_SA_RSP<0>")
		)
		(pad "AT44" smd circle
			(at -2.427732 -10.627868 270)
			(size 0.4318 0.4318)
			(layers "F.Cu" "F.Mask" "F.Paste")
			(net "GND")
		)
		(pad "AT47" smd circle
			(at 1.613916 -10.517886 270)
			(size 0.4318 0.4318)
			(layers "F.Cu" "F.Mask" "F.Paste")
			(net "M_C_CPU0_ALERT_N")
		)
		(pad "AT49" smd circle
			(at 3.241802 -10.517886 270)
			(size 0.4318 0.4318)
			(layers "F.Cu" "F.Mask" "F.Paste")
			(net "M_A_CPU0_ALERT_N")
		)
		(pad "AT51" smd circle
			(at 4.869434 -10.517886 270)
			(size 0.4318 0.4318)
			(layers "F.Cu" "F.Mask" "F.Paste")
			(net "GND")
		)
		(pad "AT53" smd circle
			(at 6.49732 -10.517886 270)
			(size 0.4318 0.4318)
			(layers "F.Cu" "F.Mask" "F.Paste")
			(net "GND")
		)
		(pad "AT55" smd circle
			(at 8.124952 -10.517886 270)
			(size 0.4318 0.4318)
			(layers "F.Cu" "F.Mask" "F.Paste")
			(net "PVCCD_HV_CPU0")
		)
		(pad "AT57" smd circle
			(at 9.752838 -10.517886 270)
			(size 0.4318 0.4318)
			(layers "F.Cu" "F.Mask" "F.Paste")
			(net "GND")
		)
		(pad "AT59" smd circle
			(at 11.380724 -10.517886 270)
			(size 0.4318 0.4318)
			(layers "F.Cu" "F.Mask" "F.Paste")
			(net "GND")
		)
		(pad "AT61" smd circle
			(at 13.008356 -10.517886 270)
			(size 0.4318 0.4318)
			(layers "F.Cu" "F.Mask" "F.Paste")
			(net "PVCCFA_EHV_CPU0")
		)
		(pad "AT63" smd circle
			(at 14.635988 -10.517886 270)
			(size 0.4318 0.4318)
			(layers "F.Cu" "F.Mask" "F.Paste")
			(net "GND")
		)
		(pad "AT65" smd circle
			(at 16.263874 -10.517886 270)
			(size 0.4318 0.4318)
			(layers "F.Cu" "F.Mask" "F.Paste")
			(net "GND")
		)
		(pad "AT67" smd circle
			(at 17.89176 -10.517886 270)
			(size 0.4318 0.4318)
			(layers "F.Cu" "F.Mask" "F.Paste")
			(net "NC_CPU0_UPI2_APROBE<1>")
		)
		(pad "AT69" smd circle
			(at 19.519392 -10.517886 270)
			(size 0.4318 0.4318)
			(layers "F.Cu" "F.Mask" "F.Paste")
			(net "GND")
		)
		(pad "AT71" smd circle
			(at 21.147278 -10.517886 270)
			(size 0.4318 0.4318)
			(layers "F.Cu" "F.Mask" "F.Paste")
			(net "GND")
		)
		(pad "AT73" smd circle
			(at 22.77491 -10.517886 270)
			(size 0.4318 0.4318)
			(layers "F.Cu" "F.Mask" "F.Paste")
			(net "PVCCFA_EHV_FIVRA_CPU0")
		)
		(pad "AT75" smd circle
			(at 24.402796 -10.517886 270)
			(size 0.4318 0.4318)
			(layers "F.Cu" "F.Mask" "F.Paste")
			(net "GND")
		)
		(pad "AT77" smd circle
			(at 26.030682 -10.517886 270)
			(size 0.4318 0.4318)
			(layers "F.Cu" "F.Mask" "F.Paste")
			(net "GND")
		)
		(pad "AT79" smd circle
			(at 27.658314 -10.517886 270)
			(size 0.4318 0.4318)
			(layers "F.Cu" "F.Mask" "F.Paste")
			(net "GND")
		)
		(pad "AT81" smd circle
			(at 29.2862 -10.517886 270)
			(size 0.4318 0.4318)
			(layers "F.Cu" "F.Mask" "F.Paste")
			(net "UPI_CPU0_CPU1_P2P2_DP<9>")
		)
		(pad "AT83" smd circle
			(at 30.914086 -10.517886 270)
			(size 0.4318 0.4318)
			(layers "F.Cu" "F.Mask" "F.Paste")
			(net "UPI_CPU0_CPU1_P2P2_DN<8>")
		)
		(pad "AT85" smd circle
			(at 32.541718 -10.517886 270)
			(size 0.4318 0.4318)
			(layers "F.Cu" "F.Mask" "F.Paste")
			(net "VSENSE_PVCCFA_EHV_FIVRA_CPU0_DN")
		)
		(pad "AT87" smd circle
			(at 34.169604 -10.517886 270)
			(size 0.4318 0.4318)
			(layers "F.Cu" "F.Mask" "F.Paste")
			(net "P5E_CPU0_PE4_TX_DP<12>")
		)
		(pad "AT89" smd circle
			(at 35.797236 -10.517886 270)
			(size 0.4318 0.4318)
			(layers "F.Cu" "F.Mask" "F.Paste")
			(net "PVCCFA_EHV_FIVRA_CPU0")
		)
		(pad "AT91" smd oval
			(at 37.425122 -10.517886)
			(size 0.381 0.4826)
			(drill
				(offset 0 -0.0508)
			)
			(layers "F.Cu" "F.Mask" "F.Paste")
			(net "P5E_CPU0_PE4_RX_DN<12>")
		)
		(pad "AU1" smd oval
			(at -37.425122 -10.157714 180)
			(size 0.381 0.4826)
			(drill
				(offset 0 -0.0508)
			)
			(layers "F.Cu" "F.Mask" "F.Paste")
			(net "UPI_CPU0_CPU1_P0P1_DN<14>")
		)
		(pad "AU3" smd circle
			(at -35.797236 -10.157714 270)
			(size 0.4318 0.4318)
			(layers "F.Cu" "F.Mask" "F.Paste")
			(net "PVCCD_HV_CPU0")
		)
		(pad "AU5" smd circle
			(at -34.169604 -10.157714 270)
			(size 0.4318 0.4318)
			(layers "F.Cu" "F.Mask" "F.Paste")
			(net "UPI_CPU1_CPU0_P1P0_DP<13>")
		)
		(pad "AU7" smd circle
			(at -32.541718 -10.157714 270)
			(size 0.4318 0.4318)
			(layers "F.Cu" "F.Mask" "F.Paste")
			(net "PVCCD_HV_CPU0")
		)
		(pad "AU9" smd circle
			(at -30.914086 -10.157714 270)
			(size 0.4318 0.4318)
			(layers "F.Cu" "F.Mask" "F.Paste")
			(net "P5E_CPU0_PE0_RX_DN<13>")
		)
		(pad "AU11" smd circle
			(at -29.2862 -10.157714 270)
			(size 0.4318 0.4318)
			(layers "F.Cu" "F.Mask" "F.Paste")
			(net "VSENSE_PVCCFA_EHV_CPU0_DP")
		)
		(pad "AU13" smd circle
			(at -27.658314 -10.157714 270)
			(size 0.4318 0.4318)
			(layers "F.Cu" "F.Mask" "F.Paste")
			(net "P5E_CPU0_PE0_TX_DN<12>")
		)
		(pad "AU15" smd circle
			(at -26.030682 -10.157714 270)
			(size 0.4318 0.4318)
			(layers "F.Cu" "F.Mask" "F.Paste")
			(net "PVCCFA_EHV_FIVRA_CPU0")
		)
		(pad "AU17" smd circle
			(at -24.402796 -10.157714 270)
			(size 0.4318 0.4318)
			(layers "F.Cu" "F.Mask" "F.Paste")
			(net "PU_CPU0_FRMAGENT")
		)
		(pad "AU19" smd circle
			(at -22.77491 -10.157714 270)
			(size 0.4318 0.4318)
			(layers "F.Cu" "F.Mask" "F.Paste")
			(net "H_CPU0_PROCHOT_LVC1_N")
		)
		(pad "AU21" smd circle
			(at -21.147278 -10.157714 270)
			(size 0.4318 0.4318)
			(layers "F.Cu" "F.Mask" "F.Paste")
			(net "H_CPU0_MEMHOT_IN_LVC1_N")
		)
		(pad "AU23" smd circle
			(at -19.519392 -10.157714 270)
			(size 0.4318 0.4318)
			(layers "F.Cu" "F.Mask" "F.Paste")
			(net "PU_CPU0_SAFE_MODE_BOOT")
		)
		(pad "AU25" smd circle
			(at -17.89176 -10.157714 270)
			(size 0.4318 0.4318)
			(layers "F.Cu" "F.Mask" "F.Paste")
			(net "NC_CPU0_VIEWPIN_DIE00<2>")
		)
		(pad "AU27" smd circle
			(at -16.263874 -10.157714 270)
			(size 0.4318 0.4318)
			(layers "F.Cu" "F.Mask" "F.Paste")
			(net "GND")
		)
		(pad "AU29" smd circle
			(at -14.635988 -10.157714 270)
			(size 0.4318 0.4318)
			(layers "F.Cu" "F.Mask" "F.Paste")
			(net "CLK_100M_DB2000_CPU0_BCLK2_DN")
		)
		(pad "AU31" smd circle
			(at -13.008356 -10.157714 270)
			(size 0.4318 0.4318)
			(layers "F.Cu" "F.Mask" "F.Paste")
			(net "GND")
		)
		(pad "AU33" smd circle
			(at -11.380724 -10.157714 270)
			(size 0.4318 0.4318)
			(layers "F.Cu" "F.Mask" "F.Paste")
			(net "NC_CPU0_DDR23_VIEWDIG1")
		)
		(pad "AU35" smd circle
			(at -9.752838 -10.157714 270)
			(size 0.4318 0.4318)
			(layers "F.Cu" "F.Mask" "F.Paste")
			(net "PVCCD_HV_CPU0")
		)
		(pad "AU37" smd circle
			(at -8.124952 -10.157714 270)
			(size 0.4318 0.4318)
			(layers "F.Cu" "F.Mask" "F.Paste")
			(net "GND")
		)
		(pad "AU39" smd circle
			(at -6.49732 -10.157714 270)
			(size 0.4318 0.4318)
			(layers "F.Cu" "F.Mask" "F.Paste")
			(net "GND")
		)
		(pad "AU41" smd circle
			(at -4.869434 -10.157714 270)
			(size 0.4318 0.4318)
			(layers "F.Cu" "F.Mask" "F.Paste")
			(net "GND")
		)
		(pad "AU43" smd circle
			(at -3.241802 -10.157714 270)
			(size 0.4318 0.4318)
			(layers "F.Cu" "F.Mask" "F.Paste")
			(net "M_A_CPU0_SA_RSP<1>")
		)
		(pad "AU45" smd circle
			(at -1.613916 -10.157714 270)
			(size 0.4318 0.4318)
			(layers "F.Cu" "F.Mask" "F.Paste")
			(net "GND")
		)
		(pad "AU48" smd circle
			(at 2.427732 -10.047732 270)
			(size 0.4318 0.4318)
			(layers "F.Cu" "F.Mask" "F.Paste")
			(net "GND")
		)
		(pad "AU50" smd circle
			(at 4.055618 -10.047732 270)
			(size 0.4318 0.4318)
			(layers "F.Cu" "F.Mask" "F.Paste")
			(net "RST_CPU0_DRAM_AB_N")
		)
		(pad "AU52" smd circle
			(at 5.68325 -10.047732 270)
			(size 0.4318 0.4318)
			(layers "F.Cu" "F.Mask" "F.Paste")
			(net "TP_CPU0_SPARE5")
		)
		(pad "AU54" smd circle
			(at 7.311136 -10.047732 270)
			(size 0.4318 0.4318)
			(layers "F.Cu" "F.Mask" "F.Paste")
			(net "PVCCD_HV_CPU0")
		)
		(pad "AU56" smd circle
			(at 8.939022 -10.047732 270)
			(size 0.4318 0.4318)
			(layers "F.Cu" "F.Mask" "F.Paste")
			(net "NC_CPU0_DDR01_VIEWDIG1")
		)
		(pad "AU58" smd circle
			(at 10.566654 -10.047732 270)
			(size 0.4318 0.4318)
			(layers "F.Cu" "F.Mask" "F.Paste")
			(net "NC_CPU0_DDR01_VIEWDIG0")
		)
		(pad "AU60" smd circle
			(at 12.19454 -10.047732 270)
			(size 0.4318 0.4318)
			(layers "F.Cu" "F.Mask" "F.Paste")
			(net "PVCCFA_EHV_CPU0")
		)
		(pad "AU62" smd circle
			(at 13.822426 -10.047732 270)
			(size 0.4318 0.4318)
			(layers "F.Cu" "F.Mask" "F.Paste")
			(net "TP_SPI_IBL_CPU0_TPM_CLK")
		)
		(pad "AU64" smd circle
			(at 15.450058 -10.047732 270)
			(size 0.4318 0.4318)
			(layers "F.Cu" "F.Mask" "F.Paste")
			(net "TP_ESPI_IBL_CPU0_IO2_LVC1")
		)
		(pad "AU66" smd circle
			(at 17.07769 -10.047732 270)
			(size 0.4318 0.4318)
			(layers "F.Cu" "F.Mask" "F.Paste")
			(net "NC_CPU0_PE4_APROBE<1>")
		)
		(pad "AU68" smd circle
			(at 18.705576 -10.047732 270)
			(size 0.4318 0.4318)
			(layers "F.Cu" "F.Mask" "F.Paste")
			(net "NC_CPU0_UPI2_APROBE<0>")
		)
		(pad "AU70" smd circle
			(at 20.333462 -10.047732 270)
			(size 0.4318 0.4318)
			(layers "F.Cu" "F.Mask" "F.Paste")
			(net "GND")
		)
		(pad "AU72" smd circle
			(at 21.961094 -10.047732 270)
			(size 0.4318 0.4318)
			(layers "F.Cu" "F.Mask" "F.Paste")
			(net "GND")
		)
		(pad "AU74" smd circle
			(at 23.58898 -10.047732 270)
			(size 0.4318 0.4318)
			(layers "F.Cu" "F.Mask" "F.Paste")
			(net "GND")
		)
		(pad "AU76" smd circle
			(at 25.216612 -10.047732 270)
			(size 0.4318 0.4318)
			(layers "F.Cu" "F.Mask" "F.Paste")
			(net "GND")
		)
		(pad "AU78" smd circle
			(at 26.844498 -10.047732 270)
			(size 0.4318 0.4318)
			(layers "F.Cu" "F.Mask" "F.Paste")
			(net "UPI_CPU0_CPU1_P2P2_DN<12>")
		)
		(pad "AU80" smd circle
			(at 28.472384 -10.047732 270)
			(size 0.4318 0.4318)
			(layers "F.Cu" "F.Mask" "F.Paste")
			(net "GND")
		)
		(pad "AU82" smd circle
			(at 30.100016 -10.047732 270)
			(size 0.4318 0.4318)
			(layers "F.Cu" "F.Mask" "F.Paste")
			(net "UPI_CPU0_CPU1_P2P2_DP<7>")
		)
		(pad "AU84" smd circle
			(at 31.727902 -10.047732 270)
			(size 0.4318 0.4318)
			(layers "F.Cu" "F.Mask" "F.Paste")
			(net "GND")
		)
		(pad "AU86" smd circle
			(at 33.355534 -10.047732 270)
			(size 0.4318 0.4318)
			(layers "F.Cu" "F.Mask" "F.Paste")
			(net "P5E_CPU0_PE4_TX_DN<13>")
		)
		(pad "AU88" smd circle
			(at 34.98342 -10.047732 270)
			(size 0.4318 0.4318)
			(layers "F.Cu" "F.Mask" "F.Paste")
			(net "GND")
		)
		(pad "AU90" smd circle
			(at 36.611306 -10.047732 270)
			(size 0.4318 0.4318)
			(layers "F.Cu" "F.Mask" "F.Paste")
			(net "P5E_CPU0_PE4_RX_DP<13>")
		)
		(pad "AV2" smd circle
			(at -36.611306 -9.688068 270)
			(size 0.4318 0.4318)
			(layers "F.Cu" "F.Mask" "F.Paste")
			(net "UPI_CPU0_CPU1_P0P1_DP<14>")
		)
		(pad "AV4" smd circle
			(at -34.98342 -9.688068 270)
			(size 0.4318 0.4318)
			(layers "F.Cu" "F.Mask" "F.Paste")
			(net "GND")
		)
		(pad "AV6" smd circle
			(at -33.355534 -9.688068 270)
			(size 0.4318 0.4318)
			(layers "F.Cu" "F.Mask" "F.Paste")
			(net "UPI_CPU1_CPU0_P1P0_DP<14>")
		)
		(pad "AV8" smd circle
			(at -31.727902 -9.688068 270)
			(size 0.4318 0.4318)
			(layers "F.Cu" "F.Mask" "F.Paste")
			(net "GND")
		)
		(pad "AV10" smd circle
			(at -30.100016 -9.688068 270)
			(size 0.4318 0.4318)
			(layers "F.Cu" "F.Mask" "F.Paste")
			(net "P5E_CPU0_PE0_RX_DN<14>")
		)
		(pad "AV12" smd circle
			(at -28.472384 -9.688068 270)
			(size 0.4318 0.4318)
			(layers "F.Cu" "F.Mask" "F.Paste")
			(net "GND")
		)
		(pad "AV14" smd circle
			(at -26.844498 -9.688068 270)
			(size 0.4318 0.4318)
			(layers "F.Cu" "F.Mask" "F.Paste")
			(net "P5E_CPU0_PE0_TX_DN<13>")
		)
		(pad "AV16" smd circle
			(at -25.216612 -9.688068 270)
			(size 0.4318 0.4318)
			(layers "F.Cu" "F.Mask" "F.Paste")
			(net "GND")
		)
		(pad "AV18" smd circle
			(at -23.58898 -9.688068 270)
			(size 0.4318 0.4318)
			(layers "F.Cu" "F.Mask" "F.Paste")
			(net "H_CPU0_NMI_LVC1_N")
		)
		(pad "AV20" smd circle
			(at -21.961094 -9.688068 270)
			(size 0.4318 0.4318)
			(layers "F.Cu" "F.Mask" "F.Paste")
			(net "PWRGD_CPU0_LVC1")
		)
		(pad "AV22" smd circle
			(at -20.333462 -9.688068 270)
			(size 0.4318 0.4318)
			(layers "F.Cu" "F.Mask" "F.Paste")
			(net "H_CPU0_PREQ_QS_GTL_R_N")
		)
		(pad "AV24" smd circle
			(at -18.705576 -9.688068 270)
			(size 0.4318 0.4318)
			(layers "F.Cu" "F.Mask" "F.Paste")
			(net "H_CPU0_MEMTRIP_LVC1_R_N")
		)
		(pad "AV26" smd circle
			(at -17.07769 -9.688068 270)
			(size 0.4318 0.4318)
			(layers "F.Cu" "F.Mask" "F.Paste")
			(net "NC_CPU0_VIEWPIN_DIE00<3>")
		)
		(pad "AV28" smd circle
			(at -15.450058 -9.688068 270)
			(size 0.4318 0.4318)
			(layers "F.Cu" "F.Mask" "F.Paste")
			(net "CLK_100M_DB2000_CPU0_BCLK2_DP")
		)
		(pad "AV30" smd circle
			(at -13.822426 -9.688068 270)
			(size 0.4318 0.4318)
			(layers "F.Cu" "F.Mask" "F.Paste")
			(net "CLK_100M_DB2000_CPU0_BCLK0_DP")
		)
		(pad "AV32" smd circle
			(at -12.19454 -9.688068 270)
			(size 0.4318 0.4318)
			(layers "F.Cu" "F.Mask" "F.Paste")
			(net "NC_CPU0_DDR23_VIEWDIG0")
		)
		(pad "AV34" smd circle
			(at -10.566654 -9.688068 270)
			(size 0.4318 0.4318)
			(layers "F.Cu" "F.Mask" "F.Paste")
			(net "PVCCD_HV_CPU0")
		)
		(pad "AV36" smd circle
			(at -8.939022 -9.688068 270)
			(size 0.4318 0.4318)
			(layers "F.Cu" "F.Mask" "F.Paste")
			(net "PVCCD_HV_CPU0")
		)
		(pad "AV38" smd circle
			(at -7.311136 -9.688068 270)
			(size 0.4318 0.4318)
			(layers "F.Cu" "F.Mask" "F.Paste")
			(net "NC_CPU0_THERMADC")
		)
		(pad "AV40" smd circle
			(at -5.68325 -9.688068 270)
			(size 0.4318 0.4318)
			(layers "F.Cu" "F.Mask" "F.Paste")
			(net "NC_CPU0_THERMADA")
		)
		(pad "AV42" smd circle
			(at -4.055618 -9.688068 270)
			(size 0.4318 0.4318)
			(layers "F.Cu" "F.Mask" "F.Paste")
			(net "M_A_CPU0_SB_RSP<1>")
		)
		(pad "AV44" smd circle
			(at -2.427732 -9.688068 270)
			(size 0.4318 0.4318)
			(layers "F.Cu" "F.Mask" "F.Paste")
			(net "M_A_CPU0_SB_RSP<0>")
		)
		(pad "AV47" smd circle
			(at 1.613916 -9.578086 270)
			(size 0.4318 0.4318)
			(layers "F.Cu" "F.Mask" "F.Paste")
			(net "M_D_CPU0_ALERT_N")
		)
		(pad "AV49" smd circle
			(at 3.241802 -9.578086 270)
			(size 0.4318 0.4318)
			(layers "F.Cu" "F.Mask" "F.Paste")
			(net "M_B_CPU0_ALERT_N")
		)
		(pad "AV51" smd circle
			(at 4.869434 -9.578086 270)
			(size 0.4318 0.4318)
			(layers "F.Cu" "F.Mask" "F.Paste")
			(net "RST_CPU0_DRAM_CD_N")
		)
		(pad "AV53" smd circle
			(at 6.49732 -9.578086 270)
			(size 0.4318 0.4318)
			(layers "F.Cu" "F.Mask" "F.Paste")
			(net "PVCCD_HV_CPU0")
		)
		(pad "AV55" smd circle
			(at 8.124952 -9.578086 270)
			(size 0.4318 0.4318)
			(layers "F.Cu" "F.Mask" "F.Paste")
			(net "PVCCD_HV_CPU0")
		)
		(pad "AV57" smd circle
			(at 9.752838 -9.578086 270)
			(size 0.4318 0.4318)
			(layers "F.Cu" "F.Mask" "F.Paste")
			(net "FM_CPU_FBRK_DEBUG_R_N")
		)
		(pad "AV59" smd circle
			(at 11.380724 -9.578086 270)
			(size 0.4318 0.4318)
			(layers "F.Cu" "F.Mask" "F.Paste")
			(net "TP_EV_CPU0_EXT_BGREF")
		)
		(pad "AV61" smd circle
			(at 13.008356 -9.578086 270)
			(size 0.4318 0.4318)
			(layers "F.Cu" "F.Mask" "F.Paste")
			(net "PVCCFA_EHV_CPU0")
		)
		(pad "AV63" smd circle
			(at 14.635988 -9.578086 270)
			(size 0.4318 0.4318)
			(layers "F.Cu" "F.Mask" "F.Paste")
			(net "TP_SPI_S3M_CPU0_CS1_LVC1_R_N")
		)
		(pad "AV65" smd circle
			(at 16.263874 -9.578086 270)
			(size 0.4318 0.4318)
			(layers "F.Cu" "F.Mask" "F.Paste")
			(net "NC_CPU0_MDFI_DIE01_EW0")
		)
		(pad "AV67" smd circle
			(at 17.89176 -9.578086 270)
			(size 0.4318 0.4318)
			(layers "F.Cu" "F.Mask" "F.Paste")
			(net "NC_CPU0_PE4_APROBE<0>")
		)
		(pad "AV69" smd circle
			(at 19.519392 -9.578086 270)
			(size 0.4318 0.4318)
			(layers "F.Cu" "F.Mask" "F.Paste")
			(net "FM_S3M_CPU0_LVC1_GPIO_2")
		)
		(pad "AV71" smd circle
			(at 21.147278 -9.578086 270)
			(size 0.4318 0.4318)
			(layers "F.Cu" "F.Mask" "F.Paste")
			(net "FM_S3M_CPU0_LVC1_GPIO_1")
		)
		(pad "AV73" smd circle
			(at 22.77491 -9.578086 270)
			(size 0.4318 0.4318)
			(layers "F.Cu" "F.Mask" "F.Paste")
			(net "UPI_CPU1_CPU0_P2P2_DN<10>")
		)
		(pad "AV75" smd circle
			(at 24.402796 -9.578086 270)
			(size 0.4318 0.4318)
			(layers "F.Cu" "F.Mask" "F.Paste")
			(net "UPI_CPU1_CPU0_P2P2_DN<7>")
		)
		(pad "AV77" smd circle
			(at 26.030682 -9.578086 270)
			(size 0.4318 0.4318)
			(layers "F.Cu" "F.Mask" "F.Paste")
			(net "GND")
		)
		(pad "AV79" smd circle
			(at 27.658314 -9.578086 270)
			(size 0.4318 0.4318)
			(layers "F.Cu" "F.Mask" "F.Paste")
			(net "UPI_CPU0_CPU1_P2P2_DP<12>")
		)
		(pad "AV81" smd circle
			(at 29.2862 -9.578086 270)
			(size 0.4318 0.4318)
			(layers "F.Cu" "F.Mask" "F.Paste")
			(net "UPI_CPU0_CPU1_P2P2_DN<7>")
		)
		(pad "AV83" smd circle
			(at 30.914086 -9.578086 270)
			(size 0.4318 0.4318)
			(layers "F.Cu" "F.Mask" "F.Paste")
			(net "UPI_CPU0_CPU1_P2P2_DP<8>")
		)
		(pad "AV85" smd circle
			(at 32.541718 -9.578086 270)
			(size 0.4318 0.4318)
			(layers "F.Cu" "F.Mask" "F.Paste")
			(net "P5E_CPU0_PE4_TX_DP<13>")
		)
		(pad "AV87" smd circle
			(at 34.169604 -9.578086 270)
			(size 0.4318 0.4318)
			(layers "F.Cu" "F.Mask" "F.Paste")
			(net "GND")
		)
		(pad "AV89" smd circle
			(at 35.797236 -9.578086 270)
			(size 0.4318 0.4318)
			(layers "F.Cu" "F.Mask" "F.Paste")
			(net "P5E_CPU0_PE4_RX_DN<13>")
		)
		(pad "AV91" smd oval
			(at 37.425122 -9.578086)
			(size 0.381 0.4826)
			(drill
				(offset 0 -0.0508)
			)
			(layers "F.Cu" "F.Mask" "F.Paste")
			(net "GND")
		)
		(pad "AW1" smd oval
			(at -37.425122 -9.217914 180)
			(size 0.381 0.4826)
			(drill
				(offset 0 -0.0508)
			)
			(layers "F.Cu" "F.Mask" "F.Paste")
			(net "GND")
		)
		(pad "AW3" smd circle
			(at -35.797236 -9.217914 270)
			(size 0.4318 0.4318)
			(layers "F.Cu" "F.Mask" "F.Paste")
			(net "UPI_CPU0_CPU1_P0P1_DN<15>")
		)
		(pad "AW5" smd circle
			(at -34.169604 -9.217914 270)
			(size 0.4318 0.4318)
			(layers "F.Cu" "F.Mask" "F.Paste")
			(net "GND")
		)
		(pad "AW7" smd circle
			(at -32.541718 -9.217914 270)
			(size 0.4318 0.4318)
			(layers "F.Cu" "F.Mask" "F.Paste")
			(net "UPI_CPU1_CPU0_P1P0_DN<14>")
		)
		(pad "AW9" smd circle
			(at -30.914086 -9.217914 270)
			(size 0.4318 0.4318)
			(layers "F.Cu" "F.Mask" "F.Paste")
			(net "GND")
		)
		(pad "AW11" smd circle
			(at -29.2862 -9.217914 270)
			(size 0.4318 0.4318)
			(layers "F.Cu" "F.Mask" "F.Paste")
			(net "P5E_CPU0_PE0_RX_DP<14>")
		)
		(pad "AW13" smd circle
			(at -27.658314 -9.217914 270)
			(size 0.4318 0.4318)
			(layers "F.Cu" "F.Mask" "F.Paste")
			(net "GND")
		)
		(pad "AW15" smd circle
			(at -26.030682 -9.217914 270)
			(size 0.4318 0.4318)
			(layers "F.Cu" "F.Mask" "F.Paste")
			(net "P5E_CPU0_PE0_TX_DP<13>")
		)
		(pad "AW17" smd circle
			(at -24.402796 -9.217914 270)
			(size 0.4318 0.4318)
			(layers "F.Cu" "F.Mask" "F.Paste")
			(net "PD_CPU0_DMIMODE_OVERRIDE")
		)
		(pad "AW19" smd circle
			(at -22.77491 -9.217914 270)
			(size 0.4318 0.4318)
			(layers "F.Cu" "F.Mask" "F.Paste")
			(net "TP_FM_IBL_WAKE_CPU0_N")
		)
		(pad "AW21" smd circle
			(at -21.147278 -9.217914 270)
			(size 0.4318 0.4318)
			(layers "F.Cu" "F.Mask" "F.Paste")
			(net "GND")
		)
		(pad "AW23" smd circle
			(at -19.519392 -9.217914 270)
			(size 0.4318 0.4318)
			(layers "F.Cu" "F.Mask" "F.Paste")
			(net "GND")
		)
		(pad "AW25" smd circle
			(at -17.89176 -9.217914 270)
			(size 0.4318 0.4318)
			(layers "F.Cu" "F.Mask" "F.Paste")
			(net "GND")
		)
		(pad "AW60" smd circle
			(at 12.19454 -9.107932 270)
			(size 0.4318 0.4318)
			(layers "F.Cu" "F.Mask" "F.Paste")
			(net "PVCCFA_EHV_CPU0")
		)
		(pad "AW62" smd circle
			(at 13.822426 -9.107932 270)
			(size 0.4318 0.4318)
			(layers "F.Cu" "F.Mask" "F.Paste")
			(net "GND")
		)
		(pad "AW64" smd circle
			(at 15.450058 -9.107932 270)
			(size 0.4318 0.4318)
			(layers "F.Cu" "F.Mask" "F.Paste")
			(net "TP_SPI_S3M_CPU0_IO1_LVC1_R")
		)
		(pad "AW66" smd circle
			(at 17.07769 -9.107932 270)
			(size 0.4318 0.4318)
			(layers "F.Cu" "F.Mask" "F.Paste")
			(net "GND")
		)
		(pad "AW68" smd circle
			(at 18.705576 -9.107932 270)
			(size 0.4318 0.4318)
			(layers "F.Cu" "F.Mask" "F.Paste")
			(net "GND")
		)
		(pad "AW70" smd circle
			(at 20.333462 -9.107932 270)
			(size 0.4318 0.4318)
			(layers "F.Cu" "F.Mask" "F.Paste")
			(net "FM_S3M_CPU0_LVC1_GPIO_4")
		)
		(pad "AW72" smd circle
			(at 21.961094 -9.107932 270)
			(size 0.4318 0.4318)
			(layers "F.Cu" "F.Mask" "F.Paste")
			(net "GND")
		)
		(pad "AW74" smd circle
			(at 23.58898 -9.107932 270)
			(size 0.4318 0.4318)
			(layers "F.Cu" "F.Mask" "F.Paste")
			(net "UPI_CPU1_CPU0_P2P2_DP<7>")
		)
		(pad "AW76" smd circle
			(at 25.216612 -9.107932 270)
			(size 0.4318 0.4318)
			(layers "F.Cu" "F.Mask" "F.Paste")
			(net "PVCCFA_EHV_FIVRA_CPU0")
		)
		(pad "AW78" smd circle
			(at 26.844498 -9.107932 270)
			(size 0.4318 0.4318)
			(layers "F.Cu" "F.Mask" "F.Paste")
			(net "UPI_CPU0_CPU1_P2P2_DN<13>")
		)
		(pad "AW80" smd circle
			(at 28.472384 -9.107932 270)
			(size 0.4318 0.4318)
			(layers "F.Cu" "F.Mask" "F.Paste")
			(net "GND")
		)
		(pad "AW82" smd circle
			(at 30.100016 -9.107932 270)
			(size 0.4318 0.4318)
			(layers "F.Cu" "F.Mask" "F.Paste")
			(net "GND")
		)
		(pad "AW84" smd circle
			(at 31.727902 -9.107932 270)
			(size 0.4318 0.4318)
			(layers "F.Cu" "F.Mask" "F.Paste")
			(net "GND")
		)
		(pad "AW86" smd circle
			(at 33.355534 -9.107932 270)
			(size 0.4318 0.4318)
			(layers "F.Cu" "F.Mask" "F.Paste")
			(net "P5E_CPU0_PE4_TX_DN<14>")
		)
		(pad "AW88" smd circle
			(at 34.98342 -9.107932 270)
			(size 0.4318 0.4318)
			(layers "F.Cu" "F.Mask" "F.Paste")
			(net "GND")
		)
		(pad "AW90" smd circle
			(at 36.611306 -9.107932 270)
			(size 0.4318 0.4318)
			(layers "F.Cu" "F.Mask" "F.Paste")
			(net "P5E_CPU0_PE4_RX_DP<14>")
		)
		(pad "AY2" smd circle
			(at -36.611306 -8.748268 270)
			(size 0.4318 0.4318)
			(layers "F.Cu" "F.Mask" "F.Paste")
			(net "UPI_CPU0_CPU1_P0P1_DP<15>")
		)
		(pad "AY4" smd circle
			(at -34.98342 -8.748268 270)
			(size 0.4318 0.4318)
			(layers "F.Cu" "F.Mask" "F.Paste")
			(net "GND")
		)
		(pad "AY6" smd circle
			(at -33.355534 -8.748268 270)
			(size 0.4318 0.4318)
			(layers "F.Cu" "F.Mask" "F.Paste")
			(net "UPI_CPU1_CPU0_P1P0_DN<15>")
		)
		(pad "AY8" smd circle
			(at -31.727902 -8.748268 270)
			(size 0.4318 0.4318)
			(layers "F.Cu" "F.Mask" "F.Paste")
			(net "GND")
		)
		(pad "AY10" smd circle
			(at -30.100016 -8.748268 270)
			(size 0.4318 0.4318)
			(layers "F.Cu" "F.Mask" "F.Paste")
			(net "P5E_CPU0_PE0_RX_DP<15>")
		)
		(pad "AY12" smd circle
			(at -28.472384 -8.748268 270)
			(size 0.4318 0.4318)
			(layers "F.Cu" "F.Mask" "F.Paste")
			(net "GND")
		)
		(pad "AY14" smd circle
			(at -26.844498 -8.748268 270)
			(size 0.4318 0.4318)
			(layers "F.Cu" "F.Mask" "F.Paste")
			(net "P5E_CPU0_PE0_TX_DP<14>")
		)
		(pad "AY16" smd circle
			(at -25.216612 -8.748268 270)
			(size 0.4318 0.4318)
			(layers "F.Cu" "F.Mask" "F.Paste")
			(net "GND")
		)
		(pad "AY18" smd circle
			(at -23.58898 -8.748268 270)
			(size 0.4318 0.4318)
			(layers "F.Cu" "F.Mask" "F.Paste")
			(net "PVCCINFAON_CPU0")
		)
		(pad "AY20" smd circle
			(at -21.961094 -8.748268 270)
			(size 0.4318 0.4318)
			(layers "F.Cu" "F.Mask" "F.Paste")
			(net "PU_TAP_ODT_CPU0_EN")
		)
		(pad "AY22" smd circle
			(at -20.333462 -8.748268 270)
			(size 0.4318 0.4318)
			(layers "F.Cu" "F.Mask" "F.Paste")
			(net "H_CPU0_ERR1_LVC1_R_N")
		)
		(pad "AY24" smd circle
			(at -18.705576 -8.748268 270)
			(size 0.4318 0.4318)
			(layers "F.Cu" "F.Mask" "F.Paste")
			(net "NC_CPU0_SOC_SPARE0")
		)
		(pad "AY26" smd circle
			(at -17.07769 -8.748268 270)
			(size 0.4318 0.4318)
			(layers "F.Cu" "F.Mask" "F.Paste")
			(net "NC_CPU0_VIEWPIN_DIE00<0>")
		)
		(pad "AY61" smd circle
			(at 13.008356 -8.638286 270)
			(size 0.4318 0.4318)
			(layers "F.Cu" "F.Mask" "F.Paste")
			(net "TP_SPI_IBL_CPU0_TPM_IO1")
		)
		(pad "AY63" smd circle
			(at 14.635988 -8.638286 270)
			(size 0.4318 0.4318)
			(layers "F.Cu" "F.Mask" "F.Paste")
			(net "FM_CPU0_PKGID1")
		)
		(pad "AY65" smd circle
			(at 16.263874 -8.638286 270)
			(size 0.4318 0.4318)
			(layers "F.Cu" "F.Mask" "F.Paste")
			(net "NC_CPU0_VIEWPIN_DIE01<2>")
		)
		(pad "AY67" smd circle
			(at 17.89176 -8.638286 270)
			(size 0.4318 0.4318)
			(layers "F.Cu" "F.Mask" "F.Paste")
			(net "TP_SPI_IBL_CPU0_TPM_CS0_N")
		)
		(pad "AY69" smd circle
			(at 19.519392 -8.638286 270)
			(size 0.4318 0.4318)
			(layers "F.Cu" "F.Mask" "F.Paste")
			(net "FM_S3M_CPU0_LVC1_GPIO_3")
		)
		(pad "AY71" smd circle
			(at 21.147278 -8.638286 270)
			(size 0.4318 0.4318)
			(layers "F.Cu" "F.Mask" "F.Paste")
			(net "GND")
		)
		(pad "AY73" smd circle
			(at 22.77491 -8.638286 270)
			(size 0.4318 0.4318)
			(layers "F.Cu" "F.Mask" "F.Paste")
			(net "UPI_CPU1_CPU0_P2P2_DP<10>")
		)
		(pad "AY75" smd circle
			(at 24.402796 -8.638286 270)
			(size 0.4318 0.4318)
			(layers "F.Cu" "F.Mask" "F.Paste")
			(net "UPI_CPU1_CPU0_P2P2_DN<9>")
		)
		(pad "AY77" smd circle
			(at 26.030682 -8.638286 270)
			(size 0.4318 0.4318)
			(layers "F.Cu" "F.Mask" "F.Paste")
			(net "GND")
		)
		(pad "AY79" smd circle
			(at 27.658314 -8.638286 270)
			(size 0.4318 0.4318)
			(layers "F.Cu" "F.Mask" "F.Paste")
			(net "GND")
		)
		(pad "AY81" smd circle
			(at 29.2862 -8.638286 270)
			(size 0.4318 0.4318)
			(layers "F.Cu" "F.Mask" "F.Paste")
			(net "GND")
		)
		(pad "AY83" smd circle
			(at 30.914086 -8.638286 270)
			(size 0.4318 0.4318)
			(layers "F.Cu" "F.Mask" "F.Paste")
			(net "GND")
		)
		(pad "AY85" smd circle
			(at 32.541718 -8.638286 270)
			(size 0.4318 0.4318)
			(layers "F.Cu" "F.Mask" "F.Paste")
			(net "VSENSE_PVCCFA_EHV_FIVRA_CPU0_DP")
		)
		(pad "AY87" smd circle
			(at 34.169604 -8.638286 270)
			(size 0.4318 0.4318)
			(layers "F.Cu" "F.Mask" "F.Paste")
			(net "P5E_CPU0_PE4_TX_DP<14>")
		)
		(pad "AY89" smd circle
			(at 35.797236 -8.638286 270)
			(size 0.4318 0.4318)
			(layers "F.Cu" "F.Mask" "F.Paste")
			(net "PVCCFA_EHV_FIVRA_CPU0")
		)
		(pad "AY91" smd oval
			(at 37.425122 -8.638286)
			(size 0.381 0.4826)
			(drill
				(offset 0 -0.0508)
			)
			(layers "F.Cu" "F.Mask" "F.Paste")
			(net "P5E_CPU0_PE4_RX_DN<14>")
		)
		(pad "B6" smd oval
			(at -33.355534 -26.604468 135)
			(size 0.381 0.4826)
			(drill
				(offset 0 -0.0508)
			)
			(layers "F.Cu" "F.Mask" "F.Paste")
			(net "GND")
		)
		(pad "B8" smd oval
			(at -31.727902 -26.604468 135)
			(size 0.381 0.4826)
			(drill
				(offset 0 -0.0508)
			)
			(layers "F.Cu" "F.Mask" "F.Paste")
			(net "M_A_CPU0_SB_DQ<28>")
		)
		(pad "B10" smd oval
			(at -30.100016 -26.604468 90)
			(size 0.381 0.4826)
			(drill
				(offset 0 -0.0508)
			)
			(layers "F.Cu" "F.Mask" "F.Paste")
			(net "M_A_CPU0_SB_DQ<25>")
		)
		(pad "B12" smd circle
			(at -28.472384 -26.604468 270)
			(size 0.4318 0.4318)
			(layers "F.Cu" "F.Mask" "F.Paste")
			(net "GND")
		)
		(pad "B14" smd circle
			(at -26.844498 -26.604468 270)
			(size 0.4318 0.4318)
			(layers "F.Cu" "F.Mask" "F.Paste")
			(net "M_B_CPU0_SB_DQ<30>")
		)
		(pad "B16" smd circle
			(at -25.216612 -26.604468 270)
			(size 0.4318 0.4318)
			(layers "F.Cu" "F.Mask" "F.Paste")
			(net "M_B_CPU0_SB_DQ<25>")
		)
		(pad "B18" smd circle
			(at -23.58898 -26.604468 270)
			(size 0.4318 0.4318)
			(layers "F.Cu" "F.Mask" "F.Paste")
			(net "GND")
		)
		(pad "B20" smd circle
			(at -21.961094 -26.604468 270)
			(size 0.4318 0.4318)
			(layers "F.Cu" "F.Mask" "F.Paste")
			(net "M_A_CPU0_SB_DQ<20>")
		)
		(pad "B22" smd circle
			(at -20.333462 -26.604468 270)
			(size 0.4318 0.4318)
			(layers "F.Cu" "F.Mask" "F.Paste")
			(net "M_A_CPU0_SB_DQ<17>")
		)
		(pad "B24" smd circle
			(at -18.705576 -26.604468 270)
			(size 0.4318 0.4318)
			(layers "F.Cu" "F.Mask" "F.Paste")
			(net "GND")
		)
		(pad "B26" smd circle
			(at -17.07769 -26.604468 270)
			(size 0.4318 0.4318)
			(layers "F.Cu" "F.Mask" "F.Paste")
			(net "M_A_CPU0_SB_DQ<12>")
		)
		(pad "B28" smd circle
			(at -15.450058 -26.604468 270)
			(size 0.4318 0.4318)
			(layers "F.Cu" "F.Mask" "F.Paste")
			(net "M_A_CPU0_SB_DQ<9>")
		)
		(pad "B30" smd circle
			(at -13.822426 -26.604468 270)
			(size 0.4318 0.4318)
			(layers "F.Cu" "F.Mask" "F.Paste")
			(net "GND")
		)
		(pad "B32" smd circle
			(at -12.19454 -26.604468 270)
			(size 0.4318 0.4318)
			(layers "F.Cu" "F.Mask" "F.Paste")
			(net "M_A_CPU0_SB_CB<0>")
		)
		(pad "B34" smd circle
			(at -10.566654 -26.604468 270)
			(size 0.4318 0.4318)
			(layers "F.Cu" "F.Mask" "F.Paste")
			(net "M_A_CPU0_SB_CB<5>")
		)
		(pad "B36" smd circle
			(at -8.939022 -26.604468 270)
			(size 0.4318 0.4318)
			(layers "F.Cu" "F.Mask" "F.Paste")
			(net "GND")
		)
		(pad "B38" smd circle
			(at -7.311136 -26.604468 270)
			(size 0.4318 0.4318)
			(layers "F.Cu" "F.Mask" "F.Paste")
			(net "M_A_CPU0_SB_CS_N<0>")
		)
		(pad "B40" smd circle
			(at -5.68325 -26.604468 270)
			(size 0.4318 0.4318)
			(layers "F.Cu" "F.Mask" "F.Paste")
			(net "M_A_CPU0_SB_CA<4>")
		)
		(pad "B42" smd circle
			(at -4.055618 -26.604468 270)
			(size 0.4318 0.4318)
			(layers "F.Cu" "F.Mask" "F.Paste")
			(net "GND")
		)
		(pad "B44" smd oval
			(at -2.427732 -26.604468 45)
			(size 0.381 0.4826)
			(drill
				(offset 0 -0.0508)
			)
			(layers "F.Cu" "F.Mask" "F.Paste")
			(net "M_A_CPU0_CLK_DN<0>")
		)
		(pad "B49" smd oval
			(at 3.241802 -26.494486 135)
			(size 0.381 0.4826)
			(drill
				(offset 0 -0.0508)
			)
			(layers "F.Cu" "F.Mask" "F.Paste")
			(net "GND")
		)
		(pad "B51" smd circle
			(at 4.869434 -26.494486 270)
			(size 0.4318 0.4318)
			(layers "F.Cu" "F.Mask" "F.Paste")
			(net "M_A_CPU0_SA_CA<2>")
		)
		(pad "B53" smd circle
			(at 6.49732 -26.494486 270)
			(size 0.4318 0.4318)
			(layers "F.Cu" "F.Mask" "F.Paste")
			(net "M_A_CPU0_SA_CS_N<1>")
		)
		(pad "B55" smd circle
			(at 8.124952 -26.494486 270)
			(size 0.4318 0.4318)
			(layers "F.Cu" "F.Mask" "F.Paste")
			(net "GND")
		)
		(pad "B57" smd circle
			(at 9.752838 -26.494486 270)
			(size 0.4318 0.4318)
			(layers "F.Cu" "F.Mask" "F.Paste")
			(net "M_A_CPU0_SA_CB<4>")
		)
		(pad "B59" smd circle
			(at 11.380724 -26.494486 270)
			(size 0.4318 0.4318)
			(layers "F.Cu" "F.Mask" "F.Paste")
			(net "M_A_CPU0_SA_CB<1>")
		)
		(pad "B61" smd circle
			(at 13.008356 -26.494486 270)
			(size 0.4318 0.4318)
			(layers "F.Cu" "F.Mask" "F.Paste")
			(net "GND")
		)
		(pad "B63" smd circle
			(at 14.635988 -26.494486 270)
			(size 0.4318 0.4318)
			(layers "F.Cu" "F.Mask" "F.Paste")
			(net "M_A_CPU0_SA_DQ<28>")
		)
		(pad "B65" smd oval
			(at 16.263874 -26.494486 90)
			(size 0.381 0.4826)
			(drill
				(offset 0 -0.0508)
			)
			(layers "F.Cu" "F.Mask" "F.Paste")
			(net "M_A_CPU0_SA_DQ<25>")
		)
		(pad "B67" smd oval
			(at 17.89176 -26.494486 90)
			(size 0.381 0.4826)
			(drill
				(offset 0 -0.0508)
			)
			(layers "F.Cu" "F.Mask" "F.Paste")
			(net "GND")
		)
		(pad "B69" smd oval
			(at 19.519392 -26.494486 90)
			(size 0.381 0.4826)
			(drill
				(offset 0 -0.0508)
			)
			(layers "F.Cu" "F.Mask" "F.Paste")
			(net "M_A_CPU0_SA_DQ<20>")
		)
		(pad "B71" smd oval
			(at 21.147278 -26.494486 90)
			(size 0.381 0.4826)
			(drill
				(offset 0 -0.0508)
			)
			(layers "F.Cu" "F.Mask" "F.Paste")
			(net "M_A_CPU0_SA_DQS_DN<2>")
		)
		(pad "B73" smd oval
			(at 22.77491 -26.494486 90)
			(size 0.381 0.4826)
			(drill
				(offset 0 -0.0508)
			)
			(layers "F.Cu" "F.Mask" "F.Paste")
			(net "M_A_CPU0_SA_DQ<16>")
		)
		(pad "B75" smd oval
			(at 24.402796 -26.494486 90)
			(size 0.381 0.4826)
			(drill
				(offset 0 -0.0508)
			)
			(layers "F.Cu" "F.Mask" "F.Paste")
			(net "GND")
		)
		(pad "B77" smd oval
			(at 26.030682 -26.494486 90)
			(size 0.381 0.4826)
			(drill
				(offset 0 -0.0508)
			)
			(layers "F.Cu" "F.Mask" "F.Paste")
			(net "M_A_CPU0_SA_DQS_DN<0>")
		)
		(pad "B79" smd oval
			(at 27.658314 -26.494486 90)
			(size 0.381 0.4826)
			(drill
				(offset 0 -0.0508)
			)
			(layers "F.Cu" "F.Mask" "F.Paste")
			(net "M_A_CPU0_SA_DQ<1>")
		)
		(pad "B81" smd oval
			(at 29.2862 -26.494486 90)
			(size 0.381 0.4826)
			(drill
				(offset 0 -0.0508)
			)
			(layers "F.Cu" "F.Mask" "F.Paste")
			(net "M_A_CPU0_SA_DQ<0>")
		)
		(pad "B83" smd oval
			(at 30.914086 -26.494486 45)
			(size 0.381 0.4826)
			(drill
				(offset 0 -0.0508)
			)
			(layers "F.Cu" "F.Mask" "F.Paste")
			(net "GND")
		)
		(pad "B85" smd oval
			(at 32.541718 -26.494486 45)
			(size 0.381 0.4826)
			(drill
				(offset 0 -0.0508)
			)
			(layers "F.Cu" "F.Mask" "F.Paste")
			(net "UPI_CPU0_CPU1_P2P2_DN<23>")
		)
		(pad "B87" smd oval
			(at 34.169604 -26.494486 45)
			(size 0.381 0.4826)
			(drill
				(offset 0 -0.0508)
			)
			(layers "F.Cu" "F.Mask" "F.Paste")
			(net "GND")
		)
		(pad "BA1" smd oval
			(at -37.425122 -8.278114 180)
			(size 0.381 0.4826)
			(drill
				(offset 0 -0.0508)
			)
			(layers "F.Cu" "F.Mask" "F.Paste")
			(net "UPI_CPU0_CPU1_P0P1_DP<16>")
		)
		(pad "BA3" smd circle
			(at -35.797236 -8.278114 270)
			(size 0.4318 0.4318)
			(layers "F.Cu" "F.Mask" "F.Paste")
			(net "PVCCD_HV_CPU0")
		)
		(pad "BA5" smd circle
			(at -34.169604 -8.278114 270)
			(size 0.4318 0.4318)
			(layers "F.Cu" "F.Mask" "F.Paste")
			(net "UPI_CPU1_CPU0_P1P0_DP<15>")
		)
		(pad "BA7" smd circle
			(at -32.541718 -8.278114 270)
			(size 0.4318 0.4318)
			(layers "F.Cu" "F.Mask" "F.Paste")
			(net "PVCCD_HV_CPU0")
		)
		(pad "BA9" smd circle
			(at -30.914086 -8.278114 270)
			(size 0.4318 0.4318)
			(layers "F.Cu" "F.Mask" "F.Paste")
			(net "P5E_CPU0_PE0_RX_DN<15>")
		)
		(pad "BA11" smd circle
			(at -29.2862 -8.278114 270)
			(size 0.4318 0.4318)
			(layers "F.Cu" "F.Mask" "F.Paste")
			(net "VSENSE_PVCCFA_EHV_CPU0_DN")
		)
		(pad "BA13" smd circle
			(at -27.658314 -8.278114 270)
			(size 0.4318 0.4318)
			(layers "F.Cu" "F.Mask" "F.Paste")
			(net "P5E_CPU0_PE0_TX_DN<14>")
		)
		(pad "BA15" smd circle
			(at -26.030682 -8.278114 270)
			(size 0.4318 0.4318)
			(layers "F.Cu" "F.Mask" "F.Paste")
			(net "PVCCINFAON_CPU0")
		)
		(pad "BA17" smd circle
			(at -24.402796 -8.278114 270)
			(size 0.4318 0.4318)
			(layers "F.Cu" "F.Mask" "F.Paste")
			(net "GND")
		)
		(pad "BA19" smd circle
			(at -22.77491 -8.278114 270)
			(size 0.4318 0.4318)
			(layers "F.Cu" "F.Mask" "F.Paste")
			(net "PVNN_MAIN_CPU0")
		)
		(pad "BA21" smd circle
			(at -21.147278 -8.278114 270)
			(size 0.4318 0.4318)
			(layers "F.Cu" "F.Mask" "F.Paste")
			(net "P3V3_AUX")
		)
		(pad "BA23" smd circle
			(at -19.519392 -8.278114 270)
			(size 0.4318 0.4318)
			(layers "F.Cu" "F.Mask" "F.Paste")
			(net "PU_CPU0_UPI0_AC_COUPLING")
		)
		(pad "BA25" smd circle
			(at -17.89176 -8.278114 270)
			(size 0.4318 0.4318)
			(layers "F.Cu" "F.Mask" "F.Paste")
			(net "NC_CPU0_SOC_SPARE4")
		)
		(pad "BA60" smd circle
			(at 12.19454 -8.168132 270)
			(size 0.4318 0.4318)
			(layers "F.Cu" "F.Mask" "F.Paste")
			(net "GND")
		)
		(pad "BA62" smd circle
			(at 13.822426 -8.168132 270)
			(size 0.4318 0.4318)
			(layers "F.Cu" "F.Mask" "F.Paste")
			(net "TP_SPI_S3M_CPU0_IO0_LVC1_R")
		)
		(pad "BA64" smd circle
			(at 15.450058 -8.168132 270)
			(size 0.4318 0.4318)
			(layers "F.Cu" "F.Mask" "F.Paste")
			(net "GND")
		)
		(pad "BA66" smd circle
			(at 17.07769 -8.168132 270)
			(size 0.4318 0.4318)
			(layers "F.Cu" "F.Mask" "F.Paste")
			(net "TP_SPI_IBL_CPU0_TPM_IO0")
		)
		(pad "BA68" smd circle
			(at 18.705576 -8.168132 270)
			(size 0.4318 0.4318)
			(layers "F.Cu" "F.Mask" "F.Paste")
			(net "TP_SPI_S3M_CPU0_OE_LVC1_R_N")
		)
		(pad "BA70" smd circle
			(at 20.333462 -8.168132 270)
			(size 0.4318 0.4318)
			(layers "F.Cu" "F.Mask" "F.Paste")
			(net "FM_S3M_CPU0_LVC1_GPIO_0")
		)
		(pad "BA72" smd circle
			(at 21.961094 -8.168132 270)
			(size 0.4318 0.4318)
			(layers "F.Cu" "F.Mask" "F.Paste")
			(net "UPI_CPU1_CPU0_P2P2_DP<11>")
		)
		(pad "BA74" smd circle
			(at 23.58898 -8.168132 270)
			(size 0.4318 0.4318)
			(layers "F.Cu" "F.Mask" "F.Paste")
			(net "GND")
		)
		(pad "BA76" smd circle
			(at 25.216612 -8.168132 270)
			(size 0.4318 0.4318)
			(layers "F.Cu" "F.Mask" "F.Paste")
			(net "UPI_CPU1_CPU0_P2P2_DP<9>")
		)
		(pad "BA78" smd circle
			(at 26.844498 -8.168132 270)
			(size 0.4318 0.4318)
			(layers "F.Cu" "F.Mask" "F.Paste")
			(net "UPI_CPU0_CPU1_P2P2_DP<13>")
		)
		(pad "BA80" smd circle
			(at 28.472384 -8.168132 270)
			(size 0.4318 0.4318)
			(layers "F.Cu" "F.Mask" "F.Paste")
			(net "UPI_CPU0_CPU1_P2P2_DN<6>")
		)
		(pad "BA82" smd circle
			(at 30.100016 -8.168132 270)
			(size 0.4318 0.4318)
			(layers "F.Cu" "F.Mask" "F.Paste")
			(net "UPI_CPU0_CPU1_P2P2_DP<5>")
		)
		(pad "BA84" smd circle
			(at 31.727902 -8.168132 270)
			(size 0.4318 0.4318)
			(layers "F.Cu" "F.Mask" "F.Paste")
			(net "GND")
		)
		(pad "BA86" smd circle
			(at 33.355534 -8.168132 270)
			(size 0.4318 0.4318)
			(layers "F.Cu" "F.Mask" "F.Paste")
			(net "P5E_CPU0_PE4_TX_DN<15>")
		)
		(pad "BA88" smd circle
			(at 34.98342 -8.168132 270)
			(size 0.4318 0.4318)
			(layers "F.Cu" "F.Mask" "F.Paste")
			(net "GND")
		)
		(pad "BA90" smd circle
			(at 36.611306 -8.168132 270)
			(size 0.4318 0.4318)
			(layers "F.Cu" "F.Mask" "F.Paste")
			(net "P5E_CPU0_PE4_RX_DP<15>")
		)
		(pad "BB2" smd circle
			(at -36.611306 -7.808468 270)
			(size 0.4318 0.4318)
			(layers "F.Cu" "F.Mask" "F.Paste")
			(net "UPI_CPU0_CPU1_P0P1_DN<16>")
		)
		(pad "BB4" smd circle
			(at -34.98342 -7.808468 270)
			(size 0.4318 0.4318)
			(layers "F.Cu" "F.Mask" "F.Paste")
			(net "GND")
		)
		(pad "BB6" smd circle
			(at -33.355534 -7.808468 270)
			(size 0.4318 0.4318)
			(layers "F.Cu" "F.Mask" "F.Paste")
			(net "UPI_CPU1_CPU0_P1P0_DP<16>")
		)
		(pad "BB8" smd circle
			(at -31.727902 -7.808468 270)
			(size 0.4318 0.4318)
			(layers "F.Cu" "F.Mask" "F.Paste")
			(net "GND")
		)
		(pad "BB10" smd circle
			(at -30.100016 -7.808468 270)
			(size 0.4318 0.4318)
			(layers "F.Cu" "F.Mask" "F.Paste")
			(net "GND")
		)
		(pad "BB12" smd circle
			(at -28.472384 -7.808468 270)
			(size 0.4318 0.4318)
			(layers "F.Cu" "F.Mask" "F.Paste")
			(net "GND")
		)
		(pad "BB14" smd circle
			(at -26.844498 -7.808468 270)
			(size 0.4318 0.4318)
			(layers "F.Cu" "F.Mask" "F.Paste")
			(net "P5E_CPU0_PE0_TX_DN<15>")
		)
		(pad "BB16" smd circle
			(at -25.216612 -7.808468 270)
			(size 0.4318 0.4318)
			(layers "F.Cu" "F.Mask" "F.Paste")
			(net "GND")
		)
		(pad "BB18" smd circle
			(at -23.58898 -7.808468 270)
			(size 0.4318 0.4318)
			(layers "F.Cu" "F.Mask" "F.Paste")
			(net "DMI_CPU0_PCH_RX_C_DN<0>")
		)
		(pad "BB20" smd circle
			(at -21.961094 -7.808468 270)
			(size 0.4318 0.4318)
			(layers "F.Cu" "F.Mask" "F.Paste")
			(net "GND")
		)
		(pad "BB22" smd circle
			(at -20.333462 -7.808468 270)
			(size 0.4318 0.4318)
			(layers "F.Cu" "F.Mask" "F.Paste")
			(net "GND")
		)
		(pad "BB24" smd circle
			(at -18.705576 -7.808468 270)
			(size 0.4318 0.4318)
			(layers "F.Cu" "F.Mask" "F.Paste")
			(net "GND")
		)
		(pad "BB26" smd circle
			(at -17.07769 -7.808468 270)
			(size 0.4318 0.4318)
			(layers "F.Cu" "F.Mask" "F.Paste")
			(net "GND")
		)
		(pad "BB61" smd circle
			(at 13.008356 -7.698486 270)
			(size 0.4318 0.4318)
			(layers "F.Cu" "F.Mask" "F.Paste")
			(net "TP_SPI_S3M_CPU0_CS0_LVC1_R_N")
		)
		(pad "BB63" smd circle
			(at 14.635988 -7.698486 270)
			(size 0.4318 0.4318)
			(layers "F.Cu" "F.Mask" "F.Paste")
			(net "GND")
		)
		(pad "BB65" smd circle
			(at 16.263874 -7.698486 270)
			(size 0.4318 0.4318)
			(layers "F.Cu" "F.Mask" "F.Paste")
			(net "PU_CPU0_UPI2_AC_COUPLING")
		)
		(pad "BB67" smd circle
			(at 17.89176 -7.698486 270)
			(size 0.4318 0.4318)
			(layers "F.Cu" "F.Mask" "F.Paste")
			(net "TP_SPI_IBL_CPU0_TPM_OE_N")
		)
		(pad "BB69" smd circle
			(at 19.519392 -7.698486 270)
			(size 0.4318 0.4318)
			(layers "F.Cu" "F.Mask" "F.Paste")
			(net "GND")
		)
		(pad "BB71" smd circle
			(at 21.147278 -7.698486 270)
			(size 0.4318 0.4318)
			(layers "F.Cu" "F.Mask" "F.Paste")
			(net "GND")
		)
		(pad "BB73" smd circle
			(at 22.77491 -7.698486 270)
			(size 0.4318 0.4318)
			(layers "F.Cu" "F.Mask" "F.Paste")
			(net "UPI_CPU1_CPU0_P2P2_DN<11>")
		)
		(pad "BB75" smd circle
			(at 24.402796 -7.698486 270)
			(size 0.4318 0.4318)
			(layers "F.Cu" "F.Mask" "F.Paste")
			(net "UPI_CPU1_CPU0_P2P2_DP<8>")
		)
		(pad "BB77" smd circle
			(at 26.030682 -7.698486 270)
			(size 0.4318 0.4318)
			(layers "F.Cu" "F.Mask" "F.Paste")
			(net "GND")
		)
		(pad "BB79" smd circle
			(at 27.658314 -7.698486 270)
			(size 0.4318 0.4318)
			(layers "F.Cu" "F.Mask" "F.Paste")
			(net "GND")
		)
		(pad "BB81" smd circle
			(at 29.2862 -7.698486 270)
			(size 0.4318 0.4318)
			(layers "F.Cu" "F.Mask" "F.Paste")
			(net "UPI_CPU0_CPU1_P2P2_DP<6>")
		)
		(pad "BB83" smd circle
			(at 30.914086 -7.698486 270)
			(size 0.4318 0.4318)
			(layers "F.Cu" "F.Mask" "F.Paste")
			(net "GND")
		)
		(pad "BB85" smd circle
			(at 32.541718 -7.698486 270)
			(size 0.4318 0.4318)
			(layers "F.Cu" "F.Mask" "F.Paste")
			(net "P5E_CPU0_PE4_TX_DP<15>")
		)
		(pad "BB87" smd circle
			(at 34.169604 -7.698486 270)
			(size 0.4318 0.4318)
			(layers "F.Cu" "F.Mask" "F.Paste")
			(net "GND")
		)
		(pad "BB89" smd circle
			(at 35.797236 -7.698486 270)
			(size 0.4318 0.4318)
			(layers "F.Cu" "F.Mask" "F.Paste")
			(net "P5E_CPU0_PE4_RX_DN<15>")
		)
		(pad "BB91" smd oval
			(at 37.425122 -7.698486)
			(size 0.381 0.4826)
			(drill
				(offset 0 -0.0508)
			)
			(layers "F.Cu" "F.Mask" "F.Paste")
			(net "GND")
		)
		(pad "BC1" smd oval
			(at -37.425122 -7.338314 180)
			(size 0.381 0.4826)
			(drill
				(offset 0 -0.0508)
			)
			(layers "F.Cu" "F.Mask" "F.Paste")
			(net "GND")
		)
		(pad "BC3" smd circle
			(at -35.797236 -7.338314 270)
			(size 0.4318 0.4318)
			(layers "F.Cu" "F.Mask" "F.Paste")
			(net "UPI_CPU0_CPU1_P0P1_DP<17>")
		)
		(pad "BC5" smd circle
			(at -34.169604 -7.338314 270)
			(size 0.4318 0.4318)
			(layers "F.Cu" "F.Mask" "F.Paste")
			(net "GND")
		)
		(pad "BC7" smd circle
			(at -32.541718 -7.338314 270)
			(size 0.4318 0.4318)
			(layers "F.Cu" "F.Mask" "F.Paste")
			(net "UPI_CPU1_CPU0_P1P0_DN<16>")
		)
		(pad "BC9" smd circle
			(at -30.914086 -7.338314 270)
			(size 0.4318 0.4318)
			(layers "F.Cu" "F.Mask" "F.Paste")
			(net "GND")
		)
		(pad "BC11" smd circle
			(at -29.2862 -7.338314 270)
			(size 0.4318 0.4318)
			(layers "F.Cu" "F.Mask" "F.Paste")
			(net "P5E_CPU0_PE1_RX_DN<15>")
		)
		(pad "BC13" smd circle
			(at -27.658314 -7.338314 270)
			(size 0.4318 0.4318)
			(layers "F.Cu" "F.Mask" "F.Paste")
			(net "GND")
		)
		(pad "BC15" smd circle
			(at -26.030682 -7.338314 270)
			(size 0.4318 0.4318)
			(layers "F.Cu" "F.Mask" "F.Paste")
			(net "P5E_CPU0_PE0_TX_DP<15>")
		)
		(pad "BC17" smd circle
			(at -24.402796 -7.338314 270)
			(size 0.4318 0.4318)
			(layers "F.Cu" "F.Mask" "F.Paste")
			(net "GND")
		)
		(pad "BC19" smd circle
			(at -22.77491 -7.338314 270)
			(size 0.4318 0.4318)
			(layers "F.Cu" "F.Mask" "F.Paste")
			(net "DMI_CPU0_PCH_RX_C_DP<0>")
		)
		(pad "BC21" smd circle
			(at -21.147278 -7.338314 270)
			(size 0.4318 0.4318)
			(layers "F.Cu" "F.Mask" "F.Paste")
			(net "P3V3_AUX")
		)
		(pad "BC23" smd circle
			(at -19.519392 -7.338314 270)
			(size 0.4318 0.4318)
			(layers "F.Cu" "F.Mask" "F.Paste")
			(net "TP_CPU0_IFST_DONE_LVC1_R")
		)
		(pad "BC25" smd circle
			(at -17.89176 -7.338314 270)
			(size 0.4318 0.4318)
			(layers "F.Cu" "F.Mask" "F.Paste")
			(net "TP_I3C_MNG2_BMC_SW_SDA")
		)
		(pad "BC60" smd circle
			(at 12.19454 -7.228332 270)
			(size 0.4318 0.4318)
			(layers "F.Cu" "F.Mask" "F.Paste")
			(net "PVCCINFAON_CPU0")
		)
		(pad "BC62" smd circle
			(at 13.822426 -7.228332 270)
			(size 0.4318 0.4318)
			(layers "F.Cu" "F.Mask" "F.Paste")
			(net "GND")
		)
		(pad "BC64" smd circle
			(at 15.450058 -7.228332 270)
			(size 0.4318 0.4318)
			(layers "F.Cu" "F.Mask" "F.Paste")
			(net "TP_SPI_S3M_CPU0_CLK_LVC1_R")
		)
		(pad "BC66" smd circle
			(at 17.07769 -7.228332 270)
			(size 0.4318 0.4318)
			(layers "F.Cu" "F.Mask" "F.Paste")
			(net "GND")
		)
		(pad "BC68" smd circle
			(at 18.705576 -7.228332 270)
			(size 0.4318 0.4318)
			(layers "F.Cu" "F.Mask" "F.Paste")
			(net "TP_TRC_CPU0_PTI<21>")
		)
		(pad "BC70" smd circle
			(at 20.333462 -7.228332 270)
			(size 0.4318 0.4318)
			(layers "F.Cu" "F.Mask" "F.Paste")
			(net "TP_TRC_CPU0_PTI<16>")
		)
		(pad "BC72" smd circle
			(at 21.961094 -7.228332 270)
			(size 0.4318 0.4318)
			(layers "F.Cu" "F.Mask" "F.Paste")
			(net "GND")
		)
		(pad "BC74" smd circle
			(at 23.58898 -7.228332 270)
			(size 0.4318 0.4318)
			(layers "F.Cu" "F.Mask" "F.Paste")
			(net "UPI_CPU1_CPU0_P2P2_DN<0>")
		)
		(pad "BC76" smd circle
			(at 25.216612 -7.228332 270)
			(size 0.4318 0.4318)
			(layers "F.Cu" "F.Mask" "F.Paste")
			(net "GND")
		)
		(pad "BC78" smd circle
			(at 26.844498 -7.228332 270)
			(size 0.4318 0.4318)
			(layers "F.Cu" "F.Mask" "F.Paste")
			(net "GND")
		)
		(pad "BC80" smd circle
			(at 28.472384 -7.228332 270)
			(size 0.4318 0.4318)
			(layers "F.Cu" "F.Mask" "F.Paste")
			(net "UPI_CPU0_CPU1_P2P2_DP<3>")
		)
		(pad "BC82" smd circle
			(at 30.100016 -7.228332 270)
			(size 0.4318 0.4318)
			(layers "F.Cu" "F.Mask" "F.Paste")
			(net "UPI_CPU0_CPU1_P2P2_DN<5>")
		)
		(pad "BC84" smd circle
			(at 31.727902 -7.228332 270)
			(size 0.4318 0.4318)
			(layers "F.Cu" "F.Mask" "F.Paste")
			(net "GND")
		)
		(pad "BC86" smd circle
			(at 33.355534 -7.228332 270)
			(size 0.4318 0.4318)
			(layers "F.Cu" "F.Mask" "F.Paste")
			(net "GND")
		)
		(pad "BC88" smd circle
			(at 34.98342 -7.228332 270)
			(size 0.4318 0.4318)
			(layers "F.Cu" "F.Mask" "F.Paste")
			(net "GND")
		)
		(pad "BC90" smd circle
			(at 36.611306 -7.228332 270)
			(size 0.4318 0.4318)
			(layers "F.Cu" "F.Mask" "F.Paste")
			(net "VSENSE_PVCCIN_CPU0_DN")
		)
		(pad "BD2" smd circle
			(at -36.611306 -6.868668 270)
			(size 0.4318 0.4318)
			(layers "F.Cu" "F.Mask" "F.Paste")
			(net "UPI_CPU0_CPU1_P0P1_DN<17>")
		)
		(pad "BD4" smd circle
			(at -34.98342 -6.868668 270)
			(size 0.4318 0.4318)
			(layers "F.Cu" "F.Mask" "F.Paste")
			(net "GND")
		)
		(pad "BD6" smd circle
			(at -33.355534 -6.868668 270)
			(size 0.4318 0.4318)
			(layers "F.Cu" "F.Mask" "F.Paste")
			(net "UPI_CPU1_CPU0_P1P0_DN<17>")
		)
		(pad "BD8" smd circle
			(at -31.727902 -6.868668 270)
			(size 0.4318 0.4318)
			(layers "F.Cu" "F.Mask" "F.Paste")
			(net "GND")
		)
		(pad "BD10" smd circle
			(at -30.100016 -6.868668 270)
			(size 0.4318 0.4318)
			(layers "F.Cu" "F.Mask" "F.Paste")
			(net "P5E_CPU0_PE1_RX_DP<15>")
		)
		(pad "BD12" smd circle
			(at -28.472384 -6.868668 270)
			(size 0.4318 0.4318)
			(layers "F.Cu" "F.Mask" "F.Paste")
			(net "GND")
		)
		(pad "BD14" smd circle
			(at -26.844498 -6.868668 270)
			(size 0.4318 0.4318)
			(layers "F.Cu" "F.Mask" "F.Paste")
			(net "P5E_CPU0_PE1_TX_DP<15>")
		)
		(pad "BD16" smd circle
			(at -25.216612 -6.868668 270)
			(size 0.4318 0.4318)
			(layers "F.Cu" "F.Mask" "F.Paste")
			(net "GND")
		)
		(pad "BD18" smd circle
			(at -23.58898 -6.868668 270)
			(size 0.4318 0.4318)
			(layers "F.Cu" "F.Mask" "F.Paste")
			(net "DMI_CPU0_PCH_RX_C_DN<1>")
		)
		(pad "BD20" smd circle
			(at -21.961094 -6.868668 270)
			(size 0.4318 0.4318)
			(layers "F.Cu" "F.Mask" "F.Paste")
			(net "GND")
		)
		(pad "BD22" smd circle
			(at -20.333462 -6.868668 270)
			(size 0.4318 0.4318)
			(layers "F.Cu" "F.Mask" "F.Paste")
			(net "H_CPU0_ERR2_LVC1_R_N")
		)
		(pad "BD24" smd circle
			(at -18.705576 -6.868668 270)
			(size 0.4318 0.4318)
			(layers "F.Cu" "F.Mask" "F.Paste")
			(net "H_PMAX_TRIGGER_IO_CPU0")
		)
		(pad "BD26" smd circle
			(at -17.07769 -6.868668 270)
			(size 0.4318 0.4318)
			(layers "F.Cu" "F.Mask" "F.Paste")
			(net "SVID_DIO0_CPU0")
		)
		(pad "BD61" smd circle
			(at 13.008356 -6.758686 270)
			(size 0.4318 0.4318)
			(layers "F.Cu" "F.Mask" "F.Paste")
			(net "TP_SPI_S3M_CPU0_IO3_LVC1_R")
		)
		(pad "BD63" smd circle
			(at 14.635988 -6.758686 270)
			(size 0.4318 0.4318)
			(layers "F.Cu" "F.Mask" "F.Paste")
			(net "TP_ESPI_IBL_CPU0_ALERT1_N")
		)
		(pad "BD65" smd circle
			(at 16.263874 -6.758686 270)
			(size 0.4318 0.4318)
			(layers "F.Cu" "F.Mask" "F.Paste")
			(net "TP_SPI_S3M_CPU0_IO2_LVC1_R")
		)
		(pad "BD67" smd circle
			(at 17.89176 -6.758686 270)
			(size 0.4318 0.4318)
			(layers "F.Cu" "F.Mask" "F.Paste")
			(net "TP_TRC_CPU0_PTI<23>")
		)
		(pad "BD69" smd circle
			(at 19.519392 -6.758686 270)
			(size 0.4318 0.4318)
			(layers "F.Cu" "F.Mask" "F.Paste")
			(net "TP_TRC_CPU0_PTI<18>")
		)
		(pad "BD71" smd circle
			(at 21.147278 -6.758686 270)
			(size 0.4318 0.4318)
			(layers "F.Cu" "F.Mask" "F.Paste")
			(net "NC_CPU0_MDFI_DIE01_NS1")
		)
		(pad "BD73" smd circle
			(at 22.77491 -6.758686 270)
			(size 0.4318 0.4318)
			(layers "F.Cu" "F.Mask" "F.Paste")
			(net "UPI_CPU1_CPU0_P2P2_DP<0>")
		)
		(pad "BD75" smd circle
			(at 24.402796 -6.758686 270)
			(size 0.4318 0.4318)
			(layers "F.Cu" "F.Mask" "F.Paste")
			(net "UPI_CPU1_CPU0_P2P2_DN<8>")
		)
		(pad "BD77" smd circle
			(at 26.030682 -6.758686 270)
			(size 0.4318 0.4318)
			(layers "F.Cu" "F.Mask" "F.Paste")
			(net "TP_CPU0_SPARE13")
		)
		(pad "BD79" smd circle
			(at 27.658314 -6.758686 270)
			(size 0.4318 0.4318)
			(layers "F.Cu" "F.Mask" "F.Paste")
			(net "UPI_CPU0_CPU1_P2P2_DN<3>")
		)
		(pad "BD81" smd circle
			(at 29.2862 -6.758686 270)
			(size 0.4318 0.4318)
			(layers "F.Cu" "F.Mask" "F.Paste")
			(net "GND")
		)
		(pad "BD83" smd circle
			(at 30.914086 -6.758686 270)
			(size 0.4318 0.4318)
			(layers "F.Cu" "F.Mask" "F.Paste")
			(net "UPI_CPU0_CPU1_P2P2_DP<4>")
		)
		(pad "BD85" smd circle
			(at 32.541718 -6.758686 270)
			(size 0.4318 0.4318)
			(layers "F.Cu" "F.Mask" "F.Paste")
			(net "GND")
		)
		(pad "BD87" smd circle
			(at 34.169604 -6.758686 270)
			(size 0.4318 0.4318)
			(layers "F.Cu" "F.Mask" "F.Paste")
			(net "VSENSE_PVCCIN_CPU0_DP")
		)
		(pad "BD89" smd circle
			(at 35.797236 -6.758686 270)
			(size 0.4318 0.4318)
			(layers "F.Cu" "F.Mask" "F.Paste")
			(net "GND")
		)
		(pad "BD91" smd oval
			(at 37.425122 -6.758686)
			(size 0.381 0.4826)
			(drill
				(offset 0 -0.0508)
			)
			(layers "F.Cu" "F.Mask" "F.Paste")
			(net "PVCCIN_CPU0")
		)
		(pad "BE1" smd oval
			(at -37.425122 -6.398514 180)
			(size 0.381 0.4826)
			(drill
				(offset 0 -0.0508)
			)
			(layers "F.Cu" "F.Mask" "F.Paste")
			(net "UPI_CPU0_CPU1_P0P1_DP<18>")
		)
		(pad "BE3" smd circle
			(at -35.797236 -6.398514 270)
			(size 0.4318 0.4318)
			(layers "F.Cu" "F.Mask" "F.Paste")
			(net "PVCCD_HV_CPU0")
		)
		(pad "BE5" smd circle
			(at -34.169604 -6.398514 270)
			(size 0.4318 0.4318)
			(layers "F.Cu" "F.Mask" "F.Paste")
			(net "UPI_CPU1_CPU0_P1P0_DP<17>")
		)
		(pad "BE7" smd circle
			(at -32.541718 -6.398514 270)
			(size 0.4318 0.4318)
			(layers "F.Cu" "F.Mask" "F.Paste")
			(net "PVCCD_HV_CPU0")
		)
		(pad "BE9" smd circle
			(at -30.914086 -6.398514 270)
			(size 0.4318 0.4318)
			(layers "F.Cu" "F.Mask" "F.Paste")
			(net "P5E_CPU0_PE1_RX_DP<14>")
		)
		(pad "BE11" smd circle
			(at -29.2862 -6.398514 270)
			(size 0.4318 0.4318)
			(layers "F.Cu" "F.Mask" "F.Paste")
			(net "PVCCD_HV_CPU0")
		)
		(pad "BE13" smd circle
			(at -27.658314 -6.398514 270)
			(size 0.4318 0.4318)
			(layers "F.Cu" "F.Mask" "F.Paste")
			(net "P5E_CPU0_PE1_TX_DN<15>")
		)
		(pad "BE15" smd circle
			(at -26.030682 -6.398514 270)
			(size 0.4318 0.4318)
			(layers "F.Cu" "F.Mask" "F.Paste")
			(net "PVCCINFAON_CPU0")
		)
		(pad "BE17" smd circle
			(at -24.402796 -6.398514 270)
			(size 0.4318 0.4318)
			(layers "F.Cu" "F.Mask" "F.Paste")
			(net "DMI_CPU0_PCH_RX_C_DP<1>")
		)
		(pad "BE19" smd circle
			(at -22.77491 -6.398514 270)
			(size 0.4318 0.4318)
			(layers "F.Cu" "F.Mask" "F.Paste")
			(net "PVNN_MAIN_CPU0")
		)
		(pad "BE21" smd circle
			(at -21.147278 -6.398514 270)
			(size 0.4318 0.4318)
			(layers "F.Cu" "F.Mask" "F.Paste")
			(net "TP_CPU0_DIE_HVM_EN_LVC1")
		)
		(pad "BE23" smd circle
			(at -19.519392 -6.398514 270)
			(size 0.4318 0.4318)
			(layers "F.Cu" "F.Mask" "F.Paste")
			(net "TP_CPU0_IFST_KOT_LVC1_R")
		)
		(pad "BE25" smd circle
			(at -17.89176 -6.398514 270)
			(size 0.4318 0.4318)
			(layers "F.Cu" "F.Mask" "F.Paste")
			(net "TP_I3C_MNG2_BMC_SW_SCL")
		)
		(pad "BE60" smd circle
			(at 12.19454 -6.288532 270)
			(size 0.4318 0.4318)
			(layers "F.Cu" "F.Mask" "F.Paste")
			(net "PVCCINFAON_CPU0")
		)
		(pad "BE62" smd circle
			(at 13.822426 -6.288532 270)
			(size 0.4318 0.4318)
			(layers "F.Cu" "F.Mask" "F.Paste")
			(net "TP_ESPI_IBL_CPU0_ALERT0_LVC1_N")
		)
		(pad "BE64" smd circle
			(at 15.450058 -6.288532 270)
			(size 0.4318 0.4318)
			(layers "F.Cu" "F.Mask" "F.Paste")
			(net "GND")
		)
		(pad "BE66" smd circle
			(at 17.07769 -6.288532 270)
			(size 0.4318 0.4318)
			(layers "F.Cu" "F.Mask" "F.Paste")
			(net "GND")
		)
		(pad "BE68" smd circle
			(at 18.705576 -6.288532 270)
			(size 0.4318 0.4318)
			(layers "F.Cu" "F.Mask" "F.Paste")
			(net "GND")
		)
		(pad "BE70" smd circle
			(at 20.333462 -6.288532 270)
			(size 0.4318 0.4318)
			(layers "F.Cu" "F.Mask" "F.Paste")
			(net "TP_TRC_CPU0_PTI<17>")
		)
		(pad "BE72" smd circle
			(at 21.961094 -6.288532 270)
			(size 0.4318 0.4318)
			(layers "F.Cu" "F.Mask" "F.Paste")
			(net "PVCCFA_EHV_FIVRA_CPU0")
		)
		(pad "BE74" smd circle
			(at 23.58898 -6.288532 270)
			(size 0.4318 0.4318)
			(layers "F.Cu" "F.Mask" "F.Paste")
			(net "GND")
		)
		(pad "BE76" smd circle
			(at 25.216612 -6.288532 270)
			(size 0.4318 0.4318)
			(layers "F.Cu" "F.Mask" "F.Paste")
			(net "GND")
		)
		(pad "BE78" smd circle
			(at 26.844498 -6.288532 270)
			(size 0.4318 0.4318)
			(layers "F.Cu" "F.Mask" "F.Paste")
			(net "GND")
		)
		(pad "BE80" smd circle
			(at 28.472384 -6.288532 270)
			(size 0.4318 0.4318)
			(layers "F.Cu" "F.Mask" "F.Paste")
			(net "UPI_CPU0_CPU1_P2P2_DP<1>")
		)
		(pad "BE82" smd circle
			(at 30.100016 -6.288532 270)
			(size 0.4318 0.4318)
			(layers "F.Cu" "F.Mask" "F.Paste")
			(net "UPI_CPU0_CPU1_P2P2_DN<4>")
		)
		(pad "BE84" smd circle
			(at 31.727902 -6.288532 270)
			(size 0.4318 0.4318)
			(layers "F.Cu" "F.Mask" "F.Paste")
			(net "GND")
		)
		(pad "BE86" smd circle
			(at 33.355534 -6.288532 270)
			(size 0.4318 0.4318)
			(layers "F.Cu" "F.Mask" "F.Paste")
			(net "PVCCIN_CPU0")
		)
		(pad "BE88" smd circle
			(at 34.98342 -6.288532 270)
			(size 0.4318 0.4318)
			(layers "F.Cu" "F.Mask" "F.Paste")
			(net "PVCCIN_CPU0")
		)
		(pad "BE90" smd circle
			(at 36.611306 -6.288532 270)
			(size 0.4318 0.4318)
			(layers "F.Cu" "F.Mask" "F.Paste")
			(net "PVCCIN_CPU0")
		)
		(pad "BF2" smd circle
			(at -36.611306 -5.928868 270)
			(size 0.4318 0.4318)
			(layers "F.Cu" "F.Mask" "F.Paste")
			(net "UPI_CPU0_CPU1_P0P1_DN<18>")
		)
		(pad "BF4" smd circle
			(at -34.98342 -5.928868 270)
			(size 0.4318 0.4318)
			(layers "F.Cu" "F.Mask" "F.Paste")
			(net "GND")
		)
		(pad "BF6" smd circle
			(at -33.355534 -5.928868 270)
			(size 0.4318 0.4318)
			(layers "F.Cu" "F.Mask" "F.Paste")
			(net "UPI_CPU1_CPU0_P1P0_DP<18>")
		)
		(pad "BF8" smd circle
			(at -31.727902 -5.928868 270)
			(size 0.4318 0.4318)
			(layers "F.Cu" "F.Mask" "F.Paste")
			(net "GND")
		)
		(pad "BF10" smd circle
			(at -30.100016 -5.928868 270)
			(size 0.4318 0.4318)
			(layers "F.Cu" "F.Mask" "F.Paste")
			(net "P5E_CPU0_PE1_RX_DN<14>")
		)
		(pad "BF12" smd circle
			(at -28.472384 -5.928868 270)
			(size 0.4318 0.4318)
			(layers "F.Cu" "F.Mask" "F.Paste")
			(net "GND")
		)
		(pad "BF14" smd circle
			(at -26.844498 -5.928868 270)
			(size 0.4318 0.4318)
			(layers "F.Cu" "F.Mask" "F.Paste")
			(net "P5E_CPU0_PE1_TX_DN<14>")
		)
		(pad "BF16" smd circle
			(at -25.216612 -5.928868 270)
			(size 0.4318 0.4318)
			(layers "F.Cu" "F.Mask" "F.Paste")
			(net "GND")
		)
		(pad "BF18" smd circle
			(at -23.58898 -5.928868 270)
			(size 0.4318 0.4318)
			(layers "F.Cu" "F.Mask" "F.Paste")
			(net "DMI_CPU0_PCH_RX_C_DN<2>")
		)
		(pad "BF20" smd circle
			(at -21.961094 -5.928868 270)
			(size 0.4318 0.4318)
			(layers "F.Cu" "F.Mask" "F.Paste")
			(net "GND")
		)
		(pad "BF22" smd circle
			(at -20.333462 -5.928868 270)
			(size 0.4318 0.4318)
			(layers "F.Cu" "F.Mask" "F.Paste")
			(net "H_CPU0_ERR0_LVC1_R_N")
		)
		(pad "BF24" smd circle
			(at -18.705576 -5.928868 270)
			(size 0.4318 0.4318)
			(layers "F.Cu" "F.Mask" "F.Paste")
			(net "TP_CPU0_IFST_TRIG_LVC1_R")
		)
		(pad "BF26" smd circle
			(at -17.07769 -5.928868 270)
			(size 0.4318 0.4318)
			(layers "F.Cu" "F.Mask" "F.Paste")
			(net "SVID_CLK1_CPU0")
		)
		(pad "BF61" smd circle
			(at 13.008356 -5.818886 270)
			(size 0.4318 0.4318)
			(layers "F.Cu" "F.Mask" "F.Paste")
			(net "GND")
		)
		(pad "BF63" smd circle
			(at 14.635988 -5.818886 270)
			(size 0.4318 0.4318)
			(layers "F.Cu" "F.Mask" "F.Paste")
			(net "GND")
		)
		(pad "BF65" smd circle
			(at 16.263874 -5.818886 270)
			(size 0.4318 0.4318)
			(layers "F.Cu" "F.Mask" "F.Paste")
			(net "TP_ESPI_IBL_CPU0_CS0_LVC1_N")
		)
		(pad "BF67" smd circle
			(at 17.89176 -5.818886 270)
			(size 0.4318 0.4318)
			(layers "F.Cu" "F.Mask" "F.Paste")
			(net "TP_TRC_CPU0_PTI2_CLK")
		)
		(pad "BF69" smd circle
			(at 19.519392 -5.818886 270)
			(size 0.4318 0.4318)
			(layers "F.Cu" "F.Mask" "F.Paste")
			(net "TP_TRC_CPU0_PTI<19>")
		)
		(pad "BF71" smd circle
			(at 21.147278 -5.818886 270)
			(size 0.4318 0.4318)
			(layers "F.Cu" "F.Mask" "F.Paste")
			(net "NC_CPU0_MDFI_DIE01_NS0")
		)
		(pad "BF73" smd circle
			(at 22.77491 -5.818886 270)
			(size 0.4318 0.4318)
			(layers "F.Cu" "F.Mask" "F.Paste")
			(net "GND")
		)
		(pad "BF75" smd circle
			(at 24.402796 -5.818886 270)
			(size 0.4318 0.4318)
			(layers "F.Cu" "F.Mask" "F.Paste")
			(net "GND")
		)
		(pad "BF77" smd circle
			(at 26.030682 -5.818886 270)
			(size 0.4318 0.4318)
			(layers "F.Cu" "F.Mask" "F.Paste")
			(net "PVCCFA_EHV_FIVRA_CPU0")
		)
		(pad "BF79" smd circle
			(at 27.658314 -5.818886 270)
			(size 0.4318 0.4318)
			(layers "F.Cu" "F.Mask" "F.Paste")
			(net "GND")
		)
		(pad "BF81" smd circle
			(at 29.2862 -5.818886 270)
			(size 0.4318 0.4318)
			(layers "F.Cu" "F.Mask" "F.Paste")
			(net "UPI_CPU0_CPU1_P2P2_DN<2>")
		)
		(pad "BF83" smd circle
			(at 30.914086 -5.818886 270)
			(size 0.4318 0.4318)
			(layers "F.Cu" "F.Mask" "F.Paste")
			(net "GND")
		)
		(pad "BF85" smd circle
			(at 32.541718 -5.818886 270)
			(size 0.4318 0.4318)
			(layers "F.Cu" "F.Mask" "F.Paste")
			(net "PVCCIN_CPU0")
		)
		(pad "BF87" smd circle
			(at 34.169604 -5.818886 270)
			(size 0.4318 0.4318)
			(layers "F.Cu" "F.Mask" "F.Paste")
			(net "PVCCIN_CPU0")
		)
		(pad "BF89" smd circle
			(at 35.797236 -5.818886 270)
			(size 0.4318 0.4318)
			(layers "F.Cu" "F.Mask" "F.Paste")
			(net "PVCCIN_CPU0")
		)
		(pad "BF91" smd oval
			(at 37.425122 -5.818886)
			(size 0.381 0.4826)
			(drill
				(offset 0 -0.0508)
			)
			(layers "F.Cu" "F.Mask" "F.Paste")
			(net "PVCCIN_CPU0")
		)
		(pad "BG1" smd oval
			(at -37.425122 -5.458714 180)
			(size 0.381 0.4826)
			(drill
				(offset 0 -0.0508)
			)
			(layers "F.Cu" "F.Mask" "F.Paste")
			(net "GND")
		)
		(pad "BG3" smd circle
			(at -35.797236 -5.458714 270)
			(size 0.4318 0.4318)
			(layers "F.Cu" "F.Mask" "F.Paste")
			(net "UPI_CPU0_CPU1_P0P1_DP<19>")
		)
		(pad "BG5" smd circle
			(at -34.169604 -5.458714 270)
			(size 0.4318 0.4318)
			(layers "F.Cu" "F.Mask" "F.Paste")
			(net "GND")
		)
		(pad "BG7" smd circle
			(at -32.541718 -5.458714 270)
			(size 0.4318 0.4318)
			(layers "F.Cu" "F.Mask" "F.Paste")
			(net "UPI_CPU1_CPU0_P1P0_DN<18>")
		)
		(pad "BG9" smd circle
			(at -30.914086 -5.458714 270)
			(size 0.4318 0.4318)
			(layers "F.Cu" "F.Mask" "F.Paste")
			(net "GND")
		)
		(pad "BG11" smd circle
			(at -29.2862 -5.458714 270)
			(size 0.4318 0.4318)
			(layers "F.Cu" "F.Mask" "F.Paste")
			(net "P5E_CPU0_PE1_RX_DN<13>")
		)
		(pad "BG13" smd circle
			(at -27.658314 -5.458714 270)
			(size 0.4318 0.4318)
			(layers "F.Cu" "F.Mask" "F.Paste")
			(net "GND")
		)
		(pad "BG15" smd circle
			(at -26.030682 -5.458714 270)
			(size 0.4318 0.4318)
			(layers "F.Cu" "F.Mask" "F.Paste")
			(net "P5E_CPU0_PE1_TX_DP<14>")
		)
		(pad "BG17" smd circle
			(at -24.402796 -5.458714 270)
			(size 0.4318 0.4318)
			(layers "F.Cu" "F.Mask" "F.Paste")
			(net "GND")
		)
		(pad "BG19" smd circle
			(at -22.77491 -5.458714 270)
			(size 0.4318 0.4318)
			(layers "F.Cu" "F.Mask" "F.Paste")
			(net "DMI_CPU0_PCH_RX_C_DP<2>")
		)
		(pad "BG21" smd circle
			(at -21.147278 -5.458714 270)
			(size 0.4318 0.4318)
			(layers "F.Cu" "F.Mask" "F.Paste")
			(net "GND")
		)
		(pad "BG23" smd circle
			(at -19.519392 -5.458714 270)
			(size 0.4318 0.4318)
			(layers "F.Cu" "F.Mask" "F.Paste")
			(net "GND")
		)
		(pad "BG25" smd circle
			(at -17.89176 -5.458714 270)
			(size 0.4318 0.4318)
			(layers "F.Cu" "F.Mask" "F.Paste")
			(net "GND")
		)
		(pad "BG60" smd circle
			(at 12.19454 -5.348732 270)
			(size 0.4318 0.4318)
			(layers "F.Cu" "F.Mask" "F.Paste")
			(net "PVCCINFAON_CPU0")
		)
		(pad "BG62" smd circle
			(at 13.822426 -5.348732 270)
			(size 0.4318 0.4318)
			(layers "F.Cu" "F.Mask" "F.Paste")
			(net "TP_CLK_66M_ESPI_IBL_CPU0_LVC1")
		)
		(pad "BG64" smd circle
			(at 15.450058 -5.348732 270)
			(size 0.4318 0.4318)
			(layers "F.Cu" "F.Mask" "F.Paste")
			(net "TP_RST_ESPI_IBL_CPU0_LVC1_N")
		)
		(pad "BG66" smd circle
			(at 17.07769 -5.348732 270)
			(size 0.4318 0.4318)
			(layers "F.Cu" "F.Mask" "F.Paste")
			(net "TP_TRC_CPU0_PTI<27>")
		)
		(pad "BG68" smd circle
			(at 18.705576 -5.348732 270)
			(size 0.4318 0.4318)
			(layers "F.Cu" "F.Mask" "F.Paste")
			(net "TP_TRC_CPU0_PTI<22>")
		)
		(pad "BG70" smd circle
			(at 20.333462 -5.348732 270)
			(size 0.4318 0.4318)
			(layers "F.Cu" "F.Mask" "F.Paste")
			(net "GND")
		)
		(pad "BG72" smd circle
			(at 21.961094 -5.348732 270)
			(size 0.4318 0.4318)
			(layers "F.Cu" "F.Mask" "F.Paste")
			(net "FM_CPU0_PROC_ID0")
		)
		(pad "BG74" smd circle
			(at 23.58898 -5.348732 270)
			(size 0.4318 0.4318)
			(layers "F.Cu" "F.Mask" "F.Paste")
			(net "UPI_CPU1_CPU0_P2P2_DP<3>")
		)
		(pad "BG76" smd circle
			(at 25.216612 -5.348732 270)
			(size 0.4318 0.4318)
			(layers "F.Cu" "F.Mask" "F.Paste")
			(net "UPI_CPU1_CPU0_P2P2_DP<6>")
		)
		(pad "BG78" smd circle
			(at 26.844498 -5.348732 270)
			(size 0.4318 0.4318)
			(layers "F.Cu" "F.Mask" "F.Paste")
			(net "NC_CPU0_HBM3_VIEWDIG0")
		)
		(pad "BG80" smd circle
			(at 28.472384 -5.348732 270)
			(size 0.4318 0.4318)
			(layers "F.Cu" "F.Mask" "F.Paste")
			(net "UPI_CPU0_CPU1_P2P2_DN<1>")
		)
		(pad "BG82" smd circle
			(at 30.100016 -5.348732 270)
			(size 0.4318 0.4318)
			(layers "F.Cu" "F.Mask" "F.Paste")
			(net "UPI_CPU0_CPU1_P2P2_DP<2>")
		)
		(pad "BG84" smd circle
			(at 31.727902 -5.348732 270)
			(size 0.4318 0.4318)
			(layers "F.Cu" "F.Mask" "F.Paste")
			(net "PVCCIN_CPU0")
		)
		(pad "BG86" smd circle
			(at 33.355534 -5.348732 270)
			(size 0.4318 0.4318)
			(layers "F.Cu" "F.Mask" "F.Paste")
			(net "PVCCIN_CPU0")
		)
		(pad "BG88" smd circle
			(at 34.98342 -5.348732 270)
			(size 0.4318 0.4318)
			(layers "F.Cu" "F.Mask" "F.Paste")
			(net "PVCCIN_CPU0")
		)
		(pad "BG90" smd circle
			(at 36.611306 -5.348732 270)
			(size 0.4318 0.4318)
			(layers "F.Cu" "F.Mask" "F.Paste")
			(net "PVCCIN_CPU0")
		)
		(pad "BH2" smd circle
			(at -36.611306 -4.989068 270)
			(size 0.4318 0.4318)
			(layers "F.Cu" "F.Mask" "F.Paste")
			(net "UPI_CPU0_CPU1_P0P1_DN<19>")
		)
		(pad "BH4" smd circle
			(at -34.98342 -4.989068 270)
			(size 0.4318 0.4318)
			(layers "F.Cu" "F.Mask" "F.Paste")
			(net "GND")
		)
		(pad "BH6" smd circle
			(at -33.355534 -4.989068 270)
			(size 0.4318 0.4318)
			(layers "F.Cu" "F.Mask" "F.Paste")
			(net "UPI_CPU1_CPU0_P1P0_DN<19>")
		)
		(pad "BH8" smd circle
			(at -31.727902 -4.989068 270)
			(size 0.4318 0.4318)
			(layers "F.Cu" "F.Mask" "F.Paste")
			(net "GND")
		)
		(pad "BH10" smd circle
			(at -30.100016 -4.989068 270)
			(size 0.4318 0.4318)
			(layers "F.Cu" "F.Mask" "F.Paste")
			(net "P5E_CPU0_PE1_RX_DP<13>")
		)
		(pad "BH12" smd circle
			(at -28.472384 -4.989068 270)
			(size 0.4318 0.4318)
			(layers "F.Cu" "F.Mask" "F.Paste")
			(net "GND")
		)
		(pad "BH14" smd circle
			(at -26.844498 -4.989068 270)
			(size 0.4318 0.4318)
			(layers "F.Cu" "F.Mask" "F.Paste")
			(net "P5E_CPU0_PE1_TX_DP<13>")
		)
		(pad "BH16" smd circle
			(at -25.216612 -4.989068 270)
			(size 0.4318 0.4318)
			(layers "F.Cu" "F.Mask" "F.Paste")
			(net "GND")
		)
		(pad "BH18" smd circle
			(at -23.58898 -4.989068 270)
			(size 0.4318 0.4318)
			(layers "F.Cu" "F.Mask" "F.Paste")
			(net "DMI_CPU0_PCH_RX_C_DN<3>")
		)
		(pad "BH20" smd circle
			(at -21.961094 -4.989068 270)
			(size 0.4318 0.4318)
			(layers "F.Cu" "F.Mask" "F.Paste")
			(net "GND")
		)
		(pad "BH22" smd circle
			(at -20.333462 -4.989068 270)
			(size 0.4318 0.4318)
			(layers "F.Cu" "F.Mask" "F.Paste")
			(net "H_CPU0_RMCA_LVC1_R_N")
		)
		(pad "BH24" smd circle
			(at -18.705576 -4.989068 270)
			(size 0.4318 0.4318)
			(layers "F.Cu" "F.Mask" "F.Paste")
			(net "PECI_CPU0_GTL_R")
		)
		(pad "BH26" smd circle
			(at -17.07769 -4.989068 270)
			(size 0.4318 0.4318)
			(layers "F.Cu" "F.Mask" "F.Paste")
			(net "SVID_CLK0_CPU0")
		)
		(pad "BH61" smd circle
			(at 13.008356 -4.879086 270)
			(size 0.4318 0.4318)
			(layers "F.Cu" "F.Mask" "F.Paste")
			(net "RST_CPU0_LVC1_N")
		)
		(pad "BH63" smd circle
			(at 14.635988 -4.879086 270)
			(size 0.4318 0.4318)
			(layers "F.Cu" "F.Mask" "F.Paste")
			(net "TP_ESPI_IBL_CPU0_OE_LVC1_N")
		)
		(pad "BH65" smd circle
			(at 16.263874 -4.879086 270)
			(size 0.4318 0.4318)
			(layers "F.Cu" "F.Mask" "F.Paste")
			(net "TP_ESPI_IBL_CPU0_CS1_N")
		)
		(pad "BH67" smd circle
			(at 17.89176 -4.879086 270)
			(size 0.4318 0.4318)
			(layers "F.Cu" "F.Mask" "F.Paste")
			(net "GND")
		)
		(pad "BH69" smd circle
			(at 19.519392 -4.879086 270)
			(size 0.4318 0.4318)
			(layers "F.Cu" "F.Mask" "F.Paste")
			(net "TP_TRC_CPU0_PTI<20>")
		)
		(pad "BH71" smd circle
			(at 21.147278 -4.879086 270)
			(size 0.4318 0.4318)
			(layers "F.Cu" "F.Mask" "F.Paste")
			(net "FM_CPU0_PROC_ID1")
		)
		(pad "BH73" smd circle
			(at 22.77491 -4.879086 270)
			(size 0.4318 0.4318)
			(layers "F.Cu" "F.Mask" "F.Paste")
			(net "GND")
		)
		(pad "BH75" smd circle
			(at 24.402796 -4.879086 270)
			(size 0.4318 0.4318)
			(layers "F.Cu" "F.Mask" "F.Paste")
			(net "UPI_CPU1_CPU0_P2P2_DN<6>")
		)
		(pad "BH77" smd circle
			(at 26.030682 -4.879086 270)
			(size 0.4318 0.4318)
			(layers "F.Cu" "F.Mask" "F.Paste")
			(net "GND")
		)
		(pad "BH79" smd circle
			(at 27.658314 -4.879086 270)
			(size 0.4318 0.4318)
			(layers "F.Cu" "F.Mask" "F.Paste")
			(net "PVCCFA_EHV_FIVRA_CPU0")
		)
		(pad "BH81" smd circle
			(at 29.2862 -4.879086 270)
			(size 0.4318 0.4318)
			(layers "F.Cu" "F.Mask" "F.Paste")
			(net "GND")
		)
		(pad "BH83" smd circle
			(at 30.914086 -4.879086 270)
			(size 0.4318 0.4318)
			(layers "F.Cu" "F.Mask" "F.Paste")
			(net "GND")
		)
		(pad "BH85" smd circle
			(at 32.541718 -4.879086 270)
			(size 0.4318 0.4318)
			(layers "F.Cu" "F.Mask" "F.Paste")
			(net "PVCCIN_CPU0")
		)
		(pad "BH87" smd circle
			(at 34.169604 -4.879086 270)
			(size 0.4318 0.4318)
			(layers "F.Cu" "F.Mask" "F.Paste")
			(net "PVCCIN_CPU0")
		)
		(pad "BH89" smd circle
			(at 35.797236 -4.879086 270)
			(size 0.4318 0.4318)
			(layers "F.Cu" "F.Mask" "F.Paste")
			(net "PVCCIN_CPU0")
		)
		(pad "BH91" smd oval
			(at 37.425122 -4.879086)
			(size 0.381 0.4826)
			(drill
				(offset 0 -0.0508)
			)
			(layers "F.Cu" "F.Mask" "F.Paste")
			(net "PVCCIN_CPU0")
		)
		(pad "BJ1" smd oval
			(at -37.425122 -4.518914 180)
			(size 0.381 0.4826)
			(drill
				(offset 0 -0.0508)
			)
			(layers "F.Cu" "F.Mask" "F.Paste")
			(net "UPI_CPU0_CPU1_P0P1_DN<20>")
		)
		(pad "BJ3" smd circle
			(at -35.797236 -4.518914 270)
			(size 0.4318 0.4318)
			(layers "F.Cu" "F.Mask" "F.Paste")
			(net "PVCCD_HV_CPU0")
		)
		(pad "BJ5" smd circle
			(at -34.169604 -4.518914 270)
			(size 0.4318 0.4318)
			(layers "F.Cu" "F.Mask" "F.Paste")
			(net "UPI_CPU1_CPU0_P1P0_DP<19>")
		)
		(pad "BJ7" smd circle
			(at -32.541718 -4.518914 270)
			(size 0.4318 0.4318)
			(layers "F.Cu" "F.Mask" "F.Paste")
			(net "PVCCD_HV_CPU0")
		)
		(pad "BJ9" smd circle
			(at -30.914086 -4.518914 270)
			(size 0.4318 0.4318)
			(layers "F.Cu" "F.Mask" "F.Paste")
			(net "P5E_CPU0_PE1_RX_DP<12>")
		)
		(pad "BJ11" smd circle
			(at -29.2862 -4.518914 270)
			(size 0.4318 0.4318)
			(layers "F.Cu" "F.Mask" "F.Paste")
			(net "PVCCD_HV_CPU0")
		)
		(pad "BJ13" smd circle
			(at -27.658314 -4.518914 270)
			(size 0.4318 0.4318)
			(layers "F.Cu" "F.Mask" "F.Paste")
			(net "P5E_CPU0_PE1_TX_DN<13>")
		)
		(pad "BJ15" smd circle
			(at -26.030682 -4.518914 270)
			(size 0.4318 0.4318)
			(layers "F.Cu" "F.Mask" "F.Paste")
			(net "PVCCINFAON_CPU0")
		)
		(pad "BJ17" smd circle
			(at -24.402796 -4.518914 270)
			(size 0.4318 0.4318)
			(layers "F.Cu" "F.Mask" "F.Paste")
			(net "DMI_CPU0_PCH_RX_C_DP<3>")
		)
		(pad "BJ19" smd circle
			(at -22.77491 -4.518914 270)
			(size 0.4318 0.4318)
			(layers "F.Cu" "F.Mask" "F.Paste")
			(net "PVNN_MAIN_CPU0")
		)
		(pad "BJ21" smd circle
			(at -21.147278 -4.518914 270)
			(size 0.4318 0.4318)
			(layers "F.Cu" "F.Mask" "F.Paste")
			(net "NC_CPU0_MDFI_DIE00_NS1")
		)
		(pad "BJ23" smd circle
			(at -19.519392 -4.518914 270)
			(size 0.4318 0.4318)
			(layers "F.Cu" "F.Mask" "F.Paste")
			(net "DBP_CPU0_HOOK8_MBP2_GTL_QS_R_N")
		)
		(pad "BJ25" smd circle
			(at -17.89176 -4.518914 270)
			(size 0.4318 0.4318)
			(layers "F.Cu" "F.Mask" "F.Paste")
			(net "SVID_ALERT1_CPU0_N")
		)
		(pad "BJ60" smd circle
			(at 12.19454 -4.408932 270)
			(size 0.4318 0.4318)
			(layers "F.Cu" "F.Mask" "F.Paste")
			(net "PVCCINFAON_CPU0")
		)
		(pad "BJ62" smd circle
			(at 13.822426 -4.408932 270)
			(size 0.4318 0.4318)
			(layers "F.Cu" "F.Mask" "F.Paste")
			(net "GND")
		)
		(pad "BJ64" smd circle
			(at 15.450058 -4.408932 270)
			(size 0.4318 0.4318)
			(layers "F.Cu" "F.Mask" "F.Paste")
			(net "TP_ESPI_IBL_CPU0_IO1_LVC1")
		)
		(pad "BJ66" smd circle
			(at 17.07769 -4.408932 270)
			(size 0.4318 0.4318)
			(layers "F.Cu" "F.Mask" "F.Paste")
			(net "TP_TRC_CPU0_PTI<28>")
		)
		(pad "BJ68" smd circle
			(at 18.705576 -4.408932 270)
			(size 0.4318 0.4318)
			(layers "F.Cu" "F.Mask" "F.Paste")
			(net "GND")
		)
		(pad "BJ70" smd circle
			(at 20.333462 -4.408932 270)
			(size 0.4318 0.4318)
			(layers "F.Cu" "F.Mask" "F.Paste")
			(net "NC_CPU0_VIEWPIN_DIE01<3>")
		)
		(pad "BJ72" smd circle
			(at 21.961094 -4.408932 270)
			(size 0.4318 0.4318)
			(layers "F.Cu" "F.Mask" "F.Paste")
			(net "PVCCFA_EHV_FIVRA_CPU0")
		)
		(pad "BJ74" smd circle
			(at 23.58898 -4.408932 270)
			(size 0.4318 0.4318)
			(layers "F.Cu" "F.Mask" "F.Paste")
			(net "UPI_CPU1_CPU0_P2P2_DN<3>")
		)
		(pad "BJ76" smd circle
			(at 25.216612 -4.408932 270)
			(size 0.4318 0.4318)
			(layers "F.Cu" "F.Mask" "F.Paste")
			(net "UPI_CPU1_CPU0_P2P2_DN<5>")
		)
		(pad "BJ78" smd circle
			(at 26.844498 -4.408932 270)
			(size 0.4318 0.4318)
			(layers "F.Cu" "F.Mask" "F.Paste")
			(net "PVCCFA_EHV_FIVRA_CPU0")
		)
		(pad "BJ80" smd circle
			(at 28.472384 -4.408932 270)
			(size 0.4318 0.4318)
			(layers "F.Cu" "F.Mask" "F.Paste")
			(net "GND")
		)
		(pad "BJ82" smd circle
			(at 30.100016 -4.408932 270)
			(size 0.4318 0.4318)
			(layers "F.Cu" "F.Mask" "F.Paste")
			(net "GND")
		)
		(pad "BJ84" smd circle
			(at 31.727902 -4.408932 270)
			(size 0.4318 0.4318)
			(layers "F.Cu" "F.Mask" "F.Paste")
			(net "GND")
		)
		(pad "BJ86" smd circle
			(at 33.355534 -4.408932 270)
			(size 0.4318 0.4318)
			(layers "F.Cu" "F.Mask" "F.Paste")
			(net "GND")
		)
		(pad "BJ88" smd circle
			(at 34.98342 -4.408932 270)
			(size 0.4318 0.4318)
			(layers "F.Cu" "F.Mask" "F.Paste")
			(net "GND")
		)
		(pad "BJ90" smd circle
			(at 36.611306 -4.408932 270)
			(size 0.4318 0.4318)
			(layers "F.Cu" "F.Mask" "F.Paste")
			(net "GND")
		)
		(pad "BK2" smd circle
			(at -36.611306 -4.049268 270)
			(size 0.4318 0.4318)
			(layers "F.Cu" "F.Mask" "F.Paste")
			(net "UPI_CPU0_CPU1_P0P1_DP<20>")
		)
		(pad "BK4" smd circle
			(at -34.98342 -4.049268 270)
			(size 0.4318 0.4318)
			(layers "F.Cu" "F.Mask" "F.Paste")
			(net "GND")
		)
		(pad "BK6" smd circle
			(at -33.355534 -4.049268 270)
			(size 0.4318 0.4318)
			(layers "F.Cu" "F.Mask" "F.Paste")
			(net "UPI_CPU1_CPU0_P1P0_DP<20>")
		)
		(pad "BK8" smd circle
			(at -31.727902 -4.049268 270)
			(size 0.4318 0.4318)
			(layers "F.Cu" "F.Mask" "F.Paste")
			(net "GND")
		)
		(pad "BK10" smd circle
			(at -30.100016 -4.049268 270)
			(size 0.4318 0.4318)
			(layers "F.Cu" "F.Mask" "F.Paste")
			(net "P5E_CPU0_PE1_RX_DN<12>")
		)
		(pad "BK12" smd circle
			(at -28.472384 -4.049268 270)
			(size 0.4318 0.4318)
			(layers "F.Cu" "F.Mask" "F.Paste")
			(net "GND")
		)
		(pad "BK14" smd circle
			(at -26.844498 -4.049268 270)
			(size 0.4318 0.4318)
			(layers "F.Cu" "F.Mask" "F.Paste")
			(net "P5E_CPU0_PE1_TX_DN<12>")
		)
		(pad "BK16" smd circle
			(at -25.216612 -4.049268 270)
			(size 0.4318 0.4318)
			(layers "F.Cu" "F.Mask" "F.Paste")
			(net "GND")
		)
		(pad "BK18" smd circle
			(at -23.58898 -4.049268 270)
			(size 0.4318 0.4318)
			(layers "F.Cu" "F.Mask" "F.Paste")
			(net "DMI_CPU0_PCH_RX_C_DP<4>")
		)
		(pad "BK20" smd circle
			(at -21.961094 -4.049268 270)
			(size 0.4318 0.4318)
			(layers "F.Cu" "F.Mask" "F.Paste")
			(net "GND")
		)
		(pad "BK22" smd circle
			(at -20.333462 -4.049268 270)
			(size 0.4318 0.4318)
			(layers "F.Cu" "F.Mask" "F.Paste")
			(net "NC_CPU0_MDFI_DIE00_NS0")
		)
		(pad "BK24" smd circle
			(at -18.705576 -4.049268 270)
			(size 0.4318 0.4318)
			(layers "F.Cu" "F.Mask" "F.Paste")
			(net "DBP_CPU0_HOOK9_MBP3_GTL_QS_R_N")
		)
		(pad "BK26" smd circle
			(at -17.07769 -4.049268 270)
			(size 0.4318 0.4318)
			(layers "F.Cu" "F.Mask" "F.Paste")
			(net "SVID_ALERT0_CPU0_N")
		)
		(pad "BK61" smd circle
			(at 13.008356 -3.939286 270)
			(size 0.4318 0.4318)
			(layers "F.Cu" "F.Mask" "F.Paste")
			(net "PVCCINFAON_CPU0")
		)
		(pad "BK63" smd circle
			(at 14.635988 -3.939286 270)
			(size 0.4318 0.4318)
			(layers "F.Cu" "F.Mask" "F.Paste")
			(net "TP_ESPI_IBL_CPU0_IO0_LVC1")
		)
		(pad "BK65" smd circle
			(at 16.263874 -3.939286 270)
			(size 0.4318 0.4318)
			(layers "F.Cu" "F.Mask" "F.Paste")
			(net "GND")
		)
		(pad "BK67" smd circle
			(at 17.89176 -3.939286 270)
			(size 0.4318 0.4318)
			(layers "F.Cu" "F.Mask" "F.Paste")
			(net "TP_TRC_CPU0_PTI3_CLK")
		)
		(pad "BK69" smd circle
			(at 19.519392 -3.939286 270)
			(size 0.4318 0.4318)
			(layers "F.Cu" "F.Mask" "F.Paste")
			(net "TP_TRC_CPU0_PTI<24>")
		)
		(pad "BK71" smd circle
			(at 21.147278 -3.939286 270)
			(size 0.4318 0.4318)
			(layers "F.Cu" "F.Mask" "F.Paste")
			(net "GND")
		)
		(pad "BK73" smd circle
			(at 22.77491 -3.939286 270)
			(size 0.4318 0.4318)
			(layers "F.Cu" "F.Mask" "F.Paste")
			(net "UPI_CPU1_CPU0_P2P2_DN<1>")
		)
		(pad "BK75" smd circle
			(at 24.402796 -3.939286 270)
			(size 0.4318 0.4318)
			(layers "F.Cu" "F.Mask" "F.Paste")
			(net "GND")
		)
		(pad "BK77" smd circle
			(at 26.030682 -3.939286 270)
			(size 0.4318 0.4318)
			(layers "F.Cu" "F.Mask" "F.Paste")
			(net "UPI_CPU1_CPU0_P2P2_DP<5>")
		)
		(pad "BK79" smd circle
			(at 27.658314 -3.939286 270)
			(size 0.4318 0.4318)
			(layers "F.Cu" "F.Mask" "F.Paste")
			(net "GND")
		)
		(pad "BK81" smd circle
			(at 29.2862 -3.939286 270)
			(size 0.4318 0.4318)
			(layers "F.Cu" "F.Mask" "F.Paste")
			(net "PVCCIN_CPU0")
		)
		(pad "BK83" smd circle
			(at 30.914086 -3.939286 270)
			(size 0.4318 0.4318)
			(layers "F.Cu" "F.Mask" "F.Paste")
			(net "PVCCIN_CPU0")
		)
		(pad "BK85" smd circle
			(at 32.541718 -3.939286 270)
			(size 0.4318 0.4318)
			(layers "F.Cu" "F.Mask" "F.Paste")
			(net "PVCCIN_CPU0")
		)
		(pad "BK87" smd circle
			(at 34.169604 -3.939286 270)
			(size 0.4318 0.4318)
			(layers "F.Cu" "F.Mask" "F.Paste")
			(net "PVCCIN_CPU0")
		)
		(pad "BK89" smd circle
			(at 35.797236 -3.939286 270)
			(size 0.4318 0.4318)
			(layers "F.Cu" "F.Mask" "F.Paste")
			(net "PVCCIN_CPU0")
		)
		(pad "BK91" smd oval
			(at 37.425122 -3.939286)
			(size 0.381 0.4826)
			(drill
				(offset 0 -0.0508)
			)
			(layers "F.Cu" "F.Mask" "F.Paste")
			(net "PVCCIN_CPU0")
		)
		(pad "BL1" smd oval
			(at -37.425122 -3.579114 180)
			(size 0.381 0.4826)
			(drill
				(offset 0 -0.0508)
			)
			(layers "F.Cu" "F.Mask" "F.Paste")
			(net "GND")
		)
		(pad "BL3" smd circle
			(at -35.797236 -3.579114 270)
			(size 0.4318 0.4318)
			(layers "F.Cu" "F.Mask" "F.Paste")
			(net "UPI_CPU0_CPU1_P0P1_DN<21>")
		)
		(pad "BL5" smd circle
			(at -34.169604 -3.579114 270)
			(size 0.4318 0.4318)
			(layers "F.Cu" "F.Mask" "F.Paste")
			(net "GND")
		)
		(pad "BL7" smd circle
			(at -32.541718 -3.579114 270)
			(size 0.4318 0.4318)
			(layers "F.Cu" "F.Mask" "F.Paste")
			(net "UPI_CPU1_CPU0_P1P0_DN<20>")
		)
		(pad "BL9" smd circle
			(at -30.914086 -3.579114 270)
			(size 0.4318 0.4318)
			(layers "F.Cu" "F.Mask" "F.Paste")
			(net "GND")
		)
		(pad "BL11" smd circle
			(at -29.2862 -3.579114 270)
			(size 0.4318 0.4318)
			(layers "F.Cu" "F.Mask" "F.Paste")
			(net "P5E_CPU0_PE1_RX_DN<11>")
		)
		(pad "BL13" smd circle
			(at -27.658314 -3.579114 270)
			(size 0.4318 0.4318)
			(layers "F.Cu" "F.Mask" "F.Paste")
			(net "GND")
		)
		(pad "BL15" smd circle
			(at -26.030682 -3.579114 270)
			(size 0.4318 0.4318)
			(layers "F.Cu" "F.Mask" "F.Paste")
			(net "P5E_CPU0_PE1_TX_DP<12>")
		)
		(pad "BL17" smd circle
			(at -24.402796 -3.579114 270)
			(size 0.4318 0.4318)
			(layers "F.Cu" "F.Mask" "F.Paste")
			(net "GND")
		)
		(pad "BL19" smd circle
			(at -22.77491 -3.579114 270)
			(size 0.4318 0.4318)
			(layers "F.Cu" "F.Mask" "F.Paste")
			(net "DMI_CPU0_PCH_RX_C_DN<4>")
		)
		(pad "BL21" smd circle
			(at -21.147278 -3.579114 270)
			(size 0.4318 0.4318)
			(layers "F.Cu" "F.Mask" "F.Paste")
			(net "NC_CPU0_PE0_APROBE<1>")
		)
		(pad "BL23" smd circle
			(at -19.519392 -3.579114 270)
			(size 0.4318 0.4318)
			(layers "F.Cu" "F.Mask" "F.Paste")
			(net "DBP_CPU0_MBP0_GTL_R_N")
		)
		(pad "BL25" smd circle
			(at -17.89176 -3.579114 270)
			(size 0.4318 0.4318)
			(layers "F.Cu" "F.Mask" "F.Paste")
			(net "SVID_DIO1_CPU0")
		)
		(pad "BL60" smd circle
			(at 12.19454 -3.469132 270)
			(size 0.4318 0.4318)
			(layers "F.Cu" "F.Mask" "F.Paste")
			(net "NC_CPU0_HBM3_VIEWDIG1")
		)
		(pad "BL62" smd circle
			(at 13.822426 -3.469132 270)
			(size 0.4318 0.4318)
			(layers "F.Cu" "F.Mask" "F.Paste")
			(net "H_CPU0_THERMTRIP_LVC1_R_N")
		)
		(pad "BL64" smd circle
			(at 15.450058 -3.469132 270)
			(size 0.4318 0.4318)
			(layers "F.Cu" "F.Mask" "F.Paste")
			(net "FM_CPU0_PKGID0")
		)
		(pad "BL66" smd circle
			(at 17.07769 -3.469132 270)
			(size 0.4318 0.4318)
			(layers "F.Cu" "F.Mask" "F.Paste")
			(net "TP_TRC_CPU0_PTI<29>")
		)
		(pad "BL68" smd circle
			(at 18.705576 -3.469132 270)
			(size 0.4318 0.4318)
			(layers "F.Cu" "F.Mask" "F.Paste")
			(net "GND")
		)
		(pad "BL70" smd circle
			(at 20.333462 -3.469132 270)
			(size 0.4318 0.4318)
			(layers "F.Cu" "F.Mask" "F.Paste")
			(net "GND")
		)
		(pad "BL72" smd circle
			(at 21.961094 -3.469132 270)
			(size 0.4318 0.4318)
			(layers "F.Cu" "F.Mask" "F.Paste")
			(net "GND")
		)
		(pad "BL74" smd circle
			(at 23.58898 -3.469132 270)
			(size 0.4318 0.4318)
			(layers "F.Cu" "F.Mask" "F.Paste")
			(net "UPI_CPU1_CPU0_P2P2_DP<1>")
		)
		(pad "BL76" smd circle
			(at 25.216612 -3.469132 270)
			(size 0.4318 0.4318)
			(layers "F.Cu" "F.Mask" "F.Paste")
			(net "UPI_CPU1_CPU0_P2P2_DP<4>")
		)
		(pad "BL78" smd circle
			(at 26.844498 -3.469132 270)
			(size 0.4318 0.4318)
			(layers "F.Cu" "F.Mask" "F.Paste")
			(net "GND")
		)
		(pad "BL80" smd circle
			(at 28.472384 -3.469132 270)
			(size 0.4318 0.4318)
			(layers "F.Cu" "F.Mask" "F.Paste")
			(net "PVCCIN_CPU0")
		)
		(pad "BL82" smd circle
			(at 30.100016 -3.469132 270)
			(size 0.4318 0.4318)
			(layers "F.Cu" "F.Mask" "F.Paste")
			(net "PVCCIN_CPU0")
		)
		(pad "BL84" smd circle
			(at 31.727902 -3.469132 270)
			(size 0.4318 0.4318)
			(layers "F.Cu" "F.Mask" "F.Paste")
			(net "PVCCIN_CPU0")
		)
		(pad "BL86" smd circle
			(at 33.355534 -3.469132 270)
			(size 0.4318 0.4318)
			(layers "F.Cu" "F.Mask" "F.Paste")
			(net "PVCCIN_CPU0")
		)
		(pad "BL88" smd circle
			(at 34.98342 -3.469132 270)
			(size 0.4318 0.4318)
			(layers "F.Cu" "F.Mask" "F.Paste")
			(net "PVCCIN_CPU0")
		)
		(pad "BL90" smd circle
			(at 36.611306 -3.469132 270)
			(size 0.4318 0.4318)
			(layers "F.Cu" "F.Mask" "F.Paste")
			(net "PVCCIN_CPU0")
		)
		(pad "BM2" smd oval
			(at -36.611306 -3.109468 180)
			(size 0.381 0.4826)
			(drill
				(offset 0 -0.0508)
			)
			(layers "F.Cu" "F.Mask" "F.Paste")
			(net "UPI_CPU0_CPU1_P0P1_DP<21>")
		)
		(pad "BM4" smd circle
			(at -34.98342 -3.109468 270)
			(size 0.4318 0.4318)
			(layers "F.Cu" "F.Mask" "F.Paste")
			(net "GND")
		)
		(pad "BM6" smd circle
			(at -33.355534 -3.109468 270)
			(size 0.4318 0.4318)
			(layers "F.Cu" "F.Mask" "F.Paste")
			(net "UPI_CPU1_CPU0_P1P0_DN<21>")
		)
		(pad "BM8" smd circle
			(at -31.727902 -3.109468 270)
			(size 0.4318 0.4318)
			(layers "F.Cu" "F.Mask" "F.Paste")
			(net "GND")
		)
		(pad "BM10" smd circle
			(at -30.100016 -3.109468 270)
			(size 0.4318 0.4318)
			(layers "F.Cu" "F.Mask" "F.Paste")
			(net "P5E_CPU0_PE1_RX_DP<11>")
		)
		(pad "BM12" smd circle
			(at -28.472384 -3.109468 270)
			(size 0.4318 0.4318)
			(layers "F.Cu" "F.Mask" "F.Paste")
			(net "GND")
		)
		(pad "BM14" smd circle
			(at -26.844498 -3.109468 270)
			(size 0.4318 0.4318)
			(layers "F.Cu" "F.Mask" "F.Paste")
			(net "P5E_CPU0_PE1_TX_DP<11>")
		)
		(pad "BM16" smd circle
			(at -25.216612 -3.109468 270)
			(size 0.4318 0.4318)
			(layers "F.Cu" "F.Mask" "F.Paste")
			(net "GND")
		)
		(pad "BM18" smd circle
			(at -23.58898 -3.109468 270)
			(size 0.4318 0.4318)
			(layers "F.Cu" "F.Mask" "F.Paste")
			(net "DMI_CPU0_PCH_RX_C_DN<5>")
		)
		(pad "BM20" smd circle
			(at -21.961094 -3.109468 270)
			(size 0.4318 0.4318)
			(layers "F.Cu" "F.Mask" "F.Paste")
			(net "GND")
		)
		(pad "BM22" smd circle
			(at -20.333462 -3.109468 270)
			(size 0.4318 0.4318)
			(layers "F.Cu" "F.Mask" "F.Paste")
			(net "GND")
		)
		(pad "BM24" smd circle
			(at -18.705576 -3.109468 270)
			(size 0.4318 0.4318)
			(layers "F.Cu" "F.Mask" "F.Paste")
			(net "GND")
		)
		(pad "BM26" smd circle
			(at -17.07769 -3.109468 270)
			(size 0.4318 0.4318)
			(layers "F.Cu" "F.Mask" "F.Paste")
			(net "GND")
		)
		(pad "BM61" smd circle
			(at 13.008356 -2.999486 270)
			(size 0.4318 0.4318)
			(layers "F.Cu" "F.Mask" "F.Paste")
			(net "GND")
		)
		(pad "BM63" smd circle
			(at 14.635988 -2.999486 270)
			(size 0.4318 0.4318)
			(layers "F.Cu" "F.Mask" "F.Paste")
			(net "TP_ESPI_IBL_CPU0_IO3_LVC1")
		)
		(pad "BM65" smd circle
			(at 16.263874 -2.999486 270)
			(size 0.4318 0.4318)
			(layers "F.Cu" "F.Mask" "F.Paste")
			(net "NC_CPU0_SOC_SPARE1")
		)
		(pad "BM67" smd circle
			(at 17.89176 -2.999486 270)
			(size 0.4318 0.4318)
			(layers "F.Cu" "F.Mask" "F.Paste")
			(net "TP_TRC_CPU0_PTI<30>")
		)
		(pad "BM69" smd circle
			(at 19.519392 -2.999486 270)
			(size 0.4318 0.4318)
			(layers "F.Cu" "F.Mask" "F.Paste")
			(net "TP_TRC_CPU0_PTI<25>")
		)
		(pad "BM71" smd circle
			(at 21.147278 -2.999486 270)
			(size 0.4318 0.4318)
			(layers "F.Cu" "F.Mask" "F.Paste")
			(net "UPI_CPU0_CPU1_P2P2_DN<0>")
		)
		(pad "BM73" smd circle
			(at 22.77491 -2.999486 270)
			(size 0.4318 0.4318)
			(layers "F.Cu" "F.Mask" "F.Paste")
			(net "GND")
		)
		(pad "BM75" smd circle
			(at 24.402796 -2.999486 270)
			(size 0.4318 0.4318)
			(layers "F.Cu" "F.Mask" "F.Paste")
			(net "UPI_CPU1_CPU0_P2P2_DN<2>")
		)
		(pad "BM77" smd circle
			(at 26.030682 -2.999486 270)
			(size 0.4318 0.4318)
			(layers "F.Cu" "F.Mask" "F.Paste")
			(net "GND")
		)
		(pad "BM79" smd circle
			(at 27.658314 -2.999486 270)
			(size 0.4318 0.4318)
			(layers "F.Cu" "F.Mask" "F.Paste")
			(net "PVCCIN_CPU0")
		)
		(pad "BM81" smd circle
			(at 29.2862 -2.999486 270)
			(size 0.4318 0.4318)
			(layers "F.Cu" "F.Mask" "F.Paste")
			(net "PVCCIN_CPU0")
		)
		(pad "BM83" smd circle
			(at 30.914086 -2.999486 270)
			(size 0.4318 0.4318)
			(layers "F.Cu" "F.Mask" "F.Paste")
			(net "PVCCIN_CPU0")
		)
		(pad "BM85" smd circle
			(at 32.541718 -2.999486 270)
			(size 0.4318 0.4318)
			(layers "F.Cu" "F.Mask" "F.Paste")
			(net "PVCCIN_CPU0")
		)
		(pad "BM87" smd circle
			(at 34.169604 -2.999486 270)
			(size 0.4318 0.4318)
			(layers "F.Cu" "F.Mask" "F.Paste")
			(net "PVCCIN_CPU0")
		)
		(pad "BM89" smd circle
			(at 35.797236 -2.999486 270)
			(size 0.4318 0.4318)
			(layers "F.Cu" "F.Mask" "F.Paste")
			(net "PVCCIN_CPU0")
		)
		(pad "BM91" smd oval
			(at 37.425122 -2.999486)
			(size 0.381 0.4826)
			(drill
				(offset 0 -0.0508)
			)
			(layers "F.Cu" "F.Mask" "F.Paste")
			(net "PVCCIN_CPU0")
		)
		(pad "BN3" smd circle
			(at -35.797236 -2.639314 270)
			(size 0.4318 0.4318)
			(layers "F.Cu" "F.Mask" "F.Paste")
			(net "UPI_CPU0_CPU1_P0P1_DN<22>")
		)
		(pad "BN5" smd circle
			(at -34.169604 -2.639314 270)
			(size 0.4318 0.4318)
			(layers "F.Cu" "F.Mask" "F.Paste")
			(net "UPI_CPU1_CPU0_P1P0_DP<21>")
		)
		(pad "BN7" smd circle
			(at -32.541718 -2.639314 270)
			(size 0.4318 0.4318)
			(layers "F.Cu" "F.Mask" "F.Paste")
			(net "PVCCD_HV_CPU0")
		)
		(pad "BN9" smd circle
			(at -30.914086 -2.639314 270)
			(size 0.4318 0.4318)
			(layers "F.Cu" "F.Mask" "F.Paste")
			(net "P5E_CPU0_PE1_RX_DP<10>")
		)
		(pad "BN11" smd circle
			(at -29.2862 -2.639314 270)
			(size 0.4318 0.4318)
			(layers "F.Cu" "F.Mask" "F.Paste")
			(net "VSENSE_PVCCD_HV_CPU0_DN")
		)
		(pad "BN13" smd circle
			(at -27.658314 -2.639314 270)
			(size 0.4318 0.4318)
			(layers "F.Cu" "F.Mask" "F.Paste")
			(net "P5E_CPU0_PE1_TX_DN<11>")
		)
		(pad "BN15" smd circle
			(at -26.030682 -2.639314 270)
			(size 0.4318 0.4318)
			(layers "F.Cu" "F.Mask" "F.Paste")
			(net "PVCCINFAON_CPU0")
		)
		(pad "BN17" smd circle
			(at -24.402796 -2.639314 270)
			(size 0.4318 0.4318)
			(layers "F.Cu" "F.Mask" "F.Paste")
			(net "DMI_CPU0_PCH_RX_C_DP<5>")
		)
		(pad "BN19" smd circle
			(at -22.77491 -2.639314 270)
			(size 0.4318 0.4318)
			(layers "F.Cu" "F.Mask" "F.Paste")
			(net "PVNN_MAIN_CPU0")
		)
		(pad "BN21" smd circle
			(at -21.147278 -2.639314 270)
			(size 0.4318 0.4318)
			(layers "F.Cu" "F.Mask" "F.Paste")
			(net "NC_CPU0_PE0_APROBE<0>")
		)
		(pad "BN23" smd circle
			(at -19.519392 -2.639314 270)
			(size 0.4318 0.4318)
			(layers "F.Cu" "F.Mask" "F.Paste")
			(net "H_CPU0_BMCINIT_LVC1")
		)
		(pad "BN25" smd circle
			(at -17.89176 -2.639314 270)
			(size 0.4318 0.4318)
			(layers "F.Cu" "F.Mask" "F.Paste")
			(net "DBP_CPU0_MBP1_GTL_R_N")
		)
		(pad "BN27" smd circle
			(at -16.263874 -2.639314 270)
			(size 0.4318 0.4318)
			(layers "F.Cu" "F.Mask" "F.Paste")
			(net "TP_TRC_CPU0_PTI<12>")
		)
		(pad "BN29" smd circle
			(at -14.635988 -2.639314 270)
			(size 0.4318 0.4318)
			(layers "F.Cu" "F.Mask" "F.Paste")
			(net "TP_TRC_CPU0_PTI<14>")
		)
		(pad "BN31" smd circle
			(at -13.008356 -2.639314 270)
			(size 0.4318 0.4318)
			(layers "F.Cu" "F.Mask" "F.Paste")
			(net "GND")
		)
		(pad "BN33" smd circle
			(at -11.380724 -2.639314 270)
			(size 0.4318 0.4318)
			(layers "F.Cu" "F.Mask" "F.Paste")
			(net "PVCCIN_CPU0")
		)
		(pad "BN35" smd circle
			(at -9.752838 -2.639314 270)
			(size 0.4318 0.4318)
			(layers "F.Cu" "F.Mask" "F.Paste")
			(net "PVCCIN_CPU0")
		)
		(pad "BN37" smd circle
			(at -8.124952 -2.639314 270)
			(size 0.4318 0.4318)
			(layers "F.Cu" "F.Mask" "F.Paste")
			(net "PVCCIN_CPU0")
		)
		(pad "BN39" smd circle
			(at -6.49732 -2.639314 270)
			(size 0.4318 0.4318)
			(layers "F.Cu" "F.Mask" "F.Paste")
			(net "PVCCIN_CPU0")
		)
		(pad "BN41" smd circle
			(at -4.869434 -2.639314 270)
			(size 0.4318 0.4318)
			(layers "F.Cu" "F.Mask" "F.Paste")
			(net "PVCCIN_CPU0")
		)
		(pad "BN43" smd circle
			(at -3.241802 -2.639314 270)
			(size 0.4318 0.4318)
			(layers "F.Cu" "F.Mask" "F.Paste")
			(net "PVCCIN_CPU0")
		)
		(pad "BN45" smd circle
			(at -1.613916 -2.639314 270)
			(size 0.4318 0.4318)
			(layers "F.Cu" "F.Mask" "F.Paste")
			(net "PVCCIN_CPU0")
		)
		(pad "BN48" smd circle
			(at 2.427732 -2.529586 270)
			(size 0.4318 0.4318)
			(layers "F.Cu" "F.Mask" "F.Paste")
			(net "PVCCIN_CPU0")
		)
		(pad "BN50" smd circle
			(at 4.055618 -2.529586 270)
			(size 0.4318 0.4318)
			(layers "F.Cu" "F.Mask" "F.Paste")
			(net "PVCCIN_CPU0")
		)
		(pad "BN52" smd circle
			(at 5.68325 -2.529586 270)
			(size 0.4318 0.4318)
			(layers "F.Cu" "F.Mask" "F.Paste")
			(net "PVCCIN_CPU0")
		)
		(pad "BN54" smd circle
			(at 7.311136 -2.529586 270)
			(size 0.4318 0.4318)
			(layers "F.Cu" "F.Mask" "F.Paste")
			(net "PVCCIN_CPU0")
		)
		(pad "BN56" smd circle
			(at 8.939022 -2.529586 270)
			(size 0.4318 0.4318)
			(layers "F.Cu" "F.Mask" "F.Paste")
			(net "PVCCIN_CPU0")
		)
		(pad "BN58" smd circle
			(at 10.566654 -2.529586 270)
			(size 0.4318 0.4318)
			(layers "F.Cu" "F.Mask" "F.Paste")
			(net "PVCCIN_CPU0")
		)
		(pad "BN60" smd circle
			(at 12.19454 -2.529586 270)
			(size 0.4318 0.4318)
			(layers "F.Cu" "F.Mask" "F.Paste")
			(net "PVCCIN_CPU0")
		)
		(pad "BN62" smd circle
			(at 13.822426 -2.529586 270)
			(size 0.4318 0.4318)
			(layers "F.Cu" "F.Mask" "F.Paste")
			(net "GND")
		)
		(pad "BN64" smd circle
			(at 15.450058 -2.529586 270)
			(size 0.4318 0.4318)
			(layers "F.Cu" "F.Mask" "F.Paste")
			(net "FM_CPU0_PKGID2")
		)
		(pad "BN66" smd circle
			(at 17.07769 -2.529586 270)
			(size 0.4318 0.4318)
			(layers "F.Cu" "F.Mask" "F.Paste")
			(net "TP_TRC_CPU0_PTI<31>")
		)
		(pad "BN68" smd circle
			(at 18.705576 -2.529586 270)
			(size 0.4318 0.4318)
			(layers "F.Cu" "F.Mask" "F.Paste")
			(net "TP_TRC_CPU0_PTI<26>")
		)
		(pad "BN70" smd circle
			(at 20.333462 -2.529586 270)
			(size 0.4318 0.4318)
			(layers "F.Cu" "F.Mask" "F.Paste")
			(net "GND")
		)
		(pad "BN72" smd circle
			(at 21.961094 -2.529586 270)
			(size 0.4318 0.4318)
			(layers "F.Cu" "F.Mask" "F.Paste")
			(net "UPI_CPU0_CPU1_P2P2_DP<0>")
		)
		(pad "BN74" smd circle
			(at 23.58898 -2.529586 270)
			(size 0.4318 0.4318)
			(layers "F.Cu" "F.Mask" "F.Paste")
			(net "UPI_CPU1_CPU0_P2P2_DP<2>")
		)
		(pad "BN76" smd circle
			(at 25.216612 -2.529586 270)
			(size 0.4318 0.4318)
			(layers "F.Cu" "F.Mask" "F.Paste")
			(net "UPI_CPU1_CPU0_P2P2_DN<4>")
		)
		(pad "BN78" smd circle
			(at 26.844498 -2.529586 270)
			(size 0.4318 0.4318)
			(layers "F.Cu" "F.Mask" "F.Paste")
			(net "PVCCIN_CPU0")
		)
		(pad "BN80" smd circle
			(at 28.472384 -2.529586 270)
			(size 0.4318 0.4318)
			(layers "F.Cu" "F.Mask" "F.Paste")
			(net "PVCCIN_CPU0")
		)
		(pad "BN82" smd circle
			(at 30.100016 -2.529586 270)
			(size 0.4318 0.4318)
			(layers "F.Cu" "F.Mask" "F.Paste")
			(net "PVCCIN_CPU0")
		)
		(pad "BN84" smd circle
			(at 31.727902 -2.529586 270)
			(size 0.4318 0.4318)
			(layers "F.Cu" "F.Mask" "F.Paste")
			(net "PVCCIN_CPU0")
		)
		(pad "BN86" smd circle
			(at 33.355534 -2.529586 270)
			(size 0.4318 0.4318)
			(layers "F.Cu" "F.Mask" "F.Paste")
			(net "PVCCIN_CPU0")
		)
		(pad "BN88" smd circle
			(at 34.98342 -2.529586 270)
			(size 0.4318 0.4318)
			(layers "F.Cu" "F.Mask" "F.Paste")
			(net "PVCCIN_CPU0")
		)
		(pad "BN90" smd oval
			(at 36.611306 -2.529586)
			(size 0.381 0.4826)
			(drill
				(offset 0 -0.0508)
			)
			(layers "F.Cu" "F.Mask" "F.Paste")
			(net "PVCCIN_CPU0")
		)
		(pad "BP2" smd oval
			(at -36.611306 -2.169668 180)
			(size 0.381 0.4826)
			(drill
				(offset 0 -0.0508)
			)
			(layers "F.Cu" "F.Mask" "F.Paste")
			(net "GND")
		)
		(pad "BP4" smd circle
			(at -34.98342 -2.169668 270)
			(size 0.4318 0.4318)
			(layers "F.Cu" "F.Mask" "F.Paste")
			(net "GND")
		)
		(pad "BP6" smd circle
			(at -33.355534 -2.169668 270)
			(size 0.4318 0.4318)
			(layers "F.Cu" "F.Mask" "F.Paste")
			(net "UPI_CPU1_CPU0_P1P0_DP<22>")
		)
		(pad "BP8" smd circle
			(at -31.727902 -2.169668 270)
			(size 0.4318 0.4318)
			(layers "F.Cu" "F.Mask" "F.Paste")
			(net "GND")
		)
		(pad "BP10" smd circle
			(at -30.100016 -2.169668 270)
			(size 0.4318 0.4318)
			(layers "F.Cu" "F.Mask" "F.Paste")
			(net "P5E_CPU0_PE1_RX_DN<10>")
		)
		(pad "BP12" smd circle
			(at -28.472384 -2.169668 270)
			(size 0.4318 0.4318)
			(layers "F.Cu" "F.Mask" "F.Paste")
			(net "GND")
		)
		(pad "BP14" smd circle
			(at -26.844498 -2.169668 270)
			(size 0.4318 0.4318)
			(layers "F.Cu" "F.Mask" "F.Paste")
			(net "P5E_CPU0_PE1_TX_DN<10>")
		)
		(pad "BP16" smd circle
			(at -25.216612 -2.169668 270)
			(size 0.4318 0.4318)
			(layers "F.Cu" "F.Mask" "F.Paste")
			(net "GND")
		)
		(pad "BP18" smd circle
			(at -23.58898 -2.169668 270)
			(size 0.4318 0.4318)
			(layers "F.Cu" "F.Mask" "F.Paste")
			(net "DMI_CPU0_PCH_RX_C_DP<6>")
		)
		(pad "BP20" smd circle
			(at -21.961094 -2.169668 270)
			(size 0.4318 0.4318)
			(layers "F.Cu" "F.Mask" "F.Paste")
			(net "GND")
		)
		(pad "BP22" smd circle
			(at -20.333462 -2.169668 270)
			(size 0.4318 0.4318)
			(layers "F.Cu" "F.Mask" "F.Paste")
			(net "NC_CPU0_MDFI_DIE00_EW0")
		)
		(pad "BP24" smd circle
			(at -18.705576 -2.169668 270)
			(size 0.4318 0.4318)
			(layers "F.Cu" "F.Mask" "F.Paste")
			(net "H_CPU0_CATERR_LVC1_R_N")
		)
		(pad "BP26" smd circle
			(at -17.07769 -2.169668 270)
			(size 0.4318 0.4318)
			(layers "F.Cu" "F.Mask" "F.Paste")
			(net "H_CPU0_PRDY_QS_GTL_R_N")
		)
		(pad "BP28" smd circle
			(at -15.450058 -2.169668 270)
			(size 0.4318 0.4318)
			(layers "F.Cu" "F.Mask" "F.Paste")
			(net "TP_TRC_CPU0_PTI<13>")
		)
		(pad "BP30" smd circle
			(at -13.822426 -2.169668 270)
			(size 0.4318 0.4318)
			(layers "F.Cu" "F.Mask" "F.Paste")
			(net "TP_TRC_CPU0_PTI<15>")
		)
		(pad "BP32" smd circle
			(at -12.19454 -2.169668 270)
			(size 0.4318 0.4318)
			(layers "F.Cu" "F.Mask" "F.Paste")
			(net "PVCCIN_CPU0")
		)
		(pad "BP34" smd circle
			(at -10.566654 -2.169668 270)
			(size 0.4318 0.4318)
			(layers "F.Cu" "F.Mask" "F.Paste")
			(net "PVCCIN_CPU0")
		)
		(pad "BP36" smd circle
			(at -8.939022 -2.169668 270)
			(size 0.4318 0.4318)
			(layers "F.Cu" "F.Mask" "F.Paste")
			(net "PVCCIN_CPU0")
		)
		(pad "BP38" smd circle
			(at -7.311136 -2.169668 270)
			(size 0.4318 0.4318)
			(layers "F.Cu" "F.Mask" "F.Paste")
			(net "PVCCIN_CPU0")
		)
		(pad "BP40" smd circle
			(at -5.68325 -2.169668 270)
			(size 0.4318 0.4318)
			(layers "F.Cu" "F.Mask" "F.Paste")
			(net "PVCCIN_CPU0")
		)
		(pad "BP42" smd circle
			(at -4.055618 -2.169668 270)
			(size 0.4318 0.4318)
			(layers "F.Cu" "F.Mask" "F.Paste")
			(net "PVCCIN_CPU0")
		)
		(pad "BP44" smd circle
			(at -2.427732 -2.169668 270)
			(size 0.4318 0.4318)
			(layers "F.Cu" "F.Mask" "F.Paste")
			(net "PVCCIN_CPU0")
		)
		(pad "BP47" smd circle
			(at 1.613916 -2.059686 270)
			(size 0.4318 0.4318)
			(layers "F.Cu" "F.Mask" "F.Paste")
			(net "PVCCIN_CPU0")
		)
		(pad "BP49" smd circle
			(at 3.241802 -2.059686 270)
			(size 0.4318 0.4318)
			(layers "F.Cu" "F.Mask" "F.Paste")
			(net "PVCCIN_CPU0")
		)
		(pad "BP51" smd circle
			(at 4.869434 -2.059686 270)
			(size 0.4318 0.4318)
			(layers "F.Cu" "F.Mask" "F.Paste")
			(net "PVCCIN_CPU0")
		)
		(pad "BP53" smd circle
			(at 6.49732 -2.059686 270)
			(size 0.4318 0.4318)
			(layers "F.Cu" "F.Mask" "F.Paste")
			(net "PVCCIN_CPU0")
		)
		(pad "BP55" smd circle
			(at 8.124952 -2.059686 270)
			(size 0.4318 0.4318)
			(layers "F.Cu" "F.Mask" "F.Paste")
			(net "PVCCIN_CPU0")
		)
		(pad "BP57" smd circle
			(at 9.752838 -2.059686 270)
			(size 0.4318 0.4318)
			(layers "F.Cu" "F.Mask" "F.Paste")
			(net "PVCCIN_CPU0")
		)
		(pad "BP59" smd circle
			(at 11.380724 -2.059686 270)
			(size 0.4318 0.4318)
			(layers "F.Cu" "F.Mask" "F.Paste")
			(net "PVCCIN_CPU0")
		)
		(pad "BP61" smd circle
			(at 13.008356 -2.059686 270)
			(size 0.4318 0.4318)
			(layers "F.Cu" "F.Mask" "F.Paste")
			(net "PVCCIN_CPU0")
		)
		(pad "BP63" smd circle
			(at 14.635988 -2.059686 270)
			(size 0.4318 0.4318)
			(layers "F.Cu" "F.Mask" "F.Paste")
			(net "GND")
		)
		(pad "BP65" smd circle
			(at 16.263874 -2.059686 270)
			(size 0.4318 0.4318)
			(layers "F.Cu" "F.Mask" "F.Paste")
			(net "NC_CPU0_SOC_SPARE5")
		)
		(pad "BP67" smd circle
			(at 17.89176 -2.059686 270)
			(size 0.4318 0.4318)
			(layers "F.Cu" "F.Mask" "F.Paste")
			(net "NC_CPU0_VIEWPIN_DIE01<1>")
		)
		(pad "BP69" smd circle
			(at 19.519392 -2.059686 270)
			(size 0.4318 0.4318)
			(layers "F.Cu" "F.Mask" "F.Paste")
			(net "NC_CPU0_VIEWPIN_DIE01<0>")
		)
		(pad "BP71" smd circle
			(at 21.147278 -2.059686 270)
			(size 0.4318 0.4318)
			(layers "F.Cu" "F.Mask" "F.Paste")
			(net "GND")
		)
		(pad "BP73" smd circle
			(at 22.77491 -2.059686 270)
			(size 0.4318 0.4318)
			(layers "F.Cu" "F.Mask" "F.Paste")
			(net "GND")
		)
		(pad "BP75" smd circle
			(at 24.402796 -2.059686 270)
			(size 0.4318 0.4318)
			(layers "F.Cu" "F.Mask" "F.Paste")
			(net "GND")
		)
		(pad "BP77" smd circle
			(at 26.030682 -2.059686 270)
			(size 0.4318 0.4318)
			(layers "F.Cu" "F.Mask" "F.Paste")
			(net "GND")
		)
		(pad "BP79" smd circle
			(at 27.658314 -2.059686 270)
			(size 0.4318 0.4318)
			(layers "F.Cu" "F.Mask" "F.Paste")
			(net "PVCCIN_CPU0")
		)
		(pad "BP81" smd circle
			(at 29.2862 -2.059686 270)
			(size 0.4318 0.4318)
			(layers "F.Cu" "F.Mask" "F.Paste")
			(net "PVCCIN_CPU0")
		)
		(pad "BP83" smd circle
			(at 30.914086 -2.059686 270)
			(size 0.4318 0.4318)
			(layers "F.Cu" "F.Mask" "F.Paste")
			(net "PVCCIN_CPU0")
		)
		(pad "BP85" smd circle
			(at 32.541718 -2.059686 270)
			(size 0.4318 0.4318)
			(layers "F.Cu" "F.Mask" "F.Paste")
			(net "PVCCIN_CPU0")
		)
		(pad "BP87" smd circle
			(at 34.169604 -2.059686 270)
			(size 0.4318 0.4318)
			(layers "F.Cu" "F.Mask" "F.Paste")
			(net "PVCCIN_CPU0")
		)
		(pad "BP89" smd circle
			(at 35.797236 -2.059686 270)
			(size 0.4318 0.4318)
			(layers "F.Cu" "F.Mask" "F.Paste")
			(net "PVCCIN_CPU0")
		)
		(pad "BR3" smd circle
			(at -35.797236 -1.699514 270)
			(size 0.4318 0.4318)
			(layers "F.Cu" "F.Mask" "F.Paste")
			(net "UPI_CPU0_CPU1_P0P1_DP<22>")
		)
		(pad "BR5" smd circle
			(at -34.169604 -1.699514 270)
			(size 0.4318 0.4318)
			(layers "F.Cu" "F.Mask" "F.Paste")
			(net "GND")
		)
		(pad "BR7" smd circle
			(at -32.541718 -1.699514 270)
			(size 0.4318 0.4318)
			(layers "F.Cu" "F.Mask" "F.Paste")
			(net "UPI_CPU1_CPU0_P1P0_DN<22>")
		)
		(pad "BR9" smd circle
			(at -30.914086 -1.699514 270)
			(size 0.4318 0.4318)
			(layers "F.Cu" "F.Mask" "F.Paste")
			(net "GND")
		)
		(pad "BR11" smd circle
			(at -29.2862 -1.699514 270)
			(size 0.4318 0.4318)
			(layers "F.Cu" "F.Mask" "F.Paste")
			(net "P5E_CPU0_PE1_RX_DN<9>")
		)
		(pad "BR13" smd circle
			(at -27.658314 -1.699514 270)
			(size 0.4318 0.4318)
			(layers "F.Cu" "F.Mask" "F.Paste")
			(net "GND")
		)
		(pad "BR15" smd circle
			(at -26.030682 -1.699514 270)
			(size 0.4318 0.4318)
			(layers "F.Cu" "F.Mask" "F.Paste")
			(net "P5E_CPU0_PE1_TX_DP<10>")
		)
		(pad "BR17" smd circle
			(at -24.402796 -1.699514 270)
			(size 0.4318 0.4318)
			(layers "F.Cu" "F.Mask" "F.Paste")
			(net "GND")
		)
		(pad "BR19" smd circle
			(at -22.77491 -1.699514 270)
			(size 0.4318 0.4318)
			(layers "F.Cu" "F.Mask" "F.Paste")
			(net "DMI_CPU0_PCH_RX_C_DN<6>")
		)
		(pad "BR21" smd circle
			(at -21.147278 -1.699514 270)
			(size 0.4318 0.4318)
			(layers "F.Cu" "F.Mask" "F.Paste")
			(net "NC_CPU0_MDFI_DIE00_EW1")
		)
		(pad "BR23" smd circle
			(at -19.519392 -1.699514 270)
			(size 0.4318 0.4318)
			(layers "F.Cu" "F.Mask" "F.Paste")
			(net "TP_CPU0_BR23")
		)
		(pad "BR25" smd circle
			(at -17.89176 -1.699514 270)
			(size 0.4318 0.4318)
			(layers "F.Cu" "F.Mask" "F.Paste")
			(net "JTAG_DBP_CPU0_QS_GTL_R_TMS")
		)
		(pad "BR27" smd circle
			(at -16.263874 -1.699514 270)
			(size 0.4318 0.4318)
			(layers "F.Cu" "F.Mask" "F.Paste")
			(net "GND")
		)
		(pad "BR29" smd circle
			(at -14.635988 -1.699514 270)
			(size 0.4318 0.4318)
			(layers "F.Cu" "F.Mask" "F.Paste")
			(net "GND")
		)
		(pad "BR31" smd circle
			(at -13.008356 -1.699514 270)
			(size 0.4318 0.4318)
			(layers "F.Cu" "F.Mask" "F.Paste")
			(net "GND")
		)
		(pad "BR33" smd circle
			(at -11.380724 -1.699514 270)
			(size 0.4318 0.4318)
			(layers "F.Cu" "F.Mask" "F.Paste")
			(net "GND")
		)
		(pad "BR35" smd circle
			(at -9.752838 -1.699514 270)
			(size 0.4318 0.4318)
			(layers "F.Cu" "F.Mask" "F.Paste")
			(net "GND")
		)
		(pad "BR37" smd circle
			(at -8.124952 -1.699514 270)
			(size 0.4318 0.4318)
			(layers "F.Cu" "F.Mask" "F.Paste")
			(net "GND")
		)
		(pad "BR39" smd circle
			(at -6.49732 -1.699514 270)
			(size 0.4318 0.4318)
			(layers "F.Cu" "F.Mask" "F.Paste")
			(net "GND")
		)
		(pad "BR41" smd circle
			(at -4.869434 -1.699514 270)
			(size 0.4318 0.4318)
			(layers "F.Cu" "F.Mask" "F.Paste")
			(net "GND")
		)
		(pad "BR43" smd circle
			(at -3.241802 -1.699514 270)
			(size 0.4318 0.4318)
			(layers "F.Cu" "F.Mask" "F.Paste")
			(net "GND")
		)
		(pad "BR45" smd circle
			(at -1.613916 -1.699514 270)
			(size 0.4318 0.4318)
			(layers "F.Cu" "F.Mask" "F.Paste")
			(net "GND")
		)
		(pad "BR48" smd circle
			(at 2.427732 -1.589532 270)
			(size 0.4318 0.4318)
			(layers "F.Cu" "F.Mask" "F.Paste")
			(net "GND")
		)
		(pad "BR50" smd circle
			(at 4.055618 -1.589532 270)
			(size 0.4318 0.4318)
			(layers "F.Cu" "F.Mask" "F.Paste")
			(net "GND")
		)
		(pad "BR52" smd circle
			(at 5.68325 -1.589532 270)
			(size 0.4318 0.4318)
			(layers "F.Cu" "F.Mask" "F.Paste")
			(net "GND")
		)
		(pad "BR54" smd circle
			(at 7.311136 -1.589532 270)
			(size 0.4318 0.4318)
			(layers "F.Cu" "F.Mask" "F.Paste")
			(net "GND")
		)
		(pad "BR56" smd circle
			(at 8.939022 -1.589532 270)
			(size 0.4318 0.4318)
			(layers "F.Cu" "F.Mask" "F.Paste")
			(net "GND")
		)
		(pad "BR58" smd circle
			(at 10.566654 -1.589532 270)
			(size 0.4318 0.4318)
			(layers "F.Cu" "F.Mask" "F.Paste")
			(net "GND")
		)
		(pad "BR60" smd circle
			(at 12.19454 -1.589532 270)
			(size 0.4318 0.4318)
			(layers "F.Cu" "F.Mask" "F.Paste")
			(net "PVCCIN_CPU0")
		)
		(pad "BR62" smd circle
			(at 13.822426 -1.589532 270)
			(size 0.4318 0.4318)
			(layers "F.Cu" "F.Mask" "F.Paste")
			(net "PVCCIN_CPU0")
		)
		(pad "BR64" smd circle
			(at 15.450058 -1.589532 270)
			(size 0.4318 0.4318)
			(layers "F.Cu" "F.Mask" "F.Paste")
			(net "GND")
		)
		(pad "BR66" smd circle
			(at 17.07769 -1.589532 270)
			(size 0.4318 0.4318)
			(layers "F.Cu" "F.Mask" "F.Paste")
			(net "GND")
		)
		(pad "BR68" smd circle
			(at 18.705576 -1.589532 270)
			(size 0.4318 0.4318)
			(layers "F.Cu" "F.Mask" "F.Paste")
			(net "GND")
		)
		(pad "BR70" smd circle
			(at 20.333462 -1.589532 270)
			(size 0.4318 0.4318)
			(layers "F.Cu" "F.Mask" "F.Paste")
			(net "GND")
		)
		(pad "BR72" smd circle
			(at 21.961094 -1.589532 270)
			(size 0.4318 0.4318)
			(layers "F.Cu" "F.Mask" "F.Paste")
			(net "GND")
		)
		(pad "BR74" smd circle
			(at 23.58898 -1.589532 270)
			(size 0.4318 0.4318)
			(layers "F.Cu" "F.Mask" "F.Paste")
			(net "GND")
		)
		(pad "BR76" smd circle
			(at 25.216612 -1.589532 270)
			(size 0.4318 0.4318)
			(layers "F.Cu" "F.Mask" "F.Paste")
			(net "GND")
		)
		(pad "BR78" smd circle
			(at 26.844498 -1.589532 270)
			(size 0.4318 0.4318)
			(layers "F.Cu" "F.Mask" "F.Paste")
			(net "PVCCIN_CPU0")
		)
		(pad "BR80" smd circle
			(at 28.472384 -1.589532 270)
			(size 0.4318 0.4318)
			(layers "F.Cu" "F.Mask" "F.Paste")
			(net "GND")
		)
		(pad "BR82" smd circle
			(at 30.100016 -1.589532 270)
			(size 0.4318 0.4318)
			(layers "F.Cu" "F.Mask" "F.Paste")
			(net "GND")
		)
		(pad "BR84" smd circle
			(at 31.727902 -1.589532 270)
			(size 0.4318 0.4318)
			(layers "F.Cu" "F.Mask" "F.Paste")
			(net "GND")
		)
		(pad "BR86" smd circle
			(at 33.355534 -1.589532 270)
			(size 0.4318 0.4318)
			(layers "F.Cu" "F.Mask" "F.Paste")
			(net "GND")
		)
		(pad "BR88" smd circle
			(at 34.98342 -1.589532 270)
			(size 0.4318 0.4318)
			(layers "F.Cu" "F.Mask" "F.Paste")
			(net "GND")
		)
		(pad "BR90" smd oval
			(at 36.611306 -1.589532)
			(size 0.381 0.4826)
			(drill
				(offset 0 -0.0508)
			)
			(layers "F.Cu" "F.Mask" "F.Paste")
			(net "GND")
		)
		(pad "BT2" smd oval
			(at -36.611306 -1.229614 180)
			(size 0.381 0.4826)
			(drill
				(offset 0 -0.0508)
			)
			(layers "F.Cu" "F.Mask" "F.Paste")
			(net "UPI_CPU0_CPU1_P0P1_DN<23>")
		)
		(pad "BT4" smd circle
			(at -34.98342 -1.229614 270)
			(size 0.4318 0.4318)
			(layers "F.Cu" "F.Mask" "F.Paste")
			(net "GND")
		)
		(pad "BT6" smd circle
			(at -33.355534 -1.229614 270)
			(size 0.4318 0.4318)
			(layers "F.Cu" "F.Mask" "F.Paste")
			(net "UPI_CPU1_CPU0_P1P0_DN<23>")
		)
		(pad "BT8" smd circle
			(at -31.727902 -1.229614 270)
			(size 0.4318 0.4318)
			(layers "F.Cu" "F.Mask" "F.Paste")
			(net "GND")
		)
		(pad "BT10" smd circle
			(at -30.100016 -1.229614 270)
			(size 0.4318 0.4318)
			(layers "F.Cu" "F.Mask" "F.Paste")
			(net "P5E_CPU0_PE1_RX_DP<9>")
		)
		(pad "BT12" smd circle
			(at -28.472384 -1.229614 270)
			(size 0.4318 0.4318)
			(layers "F.Cu" "F.Mask" "F.Paste")
			(net "GND")
		)
		(pad "BT14" smd circle
			(at -26.844498 -1.229614 270)
			(size 0.4318 0.4318)
			(layers "F.Cu" "F.Mask" "F.Paste")
			(net "P5E_CPU0_PE1_TX_DP<9>")
		)
		(pad "BT16" smd circle
			(at -25.216612 -1.229614 270)
			(size 0.4318 0.4318)
			(layers "F.Cu" "F.Mask" "F.Paste")
			(net "GND")
		)
		(pad "BT18" smd circle
			(at -23.58898 -1.229614 270)
			(size 0.4318 0.4318)
			(layers "F.Cu" "F.Mask" "F.Paste")
			(net "DMI_CPU0_PCH_RX_C_DP<7>")
		)
		(pad "BT20" smd circle
			(at -21.961094 -1.229614 270)
			(size 0.4318 0.4318)
			(layers "F.Cu" "F.Mask" "F.Paste")
			(net "GND")
		)
		(pad "BT22" smd circle
			(at -20.333462 -1.229614 270)
			(size 0.4318 0.4318)
			(layers "F.Cu" "F.Mask" "F.Paste")
			(net "I3C_SPD_DDRABCD_CPU0_SCL")
		)
		(pad "BT24" smd circle
			(at -18.705576 -1.229614 270)
			(size 0.4318 0.4318)
			(layers "F.Cu" "F.Mask" "F.Paste")
			(net "JTAG_DBP_CPU0_GTL_R_TCK")
		)
		(pad "BT26" smd circle
			(at -17.07769 -1.229614 270)
			(size 0.4318 0.4318)
			(layers "F.Cu" "F.Mask" "F.Paste")
			(net "PU_CPU0_TXT_AGENT")
		)
		(pad "BT28" smd circle
			(at -15.450058 -1.229614 270)
			(size 0.4318 0.4318)
			(layers "F.Cu" "F.Mask" "F.Paste")
			(net "TP_TRC_CPU0_PTI<9>")
		)
		(pad "BT30" smd circle
			(at -13.822426 -1.229614 270)
			(size 0.4318 0.4318)
			(layers "F.Cu" "F.Mask" "F.Paste")
			(net "TP_TRC_CPU0_PTI<11>")
		)
		(pad "BT32" smd circle
			(at -12.19454 -1.229614 270)
			(size 0.4318 0.4318)
			(layers "F.Cu" "F.Mask" "F.Paste")
			(net "PVCCIN_CPU0")
		)
		(pad "BT34" smd circle
			(at -10.566654 -1.229614 270)
			(size 0.4318 0.4318)
			(layers "F.Cu" "F.Mask" "F.Paste")
			(net "PVCCIN_CPU0")
		)
		(pad "BT36" smd circle
			(at -8.939022 -1.229614 270)
			(size 0.4318 0.4318)
			(layers "F.Cu" "F.Mask" "F.Paste")
			(net "PVCCIN_CPU0")
		)
		(pad "BT38" smd circle
			(at -7.311136 -1.229614 270)
			(size 0.4318 0.4318)
			(layers "F.Cu" "F.Mask" "F.Paste")
			(net "PVCCIN_CPU0")
		)
		(pad "BT40" smd circle
			(at -5.68325 -1.229614 270)
			(size 0.4318 0.4318)
			(layers "F.Cu" "F.Mask" "F.Paste")
			(net "PVCCIN_CPU0")
		)
		(pad "BT42" smd circle
			(at -4.055618 -1.229614 270)
			(size 0.4318 0.4318)
			(layers "F.Cu" "F.Mask" "F.Paste")
			(net "PVCCIN_CPU0")
		)
		(pad "BT44" smd circle
			(at -2.427732 -1.229614 270)
			(size 0.4318 0.4318)
			(layers "F.Cu" "F.Mask" "F.Paste")
			(net "PVCCIN_CPU0")
		)
		(pad "BT47" smd circle
			(at 1.613916 -1.119886 270)
			(size 0.4318 0.4318)
			(layers "F.Cu" "F.Mask" "F.Paste")
			(net "PVCCIN_CPU0")
		)
		(pad "BT49" smd circle
			(at 3.241802 -1.119886 270)
			(size 0.4318 0.4318)
			(layers "F.Cu" "F.Mask" "F.Paste")
			(net "PVCCIN_CPU0")
		)
		(pad "BT51" smd circle
			(at 4.869434 -1.119886 270)
			(size 0.4318 0.4318)
			(layers "F.Cu" "F.Mask" "F.Paste")
			(net "PVCCIN_CPU0")
		)
		(pad "BT53" smd circle
			(at 6.49732 -1.119886 270)
			(size 0.4318 0.4318)
			(layers "F.Cu" "F.Mask" "F.Paste")
			(net "PVCCIN_CPU0")
		)
		(pad "BT55" smd circle
			(at 8.124952 -1.119886 270)
			(size 0.4318 0.4318)
			(layers "F.Cu" "F.Mask" "F.Paste")
			(net "PVCCIN_CPU0")
		)
		(pad "BT57" smd circle
			(at 9.752838 -1.119886 270)
			(size 0.4318 0.4318)
			(layers "F.Cu" "F.Mask" "F.Paste")
			(net "PVCCIN_CPU0")
		)
		(pad "BT59" smd circle
			(at 11.380724 -1.119886 270)
			(size 0.4318 0.4318)
			(layers "F.Cu" "F.Mask" "F.Paste")
			(net "PVCCIN_CPU0")
		)
		(pad "BT61" smd circle
			(at 13.008356 -1.119886 270)
			(size 0.4318 0.4318)
			(layers "F.Cu" "F.Mask" "F.Paste")
			(net "PVCCIN_CPU0")
		)
		(pad "BT63" smd circle
			(at 14.635988 -1.119886 270)
			(size 0.4318 0.4318)
			(layers "F.Cu" "F.Mask" "F.Paste")
			(net "PVCCIN_CPU0")
		)
		(pad "BT65" smd circle
			(at 16.263874 -1.119886 270)
			(size 0.4318 0.4318)
			(layers "F.Cu" "F.Mask" "F.Paste")
			(net "PVCCIN_CPU0")
		)
		(pad "BT67" smd circle
			(at 17.89176 -1.119886 270)
			(size 0.4318 0.4318)
			(layers "F.Cu" "F.Mask" "F.Paste")
			(net "PVCCIN_CPU0")
		)
		(pad "BT69" smd circle
			(at 19.519392 -1.119886 270)
			(size 0.4318 0.4318)
			(layers "F.Cu" "F.Mask" "F.Paste")
			(net "PVCCIN_CPU0")
		)
		(pad "BT71" smd circle
			(at 21.147278 -1.119886 270)
			(size 0.4318 0.4318)
			(layers "F.Cu" "F.Mask" "F.Paste")
			(net "PVCCIN_CPU0")
		)
		(pad "BT73" smd circle
			(at 22.77491 -1.119886 270)
			(size 0.4318 0.4318)
			(layers "F.Cu" "F.Mask" "F.Paste")
			(net "PVCCIN_CPU0")
		)
		(pad "BT75" smd circle
			(at 24.402796 -1.119886 270)
			(size 0.4318 0.4318)
			(layers "F.Cu" "F.Mask" "F.Paste")
			(net "PVCCIN_CPU0")
		)
		(pad "BT77" smd circle
			(at 26.030682 -1.119886 270)
			(size 0.4318 0.4318)
			(layers "F.Cu" "F.Mask" "F.Paste")
			(net "PVCCIN_CPU0")
		)
		(pad "BT79" smd circle
			(at 27.658314 -1.119886 270)
			(size 0.4318 0.4318)
			(layers "F.Cu" "F.Mask" "F.Paste")
			(net "PVCCIN_CPU0")
		)
		(pad "BT81" smd circle
			(at 29.2862 -1.119886 270)
			(size 0.4318 0.4318)
			(layers "F.Cu" "F.Mask" "F.Paste")
			(net "PVCCIN_CPU0")
		)
		(pad "BT83" smd circle
			(at 30.914086 -1.119886 270)
			(size 0.4318 0.4318)
			(layers "F.Cu" "F.Mask" "F.Paste")
			(net "PVCCIN_CPU0")
		)
		(pad "BT85" smd circle
			(at 32.541718 -1.119886 270)
			(size 0.4318 0.4318)
			(layers "F.Cu" "F.Mask" "F.Paste")
			(net "PVCCIN_CPU0")
		)
		(pad "BT87" smd circle
			(at 34.169604 -1.119886 270)
			(size 0.4318 0.4318)
			(layers "F.Cu" "F.Mask" "F.Paste")
			(net "PVCCIN_CPU0")
		)
		(pad "BT89" smd circle
			(at 35.797236 -1.119886 270)
			(size 0.4318 0.4318)
			(layers "F.Cu" "F.Mask" "F.Paste")
			(net "PVCCIN_CPU0")
		)
		(pad "BU3" smd circle
			(at -35.797236 -0.759714 270)
			(size 0.4318 0.4318)
			(layers "F.Cu" "F.Mask" "F.Paste")
			(net "UPI_CPU0_CPU1_P0P1_DP<23>")
		)
		(pad "BU5" smd circle
			(at -34.169604 -0.759714 270)
			(size 0.4318 0.4318)
			(layers "F.Cu" "F.Mask" "F.Paste")
			(net "UPI_CPU1_CPU0_P1P0_DP<23>")
		)
		(pad "BU7" smd circle
			(at -32.541718 -0.759714 270)
			(size 0.4318 0.4318)
			(layers "F.Cu" "F.Mask" "F.Paste")
			(net "GND")
		)
		(pad "BU9" smd circle
			(at -30.914086 -0.759714 270)
			(size 0.4318 0.4318)
			(layers "F.Cu" "F.Mask" "F.Paste")
			(net "P5E_CPU0_PE1_RX_DP<8>")
		)
		(pad "BU11" smd circle
			(at -29.2862 -0.759714 270)
			(size 0.4318 0.4318)
			(layers "F.Cu" "F.Mask" "F.Paste")
			(net "VSENSE_PVCCD_HV_CPU0_DP")
		)
		(pad "BU13" smd circle
			(at -27.658314 -0.759714 270)
			(size 0.4318 0.4318)
			(layers "F.Cu" "F.Mask" "F.Paste")
			(net "P5E_CPU0_PE1_TX_DN<9>")
		)
		(pad "BU15" smd circle
			(at -26.030682 -0.759714 270)
			(size 0.4318 0.4318)
			(layers "F.Cu" "F.Mask" "F.Paste")
			(net "GND")
		)
		(pad "BU17" smd circle
			(at -24.402796 -0.759714 270)
			(size 0.4318 0.4318)
			(layers "F.Cu" "F.Mask" "F.Paste")
			(net "DMI_CPU0_PCH_RX_C_DN<7>")
		)
		(pad "BU19" smd circle
			(at -22.77491 -0.759714 270)
			(size 0.4318 0.4318)
			(layers "F.Cu" "F.Mask" "F.Paste")
			(net "GND")
		)
		(pad "BU21" smd circle
			(at -21.147278 -0.759714 270)
			(size 0.4318 0.4318)
			(layers "F.Cu" "F.Mask" "F.Paste")
			(net "GND")
		)
		(pad "BU23" smd circle
			(at -19.519392 -0.759714 270)
			(size 0.4318 0.4318)
			(layers "F.Cu" "F.Mask" "F.Paste")
			(net "GND")
		)
		(pad "BU25" smd circle
			(at -17.89176 -0.759714 270)
			(size 0.4318 0.4318)
			(layers "F.Cu" "F.Mask" "F.Paste")
			(net "GND")
		)
		(pad "BU27" smd circle
			(at -16.263874 -0.759714 270)
			(size 0.4318 0.4318)
			(layers "F.Cu" "F.Mask" "F.Paste")
			(net "TP_TRC_CPU0_PTI<8>")
		)
		(pad "BU29" smd circle
			(at -14.635988 -0.759714 270)
			(size 0.4318 0.4318)
			(layers "F.Cu" "F.Mask" "F.Paste")
			(net "TP_TRC_CPU0_PTI<10>")
		)
		(pad "BU31" smd circle
			(at -13.008356 -0.759714 270)
			(size 0.4318 0.4318)
			(layers "F.Cu" "F.Mask" "F.Paste")
			(net "GND")
		)
		(pad "BU33" smd circle
			(at -11.380724 -0.759714 270)
			(size 0.4318 0.4318)
			(layers "F.Cu" "F.Mask" "F.Paste")
			(net "PVCCIN_CPU0")
		)
		(pad "BU35" smd circle
			(at -9.752838 -0.759714 270)
			(size 0.4318 0.4318)
			(layers "F.Cu" "F.Mask" "F.Paste")
			(net "PVCCIN_CPU0")
		)
		(pad "BU37" smd circle
			(at -8.124952 -0.759714 270)
			(size 0.4318 0.4318)
			(layers "F.Cu" "F.Mask" "F.Paste")
			(net "PVCCIN_CPU0")
		)
		(pad "BU39" smd circle
			(at -6.49732 -0.759714 270)
			(size 0.4318 0.4318)
			(layers "F.Cu" "F.Mask" "F.Paste")
			(net "PVCCIN_CPU0")
		)
		(pad "BU41" smd circle
			(at -4.869434 -0.759714 270)
			(size 0.4318 0.4318)
			(layers "F.Cu" "F.Mask" "F.Paste")
			(net "PVCCIN_CPU0")
		)
		(pad "BU43" smd circle
			(at -3.241802 -0.759714 270)
			(size 0.4318 0.4318)
			(layers "F.Cu" "F.Mask" "F.Paste")
			(net "PVCCIN_CPU0")
		)
		(pad "BU45" smd circle
			(at -1.613916 -0.759714 270)
			(size 0.4318 0.4318)
			(layers "F.Cu" "F.Mask" "F.Paste")
			(net "PVCCIN_CPU0")
		)
		(pad "BU48" smd circle
			(at 2.427732 -0.649732 270)
			(size 0.4318 0.4318)
			(layers "F.Cu" "F.Mask" "F.Paste")
			(net "PVCCIN_CPU0")
		)
		(pad "BU50" smd circle
			(at 4.055618 -0.649732 270)
			(size 0.4318 0.4318)
			(layers "F.Cu" "F.Mask" "F.Paste")
			(net "PVCCIN_CPU0")
		)
		(pad "BU52" smd circle
			(at 5.68325 -0.649732 270)
			(size 0.4318 0.4318)
			(layers "F.Cu" "F.Mask" "F.Paste")
			(net "PVCCIN_CPU0")
		)
		(pad "BU54" smd circle
			(at 7.311136 -0.649732 270)
			(size 0.4318 0.4318)
			(layers "F.Cu" "F.Mask" "F.Paste")
			(net "PVCCIN_CPU0")
		)
		(pad "BU56" smd circle
			(at 8.939022 -0.649732 270)
			(size 0.4318 0.4318)
			(layers "F.Cu" "F.Mask" "F.Paste")
			(net "PVCCIN_CPU0")
		)
		(pad "BU58" smd circle
			(at 10.566654 -0.649732 270)
			(size 0.4318 0.4318)
			(layers "F.Cu" "F.Mask" "F.Paste")
			(net "PVCCIN_CPU0")
		)
		(pad "BU60" smd circle
			(at 12.19454 -0.649732 270)
			(size 0.4318 0.4318)
			(layers "F.Cu" "F.Mask" "F.Paste")
			(net "PVCCIN_CPU0")
		)
		(pad "BU62" smd circle
			(at 13.822426 -0.649732 270)
			(size 0.4318 0.4318)
			(layers "F.Cu" "F.Mask" "F.Paste")
			(net "PVCCIN_CPU0")
		)
		(pad "BU64" smd circle
			(at 15.450058 -0.649732 270)
			(size 0.4318 0.4318)
			(layers "F.Cu" "F.Mask" "F.Paste")
			(net "PVCCIN_CPU0")
		)
		(pad "BU66" smd circle
			(at 17.07769 -0.649732 270)
			(size 0.4318 0.4318)
			(layers "F.Cu" "F.Mask" "F.Paste")
			(net "PVCCIN_CPU0")
		)
		(pad "BU68" smd circle
			(at 18.705576 -0.649732 270)
			(size 0.4318 0.4318)
			(layers "F.Cu" "F.Mask" "F.Paste")
			(net "PVCCIN_CPU0")
		)
		(pad "BU70" smd circle
			(at 20.333462 -0.649732 270)
			(size 0.4318 0.4318)
			(layers "F.Cu" "F.Mask" "F.Paste")
			(net "PVCCIN_CPU0")
		)
		(pad "BU72" smd circle
			(at 21.961094 -0.649732 270)
			(size 0.4318 0.4318)
			(layers "F.Cu" "F.Mask" "F.Paste")
			(net "PVCCIN_CPU0")
		)
		(pad "BU74" smd circle
			(at 23.58898 -0.649732 270)
			(size 0.4318 0.4318)
			(layers "F.Cu" "F.Mask" "F.Paste")
			(net "PVCCIN_CPU0")
		)
		(pad "BU76" smd circle
			(at 25.216612 -0.649732 270)
			(size 0.4318 0.4318)
			(layers "F.Cu" "F.Mask" "F.Paste")
			(net "PVCCIN_CPU0")
		)
		(pad "BU78" smd circle
			(at 26.844498 -0.649732 270)
			(size 0.4318 0.4318)
			(layers "F.Cu" "F.Mask" "F.Paste")
			(net "PVCCIN_CPU0")
		)
		(pad "BU80" smd circle
			(at 28.472384 -0.649732 270)
			(size 0.4318 0.4318)
			(layers "F.Cu" "F.Mask" "F.Paste")
			(net "PVCCIN_CPU0")
		)
		(pad "BU82" smd circle
			(at 30.100016 -0.649732 270)
			(size 0.4318 0.4318)
			(layers "F.Cu" "F.Mask" "F.Paste")
			(net "PVCCIN_CPU0")
		)
		(pad "BU84" smd circle
			(at 31.727902 -0.649732 270)
			(size 0.4318 0.4318)
			(layers "F.Cu" "F.Mask" "F.Paste")
			(net "PVCCIN_CPU0")
		)
		(pad "BU86" smd circle
			(at 33.355534 -0.649732 270)
			(size 0.4318 0.4318)
			(layers "F.Cu" "F.Mask" "F.Paste")
			(net "PVCCIN_CPU0")
		)
		(pad "BU88" smd circle
			(at 34.98342 -0.649732 270)
			(size 0.4318 0.4318)
			(layers "F.Cu" "F.Mask" "F.Paste")
			(net "PVCCIN_CPU0")
		)
		(pad "BU90" smd oval
			(at 36.611306 -0.649732)
			(size 0.381 0.4826)
			(drill
				(offset 0 -0.0508)
			)
			(layers "F.Cu" "F.Mask" "F.Paste")
			(net "PVCCIN_CPU0")
		)
		(pad "BV2" smd oval
			(at -36.611306 -0.290068 180)
			(size 0.381 0.4826)
			(drill
				(offset 0 -0.0508)
			)
			(layers "F.Cu" "F.Mask" "F.Paste")
			(net "GND")
		)
		(pad "BV4" smd circle
			(at -34.98342 -0.290068 270)
			(size 0.4318 0.4318)
			(layers "F.Cu" "F.Mask" "F.Paste")
			(net "GND")
		)
		(pad "BV6" smd circle
			(at -33.355534 -0.290068 270)
			(size 0.4318 0.4318)
			(layers "F.Cu" "F.Mask" "F.Paste")
			(net "GND")
		)
		(pad "BV8" smd circle
			(at -31.727902 -0.290068 270)
			(size 0.4318 0.4318)
			(layers "F.Cu" "F.Mask" "F.Paste")
			(net "GND")
		)
		(pad "BV10" smd circle
			(at -30.100016 -0.290068 270)
			(size 0.4318 0.4318)
			(layers "F.Cu" "F.Mask" "F.Paste")
			(net "P5E_CPU0_PE1_RX_DN<8>")
		)
		(pad "BV12" smd circle
			(at -28.472384 -0.290068 270)
			(size 0.4318 0.4318)
			(layers "F.Cu" "F.Mask" "F.Paste")
			(net "GND")
		)
		(pad "BV14" smd circle
			(at -26.844498 -0.290068 270)
			(size 0.4318 0.4318)
			(layers "F.Cu" "F.Mask" "F.Paste")
			(net "P5E_CPU0_PE1_TX_DN<8>")
		)
		(pad "BV16" smd circle
			(at -25.216612 -0.290068 270)
			(size 0.4318 0.4318)
			(layers "F.Cu" "F.Mask" "F.Paste")
			(net "GND")
		)
		(pad "BV18" smd circle
			(at -23.58898 -0.290068 270)
			(size 0.4318 0.4318)
			(layers "F.Cu" "F.Mask" "F.Paste")
			(net "GND")
		)
		(pad "BV20" smd circle
			(at -21.961094 -0.290068 270)
			(size 0.4318 0.4318)
			(layers "F.Cu" "F.Mask" "F.Paste")
			(net "GND")
		)
		(pad "BV22" smd circle
			(at -20.333462 -0.290068 270)
			(size 0.4318 0.4318)
			(layers "F.Cu" "F.Mask" "F.Paste")
			(net "NC_CPU0_UPI1_APROBE<0>")
		)
		(pad "BV24" smd circle
			(at -18.705576 -0.290068 270)
			(size 0.4318 0.4318)
			(layers "F.Cu" "F.Mask" "F.Paste")
			(net "JTAG_DBP_CPU0_GTL_R_TDI")
		)
		(pad "BV26" smd circle
			(at -17.07769 -0.290068 270)
			(size 0.4318 0.4318)
			(layers "F.Cu" "F.Mask" "F.Paste")
			(net "FM_PEHPCPU0_ALERT_N")
		)
		(pad "BV28" smd circle
			(at -15.450058 -0.290068 270)
			(size 0.4318 0.4318)
			(layers "F.Cu" "F.Mask" "F.Paste")
			(net "TP_TRC_CPU0_PTI<7>")
		)
		(pad "BV30" smd circle
			(at -13.822426 -0.290068 270)
			(size 0.4318 0.4318)
			(layers "F.Cu" "F.Mask" "F.Paste")
			(net "TP_TRC_CPU0_PTI<5>")
		)
		(pad "BV32" smd circle
			(at -12.19454 -0.290068 270)
			(size 0.4318 0.4318)
			(layers "F.Cu" "F.Mask" "F.Paste")
			(net "PVCCIN_CPU0")
		)
		(pad "BV34" smd circle
			(at -10.566654 -0.290068 270)
			(size 0.4318 0.4318)
			(layers "F.Cu" "F.Mask" "F.Paste")
			(net "PVCCIN_CPU0")
		)
		(pad "BV36" smd circle
			(at -8.939022 -0.290068 270)
			(size 0.4318 0.4318)
			(layers "F.Cu" "F.Mask" "F.Paste")
			(net "PVCCIN_CPU0")
		)
		(pad "BV38" smd circle
			(at -7.311136 -0.290068 270)
			(size 0.4318 0.4318)
			(layers "F.Cu" "F.Mask" "F.Paste")
			(net "PVCCIN_CPU0")
		)
		(pad "BV40" smd circle
			(at -5.68325 -0.290068 270)
			(size 0.4318 0.4318)
			(layers "F.Cu" "F.Mask" "F.Paste")
			(net "PVCCIN_CPU0")
		)
		(pad "BV42" smd circle
			(at -4.055618 -0.290068 270)
			(size 0.4318 0.4318)
			(layers "F.Cu" "F.Mask" "F.Paste")
			(net "PVCCIN_CPU0")
		)
		(pad "BV44" smd circle
			(at -2.427732 -0.290068 270)
			(size 0.4318 0.4318)
			(layers "F.Cu" "F.Mask" "F.Paste")
			(net "PVCCIN_CPU0")
		)
		(pad "BV47" smd circle
			(at 1.613916 -0.180086 270)
			(size 0.4318 0.4318)
			(layers "F.Cu" "F.Mask" "F.Paste")
			(net "PVCCIN_CPU0")
		)
		(pad "BV49" smd circle
			(at 3.241802 -0.180086 270)
			(size 0.4318 0.4318)
			(layers "F.Cu" "F.Mask" "F.Paste")
			(net "PVCCIN_CPU0")
		)
		(pad "BV51" smd circle
			(at 4.869434 -0.180086 270)
			(size 0.4318 0.4318)
			(layers "F.Cu" "F.Mask" "F.Paste")
			(net "PVCCIN_CPU0")
		)
		(pad "BV53" smd circle
			(at 6.49732 -0.180086 270)
			(size 0.4318 0.4318)
			(layers "F.Cu" "F.Mask" "F.Paste")
			(net "PVCCIN_CPU0")
		)
		(pad "BV55" smd circle
			(at 8.124952 -0.180086 270)
			(size 0.4318 0.4318)
			(layers "F.Cu" "F.Mask" "F.Paste")
			(net "PVCCIN_CPU0")
		)
		(pad "BV57" smd circle
			(at 9.752838 -0.180086 270)
			(size 0.4318 0.4318)
			(layers "F.Cu" "F.Mask" "F.Paste")
			(net "PVCCIN_CPU0")
		)
		(pad "BV59" smd circle
			(at 11.380724 -0.180086 270)
			(size 0.4318 0.4318)
			(layers "F.Cu" "F.Mask" "F.Paste")
			(net "PVCCIN_CPU0")
		)
		(pad "BV61" smd circle
			(at 13.008356 -0.180086 270)
			(size 0.4318 0.4318)
			(layers "F.Cu" "F.Mask" "F.Paste")
			(net "PVCCIN_CPU0")
		)
		(pad "BV63" smd circle
			(at 14.635988 -0.180086 270)
			(size 0.4318 0.4318)
			(layers "F.Cu" "F.Mask" "F.Paste")
			(net "PVCCIN_CPU0")
		)
		(pad "BV65" smd circle
			(at 16.263874 -0.180086 270)
			(size 0.4318 0.4318)
			(layers "F.Cu" "F.Mask" "F.Paste")
			(net "PVCCIN_CPU0")
		)
		(pad "BV67" smd circle
			(at 17.89176 -0.180086 270)
			(size 0.4318 0.4318)
			(layers "F.Cu" "F.Mask" "F.Paste")
			(net "PVCCIN_CPU0")
		)
		(pad "BV69" smd circle
			(at 19.519392 -0.180086 270)
			(size 0.4318 0.4318)
			(layers "F.Cu" "F.Mask" "F.Paste")
			(net "PVCCIN_CPU0")
		)
		(pad "BV71" smd circle
			(at 21.147278 -0.180086 270)
			(size 0.4318 0.4318)
			(layers "F.Cu" "F.Mask" "F.Paste")
			(net "PVCCIN_CPU0")
		)
		(pad "BV73" smd circle
			(at 22.77491 -0.180086 270)
			(size 0.4318 0.4318)
			(layers "F.Cu" "F.Mask" "F.Paste")
			(net "PVCCIN_CPU0")
		)
		(pad "BV75" smd circle
			(at 24.402796 -0.180086 270)
			(size 0.4318 0.4318)
			(layers "F.Cu" "F.Mask" "F.Paste")
			(net "PVCCIN_CPU0")
		)
		(pad "BV77" smd circle
			(at 26.030682 -0.180086 270)
			(size 0.4318 0.4318)
			(layers "F.Cu" "F.Mask" "F.Paste")
			(net "PVCCIN_CPU0")
		)
		(pad "BV79" smd circle
			(at 27.658314 -0.180086 270)
			(size 0.4318 0.4318)
			(layers "F.Cu" "F.Mask" "F.Paste")
			(net "PVCCIN_CPU0")
		)
		(pad "BV81" smd circle
			(at 29.2862 -0.180086 270)
			(size 0.4318 0.4318)
			(layers "F.Cu" "F.Mask" "F.Paste")
			(net "PVCCIN_CPU0")
		)
		(pad "BV83" smd circle
			(at 30.914086 -0.180086 270)
			(size 0.4318 0.4318)
			(layers "F.Cu" "F.Mask" "F.Paste")
			(net "PVCCIN_CPU0")
		)
		(pad "BV85" smd circle
			(at 32.541718 -0.180086 270)
			(size 0.4318 0.4318)
			(layers "F.Cu" "F.Mask" "F.Paste")
			(net "PVCCIN_CPU0")
		)
		(pad "BV87" smd circle
			(at 34.169604 -0.180086 270)
			(size 0.4318 0.4318)
			(layers "F.Cu" "F.Mask" "F.Paste")
			(net "PVCCIN_CPU0")
		)
		(pad "BV89" smd circle
			(at 35.797236 -0.180086 270)
			(size 0.4318 0.4318)
			(layers "F.Cu" "F.Mask" "F.Paste")
			(net "PVCCIN_CPU0")
		)
		(pad "BW3" smd circle
			(at -35.797236 0.180086 270)
			(size 0.4318 0.4318)
			(layers "F.Cu" "F.Mask" "F.Paste")
			(net "GND")
		)
		(pad "BW5" smd circle
			(at -34.169604 0.180086 270)
			(size 0.4318 0.4318)
			(layers "F.Cu" "F.Mask" "F.Paste")
			(net "GND")
		)
		(pad "BW7" smd circle
			(at -32.541718 0.180086 270)
			(size 0.4318 0.4318)
			(layers "F.Cu" "F.Mask" "F.Paste")
			(net "UPI_CPU0_CPU1_P1P0_DN<23>")
		)
		(pad "BW9" smd circle
			(at -30.914086 0.180086 270)
			(size 0.4318 0.4318)
			(layers "F.Cu" "F.Mask" "F.Paste")
			(net "GND")
		)
		(pad "BW11" smd circle
			(at -29.2862 0.180086 270)
			(size 0.4318 0.4318)
			(layers "F.Cu" "F.Mask" "F.Paste")
			(net "P5E_CPU0_PE1_RX_DN<7>")
		)
		(pad "BW13" smd circle
			(at -27.658314 0.180086 270)
			(size 0.4318 0.4318)
			(layers "F.Cu" "F.Mask" "F.Paste")
			(net "GND")
		)
		(pad "BW15" smd circle
			(at -26.030682 0.180086 270)
			(size 0.4318 0.4318)
			(layers "F.Cu" "F.Mask" "F.Paste")
			(net "P5E_CPU0_PE1_TX_DP<8>")
		)
		(pad "BW17" smd circle
			(at -24.402796 0.180086 270)
			(size 0.4318 0.4318)
			(layers "F.Cu" "F.Mask" "F.Paste")
			(net "GND")
		)
		(pad "BW19" smd circle
			(at -22.77491 0.180086 270)
			(size 0.4318 0.4318)
			(layers "F.Cu" "F.Mask" "F.Paste")
			(net "DMI_CPU0_PCH_TX_DP<0>")
		)
		(pad "BW21" smd circle
			(at -21.147278 0.180086 270)
			(size 0.4318 0.4318)
			(layers "F.Cu" "F.Mask" "F.Paste")
			(net "NC_CPU0_DMI_APROBE<1>")
		)
		(pad "BW23" smd circle
			(at -19.519392 0.180086 270)
			(size 0.4318 0.4318)
			(layers "F.Cu" "F.Mask" "F.Paste")
			(net "NC_CPU0_PE2_APROBE<1>")
		)
		(pad "BW25" smd circle
			(at -17.89176 0.180086 270)
			(size 0.4318 0.4318)
			(layers "F.Cu" "F.Mask" "F.Paste")
			(net "JTAG_CPU0_MUX_GTL_TDO")
		)
		(pad "BW27" smd circle
			(at -16.263874 0.180086 270)
			(size 0.4318 0.4318)
			(layers "F.Cu" "F.Mask" "F.Paste")
			(net "GND")
		)
		(pad "BW29" smd circle
			(at -14.635988 0.180086 270)
			(size 0.4318 0.4318)
			(layers "F.Cu" "F.Mask" "F.Paste")
			(net "GND")
		)
		(pad "BW31" smd circle
			(at -13.008356 0.180086 270)
			(size 0.4318 0.4318)
			(layers "F.Cu" "F.Mask" "F.Paste")
			(net "GND")
		)
		(pad "BW33" smd circle
			(at -11.380724 0.180086 270)
			(size 0.4318 0.4318)
			(layers "F.Cu" "F.Mask" "F.Paste")
			(net "PVCCIN_CPU0")
		)
		(pad "BW35" smd circle
			(at -9.752838 0.180086 270)
			(size 0.4318 0.4318)
			(layers "F.Cu" "F.Mask" "F.Paste")
			(net "PVCCIN_CPU0")
		)
		(pad "BW37" smd circle
			(at -8.124952 0.180086 270)
			(size 0.4318 0.4318)
			(layers "F.Cu" "F.Mask" "F.Paste")
			(net "PVCCIN_CPU0")
		)
		(pad "BW39" smd circle
			(at -6.49732 0.180086 270)
			(size 0.4318 0.4318)
			(layers "F.Cu" "F.Mask" "F.Paste")
			(net "PVCCIN_CPU0")
		)
		(pad "BW41" smd circle
			(at -4.869434 0.180086 270)
			(size 0.4318 0.4318)
			(layers "F.Cu" "F.Mask" "F.Paste")
			(net "PVCCIN_CPU0")
		)
		(pad "BW43" smd circle
			(at -3.241802 0.180086 270)
			(size 0.4318 0.4318)
			(layers "F.Cu" "F.Mask" "F.Paste")
			(net "PVCCIN_CPU0")
		)
		(pad "BW45" smd circle
			(at -1.613916 0.180086 270)
			(size 0.4318 0.4318)
			(layers "F.Cu" "F.Mask" "F.Paste")
			(net "PVCCIN_CPU0")
		)
		(pad "BW48" smd circle
			(at 2.427732 0.290068 270)
			(size 0.4318 0.4318)
			(layers "F.Cu" "F.Mask" "F.Paste")
			(net "PVCCIN_CPU0")
		)
		(pad "BW50" smd circle
			(at 4.055618 0.290068 270)
			(size 0.4318 0.4318)
			(layers "F.Cu" "F.Mask" "F.Paste")
			(net "PVCCIN_CPU0")
		)
		(pad "BW52" smd circle
			(at 5.68325 0.290068 270)
			(size 0.4318 0.4318)
			(layers "F.Cu" "F.Mask" "F.Paste")
			(net "PVCCIN_CPU0")
		)
		(pad "BW54" smd circle
			(at 7.311136 0.290068 270)
			(size 0.4318 0.4318)
			(layers "F.Cu" "F.Mask" "F.Paste")
			(net "PVCCIN_CPU0")
		)
		(pad "BW56" smd circle
			(at 8.939022 0.290068 270)
			(size 0.4318 0.4318)
			(layers "F.Cu" "F.Mask" "F.Paste")
			(net "PVCCIN_CPU0")
		)
		(pad "BW58" smd circle
			(at 10.566654 0.290068 270)
			(size 0.4318 0.4318)
			(layers "F.Cu" "F.Mask" "F.Paste")
			(net "PVCCIN_CPU0")
		)
		(pad "BW60" smd circle
			(at 12.19454 0.290068 270)
			(size 0.4318 0.4318)
			(layers "F.Cu" "F.Mask" "F.Paste")
			(net "PVCCIN_CPU0")
		)
		(pad "BW62" smd circle
			(at 13.822426 0.290068 270)
			(size 0.4318 0.4318)
			(layers "F.Cu" "F.Mask" "F.Paste")
			(net "PVCCIN_CPU0")
		)
		(pad "BW64" smd circle
			(at 15.450058 0.290068 270)
			(size 0.4318 0.4318)
			(layers "F.Cu" "F.Mask" "F.Paste")
			(net "PVCCIN_CPU0")
		)
		(pad "BW66" smd circle
			(at 17.07769 0.290068 270)
			(size 0.4318 0.4318)
			(layers "F.Cu" "F.Mask" "F.Paste")
			(net "PVCCIN_CPU0")
		)
		(pad "BW68" smd circle
			(at 18.705576 0.290068 270)
			(size 0.4318 0.4318)
			(layers "F.Cu" "F.Mask" "F.Paste")
			(net "PVCCIN_CPU0")
		)
		(pad "BW70" smd circle
			(at 20.333462 0.290068 270)
			(size 0.4318 0.4318)
			(layers "F.Cu" "F.Mask" "F.Paste")
			(net "PVCCIN_CPU0")
		)
		(pad "BW72" smd circle
			(at 21.961094 0.290068 270)
			(size 0.4318 0.4318)
			(layers "F.Cu" "F.Mask" "F.Paste")
			(net "PVCCIN_CPU0")
		)
		(pad "BW74" smd circle
			(at 23.58898 0.290068 270)
			(size 0.4318 0.4318)
			(layers "F.Cu" "F.Mask" "F.Paste")
			(net "PVCCIN_CPU0")
		)
		(pad "BW76" smd circle
			(at 25.216612 0.290068 270)
			(size 0.4318 0.4318)
			(layers "F.Cu" "F.Mask" "F.Paste")
			(net "PVCCIN_CPU0")
		)
		(pad "BW78" smd circle
			(at 26.844498 0.290068 270)
			(size 0.4318 0.4318)
			(layers "F.Cu" "F.Mask" "F.Paste")
			(net "PVCCIN_CPU0")
		)
		(pad "BW80" smd circle
			(at 28.472384 0.290068 270)
			(size 0.4318 0.4318)
			(layers "F.Cu" "F.Mask" "F.Paste")
			(net "PVCCIN_CPU0")
		)
		(pad "BW82" smd circle
			(at 30.100016 0.290068 270)
			(size 0.4318 0.4318)
			(layers "F.Cu" "F.Mask" "F.Paste")
			(net "PVCCIN_CPU0")
		)
		(pad "BW84" smd circle
			(at 31.727902 0.290068 270)
			(size 0.4318 0.4318)
			(layers "F.Cu" "F.Mask" "F.Paste")
			(net "PVCCIN_CPU0")
		)
		(pad "BW86" smd circle
			(at 33.355534 0.290068 270)
			(size 0.4318 0.4318)
			(layers "F.Cu" "F.Mask" "F.Paste")
			(net "PVCCIN_CPU0")
		)
		(pad "BW88" smd circle
			(at 34.98342 0.290068 270)
			(size 0.4318 0.4318)
			(layers "F.Cu" "F.Mask" "F.Paste")
			(net "PVCCIN_CPU0")
		)
		(pad "BW90" smd oval
			(at 36.611306 0.290068)
			(size 0.381 0.4826)
			(drill
				(offset 0 -0.0508)
			)
			(layers "F.Cu" "F.Mask" "F.Paste")
			(net "PVCCIN_CPU0")
		)
		(pad "BY2" smd oval
			(at -36.611306 0.649732 180)
			(size 0.381 0.4826)
			(drill
				(offset 0 -0.0508)
			)
			(layers "F.Cu" "F.Mask" "F.Paste")
			(net "UPI_CPU1_CPU0_P0P1_DN<23>")
		)
		(pad "BY4" smd circle
			(at -34.98342 0.649732 270)
			(size 0.4318 0.4318)
			(layers "F.Cu" "F.Mask" "F.Paste")
			(net "GND")
		)
		(pad "BY6" smd circle
			(at -33.355534 0.649732 270)
			(size 0.4318 0.4318)
			(layers "F.Cu" "F.Mask" "F.Paste")
			(net "UPI_CPU0_CPU1_P1P0_DP<23>")
		)
		(pad "BY8" smd circle
			(at -31.727902 0.649732 270)
			(size 0.4318 0.4318)
			(layers "F.Cu" "F.Mask" "F.Paste")
			(net "GND")
		)
		(pad "BY10" smd circle
			(at -30.100016 0.649732 270)
			(size 0.4318 0.4318)
			(layers "F.Cu" "F.Mask" "F.Paste")
			(net "P5E_CPU0_PE1_RX_DP<7>")
		)
		(pad "BY12" smd circle
			(at -28.472384 0.649732 270)
			(size 0.4318 0.4318)
			(layers "F.Cu" "F.Mask" "F.Paste")
			(net "GND")
		)
		(pad "BY14" smd circle
			(at -26.844498 0.649732 270)
			(size 0.4318 0.4318)
			(layers "F.Cu" "F.Mask" "F.Paste")
			(net "P5E_CPU0_PE1_TX_DP<7>")
		)
		(pad "BY16" smd circle
			(at -25.216612 0.649732 270)
			(size 0.4318 0.4318)
			(layers "F.Cu" "F.Mask" "F.Paste")
			(net "GND")
		)
		(pad "BY18" smd circle
			(at -23.58898 0.649732 270)
			(size 0.4318 0.4318)
			(layers "F.Cu" "F.Mask" "F.Paste")
			(net "DMI_CPU0_PCH_TX_DN<1>")
		)
		(pad "BY20" smd circle
			(at -21.961094 0.649732 270)
			(size 0.4318 0.4318)
			(layers "F.Cu" "F.Mask" "F.Paste")
			(net "GND")
		)
		(pad "BY22" smd circle
			(at -20.333462 0.649732 270)
			(size 0.4318 0.4318)
			(layers "F.Cu" "F.Mask" "F.Paste")
			(net "I3C_SPD_DDRABCD_CPU0_SDA")
		)
		(pad "BY24" smd circle
			(at -18.705576 0.649732 270)
			(size 0.4318 0.4318)
			(layers "F.Cu" "F.Mask" "F.Paste")
			(net "PD_EXT_CLK_SEL_CPU0")
		)
		(pad "BY26" smd circle
			(at -17.07769 0.649732 270)
			(size 0.4318 0.4318)
			(layers "F.Cu" "F.Mask" "F.Paste")
			(net "SMB_PEHPCPU0_GTL_SDA")
		)
		(pad "BY28" smd circle
			(at -15.450058 0.649732 270)
			(size 0.4318 0.4318)
			(layers "F.Cu" "F.Mask" "F.Paste")
			(net "TP_TRC_CPU0_PTI1_CLK")
		)
		(pad "BY30" smd circle
			(at -13.822426 0.649732 270)
			(size 0.4318 0.4318)
			(layers "F.Cu" "F.Mask" "F.Paste")
			(net "TP_TRC_CPU0_PTI<3>")
		)
		(pad "BY32" smd circle
			(at -12.19454 0.649732 270)
			(size 0.4318 0.4318)
			(layers "F.Cu" "F.Mask" "F.Paste")
			(net "PVCCIN_CPU0")
		)
		(pad "BY34" smd circle
			(at -10.566654 0.649732 270)
			(size 0.4318 0.4318)
			(layers "F.Cu" "F.Mask" "F.Paste")
			(net "PVCCIN_CPU0")
		)
		(pad "BY36" smd circle
			(at -8.939022 0.649732 270)
			(size 0.4318 0.4318)
			(layers "F.Cu" "F.Mask" "F.Paste")
			(net "PVCCIN_CPU0")
		)
		(pad "BY38" smd circle
			(at -7.311136 0.649732 270)
			(size 0.4318 0.4318)
			(layers "F.Cu" "F.Mask" "F.Paste")
			(net "PVCCIN_CPU0")
		)
		(pad "BY40" smd circle
			(at -5.68325 0.649732 270)
			(size 0.4318 0.4318)
			(layers "F.Cu" "F.Mask" "F.Paste")
			(net "PVCCIN_CPU0")
		)
		(pad "BY42" smd circle
			(at -4.055618 0.649732 270)
			(size 0.4318 0.4318)
			(layers "F.Cu" "F.Mask" "F.Paste")
			(net "PVCCIN_CPU0")
		)
		(pad "BY44" smd circle
			(at -2.427732 0.649732 270)
			(size 0.4318 0.4318)
			(layers "F.Cu" "F.Mask" "F.Paste")
			(net "PVCCIN_CPU0")
		)
		(pad "BY47" smd circle
			(at 1.613916 0.759714 270)
			(size 0.4318 0.4318)
			(layers "F.Cu" "F.Mask" "F.Paste")
			(net "PVCCIN_CPU0")
		)
		(pad "BY49" smd circle
			(at 3.241802 0.759714 270)
			(size 0.4318 0.4318)
			(layers "F.Cu" "F.Mask" "F.Paste")
			(net "PVCCIN_CPU0")
		)
		(pad "BY51" smd circle
			(at 4.869434 0.759714 270)
			(size 0.4318 0.4318)
			(layers "F.Cu" "F.Mask" "F.Paste")
			(net "PVCCIN_CPU0")
		)
		(pad "BY53" smd circle
			(at 6.49732 0.759714 270)
			(size 0.4318 0.4318)
			(layers "F.Cu" "F.Mask" "F.Paste")
			(net "PVCCIN_CPU0")
		)
		(pad "BY55" smd circle
			(at 8.124952 0.759714 270)
			(size 0.4318 0.4318)
			(layers "F.Cu" "F.Mask" "F.Paste")
			(net "PVCCIN_CPU0")
		)
		(pad "BY57" smd circle
			(at 9.752838 0.759714 270)
			(size 0.4318 0.4318)
			(layers "F.Cu" "F.Mask" "F.Paste")
			(net "PVCCIN_CPU0")
		)
		(pad "BY59" smd circle
			(at 11.380724 0.759714 270)
			(size 0.4318 0.4318)
			(layers "F.Cu" "F.Mask" "F.Paste")
			(net "PVCCIN_CPU0")
		)
		(pad "BY61" smd circle
			(at 13.008356 0.759714 270)
			(size 0.4318 0.4318)
			(layers "F.Cu" "F.Mask" "F.Paste")
			(net "PVCCIN_CPU0")
		)
		(pad "BY63" smd circle
			(at 14.635988 0.759714 270)
			(size 0.4318 0.4318)
			(layers "F.Cu" "F.Mask" "F.Paste")
			(net "PVCCIN_CPU0")
		)
		(pad "BY65" smd circle
			(at 16.263874 0.759714 270)
			(size 0.4318 0.4318)
			(layers "F.Cu" "F.Mask" "F.Paste")
			(net "PVCCIN_CPU0")
		)
		(pad "BY67" smd circle
			(at 17.89176 0.759714 270)
			(size 0.4318 0.4318)
			(layers "F.Cu" "F.Mask" "F.Paste")
			(net "PVCCIN_CPU0")
		)
		(pad "BY69" smd circle
			(at 19.519392 0.759714 270)
			(size 0.4318 0.4318)
			(layers "F.Cu" "F.Mask" "F.Paste")
			(net "PVCCIN_CPU0")
		)
		(pad "BY71" smd circle
			(at 21.147278 0.759714 270)
			(size 0.4318 0.4318)
			(layers "F.Cu" "F.Mask" "F.Paste")
			(net "PVCCIN_CPU0")
		)
		(pad "BY73" smd circle
			(at 22.77491 0.759714 270)
			(size 0.4318 0.4318)
			(layers "F.Cu" "F.Mask" "F.Paste")
			(net "PVCCIN_CPU0")
		)
		(pad "BY75" smd circle
			(at 24.402796 0.759714 270)
			(size 0.4318 0.4318)
			(layers "F.Cu" "F.Mask" "F.Paste")
			(net "PVCCIN_CPU0")
		)
		(pad "BY77" smd circle
			(at 26.030682 0.759714 270)
			(size 0.4318 0.4318)
			(layers "F.Cu" "F.Mask" "F.Paste")
			(net "PVCCIN_CPU0")
		)
		(pad "BY79" smd circle
			(at 27.658314 0.759714 270)
			(size 0.4318 0.4318)
			(layers "F.Cu" "F.Mask" "F.Paste")
			(net "PVCCIN_CPU0")
		)
		(pad "BY81" smd circle
			(at 29.2862 0.759714 270)
			(size 0.4318 0.4318)
			(layers "F.Cu" "F.Mask" "F.Paste")
			(net "PVCCIN_CPU0")
		)
		(pad "BY83" smd circle
			(at 30.914086 0.759714 270)
			(size 0.4318 0.4318)
			(layers "F.Cu" "F.Mask" "F.Paste")
			(net "PVCCIN_CPU0")
		)
		(pad "BY85" smd circle
			(at 32.541718 0.759714 270)
			(size 0.4318 0.4318)
			(layers "F.Cu" "F.Mask" "F.Paste")
			(net "PVCCIN_CPU0")
		)
		(pad "BY87" smd circle
			(at 34.169604 0.759714 270)
			(size 0.4318 0.4318)
			(layers "F.Cu" "F.Mask" "F.Paste")
			(net "PVCCIN_CPU0")
		)
		(pad "BY89" smd circle
			(at 35.797236 0.759714 270)
			(size 0.4318 0.4318)
			(layers "F.Cu" "F.Mask" "F.Paste")
			(net "PVCCIN_CPU0")
		)
		(pad "C5" smd oval
			(at -34.169604 -26.134314 135)
			(size 0.381 0.4826)
			(drill
				(offset 0 -0.0508)
			)
			(layers "F.Cu" "F.Mask" "F.Paste")
			(net "GND")
		)
		(pad "C7" smd oval
			(at -32.541718 -26.134314 135)
			(size 0.381 0.4826)
			(drill
				(offset 0 -0.0508)
			)
			(layers "F.Cu" "F.Mask" "F.Paste")
			(net "M_A_CPU0_SB_DQ<29>")
		)
		(pad "C9" smd oval
			(at -30.914086 -26.134314 90)
			(size 0.381 0.4826)
			(drill
				(offset 0 -0.0508)
			)
			(layers "F.Cu" "F.Mask" "F.Paste")
			(net "M_A_CPU0_SB_DQS_DP<3>")
		)
		(pad "C11" smd circle
			(at -29.2862 -26.134314 270)
			(size 0.4318 0.4318)
			(layers "F.Cu" "F.Mask" "F.Paste")
			(net "M_A_CPU0_SB_DQ<24>")
		)
		(pad "C13" smd circle
			(at -27.658314 -26.134314 270)
			(size 0.4318 0.4318)
			(layers "F.Cu" "F.Mask" "F.Paste")
			(net "M_B_CPU0_SB_DQ<28>")
		)
		(pad "C15" smd circle
			(at -26.030682 -26.134314 270)
			(size 0.4318 0.4318)
			(layers "F.Cu" "F.Mask" "F.Paste")
			(net "M_B_CPU0_SB_DQS_DP<3>")
		)
		(pad "C17" smd circle
			(at -24.402796 -26.134314 270)
			(size 0.4318 0.4318)
			(layers "F.Cu" "F.Mask" "F.Paste")
			(net "M_B_CPU0_SB_DQ<24>")
		)
		(pad "C19" smd circle
			(at -22.77491 -26.134314 270)
			(size 0.4318 0.4318)
			(layers "F.Cu" "F.Mask" "F.Paste")
			(net "M_A_CPU0_SB_DQ<21>")
		)
		(pad "C21" smd circle
			(at -21.147278 -26.134314 270)
			(size 0.4318 0.4318)
			(layers "F.Cu" "F.Mask" "F.Paste")
			(net "M_A_CPU0_SB_DQS_DP<2>")
		)
		(pad "C23" smd circle
			(at -19.519392 -26.134314 270)
			(size 0.4318 0.4318)
			(layers "F.Cu" "F.Mask" "F.Paste")
			(net "M_A_CPU0_SB_DQ<16>")
		)
		(pad "C25" smd circle
			(at -17.89176 -26.134314 270)
			(size 0.4318 0.4318)
			(layers "F.Cu" "F.Mask" "F.Paste")
			(net "M_A_CPU0_SB_DQ<13>")
		)
		(pad "C27" smd circle
			(at -16.263874 -26.134314 270)
			(size 0.4318 0.4318)
			(layers "F.Cu" "F.Mask" "F.Paste")
			(net "M_A_CPU0_SB_DQS_DP<1>")
		)
		(pad "C29" smd circle
			(at -14.635988 -26.134314 270)
			(size 0.4318 0.4318)
			(layers "F.Cu" "F.Mask" "F.Paste")
			(net "M_A_CPU0_SB_DQ<8>")
		)
		(pad "C31" smd circle
			(at -13.008356 -26.134314 270)
			(size 0.4318 0.4318)
			(layers "F.Cu" "F.Mask" "F.Paste")
			(net "M_A_CPU0_SB_CB<1>")
		)
		(pad "C33" smd circle
			(at -11.380724 -26.134314 270)
			(size 0.4318 0.4318)
			(layers "F.Cu" "F.Mask" "F.Paste")
			(net "M_A_CPU0_SB_DQS_DP<9>")
		)
		(pad "C35" smd circle
			(at -9.752838 -26.134314 270)
			(size 0.4318 0.4318)
			(layers "F.Cu" "F.Mask" "F.Paste")
			(net "M_A_CPU0_SB_CB<4>")
		)
		(pad "C37" smd circle
			(at -8.124952 -26.134314 270)
			(size 0.4318 0.4318)
			(layers "F.Cu" "F.Mask" "F.Paste")
			(net "M_A_CPU0_SB_CS_N<1>")
		)
		(pad "C39" smd circle
			(at -6.49732 -26.134314 270)
			(size 0.4318 0.4318)
			(layers "F.Cu" "F.Mask" "F.Paste")
			(net "GND")
		)
		(pad "C41" smd circle
			(at -4.869434 -26.134314 270)
			(size 0.4318 0.4318)
			(layers "F.Cu" "F.Mask" "F.Paste")
			(net "M_A_CPU0_SB_CA<2>")
		)
		(pad "C43" smd circle
			(at -3.241802 -26.134314 270)
			(size 0.4318 0.4318)
			(layers "F.Cu" "F.Mask" "F.Paste")
			(net "M_A_CPU0_CLK_DP<0>")
		)
		(pad "C45" smd oval
			(at -1.613916 -26.134314 45)
			(size 0.381 0.4826)
			(drill
				(offset 0 -0.0508)
			)
			(layers "F.Cu" "F.Mask" "F.Paste")
			(net "GND")
		)
		(pad "C48" smd oval
			(at 2.427732 -26.024586 135)
			(size 0.381 0.4826)
			(drill
				(offset 0 -0.0508)
			)
			(layers "F.Cu" "F.Mask" "F.Paste")
			(net "M_A_CPU0_SA_CA<6>")
		)
		(pad "C50" smd circle
			(at 4.055618 -26.024586 270)
			(size 0.4318 0.4318)
			(layers "F.Cu" "F.Mask" "F.Paste")
			(net "M_A_CPU0_SA_CA<4>")
		)
		(pad "C52" smd circle
			(at 5.68325 -26.024586 270)
			(size 0.4318 0.4318)
			(layers "F.Cu" "F.Mask" "F.Paste")
			(net "GND")
		)
		(pad "C54" smd circle
			(at 7.311136 -26.024586 270)
			(size 0.4318 0.4318)
			(layers "F.Cu" "F.Mask" "F.Paste")
			(net "M_A_CPU0_SA_CS_N<0>")
		)
		(pad "C56" smd circle
			(at 8.939022 -26.024586 270)
			(size 0.4318 0.4318)
			(layers "F.Cu" "F.Mask" "F.Paste")
			(net "M_A_CPU0_SA_CB<5>")
		)
		(pad "C58" smd circle
			(at 10.566654 -26.024586 270)
			(size 0.4318 0.4318)
			(layers "F.Cu" "F.Mask" "F.Paste")
			(net "M_A_CPU0_SA_DQS_DP<4>")
		)
		(pad "C60" smd circle
			(at 12.19454 -26.024586 270)
			(size 0.4318 0.4318)
			(layers "F.Cu" "F.Mask" "F.Paste")
			(net "M_A_CPU0_SA_CB<0>")
		)
		(pad "C62" smd circle
			(at 13.822426 -26.024586 270)
			(size 0.4318 0.4318)
			(layers "F.Cu" "F.Mask" "F.Paste")
			(net "M_A_CPU0_SA_DQ<29>")
		)
		(pad "C64" smd circle
			(at 15.450058 -26.024586 270)
			(size 0.4318 0.4318)
			(layers "F.Cu" "F.Mask" "F.Paste")
			(net "M_A_CPU0_SA_DQS_DP<3>")
		)
		(pad "C66" smd circle
			(at 17.07769 -26.024586 270)
			(size 0.4318 0.4318)
			(layers "F.Cu" "F.Mask" "F.Paste")
			(net "M_A_CPU0_SA_DQ<24>")
		)
		(pad "C68" smd circle
			(at 18.705576 -26.024586 270)
			(size 0.4318 0.4318)
			(layers "F.Cu" "F.Mask" "F.Paste")
			(net "M_A_CPU0_SA_DQ<21>")
		)
		(pad "C70" smd circle
			(at 20.333462 -26.024586 270)
			(size 0.4318 0.4318)
			(layers "F.Cu" "F.Mask" "F.Paste")
			(net "M_A_CPU0_SA_DQS_DP<2>")
		)
		(pad "C72" smd circle
			(at 21.961094 -26.024586 270)
			(size 0.4318 0.4318)
			(layers "F.Cu" "F.Mask" "F.Paste")
			(net "GND")
		)
		(pad "C74" smd circle
			(at 23.58898 -26.024586 270)
			(size 0.4318 0.4318)
			(layers "F.Cu" "F.Mask" "F.Paste")
			(net "GND")
		)
		(pad "C76" smd circle
			(at 25.216612 -26.024586 270)
			(size 0.4318 0.4318)
			(layers "F.Cu" "F.Mask" "F.Paste")
			(net "M_A_CPU0_SA_DQ<4>")
		)
		(pad "C78" smd circle
			(at 26.844498 -26.024586 270)
			(size 0.4318 0.4318)
			(layers "F.Cu" "F.Mask" "F.Paste")
			(net "GND")
		)
		(pad "C80" smd circle
			(at 28.472384 -26.024586 270)
			(size 0.4318 0.4318)
			(layers "F.Cu" "F.Mask" "F.Paste")
			(net "GND")
		)
		(pad "C82" smd circle
			(at 30.100016 -26.024586 270)
			(size 0.4318 0.4318)
			(layers "F.Cu" "F.Mask" "F.Paste")
			(net "GND")
		)
		(pad "C84" smd oval
			(at 31.727902 -26.024586 45)
			(size 0.381 0.4826)
			(drill
				(offset 0 -0.0508)
			)
			(layers "F.Cu" "F.Mask" "F.Paste")
			(net "PVCCFA_EHV_FIVRA_CPU0")
		)
		(pad "C86" smd oval
			(at 33.355534 -26.024586 45)
			(size 0.381 0.4826)
			(drill
				(offset 0 -0.0508)
			)
			(layers "F.Cu" "F.Mask" "F.Paste")
			(net "GND")
		)
		(pad "C88" smd oval
			(at 34.98342 -26.024586 45)
			(size 0.381 0.4826)
			(drill
				(offset 0 -0.0508)
			)
			(layers "F.Cu" "F.Mask" "F.Paste")
			(net "PVCCFA_EHV_FIVRA_CPU0")
		)
		(pad "CA3" smd circle
			(at -35.797236 1.119886 270)
			(size 0.4318 0.4318)
			(layers "F.Cu" "F.Mask" "F.Paste")
			(net "GND")
		)
		(pad "CA5" smd circle
			(at -34.169604 1.119886 270)
			(size 0.4318 0.4318)
			(layers "F.Cu" "F.Mask" "F.Paste")
			(net "UPI_CPU0_CPU1_P1P0_DN<22>")
		)
		(pad "CA7" smd circle
			(at -32.541718 1.119886 270)
			(size 0.4318 0.4318)
			(layers "F.Cu" "F.Mask" "F.Paste")
			(net "PVCCD_HV_CPU0")
		)
		(pad "CA9" smd circle
			(at -30.914086 1.119886 270)
			(size 0.4318 0.4318)
			(layers "F.Cu" "F.Mask" "F.Paste")
			(net "P5E_CPU0_PE1_RX_DP<6>")
		)
		(pad "CA11" smd circle
			(at -29.2862 1.119886 270)
			(size 0.4318 0.4318)
			(layers "F.Cu" "F.Mask" "F.Paste")
			(net "VSENSE_PVCCINFAON_CPU0_DP")
		)
		(pad "CA13" smd circle
			(at -27.658314 1.119886 270)
			(size 0.4318 0.4318)
			(layers "F.Cu" "F.Mask" "F.Paste")
			(net "P5E_CPU0_PE1_TX_DN<7>")
		)
		(pad "CA15" smd circle
			(at -26.030682 1.119886 270)
			(size 0.4318 0.4318)
			(layers "F.Cu" "F.Mask" "F.Paste")
			(net "PVCCINFAON_CPU0")
		)
		(pad "CA17" smd circle
			(at -24.402796 1.119886 270)
			(size 0.4318 0.4318)
			(layers "F.Cu" "F.Mask" "F.Paste")
			(net "DMI_CPU0_PCH_TX_DP<1>")
		)
		(pad "CA19" smd circle
			(at -22.77491 1.119886 270)
			(size 0.4318 0.4318)
			(layers "F.Cu" "F.Mask" "F.Paste")
			(net "DMI_CPU0_PCH_TX_DN<0>")
		)
		(pad "CA21" smd circle
			(at -21.147278 1.119886 270)
			(size 0.4318 0.4318)
			(layers "F.Cu" "F.Mask" "F.Paste")
			(net "NC_CPU0_DMI_APROBE<0>")
		)
		(pad "CA23" smd circle
			(at -19.519392 1.119886 270)
			(size 0.4318 0.4318)
			(layers "F.Cu" "F.Mask" "F.Paste")
			(net "NC_CPU0_UPI1_APROBE<1>")
		)
		(pad "CA25" smd circle
			(at -17.89176 1.119886 270)
			(size 0.4318 0.4318)
			(layers "F.Cu" "F.Mask" "F.Paste")
			(net "SMB_PEHPCPU0_GTL_SCL")
		)
		(pad "CA27" smd circle
			(at -16.263874 1.119886 270)
			(size 0.4318 0.4318)
			(layers "F.Cu" "F.Mask" "F.Paste")
			(net "TP_TRC_CPU0_PTI<6>")
		)
		(pad "CA29" smd circle
			(at -14.635988 1.119886 270)
			(size 0.4318 0.4318)
			(layers "F.Cu" "F.Mask" "F.Paste")
			(net "TP_TRC_CPU0_PTI<4>")
		)
		(pad "CA31" smd circle
			(at -13.008356 1.119886 270)
			(size 0.4318 0.4318)
			(layers "F.Cu" "F.Mask" "F.Paste")
			(net "GND")
		)
		(pad "CA33" smd circle
			(at -11.380724 1.119886 270)
			(size 0.4318 0.4318)
			(layers "F.Cu" "F.Mask" "F.Paste")
			(net "PVCCIN_CPU0")
		)
		(pad "CA35" smd circle
			(at -9.752838 1.119886 270)
			(size 0.4318 0.4318)
			(layers "F.Cu" "F.Mask" "F.Paste")
			(net "PVCCIN_CPU0")
		)
		(pad "CA37" smd circle
			(at -8.124952 1.119886 270)
			(size 0.4318 0.4318)
			(layers "F.Cu" "F.Mask" "F.Paste")
			(net "PVCCIN_CPU0")
		)
		(pad "CA39" smd circle
			(at -6.49732 1.119886 270)
			(size 0.4318 0.4318)
			(layers "F.Cu" "F.Mask" "F.Paste")
			(net "PVCCIN_CPU0")
		)
		(pad "CA41" smd circle
			(at -4.869434 1.119886 270)
			(size 0.4318 0.4318)
			(layers "F.Cu" "F.Mask" "F.Paste")
			(net "PVCCIN_CPU0")
		)
		(pad "CA43" smd circle
			(at -3.241802 1.119886 270)
			(size 0.4318 0.4318)
			(layers "F.Cu" "F.Mask" "F.Paste")
			(net "PVCCIN_CPU0")
		)
		(pad "CA45" smd circle
			(at -1.613916 1.119886 270)
			(size 0.4318 0.4318)
			(layers "F.Cu" "F.Mask" "F.Paste")
			(net "PVCCIN_CPU0")
		)
		(pad "CA48" smd circle
			(at 2.427732 1.229614 270)
			(size 0.4318 0.4318)
			(layers "F.Cu" "F.Mask" "F.Paste")
			(net "PVCCIN_CPU0")
		)
		(pad "CA50" smd circle
			(at 4.055618 1.229614 270)
			(size 0.4318 0.4318)
			(layers "F.Cu" "F.Mask" "F.Paste")
			(net "PVCCIN_CPU0")
		)
		(pad "CA52" smd circle
			(at 5.68325 1.229614 270)
			(size 0.4318 0.4318)
			(layers "F.Cu" "F.Mask" "F.Paste")
			(net "PVCCIN_CPU0")
		)
		(pad "CA54" smd circle
			(at 7.311136 1.229614 270)
			(size 0.4318 0.4318)
			(layers "F.Cu" "F.Mask" "F.Paste")
			(net "PVCCIN_CPU0")
		)
		(pad "CA56" smd circle
			(at 8.939022 1.229614 270)
			(size 0.4318 0.4318)
			(layers "F.Cu" "F.Mask" "F.Paste")
			(net "PVCCIN_CPU0")
		)
		(pad "CA58" smd circle
			(at 10.566654 1.229614 270)
			(size 0.4318 0.4318)
			(layers "F.Cu" "F.Mask" "F.Paste")
			(net "PVCCIN_CPU0")
		)
		(pad "CA60" smd circle
			(at 12.19454 1.229614 270)
			(size 0.4318 0.4318)
			(layers "F.Cu" "F.Mask" "F.Paste")
			(net "PVCCIN_CPU0")
		)
		(pad "CA62" smd circle
			(at 13.822426 1.229614 270)
			(size 0.4318 0.4318)
			(layers "F.Cu" "F.Mask" "F.Paste")
			(net "PVCCIN_CPU0")
		)
		(pad "CA64" smd circle
			(at 15.450058 1.229614 270)
			(size 0.4318 0.4318)
			(layers "F.Cu" "F.Mask" "F.Paste")
			(net "PVCCIN_CPU0")
		)
		(pad "CA66" smd circle
			(at 17.07769 1.229614 270)
			(size 0.4318 0.4318)
			(layers "F.Cu" "F.Mask" "F.Paste")
			(net "PVCCIN_CPU0")
		)
		(pad "CA68" smd circle
			(at 18.705576 1.229614 270)
			(size 0.4318 0.4318)
			(layers "F.Cu" "F.Mask" "F.Paste")
			(net "PVCCIN_CPU0")
		)
		(pad "CA70" smd circle
			(at 20.333462 1.229614 270)
			(size 0.4318 0.4318)
			(layers "F.Cu" "F.Mask" "F.Paste")
			(net "PVCCIN_CPU0")
		)
		(pad "CA72" smd circle
			(at 21.961094 1.229614 270)
			(size 0.4318 0.4318)
			(layers "F.Cu" "F.Mask" "F.Paste")
			(net "PVCCIN_CPU0")
		)
		(pad "CA74" smd circle
			(at 23.58898 1.229614 270)
			(size 0.4318 0.4318)
			(layers "F.Cu" "F.Mask" "F.Paste")
			(net "PVCCIN_CPU0")
		)
		(pad "CA76" smd circle
			(at 25.216612 1.229614 270)
			(size 0.4318 0.4318)
			(layers "F.Cu" "F.Mask" "F.Paste")
			(net "PVCCIN_CPU0")
		)
		(pad "CA78" smd circle
			(at 26.844498 1.229614 270)
			(size 0.4318 0.4318)
			(layers "F.Cu" "F.Mask" "F.Paste")
			(net "PVCCIN_CPU0")
		)
		(pad "CA80" smd circle
			(at 28.472384 1.229614 270)
			(size 0.4318 0.4318)
			(layers "F.Cu" "F.Mask" "F.Paste")
			(net "PVCCIN_CPU0")
		)
		(pad "CA82" smd circle
			(at 30.100016 1.229614 270)
			(size 0.4318 0.4318)
			(layers "F.Cu" "F.Mask" "F.Paste")
			(net "PVCCIN_CPU0")
		)
		(pad "CA84" smd circle
			(at 31.727902 1.229614 270)
			(size 0.4318 0.4318)
			(layers "F.Cu" "F.Mask" "F.Paste")
			(net "PVCCIN_CPU0")
		)
		(pad "CA86" smd circle
			(at 33.355534 1.229614 270)
			(size 0.4318 0.4318)
			(layers "F.Cu" "F.Mask" "F.Paste")
			(net "PVCCIN_CPU0")
		)
		(pad "CA88" smd circle
			(at 34.98342 1.229614 270)
			(size 0.4318 0.4318)
			(layers "F.Cu" "F.Mask" "F.Paste")
			(net "PVCCIN_CPU0")
		)
		(pad "CA90" smd oval
			(at 36.611306 1.229614)
			(size 0.381 0.4826)
			(drill
				(offset 0 -0.0508)
			)
			(layers "F.Cu" "F.Mask" "F.Paste")
			(net "PVCCIN_CPU0")
		)
		(pad "CB2" smd oval
			(at -36.611306 1.589532 180)
			(size 0.381 0.4826)
			(drill
				(offset 0 -0.0508)
			)
			(layers "F.Cu" "F.Mask" "F.Paste")
			(net "UPI_CPU1_CPU0_P0P1_DP<23>")
		)
		(pad "CB4" smd circle
			(at -34.98342 1.589532 270)
			(size 0.4318 0.4318)
			(layers "F.Cu" "F.Mask" "F.Paste")
			(net "GND")
		)
		(pad "CB6" smd circle
			(at -33.355534 1.589532 270)
			(size 0.4318 0.4318)
			(layers "F.Cu" "F.Mask" "F.Paste")
			(net "UPI_CPU0_CPU1_P1P0_DP<22>")
		)
		(pad "CB8" smd circle
			(at -31.727902 1.589532 270)
			(size 0.4318 0.4318)
			(layers "F.Cu" "F.Mask" "F.Paste")
			(net "GND")
		)
		(pad "CB10" smd circle
			(at -30.100016 1.589532 270)
			(size 0.4318 0.4318)
			(layers "F.Cu" "F.Mask" "F.Paste")
			(net "P5E_CPU0_PE1_RX_DN<6>")
		)
		(pad "CB12" smd circle
			(at -28.472384 1.589532 270)
			(size 0.4318 0.4318)
			(layers "F.Cu" "F.Mask" "F.Paste")
			(net "GND")
		)
		(pad "CB14" smd circle
			(at -26.844498 1.589532 270)
			(size 0.4318 0.4318)
			(layers "F.Cu" "F.Mask" "F.Paste")
			(net "P5E_CPU0_PE1_TX_DN<6>")
		)
		(pad "CB16" smd circle
			(at -25.216612 1.589532 270)
			(size 0.4318 0.4318)
			(layers "F.Cu" "F.Mask" "F.Paste")
			(net "GND")
		)
		(pad "CB18" smd circle
			(at -23.58898 1.589532 270)
			(size 0.4318 0.4318)
			(layers "F.Cu" "F.Mask" "F.Paste")
			(net "DMI_CPU0_PCH_TX_DP<2>")
		)
		(pad "CB20" smd circle
			(at -21.961094 1.589532 270)
			(size 0.4318 0.4318)
			(layers "F.Cu" "F.Mask" "F.Paste")
			(net "GND")
		)
		(pad "CB22" smd circle
			(at -20.333462 1.589532 270)
			(size 0.4318 0.4318)
			(layers "F.Cu" "F.Mask" "F.Paste")
			(net "GND")
		)
		(pad "CB24" smd circle
			(at -18.705576 1.589532 270)
			(size 0.4318 0.4318)
			(layers "F.Cu" "F.Mask" "F.Paste")
			(net "GND")
		)
		(pad "CB26" smd circle
			(at -17.07769 1.589532 270)
			(size 0.4318 0.4318)
			(layers "F.Cu" "F.Mask" "F.Paste")
			(net "GND")
		)
		(pad "CB28" smd circle
			(at -15.450058 1.589532 270)
			(size 0.4318 0.4318)
			(layers "F.Cu" "F.Mask" "F.Paste")
			(net "GND")
		)
		(pad "CB30" smd circle
			(at -13.822426 1.589532 270)
			(size 0.4318 0.4318)
			(layers "F.Cu" "F.Mask" "F.Paste")
			(net "TP_TRC_CPU0_PTI0_CLK")
		)
		(pad "CB32" smd circle
			(at -12.19454 1.589532 270)
			(size 0.4318 0.4318)
			(layers "F.Cu" "F.Mask" "F.Paste")
			(net "GND")
		)
		(pad "CB34" smd circle
			(at -10.566654 1.589532 270)
			(size 0.4318 0.4318)
			(layers "F.Cu" "F.Mask" "F.Paste")
			(net "GND")
		)
		(pad "CB36" smd circle
			(at -8.939022 1.589532 270)
			(size 0.4318 0.4318)
			(layers "F.Cu" "F.Mask" "F.Paste")
			(net "GND")
		)
		(pad "CB38" smd circle
			(at -7.311136 1.589532 270)
			(size 0.4318 0.4318)
			(layers "F.Cu" "F.Mask" "F.Paste")
			(net "GND")
		)
		(pad "CB40" smd circle
			(at -5.68325 1.589532 270)
			(size 0.4318 0.4318)
			(layers "F.Cu" "F.Mask" "F.Paste")
			(net "GND")
		)
		(pad "CB42" smd circle
			(at -4.055618 1.589532 270)
			(size 0.4318 0.4318)
			(layers "F.Cu" "F.Mask" "F.Paste")
			(net "GND")
		)
		(pad "CB44" smd circle
			(at -2.427732 1.589532 270)
			(size 0.4318 0.4318)
			(layers "F.Cu" "F.Mask" "F.Paste")
			(net "GND")
		)
		(pad "CB47" smd circle
			(at 1.613916 1.699514 270)
			(size 0.4318 0.4318)
			(layers "F.Cu" "F.Mask" "F.Paste")
			(net "GND")
		)
		(pad "CB49" smd circle
			(at 3.241802 1.699514 270)
			(size 0.4318 0.4318)
			(layers "F.Cu" "F.Mask" "F.Paste")
			(net "GND")
		)
		(pad "CB51" smd circle
			(at 4.869434 1.699514 270)
			(size 0.4318 0.4318)
			(layers "F.Cu" "F.Mask" "F.Paste")
			(net "GND")
		)
		(pad "CB53" smd circle
			(at 6.49732 1.699514 270)
			(size 0.4318 0.4318)
			(layers "F.Cu" "F.Mask" "F.Paste")
			(net "GND")
		)
		(pad "CB55" smd circle
			(at 8.124952 1.699514 270)
			(size 0.4318 0.4318)
			(layers "F.Cu" "F.Mask" "F.Paste")
			(net "GND")
		)
		(pad "CB57" smd circle
			(at 9.752838 1.699514 270)
			(size 0.4318 0.4318)
			(layers "F.Cu" "F.Mask" "F.Paste")
			(net "GND")
		)
		(pad "CB59" smd circle
			(at 11.380724 1.699514 270)
			(size 0.4318 0.4318)
			(layers "F.Cu" "F.Mask" "F.Paste")
			(net "GND")
		)
		(pad "CB61" smd circle
			(at 13.008356 1.699514 270)
			(size 0.4318 0.4318)
			(layers "F.Cu" "F.Mask" "F.Paste")
			(net "PVCCIN_CPU0")
		)
		(pad "CB63" smd circle
			(at 14.635988 1.699514 270)
			(size 0.4318 0.4318)
			(layers "F.Cu" "F.Mask" "F.Paste")
			(net "GND")
		)
		(pad "CB65" smd circle
			(at 16.263874 1.699514 270)
			(size 0.4318 0.4318)
			(layers "F.Cu" "F.Mask" "F.Paste")
			(net "GND")
		)
		(pad "CB67" smd circle
			(at 17.89176 1.699514 270)
			(size 0.4318 0.4318)
			(layers "F.Cu" "F.Mask" "F.Paste")
			(net "GND")
		)
		(pad "CB69" smd circle
			(at 19.519392 1.699514 270)
			(size 0.4318 0.4318)
			(layers "F.Cu" "F.Mask" "F.Paste")
			(net "GND")
		)
		(pad "CB71" smd circle
			(at 21.147278 1.699514 270)
			(size 0.4318 0.4318)
			(layers "F.Cu" "F.Mask" "F.Paste")
			(net "GND")
		)
		(pad "CB73" smd circle
			(at 22.77491 1.699514 270)
			(size 0.4318 0.4318)
			(layers "F.Cu" "F.Mask" "F.Paste")
			(net "GND")
		)
		(pad "CB75" smd circle
			(at 24.402796 1.699514 270)
			(size 0.4318 0.4318)
			(layers "F.Cu" "F.Mask" "F.Paste")
			(net "PVCCIN_CPU0")
		)
		(pad "CB77" smd circle
			(at 26.030682 1.699514 270)
			(size 0.4318 0.4318)
			(layers "F.Cu" "F.Mask" "F.Paste")
			(net "PVCCIN_CPU0")
		)
		(pad "CB79" smd circle
			(at 27.658314 1.699514 270)
			(size 0.4318 0.4318)
			(layers "F.Cu" "F.Mask" "F.Paste")
			(net "GND")
		)
		(pad "CB81" smd circle
			(at 29.2862 1.699514 270)
			(size 0.4318 0.4318)
			(layers "F.Cu" "F.Mask" "F.Paste")
			(net "GND")
		)
		(pad "CB83" smd circle
			(at 30.914086 1.699514 270)
			(size 0.4318 0.4318)
			(layers "F.Cu" "F.Mask" "F.Paste")
			(net "GND")
		)
		(pad "CB85" smd circle
			(at 32.541718 1.699514 270)
			(size 0.4318 0.4318)
			(layers "F.Cu" "F.Mask" "F.Paste")
			(net "GND")
		)
		(pad "CB87" smd circle
			(at 34.169604 1.699514 270)
			(size 0.4318 0.4318)
			(layers "F.Cu" "F.Mask" "F.Paste")
			(net "GND")
		)
		(pad "CB89" smd circle
			(at 35.797236 1.699514 270)
			(size 0.4318 0.4318)
			(layers "F.Cu" "F.Mask" "F.Paste")
			(net "GND")
		)
		(pad "CC3" smd circle
			(at -35.797236 2.059686 270)
			(size 0.4318 0.4318)
			(layers "F.Cu" "F.Mask" "F.Paste")
			(net "UPI_CPU1_CPU0_P0P1_DN<22>")
		)
		(pad "CC5" smd circle
			(at -34.169604 2.059686 270)
			(size 0.4318 0.4318)
			(layers "F.Cu" "F.Mask" "F.Paste")
			(net "GND")
		)
		(pad "CC7" smd circle
			(at -32.541718 2.059686 270)
			(size 0.4318 0.4318)
			(layers "F.Cu" "F.Mask" "F.Paste")
			(net "UPI_CPU0_CPU1_P1P0_DN<21>")
		)
		(pad "CC9" smd circle
			(at -30.914086 2.059686 270)
			(size 0.4318 0.4318)
			(layers "F.Cu" "F.Mask" "F.Paste")
			(net "GND")
		)
		(pad "CC11" smd circle
			(at -29.2862 2.059686 270)
			(size 0.4318 0.4318)
			(layers "F.Cu" "F.Mask" "F.Paste")
			(net "P5E_CPU0_PE1_RX_DN<5>")
		)
		(pad "CC13" smd circle
			(at -27.658314 2.059686 270)
			(size 0.4318 0.4318)
			(layers "F.Cu" "F.Mask" "F.Paste")
			(net "GND")
		)
		(pad "CC15" smd circle
			(at -26.030682 2.059686 270)
			(size 0.4318 0.4318)
			(layers "F.Cu" "F.Mask" "F.Paste")
			(net "P5E_CPU0_PE1_TX_DP<6>")
		)
		(pad "CC17" smd circle
			(at -24.402796 2.059686 270)
			(size 0.4318 0.4318)
			(layers "F.Cu" "F.Mask" "F.Paste")
			(net "GND")
		)
		(pad "CC19" smd circle
			(at -22.77491 2.059686 270)
			(size 0.4318 0.4318)
			(layers "F.Cu" "F.Mask" "F.Paste")
			(net "DMI_CPU0_PCH_TX_DN<2>")
		)
		(pad "CC21" smd circle
			(at -21.147278 2.059686 270)
			(size 0.4318 0.4318)
			(layers "F.Cu" "F.Mask" "F.Paste")
			(net "NC_CPU0_PE1_APROBE<1>")
		)
		(pad "CC23" smd circle
			(at -19.519392 2.059686 270)
			(size 0.4318 0.4318)
			(layers "F.Cu" "F.Mask" "F.Paste")
			(net "NC_CPU0_PE2_APROBE<0>")
		)
		(pad "CC25" smd circle
			(at -17.89176 2.059686 270)
			(size 0.4318 0.4318)
			(layers "F.Cu" "F.Mask" "F.Paste")
			(net "TP_H_SBLINK7_CPU0_PMDOWN")
		)
		(pad "CC27" smd circle
			(at -16.263874 2.059686 270)
			(size 0.4318 0.4318)
			(layers "F.Cu" "F.Mask" "F.Paste")
			(net "TP_TRC_CPU0_PTI<2>")
		)
		(pad "CC29" smd circle
			(at -14.635988 2.059686 270)
			(size 0.4318 0.4318)
			(layers "F.Cu" "F.Mask" "F.Paste")
			(net "TP_TP_TRC_CPU0_PTI_MON<0>")
		)
		(pad "CC31" smd circle
			(at -13.008356 2.059686 270)
			(size 0.4318 0.4318)
			(layers "F.Cu" "F.Mask" "F.Paste")
			(net "GND")
		)
		(pad "CC33" smd circle
			(at -11.380724 2.059686 270)
			(size 0.4318 0.4318)
			(layers "F.Cu" "F.Mask" "F.Paste")
			(net "PVCCIN_CPU0")
		)
		(pad "CC35" smd circle
			(at -9.752838 2.059686 270)
			(size 0.4318 0.4318)
			(layers "F.Cu" "F.Mask" "F.Paste")
			(net "PVCCIN_CPU0")
		)
		(pad "CC37" smd circle
			(at -8.124952 2.059686 270)
			(size 0.4318 0.4318)
			(layers "F.Cu" "F.Mask" "F.Paste")
			(net "PVCCIN_CPU0")
		)
		(pad "CC39" smd circle
			(at -6.49732 2.059686 270)
			(size 0.4318 0.4318)
			(layers "F.Cu" "F.Mask" "F.Paste")
			(net "PVCCIN_CPU0")
		)
		(pad "CC41" smd circle
			(at -4.869434 2.059686 270)
			(size 0.4318 0.4318)
			(layers "F.Cu" "F.Mask" "F.Paste")
			(net "PVCCIN_CPU0")
		)
		(pad "CC43" smd circle
			(at -3.241802 2.059686 270)
			(size 0.4318 0.4318)
			(layers "F.Cu" "F.Mask" "F.Paste")
			(net "PVCCIN_CPU0")
		)
		(pad "CC45" smd circle
			(at -1.613916 2.059686 270)
			(size 0.4318 0.4318)
			(layers "F.Cu" "F.Mask" "F.Paste")
			(net "PVCCIN_CPU0")
		)
		(pad "CC48" smd circle
			(at 2.427732 2.169668 270)
			(size 0.4318 0.4318)
			(layers "F.Cu" "F.Mask" "F.Paste")
			(net "PVCCIN_CPU0")
		)
		(pad "CC50" smd circle
			(at 4.055618 2.169668 270)
			(size 0.4318 0.4318)
			(layers "F.Cu" "F.Mask" "F.Paste")
			(net "PVCCIN_CPU0")
		)
		(pad "CC52" smd circle
			(at 5.68325 2.169668 270)
			(size 0.4318 0.4318)
			(layers "F.Cu" "F.Mask" "F.Paste")
			(net "PVCCIN_CPU0")
		)
		(pad "CC54" smd circle
			(at 7.311136 2.169668 270)
			(size 0.4318 0.4318)
			(layers "F.Cu" "F.Mask" "F.Paste")
			(net "PVCCIN_CPU0")
		)
		(pad "CC56" smd circle
			(at 8.939022 2.169668 270)
			(size 0.4318 0.4318)
			(layers "F.Cu" "F.Mask" "F.Paste")
			(net "PVCCIN_CPU0")
		)
		(pad "CC58" smd circle
			(at 10.566654 2.169668 270)
			(size 0.4318 0.4318)
			(layers "F.Cu" "F.Mask" "F.Paste")
			(net "PVCCIN_CPU0")
		)
		(pad "CC60" smd circle
			(at 12.19454 2.169668 270)
			(size 0.4318 0.4318)
			(layers "F.Cu" "F.Mask" "F.Paste")
			(net "PVCCIN_CPU0")
		)
		(pad "CC62" smd circle
			(at 13.822426 2.169668 270)
			(size 0.4318 0.4318)
			(layers "F.Cu" "F.Mask" "F.Paste")
			(net "GND")
		)
		(pad "CC64" smd circle
			(at 15.450058 2.169668 270)
			(size 0.4318 0.4318)
			(layers "F.Cu" "F.Mask" "F.Paste")
			(net "NC_CPU0_LGSSPARE4")
		)
		(pad "CC66" smd circle
			(at 17.07769 2.169668 270)
			(size 0.4318 0.4318)
			(layers "F.Cu" "F.Mask" "F.Paste")
			(net "NC_CPU0_MDFI_DIE01_EW1")
		)
		(pad "CC68" smd circle
			(at 18.705576 2.169668 270)
			(size 0.4318 0.4318)
			(layers "F.Cu" "F.Mask" "F.Paste")
			(net "PVPP_HBM_CPU0")
		)
		(pad "CC70" smd circle
			(at 20.333462 2.169668 270)
			(size 0.4318 0.4318)
			(layers "F.Cu" "F.Mask" "F.Paste")
			(net "GND")
		)
		(pad "CC72" smd circle
			(at 21.961094 2.169668 270)
			(size 0.4318 0.4318)
			(layers "F.Cu" "F.Mask" "F.Paste")
			(net "GND")
		)
		(pad "CC74" smd circle
			(at 23.58898 2.169668 270)
			(size 0.4318 0.4318)
			(layers "F.Cu" "F.Mask" "F.Paste")
			(net "GND")
		)
		(pad "CC76" smd circle
			(at 25.216612 2.169668 270)
			(size 0.4318 0.4318)
			(layers "F.Cu" "F.Mask" "F.Paste")
			(net "PVCCIN_CPU0")
		)
		(pad "CC78" smd circle
			(at 26.844498 2.169668 270)
			(size 0.4318 0.4318)
			(layers "F.Cu" "F.Mask" "F.Paste")
			(net "PVCCIN_CPU0")
		)
		(pad "CC80" smd circle
			(at 28.472384 2.169668 270)
			(size 0.4318 0.4318)
			(layers "F.Cu" "F.Mask" "F.Paste")
			(net "PVCCIN_CPU0")
		)
		(pad "CC82" smd circle
			(at 30.100016 2.169668 270)
			(size 0.4318 0.4318)
			(layers "F.Cu" "F.Mask" "F.Paste")
			(net "PVCCIN_CPU0")
		)
		(pad "CC84" smd circle
			(at 31.727902 2.169668 270)
			(size 0.4318 0.4318)
			(layers "F.Cu" "F.Mask" "F.Paste")
			(net "PVCCIN_CPU0")
		)
		(pad "CC86" smd circle
			(at 33.355534 2.169668 270)
			(size 0.4318 0.4318)
			(layers "F.Cu" "F.Mask" "F.Paste")
			(net "PVCCIN_CPU0")
		)
		(pad "CC88" smd circle
			(at 34.98342 2.169668 270)
			(size 0.4318 0.4318)
			(layers "F.Cu" "F.Mask" "F.Paste")
			(net "PVCCIN_CPU0")
		)
		(pad "CC90" smd oval
			(at 36.611306 2.169668)
			(size 0.381 0.4826)
			(drill
				(offset 0 -0.0508)
			)
			(layers "F.Cu" "F.Mask" "F.Paste")
			(net "PVCCIN_CPU0")
		)
		(pad "CD2" smd oval
			(at -36.611306 2.529586 180)
			(size 0.381 0.4826)
			(drill
				(offset 0 -0.0508)
			)
			(layers "F.Cu" "F.Mask" "F.Paste")
			(net "UPI_CPU1_CPU0_P0P1_DP<22>")
		)
		(pad "CD4" smd circle
			(at -34.98342 2.529586 270)
			(size 0.4318 0.4318)
			(layers "F.Cu" "F.Mask" "F.Paste")
			(net "GND")
		)
		(pad "CD6" smd circle
			(at -33.355534 2.529586 270)
			(size 0.4318 0.4318)
			(layers "F.Cu" "F.Mask" "F.Paste")
			(net "UPI_CPU0_CPU1_P1P0_DP<21>")
		)
		(pad "CD8" smd circle
			(at -31.727902 2.529586 270)
			(size 0.4318 0.4318)
			(layers "F.Cu" "F.Mask" "F.Paste")
			(net "GND")
		)
		(pad "CD10" smd circle
			(at -30.100016 2.529586 270)
			(size 0.4318 0.4318)
			(layers "F.Cu" "F.Mask" "F.Paste")
			(net "P5E_CPU0_PE1_RX_DP<5>")
		)
		(pad "CD12" smd circle
			(at -28.472384 2.529586 270)
			(size 0.4318 0.4318)
			(layers "F.Cu" "F.Mask" "F.Paste")
			(net "GND")
		)
		(pad "CD14" smd circle
			(at -26.844498 2.529586 270)
			(size 0.4318 0.4318)
			(layers "F.Cu" "F.Mask" "F.Paste")
			(net "P5E_CPU0_PE1_TX_DP<5>")
		)
		(pad "CD16" smd circle
			(at -25.216612 2.529586 270)
			(size 0.4318 0.4318)
			(layers "F.Cu" "F.Mask" "F.Paste")
			(net "GND")
		)
		(pad "CD18" smd circle
			(at -23.58898 2.529586 270)
			(size 0.4318 0.4318)
			(layers "F.Cu" "F.Mask" "F.Paste")
			(net "DMI_CPU0_PCH_TX_DN<3>")
		)
		(pad "CD20" smd circle
			(at -21.961094 2.529586 270)
			(size 0.4318 0.4318)
			(layers "F.Cu" "F.Mask" "F.Paste")
			(net "GND")
		)
		(pad "CD22" smd circle
			(at -20.333462 2.529586 270)
			(size 0.4318 0.4318)
			(layers "F.Cu" "F.Mask" "F.Paste")
			(net "NC_CPU0_MDFI_DIE10_NS1")
		)
		(pad "CD24" smd circle
			(at -18.705576 2.529586 270)
			(size 0.4318 0.4318)
			(layers "F.Cu" "F.Mask" "F.Paste")
			(net "TP_H_SBLINK4_CPU0_PMDOWN")
		)
		(pad "CD26" smd circle
			(at -17.07769 2.529586 270)
			(size 0.4318 0.4318)
			(layers "F.Cu" "F.Mask" "F.Paste")
			(net "NC_CPU0_MDFI_DIE10_EW0")
		)
		(pad "CD28" smd circle
			(at -15.450058 2.529586 270)
			(size 0.4318 0.4318)
			(layers "F.Cu" "F.Mask" "F.Paste")
			(net "TP_TRC_CPU0_PTI_MON<1>")
		)
		(pad "CD30" smd circle
			(at -13.822426 2.529586 270)
			(size 0.4318 0.4318)
			(layers "F.Cu" "F.Mask" "F.Paste")
			(net "NC_CPU0_MDFI_DIE10_EW1")
		)
		(pad "CD32" smd circle
			(at -12.19454 2.529586 270)
			(size 0.4318 0.4318)
			(layers "F.Cu" "F.Mask" "F.Paste")
			(net "PVCCIN_CPU0")
		)
		(pad "CD34" smd circle
			(at -10.566654 2.529586 270)
			(size 0.4318 0.4318)
			(layers "F.Cu" "F.Mask" "F.Paste")
			(net "PVCCIN_CPU0")
		)
		(pad "CD36" smd circle
			(at -8.939022 2.529586 270)
			(size 0.4318 0.4318)
			(layers "F.Cu" "F.Mask" "F.Paste")
			(net "PVCCIN_CPU0")
		)
		(pad "CD38" smd circle
			(at -7.311136 2.529586 270)
			(size 0.4318 0.4318)
			(layers "F.Cu" "F.Mask" "F.Paste")
			(net "PVCCIN_CPU0")
		)
		(pad "CD40" smd circle
			(at -5.68325 2.529586 270)
			(size 0.4318 0.4318)
			(layers "F.Cu" "F.Mask" "F.Paste")
			(net "PVCCIN_CPU0")
		)
		(pad "CD42" smd circle
			(at -4.055618 2.529586 270)
			(size 0.4318 0.4318)
			(layers "F.Cu" "F.Mask" "F.Paste")
			(net "PVCCIN_CPU0")
		)
		(pad "CD44" smd circle
			(at -2.427732 2.529586 270)
			(size 0.4318 0.4318)
			(layers "F.Cu" "F.Mask" "F.Paste")
			(net "PVCCIN_CPU0")
		)
		(pad "CD47" smd circle
			(at 1.613916 2.639314 270)
			(size 0.4318 0.4318)
			(layers "F.Cu" "F.Mask" "F.Paste")
			(net "PVCCIN_CPU0")
		)
		(pad "CD49" smd circle
			(at 3.241802 2.639314 270)
			(size 0.4318 0.4318)
			(layers "F.Cu" "F.Mask" "F.Paste")
			(net "PVCCIN_CPU0")
		)
		(pad "CD51" smd circle
			(at 4.869434 2.639314 270)
			(size 0.4318 0.4318)
			(layers "F.Cu" "F.Mask" "F.Paste")
			(net "PVCCIN_CPU0")
		)
		(pad "CD53" smd circle
			(at 6.49732 2.639314 270)
			(size 0.4318 0.4318)
			(layers "F.Cu" "F.Mask" "F.Paste")
			(net "PVCCIN_CPU0")
		)
		(pad "CD55" smd circle
			(at 8.124952 2.639314 270)
			(size 0.4318 0.4318)
			(layers "F.Cu" "F.Mask" "F.Paste")
			(net "PVCCIN_CPU0")
		)
		(pad "CD57" smd circle
			(at 9.752838 2.639314 270)
			(size 0.4318 0.4318)
			(layers "F.Cu" "F.Mask" "F.Paste")
			(net "PVCCIN_CPU0")
		)
		(pad "CD59" smd circle
			(at 11.380724 2.639314 270)
			(size 0.4318 0.4318)
			(layers "F.Cu" "F.Mask" "F.Paste")
			(net "PVCCIN_CPU0")
		)
		(pad "CD61" smd circle
			(at 13.008356 2.639314 270)
			(size 0.4318 0.4318)
			(layers "F.Cu" "F.Mask" "F.Paste")
			(net "GND")
		)
		(pad "CD63" smd circle
			(at 14.635988 2.639314 270)
			(size 0.4318 0.4318)
			(layers "F.Cu" "F.Mask" "F.Paste")
			(net "SMB_S3M_CPU0_SDA")
		)
		(pad "CD65" smd circle
			(at 16.263874 2.639314 270)
			(size 0.4318 0.4318)
			(layers "F.Cu" "F.Mask" "F.Paste")
			(net "TP_SGPIO_S3M_CPU0_RST_R_N")
		)
		(pad "CD67" smd circle
			(at 17.89176 2.639314 270)
			(size 0.4318 0.4318)
			(layers "F.Cu" "F.Mask" "F.Paste")
			(net "PVPP_HBM_CPU0")
		)
		(pad "CD69" smd circle
			(at 19.519392 2.639314 270)
			(size 0.4318 0.4318)
			(layers "F.Cu" "F.Mask" "F.Paste")
			(net "TP_CPU0_SPARE11")
		)
		(pad "CD71" smd circle
			(at 21.147278 2.639314 270)
			(size 0.4318 0.4318)
			(layers "F.Cu" "F.Mask" "F.Paste")
			(net "NC_CLK_PFT_OUT_CPU0_DP")
		)
		(pad "CD73" smd circle
			(at 22.77491 2.639314 270)
			(size 0.4318 0.4318)
			(layers "F.Cu" "F.Mask" "F.Paste")
			(net "Net_661")
		)
		(pad "CD75" smd circle
			(at 24.402796 2.639314 270)
			(size 0.4318 0.4318)
			(layers "F.Cu" "F.Mask" "F.Paste")
			(net "GND")
		)
		(pad "CD77" smd circle
			(at 26.030682 2.639314 270)
			(size 0.4318 0.4318)
			(layers "F.Cu" "F.Mask" "F.Paste")
			(net "GND")
		)
		(pad "CD79" smd circle
			(at 27.658314 2.639314 270)
			(size 0.4318 0.4318)
			(layers "F.Cu" "F.Mask" "F.Paste")
			(net "PVCCIN_CPU0")
		)
		(pad "CD81" smd circle
			(at 29.2862 2.639314 270)
			(size 0.4318 0.4318)
			(layers "F.Cu" "F.Mask" "F.Paste")
			(net "PVCCIN_CPU0")
		)
		(pad "CD83" smd circle
			(at 30.914086 2.639314 270)
			(size 0.4318 0.4318)
			(layers "F.Cu" "F.Mask" "F.Paste")
			(net "PVCCIN_CPU0")
		)
		(pad "CD85" smd circle
			(at 32.541718 2.639314 270)
			(size 0.4318 0.4318)
			(layers "F.Cu" "F.Mask" "F.Paste")
			(net "PVCCIN_CPU0")
		)
		(pad "CD87" smd circle
			(at 34.169604 2.639314 270)
			(size 0.4318 0.4318)
			(layers "F.Cu" "F.Mask" "F.Paste")
			(net "PVCCIN_CPU0")
		)
		(pad "CD89" smd circle
			(at 35.797236 2.639314 270)
			(size 0.4318 0.4318)
			(layers "F.Cu" "F.Mask" "F.Paste")
			(net "PVCCIN_CPU0")
		)
		(pad "CE1" smd oval
			(at -37.425122 2.999486 180)
			(size 0.381 0.4826)
			(drill
				(offset 0 -0.0508)
			)
			(layers "F.Cu" "F.Mask" "F.Paste")
			(net "UPI_CPU1_CPU0_P0P1_DP<21>")
		)
		(pad "CE3" smd circle
			(at -35.797236 2.999486 270)
			(size 0.4318 0.4318)
			(layers "F.Cu" "F.Mask" "F.Paste")
			(net "GND")
		)
		(pad "CE5" smd circle
			(at -34.169604 2.999486 270)
			(size 0.4318 0.4318)
			(layers "F.Cu" "F.Mask" "F.Paste")
			(net "UPI_CPU0_CPU1_P1P0_DP<20>")
		)
		(pad "CE7" smd circle
			(at -32.541718 2.999486 270)
			(size 0.4318 0.4318)
			(layers "F.Cu" "F.Mask" "F.Paste")
			(net "PVCCD_HV_CPU0")
		)
		(pad "CE9" smd circle
			(at -30.914086 2.999486 270)
			(size 0.4318 0.4318)
			(layers "F.Cu" "F.Mask" "F.Paste")
			(net "P5E_CPU0_PE1_RX_DP<4>")
		)
		(pad "CE11" smd circle
			(at -29.2862 2.999486 270)
			(size 0.4318 0.4318)
			(layers "F.Cu" "F.Mask" "F.Paste")
			(net "VSENSE_PVCCINFAON_CPU0_DN")
		)
		(pad "CE13" smd circle
			(at -27.658314 2.999486 270)
			(size 0.4318 0.4318)
			(layers "F.Cu" "F.Mask" "F.Paste")
			(net "P5E_CPU0_PE1_TX_DN<5>")
		)
		(pad "CE15" smd circle
			(at -26.030682 2.999486 270)
			(size 0.4318 0.4318)
			(layers "F.Cu" "F.Mask" "F.Paste")
			(net "PVCCINFAON_CPU0")
		)
		(pad "CE17" smd circle
			(at -24.402796 2.999486 270)
			(size 0.4318 0.4318)
			(layers "F.Cu" "F.Mask" "F.Paste")
			(net "DMI_CPU0_PCH_TX_DP<3>")
		)
		(pad "CE19" smd circle
			(at -22.77491 2.999486 270)
			(size 0.4318 0.4318)
			(layers "F.Cu" "F.Mask" "F.Paste")
			(net "PVCCINFAON_CPU0")
		)
		(pad "CE21" smd circle
			(at -21.147278 2.999486 270)
			(size 0.4318 0.4318)
			(layers "F.Cu" "F.Mask" "F.Paste")
			(net "NC_CPU0_PE1_APROBE<0>")
		)
		(pad "CE23" smd circle
			(at -19.519392 2.999486 270)
			(size 0.4318 0.4318)
			(layers "F.Cu" "F.Mask" "F.Paste")
			(net "TP_H_SBLINK6_CPU0_PMDOWN")
		)
		(pad "CE25" smd circle
			(at -17.89176 2.999486 270)
			(size 0.4318 0.4318)
			(layers "F.Cu" "F.Mask" "F.Paste")
			(net "TP_H_SBLINK4_CPU0_PMSYNC")
		)
		(pad "CE60" smd circle
			(at 12.19454 3.109468 270)
			(size 0.4318 0.4318)
			(layers "F.Cu" "F.Mask" "F.Paste")
			(net "GND")
		)
		(pad "CE62" smd circle
			(at 13.822426 3.109468 270)
			(size 0.4318 0.4318)
			(layers "F.Cu" "F.Mask" "F.Paste")
			(net "NC_CPU0_LGSSPARE3")
		)
		(pad "CE64" smd circle
			(at 15.450058 3.109468 270)
			(size 0.4318 0.4318)
			(layers "F.Cu" "F.Mask" "F.Paste")
			(net "SMB_S3M_CPU0_SCL")
		)
		(pad "CE66" smd circle
			(at 17.07769 3.109468 270)
			(size 0.4318 0.4318)
			(layers "F.Cu" "F.Mask" "F.Paste")
			(net "GND")
		)
		(pad "CE68" smd circle
			(at 18.705576 3.109468 270)
			(size 0.4318 0.4318)
			(layers "F.Cu" "F.Mask" "F.Paste")
			(net "PVPP_HBM_CPU0")
		)
		(pad "CE70" smd circle
			(at 20.333462 3.109468 270)
			(size 0.4318 0.4318)
			(layers "F.Cu" "F.Mask" "F.Paste")
			(net "NC_CLK_PFT_OUT_CPU0_DN")
		)
		(pad "CE72" smd circle
			(at 21.961094 3.109468 270)
			(size 0.4318 0.4318)
			(layers "F.Cu" "F.Mask" "F.Paste")
			(net "GND")
		)
		(pad "CE74" smd circle
			(at 23.58898 3.109468 270)
			(size 0.4318 0.4318)
			(layers "F.Cu" "F.Mask" "F.Paste")
			(net "PVCCFA_EHV_FIVRA_CPU0")
		)
		(pad "CE76" smd circle
			(at 25.216612 3.109468 270)
			(size 0.4318 0.4318)
			(layers "F.Cu" "F.Mask" "F.Paste")
			(net "GND")
		)
		(pad "CE78" smd circle
			(at 26.844498 3.109468 270)
			(size 0.4318 0.4318)
			(layers "F.Cu" "F.Mask" "F.Paste")
			(net "GND")
		)
		(pad "CE80" smd circle
			(at 28.472384 3.109468 270)
			(size 0.4318 0.4318)
			(layers "F.Cu" "F.Mask" "F.Paste")
			(net "PVCCIN_CPU0")
		)
		(pad "CE82" smd circle
			(at 30.100016 3.109468 270)
			(size 0.4318 0.4318)
			(layers "F.Cu" "F.Mask" "F.Paste")
			(net "PVCCIN_CPU0")
		)
		(pad "CE84" smd circle
			(at 31.727902 3.109468 270)
			(size 0.4318 0.4318)
			(layers "F.Cu" "F.Mask" "F.Paste")
			(net "PVCCIN_CPU0")
		)
		(pad "CE86" smd circle
			(at 33.355534 3.109468 270)
			(size 0.4318 0.4318)
			(layers "F.Cu" "F.Mask" "F.Paste")
			(net "PVCCIN_CPU0")
		)
		(pad "CE88" smd circle
			(at 34.98342 3.109468 270)
			(size 0.4318 0.4318)
			(layers "F.Cu" "F.Mask" "F.Paste")
			(net "PVCCIN_CPU0")
		)
		(pad "CE90" smd oval
			(at 36.611306 3.109468)
			(size 0.381 0.4826)
			(drill
				(offset 0 -0.0508)
			)
			(layers "F.Cu" "F.Mask" "F.Paste")
			(net "PVCCIN_CPU0")
		)
		(pad "CF2" smd circle
			(at -36.611306 3.469132 270)
			(size 0.4318 0.4318)
			(layers "F.Cu" "F.Mask" "F.Paste")
			(net "UPI_CPU1_CPU0_P0P1_DN<21>")
		)
		(pad "CF4" smd circle
			(at -34.98342 3.469132 270)
			(size 0.4318 0.4318)
			(layers "F.Cu" "F.Mask" "F.Paste")
			(net "GND")
		)
		(pad "CF6" smd circle
			(at -33.355534 3.469132 270)
			(size 0.4318 0.4318)
			(layers "F.Cu" "F.Mask" "F.Paste")
			(net "UPI_CPU0_CPU1_P1P0_DN<20>")
		)
		(pad "CF8" smd circle
			(at -31.727902 3.469132 270)
			(size 0.4318 0.4318)
			(layers "F.Cu" "F.Mask" "F.Paste")
			(net "GND")
		)
		(pad "CF10" smd circle
			(at -30.100016 3.469132 270)
			(size 0.4318 0.4318)
			(layers "F.Cu" "F.Mask" "F.Paste")
			(net "P5E_CPU0_PE1_RX_DN<4>")
		)
		(pad "CF12" smd circle
			(at -28.472384 3.469132 270)
			(size 0.4318 0.4318)
			(layers "F.Cu" "F.Mask" "F.Paste")
			(net "GND")
		)
		(pad "CF14" smd circle
			(at -26.844498 3.469132 270)
			(size 0.4318 0.4318)
			(layers "F.Cu" "F.Mask" "F.Paste")
			(net "P5E_CPU0_PE1_TX_DN<4>")
		)
		(pad "CF16" smd circle
			(at -25.216612 3.469132 270)
			(size 0.4318 0.4318)
			(layers "F.Cu" "F.Mask" "F.Paste")
			(net "GND")
		)
		(pad "CF18" smd circle
			(at -23.58898 3.469132 270)
			(size 0.4318 0.4318)
			(layers "F.Cu" "F.Mask" "F.Paste")
			(net "DMI_CPU0_PCH_TX_DN<4>")
		)
		(pad "CF20" smd circle
			(at -21.961094 3.469132 270)
			(size 0.4318 0.4318)
			(layers "F.Cu" "F.Mask" "F.Paste")
			(net "GND")
		)
		(pad "CF22" smd circle
			(at -20.333462 3.469132 270)
			(size 0.4318 0.4318)
			(layers "F.Cu" "F.Mask" "F.Paste")
			(net "NC_CPU0_MDFI_DIE10_NS0")
		)
		(pad "CF24" smd circle
			(at -18.705576 3.469132 270)
			(size 0.4318 0.4318)
			(layers "F.Cu" "F.Mask" "F.Paste")
			(net "TP_H_SBLINK7_CPU0_PMSYNC")
		)
		(pad "CF26" smd circle
			(at -17.07769 3.469132 270)
			(size 0.4318 0.4318)
			(layers "F.Cu" "F.Mask" "F.Paste")
			(net "H_CPU0_MEMHOT_OUT_LVC1_R_N")
		)
		(pad "CF61" smd circle
			(at 13.008356 3.579114 270)
			(size 0.4318 0.4318)
			(layers "F.Cu" "F.Mask" "F.Paste")
			(net "PUD_PCH_BOOT_MODE_CPU0")
		)
		(pad "CF63" smd circle
			(at 14.635988 3.579114 270)
			(size 0.4318 0.4318)
			(layers "F.Cu" "F.Mask" "F.Paste")
			(net "TP_SGPIO_S3M_CPU0_GSXCLK_R")
		)
		(pad "CF65" smd circle
			(at 16.263874 3.579114 270)
			(size 0.4318 0.4318)
			(layers "F.Cu" "F.Mask" "F.Paste")
			(net "TP_SGPIO_S3M_CPU0_GSXDOUT_R")
		)
		(pad "CF67" smd circle
			(at 17.89176 3.579114 270)
			(size 0.4318 0.4318)
			(layers "F.Cu" "F.Mask" "F.Paste")
			(net "PVPP_HBM_CPU0")
		)
		(pad "CF69" smd circle
			(at 19.519392 3.579114 270)
			(size 0.4318 0.4318)
			(layers "F.Cu" "F.Mask" "F.Paste")
			(net "GND")
		)
		(pad "CF71" smd circle
			(at 21.147278 3.579114 270)
			(size 0.4318 0.4318)
			(layers "F.Cu" "F.Mask" "F.Paste")
			(net "GND")
		)
		(pad "CF73" smd circle
			(at 22.77491 3.579114 270)
			(size 0.4318 0.4318)
			(layers "F.Cu" "F.Mask" "F.Paste")
			(net "Net_685")
		)
		(pad "CF75" smd circle
			(at 24.402796 3.579114 270)
			(size 0.4318 0.4318)
			(layers "F.Cu" "F.Mask" "F.Paste")
			(net "Net_688")
		)
		(pad "CF77" smd circle
			(at 26.030682 3.579114 270)
			(size 0.4318 0.4318)
			(layers "F.Cu" "F.Mask" "F.Paste")
			(net "Net_666")
		)
		(pad "CF79" smd circle
			(at 27.658314 3.579114 270)
			(size 0.4318 0.4318)
			(layers "F.Cu" "F.Mask" "F.Paste")
			(net "PVCCIN_CPU0")
		)
		(pad "CF81" smd circle
			(at 29.2862 3.579114 270)
			(size 0.4318 0.4318)
			(layers "F.Cu" "F.Mask" "F.Paste")
			(net "PVCCIN_CPU0")
		)
		(pad "CF83" smd circle
			(at 30.914086 3.579114 270)
			(size 0.4318 0.4318)
			(layers "F.Cu" "F.Mask" "F.Paste")
			(net "PVCCIN_CPU0")
		)
		(pad "CF85" smd circle
			(at 32.541718 3.579114 270)
			(size 0.4318 0.4318)
			(layers "F.Cu" "F.Mask" "F.Paste")
			(net "PVCCIN_CPU0")
		)
		(pad "CF87" smd circle
			(at 34.169604 3.579114 270)
			(size 0.4318 0.4318)
			(layers "F.Cu" "F.Mask" "F.Paste")
			(net "PVCCIN_CPU0")
		)
		(pad "CF89" smd circle
			(at 35.797236 3.579114 270)
			(size 0.4318 0.4318)
			(layers "F.Cu" "F.Mask" "F.Paste")
			(net "PVCCIN_CPU0")
		)
		(pad "CF91" smd oval
			(at 37.425122 3.579114)
			(size 0.381 0.4826)
			(drill
				(offset 0 -0.0508)
			)
			(layers "F.Cu" "F.Mask" "F.Paste")
			(net "PVCCIN_CPU0")
		)
		(pad "CG1" smd oval
			(at -37.425122 3.939286 180)
			(size 0.381 0.4826)
			(drill
				(offset 0 -0.0508)
			)
			(layers "F.Cu" "F.Mask" "F.Paste")
			(net "GND")
		)
		(pad "CG3" smd circle
			(at -35.797236 3.939286 270)
			(size 0.4318 0.4318)
			(layers "F.Cu" "F.Mask" "F.Paste")
			(net "UPI_CPU1_CPU0_P0P1_DN<20>")
		)
		(pad "CG5" smd circle
			(at -34.169604 3.939286 270)
			(size 0.4318 0.4318)
			(layers "F.Cu" "F.Mask" "F.Paste")
			(net "GND")
		)
		(pad "CG7" smd circle
			(at -32.541718 3.939286 270)
			(size 0.4318 0.4318)
			(layers "F.Cu" "F.Mask" "F.Paste")
			(net "UPI_CPU0_CPU1_P1P0_DN<19>")
		)
		(pad "CG9" smd circle
			(at -30.914086 3.939286 270)
			(size 0.4318 0.4318)
			(layers "F.Cu" "F.Mask" "F.Paste")
			(net "GND")
		)
		(pad "CG11" smd circle
			(at -29.2862 3.939286 270)
			(size 0.4318 0.4318)
			(layers "F.Cu" "F.Mask" "F.Paste")
			(net "P5E_CPU0_PE1_RX_DN<3>")
		)
		(pad "CG13" smd circle
			(at -27.658314 3.939286 270)
			(size 0.4318 0.4318)
			(layers "F.Cu" "F.Mask" "F.Paste")
			(net "GND")
		)
		(pad "CG15" smd circle
			(at -26.030682 3.939286 270)
			(size 0.4318 0.4318)
			(layers "F.Cu" "F.Mask" "F.Paste")
			(net "P5E_CPU0_PE1_TX_DP<4>")
		)
		(pad "CG17" smd circle
			(at -24.402796 3.939286 270)
			(size 0.4318 0.4318)
			(layers "F.Cu" "F.Mask" "F.Paste")
			(net "GND")
		)
		(pad "CG19" smd circle
			(at -22.77491 3.939286 270)
			(size 0.4318 0.4318)
			(layers "F.Cu" "F.Mask" "F.Paste")
			(net "DMI_CPU0_PCH_TX_DP<4>")
		)
		(pad "CG21" smd circle
			(at -21.147278 3.939286 270)
			(size 0.4318 0.4318)
			(layers "F.Cu" "F.Mask" "F.Paste")
			(net "GND")
		)
		(pad "CG23" smd circle
			(at -19.519392 3.939286 270)
			(size 0.4318 0.4318)
			(layers "F.Cu" "F.Mask" "F.Paste")
			(net "GND")
		)
		(pad "CG25" smd circle
			(at -17.89176 3.939286 270)
			(size 0.4318 0.4318)
			(layers "F.Cu" "F.Mask" "F.Paste")
			(net "GND")
		)
		(pad "CG60" smd circle
			(at 12.19454 4.049268 270)
			(size 0.4318 0.4318)
			(layers "F.Cu" "F.Mask" "F.Paste")
			(net "TP_CPU0_SPARE10")
		)
		(pad "CG62" smd circle
			(at 13.822426 4.049268 270)
			(size 0.4318 0.4318)
			(layers "F.Cu" "F.Mask" "F.Paste")
			(net "GND")
		)
		(pad "CG64" smd circle
			(at 15.450058 4.049268 270)
			(size 0.4318 0.4318)
			(layers "F.Cu" "F.Mask" "F.Paste")
			(net "GND")
		)
		(pad "CG66" smd circle
			(at 17.07769 4.049268 270)
			(size 0.4318 0.4318)
			(layers "F.Cu" "F.Mask" "F.Paste")
			(net "FM_CPU0_SKTOCC_LVT3_N")
		)
		(pad "CG68" smd circle
			(at 18.705576 4.049268 270)
			(size 0.4318 0.4318)
			(layers "F.Cu" "F.Mask" "F.Paste")
			(net "PVPP_HBM_CPU0")
		)
		(pad "CG70" smd circle
			(at 20.333462 4.049268 270)
			(size 0.4318 0.4318)
			(layers "F.Cu" "F.Mask" "F.Paste")
			(net "GND")
		)
		(pad "CG72" smd circle
			(at 21.961094 4.049268 270)
			(size 0.4318 0.4318)
			(layers "F.Cu" "F.Mask" "F.Paste")
			(net "GND")
		)
		(pad "CG74" smd circle
			(at 23.58898 4.049268 270)
			(size 0.4318 0.4318)
			(layers "F.Cu" "F.Mask" "F.Paste")
			(net "GND")
		)
		(pad "CG76" smd circle
			(at 25.216612 4.049268 270)
			(size 0.4318 0.4318)
			(layers "F.Cu" "F.Mask" "F.Paste")
			(net "Net_690")
		)
		(pad "CG78" smd circle
			(at 26.844498 4.049268 270)
			(size 0.4318 0.4318)
			(layers "F.Cu" "F.Mask" "F.Paste")
			(net "GND")
		)
		(pad "CG80" smd circle
			(at 28.472384 4.049268 270)
			(size 0.4318 0.4318)
			(layers "F.Cu" "F.Mask" "F.Paste")
			(net "PVCCIN_CPU0")
		)
		(pad "CG82" smd circle
			(at 30.100016 4.049268 270)
			(size 0.4318 0.4318)
			(layers "F.Cu" "F.Mask" "F.Paste")
			(net "PVCCIN_CPU0")
		)
		(pad "CG84" smd circle
			(at 31.727902 4.049268 270)
			(size 0.4318 0.4318)
			(layers "F.Cu" "F.Mask" "F.Paste")
			(net "PVCCIN_CPU0")
		)
		(pad "CG86" smd circle
			(at 33.355534 4.049268 270)
			(size 0.4318 0.4318)
			(layers "F.Cu" "F.Mask" "F.Paste")
			(net "PVCCIN_CPU0")
		)
		(pad "CG88" smd circle
			(at 34.98342 4.049268 270)
			(size 0.4318 0.4318)
			(layers "F.Cu" "F.Mask" "F.Paste")
			(net "PVCCIN_CPU0")
		)
		(pad "CG90" smd circle
			(at 36.611306 4.049268 270)
			(size 0.4318 0.4318)
			(layers "F.Cu" "F.Mask" "F.Paste")
			(net "PVCCIN_CPU0")
		)
		(pad "CH2" smd circle
			(at -36.611306 4.408932 270)
			(size 0.4318 0.4318)
			(layers "F.Cu" "F.Mask" "F.Paste")
			(net "UPI_CPU1_CPU0_P0P1_DP<20>")
		)
		(pad "CH4" smd circle
			(at -34.98342 4.408932 270)
			(size 0.4318 0.4318)
			(layers "F.Cu" "F.Mask" "F.Paste")
			(net "GND")
		)
		(pad "CH6" smd circle
			(at -33.355534 4.408932 270)
			(size 0.4318 0.4318)
			(layers "F.Cu" "F.Mask" "F.Paste")
			(net "UPI_CPU0_CPU1_P1P0_DP<19>")
		)
		(pad "CH8" smd circle
			(at -31.727902 4.408932 270)
			(size 0.4318 0.4318)
			(layers "F.Cu" "F.Mask" "F.Paste")
			(net "GND")
		)
		(pad "CH10" smd circle
			(at -30.100016 4.408932 270)
			(size 0.4318 0.4318)
			(layers "F.Cu" "F.Mask" "F.Paste")
			(net "P5E_CPU0_PE1_RX_DP<3>")
		)
		(pad "CH12" smd circle
			(at -28.472384 4.408932 270)
			(size 0.4318 0.4318)
			(layers "F.Cu" "F.Mask" "F.Paste")
			(net "GND")
		)
		(pad "CH14" smd circle
			(at -26.844498 4.408932 270)
			(size 0.4318 0.4318)
			(layers "F.Cu" "F.Mask" "F.Paste")
			(net "P5E_CPU0_PE1_TX_DP<3>")
		)
		(pad "CH16" smd circle
			(at -25.216612 4.408932 270)
			(size 0.4318 0.4318)
			(layers "F.Cu" "F.Mask" "F.Paste")
			(net "GND")
		)
		(pad "CH18" smd circle
			(at -23.58898 4.408932 270)
			(size 0.4318 0.4318)
			(layers "F.Cu" "F.Mask" "F.Paste")
			(net "DMI_CPU0_PCH_TX_DP<5>")
		)
		(pad "CH20" smd circle
			(at -21.961094 4.408932 270)
			(size 0.4318 0.4318)
			(layers "F.Cu" "F.Mask" "F.Paste")
			(net "GND")
		)
		(pad "CH22" smd circle
			(at -20.333462 4.408932 270)
			(size 0.4318 0.4318)
			(layers "F.Cu" "F.Mask" "F.Paste")
			(net "PD_CPU0_ENH_MCECC_DIS")
		)
		(pad "CH24" smd circle
			(at -18.705576 4.408932 270)
			(size 0.4318 0.4318)
			(layers "F.Cu" "F.Mask" "F.Paste")
			(net "TP_H_SBLINK6_CPU0_PMSYNC")
		)
		(pad "CH26" smd circle
			(at -17.07769 4.408932 270)
			(size 0.4318 0.4318)
			(layers "F.Cu" "F.Mask" "F.Paste")
			(net "TP_H_SBLINK3_CPU0_PMSYNC")
		)
		(pad "CH61" smd circle
			(at 13.008356 4.518914 270)
			(size 0.4318 0.4318)
			(layers "F.Cu" "F.Mask" "F.Paste")
			(net "TP_CPU0_SPARE9")
		)
		(pad "CH63" smd circle
			(at 14.635988 4.518914 270)
			(size 0.4318 0.4318)
			(layers "F.Cu" "F.Mask" "F.Paste")
			(net "TP_SGPIO_S3M_CPU0_GSXDIN")
		)
		(pad "CH65" smd circle
			(at 16.263874 4.518914 270)
			(size 0.4318 0.4318)
			(layers "F.Cu" "F.Mask" "F.Paste")
			(net "PU_S3M_CPU0_CPLD_STATUS")
		)
		(pad "CH67" smd circle
			(at 17.89176 4.518914 270)
			(size 0.4318 0.4318)
			(layers "F.Cu" "F.Mask" "F.Paste")
			(net "GND")
		)
		(pad "CH69" smd circle
			(at 19.519392 4.518914 270)
			(size 0.4318 0.4318)
			(layers "F.Cu" "F.Mask" "F.Paste")
			(net "NC_CPU0_MDFI_DIE11_EW1")
		)
		(pad "CH71" smd circle
			(at 21.147278 4.518914 270)
			(size 0.4318 0.4318)
			(layers "F.Cu" "F.Mask" "F.Paste")
			(net "TP_PWRGD_S0_PWROK_CPU0_LVC1")
		)
		(pad "CH73" smd circle
			(at 22.77491 4.518914 270)
			(size 0.4318 0.4318)
			(layers "F.Cu" "F.Mask" "F.Paste")
			(net "GND")
		)
		(pad "CH75" smd circle
			(at 24.402796 4.518914 270)
			(size 0.4318 0.4318)
			(layers "F.Cu" "F.Mask" "F.Paste")
			(net "Net_664")
		)
		(pad "CH77" smd circle
			(at 26.030682 4.518914 270)
			(size 0.4318 0.4318)
			(layers "F.Cu" "F.Mask" "F.Paste")
			(net "Net_692")
		)
		(pad "CH79" smd circle
			(at 27.658314 4.518914 270)
			(size 0.4318 0.4318)
			(layers "F.Cu" "F.Mask" "F.Paste")
			(net "GND")
		)
		(pad "CH81" smd circle
			(at 29.2862 4.518914 270)
			(size 0.4318 0.4318)
			(layers "F.Cu" "F.Mask" "F.Paste")
			(net "PVCCIN_CPU0")
		)
		(pad "CH83" smd circle
			(at 30.914086 4.518914 270)
			(size 0.4318 0.4318)
			(layers "F.Cu" "F.Mask" "F.Paste")
			(net "GND")
		)
		(pad "CH85" smd circle
			(at 32.541718 4.518914 270)
			(size 0.4318 0.4318)
			(layers "F.Cu" "F.Mask" "F.Paste")
			(net "GND")
		)
		(pad "CH87" smd circle
			(at 34.169604 4.518914 270)
			(size 0.4318 0.4318)
			(layers "F.Cu" "F.Mask" "F.Paste")
			(net "GND")
		)
		(pad "CH89" smd circle
			(at 35.797236 4.518914 270)
			(size 0.4318 0.4318)
			(layers "F.Cu" "F.Mask" "F.Paste")
			(net "GND")
		)
		(pad "CH91" smd oval
			(at 37.425122 4.518914)
			(size 0.381 0.4826)
			(drill
				(offset 0 -0.0508)
			)
			(layers "F.Cu" "F.Mask" "F.Paste")
			(net "PVCCIN_CPU0")
		)
		(pad "CJ1" smd oval
			(at -37.425122 4.879086 180)
			(size 0.381 0.4826)
			(drill
				(offset 0 -0.0508)
			)
			(layers "F.Cu" "F.Mask" "F.Paste")
			(net "UPI_CPU1_CPU0_P0P1_DP<19>")
		)
		(pad "CJ3" smd circle
			(at -35.797236 4.879086 270)
			(size 0.4318 0.4318)
			(layers "F.Cu" "F.Mask" "F.Paste")
			(net "PVCCINFAON_CPU0")
		)
		(pad "CJ5" smd circle
			(at -34.169604 4.879086 270)
			(size 0.4318 0.4318)
			(layers "F.Cu" "F.Mask" "F.Paste")
			(net "UPI_CPU0_CPU1_P1P0_DP<18>")
		)
		(pad "CJ7" smd circle
			(at -32.541718 4.879086 270)
			(size 0.4318 0.4318)
			(layers "F.Cu" "F.Mask" "F.Paste")
			(net "PVCCINFAON_CPU0")
		)
		(pad "CJ9" smd circle
			(at -30.914086 4.879086 270)
			(size 0.4318 0.4318)
			(layers "F.Cu" "F.Mask" "F.Paste")
			(net "P5E_CPU0_PE1_RX_DP<2>")
		)
		(pad "CJ11" smd circle
			(at -29.2862 4.879086 270)
			(size 0.4318 0.4318)
			(layers "F.Cu" "F.Mask" "F.Paste")
			(net "PVCCINFAON_CPU0")
		)
		(pad "CJ13" smd circle
			(at -27.658314 4.879086 270)
			(size 0.4318 0.4318)
			(layers "F.Cu" "F.Mask" "F.Paste")
			(net "P5E_CPU0_PE1_TX_DN<3>")
		)
		(pad "CJ15" smd circle
			(at -26.030682 4.879086 270)
			(size 0.4318 0.4318)
			(layers "F.Cu" "F.Mask" "F.Paste")
			(net "PVCCINFAON_CPU0")
		)
		(pad "CJ17" smd circle
			(at -24.402796 4.879086 270)
			(size 0.4318 0.4318)
			(layers "F.Cu" "F.Mask" "F.Paste")
			(net "DMI_CPU0_PCH_TX_DN<5>")
		)
		(pad "CJ19" smd circle
			(at -22.77491 4.879086 270)
			(size 0.4318 0.4318)
			(layers "F.Cu" "F.Mask" "F.Paste")
			(net "PVCCINFAON_CPU0")
		)
		(pad "CJ21" smd circle
			(at -21.147278 4.879086 270)
			(size 0.4318 0.4318)
			(layers "F.Cu" "F.Mask" "F.Paste")
			(net "TP_IBL_GRST_WARN_PLD_R_N")
		)
		(pad "CJ23" smd circle
			(at -19.519392 4.879086 270)
			(size 0.4318 0.4318)
			(layers "F.Cu" "F.Mask" "F.Paste")
			(net "TP_I2C_S3M_RTC_CPU0_SDA")
		)
		(pad "CJ25" smd circle
			(at -17.89176 4.879086 270)
			(size 0.4318 0.4318)
			(layers "F.Cu" "F.Mask" "F.Paste")
			(net "TP_I2C_S3M_RTC_CPU0_ALERT_N")
		)
		(pad "CJ60" smd circle
			(at 12.19454 4.989068 270)
			(size 0.4318 0.4318)
			(layers "F.Cu" "F.Mask" "F.Paste")
			(net "GND")
		)
		(pad "CJ62" smd circle
			(at 13.822426 4.989068 270)
			(size 0.4318 0.4318)
			(layers "F.Cu" "F.Mask" "F.Paste")
			(net "NC_CPU0_VIEWPIN_DIE11<0>")
		)
		(pad "CJ64" smd circle
			(at 15.450058 4.989068 270)
			(size 0.4318 0.4318)
			(layers "F.Cu" "F.Mask" "F.Paste")
			(net "PU_S3M_CPU0_CPLD_CONFD")
		)
		(pad "CJ66" smd circle
			(at 17.07769 4.989068 270)
			(size 0.4318 0.4318)
			(layers "F.Cu" "F.Mask" "F.Paste")
			(net "TP_SGPIO_S3M_CPU0_GSXDLOAD_R")
		)
		(pad "CJ68" smd circle
			(at 18.705576 4.989068 270)
			(size 0.4318 0.4318)
			(layers "F.Cu" "F.Mask" "F.Paste")
			(net "NC_CPU0_MDFI_DIE11_NS0")
		)
		(pad "CJ70" smd circle
			(at 20.333462 4.989068 270)
			(size 0.4318 0.4318)
			(layers "F.Cu" "F.Mask" "F.Paste")
			(net "NC_CPU0_MDFI_DIE11_EW0")
		)
		(pad "CJ72" smd circle
			(at 21.961094 4.989068 270)
			(size 0.4318 0.4318)
			(layers "F.Cu" "F.Mask" "F.Paste")
			(net "PUD_XTAL_CPU0_MODE1")
		)
		(pad "CJ74" smd circle
			(at 23.58898 4.989068 270)
			(size 0.4318 0.4318)
			(layers "F.Cu" "F.Mask" "F.Paste")
			(net "Net_687")
		)
		(pad "CJ76" smd circle
			(at 25.216612 4.989068 270)
			(size 0.4318 0.4318)
			(layers "F.Cu" "F.Mask" "F.Paste")
			(net "GND")
		)
		(pad "CJ78" smd circle
			(at 26.844498 4.989068 270)
			(size 0.4318 0.4318)
			(layers "F.Cu" "F.Mask" "F.Paste")
			(net "Net_668")
		)
		(pad "CJ80" smd circle
			(at 28.472384 4.989068 270)
			(size 0.4318 0.4318)
			(layers "F.Cu" "F.Mask" "F.Paste")
			(net "GND")
		)
		(pad "CJ82" smd circle
			(at 30.100016 4.989068 270)
			(size 0.4318 0.4318)
			(layers "F.Cu" "F.Mask" "F.Paste")
			(net "PVCCIN_CPU0")
		)
		(pad "CJ84" smd circle
			(at 31.727902 4.989068 270)
			(size 0.4318 0.4318)
			(layers "F.Cu" "F.Mask" "F.Paste")
			(net "PVCCIN_CPU0")
		)
		(pad "CJ86" smd circle
			(at 33.355534 4.989068 270)
			(size 0.4318 0.4318)
			(layers "F.Cu" "F.Mask" "F.Paste")
			(net "PVCCIN_CPU0")
		)
		(pad "CJ88" smd circle
			(at 34.98342 4.989068 270)
			(size 0.4318 0.4318)
			(layers "F.Cu" "F.Mask" "F.Paste")
			(net "PVCCIN_CPU0")
		)
		(pad "CJ90" smd circle
			(at 36.611306 4.989068 270)
			(size 0.4318 0.4318)
			(layers "F.Cu" "F.Mask" "F.Paste")
			(net "PVCCIN_CPU0")
		)
		(pad "CK2" smd circle
			(at -36.611306 5.348732 270)
			(size 0.4318 0.4318)
			(layers "F.Cu" "F.Mask" "F.Paste")
			(net "UPI_CPU1_CPU0_P0P1_DN<19>")
		)
		(pad "CK4" smd circle
			(at -34.98342 5.348732 270)
			(size 0.4318 0.4318)
			(layers "F.Cu" "F.Mask" "F.Paste")
			(net "GND")
		)
		(pad "CK6" smd circle
			(at -33.355534 5.348732 270)
			(size 0.4318 0.4318)
			(layers "F.Cu" "F.Mask" "F.Paste")
			(net "UPI_CPU0_CPU1_P1P0_DN<18>")
		)
		(pad "CK8" smd circle
			(at -31.727902 5.348732 270)
			(size 0.4318 0.4318)
			(layers "F.Cu" "F.Mask" "F.Paste")
			(net "GND")
		)
		(pad "CK10" smd circle
			(at -30.100016 5.348732 270)
			(size 0.4318 0.4318)
			(layers "F.Cu" "F.Mask" "F.Paste")
			(net "P5E_CPU0_PE1_RX_DN<2>")
		)
		(pad "CK12" smd circle
			(at -28.472384 5.348732 270)
			(size 0.4318 0.4318)
			(layers "F.Cu" "F.Mask" "F.Paste")
			(net "GND")
		)
		(pad "CK14" smd circle
			(at -26.844498 5.348732 270)
			(size 0.4318 0.4318)
			(layers "F.Cu" "F.Mask" "F.Paste")
			(net "P5E_CPU0_PE1_TX_DN<2>")
		)
		(pad "CK16" smd circle
			(at -25.216612 5.348732 270)
			(size 0.4318 0.4318)
			(layers "F.Cu" "F.Mask" "F.Paste")
			(net "GND")
		)
		(pad "CK18" smd circle
			(at -23.58898 5.348732 270)
			(size 0.4318 0.4318)
			(layers "F.Cu" "F.Mask" "F.Paste")
			(net "DMI_CPU0_PCH_TX_DN<6>")
		)
		(pad "CK20" smd circle
			(at -21.961094 5.348732 270)
			(size 0.4318 0.4318)
			(layers "F.Cu" "F.Mask" "F.Paste")
			(net "GND")
		)
		(pad "CK22" smd circle
			(at -20.333462 5.348732 270)
			(size 0.4318 0.4318)
			(layers "F.Cu" "F.Mask" "F.Paste")
			(net "TP_FM_IBL_SYS_RST_CPU0_N")
		)
		(pad "CK24" smd circle
			(at -18.705576 5.348732 270)
			(size 0.4318 0.4318)
			(layers "F.Cu" "F.Mask" "F.Paste")
			(net "TP_CPU0_PWRBTN_N")
		)
		(pad "CK26" smd circle
			(at -17.07769 5.348732 270)
			(size 0.4318 0.4318)
			(layers "F.Cu" "F.Mask" "F.Paste")
			(net "GND")
		)
		(pad "CK61" smd circle
			(at 13.008356 5.458714 270)
			(size 0.4318 0.4318)
			(layers "F.Cu" "F.Mask" "F.Paste")
			(net "TP_CPU0_SPARE8")
		)
		(pad "CK63" smd circle
			(at 14.635988 5.458714 270)
			(size 0.4318 0.4318)
			(layers "F.Cu" "F.Mask" "F.Paste")
			(net "GND")
		)
		(pad "CK65" smd circle
			(at 16.263874 5.458714 270)
			(size 0.4318 0.4318)
			(layers "F.Cu" "F.Mask" "F.Paste")
			(net "FM_S3M_CPU0_CPLD_CONFIG_N")
		)
		(pad "CK67" smd circle
			(at 17.89176 5.458714 270)
			(size 0.4318 0.4318)
			(layers "F.Cu" "F.Mask" "F.Paste")
			(net "NC_CPU0_MDFI_DIE11_NS1")
		)
		(pad "CK69" smd circle
			(at 19.519392 5.458714 270)
			(size 0.4318 0.4318)
			(layers "F.Cu" "F.Mask" "F.Paste")
			(net "GND")
		)
		(pad "CK71" smd circle
			(at 21.147278 5.458714 270)
			(size 0.4318 0.4318)
			(layers "F.Cu" "F.Mask" "F.Paste")
			(net "PU_CPU0_UPI3_AC_COUPLING")
		)
		(pad "CK73" smd circle
			(at 22.77491 5.458714 270)
			(size 0.4318 0.4318)
			(layers "F.Cu" "F.Mask" "F.Paste")
			(net "PVCCFA_EHV_FIVRA_CPU0")
		)
		(pad "CK75" smd circle
			(at 24.402796 5.458714 270)
			(size 0.4318 0.4318)
			(layers "F.Cu" "F.Mask" "F.Paste")
			(net "Net_663")
		)
		(pad "CK77" smd circle
			(at 26.030682 5.458714 270)
			(size 0.4318 0.4318)
			(layers "F.Cu" "F.Mask" "F.Paste")
			(net "Net_693")
		)
		(pad "CK79" smd circle
			(at 27.658314 5.458714 270)
			(size 0.4318 0.4318)
			(layers "F.Cu" "F.Mask" "F.Paste")
			(net "PVCCFA_EHV_FIVRA_CPU0")
		)
		(pad "CK81" smd circle
			(at 29.2862 5.458714 270)
			(size 0.4318 0.4318)
			(layers "F.Cu" "F.Mask" "F.Paste")
			(net "GND")
		)
		(pad "CK83" smd circle
			(at 30.914086 5.458714 270)
			(size 0.4318 0.4318)
			(layers "F.Cu" "F.Mask" "F.Paste")
			(net "PVCCIN_CPU0")
		)
		(pad "CK85" smd circle
			(at 32.541718 5.458714 270)
			(size 0.4318 0.4318)
			(layers "F.Cu" "F.Mask" "F.Paste")
			(net "PVCCIN_CPU0")
		)
		(pad "CK87" smd circle
			(at 34.169604 5.458714 270)
			(size 0.4318 0.4318)
			(layers "F.Cu" "F.Mask" "F.Paste")
			(net "PVCCIN_CPU0")
		)
		(pad "CK89" smd circle
			(at 35.797236 5.458714 270)
			(size 0.4318 0.4318)
			(layers "F.Cu" "F.Mask" "F.Paste")
			(net "PVCCIN_CPU0")
		)
		(pad "CK91" smd oval
			(at 37.425122 5.458714)
			(size 0.381 0.4826)
			(drill
				(offset 0 -0.0508)
			)
			(layers "F.Cu" "F.Mask" "F.Paste")
			(net "PVCCIN_CPU0")
		)
		(pad "CL1" smd oval
			(at -37.425122 5.818886 180)
			(size 0.381 0.4826)
			(drill
				(offset 0 -0.0508)
			)
			(layers "F.Cu" "F.Mask" "F.Paste")
			(net "GND")
		)
		(pad "CL3" smd circle
			(at -35.797236 5.818886 270)
			(size 0.4318 0.4318)
			(layers "F.Cu" "F.Mask" "F.Paste")
			(net "UPI_CPU1_CPU0_P0P1_DN<18>")
		)
		(pad "CL5" smd circle
			(at -34.169604 5.818886 270)
			(size 0.4318 0.4318)
			(layers "F.Cu" "F.Mask" "F.Paste")
			(net "GND")
		)
		(pad "CL7" smd circle
			(at -32.541718 5.818886 270)
			(size 0.4318 0.4318)
			(layers "F.Cu" "F.Mask" "F.Paste")
			(net "UPI_CPU0_CPU1_P1P0_DN<17>")
		)
		(pad "CL9" smd circle
			(at -30.914086 5.818886 270)
			(size 0.4318 0.4318)
			(layers "F.Cu" "F.Mask" "F.Paste")
			(net "GND")
		)
		(pad "CL11" smd circle
			(at -29.2862 5.818886 270)
			(size 0.4318 0.4318)
			(layers "F.Cu" "F.Mask" "F.Paste")
			(net "P5E_CPU0_PE1_RX_DN<1>")
		)
		(pad "CL13" smd circle
			(at -27.658314 5.818886 270)
			(size 0.4318 0.4318)
			(layers "F.Cu" "F.Mask" "F.Paste")
			(net "GND")
		)
		(pad "CL15" smd circle
			(at -26.030682 5.818886 270)
			(size 0.4318 0.4318)
			(layers "F.Cu" "F.Mask" "F.Paste")
			(net "P5E_CPU0_PE1_TX_DP<2>")
		)
		(pad "CL17" smd circle
			(at -24.402796 5.818886 270)
			(size 0.4318 0.4318)
			(layers "F.Cu" "F.Mask" "F.Paste")
			(net "GND")
		)
		(pad "CL19" smd circle
			(at -22.77491 5.818886 270)
			(size 0.4318 0.4318)
			(layers "F.Cu" "F.Mask" "F.Paste")
			(net "DMI_CPU0_PCH_TX_DP<6>")
		)
		(pad "CL21" smd circle
			(at -21.147278 5.818886 270)
			(size 0.4318 0.4318)
			(layers "F.Cu" "F.Mask" "F.Paste")
			(net "TP_IBL_PLT_RST_SYNC_N")
		)
		(pad "CL23" smd circle
			(at -19.519392 5.818886 270)
			(size 0.4318 0.4318)
			(layers "F.Cu" "F.Mask" "F.Paste")
			(net "TP_I2C_S3M_RTC_CPU0_SCL")
		)
		(pad "CL25" smd circle
			(at -17.89176 5.818886 270)
			(size 0.4318 0.4318)
			(layers "F.Cu" "F.Mask" "F.Paste")
			(net "TP_H_SBLINK2_CPU0_PMSYNC")
		)
		(pad "CL60" smd circle
			(at 12.19454 5.928868 270)
			(size 0.4318 0.4318)
			(layers "F.Cu" "F.Mask" "F.Paste")
			(net "TP_CPU0_SPARE7")
		)
		(pad "CL62" smd circle
			(at 13.822426 5.928868 270)
			(size 0.4318 0.4318)
			(layers "F.Cu" "F.Mask" "F.Paste")
			(net "GND")
		)
		(pad "CL64" smd circle
			(at 15.450058 5.928868 270)
			(size 0.4318 0.4318)
			(layers "F.Cu" "F.Mask" "F.Paste")
			(net "NC_CPU0_VIEWPIN_DIE11<3>")
		)
		(pad "CL66" smd circle
			(at 17.07769 5.928868 270)
			(size 0.4318 0.4318)
			(layers "F.Cu" "F.Mask" "F.Paste")
			(net "TP_CPU0_SSC_SYNC")
		)
		(pad "CL68" smd circle
			(at 18.705576 5.928868 270)
			(size 0.4318 0.4318)
			(layers "F.Cu" "F.Mask" "F.Paste")
			(net "NC_CPU0_PE3_APROBE<0>")
		)
		(pad "CL70" smd circle
			(at 20.333462 5.928868 270)
			(size 0.4318 0.4318)
			(layers "F.Cu" "F.Mask" "F.Paste")
			(net "TP_CPU0_SPARE12")
		)
		(pad "CL72" smd circle
			(at 21.961094 5.928868 270)
			(size 0.4318 0.4318)
			(layers "F.Cu" "F.Mask" "F.Paste")
			(net "PUD_XTAL_CPU0_MODE0")
		)
		(pad "CL74" smd circle
			(at 23.58898 5.928868 270)
			(size 0.4318 0.4318)
			(layers "F.Cu" "F.Mask" "F.Paste")
			(net "GND")
		)
		(pad "CL76" smd circle
			(at 25.216612 5.928868 270)
			(size 0.4318 0.4318)
			(layers "F.Cu" "F.Mask" "F.Paste")
			(net "Net_667")
		)
		(pad "CL78" smd circle
			(at 26.844498 5.928868 270)
			(size 0.4318 0.4318)
			(layers "F.Cu" "F.Mask" "F.Paste")
			(net "GND")
		)
		(pad "CL80" smd circle
			(at 28.472384 5.928868 270)
			(size 0.4318 0.4318)
			(layers "F.Cu" "F.Mask" "F.Paste")
			(net "GND")
		)
		(pad "CL82" smd circle
			(at 30.100016 5.928868 270)
			(size 0.4318 0.4318)
			(layers "F.Cu" "F.Mask" "F.Paste")
			(net "GND")
		)
		(pad "CL84" smd circle
			(at 31.727902 5.928868 270)
			(size 0.4318 0.4318)
			(layers "F.Cu" "F.Mask" "F.Paste")
			(net "PVCCIN_CPU0")
		)
		(pad "CL86" smd circle
			(at 33.355534 5.928868 270)
			(size 0.4318 0.4318)
			(layers "F.Cu" "F.Mask" "F.Paste")
			(net "PVCCIN_CPU0")
		)
		(pad "CL88" smd circle
			(at 34.98342 5.928868 270)
			(size 0.4318 0.4318)
			(layers "F.Cu" "F.Mask" "F.Paste")
			(net "PVCCIN_CPU0")
		)
		(pad "CL90" smd circle
			(at 36.611306 5.928868 270)
			(size 0.4318 0.4318)
			(layers "F.Cu" "F.Mask" "F.Paste")
			(net "PVCCIN_CPU0")
		)
		(pad "CM2" smd circle
			(at -36.611306 6.288532 270)
			(size 0.4318 0.4318)
			(layers "F.Cu" "F.Mask" "F.Paste")
			(net "UPI_CPU1_CPU0_P0P1_DP<18>")
		)
		(pad "CM4" smd circle
			(at -34.98342 6.288532 270)
			(size 0.4318 0.4318)
			(layers "F.Cu" "F.Mask" "F.Paste")
			(net "GND")
		)
		(pad "CM6" smd circle
			(at -33.355534 6.288532 270)
			(size 0.4318 0.4318)
			(layers "F.Cu" "F.Mask" "F.Paste")
			(net "UPI_CPU0_CPU1_P1P0_DP<17>")
		)
		(pad "CM8" smd circle
			(at -31.727902 6.288532 270)
			(size 0.4318 0.4318)
			(layers "F.Cu" "F.Mask" "F.Paste")
			(net "GND")
		)
		(pad "CM10" smd circle
			(at -30.100016 6.288532 270)
			(size 0.4318 0.4318)
			(layers "F.Cu" "F.Mask" "F.Paste")
			(net "P5E_CPU0_PE1_RX_DP<1>")
		)
		(pad "CM12" smd circle
			(at -28.472384 6.288532 270)
			(size 0.4318 0.4318)
			(layers "F.Cu" "F.Mask" "F.Paste")
			(net "GND")
		)
		(pad "CM14" smd circle
			(at -26.844498 6.288532 270)
			(size 0.4318 0.4318)
			(layers "F.Cu" "F.Mask" "F.Paste")
			(net "P5E_CPU0_PE1_TX_DP<1>")
		)
		(pad "CM16" smd circle
			(at -25.216612 6.288532 270)
			(size 0.4318 0.4318)
			(layers "F.Cu" "F.Mask" "F.Paste")
			(net "GND")
		)
		(pad "CM18" smd circle
			(at -23.58898 6.288532 270)
			(size 0.4318 0.4318)
			(layers "F.Cu" "F.Mask" "F.Paste")
			(net "DMI_CPU0_PCH_TX_DN<7>")
		)
		(pad "CM20" smd circle
			(at -21.961094 6.288532 270)
			(size 0.4318 0.4318)
			(layers "F.Cu" "F.Mask" "F.Paste")
			(net "GND")
		)
		(pad "CM22" smd circle
			(at -20.333462 6.288532 270)
			(size 0.4318 0.4318)
			(layers "F.Cu" "F.Mask" "F.Paste")
			(net "GND")
		)
		(pad "CM24" smd circle
			(at -18.705576 6.288532 270)
			(size 0.4318 0.4318)
			(layers "F.Cu" "F.Mask" "F.Paste")
			(net "GND")
		)
		(pad "CM26" smd circle
			(at -17.07769 6.288532 270)
			(size 0.4318 0.4318)
			(layers "F.Cu" "F.Mask" "F.Paste")
			(net "TP_H_SBLINK3_CPU0_PMDOWN")
		)
		(pad "CM61" smd circle
			(at 13.008356 6.398514 270)
			(size 0.4318 0.4318)
			(layers "F.Cu" "F.Mask" "F.Paste")
			(net "GND")
		)
		(pad "CM63" smd circle
			(at 14.635988 6.398514 270)
			(size 0.4318 0.4318)
			(layers "F.Cu" "F.Mask" "F.Paste")
			(net "NC_CPU0_VIEWPIN_DIE11<2>")
		)
		(pad "CM65" smd circle
			(at 16.263874 6.398514 270)
			(size 0.4318 0.4318)
			(layers "F.Cu" "F.Mask" "F.Paste")
			(net "GND")
		)
		(pad "CM67" smd circle
			(at 17.89176 6.398514 270)
			(size 0.4318 0.4318)
			(layers "F.Cu" "F.Mask" "F.Paste")
			(net "GND")
		)
		(pad "CM69" smd circle
			(at 19.519392 6.398514 270)
			(size 0.4318 0.4318)
			(layers "F.Cu" "F.Mask" "F.Paste")
			(net "NC_CPU0_PE3_APROBE<1>")
		)
		(pad "CM71" smd circle
			(at 21.147278 6.398514 270)
			(size 0.4318 0.4318)
			(layers "F.Cu" "F.Mask" "F.Paste")
			(net "SMB_S3M_CPU0_PIROM_3V3AUX_SDA_1")
		)
		(pad "CM73" smd circle
			(at 22.77491 6.398514 270)
			(size 0.4318 0.4318)
			(layers "F.Cu" "F.Mask" "F.Paste")
			(net "PVCCFA_EHV_FIVRA_CPU0")
		)
		(pad "CM75" smd circle
			(at 24.402796 6.398514 270)
			(size 0.4318 0.4318)
			(layers "F.Cu" "F.Mask" "F.Paste")
			(net "Net_691")
		)
		(pad "CM77" smd circle
			(at 26.030682 6.398514 270)
			(size 0.4318 0.4318)
			(layers "F.Cu" "F.Mask" "F.Paste")
			(net "Net_669")
		)
		(pad "CM79" smd circle
			(at 27.658314 6.398514 270)
			(size 0.4318 0.4318)
			(layers "F.Cu" "F.Mask" "F.Paste")
			(net "GND")
		)
		(pad "CM81" smd circle
			(at 29.2862 6.398514 270)
			(size 0.4318 0.4318)
			(layers "F.Cu" "F.Mask" "F.Paste")
			(net "GND")
		)
		(pad "CM83" smd circle
			(at 30.914086 6.398514 270)
			(size 0.4318 0.4318)
			(layers "F.Cu" "F.Mask" "F.Paste")
			(net "GND")
		)
		(pad "CM85" smd circle
			(at 32.541718 6.398514 270)
			(size 0.4318 0.4318)
			(layers "F.Cu" "F.Mask" "F.Paste")
			(net "GND")
		)
		(pad "CM87" smd circle
			(at 34.169604 6.398514 270)
			(size 0.4318 0.4318)
			(layers "F.Cu" "F.Mask" "F.Paste")
			(net "PVCCIN_CPU0")
		)
		(pad "CM89" smd circle
			(at 35.797236 6.398514 270)
			(size 0.4318 0.4318)
			(layers "F.Cu" "F.Mask" "F.Paste")
			(net "PVCCIN_CPU0")
		)
		(pad "CM91" smd oval
			(at 37.425122 6.398514)
			(size 0.381 0.4826)
			(drill
				(offset 0 -0.0508)
			)
			(layers "F.Cu" "F.Mask" "F.Paste")
			(net "PVCCIN_CPU0")
		)
		(pad "CN1" smd oval
			(at -37.425122 6.758686 180)
			(size 0.381 0.4826)
			(drill
				(offset 0 -0.0508)
			)
			(layers "F.Cu" "F.Mask" "F.Paste")
			(net "UPI_CPU1_CPU0_P0P1_DP<17>")
		)
		(pad "CN3" smd circle
			(at -35.797236 6.758686 270)
			(size 0.4318 0.4318)
			(layers "F.Cu" "F.Mask" "F.Paste")
			(net "PVCCINFAON_CPU0")
		)
		(pad "CN5" smd circle
			(at -34.169604 6.758686 270)
			(size 0.4318 0.4318)
			(layers "F.Cu" "F.Mask" "F.Paste")
			(net "UPI_CPU0_CPU1_P1P0_DP<16>")
		)
		(pad "CN7" smd circle
			(at -32.541718 6.758686 270)
			(size 0.4318 0.4318)
			(layers "F.Cu" "F.Mask" "F.Paste")
			(net "PVCCINFAON_CPU0")
		)
		(pad "CN9" smd circle
			(at -30.914086 6.758686 270)
			(size 0.4318 0.4318)
			(layers "F.Cu" "F.Mask" "F.Paste")
			(net "P5E_CPU0_PE1_RX_DP<0>")
		)
		(pad "CN11" smd circle
			(at -29.2862 6.758686 270)
			(size 0.4318 0.4318)
			(layers "F.Cu" "F.Mask" "F.Paste")
			(net "PVCCINFAON_CPU0")
		)
		(pad "CN13" smd circle
			(at -27.658314 6.758686 270)
			(size 0.4318 0.4318)
			(layers "F.Cu" "F.Mask" "F.Paste")
			(net "P5E_CPU0_PE1_TX_DN<1>")
		)
		(pad "CN15" smd circle
			(at -26.030682 6.758686 270)
			(size 0.4318 0.4318)
			(layers "F.Cu" "F.Mask" "F.Paste")
			(net "PVCCINFAON_CPU0")
		)
		(pad "CN17" smd circle
			(at -24.402796 6.758686 270)
			(size 0.4318 0.4318)
			(layers "F.Cu" "F.Mask" "F.Paste")
			(net "DMI_CPU0_PCH_TX_DP<7>")
		)
		(pad "CN19" smd circle
			(at -22.77491 6.758686 270)
			(size 0.4318 0.4318)
			(layers "F.Cu" "F.Mask" "F.Paste")
			(net "PVCCINFAON_CPU0")
		)
		(pad "CN21" smd circle
			(at -21.147278 6.758686 270)
			(size 0.4318 0.4318)
			(layers "F.Cu" "F.Mask" "F.Paste")
			(net "TP_IBL_SLPS4_CPU0_R_N")
		)
		(pad "CN23" smd circle
			(at -19.519392 6.758686 270)
			(size 0.4318 0.4318)
			(layers "F.Cu" "F.Mask" "F.Paste")
			(net "TP_FM_IBL_ADR_ACK_CPU0")
		)
		(pad "CN25" smd circle
			(at -17.89176 6.758686 270)
			(size 0.4318 0.4318)
			(layers "F.Cu" "F.Mask" "F.Paste")
			(net "H_CPU0_PMSYNC_CPU1_R")
		)
		(pad "CN60" smd circle
			(at 12.19454 6.868668 270)
			(size 0.4318 0.4318)
			(layers "F.Cu" "F.Mask" "F.Paste")
			(net "NC_CPU0_LGSSPARE1")
		)
		(pad "CN62" smd circle
			(at 13.822426 6.868668 270)
			(size 0.4318 0.4318)
			(layers "F.Cu" "F.Mask" "F.Paste")
			(net "NC_CPU0_VIEWPIN_DIE11<1>")
		)
		(pad "CN64" smd circle
			(at 15.450058 6.868668 270)
			(size 0.4318 0.4318)
			(layers "F.Cu" "F.Mask" "F.Paste")
			(net "PVCCINFAON_CPU0")
		)
		(pad "CN66" smd circle
			(at 17.07769 6.868668 270)
			(size 0.4318 0.4318)
			(layers "F.Cu" "F.Mask" "F.Paste")
			(net "PVCCINFAON_CPU0")
		)
		(pad "CN68" smd circle
			(at 18.705576 6.868668 270)
			(size 0.4318 0.4318)
			(layers "F.Cu" "F.Mask" "F.Paste")
			(net "GND")
		)
		(pad "CN70" smd circle
			(at 20.333462 6.868668 270)
			(size 0.4318 0.4318)
			(layers "F.Cu" "F.Mask" "F.Paste")
			(net "GND")
		)
		(pad "CN72" smd circle
			(at 21.961094 6.868668 270)
			(size 0.4318 0.4318)
			(layers "F.Cu" "F.Mask" "F.Paste")
			(net "GND")
		)
		(pad "CN74" smd circle
			(at 23.58898 6.868668 270)
			(size 0.4318 0.4318)
			(layers "F.Cu" "F.Mask" "F.Paste")
			(net "GND")
		)
		(pad "CN76" smd circle
			(at 25.216612 6.868668 270)
			(size 0.4318 0.4318)
			(layers "F.Cu" "F.Mask" "F.Paste")
			(net "GND")
		)
		(pad "CN78" smd circle
			(at 26.844498 6.868668 270)
			(size 0.4318 0.4318)
			(layers "F.Cu" "F.Mask" "F.Paste")
			(net "PVCCFA_EHV_FIVRA_CPU0")
		)
		(pad "CN80" smd circle
			(at 28.472384 6.868668 270)
			(size 0.4318 0.4318)
			(layers "F.Cu" "F.Mask" "F.Paste")
			(net "GND")
		)
		(pad "CN82" smd circle
			(at 30.100016 6.868668 270)
			(size 0.4318 0.4318)
			(layers "F.Cu" "F.Mask" "F.Paste")
			(net "GND")
		)
		(pad "CN84" smd circle
			(at 31.727902 6.868668 270)
			(size 0.4318 0.4318)
			(layers "F.Cu" "F.Mask" "F.Paste")
			(net "GND")
		)
		(pad "CN86" smd circle
			(at 33.355534 6.868668 270)
			(size 0.4318 0.4318)
			(layers "F.Cu" "F.Mask" "F.Paste")
			(net "GND")
		)
		(pad "CN88" smd circle
			(at 34.98342 6.868668 270)
			(size 0.4318 0.4318)
			(layers "F.Cu" "F.Mask" "F.Paste")
			(net "PVCCIN_CPU0")
		)
		(pad "CN90" smd circle
			(at 36.611306 6.868668 270)
			(size 0.4318 0.4318)
			(layers "F.Cu" "F.Mask" "F.Paste")
			(net "PVCCIN_CPU0")
		)
		(pad "CP2" smd circle
			(at -36.611306 7.228332 270)
			(size 0.4318 0.4318)
			(layers "F.Cu" "F.Mask" "F.Paste")
			(net "UPI_CPU1_CPU0_P0P1_DN<17>")
		)
		(pad "CP4" smd circle
			(at -34.98342 7.228332 270)
			(size 0.4318 0.4318)
			(layers "F.Cu" "F.Mask" "F.Paste")
			(net "GND")
		)
		(pad "CP6" smd circle
			(at -33.355534 7.228332 270)
			(size 0.4318 0.4318)
			(layers "F.Cu" "F.Mask" "F.Paste")
			(net "UPI_CPU0_CPU1_P1P0_DN<16>")
		)
		(pad "CP8" smd circle
			(at -31.727902 7.228332 270)
			(size 0.4318 0.4318)
			(layers "F.Cu" "F.Mask" "F.Paste")
			(net "GND")
		)
		(pad "CP10" smd circle
			(at -30.100016 7.228332 270)
			(size 0.4318 0.4318)
			(layers "F.Cu" "F.Mask" "F.Paste")
			(net "P5E_CPU0_PE1_RX_DN<0>")
		)
		(pad "CP12" smd circle
			(at -28.472384 7.228332 270)
			(size 0.4318 0.4318)
			(layers "F.Cu" "F.Mask" "F.Paste")
			(net "GND")
		)
		(pad "CP14" smd circle
			(at -26.844498 7.228332 270)
			(size 0.4318 0.4318)
			(layers "F.Cu" "F.Mask" "F.Paste")
			(net "P5E_CPU0_PE1_TX_DN<0>")
		)
		(pad "CP16" smd circle
			(at -25.216612 7.228332 270)
			(size 0.4318 0.4318)
			(layers "F.Cu" "F.Mask" "F.Paste")
			(net "GND")
		)
		(pad "CP18" smd circle
			(at -23.58898 7.228332 270)
			(size 0.4318 0.4318)
			(layers "F.Cu" "F.Mask" "F.Paste")
			(net "GND")
		)
		(pad "CP20" smd circle
			(at -21.961094 7.228332 270)
			(size 0.4318 0.4318)
			(layers "F.Cu" "F.Mask" "F.Paste")
			(net "H_CPU0_PM_FAST_WAKE_N")
		)
		(pad "CP22" smd circle
			(at -20.333462 7.228332 270)
			(size 0.4318 0.4318)
			(layers "F.Cu" "F.Mask" "F.Paste")
			(net "TP_JTAG_CPU0_PLD_TDO")
		)
		(pad "CP24" smd circle
			(at -18.705576 7.228332 270)
			(size 0.4318 0.4318)
			(layers "F.Cu" "F.Mask" "F.Paste")
			(net "TP_FM_IBL_ADR_COMPLETE_CPU0_R")
		)
		(pad "CP26" smd circle
			(at -17.07769 7.228332 270)
			(size 0.4318 0.4318)
			(layers "F.Cu" "F.Mask" "F.Paste")
			(net "TP_H_SBLINK2_CPU0_PMDOWN")
		)
		(pad "CP61" smd circle
			(at 13.008356 7.338314 270)
			(size 0.4318 0.4318)
			(layers "F.Cu" "F.Mask" "F.Paste")
			(net "NC_CPU0_LGSSPARE5")
		)
		(pad "CP63" smd circle
			(at 14.635988 7.338314 270)
			(size 0.4318 0.4318)
			(layers "F.Cu" "F.Mask" "F.Paste")
			(net "PVCCINFAON_CPU0")
		)
		(pad "CP65" smd circle
			(at 16.263874 7.338314 270)
			(size 0.4318 0.4318)
			(layers "F.Cu" "F.Mask" "F.Paste")
			(net "PVCCINFAON_CPU0")
		)
		(pad "CP67" smd circle
			(at 17.89176 7.338314 270)
			(size 0.4318 0.4318)
			(layers "F.Cu" "F.Mask" "F.Paste")
			(net "PVCCINFAON_CPU0")
		)
		(pad "CP69" smd circle
			(at 19.519392 7.338314 270)
			(size 0.4318 0.4318)
			(layers "F.Cu" "F.Mask" "F.Paste")
			(net "NC_CPU0_UPI3_APROBE<0>")
		)
		(pad "CP71" smd circle
			(at 21.147278 7.338314 270)
			(size 0.4318 0.4318)
			(layers "F.Cu" "F.Mask" "F.Paste")
			(net "PD_PIROM_CPU0_ADDR2")
		)
		(pad "CP73" smd circle
			(at 22.77491 7.338314 270)
			(size 0.4318 0.4318)
			(layers "F.Cu" "F.Mask" "F.Paste")
			(net "PVCCFA_EHV_FIVRA_CPU0")
		)
		(pad "CP75" smd circle
			(at 24.402796 7.338314 270)
			(size 0.4318 0.4318)
			(layers "F.Cu" "F.Mask" "F.Paste")
			(net "GND")
		)
		(pad "CP77" smd circle
			(at 26.030682 7.338314 270)
			(size 0.4318 0.4318)
			(layers "F.Cu" "F.Mask" "F.Paste")
			(net "GND")
		)
		(pad "CP79" smd circle
			(at 27.658314 7.338314 270)
			(size 0.4318 0.4318)
			(layers "F.Cu" "F.Mask" "F.Paste")
			(net "GND")
		)
		(pad "CP81" smd circle
			(at 29.2862 7.338314 270)
			(size 0.4318 0.4318)
			(layers "F.Cu" "F.Mask" "F.Paste")
			(net "GND")
		)
		(pad "CP83" smd circle
			(at 30.914086 7.338314 270)
			(size 0.4318 0.4318)
			(layers "F.Cu" "F.Mask" "F.Paste")
			(net "GND")
		)
		(pad "CP85" smd circle
			(at 32.541718 7.338314 270)
			(size 0.4318 0.4318)
			(layers "F.Cu" "F.Mask" "F.Paste")
			(net "P5E_CPU0_PE3_TX_DN<15>")
		)
		(pad "CP87" smd circle
			(at 34.169604 7.338314 270)
			(size 0.4318 0.4318)
			(layers "F.Cu" "F.Mask" "F.Paste")
			(net "GND")
		)
		(pad "CP89" smd circle
			(at 35.797236 7.338314 270)
			(size 0.4318 0.4318)
			(layers "F.Cu" "F.Mask" "F.Paste")
			(net "PVCCIN_CPU0")
		)
		(pad "CP91" smd oval
			(at 37.425122 7.338314)
			(size 0.381 0.4826)
			(drill
				(offset 0 -0.0508)
			)
			(layers "F.Cu" "F.Mask" "F.Paste")
			(net "GND")
		)
		(pad "CR1" smd oval
			(at -37.425122 7.698486 180)
			(size 0.381 0.4826)
			(drill
				(offset 0 -0.0508)
			)
			(layers "F.Cu" "F.Mask" "F.Paste")
			(net "GND")
		)
		(pad "CR3" smd circle
			(at -35.797236 7.698486 270)
			(size 0.4318 0.4318)
			(layers "F.Cu" "F.Mask" "F.Paste")
			(net "UPI_CPU1_CPU0_P0P1_DN<16>")
		)
		(pad "CR5" smd circle
			(at -34.169604 7.698486 270)
			(size 0.4318 0.4318)
			(layers "F.Cu" "F.Mask" "F.Paste")
			(net "GND")
		)
		(pad "CR7" smd circle
			(at -32.541718 7.698486 270)
			(size 0.4318 0.4318)
			(layers "F.Cu" "F.Mask" "F.Paste")
			(net "UPI_CPU0_CPU1_P1P0_DN<15>")
		)
		(pad "CR9" smd circle
			(at -30.914086 7.698486 270)
			(size 0.4318 0.4318)
			(layers "F.Cu" "F.Mask" "F.Paste")
			(net "GND")
		)
		(pad "CR11" smd circle
			(at -29.2862 7.698486 270)
			(size 0.4318 0.4318)
			(layers "F.Cu" "F.Mask" "F.Paste")
			(net "GND")
		)
		(pad "CR13" smd circle
			(at -27.658314 7.698486 270)
			(size 0.4318 0.4318)
			(layers "F.Cu" "F.Mask" "F.Paste")
			(net "GND")
		)
		(pad "CR15" smd circle
			(at -26.030682 7.698486 270)
			(size 0.4318 0.4318)
			(layers "F.Cu" "F.Mask" "F.Paste")
			(net "P5E_CPU0_PE1_TX_DP<0>")
		)
		(pad "CR17" smd circle
			(at -24.402796 7.698486 270)
			(size 0.4318 0.4318)
			(layers "F.Cu" "F.Mask" "F.Paste")
			(net "GND")
		)
		(pad "CR19" smd circle
			(at -22.77491 7.698486 270)
			(size 0.4318 0.4318)
			(layers "F.Cu" "F.Mask" "F.Paste")
			(net "TP_H_SBLINK5_CPU0_PMSYNC")
		)
		(pad "CR21" smd circle
			(at -21.147278 7.698486 270)
			(size 0.4318 0.4318)
			(layers "F.Cu" "F.Mask" "F.Paste")
			(net "TP_IBL_SLPS3_CPU0_R_N")
		)
		(pad "CR23" smd circle
			(at -19.519392 7.698486 270)
			(size 0.4318 0.4318)
			(layers "F.Cu" "F.Mask" "F.Paste")
			(net "NC_CPU0_VIEWPIN_DIE10<0>")
		)
		(pad "CR25" smd circle
			(at -17.89176 7.698486 270)
			(size 0.4318 0.4318)
			(layers "F.Cu" "F.Mask" "F.Paste")
			(net "NC_CPU0_VIEWPIN_GNR2")
		)
		(pad "CR60" smd circle
			(at 12.19454 7.808468 270)
			(size 0.4318 0.4318)
			(layers "F.Cu" "F.Mask" "F.Paste")
			(net "NC_CPU0_LGSSPARE0")
		)
		(pad "CR62" smd circle
			(at 13.822426 7.808468 270)
			(size 0.4318 0.4318)
			(layers "F.Cu" "F.Mask" "F.Paste")
			(net "GND")
		)
		(pad "CR64" smd circle
			(at 15.450058 7.808468 270)
			(size 0.4318 0.4318)
			(layers "F.Cu" "F.Mask" "F.Paste")
			(net "GND")
		)
		(pad "CR66" smd circle
			(at 17.07769 7.808468 270)
			(size 0.4318 0.4318)
			(layers "F.Cu" "F.Mask" "F.Paste")
			(net "PVCCINFAON_CPU0")
		)
		(pad "CR68" smd circle
			(at 18.705576 7.808468 270)
			(size 0.4318 0.4318)
			(layers "F.Cu" "F.Mask" "F.Paste")
			(net "NC_CPU0_UPI3_APROBE<1>")
		)
		(pad "CR70" smd circle
			(at 20.333462 7.808468 270)
			(size 0.4318 0.4318)
			(layers "F.Cu" "F.Mask" "F.Paste")
			(net "PD_PIROM_CPU0_ADDR0")
		)
		(pad "CR72" smd circle
			(at 21.961094 7.808468 270)
			(size 0.4318 0.4318)
			(layers "F.Cu" "F.Mask" "F.Paste")
			(net "PU_PIROM_CPU0_SM_WP")
		)
		(pad "CR74" smd circle
			(at 23.58898 7.808468 270)
			(size 0.4318 0.4318)
			(layers "F.Cu" "F.Mask" "F.Paste")
			(net "Net_694")
		)
		(pad "CR76" smd circle
			(at 25.216612 7.808468 270)
			(size 0.4318 0.4318)
			(layers "F.Cu" "F.Mask" "F.Paste")
			(net "Net_671")
		)
		(pad "CR78" smd circle
			(at 26.844498 7.808468 270)
			(size 0.4318 0.4318)
			(layers "F.Cu" "F.Mask" "F.Paste")
			(net "GND")
		)
		(pad "CR80" smd circle
			(at 28.472384 7.808468 270)
			(size 0.4318 0.4318)
			(layers "F.Cu" "F.Mask" "F.Paste")
			(net "GND")
		)
		(pad "CR82" smd circle
			(at 30.100016 7.808468 270)
			(size 0.4318 0.4318)
			(layers "F.Cu" "F.Mask" "F.Paste")
			(net "GND")
		)
		(pad "CR84" smd circle
			(at 31.727902 7.808468 270)
			(size 0.4318 0.4318)
			(layers "F.Cu" "F.Mask" "F.Paste")
			(net "GND")
		)
		(pad "CR86" smd circle
			(at 33.355534 7.808468 270)
			(size 0.4318 0.4318)
			(layers "F.Cu" "F.Mask" "F.Paste")
			(net "P5E_CPU0_PE3_TX_DP<15>")
		)
		(pad "CR88" smd circle
			(at 34.98342 7.808468 270)
			(size 0.4318 0.4318)
			(layers "F.Cu" "F.Mask" "F.Paste")
			(net "GND")
		)
		(pad "CR90" smd circle
			(at 36.611306 7.808468 270)
			(size 0.4318 0.4318)
			(layers "F.Cu" "F.Mask" "F.Paste")
			(net "GND")
		)
		(pad "CT2" smd circle
			(at -36.611306 8.168132 270)
			(size 0.4318 0.4318)
			(layers "F.Cu" "F.Mask" "F.Paste")
			(net "UPI_CPU1_CPU0_P0P1_DP<16>")
		)
		(pad "CT4" smd circle
			(at -34.98342 8.168132 270)
			(size 0.4318 0.4318)
			(layers "F.Cu" "F.Mask" "F.Paste")
			(net "GND")
		)
		(pad "CT6" smd circle
			(at -33.355534 8.168132 270)
			(size 0.4318 0.4318)
			(layers "F.Cu" "F.Mask" "F.Paste")
			(net "UPI_CPU0_CPU1_P1P0_DP<15>")
		)
		(pad "CT8" smd circle
			(at -31.727902 8.168132 270)
			(size 0.4318 0.4318)
			(layers "F.Cu" "F.Mask" "F.Paste")
			(net "GND")
		)
		(pad "CT10" smd circle
			(at -30.100016 8.168132 270)
			(size 0.4318 0.4318)
			(layers "F.Cu" "F.Mask" "F.Paste")
			(net "GND")
		)
		(pad "CT12" smd circle
			(at -28.472384 8.168132 270)
			(size 0.4318 0.4318)
			(layers "F.Cu" "F.Mask" "F.Paste")
			(net "GND")
		)
		(pad "CT14" smd circle
			(at -26.844498 8.168132 270)
			(size 0.4318 0.4318)
			(layers "F.Cu" "F.Mask" "F.Paste")
			(net "P5E_CPU0_PE2_TX_DP<0>")
		)
		(pad "CT16" smd circle
			(at -25.216612 8.168132 270)
			(size 0.4318 0.4318)
			(layers "F.Cu" "F.Mask" "F.Paste")
			(net "GND")
		)
		(pad "CT18" smd circle
			(at -23.58898 8.168132 270)
			(size 0.4318 0.4318)
			(layers "F.Cu" "F.Mask" "F.Paste")
			(net "I3C_SPD_DDREFGH_CPU0_SDA")
		)
		(pad "CT20" smd circle
			(at -21.961094 8.168132 270)
			(size 0.4318 0.4318)
			(layers "F.Cu" "F.Mask" "F.Paste")
			(net "PD_CPU0_TXT_PLTEN")
		)
		(pad "CT22" smd circle
			(at -20.333462 8.168132 270)
			(size 0.4318 0.4318)
			(layers "F.Cu" "F.Mask" "F.Paste")
			(net "TP_JTAG_CPU0_PLD_TDI")
		)
		(pad "CT24" smd circle
			(at -18.705576 8.168132 270)
			(size 0.4318 0.4318)
			(layers "F.Cu" "F.Mask" "F.Paste")
			(net "TP_FM_IBL_ADR_TRIGGER_CPU0_R")
		)
		(pad "CT26" smd circle
			(at -17.07769 8.168132 270)
			(size 0.4318 0.4318)
			(layers "F.Cu" "F.Mask" "F.Paste")
			(net "NC_CPU0_VIEWPIN_GNR0")
		)
		(pad "CT61" smd circle
			(at 13.008356 8.278114 270)
			(size 0.4318 0.4318)
			(layers "F.Cu" "F.Mask" "F.Paste")
			(net "PU_CPU0_SOCKET_ID2")
		)
		(pad "CT63" smd circle
			(at 14.635988 8.278114 270)
			(size 0.4318 0.4318)
			(layers "F.Cu" "F.Mask" "F.Paste")
			(net "PVCCINFAON_CPU0")
		)
		(pad "CT65" smd circle
			(at 16.263874 8.278114 270)
			(size 0.4318 0.4318)
			(layers "F.Cu" "F.Mask" "F.Paste")
			(net "PVCCINFAON_CPU0")
		)
		(pad "CT67" smd circle
			(at 17.89176 8.278114 270)
			(size 0.4318 0.4318)
			(layers "F.Cu" "F.Mask" "F.Paste")
			(net "PVCCINFAON_CPU0")
		)
		(pad "CT69" smd circle
			(at 19.519392 8.278114 270)
			(size 0.4318 0.4318)
			(layers "F.Cu" "F.Mask" "F.Paste")
			(net "GND")
		)
		(pad "CT71" smd circle
			(at 21.147278 8.278114 270)
			(size 0.4318 0.4318)
			(layers "F.Cu" "F.Mask" "F.Paste")
			(net "PD_PIROM_CPU0_ADDR1")
		)
		(pad "CT73" smd circle
			(at 22.77491 8.278114 270)
			(size 0.4318 0.4318)
			(layers "F.Cu" "F.Mask" "F.Paste")
			(net "GND")
		)
		(pad "CT75" smd circle
			(at 24.402796 8.278114 270)
			(size 0.4318 0.4318)
			(layers "F.Cu" "F.Mask" "F.Paste")
			(net "Net_695")
		)
		(pad "CT77" smd circle
			(at 26.030682 8.278114 270)
			(size 0.4318 0.4318)
			(layers "F.Cu" "F.Mask" "F.Paste")
			(net "PVCCFA_EHV_FIVRA_CPU0")
		)
		(pad "CT79" smd circle
			(at 27.658314 8.278114 270)
			(size 0.4318 0.4318)
			(layers "F.Cu" "F.Mask" "F.Paste")
			(net "GND")
		)
		(pad "CT81" smd circle
			(at 29.2862 8.278114 270)
			(size 0.4318 0.4318)
			(layers "F.Cu" "F.Mask" "F.Paste")
			(net "GND")
		)
		(pad "CT83" smd circle
			(at 30.914086 8.278114 270)
			(size 0.4318 0.4318)
			(layers "F.Cu" "F.Mask" "F.Paste")
			(net "GND")
		)
		(pad "CT85" smd circle
			(at 32.541718 8.278114 270)
			(size 0.4318 0.4318)
			(layers "F.Cu" "F.Mask" "F.Paste")
			(net "PVCCFA_EHV_FIVRA_CPU0")
		)
		(pad "CT87" smd circle
			(at 34.169604 8.278114 270)
			(size 0.4318 0.4318)
			(layers "F.Cu" "F.Mask" "F.Paste")
			(net "P5E_CPU0_PE3_TX_DN<14>")
		)
		(pad "CT89" smd circle
			(at 35.797236 8.278114 270)
			(size 0.4318 0.4318)
			(layers "F.Cu" "F.Mask" "F.Paste")
			(net "GND")
		)
		(pad "CT91" smd oval
			(at 37.425122 8.278114)
			(size 0.381 0.4826)
			(drill
				(offset 0 -0.0508)
			)
			(layers "F.Cu" "F.Mask" "F.Paste")
			(net "P5E_CPU0_PE3_RX_DP<15>")
		)
		(pad "CU1" smd oval
			(at -37.425122 8.638286 180)
			(size 0.381 0.4826)
			(drill
				(offset 0 -0.0508)
			)
			(layers "F.Cu" "F.Mask" "F.Paste")
			(net "UPI_CPU1_CPU0_P0P1_DP<15>")
		)
		(pad "CU3" smd circle
			(at -35.797236 8.638286 270)
			(size 0.4318 0.4318)
			(layers "F.Cu" "F.Mask" "F.Paste")
			(net "PVCCINFAON_CPU0")
		)
		(pad "CU5" smd circle
			(at -34.169604 8.638286 270)
			(size 0.4318 0.4318)
			(layers "F.Cu" "F.Mask" "F.Paste")
			(net "UPI_CPU0_CPU1_P1P0_DP<14>")
		)
		(pad "CU7" smd circle
			(at -32.541718 8.638286 270)
			(size 0.4318 0.4318)
			(layers "F.Cu" "F.Mask" "F.Paste")
			(net "PVCCINFAON_CPU0")
		)
		(pad "CU9" smd circle
			(at -30.914086 8.638286 270)
			(size 0.4318 0.4318)
			(layers "F.Cu" "F.Mask" "F.Paste")
			(net "P5E_CPU0_PE2_RX_DN<0>")
		)
		(pad "CU11" smd circle
			(at -29.2862 8.638286 270)
			(size 0.4318 0.4318)
			(layers "F.Cu" "F.Mask" "F.Paste")
			(net "PVCCINFAON_CPU0")
		)
		(pad "CU13" smd circle
			(at -27.658314 8.638286 270)
			(size 0.4318 0.4318)
			(layers "F.Cu" "F.Mask" "F.Paste")
			(net "P5E_CPU0_PE2_TX_DN<0>")
		)
		(pad "CU15" smd circle
			(at -26.030682 8.638286 270)
			(size 0.4318 0.4318)
			(layers "F.Cu" "F.Mask" "F.Paste")
			(net "PVCCINFAON_CPU0")
		)
		(pad "CU17" smd circle
			(at -24.402796 8.638286 270)
			(size 0.4318 0.4318)
			(layers "F.Cu" "F.Mask" "F.Paste")
			(net "I3C_SPD_DDREFGH_CPU0_SCL")
		)
		(pad "CU19" smd circle
			(at -22.77491 8.638286 270)
			(size 0.4318 0.4318)
			(layers "F.Cu" "F.Mask" "F.Paste")
			(net "GND")
		)
		(pad "CU21" smd circle
			(at -21.147278 8.638286 270)
			(size 0.4318 0.4318)
			(layers "F.Cu" "F.Mask" "F.Paste")
			(net "GND")
		)
		(pad "CU23" smd circle
			(at -19.519392 8.638286 270)
			(size 0.4318 0.4318)
			(layers "F.Cu" "F.Mask" "F.Paste")
			(net "GND")
		)
		(pad "CU25" smd circle
			(at -17.89176 8.638286 270)
			(size 0.4318 0.4318)
			(layers "F.Cu" "F.Mask" "F.Paste")
			(net "GND")
		)
		(pad "CU60" smd circle
			(at 12.19454 8.748268 270)
			(size 0.4318 0.4318)
			(layers "F.Cu" "F.Mask" "F.Paste")
			(net "GND")
		)
		(pad "CU62" smd circle
			(at 13.822426 8.748268 270)
			(size 0.4318 0.4318)
			(layers "F.Cu" "F.Mask" "F.Paste")
			(net "NC_CPU0_LGSSPARE2")
		)
		(pad "CU64" smd circle
			(at 15.450058 8.748268 270)
			(size 0.4318 0.4318)
			(layers "F.Cu" "F.Mask" "F.Paste")
			(net "PVCCINFAON_CPU0")
		)
		(pad "CU66" smd circle
			(at 17.07769 8.748268 270)
			(size 0.4318 0.4318)
			(layers "F.Cu" "F.Mask" "F.Paste")
			(net "GND")
		)
		(pad "CU68" smd circle
			(at 18.705576 8.748268 270)
			(size 0.4318 0.4318)
			(layers "F.Cu" "F.Mask" "F.Paste")
			(net "GND")
		)
		(pad "CU70" smd circle
			(at 20.333462 8.748268 270)
			(size 0.4318 0.4318)
			(layers "F.Cu" "F.Mask" "F.Paste")
			(net "SMB_S3M_CPU0_PIROM_3V3AUX_SCL_1")
		)
		(pad "CU72" smd circle
			(at 21.961094 8.748268 270)
			(size 0.4318 0.4318)
			(layers "F.Cu" "F.Mask" "F.Paste")
			(net "GND")
		)
		(pad "CU74" smd circle
			(at 23.58898 8.748268 270)
			(size 0.4318 0.4318)
			(layers "F.Cu" "F.Mask" "F.Paste")
			(net "Net_670")
		)
		(pad "CU76" smd circle
			(at 25.216612 8.748268 270)
			(size 0.4318 0.4318)
			(layers "F.Cu" "F.Mask" "F.Paste")
			(net "Net_696")
		)
		(pad "CU78" smd circle
			(at 26.844498 8.748268 270)
			(size 0.4318 0.4318)
			(layers "F.Cu" "F.Mask" "F.Paste")
			(net "GND")
		)
		(pad "CU80" smd circle
			(at 28.472384 8.748268 270)
			(size 0.4318 0.4318)
			(layers "F.Cu" "F.Mask" "F.Paste")
			(net "GND")
		)
		(pad "CU82" smd circle
			(at 30.100016 8.748268 270)
			(size 0.4318 0.4318)
			(layers "F.Cu" "F.Mask" "F.Paste")
			(net "GND")
		)
		(pad "CU84" smd circle
			(at 31.727902 8.748268 270)
			(size 0.4318 0.4318)
			(layers "F.Cu" "F.Mask" "F.Paste")
			(net "GND")
		)
		(pad "CU86" smd circle
			(at 33.355534 8.748268 270)
			(size 0.4318 0.4318)
			(layers "F.Cu" "F.Mask" "F.Paste")
			(net "P5E_CPU0_PE3_TX_DP<14>")
		)
		(pad "CU88" smd circle
			(at 34.98342 8.748268 270)
			(size 0.4318 0.4318)
			(layers "F.Cu" "F.Mask" "F.Paste")
			(net "GND")
		)
		(pad "CU90" smd circle
			(at 36.611306 8.748268 270)
			(size 0.4318 0.4318)
			(layers "F.Cu" "F.Mask" "F.Paste")
			(net "P5E_CPU0_PE3_RX_DN<15>")
		)
		(pad "CV2" smd circle
			(at -36.611306 9.107932 270)
			(size 0.4318 0.4318)
			(layers "F.Cu" "F.Mask" "F.Paste")
			(net "UPI_CPU1_CPU0_P0P1_DN<15>")
		)
		(pad "CV4" smd circle
			(at -34.98342 9.107932 270)
			(size 0.4318 0.4318)
			(layers "F.Cu" "F.Mask" "F.Paste")
			(net "GND")
		)
		(pad "CV6" smd circle
			(at -33.355534 9.107932 270)
			(size 0.4318 0.4318)
			(layers "F.Cu" "F.Mask" "F.Paste")
			(net "UPI_CPU0_CPU1_P1P0_DN<14>")
		)
		(pad "CV8" smd circle
			(at -31.727902 9.107932 270)
			(size 0.4318 0.4318)
			(layers "F.Cu" "F.Mask" "F.Paste")
			(net "GND")
		)
		(pad "CV10" smd circle
			(at -30.100016 9.107932 270)
			(size 0.4318 0.4318)
			(layers "F.Cu" "F.Mask" "F.Paste")
			(net "P5E_CPU0_PE2_RX_DP<0>")
		)
		(pad "CV12" smd circle
			(at -28.472384 9.107932 270)
			(size 0.4318 0.4318)
			(layers "F.Cu" "F.Mask" "F.Paste")
			(net "GND")
		)
		(pad "CV14" smd circle
			(at -26.844498 9.107932 270)
			(size 0.4318 0.4318)
			(layers "F.Cu" "F.Mask" "F.Paste")
			(net "P5E_CPU0_PE2_TX_DN<1>")
		)
		(pad "CV16" smd circle
			(at -25.216612 9.107932 270)
			(size 0.4318 0.4318)
			(layers "F.Cu" "F.Mask" "F.Paste")
			(net "GND")
		)
		(pad "CV18" smd circle
			(at -23.58898 9.107932 270)
			(size 0.4318 0.4318)
			(layers "F.Cu" "F.Mask" "F.Paste")
			(net "TP_H_SBLINK5_CPU0_PMDOWN")
		)
		(pad "CV20" smd circle
			(at -21.961094 9.107932 270)
			(size 0.4318 0.4318)
			(layers "F.Cu" "F.Mask" "F.Paste")
			(net "PWRGD_PLT_AUX_CPU0_LVT3")
		)
		(pad "CV22" smd circle
			(at -20.333462 9.107932 270)
			(size 0.4318 0.4318)
			(layers "F.Cu" "F.Mask" "F.Paste")
			(net "TP_JTAG_CPU0_PLD_TMS")
		)
		(pad "CV24" smd circle
			(at -18.705576 9.107932 270)
			(size 0.4318 0.4318)
			(layers "F.Cu" "F.Mask" "F.Paste")
			(net "NC_CPU0_VIEWPIN_DIE10<2>")
		)
		(pad "CV26" smd circle
			(at -17.07769 9.107932 270)
			(size 0.4318 0.4318)
			(layers "F.Cu" "F.Mask" "F.Paste")
			(net "GND")
		)
		(pad "CV61" smd circle
			(at 13.008356 9.217914 270)
			(size 0.4318 0.4318)
			(layers "F.Cu" "F.Mask" "F.Paste")
			(net "PVCCINFAON_CPU0")
		)
		(pad "CV63" smd circle
			(at 14.635988 9.217914 270)
			(size 0.4318 0.4318)
			(layers "F.Cu" "F.Mask" "F.Paste")
			(net "PVCCINFAON_CPU0")
		)
		(pad "CV65" smd circle
			(at 16.263874 9.217914 270)
			(size 0.4318 0.4318)
			(layers "F.Cu" "F.Mask" "F.Paste")
			(net "PVCCINFAON_CPU0")
		)
		(pad "CV67" smd circle
			(at 17.89176 9.217914 270)
			(size 0.4318 0.4318)
			(layers "F.Cu" "F.Mask" "F.Paste")
			(net "PVCCINFAON_CPU0")
		)
		(pad "CV69" smd circle
			(at 19.519392 9.217914 270)
			(size 0.4318 0.4318)
			(layers "F.Cu" "F.Mask" "F.Paste")
			(net "NC_UART_IBL_CPU0_TXD")
		)
		(pad "CV71" smd circle
			(at 21.147278 9.217914 270)
			(size 0.4318 0.4318)
			(layers "F.Cu" "F.Mask" "F.Paste")
			(net "NC_UART_IBL_CPU0_CTS")
		)
		(pad "CV73" smd circle
			(at 22.77491 9.217914 270)
			(size 0.4318 0.4318)
			(layers "F.Cu" "F.Mask" "F.Paste")
			(net "Net_686")
		)
		(pad "CV75" smd circle
			(at 24.402796 9.217914 270)
			(size 0.4318 0.4318)
			(layers "F.Cu" "F.Mask" "F.Paste")
			(net "GND")
		)
		(pad "CV77" smd circle
			(at 26.030682 9.217914 270)
			(size 0.4318 0.4318)
			(layers "F.Cu" "F.Mask" "F.Paste")
			(net "Net_672")
		)
		(pad "CV79" smd circle
			(at 27.658314 9.217914 270)
			(size 0.4318 0.4318)
			(layers "F.Cu" "F.Mask" "F.Paste")
			(net "GND")
		)
		(pad "CV81" smd circle
			(at 29.2862 9.217914 270)
			(size 0.4318 0.4318)
			(layers "F.Cu" "F.Mask" "F.Paste")
			(net "GND")
		)
		(pad "CV83" smd circle
			(at 30.914086 9.217914 270)
			(size 0.4318 0.4318)
			(layers "F.Cu" "F.Mask" "F.Paste")
			(net "GND")
		)
		(pad "CV85" smd circle
			(at 32.541718 9.217914 270)
			(size 0.4318 0.4318)
			(layers "F.Cu" "F.Mask" "F.Paste")
			(net "P5E_CPU0_PE3_TX_DN<13>")
		)
		(pad "CV87" smd circle
			(at 34.169604 9.217914 270)
			(size 0.4318 0.4318)
			(layers "F.Cu" "F.Mask" "F.Paste")
			(net "GND")
		)
		(pad "CV89" smd circle
			(at 35.797236 9.217914 270)
			(size 0.4318 0.4318)
			(layers "F.Cu" "F.Mask" "F.Paste")
			(net "P5E_CPU0_PE3_RX_DN<14>")
		)
		(pad "CV91" smd oval
			(at 37.425122 9.217914)
			(size 0.381 0.4826)
			(drill
				(offset 0 -0.0508)
			)
			(layers "F.Cu" "F.Mask" "F.Paste")
			(net "GND")
		)
		(pad "CW1" smd oval
			(at -37.425122 9.578086 180)
			(size 0.381 0.4826)
			(drill
				(offset 0 -0.0508)
			)
			(layers "F.Cu" "F.Mask" "F.Paste")
			(net "GND")
		)
		(pad "CW3" smd circle
			(at -35.797236 9.578086 270)
			(size 0.4318 0.4318)
			(layers "F.Cu" "F.Mask" "F.Paste")
			(net "UPI_CPU1_CPU0_P0P1_DP<14>")
		)
		(pad "CW5" smd circle
			(at -34.169604 9.578086 270)
			(size 0.4318 0.4318)
			(layers "F.Cu" "F.Mask" "F.Paste")
			(net "GND")
		)
		(pad "CW7" smd circle
			(at -32.541718 9.578086 270)
			(size 0.4318 0.4318)
			(layers "F.Cu" "F.Mask" "F.Paste")
			(net "UPI_CPU0_CPU1_P1P0_DN<13>")
		)
		(pad "CW9" smd circle
			(at -30.914086 9.578086 270)
			(size 0.4318 0.4318)
			(layers "F.Cu" "F.Mask" "F.Paste")
			(net "GND")
		)
		(pad "CW11" smd circle
			(at -29.2862 9.578086 270)
			(size 0.4318 0.4318)
			(layers "F.Cu" "F.Mask" "F.Paste")
			(net "P5E_CPU0_PE2_RX_DP<1>")
		)
		(pad "CW13" smd circle
			(at -27.658314 9.578086 270)
			(size 0.4318 0.4318)
			(layers "F.Cu" "F.Mask" "F.Paste")
			(net "GND")
		)
		(pad "CW15" smd circle
			(at -26.030682 9.578086 270)
			(size 0.4318 0.4318)
			(layers "F.Cu" "F.Mask" "F.Paste")
			(net "P5E_CPU0_PE2_TX_DP<1>")
		)
		(pad "CW17" smd circle
			(at -24.402796 9.578086 270)
			(size 0.4318 0.4318)
			(layers "F.Cu" "F.Mask" "F.Paste")
			(net "GND")
		)
		(pad "CW19" smd circle
			(at -22.77491 9.578086 270)
			(size 0.4318 0.4318)
			(layers "F.Cu" "F.Mask" "F.Paste")
			(net "PU_CPU0_UPI1_AC_COUPLING")
		)
		(pad "CW21" smd circle
			(at -21.147278 9.578086 270)
			(size 0.4318 0.4318)
			(layers "F.Cu" "F.Mask" "F.Paste")
			(net "TP_IBL_SLPS5_CPU0_R_N")
		)
		(pad "CW23" smd circle
			(at -19.519392 9.578086 270)
			(size 0.4318 0.4318)
			(layers "F.Cu" "F.Mask" "F.Paste")
			(net "NC_CPU0_VIEWPIN_DIE10<3>")
		)
		(pad "CW25" smd circle
			(at -17.89176 9.578086 270)
			(size 0.4318 0.4318)
			(layers "F.Cu" "F.Mask" "F.Paste")
			(net "NC_CPU0_VIEWPIN_DIE10<1>")
		)
		(pad "CW27" smd circle
			(at -16.263874 9.578086 270)
			(size 0.4318 0.4318)
			(layers "F.Cu" "F.Mask" "F.Paste")
			(net "CLK_100M_DB2000_CPU0_BCLK3_DN")
		)
		(pad "CW29" smd circle
			(at -14.635988 9.578086 270)
			(size 0.4318 0.4318)
			(layers "F.Cu" "F.Mask" "F.Paste")
			(net "CLK_100M_DB2000_CPU0_BCLK1_DP")
		)
		(pad "CW31" smd circle
			(at -13.008356 9.578086 270)
			(size 0.4318 0.4318)
			(layers "F.Cu" "F.Mask" "F.Paste")
			(net "CLK_25M_NSSC_CPU0_DN")
		)
		(pad "CW33" smd circle
			(at -11.380724 9.578086 270)
			(size 0.4318 0.4318)
			(layers "F.Cu" "F.Mask" "F.Paste")
			(net "GND")
		)
		(pad "CW35" smd circle
			(at -9.752838 9.578086 270)
			(size 0.4318 0.4318)
			(layers "F.Cu" "F.Mask" "F.Paste")
			(net "PVCCD_HV_CPU0")
		)
		(pad "CW37" smd circle
			(at -8.124952 9.578086 270)
			(size 0.4318 0.4318)
			(layers "F.Cu" "F.Mask" "F.Paste")
			(net "PVCCD_HV_CPU0")
		)
		(pad "CW39" smd circle
			(at -6.49732 9.578086 270)
			(size 0.4318 0.4318)
			(layers "F.Cu" "F.Mask" "F.Paste")
			(net "H_CPU0_PMDOWN_CPU1_R")
		)
		(pad "CW41" smd circle
			(at -4.869434 9.578086 270)
			(size 0.4318 0.4318)
			(layers "F.Cu" "F.Mask" "F.Paste")
			(net "NC_CPU0_HBM1_VIEWDIG1")
		)
		(pad "CW43" smd circle
			(at -3.241802 9.578086 270)
			(size 0.4318 0.4318)
			(layers "F.Cu" "F.Mask" "F.Paste")
			(net "TP_CPU0_SPARE6")
		)
		(pad "CW45" smd circle
			(at -1.613916 9.578086 270)
			(size 0.4318 0.4318)
			(layers "F.Cu" "F.Mask" "F.Paste")
			(net "PWRGD_DRAMPWRGD_CPU0_GH_LVC1_R")
		)
		(pad "CW48" smd circle
			(at 2.427732 9.688068 270)
			(size 0.4318 0.4318)
			(layers "F.Cu" "F.Mask" "F.Paste")
			(net "M_F_CPU0_ALERT_N")
		)
		(pad "CW50" smd circle
			(at 4.055618 9.688068 270)
			(size 0.4318 0.4318)
			(layers "F.Cu" "F.Mask" "F.Paste")
			(net "M_G_CPU0_ALERT_N")
		)
		(pad "CW52" smd circle
			(at 5.68325 9.688068 270)
			(size 0.4318 0.4318)
			(layers "F.Cu" "F.Mask" "F.Paste")
			(net "PVCCD_HV_CPU0")
		)
		(pad "CW54" smd circle
			(at 7.311136 9.688068 270)
			(size 0.4318 0.4318)
			(layers "F.Cu" "F.Mask" "F.Paste")
			(net "PVCCD_HV_CPU0")
		)
		(pad "CW56" smd circle
			(at 8.939022 9.688068 270)
			(size 0.4318 0.4318)
			(layers "F.Cu" "F.Mask" "F.Paste")
			(net "PVCCD_HV_CPU0")
		)
		(pad "CW58" smd circle
			(at 10.566654 9.688068 270)
			(size 0.4318 0.4318)
			(layers "F.Cu" "F.Mask" "F.Paste")
			(net "NC_CPU0_VIEWPIN_GNR1")
		)
		(pad "CW60" smd circle
			(at 12.19454 9.688068 270)
			(size 0.4318 0.4318)
			(layers "F.Cu" "F.Mask" "F.Paste")
			(net "PU_CPU0_SOCKET_ID0")
		)
		(pad "CW62" smd circle
			(at 13.822426 9.688068 270)
			(size 0.4318 0.4318)
			(layers "F.Cu" "F.Mask" "F.Paste")
			(net "PVCCINFAON_CPU0")
		)
		(pad "CW64" smd circle
			(at 15.450058 9.688068 270)
			(size 0.4318 0.4318)
			(layers "F.Cu" "F.Mask" "F.Paste")
			(net "PVCCINFAON_CPU0")
		)
		(pad "CW66" smd circle
			(at 17.07769 9.688068 270)
			(size 0.4318 0.4318)
			(layers "F.Cu" "F.Mask" "F.Paste")
			(net "PVCCINFAON_CPU0")
		)
		(pad "CW68" smd circle
			(at 18.705576 9.688068 270)
			(size 0.4318 0.4318)
			(layers "F.Cu" "F.Mask" "F.Paste")
			(net "NC_CPU0_RSVD<144>")
		)
		(pad "CW70" smd circle
			(at 20.333462 9.688068 270)
			(size 0.4318 0.4318)
			(layers "F.Cu" "F.Mask" "F.Paste")
			(net "GND")
		)
		(pad "CW72" smd circle
			(at 21.961094 9.688068 270)
			(size 0.4318 0.4318)
			(layers "F.Cu" "F.Mask" "F.Paste")
			(net "GND")
		)
		(pad "CW74" smd circle
			(at 23.58898 9.688068 270)
			(size 0.4318 0.4318)
			(layers "F.Cu" "F.Mask" "F.Paste")
			(net "Net_662")
		)
		(pad "CW76" smd circle
			(at 25.216612 9.688068 270)
			(size 0.4318 0.4318)
			(layers "F.Cu" "F.Mask" "F.Paste")
			(net "Net_697")
		)
		(pad "CW78" smd circle
			(at 26.844498 9.688068 270)
			(size 0.4318 0.4318)
			(layers "F.Cu" "F.Mask" "F.Paste")
			(net "GND")
		)
		(pad "CW80" smd circle
			(at 28.472384 9.688068 270)
			(size 0.4318 0.4318)
			(layers "F.Cu" "F.Mask" "F.Paste")
			(net "GND")
		)
		(pad "CW82" smd circle
			(at 30.100016 9.688068 270)
			(size 0.4318 0.4318)
			(layers "F.Cu" "F.Mask" "F.Paste")
			(net "GND")
		)
		(pad "CW84" smd circle
			(at 31.727902 9.688068 270)
			(size 0.4318 0.4318)
			(layers "F.Cu" "F.Mask" "F.Paste")
			(net "GND")
		)
		(pad "CW86" smd circle
			(at 33.355534 9.688068 270)
			(size 0.4318 0.4318)
			(layers "F.Cu" "F.Mask" "F.Paste")
			(net "P5E_CPU0_PE3_TX_DP<13>")
		)
		(pad "CW88" smd circle
			(at 34.98342 9.688068 270)
			(size 0.4318 0.4318)
			(layers "F.Cu" "F.Mask" "F.Paste")
			(net "GND")
		)
		(pad "CW90" smd circle
			(at 36.611306 9.688068 270)
			(size 0.4318 0.4318)
			(layers "F.Cu" "F.Mask" "F.Paste")
			(net "P5E_CPU0_PE3_RX_DP<14>")
		)
		(pad "CY2" smd circle
			(at -36.611306 10.047732 270)
			(size 0.4318 0.4318)
			(layers "F.Cu" "F.Mask" "F.Paste")
			(net "UPI_CPU1_CPU0_P0P1_DN<14>")
		)
		(pad "CY4" smd circle
			(at -34.98342 10.047732 270)
			(size 0.4318 0.4318)
			(layers "F.Cu" "F.Mask" "F.Paste")
			(net "GND")
		)
		(pad "CY6" smd circle
			(at -33.355534 10.047732 270)
			(size 0.4318 0.4318)
			(layers "F.Cu" "F.Mask" "F.Paste")
			(net "UPI_CPU0_CPU1_P1P0_DP<13>")
		)
		(pad "CY8" smd circle
			(at -31.727902 10.047732 270)
			(size 0.4318 0.4318)
			(layers "F.Cu" "F.Mask" "F.Paste")
			(net "GND")
		)
		(pad "CY10" smd circle
			(at -30.100016 10.047732 270)
			(size 0.4318 0.4318)
			(layers "F.Cu" "F.Mask" "F.Paste")
			(net "P5E_CPU0_PE2_RX_DN<1>")
		)
		(pad "CY12" smd circle
			(at -28.472384 10.047732 270)
			(size 0.4318 0.4318)
			(layers "F.Cu" "F.Mask" "F.Paste")
			(net "GND")
		)
		(pad "CY14" smd circle
			(at -26.844498 10.047732 270)
			(size 0.4318 0.4318)
			(layers "F.Cu" "F.Mask" "F.Paste")
			(net "P5E_CPU0_PE2_TX_DP<2>")
		)
		(pad "CY16" smd circle
			(at -25.216612 10.047732 270)
			(size 0.4318 0.4318)
			(layers "F.Cu" "F.Mask" "F.Paste")
			(net "GND")
		)
		(pad "CY18" smd circle
			(at -23.58898 10.047732 270)
			(size 0.4318 0.4318)
			(layers "F.Cu" "F.Mask" "F.Paste")
			(net "GND")
		)
		(pad "CY20" smd circle
			(at -21.961094 10.047732 270)
			(size 0.4318 0.4318)
			(layers "F.Cu" "F.Mask" "F.Paste")
			(net "FM_S3M_CPU0_CPLD_CRC_ERROR")
		)
		(pad "CY22" smd circle
			(at -20.333462 10.047732 270)
			(size 0.4318 0.4318)
			(layers "F.Cu" "F.Mask" "F.Paste")
			(net "PD_JTAG_CPU0_PLD_TCK")
		)
		(pad "CY24" smd circle
			(at -18.705576 10.047732 270)
			(size 0.4318 0.4318)
			(layers "F.Cu" "F.Mask" "F.Paste")
			(net "NC_CPU0_DDR45_VIEWDIG0")
		)
		(pad "CY26" smd circle
			(at -17.07769 10.047732 270)
			(size 0.4318 0.4318)
			(layers "F.Cu" "F.Mask" "F.Paste")
			(net "GND")
		)
		(pad "CY28" smd circle
			(at -15.450058 10.047732 270)
			(size 0.4318 0.4318)
			(layers "F.Cu" "F.Mask" "F.Paste")
			(net "CLK_100M_DB2000_CPU0_BCLK1_DN")
		)
		(pad "CY30" smd circle
			(at -13.822426 10.047732 270)
			(size 0.4318 0.4318)
			(layers "F.Cu" "F.Mask" "F.Paste")
			(net "GND")
		)
		(pad "CY32" smd circle
			(at -12.19454 10.047732 270)
			(size 0.4318 0.4318)
			(layers "F.Cu" "F.Mask" "F.Paste")
			(net "CLK_25M_NSSC_CPU0_DP")
		)
		(pad "CY34" smd circle
			(at -10.566654 10.047732 270)
			(size 0.4318 0.4318)
			(layers "F.Cu" "F.Mask" "F.Paste")
			(net "PVCCD_HV_CPU0")
		)
		(pad "CY36" smd circle
			(at -8.939022 10.047732 270)
			(size 0.4318 0.4318)
			(layers "F.Cu" "F.Mask" "F.Paste")
			(net "PVCCD_HV_CPU0")
		)
		(pad "CY38" smd circle
			(at -7.311136 10.047732 270)
			(size 0.4318 0.4318)
			(layers "F.Cu" "F.Mask" "F.Paste")
			(net "NC_CPU0_DDR45_VIEWDIG1")
		)
		(pad "CY40" smd circle
			(at -5.68325 10.047732 270)
			(size 0.4318 0.4318)
			(layers "F.Cu" "F.Mask" "F.Paste")
			(net "H_CPU0_PMDOWN_PCH_R2")
		)
		(pad "CY42" smd circle
			(at -4.055618 10.047732 270)
			(size 0.4318 0.4318)
			(layers "F.Cu" "F.Mask" "F.Paste")
			(net "RST_CPU0_DRAM_EF_N")
		)
		(pad "CY44" smd circle
			(at -2.427732 10.047732 270)
			(size 0.4318 0.4318)
			(layers "F.Cu" "F.Mask" "F.Paste")
			(net "PWRGD_DRAMPWRGD_CPU0_EF_LVC1_R")
		)
		(pad "CY47" smd circle
			(at 1.613916 10.157714 270)
			(size 0.4318 0.4318)
			(layers "F.Cu" "F.Mask" "F.Paste")
			(net "M_E_CPU0_ALERT_N")
		)
		(pad "CY49" smd circle
			(at 3.241802 10.157714 270)
			(size 0.4318 0.4318)
			(layers "F.Cu" "F.Mask" "F.Paste")
			(net "NC_CPU0_DDR67_VIEWDIG1")
		)
		(pad "CY51" smd circle
			(at 4.869434 10.157714 270)
			(size 0.4318 0.4318)
			(layers "F.Cu" "F.Mask" "F.Paste")
			(net "M_H_CPU0_ALERT_N")
		)
		(pad "CY53" smd circle
			(at 6.49732 10.157714 270)
			(size 0.4318 0.4318)
			(layers "F.Cu" "F.Mask" "F.Paste")
			(net "PVCCD_HV_CPU0")
		)
		(pad "CY55" smd circle
			(at 8.124952 10.157714 270)
			(size 0.4318 0.4318)
			(layers "F.Cu" "F.Mask" "F.Paste")
			(net "RST_CPU0_DRAM_GH_N")
		)
		(pad "CY57" smd circle
			(at 9.752838 10.157714 270)
			(size 0.4318 0.4318)
			(layers "F.Cu" "F.Mask" "F.Paste")
			(net "NC_CPU0_VIEWPIN_GNR3")
		)
		(pad "CY59" smd circle
			(at 11.380724 10.157714 270)
			(size 0.4318 0.4318)
			(layers "F.Cu" "F.Mask" "F.Paste")
			(net "PU_CPU0_LEGACY_SKT")
		)
		(pad "CY61" smd circle
			(at 13.008356 10.157714 270)
			(size 0.4318 0.4318)
			(layers "F.Cu" "F.Mask" "F.Paste")
			(net "PU_CPU0_SOCKET_ID1")
		)
		(pad "CY63" smd circle
			(at 14.635988 10.157714 270)
			(size 0.4318 0.4318)
			(layers "F.Cu" "F.Mask" "F.Paste")
			(net "GND")
		)
		(pad "CY65" smd circle
			(at 16.263874 10.157714 270)
			(size 0.4318 0.4318)
			(layers "F.Cu" "F.Mask" "F.Paste")
			(net "PVCCINFAON_CPU0")
		)
		(pad "CY67" smd circle
			(at 17.89176 10.157714 270)
			(size 0.4318 0.4318)
			(layers "F.Cu" "F.Mask" "F.Paste")
			(net "PVCCINFAON_CPU0")
		)
		(pad "CY69" smd circle
			(at 19.519392 10.157714 270)
			(size 0.4318 0.4318)
			(layers "F.Cu" "F.Mask" "F.Paste")
			(net "NC_UART_IBL_CPU0_RXD")
		)
		(pad "CY71" smd circle
			(at 21.147278 10.157714 270)
			(size 0.4318 0.4318)
			(layers "F.Cu" "F.Mask" "F.Paste")
			(net "NC_UART_IBL_CPU0_RTS")
		)
		(pad "CY73" smd circle
			(at 22.77491 10.157714 270)
			(size 0.4318 0.4318)
			(layers "F.Cu" "F.Mask" "F.Paste")
			(net "GND")
		)
		(pad "CY75" smd circle
			(at 24.402796 10.157714 270)
			(size 0.4318 0.4318)
			(layers "F.Cu" "F.Mask" "F.Paste")
			(net "PVCCFA_EHV_FIVRA_CPU0")
		)
		(pad "CY77" smd circle
			(at 26.030682 10.157714 270)
			(size 0.4318 0.4318)
			(layers "F.Cu" "F.Mask" "F.Paste")
			(net "GND")
		)
		(pad "CY79" smd circle
			(at 27.658314 10.157714 270)
			(size 0.4318 0.4318)
			(layers "F.Cu" "F.Mask" "F.Paste")
			(net "PVCCFA_EHV_FIVRA_CPU0")
		)
		(pad "CY81" smd circle
			(at 29.2862 10.157714 270)
			(size 0.4318 0.4318)
			(layers "F.Cu" "F.Mask" "F.Paste")
			(net "GND")
		)
		(pad "CY83" smd circle
			(at 30.914086 10.157714 270)
			(size 0.4318 0.4318)
			(layers "F.Cu" "F.Mask" "F.Paste")
			(net "GND")
		)
		(pad "CY85" smd circle
			(at 32.541718 10.157714 270)
			(size 0.4318 0.4318)
			(layers "F.Cu" "F.Mask" "F.Paste")
			(net "PVCCFA_EHV_FIVRA_CPU0")
		)
		(pad "CY87" smd circle
			(at 34.169604 10.157714 270)
			(size 0.4318 0.4318)
			(layers "F.Cu" "F.Mask" "F.Paste")
			(net "P5E_CPU0_PE3_TX_DN<12>")
		)
		(pad "CY89" smd circle
			(at 35.797236 10.157714 270)
			(size 0.4318 0.4318)
			(layers "F.Cu" "F.Mask" "F.Paste")
			(net "PVCCFA_EHV_FIVRA_CPU0")
		)
		(pad "CY91" smd oval
			(at 37.425122 10.157714)
			(size 0.381 0.4826)
			(drill
				(offset 0 -0.0508)
			)
			(layers "F.Cu" "F.Mask" "F.Paste")
			(net "P5E_CPU0_PE3_RX_DP<13>")
		)
		(pad "D4" smd oval
			(at -34.98342 -25.664414 135)
			(size 0.381 0.4826)
			(drill
				(offset 0 -0.0508)
			)
			(layers "F.Cu" "F.Mask" "F.Paste")
			(net "NC_XTAL_CPU0_25M_OUT")
		)
		(pad "D6" smd oval
			(at -33.355534 -25.664414 135)
			(size 0.381 0.4826)
			(drill
				(offset 0 -0.0508)
			)
			(layers "F.Cu" "F.Mask" "F.Paste")
			(net "GND")
		)
		(pad "D8" smd oval
			(at -31.727902 -25.664414 135)
			(size 0.381 0.4826)
			(drill
				(offset 0 -0.0508)
			)
			(layers "F.Cu" "F.Mask" "F.Paste")
			(net "GND")
		)
		(pad "D10" smd circle
			(at -30.100016 -25.664414 270)
			(size 0.4318 0.4318)
			(layers "F.Cu" "F.Mask" "F.Paste")
			(net "GND")
		)
		(pad "D12" smd circle
			(at -28.472384 -25.664414 270)
			(size 0.4318 0.4318)
			(layers "F.Cu" "F.Mask" "F.Paste")
			(net "GND")
		)
		(pad "D14" smd circle
			(at -26.844498 -25.664414 270)
			(size 0.4318 0.4318)
			(layers "F.Cu" "F.Mask" "F.Paste")
			(net "GND")
		)
		(pad "D16" smd circle
			(at -25.216612 -25.664414 270)
			(size 0.4318 0.4318)
			(layers "F.Cu" "F.Mask" "F.Paste")
			(net "GND")
		)
		(pad "D18" smd circle
			(at -23.58898 -25.664414 270)
			(size 0.4318 0.4318)
			(layers "F.Cu" "F.Mask" "F.Paste")
			(net "GND")
		)
		(pad "D20" smd circle
			(at -21.961094 -25.664414 270)
			(size 0.4318 0.4318)
			(layers "F.Cu" "F.Mask" "F.Paste")
			(net "GND")
		)
		(pad "D22" smd circle
			(at -20.333462 -25.664414 270)
			(size 0.4318 0.4318)
			(layers "F.Cu" "F.Mask" "F.Paste")
			(net "GND")
		)
		(pad "D24" smd circle
			(at -18.705576 -25.664414 270)
			(size 0.4318 0.4318)
			(layers "F.Cu" "F.Mask" "F.Paste")
			(net "GND")
		)
		(pad "D26" smd circle
			(at -17.07769 -25.664414 270)
			(size 0.4318 0.4318)
			(layers "F.Cu" "F.Mask" "F.Paste")
			(net "GND")
		)
		(pad "D28" smd circle
			(at -15.450058 -25.664414 270)
			(size 0.4318 0.4318)
			(layers "F.Cu" "F.Mask" "F.Paste")
			(net "GND")
		)
		(pad "D30" smd circle
			(at -13.822426 -25.664414 270)
			(size 0.4318 0.4318)
			(layers "F.Cu" "F.Mask" "F.Paste")
			(net "GND")
		)
		(pad "D32" smd circle
			(at -12.19454 -25.664414 270)
			(size 0.4318 0.4318)
			(layers "F.Cu" "F.Mask" "F.Paste")
			(net "GND")
		)
		(pad "D34" smd circle
			(at -10.566654 -25.664414 270)
			(size 0.4318 0.4318)
			(layers "F.Cu" "F.Mask" "F.Paste")
			(net "GND")
		)
		(pad "D36" smd circle
			(at -8.939022 -25.664414 270)
			(size 0.4318 0.4318)
			(layers "F.Cu" "F.Mask" "F.Paste")
			(net "GND")
		)
		(pad "D38" smd circle
			(at -7.311136 -25.664414 270)
			(size 0.4318 0.4318)
			(layers "F.Cu" "F.Mask" "F.Paste")
			(net "GND")
		)
		(pad "D40" smd circle
			(at -5.68325 -25.664414 270)
			(size 0.4318 0.4318)
			(layers "F.Cu" "F.Mask" "F.Paste")
			(net "GND")
		)
		(pad "D42" smd circle
			(at -4.055618 -25.664414 270)
			(size 0.4318 0.4318)
			(layers "F.Cu" "F.Mask" "F.Paste")
			(net "GND")
		)
		(pad "D44" smd circle
			(at -2.427732 -25.664414 270)
			(size 0.4318 0.4318)
			(layers "F.Cu" "F.Mask" "F.Paste")
			(net "GND")
		)
		(pad "D47" smd oval
			(at 1.613916 -25.554686 135)
			(size 0.381 0.4826)
			(drill
				(offset 0 -0.0508)
			)
			(layers "F.Cu" "F.Mask" "F.Paste")
			(net "GND")
		)
		(pad "D49" smd circle
			(at 3.241802 -25.554686 270)
			(size 0.4318 0.4318)
			(layers "F.Cu" "F.Mask" "F.Paste")
			(net "GND")
		)
		(pad "D51" smd circle
			(at 4.869434 -25.554686 270)
			(size 0.4318 0.4318)
			(layers "F.Cu" "F.Mask" "F.Paste")
			(net "GND")
		)
		(pad "D53" smd circle
			(at 6.49732 -25.554686 270)
			(size 0.4318 0.4318)
			(layers "F.Cu" "F.Mask" "F.Paste")
			(net "GND")
		)
		(pad "D55" smd circle
			(at 8.124952 -25.554686 270)
			(size 0.4318 0.4318)
			(layers "F.Cu" "F.Mask" "F.Paste")
			(net "GND")
		)
		(pad "D57" smd circle
			(at 9.752838 -25.554686 270)
			(size 0.4318 0.4318)
			(layers "F.Cu" "F.Mask" "F.Paste")
			(net "GND")
		)
		(pad "D59" smd circle
			(at 11.380724 -25.554686 270)
			(size 0.4318 0.4318)
			(layers "F.Cu" "F.Mask" "F.Paste")
			(net "GND")
		)
		(pad "D61" smd circle
			(at 13.008356 -25.554686 270)
			(size 0.4318 0.4318)
			(layers "F.Cu" "F.Mask" "F.Paste")
			(net "GND")
		)
		(pad "D63" smd circle
			(at 14.635988 -25.554686 270)
			(size 0.4318 0.4318)
			(layers "F.Cu" "F.Mask" "F.Paste")
			(net "GND")
		)
		(pad "D65" smd circle
			(at 16.263874 -25.554686 270)
			(size 0.4318 0.4318)
			(layers "F.Cu" "F.Mask" "F.Paste")
			(net "GND")
		)
		(pad "D67" smd circle
			(at 17.89176 -25.554686 270)
			(size 0.4318 0.4318)
			(layers "F.Cu" "F.Mask" "F.Paste")
			(net "GND")
		)
		(pad "D69" smd circle
			(at 19.519392 -25.554686 270)
			(size 0.4318 0.4318)
			(layers "F.Cu" "F.Mask" "F.Paste")
			(net "GND")
		)
		(pad "D71" smd circle
			(at 21.147278 -25.554686 270)
			(size 0.4318 0.4318)
			(layers "F.Cu" "F.Mask" "F.Paste")
			(net "GND")
		)
		(pad "D73" smd circle
			(at 22.77491 -25.554686 270)
			(size 0.4318 0.4318)
			(layers "F.Cu" "F.Mask" "F.Paste")
			(net "M_A_CPU0_SA_DQ<18>")
		)
		(pad "D75" smd circle
			(at 24.402796 -25.554686 270)
			(size 0.4318 0.4318)
			(layers "F.Cu" "F.Mask" "F.Paste")
			(net "M_A_CPU0_SA_DQ<5>")
		)
		(pad "D77" smd circle
			(at 26.030682 -25.554686 270)
			(size 0.4318 0.4318)
			(layers "F.Cu" "F.Mask" "F.Paste")
			(net "M_A_CPU0_SA_DQS_DP<0>")
		)
		(pad "D79" smd circle
			(at 27.658314 -25.554686 270)
			(size 0.4318 0.4318)
			(layers "F.Cu" "F.Mask" "F.Paste")
			(net "GND")
		)
		(pad "D81" smd circle
			(at 29.2862 -25.554686 270)
			(size 0.4318 0.4318)
			(layers "F.Cu" "F.Mask" "F.Paste")
			(net "GND")
		)
		(pad "D83" smd circle
			(at 30.914086 -25.554686 270)
			(size 0.4318 0.4318)
			(layers "F.Cu" "F.Mask" "F.Paste")
			(net "GND")
		)
		(pad "D85" smd oval
			(at 32.541718 -25.554686 45)
			(size 0.381 0.4826)
			(drill
				(offset 0 -0.0508)
			)
			(layers "F.Cu" "F.Mask" "F.Paste")
			(net "UPI_CPU0_CPU1_P2P2_DP<23>")
		)
		(pad "D87" smd oval
			(at 34.169604 -25.554686 45)
			(size 0.381 0.4826)
			(drill
				(offset 0 -0.0508)
			)
			(layers "F.Cu" "F.Mask" "F.Paste")
			(net "UPI_CPU0_CPU1_P2P2_DN<21>")
		)
		(pad "DA1" smd oval
			(at -37.425122 10.517886 180)
			(size 0.381 0.4826)
			(drill
				(offset 0 -0.0508)
			)
			(layers "F.Cu" "F.Mask" "F.Paste")
			(net "UPI_CPU1_CPU0_P0P1_DP<13>")
		)
		(pad "DA3" smd circle
			(at -35.797236 10.517886 270)
			(size 0.4318 0.4318)
			(layers "F.Cu" "F.Mask" "F.Paste")
			(net "PVCCINFAON_CPU0")
		)
		(pad "DA5" smd circle
			(at -34.169604 10.517886 270)
			(size 0.4318 0.4318)
			(layers "F.Cu" "F.Mask" "F.Paste")
			(net "UPI_CPU0_CPU1_P1P0_DP<12>")
		)
		(pad "DA7" smd circle
			(at -32.541718 10.517886 270)
			(size 0.4318 0.4318)
			(layers "F.Cu" "F.Mask" "F.Paste")
			(net "PVCCINFAON_CPU0")
		)
		(pad "DA9" smd circle
			(at -30.914086 10.517886 270)
			(size 0.4318 0.4318)
			(layers "F.Cu" "F.Mask" "F.Paste")
			(net "P5E_CPU0_PE2_RX_DN<2>")
		)
		(pad "DA11" smd circle
			(at -29.2862 10.517886 270)
			(size 0.4318 0.4318)
			(layers "F.Cu" "F.Mask" "F.Paste")
			(net "PVCCINFAON_CPU0")
		)
		(pad "DA13" smd circle
			(at -27.658314 10.517886 270)
			(size 0.4318 0.4318)
			(layers "F.Cu" "F.Mask" "F.Paste")
			(net "P5E_CPU0_PE2_TX_DN<2>")
		)
		(pad "DA15" smd circle
			(at -26.030682 10.517886 270)
			(size 0.4318 0.4318)
			(layers "F.Cu" "F.Mask" "F.Paste")
			(net "PVCCINFAON_CPU0")
		)
		(pad "DA17" smd circle
			(at -24.402796 10.517886 270)
			(size 0.4318 0.4318)
			(layers "F.Cu" "F.Mask" "F.Paste")
			(net "M_H_CPU0_SB_DQ<29>")
		)
		(pad "DA19" smd circle
			(at -22.77491 10.517886 270)
			(size 0.4318 0.4318)
			(layers "F.Cu" "F.Mask" "F.Paste")
			(net "GND")
		)
		(pad "DA21" smd circle
			(at -21.147278 10.517886 270)
			(size 0.4318 0.4318)
			(layers "F.Cu" "F.Mask" "F.Paste")
			(net "PVCCINFAON_CPU0")
		)
		(pad "DA23" smd circle
			(at -19.519392 10.517886 270)
			(size 0.4318 0.4318)
			(layers "F.Cu" "F.Mask" "F.Paste")
			(net "GND")
		)
		(pad "DA25" smd circle
			(at -17.89176 10.517886 270)
			(size 0.4318 0.4318)
			(layers "F.Cu" "F.Mask" "F.Paste")
			(net "GND")
		)
		(pad "DA27" smd circle
			(at -16.263874 10.517886 270)
			(size 0.4318 0.4318)
			(layers "F.Cu" "F.Mask" "F.Paste")
			(net "CLK_100M_DB2000_CPU0_BCLK3_DP")
		)
		(pad "DA29" smd circle
			(at -14.635988 10.517886 270)
			(size 0.4318 0.4318)
			(layers "F.Cu" "F.Mask" "F.Paste")
			(net "GND")
		)
		(pad "DA31" smd circle
			(at -13.008356 10.517886 270)
			(size 0.4318 0.4318)
			(layers "F.Cu" "F.Mask" "F.Paste")
			(net "GND")
		)
		(pad "DA33" smd circle
			(at -11.380724 10.517886 270)
			(size 0.4318 0.4318)
			(layers "F.Cu" "F.Mask" "F.Paste")
			(net "GND")
		)
		(pad "DA35" smd circle
			(at -9.752838 10.517886 270)
			(size 0.4318 0.4318)
			(layers "F.Cu" "F.Mask" "F.Paste")
			(net "GND")
		)
		(pad "DA37" smd circle
			(at -8.124952 10.517886 270)
			(size 0.4318 0.4318)
			(layers "F.Cu" "F.Mask" "F.Paste")
			(net "GND")
		)
		(pad "DA39" smd circle
			(at -6.49732 10.517886 270)
			(size 0.4318 0.4318)
			(layers "F.Cu" "F.Mask" "F.Paste")
			(net "H_CPU0_PMSYNC_PCH")
		)
		(pad "DA41" smd circle
			(at -4.869434 10.517886 270)
			(size 0.4318 0.4318)
			(layers "F.Cu" "F.Mask" "F.Paste")
			(net "GND")
		)
		(pad "DA43" smd circle
			(at -3.241802 10.517886 270)
			(size 0.4318 0.4318)
			(layers "F.Cu" "F.Mask" "F.Paste")
			(net "GND")
		)
		(pad "DA45" smd circle
			(at -1.613916 10.517886 270)
			(size 0.4318 0.4318)
			(layers "F.Cu" "F.Mask" "F.Paste")
			(net "NC_CPU0_DDR67_VIEWDIG0")
		)
		(pad "DA48" smd circle
			(at 2.427732 10.627868 270)
			(size 0.4318 0.4318)
			(layers "F.Cu" "F.Mask" "F.Paste")
			(net "GND")
		)
		(pad "DA50" smd circle
			(at 4.055618 10.627868 270)
			(size 0.4318 0.4318)
			(layers "F.Cu" "F.Mask" "F.Paste")
			(net "GND")
		)
		(pad "DA52" smd circle
			(at 5.68325 10.627868 270)
			(size 0.4318 0.4318)
			(layers "F.Cu" "F.Mask" "F.Paste")
			(net "TP_CPU0_PROCDIS_COD_GTL_N")
		)
		(pad "DA54" smd circle
			(at 7.311136 10.627868 270)
			(size 0.4318 0.4318)
			(layers "F.Cu" "F.Mask" "F.Paste")
			(net "GND")
		)
		(pad "DA56" smd circle
			(at 8.939022 10.627868 270)
			(size 0.4318 0.4318)
			(layers "F.Cu" "F.Mask" "F.Paste")
			(net "GND")
		)
		(pad "DA58" smd circle
			(at 10.566654 10.627868 270)
			(size 0.4318 0.4318)
			(layers "F.Cu" "F.Mask" "F.Paste")
			(net "GND")
		)
		(pad "DA60" smd circle
			(at 12.19454 10.627868 270)
			(size 0.4318 0.4318)
			(layers "F.Cu" "F.Mask" "F.Paste")
			(net "GND")
		)
		(pad "DA62" smd circle
			(at 13.822426 10.627868 270)
			(size 0.4318 0.4318)
			(layers "F.Cu" "F.Mask" "F.Paste")
			(net "GND")
		)
		(pad "DA64" smd circle
			(at 15.450058 10.627868 270)
			(size 0.4318 0.4318)
			(layers "F.Cu" "F.Mask" "F.Paste")
			(net "PVCCINFAON_CPU0")
		)
		(pad "DA66" smd circle
			(at 17.07769 10.627868 270)
			(size 0.4318 0.4318)
			(layers "F.Cu" "F.Mask" "F.Paste")
			(net "GND")
		)
		(pad "DA68" smd circle
			(at 18.705576 10.627868 270)
			(size 0.4318 0.4318)
			(layers "F.Cu" "F.Mask" "F.Paste")
			(net "GND")
		)
		(pad "DA70" smd circle
			(at 20.333462 10.627868 270)
			(size 0.4318 0.4318)
			(layers "F.Cu" "F.Mask" "F.Paste")
			(net "TP_CPU0_SPARE4")
		)
		(pad "DA72" smd circle
			(at 21.961094 10.627868 270)
			(size 0.4318 0.4318)
			(layers "F.Cu" "F.Mask" "F.Paste")
			(net "GND")
		)
		(pad "DA74" smd circle
			(at 23.58898 10.627868 270)
			(size 0.4318 0.4318)
			(layers "F.Cu" "F.Mask" "F.Paste")
			(net "GND")
		)
		(pad "DA76" smd circle
			(at 25.216612 10.627868 270)
			(size 0.4318 0.4318)
			(layers "F.Cu" "F.Mask" "F.Paste")
			(net "Net_673")
		)
		(pad "DA78" smd circle
			(at 26.844498 10.627868 270)
			(size 0.4318 0.4318)
			(layers "F.Cu" "F.Mask" "F.Paste")
			(net "GND")
		)
		(pad "DA80" smd circle
			(at 28.472384 10.627868 270)
			(size 0.4318 0.4318)
			(layers "F.Cu" "F.Mask" "F.Paste")
			(net "GND")
		)
		(pad "DA82" smd circle
			(at 30.100016 10.627868 270)
			(size 0.4318 0.4318)
			(layers "F.Cu" "F.Mask" "F.Paste")
			(net "GND")
		)
		(pad "DA84" smd circle
			(at 31.727902 10.627868 270)
			(size 0.4318 0.4318)
			(layers "F.Cu" "F.Mask" "F.Paste")
			(net "GND")
		)
		(pad "DA86" smd circle
			(at 33.355534 10.627868 270)
			(size 0.4318 0.4318)
			(layers "F.Cu" "F.Mask" "F.Paste")
			(net "P5E_CPU0_PE3_TX_DP<12>")
		)
		(pad "DA88" smd circle
			(at 34.98342 10.627868 270)
			(size 0.4318 0.4318)
			(layers "F.Cu" "F.Mask" "F.Paste")
			(net "GND")
		)
		(pad "DA90" smd circle
			(at 36.611306 10.627868 270)
			(size 0.4318 0.4318)
			(layers "F.Cu" "F.Mask" "F.Paste")
			(net "P5E_CPU0_PE3_RX_DN<13>")
		)
		(pad "DB2" smd circle
			(at -36.611306 10.987532 270)
			(size 0.4318 0.4318)
			(layers "F.Cu" "F.Mask" "F.Paste")
			(net "UPI_CPU1_CPU0_P0P1_DN<13>")
		)
		(pad "DB4" smd circle
			(at -34.98342 10.987532 270)
			(size 0.4318 0.4318)
			(layers "F.Cu" "F.Mask" "F.Paste")
			(net "GND")
		)
		(pad "DB6" smd circle
			(at -33.355534 10.987532 270)
			(size 0.4318 0.4318)
			(layers "F.Cu" "F.Mask" "F.Paste")
			(net "UPI_CPU0_CPU1_P1P0_DN<12>")
		)
		(pad "DB8" smd circle
			(at -31.727902 10.987532 270)
			(size 0.4318 0.4318)
			(layers "F.Cu" "F.Mask" "F.Paste")
			(net "GND")
		)
		(pad "DB10" smd circle
			(at -30.100016 10.987532 270)
			(size 0.4318 0.4318)
			(layers "F.Cu" "F.Mask" "F.Paste")
			(net "P5E_CPU0_PE2_RX_DP<2>")
		)
		(pad "DB12" smd circle
			(at -28.472384 10.987532 270)
			(size 0.4318 0.4318)
			(layers "F.Cu" "F.Mask" "F.Paste")
			(net "GND")
		)
		(pad "DB14" smd circle
			(at -26.844498 10.987532 270)
			(size 0.4318 0.4318)
			(layers "F.Cu" "F.Mask" "F.Paste")
			(net "P5E_CPU0_PE2_TX_DN<3>")
		)
		(pad "DB16" smd circle
			(at -25.216612 10.987532 270)
			(size 0.4318 0.4318)
			(layers "F.Cu" "F.Mask" "F.Paste")
			(net "GND")
		)
		(pad "DB18" smd circle
			(at -23.58898 10.987532 270)
			(size 0.4318 0.4318)
			(layers "F.Cu" "F.Mask" "F.Paste")
			(net "M_H_CPU0_SB_DQS_DN<3>")
		)
		(pad "DB20" smd circle
			(at -21.961094 10.987532 270)
			(size 0.4318 0.4318)
			(layers "F.Cu" "F.Mask" "F.Paste")
			(net "GND")
		)
		(pad "DB22" smd circle
			(at -20.333462 10.987532 270)
			(size 0.4318 0.4318)
			(layers "F.Cu" "F.Mask" "F.Paste")
			(net "GND")
		)
		(pad "DB24" smd circle
			(at -18.705576 10.987532 270)
			(size 0.4318 0.4318)
			(layers "F.Cu" "F.Mask" "F.Paste")
			(net "M_H_CPU0_SB_DQS_DP<1>")
		)
		(pad "DB26" smd circle
			(at -17.07769 10.987532 270)
			(size 0.4318 0.4318)
			(layers "F.Cu" "F.Mask" "F.Paste")
			(net "GND")
		)
		(pad "DB28" smd circle
			(at -15.450058 10.987532 270)
			(size 0.4318 0.4318)
			(layers "F.Cu" "F.Mask" "F.Paste")
			(net "GND")
		)
		(pad "DB30" smd circle
			(at -13.822426 10.987532 270)
			(size 0.4318 0.4318)
			(layers "F.Cu" "F.Mask" "F.Paste")
			(net "M_H_CPU0_SB_DQS_DP<0>")
		)
		(pad "DB32" smd circle
			(at -12.19454 10.987532 270)
			(size 0.4318 0.4318)
			(layers "F.Cu" "F.Mask" "F.Paste")
			(net "GND")
		)
		(pad "DB34" smd circle
			(at -10.566654 10.987532 270)
			(size 0.4318 0.4318)
			(layers "F.Cu" "F.Mask" "F.Paste")
			(net "GND")
		)
		(pad "DB36" smd circle
			(at -8.939022 10.987532 270)
			(size 0.4318 0.4318)
			(layers "F.Cu" "F.Mask" "F.Paste")
			(net "M_H_CPU0_SB_DQS_DP<9>")
		)
		(pad "DB38" smd circle
			(at -7.311136 10.987532 270)
			(size 0.4318 0.4318)
			(layers "F.Cu" "F.Mask" "F.Paste")
			(net "GND")
		)
		(pad "DB40" smd circle
			(at -5.68325 10.987532 270)
			(size 0.4318 0.4318)
			(layers "F.Cu" "F.Mask" "F.Paste")
			(net "GND")
		)
		(pad "DB42" smd circle
			(at -4.055618 10.987532 270)
			(size 0.4318 0.4318)
			(layers "F.Cu" "F.Mask" "F.Paste")
			(net "M_H_CPU0_CLK_DP<1>")
		)
		(pad "DB44" smd circle
			(at -2.427732 10.987532 270)
			(size 0.4318 0.4318)
			(layers "F.Cu" "F.Mask" "F.Paste")
			(net "GND")
		)
		(pad "DB47" smd circle
			(at 1.613916 11.097514 270)
			(size 0.4318 0.4318)
			(layers "F.Cu" "F.Mask" "F.Paste")
			(net "GND")
		)
		(pad "DB49" smd circle
			(at 3.241802 11.097514 270)
			(size 0.4318 0.4318)
			(layers "F.Cu" "F.Mask" "F.Paste")
			(net "M_H_CPU0_SA_CA<0>")
		)
		(pad "DB51" smd circle
			(at 4.869434 11.097514 270)
			(size 0.4318 0.4318)
			(layers "F.Cu" "F.Mask" "F.Paste")
			(net "GND")
		)
		(pad "DB53" smd circle
			(at 6.49732 11.097514 270)
			(size 0.4318 0.4318)
			(layers "F.Cu" "F.Mask" "F.Paste")
			(net "GND")
		)
		(pad "DB55" smd circle
			(at 8.124952 11.097514 270)
			(size 0.4318 0.4318)
			(layers "F.Cu" "F.Mask" "F.Paste")
			(net "M_H_CPU0_SA_DQS_DP<4>")
		)
		(pad "DB57" smd circle
			(at 9.752838 11.097514 270)
			(size 0.4318 0.4318)
			(layers "F.Cu" "F.Mask" "F.Paste")
			(net "GND")
		)
		(pad "DB59" smd circle
			(at 11.380724 11.097514 270)
			(size 0.4318 0.4318)
			(layers "F.Cu" "F.Mask" "F.Paste")
			(net "GND")
		)
		(pad "DB61" smd circle
			(at 13.008356 11.097514 270)
			(size 0.4318 0.4318)
			(layers "F.Cu" "F.Mask" "F.Paste")
			(net "M_H_CPU0_SA_DQS_DP<3>")
		)
		(pad "DB63" smd circle
			(at 14.635988 11.097514 270)
			(size 0.4318 0.4318)
			(layers "F.Cu" "F.Mask" "F.Paste")
			(net "GND")
		)
		(pad "DB65" smd circle
			(at 16.263874 11.097514 270)
			(size 0.4318 0.4318)
			(layers "F.Cu" "F.Mask" "F.Paste")
			(net "GND")
		)
		(pad "DB67" smd circle
			(at 17.89176 11.097514 270)
			(size 0.4318 0.4318)
			(layers "F.Cu" "F.Mask" "F.Paste")
			(net "M_H_CPU0_SA_DQS_DP<2>")
		)
		(pad "DB69" smd circle
			(at 19.519392 11.097514 270)
			(size 0.4318 0.4318)
			(layers "F.Cu" "F.Mask" "F.Paste")
			(net "GND")
		)
		(pad "DB71" smd circle
			(at 21.147278 11.097514 270)
			(size 0.4318 0.4318)
			(layers "F.Cu" "F.Mask" "F.Paste")
			(net "GND")
		)
		(pad "DB73" smd circle
			(at 22.77491 11.097514 270)
			(size 0.4318 0.4318)
			(layers "F.Cu" "F.Mask" "F.Paste")
			(net "M_H_CPU0_SA_DQS_DN<1>")
		)
		(pad "DB75" smd circle
			(at 24.402796 11.097514 270)
			(size 0.4318 0.4318)
			(layers "F.Cu" "F.Mask" "F.Paste")
			(net "GND")
		)
		(pad "DB77" smd circle
			(at 26.030682 11.097514 270)
			(size 0.4318 0.4318)
			(layers "F.Cu" "F.Mask" "F.Paste")
			(net "GND")
		)
		(pad "DB79" smd circle
			(at 27.658314 11.097514 270)
			(size 0.4318 0.4318)
			(layers "F.Cu" "F.Mask" "F.Paste")
			(net "GND")
		)
		(pad "DB81" smd circle
			(at 29.2862 11.097514 270)
			(size 0.4318 0.4318)
			(layers "F.Cu" "F.Mask" "F.Paste")
			(net "GND")
		)
		(pad "DB83" smd circle
			(at 30.914086 11.097514 270)
			(size 0.4318 0.4318)
			(layers "F.Cu" "F.Mask" "F.Paste")
			(net "GND")
		)
		(pad "DB85" smd circle
			(at 32.541718 11.097514 270)
			(size 0.4318 0.4318)
			(layers "F.Cu" "F.Mask" "F.Paste")
			(net "P5E_CPU0_PE3_TX_DN<11>")
		)
		(pad "DB87" smd circle
			(at 34.169604 11.097514 270)
			(size 0.4318 0.4318)
			(layers "F.Cu" "F.Mask" "F.Paste")
			(net "GND")
		)
		(pad "DB89" smd circle
			(at 35.797236 11.097514 270)
			(size 0.4318 0.4318)
			(layers "F.Cu" "F.Mask" "F.Paste")
			(net "P5E_CPU0_PE3_RX_DN<12>")
		)
		(pad "DB91" smd oval
			(at 37.425122 11.097514)
			(size 0.381 0.4826)
			(drill
				(offset 0 -0.0508)
			)
			(layers "F.Cu" "F.Mask" "F.Paste")
			(net "GND")
		)
		(pad "DC1" smd oval
			(at -37.425122 11.457686 180)
			(size 0.381 0.4826)
			(drill
				(offset 0 -0.0508)
			)
			(layers "F.Cu" "F.Mask" "F.Paste")
			(net "GND")
		)
		(pad "DC3" smd circle
			(at -35.797236 11.457686 270)
			(size 0.4318 0.4318)
			(layers "F.Cu" "F.Mask" "F.Paste")
			(net "UPI_CPU1_CPU0_P0P1_DN<12>")
		)
		(pad "DC5" smd circle
			(at -34.169604 11.457686 270)
			(size 0.4318 0.4318)
			(layers "F.Cu" "F.Mask" "F.Paste")
			(net "GND")
		)
		(pad "DC7" smd circle
			(at -32.541718 11.457686 270)
			(size 0.4318 0.4318)
			(layers "F.Cu" "F.Mask" "F.Paste")
			(net "UPI_CPU0_CPU1_P1P0_DN<11>")
		)
		(pad "DC9" smd circle
			(at -30.914086 11.457686 270)
			(size 0.4318 0.4318)
			(layers "F.Cu" "F.Mask" "F.Paste")
			(net "GND")
		)
		(pad "DC11" smd circle
			(at -29.2862 11.457686 270)
			(size 0.4318 0.4318)
			(layers "F.Cu" "F.Mask" "F.Paste")
			(net "P5E_CPU0_PE2_RX_DP<3>")
		)
		(pad "DC13" smd circle
			(at -27.658314 11.457686 270)
			(size 0.4318 0.4318)
			(layers "F.Cu" "F.Mask" "F.Paste")
			(net "GND")
		)
		(pad "DC15" smd circle
			(at -26.030682 11.457686 270)
			(size 0.4318 0.4318)
			(layers "F.Cu" "F.Mask" "F.Paste")
			(net "P5E_CPU0_PE2_TX_DP<3>")
		)
		(pad "DC17" smd circle
			(at -24.402796 11.457686 270)
			(size 0.4318 0.4318)
			(layers "F.Cu" "F.Mask" "F.Paste")
			(net "M_H_CPU0_SB_DQ<31>")
		)
		(pad "DC19" smd circle
			(at -22.77491 11.457686 270)
			(size 0.4318 0.4318)
			(layers "F.Cu" "F.Mask" "F.Paste")
			(net "M_H_CPU0_SB_DQ<25>")
		)
		(pad "DC21" smd circle
			(at -21.147278 11.457686 270)
			(size 0.4318 0.4318)
			(layers "F.Cu" "F.Mask" "F.Paste")
			(net "GND")
		)
		(pad "DC23" smd circle
			(at -19.519392 11.457686 270)
			(size 0.4318 0.4318)
			(layers "F.Cu" "F.Mask" "F.Paste")
			(net "M_H_CPU0_SB_DQ<12>")
		)
		(pad "DC25" smd circle
			(at -17.89176 11.457686 270)
			(size 0.4318 0.4318)
			(layers "F.Cu" "F.Mask" "F.Paste")
			(net "M_H_CPU0_SB_DQ<9>")
		)
		(pad "DC27" smd circle
			(at -16.263874 11.457686 270)
			(size 0.4318 0.4318)
			(layers "F.Cu" "F.Mask" "F.Paste")
			(net "GND")
		)
		(pad "DC29" smd circle
			(at -14.635988 11.457686 270)
			(size 0.4318 0.4318)
			(layers "F.Cu" "F.Mask" "F.Paste")
			(net "M_H_CPU0_SB_DQ<4>")
		)
		(pad "DC31" smd circle
			(at -13.008356 11.457686 270)
			(size 0.4318 0.4318)
			(layers "F.Cu" "F.Mask" "F.Paste")
			(net "M_H_CPU0_SB_DQ<1>")
		)
		(pad "DC33" smd circle
			(at -11.380724 11.457686 270)
			(size 0.4318 0.4318)
			(layers "F.Cu" "F.Mask" "F.Paste")
			(net "GND")
		)
		(pad "DC35" smd circle
			(at -9.752838 11.457686 270)
			(size 0.4318 0.4318)
			(layers "F.Cu" "F.Mask" "F.Paste")
			(net "M_H_CPU0_SB_CB<0>")
		)
		(pad "DC37" smd circle
			(at -8.124952 11.457686 270)
			(size 0.4318 0.4318)
			(layers "F.Cu" "F.Mask" "F.Paste")
			(net "M_H_CPU0_SB_CB<7>")
		)
		(pad "DC39" smd circle
			(at -6.49732 11.457686 270)
			(size 0.4318 0.4318)
			(layers "F.Cu" "F.Mask" "F.Paste")
			(net "GND")
		)
		(pad "DC41" smd circle
			(at -4.869434 11.457686 270)
			(size 0.4318 0.4318)
			(layers "F.Cu" "F.Mask" "F.Paste")
			(net "M_H_CPU0_SA_CA<6>")
		)
		(pad "DC43" smd circle
			(at -3.241802 11.457686 270)
			(size 0.4318 0.4318)
			(layers "F.Cu" "F.Mask" "F.Paste")
			(net "M_E_CPU0_SA_RSP<1>")
		)
		(pad "DC45" smd circle
			(at -1.613916 11.457686 270)
			(size 0.4318 0.4318)
			(layers "F.Cu" "F.Mask" "F.Paste")
			(net "GND")
		)
		(pad "DC48" smd circle
			(at 2.427732 11.567668 270)
			(size 0.4318 0.4318)
			(layers "F.Cu" "F.Mask" "F.Paste")
			(net "M_H_CPU0_SA_CA<2>")
		)
		(pad "DC50" smd circle
			(at 4.055618 11.567668 270)
			(size 0.4318 0.4318)
			(layers "F.Cu" "F.Mask" "F.Paste")
			(net "M_H_CPU0_SA_CS_N<3>")
		)
		(pad "DC52" smd circle
			(at 5.68325 11.567668 270)
			(size 0.4318 0.4318)
			(layers "F.Cu" "F.Mask" "F.Paste")
			(net "GND")
		)
		(pad "DC54" smd circle
			(at 7.311136 11.567668 270)
			(size 0.4318 0.4318)
			(layers "F.Cu" "F.Mask" "F.Paste")
			(net "M_H_CPU0_SA_CB<4>")
		)
		(pad "DC56" smd circle
			(at 8.939022 11.567668 270)
			(size 0.4318 0.4318)
			(layers "F.Cu" "F.Mask" "F.Paste")
			(net "M_H_CPU0_SA_CB<1>")
		)
		(pad "DC58" smd circle
			(at 10.566654 11.567668 270)
			(size 0.4318 0.4318)
			(layers "F.Cu" "F.Mask" "F.Paste")
			(net "GND")
		)
		(pad "DC60" smd circle
			(at 12.19454 11.567668 270)
			(size 0.4318 0.4318)
			(layers "F.Cu" "F.Mask" "F.Paste")
			(net "M_H_CPU0_SA_DQ<28>")
		)
		(pad "DC62" smd circle
			(at 13.822426 11.567668 270)
			(size 0.4318 0.4318)
			(layers "F.Cu" "F.Mask" "F.Paste")
			(net "M_H_CPU0_SA_DQ<25>")
		)
		(pad "DC64" smd circle
			(at 15.450058 11.567668 270)
			(size 0.4318 0.4318)
			(layers "F.Cu" "F.Mask" "F.Paste")
			(net "GND")
		)
		(pad "DC66" smd circle
			(at 17.07769 11.567668 270)
			(size 0.4318 0.4318)
			(layers "F.Cu" "F.Mask" "F.Paste")
			(net "M_H_CPU0_SA_DQ<20>")
		)
		(pad "DC68" smd circle
			(at 18.705576 11.567668 270)
			(size 0.4318 0.4318)
			(layers "F.Cu" "F.Mask" "F.Paste")
			(net "M_H_CPU0_SA_DQ<17>")
		)
		(pad "DC70" smd circle
			(at 20.333462 11.567668 270)
			(size 0.4318 0.4318)
			(layers "F.Cu" "F.Mask" "F.Paste")
			(net "GND")
		)
		(pad "DC72" smd circle
			(at 21.961094 11.567668 270)
			(size 0.4318 0.4318)
			(layers "F.Cu" "F.Mask" "F.Paste")
			(net "M_H_CPU0_SA_DQ<12>")
		)
		(pad "DC74" smd circle
			(at 23.58898 11.567668 270)
			(size 0.4318 0.4318)
			(layers "F.Cu" "F.Mask" "F.Paste")
			(net "M_H_CPU0_SA_DQ<9>")
		)
		(pad "DC76" smd circle
			(at 25.216612 11.567668 270)
			(size 0.4318 0.4318)
			(layers "F.Cu" "F.Mask" "F.Paste")
			(net "GND")
		)
		(pad "DC78" smd circle
			(at 26.844498 11.567668 270)
			(size 0.4318 0.4318)
			(layers "F.Cu" "F.Mask" "F.Paste")
			(net "GND")
		)
		(pad "DC80" smd circle
			(at 28.472384 11.567668 270)
			(size 0.4318 0.4318)
			(layers "F.Cu" "F.Mask" "F.Paste")
			(net "GND")
		)
		(pad "DC82" smd circle
			(at 30.100016 11.567668 270)
			(size 0.4318 0.4318)
			(layers "F.Cu" "F.Mask" "F.Paste")
			(net "GND")
		)
		(pad "DC84" smd circle
			(at 31.727902 11.567668 270)
			(size 0.4318 0.4318)
			(layers "F.Cu" "F.Mask" "F.Paste")
			(net "GND")
		)
		(pad "DC86" smd circle
			(at 33.355534 11.567668 270)
			(size 0.4318 0.4318)
			(layers "F.Cu" "F.Mask" "F.Paste")
			(net "P5E_CPU0_PE3_TX_DP<11>")
		)
		(pad "DC88" smd circle
			(at 34.98342 11.567668 270)
			(size 0.4318 0.4318)
			(layers "F.Cu" "F.Mask" "F.Paste")
			(net "GND")
		)
		(pad "DC90" smd circle
			(at 36.611306 11.567668 270)
			(size 0.4318 0.4318)
			(layers "F.Cu" "F.Mask" "F.Paste")
			(net "P5E_CPU0_PE3_RX_DP<12>")
		)
		(pad "DD2" smd circle
			(at -36.611306 11.927332 270)
			(size 0.4318 0.4318)
			(layers "F.Cu" "F.Mask" "F.Paste")
			(net "UPI_CPU1_CPU0_P0P1_DP<12>")
		)
		(pad "DD4" smd circle
			(at -34.98342 11.927332 270)
			(size 0.4318 0.4318)
			(layers "F.Cu" "F.Mask" "F.Paste")
			(net "GND")
		)
		(pad "DD6" smd circle
			(at -33.355534 11.927332 270)
			(size 0.4318 0.4318)
			(layers "F.Cu" "F.Mask" "F.Paste")
			(net "UPI_CPU0_CPU1_P1P0_DP<11>")
		)
		(pad "DD8" smd circle
			(at -31.727902 11.927332 270)
			(size 0.4318 0.4318)
			(layers "F.Cu" "F.Mask" "F.Paste")
			(net "GND")
		)
		(pad "DD10" smd circle
			(at -30.100016 11.927332 270)
			(size 0.4318 0.4318)
			(layers "F.Cu" "F.Mask" "F.Paste")
			(net "P5E_CPU0_PE2_RX_DN<3>")
		)
		(pad "DD12" smd circle
			(at -28.472384 11.927332 270)
			(size 0.4318 0.4318)
			(layers "F.Cu" "F.Mask" "F.Paste")
			(net "GND")
		)
		(pad "DD14" smd circle
			(at -26.844498 11.927332 270)
			(size 0.4318 0.4318)
			(layers "F.Cu" "F.Mask" "F.Paste")
			(net "P5E_CPU0_PE2_TX_DP<4>")
		)
		(pad "DD16" smd circle
			(at -25.216612 11.927332 270)
			(size 0.4318 0.4318)
			(layers "F.Cu" "F.Mask" "F.Paste")
			(net "GND")
		)
		(pad "DD18" smd circle
			(at -23.58898 11.927332 270)
			(size 0.4318 0.4318)
			(layers "F.Cu" "F.Mask" "F.Paste")
			(net "M_H_CPU0_SB_DQS_DP<3>")
		)
		(pad "DD20" smd circle
			(at -21.961094 11.927332 270)
			(size 0.4318 0.4318)
			(layers "F.Cu" "F.Mask" "F.Paste")
			(net "M_H_CPU0_SB_DQ<24>")
		)
		(pad "DD22" smd circle
			(at -20.333462 11.927332 270)
			(size 0.4318 0.4318)
			(layers "F.Cu" "F.Mask" "F.Paste")
			(net "M_H_CPU0_SB_DQ<13>")
		)
		(pad "DD24" smd circle
			(at -18.705576 11.927332 270)
			(size 0.4318 0.4318)
			(layers "F.Cu" "F.Mask" "F.Paste")
			(net "M_H_CPU0_SB_DQS_DN<1>")
		)
		(pad "DD26" smd circle
			(at -17.07769 11.927332 270)
			(size 0.4318 0.4318)
			(layers "F.Cu" "F.Mask" "F.Paste")
			(net "M_H_CPU0_SB_DQ<8>")
		)
		(pad "DD28" smd circle
			(at -15.450058 11.927332 270)
			(size 0.4318 0.4318)
			(layers "F.Cu" "F.Mask" "F.Paste")
			(net "M_H_CPU0_SB_DQ<7>")
		)
		(pad "DD30" smd circle
			(at -13.822426 11.927332 270)
			(size 0.4318 0.4318)
			(layers "F.Cu" "F.Mask" "F.Paste")
			(net "M_H_CPU0_SB_DQS_DN<0>")
		)
		(pad "DD32" smd circle
			(at -12.19454 11.927332 270)
			(size 0.4318 0.4318)
			(layers "F.Cu" "F.Mask" "F.Paste")
			(net "M_H_CPU0_SB_DQ<0>")
		)
		(pad "DD34" smd circle
			(at -10.566654 11.927332 270)
			(size 0.4318 0.4318)
			(layers "F.Cu" "F.Mask" "F.Paste")
			(net "M_H_CPU0_SB_CB<1>")
		)
		(pad "DD36" smd circle
			(at -8.939022 11.927332 270)
			(size 0.4318 0.4318)
			(layers "F.Cu" "F.Mask" "F.Paste")
			(net "M_H_CPU0_SB_DQS_DN<9>")
		)
		(pad "DD38" smd circle
			(at -7.311136 11.927332 270)
			(size 0.4318 0.4318)
			(layers "F.Cu" "F.Mask" "F.Paste")
			(net "M_H_CPU0_SB_CB<6>")
		)
		(pad "DD40" smd circle
			(at -5.68325 11.927332 270)
			(size 0.4318 0.4318)
			(layers "F.Cu" "F.Mask" "F.Paste")
			(net "M_H_CPU0_SA_PAR")
		)
		(pad "DD42" smd circle
			(at -4.055618 11.927332 270)
			(size 0.4318 0.4318)
			(layers "F.Cu" "F.Mask" "F.Paste")
			(net "M_H_CPU0_CLK_DN<1>")
		)
		(pad "DD44" smd circle
			(at -2.427732 11.927332 270)
			(size 0.4318 0.4318)
			(layers "F.Cu" "F.Mask" "F.Paste")
			(net "M_E_CPU0_SA_RSP<0>")
		)
		(pad "DD47" smd circle
			(at 1.613916 12.037314 270)
			(size 0.4318 0.4318)
			(layers "F.Cu" "F.Mask" "F.Paste")
			(net "M_H_CPU0_SA_CA<4>")
		)
		(pad "DD49" smd circle
			(at 3.241802 12.037314 270)
			(size 0.4318 0.4318)
			(layers "F.Cu" "F.Mask" "F.Paste")
			(net "GND")
		)
		(pad "DD51" smd circle
			(at 4.869434 12.037314 270)
			(size 0.4318 0.4318)
			(layers "F.Cu" "F.Mask" "F.Paste")
			(net "M_H_CPU0_SA_CS_N<2>")
		)
		(pad "DD53" smd circle
			(at 6.49732 12.037314 270)
			(size 0.4318 0.4318)
			(layers "F.Cu" "F.Mask" "F.Paste")
			(net "M_H_CPU0_SA_CB<5>")
		)
		(pad "DD55" smd circle
			(at 8.124952 12.037314 270)
			(size 0.4318 0.4318)
			(layers "F.Cu" "F.Mask" "F.Paste")
			(net "M_H_CPU0_SA_DQS_DN<4>")
		)
		(pad "DD57" smd circle
			(at 9.752838 12.037314 270)
			(size 0.4318 0.4318)
			(layers "F.Cu" "F.Mask" "F.Paste")
			(net "M_H_CPU0_SA_CB<0>")
		)
		(pad "DD59" smd circle
			(at 11.380724 12.037314 270)
			(size 0.4318 0.4318)
			(layers "F.Cu" "F.Mask" "F.Paste")
			(net "M_H_CPU0_SA_DQ<29>")
		)
		(pad "DD61" smd circle
			(at 13.008356 12.037314 270)
			(size 0.4318 0.4318)
			(layers "F.Cu" "F.Mask" "F.Paste")
			(net "M_H_CPU0_SA_DQS_DN<3>")
		)
		(pad "DD63" smd circle
			(at 14.635988 12.037314 270)
			(size 0.4318 0.4318)
			(layers "F.Cu" "F.Mask" "F.Paste")
			(net "M_H_CPU0_SA_DQ<24>")
		)
		(pad "DD65" smd circle
			(at 16.263874 12.037314 270)
			(size 0.4318 0.4318)
			(layers "F.Cu" "F.Mask" "F.Paste")
			(net "M_H_CPU0_SA_DQ<21>")
		)
		(pad "DD67" smd circle
			(at 17.89176 12.037314 270)
			(size 0.4318 0.4318)
			(layers "F.Cu" "F.Mask" "F.Paste")
			(net "M_H_CPU0_SA_DQS_DN<2>")
		)
		(pad "DD69" smd circle
			(at 19.519392 12.037314 270)
			(size 0.4318 0.4318)
			(layers "F.Cu" "F.Mask" "F.Paste")
			(net "M_H_CPU0_SA_DQ<16>")
		)
		(pad "DD71" smd circle
			(at 21.147278 12.037314 270)
			(size 0.4318 0.4318)
			(layers "F.Cu" "F.Mask" "F.Paste")
			(net "M_H_CPU0_SA_DQ<13>")
		)
		(pad "DD73" smd circle
			(at 22.77491 12.037314 270)
			(size 0.4318 0.4318)
			(layers "F.Cu" "F.Mask" "F.Paste")
			(net "M_H_CPU0_SA_DQS_DP<1>")
		)
		(pad "DD75" smd circle
			(at 24.402796 12.037314 270)
			(size 0.4318 0.4318)
			(layers "F.Cu" "F.Mask" "F.Paste")
			(net "M_H_CPU0_SA_DQ<8>")
		)
		(pad "DD77" smd circle
			(at 26.030682 12.037314 270)
			(size 0.4318 0.4318)
			(layers "F.Cu" "F.Mask" "F.Paste")
			(net "PVCCFA_EHV_FIVRA_CPU0")
		)
		(pad "DD79" smd circle
			(at 27.658314 12.037314 270)
			(size 0.4318 0.4318)
			(layers "F.Cu" "F.Mask" "F.Paste")
			(net "GND")
		)
		(pad "DD81" smd circle
			(at 29.2862 12.037314 270)
			(size 0.4318 0.4318)
			(layers "F.Cu" "F.Mask" "F.Paste")
			(net "GND")
		)
		(pad "DD83" smd circle
			(at 30.914086 12.037314 270)
			(size 0.4318 0.4318)
			(layers "F.Cu" "F.Mask" "F.Paste")
			(net "PVCCFA_EHV_FIVRA_CPU0")
		)
		(pad "DD85" smd circle
			(at 32.541718 12.037314 270)
			(size 0.4318 0.4318)
			(layers "F.Cu" "F.Mask" "F.Paste")
			(net "PVCCFA_EHV_FIVRA_CPU0")
		)
		(pad "DD87" smd circle
			(at 34.169604 12.037314 270)
			(size 0.4318 0.4318)
			(layers "F.Cu" "F.Mask" "F.Paste")
			(net "P5E_CPU0_PE3_TX_DN<10>")
		)
		(pad "DD89" smd circle
			(at 35.797236 12.037314 270)
			(size 0.4318 0.4318)
			(layers "F.Cu" "F.Mask" "F.Paste")
			(net "PVCCFA_EHV_FIVRA_CPU0")
		)
		(pad "DD91" smd oval
			(at 37.425122 12.037314)
			(size 0.381 0.4826)
			(drill
				(offset 0 -0.0508)
			)
			(layers "F.Cu" "F.Mask" "F.Paste")
			(net "P5E_CPU0_PE3_RX_DN<11>")
		)
		(pad "DE1" smd oval
			(at -37.425122 12.397486 180)
			(size 0.381 0.4826)
			(drill
				(offset 0 -0.0508)
			)
			(layers "F.Cu" "F.Mask" "F.Paste")
			(net "UPI_CPU1_CPU0_P0P1_DN<11>")
		)
		(pad "DE3" smd circle
			(at -35.797236 12.397486 270)
			(size 0.4318 0.4318)
			(layers "F.Cu" "F.Mask" "F.Paste")
			(net "PVCCINFAON_CPU0")
		)
		(pad "DE5" smd circle
			(at -34.169604 12.397486 270)
			(size 0.4318 0.4318)
			(layers "F.Cu" "F.Mask" "F.Paste")
			(net "UPI_CPU0_CPU1_P1P0_DP<10>")
		)
		(pad "DE7" smd circle
			(at -32.541718 12.397486 270)
			(size 0.4318 0.4318)
			(layers "F.Cu" "F.Mask" "F.Paste")
			(net "PVCCINFAON_CPU0")
		)
		(pad "DE9" smd circle
			(at -30.914086 12.397486 270)
			(size 0.4318 0.4318)
			(layers "F.Cu" "F.Mask" "F.Paste")
			(net "P5E_CPU0_PE2_RX_DN<4>")
		)
		(pad "DE11" smd circle
			(at -29.2862 12.397486 270)
			(size 0.4318 0.4318)
			(layers "F.Cu" "F.Mask" "F.Paste")
			(net "PVCCINFAON_CPU0")
		)
		(pad "DE13" smd circle
			(at -27.658314 12.397486 270)
			(size 0.4318 0.4318)
			(layers "F.Cu" "F.Mask" "F.Paste")
			(net "P5E_CPU0_PE2_TX_DN<4>")
		)
		(pad "DE15" smd circle
			(at -26.030682 12.397486 270)
			(size 0.4318 0.4318)
			(layers "F.Cu" "F.Mask" "F.Paste")
			(net "PVCCINFAON_CPU0")
		)
		(pad "DE17" smd circle
			(at -24.402796 12.397486 270)
			(size 0.4318 0.4318)
			(layers "F.Cu" "F.Mask" "F.Paste")
			(net "GND")
		)
		(pad "DE19" smd circle
			(at -22.77491 12.397486 270)
			(size 0.4318 0.4318)
			(layers "F.Cu" "F.Mask" "F.Paste")
			(net "GND")
		)
		(pad "DE21" smd circle
			(at -21.147278 12.397486 270)
			(size 0.4318 0.4318)
			(layers "F.Cu" "F.Mask" "F.Paste")
			(net "GND")
		)
		(pad "DE23" smd circle
			(at -19.519392 12.397486 270)
			(size 0.4318 0.4318)
			(layers "F.Cu" "F.Mask" "F.Paste")
			(net "GND")
		)
		(pad "DE25" smd circle
			(at -17.89176 12.397486 270)
			(size 0.4318 0.4318)
			(layers "F.Cu" "F.Mask" "F.Paste")
			(net "GND")
		)
		(pad "DE27" smd circle
			(at -16.263874 12.397486 270)
			(size 0.4318 0.4318)
			(layers "F.Cu" "F.Mask" "F.Paste")
			(net "GND")
		)
		(pad "DE29" smd circle
			(at -14.635988 12.397486 270)
			(size 0.4318 0.4318)
			(layers "F.Cu" "F.Mask" "F.Paste")
			(net "GND")
		)
		(pad "DE31" smd circle
			(at -13.008356 12.397486 270)
			(size 0.4318 0.4318)
			(layers "F.Cu" "F.Mask" "F.Paste")
			(net "GND")
		)
		(pad "DE33" smd circle
			(at -11.380724 12.397486 270)
			(size 0.4318 0.4318)
			(layers "F.Cu" "F.Mask" "F.Paste")
			(net "GND")
		)
		(pad "DE35" smd circle
			(at -9.752838 12.397486 270)
			(size 0.4318 0.4318)
			(layers "F.Cu" "F.Mask" "F.Paste")
			(net "GND")
		)
		(pad "DE37" smd circle
			(at -8.124952 12.397486 270)
			(size 0.4318 0.4318)
			(layers "F.Cu" "F.Mask" "F.Paste")
			(net "GND")
		)
		(pad "DE39" smd circle
			(at -6.49732 12.397486 270)
			(size 0.4318 0.4318)
			(layers "F.Cu" "F.Mask" "F.Paste")
			(net "GND")
		)
		(pad "DE41" smd circle
			(at -4.869434 12.397486 270)
			(size 0.4318 0.4318)
			(layers "F.Cu" "F.Mask" "F.Paste")
			(net "GND")
		)
		(pad "DE43" smd circle
			(at -3.241802 12.397486 270)
			(size 0.4318 0.4318)
			(layers "F.Cu" "F.Mask" "F.Paste")
			(net "GND")
		)
		(pad "DE45" smd circle
			(at -1.613916 12.397486 270)
			(size 0.4318 0.4318)
			(layers "F.Cu" "F.Mask" "F.Paste")
			(net "GND")
		)
		(pad "DE48" smd circle
			(at 2.427732 12.507468 270)
			(size 0.4318 0.4318)
			(layers "F.Cu" "F.Mask" "F.Paste")
			(net "GND")
		)
		(pad "DE50" smd circle
			(at 4.055618 12.507468 270)
			(size 0.4318 0.4318)
			(layers "F.Cu" "F.Mask" "F.Paste")
			(net "GND")
		)
		(pad "DE52" smd circle
			(at 5.68325 12.507468 270)
			(size 0.4318 0.4318)
			(layers "F.Cu" "F.Mask" "F.Paste")
			(net "GND")
		)
		(pad "DE54" smd circle
			(at 7.311136 12.507468 270)
			(size 0.4318 0.4318)
			(layers "F.Cu" "F.Mask" "F.Paste")
			(net "GND")
		)
		(pad "DE56" smd circle
			(at 8.939022 12.507468 270)
			(size 0.4318 0.4318)
			(layers "F.Cu" "F.Mask" "F.Paste")
			(net "GND")
		)
		(pad "DE58" smd circle
			(at 10.566654 12.507468 270)
			(size 0.4318 0.4318)
			(layers "F.Cu" "F.Mask" "F.Paste")
			(net "GND")
		)
		(pad "DE60" smd circle
			(at 12.19454 12.507468 270)
			(size 0.4318 0.4318)
			(layers "F.Cu" "F.Mask" "F.Paste")
			(net "GND")
		)
		(pad "DE62" smd circle
			(at 13.822426 12.507468 270)
			(size 0.4318 0.4318)
			(layers "F.Cu" "F.Mask" "F.Paste")
			(net "GND")
		)
		(pad "DE64" smd circle
			(at 15.450058 12.507468 270)
			(size 0.4318 0.4318)
			(layers "F.Cu" "F.Mask" "F.Paste")
			(net "GND")
		)
		(pad "DE66" smd circle
			(at 17.07769 12.507468 270)
			(size 0.4318 0.4318)
			(layers "F.Cu" "F.Mask" "F.Paste")
			(net "GND")
		)
		(pad "DE68" smd circle
			(at 18.705576 12.507468 270)
			(size 0.4318 0.4318)
			(layers "F.Cu" "F.Mask" "F.Paste")
			(net "GND")
		)
		(pad "DE70" smd circle
			(at 20.333462 12.507468 270)
			(size 0.4318 0.4318)
			(layers "F.Cu" "F.Mask" "F.Paste")
			(net "GND")
		)
		(pad "DE72" smd circle
			(at 21.961094 12.507468 270)
			(size 0.4318 0.4318)
			(layers "F.Cu" "F.Mask" "F.Paste")
			(net "GND")
		)
		(pad "DE74" smd circle
			(at 23.58898 12.507468 270)
			(size 0.4318 0.4318)
			(layers "F.Cu" "F.Mask" "F.Paste")
			(net "GND")
		)
		(pad "DE76" smd circle
			(at 25.216612 12.507468 270)
			(size 0.4318 0.4318)
			(layers "F.Cu" "F.Mask" "F.Paste")
			(net "GND")
		)
		(pad "DE78" smd circle
			(at 26.844498 12.507468 270)
			(size 0.4318 0.4318)
			(layers "F.Cu" "F.Mask" "F.Paste")
			(net "GND")
		)
		(pad "DE80" smd circle
			(at 28.472384 12.507468 270)
			(size 0.4318 0.4318)
			(layers "F.Cu" "F.Mask" "F.Paste")
			(net "GND")
		)
		(pad "DE82" smd circle
			(at 30.100016 12.507468 270)
			(size 0.4318 0.4318)
			(layers "F.Cu" "F.Mask" "F.Paste")
			(net "GND")
		)
		(pad "DE84" smd circle
			(at 31.727902 12.507468 270)
			(size 0.4318 0.4318)
			(layers "F.Cu" "F.Mask" "F.Paste")
			(net "GND")
		)
		(pad "DE86" smd circle
			(at 33.355534 12.507468 270)
			(size 0.4318 0.4318)
			(layers "F.Cu" "F.Mask" "F.Paste")
			(net "P5E_CPU0_PE3_TX_DP<10>")
		)
		(pad "DE88" smd circle
			(at 34.98342 12.507468 270)
			(size 0.4318 0.4318)
			(layers "F.Cu" "F.Mask" "F.Paste")
			(net "GND")
		)
		(pad "DE90" smd circle
			(at 36.611306 12.507468 270)
			(size 0.4318 0.4318)
			(layers "F.Cu" "F.Mask" "F.Paste")
			(net "P5E_CPU0_PE3_RX_DP<11>")
		)
		(pad "DF2" smd circle
			(at -36.611306 12.867132 270)
			(size 0.4318 0.4318)
			(layers "F.Cu" "F.Mask" "F.Paste")
			(net "UPI_CPU1_CPU0_P0P1_DP<11>")
		)
		(pad "DF4" smd circle
			(at -34.98342 12.867132 270)
			(size 0.4318 0.4318)
			(layers "F.Cu" "F.Mask" "F.Paste")
			(net "GND")
		)
		(pad "DF6" smd circle
			(at -33.355534 12.867132 270)
			(size 0.4318 0.4318)
			(layers "F.Cu" "F.Mask" "F.Paste")
			(net "UPI_CPU0_CPU1_P1P0_DN<10>")
		)
		(pad "DF8" smd circle
			(at -31.727902 12.867132 270)
			(size 0.4318 0.4318)
			(layers "F.Cu" "F.Mask" "F.Paste")
			(net "GND")
		)
		(pad "DF10" smd circle
			(at -30.100016 12.867132 270)
			(size 0.4318 0.4318)
			(layers "F.Cu" "F.Mask" "F.Paste")
			(net "P5E_CPU0_PE2_RX_DP<4>")
		)
		(pad "DF12" smd circle
			(at -28.472384 12.867132 270)
			(size 0.4318 0.4318)
			(layers "F.Cu" "F.Mask" "F.Paste")
			(net "GND")
		)
		(pad "DF14" smd circle
			(at -26.844498 12.867132 270)
			(size 0.4318 0.4318)
			(layers "F.Cu" "F.Mask" "F.Paste")
			(net "P5E_CPU0_PE2_TX_DN<5>")
		)
		(pad "DF16" smd circle
			(at -25.216612 12.867132 270)
			(size 0.4318 0.4318)
			(layers "F.Cu" "F.Mask" "F.Paste")
			(net "GND")
		)
		(pad "DF18" smd circle
			(at -23.58898 12.867132 270)
			(size 0.4318 0.4318)
			(layers "F.Cu" "F.Mask" "F.Paste")
			(net "M_H_CPU0_SB_DQS_DN<8>")
		)
		(pad "DF20" smd circle
			(at -21.961094 12.867132 270)
			(size 0.4318 0.4318)
			(layers "F.Cu" "F.Mask" "F.Paste")
			(net "M_H_CPU0_SB_DQ<26>")
		)
		(pad "DF22" smd circle
			(at -20.333462 12.867132 270)
			(size 0.4318 0.4318)
			(layers "F.Cu" "F.Mask" "F.Paste")
			(net "M_H_CPU0_SB_DQ<15>")
		)
		(pad "DF24" smd circle
			(at -18.705576 12.867132 270)
			(size 0.4318 0.4318)
			(layers "F.Cu" "F.Mask" "F.Paste")
			(net "M_H_CPU0_SB_DQS_DP<6>")
		)
		(pad "DF26" smd circle
			(at -17.07769 12.867132 270)
			(size 0.4318 0.4318)
			(layers "F.Cu" "F.Mask" "F.Paste")
			(net "M_H_CPU0_SB_DQ<10>")
		)
		(pad "DF28" smd circle
			(at -15.450058 12.867132 270)
			(size 0.4318 0.4318)
			(layers "F.Cu" "F.Mask" "F.Paste")
			(net "M_H_CPU0_SB_DQ<5>")
		)
		(pad "DF30" smd circle
			(at -13.822426 12.867132 270)
			(size 0.4318 0.4318)
			(layers "F.Cu" "F.Mask" "F.Paste")
			(net "M_H_CPU0_SB_DQS_DP<5>")
		)
		(pad "DF32" smd circle
			(at -12.19454 12.867132 270)
			(size 0.4318 0.4318)
			(layers "F.Cu" "F.Mask" "F.Paste")
			(net "M_H_CPU0_SB_DQ<2>")
		)
		(pad "DF34" smd circle
			(at -10.566654 12.867132 270)
			(size 0.4318 0.4318)
			(layers "F.Cu" "F.Mask" "F.Paste")
			(net "M_H_CPU0_SB_CB<3>")
		)
		(pad "DF36" smd circle
			(at -8.939022 12.867132 270)
			(size 0.4318 0.4318)
			(layers "F.Cu" "F.Mask" "F.Paste")
			(net "M_H_CPU0_SB_DQS_DP<4>")
		)
		(pad "DF38" smd circle
			(at -7.311136 12.867132 270)
			(size 0.4318 0.4318)
			(layers "F.Cu" "F.Mask" "F.Paste")
			(net "M_H_CPU0_SB_CB<4>")
		)
		(pad "DF40" smd circle
			(at -5.68325 12.867132 270)
			(size 0.4318 0.4318)
			(layers "F.Cu" "F.Mask" "F.Paste")
			(net "M_H_CPU0_SB_CA<0>")
		)
		(pad "DF42" smd circle
			(at -4.055618 12.867132 270)
			(size 0.4318 0.4318)
			(layers "F.Cu" "F.Mask" "F.Paste")
			(net "M_H_CPU0_CLK_DP<0>")
		)
		(pad "DF44" smd circle
			(at -2.427732 12.867132 270)
			(size 0.4318 0.4318)
			(layers "F.Cu" "F.Mask" "F.Paste")
			(net "M_E_CPU0_SB_RSP<0>")
		)
		(pad "DF47" smd circle
			(at 1.613916 12.977114 270)
			(size 0.4318 0.4318)
			(layers "F.Cu" "F.Mask" "F.Paste")
			(net "M_H_CPU0_SA_CA<5>")
		)
		(pad "DF49" smd circle
			(at 3.241802 12.977114 270)
			(size 0.4318 0.4318)
			(layers "F.Cu" "F.Mask" "F.Paste")
			(net "GND")
		)
		(pad "DF51" smd circle
			(at 4.869434 12.977114 270)
			(size 0.4318 0.4318)
			(layers "F.Cu" "F.Mask" "F.Paste")
			(net "M_H_CPU0_SA_CS_N<0>")
		)
		(pad "DF53" smd circle
			(at 6.49732 12.977114 270)
			(size 0.4318 0.4318)
			(layers "F.Cu" "F.Mask" "F.Paste")
			(net "M_H_CPU0_SA_CB<7>")
		)
		(pad "DF55" smd circle
			(at 8.124952 12.977114 270)
			(size 0.4318 0.4318)
			(layers "F.Cu" "F.Mask" "F.Paste")
			(net "M_H_CPU0_SA_DQS_DP<9>")
		)
		(pad "DF57" smd circle
			(at 9.752838 12.977114 270)
			(size 0.4318 0.4318)
			(layers "F.Cu" "F.Mask" "F.Paste")
			(net "M_H_CPU0_SA_CB<2>")
		)
		(pad "DF59" smd circle
			(at 11.380724 12.977114 270)
			(size 0.4318 0.4318)
			(layers "F.Cu" "F.Mask" "F.Paste")
			(net "M_H_CPU0_SA_DQ<31>")
		)
		(pad "DF61" smd circle
			(at 13.008356 12.977114 270)
			(size 0.4318 0.4318)
			(layers "F.Cu" "F.Mask" "F.Paste")
			(net "M_H_CPU0_SA_DQS_DP<8>")
		)
		(pad "DF63" smd circle
			(at 14.635988 12.977114 270)
			(size 0.4318 0.4318)
			(layers "F.Cu" "F.Mask" "F.Paste")
			(net "M_H_CPU0_SA_DQ<26>")
		)
		(pad "DF65" smd circle
			(at 16.263874 12.977114 270)
			(size 0.4318 0.4318)
			(layers "F.Cu" "F.Mask" "F.Paste")
			(net "M_H_CPU0_SA_DQ<23>")
		)
		(pad "DF67" smd circle
			(at 17.89176 12.977114 270)
			(size 0.4318 0.4318)
			(layers "F.Cu" "F.Mask" "F.Paste")
			(net "M_H_CPU0_SA_DQS_DP<7>")
		)
		(pad "DF69" smd circle
			(at 19.519392 12.977114 270)
			(size 0.4318 0.4318)
			(layers "F.Cu" "F.Mask" "F.Paste")
			(net "M_H_CPU0_SA_DQ<18>")
		)
		(pad "DF71" smd circle
			(at 21.147278 12.977114 270)
			(size 0.4318 0.4318)
			(layers "F.Cu" "F.Mask" "F.Paste")
			(net "M_H_CPU0_SA_DQ<15>")
		)
		(pad "DF73" smd circle
			(at 22.77491 12.977114 270)
			(size 0.4318 0.4318)
			(layers "F.Cu" "F.Mask" "F.Paste")
			(net "M_H_CPU0_SA_DQS_DP<6>")
		)
		(pad "DF75" smd circle
			(at 24.402796 12.977114 270)
			(size 0.4318 0.4318)
			(layers "F.Cu" "F.Mask" "F.Paste")
			(net "M_H_CPU0_SA_DQ<10>")
		)
		(pad "DF77" smd circle
			(at 26.030682 12.977114 270)
			(size 0.4318 0.4318)
			(layers "F.Cu" "F.Mask" "F.Paste")
			(net "GND")
		)
		(pad "DF79" smd circle
			(at 27.658314 12.977114 270)
			(size 0.4318 0.4318)
			(layers "F.Cu" "F.Mask" "F.Paste")
			(net "GND")
		)
		(pad "DF81" smd circle
			(at 29.2862 12.977114 270)
			(size 0.4318 0.4318)
			(layers "F.Cu" "F.Mask" "F.Paste")
			(net "GND")
		)
		(pad "DF83" smd circle
			(at 30.914086 12.977114 270)
			(size 0.4318 0.4318)
			(layers "F.Cu" "F.Mask" "F.Paste")
			(net "GND")
		)
		(pad "DF85" smd circle
			(at 32.541718 12.977114 270)
			(size 0.4318 0.4318)
			(layers "F.Cu" "F.Mask" "F.Paste")
			(net "P5E_CPU0_PE3_TX_DN<9>")
		)
		(pad "DF87" smd circle
			(at 34.169604 12.977114 270)
			(size 0.4318 0.4318)
			(layers "F.Cu" "F.Mask" "F.Paste")
			(net "GND")
		)
		(pad "DF89" smd circle
			(at 35.797236 12.977114 270)
			(size 0.4318 0.4318)
			(layers "F.Cu" "F.Mask" "F.Paste")
			(net "P5E_CPU0_PE3_RX_DP<10>")
		)
		(pad "DF91" smd oval
			(at 37.425122 12.977114)
			(size 0.381 0.4826)
			(drill
				(offset 0 -0.0508)
			)
			(layers "F.Cu" "F.Mask" "F.Paste")
			(net "GND")
		)
		(pad "DG1" smd oval
			(at -37.425122 13.337286 180)
			(size 0.381 0.4826)
			(drill
				(offset 0 -0.0508)
			)
			(layers "F.Cu" "F.Mask" "F.Paste")
			(net "GND")
		)
		(pad "DG3" smd circle
			(at -35.797236 13.337286 270)
			(size 0.4318 0.4318)
			(layers "F.Cu" "F.Mask" "F.Paste")
			(net "UPI_CPU1_CPU0_P0P1_DN<10>")
		)
		(pad "DG5" smd circle
			(at -34.169604 13.337286 270)
			(size 0.4318 0.4318)
			(layers "F.Cu" "F.Mask" "F.Paste")
			(net "GND")
		)
		(pad "DG7" smd circle
			(at -32.541718 13.337286 270)
			(size 0.4318 0.4318)
			(layers "F.Cu" "F.Mask" "F.Paste")
			(net "UPI_CPU0_CPU1_P1P0_DP<9>")
		)
		(pad "DG9" smd circle
			(at -30.914086 13.337286 270)
			(size 0.4318 0.4318)
			(layers "F.Cu" "F.Mask" "F.Paste")
			(net "GND")
		)
		(pad "DG11" smd circle
			(at -29.2862 13.337286 270)
			(size 0.4318 0.4318)
			(layers "F.Cu" "F.Mask" "F.Paste")
			(net "P5E_CPU0_PE2_RX_DP<5>")
		)
		(pad "DG13" smd circle
			(at -27.658314 13.337286 270)
			(size 0.4318 0.4318)
			(layers "F.Cu" "F.Mask" "F.Paste")
			(net "GND")
		)
		(pad "DG15" smd circle
			(at -26.030682 13.337286 270)
			(size 0.4318 0.4318)
			(layers "F.Cu" "F.Mask" "F.Paste")
			(net "P5E_CPU0_PE2_TX_DP<5>")
		)
		(pad "DG17" smd circle
			(at -24.402796 13.337286 270)
			(size 0.4318 0.4318)
			(layers "F.Cu" "F.Mask" "F.Paste")
			(net "M_H_CPU0_SB_DQ<28>")
		)
		(pad "DG19" smd circle
			(at -22.77491 13.337286 270)
			(size 0.4318 0.4318)
			(layers "F.Cu" "F.Mask" "F.Paste")
			(net "M_H_CPU0_SB_DQ<27>")
		)
		(pad "DG21" smd circle
			(at -21.147278 13.337286 270)
			(size 0.4318 0.4318)
			(layers "F.Cu" "F.Mask" "F.Paste")
			(net "GND")
		)
		(pad "DG23" smd circle
			(at -19.519392 13.337286 270)
			(size 0.4318 0.4318)
			(layers "F.Cu" "F.Mask" "F.Paste")
			(net "M_H_CPU0_SB_DQ<14>")
		)
		(pad "DG25" smd circle
			(at -17.89176 13.337286 270)
			(size 0.4318 0.4318)
			(layers "F.Cu" "F.Mask" "F.Paste")
			(net "M_H_CPU0_SB_DQ<11>")
		)
		(pad "DG27" smd circle
			(at -16.263874 13.337286 270)
			(size 0.4318 0.4318)
			(layers "F.Cu" "F.Mask" "F.Paste")
			(net "GND")
		)
		(pad "DG29" smd circle
			(at -14.635988 13.337286 270)
			(size 0.4318 0.4318)
			(layers "F.Cu" "F.Mask" "F.Paste")
			(net "M_H_CPU0_SB_DQ<6>")
		)
		(pad "DG31" smd circle
			(at -13.008356 13.337286 270)
			(size 0.4318 0.4318)
			(layers "F.Cu" "F.Mask" "F.Paste")
			(net "M_H_CPU0_SB_DQ<3>")
		)
		(pad "DG33" smd circle
			(at -11.380724 13.337286 270)
			(size 0.4318 0.4318)
			(layers "F.Cu" "F.Mask" "F.Paste")
			(net "GND")
		)
		(pad "DG35" smd circle
			(at -9.752838 13.337286 270)
			(size 0.4318 0.4318)
			(layers "F.Cu" "F.Mask" "F.Paste")
			(net "M_H_CPU0_SB_CB<2>")
		)
		(pad "DG37" smd circle
			(at -8.124952 13.337286 270)
			(size 0.4318 0.4318)
			(layers "F.Cu" "F.Mask" "F.Paste")
			(net "M_H_CPU0_SB_CB<5>")
		)
		(pad "DG39" smd circle
			(at -6.49732 13.337286 270)
			(size 0.4318 0.4318)
			(layers "F.Cu" "F.Mask" "F.Paste")
			(net "GND")
		)
		(pad "DG41" smd circle
			(at -4.869434 13.337286 270)
			(size 0.4318 0.4318)
			(layers "F.Cu" "F.Mask" "F.Paste")
			(net "M_H_CPU0_SB_CA<1>")
		)
		(pad "DG43" smd circle
			(at -3.241802 13.337286 270)
			(size 0.4318 0.4318)
			(layers "F.Cu" "F.Mask" "F.Paste")
			(net "M_E_CPU0_SB_RSP<1>")
		)
		(pad "DG45" smd circle
			(at -1.613916 13.337286 270)
			(size 0.4318 0.4318)
			(layers "F.Cu" "F.Mask" "F.Paste")
			(net "GND")
		)
		(pad "DG48" smd circle
			(at 2.427732 13.447268 270)
			(size 0.4318 0.4318)
			(layers "F.Cu" "F.Mask" "F.Paste")
			(net "M_H_CPU0_SA_CA<3>")
		)
		(pad "DG50" smd circle
			(at 4.055618 13.447268 270)
			(size 0.4318 0.4318)
			(layers "F.Cu" "F.Mask" "F.Paste")
			(net "M_H_CPU0_SA_CS_N<1>")
		)
		(pad "DG52" smd circle
			(at 5.68325 13.447268 270)
			(size 0.4318 0.4318)
			(layers "F.Cu" "F.Mask" "F.Paste")
			(net "GND")
		)
		(pad "DG54" smd circle
			(at 7.311136 13.447268 270)
			(size 0.4318 0.4318)
			(layers "F.Cu" "F.Mask" "F.Paste")
			(net "M_H_CPU0_SA_CB<6>")
		)
		(pad "DG56" smd circle
			(at 8.939022 13.447268 270)
			(size 0.4318 0.4318)
			(layers "F.Cu" "F.Mask" "F.Paste")
			(net "M_H_CPU0_SA_CB<3>")
		)
		(pad "DG58" smd circle
			(at 10.566654 13.447268 270)
			(size 0.4318 0.4318)
			(layers "F.Cu" "F.Mask" "F.Paste")
			(net "GND")
		)
		(pad "DG60" smd circle
			(at 12.19454 13.447268 270)
			(size 0.4318 0.4318)
			(layers "F.Cu" "F.Mask" "F.Paste")
			(net "M_H_CPU0_SA_DQ<30>")
		)
		(pad "DG62" smd circle
			(at 13.822426 13.447268 270)
			(size 0.4318 0.4318)
			(layers "F.Cu" "F.Mask" "F.Paste")
			(net "M_H_CPU0_SA_DQ<27>")
		)
		(pad "DG64" smd circle
			(at 15.450058 13.447268 270)
			(size 0.4318 0.4318)
			(layers "F.Cu" "F.Mask" "F.Paste")
			(net "GND")
		)
		(pad "DG66" smd circle
			(at 17.07769 13.447268 270)
			(size 0.4318 0.4318)
			(layers "F.Cu" "F.Mask" "F.Paste")
			(net "M_H_CPU0_SA_DQ<22>")
		)
		(pad "DG68" smd circle
			(at 18.705576 13.447268 270)
			(size 0.4318 0.4318)
			(layers "F.Cu" "F.Mask" "F.Paste")
			(net "M_H_CPU0_SA_DQ<19>")
		)
		(pad "DG70" smd circle
			(at 20.333462 13.447268 270)
			(size 0.4318 0.4318)
			(layers "F.Cu" "F.Mask" "F.Paste")
			(net "GND")
		)
		(pad "DG72" smd circle
			(at 21.961094 13.447268 270)
			(size 0.4318 0.4318)
			(layers "F.Cu" "F.Mask" "F.Paste")
			(net "M_H_CPU0_SA_DQ<14>")
		)
		(pad "DG74" smd circle
			(at 23.58898 13.447268 270)
			(size 0.4318 0.4318)
			(layers "F.Cu" "F.Mask" "F.Paste")
			(net "M_H_CPU0_SA_DQ<11>")
		)
		(pad "DG76" smd circle
			(at 25.216612 13.447268 270)
			(size 0.4318 0.4318)
			(layers "F.Cu" "F.Mask" "F.Paste")
			(net "GND")
		)
		(pad "DG78" smd circle
			(at 26.844498 13.447268 270)
			(size 0.4318 0.4318)
			(layers "F.Cu" "F.Mask" "F.Paste")
			(net "GND")
		)
		(pad "DG80" smd circle
			(at 28.472384 13.447268 270)
			(size 0.4318 0.4318)
			(layers "F.Cu" "F.Mask" "F.Paste")
			(net "GND")
		)
		(pad "DG82" smd circle
			(at 30.100016 13.447268 270)
			(size 0.4318 0.4318)
			(layers "F.Cu" "F.Mask" "F.Paste")
			(net "GND")
		)
		(pad "DG84" smd circle
			(at 31.727902 13.447268 270)
			(size 0.4318 0.4318)
			(layers "F.Cu" "F.Mask" "F.Paste")
			(net "GND")
		)
		(pad "DG86" smd circle
			(at 33.355534 13.447268 270)
			(size 0.4318 0.4318)
			(layers "F.Cu" "F.Mask" "F.Paste")
			(net "P5E_CPU0_PE3_TX_DP<9>")
		)
		(pad "DG88" smd circle
			(at 34.98342 13.447268 270)
			(size 0.4318 0.4318)
			(layers "F.Cu" "F.Mask" "F.Paste")
			(net "GND")
		)
		(pad "DG90" smd circle
			(at 36.611306 13.447268 270)
			(size 0.4318 0.4318)
			(layers "F.Cu" "F.Mask" "F.Paste")
			(net "P5E_CPU0_PE3_RX_DN<10>")
		)
		(pad "DH2" smd circle
			(at -36.611306 13.806932 270)
			(size 0.4318 0.4318)
			(layers "F.Cu" "F.Mask" "F.Paste")
			(net "UPI_CPU1_CPU0_P0P1_DP<10>")
		)
		(pad "DH4" smd circle
			(at -34.98342 13.806932 270)
			(size 0.4318 0.4318)
			(layers "F.Cu" "F.Mask" "F.Paste")
			(net "GND")
		)
		(pad "DH6" smd circle
			(at -33.355534 13.806932 270)
			(size 0.4318 0.4318)
			(layers "F.Cu" "F.Mask" "F.Paste")
			(net "UPI_CPU0_CPU1_P1P0_DN<9>")
		)
		(pad "DH8" smd circle
			(at -31.727902 13.806932 270)
			(size 0.4318 0.4318)
			(layers "F.Cu" "F.Mask" "F.Paste")
			(net "GND")
		)
		(pad "DH10" smd circle
			(at -30.100016 13.806932 270)
			(size 0.4318 0.4318)
			(layers "F.Cu" "F.Mask" "F.Paste")
			(net "P5E_CPU0_PE2_RX_DN<5>")
		)
		(pad "DH12" smd circle
			(at -28.472384 13.806932 270)
			(size 0.4318 0.4318)
			(layers "F.Cu" "F.Mask" "F.Paste")
			(net "GND")
		)
		(pad "DH14" smd circle
			(at -26.844498 13.806932 270)
			(size 0.4318 0.4318)
			(layers "F.Cu" "F.Mask" "F.Paste")
			(net "P5E_CPU0_PE2_TX_DP<6>")
		)
		(pad "DH16" smd circle
			(at -25.216612 13.806932 270)
			(size 0.4318 0.4318)
			(layers "F.Cu" "F.Mask" "F.Paste")
			(net "GND")
		)
		(pad "DH18" smd circle
			(at -23.58898 13.806932 270)
			(size 0.4318 0.4318)
			(layers "F.Cu" "F.Mask" "F.Paste")
			(net "M_H_CPU0_SB_DQS_DP<8>")
		)
		(pad "DH20" smd circle
			(at -21.961094 13.806932 270)
			(size 0.4318 0.4318)
			(layers "F.Cu" "F.Mask" "F.Paste")
			(net "GND")
		)
		(pad "DH22" smd circle
			(at -20.333462 13.806932 270)
			(size 0.4318 0.4318)
			(layers "F.Cu" "F.Mask" "F.Paste")
			(net "GND")
		)
		(pad "DH24" smd circle
			(at -18.705576 13.806932 270)
			(size 0.4318 0.4318)
			(layers "F.Cu" "F.Mask" "F.Paste")
			(net "M_H_CPU0_SB_DQS_DN<6>")
		)
		(pad "DH26" smd circle
			(at -17.07769 13.806932 270)
			(size 0.4318 0.4318)
			(layers "F.Cu" "F.Mask" "F.Paste")
			(net "GND")
		)
		(pad "DH28" smd circle
			(at -15.450058 13.806932 270)
			(size 0.4318 0.4318)
			(layers "F.Cu" "F.Mask" "F.Paste")
			(net "GND")
		)
		(pad "DH30" smd circle
			(at -13.822426 13.806932 270)
			(size 0.4318 0.4318)
			(layers "F.Cu" "F.Mask" "F.Paste")
			(net "M_H_CPU0_SB_DQS_DN<5>")
		)
		(pad "DH32" smd circle
			(at -12.19454 13.806932 270)
			(size 0.4318 0.4318)
			(layers "F.Cu" "F.Mask" "F.Paste")
			(net "GND")
		)
		(pad "DH34" smd circle
			(at -10.566654 13.806932 270)
			(size 0.4318 0.4318)
			(layers "F.Cu" "F.Mask" "F.Paste")
			(net "GND")
		)
		(pad "DH36" smd circle
			(at -8.939022 13.806932 270)
			(size 0.4318 0.4318)
			(layers "F.Cu" "F.Mask" "F.Paste")
			(net "M_H_CPU0_SB_DQS_DN<4>")
		)
		(pad "DH38" smd circle
			(at -7.311136 13.806932 270)
			(size 0.4318 0.4318)
			(layers "F.Cu" "F.Mask" "F.Paste")
			(net "GND")
		)
		(pad "DH40" smd circle
			(at -5.68325 13.806932 270)
			(size 0.4318 0.4318)
			(layers "F.Cu" "F.Mask" "F.Paste")
			(net "GND")
		)
		(pad "DH42" smd circle
			(at -4.055618 13.806932 270)
			(size 0.4318 0.4318)
			(layers "F.Cu" "F.Mask" "F.Paste")
			(net "M_H_CPU0_CLK_DN<0>")
		)
		(pad "DH44" smd circle
			(at -2.427732 13.806932 270)
			(size 0.4318 0.4318)
			(layers "F.Cu" "F.Mask" "F.Paste")
			(net "GND")
		)
		(pad "DH47" smd circle
			(at 1.613916 13.916914 270)
			(size 0.4318 0.4318)
			(layers "F.Cu" "F.Mask" "F.Paste")
			(net "GND")
		)
		(pad "DH49" smd circle
			(at 3.241802 13.916914 270)
			(size 0.4318 0.4318)
			(layers "F.Cu" "F.Mask" "F.Paste")
			(net "M_H_CPU0_SA_CA<1>")
		)
		(pad "DH51" smd circle
			(at 4.869434 13.916914 270)
			(size 0.4318 0.4318)
			(layers "F.Cu" "F.Mask" "F.Paste")
			(net "GND")
		)
		(pad "DH53" smd circle
			(at 6.49732 13.916914 270)
			(size 0.4318 0.4318)
			(layers "F.Cu" "F.Mask" "F.Paste")
			(net "GND")
		)
		(pad "DH55" smd circle
			(at 8.124952 13.916914 270)
			(size 0.4318 0.4318)
			(layers "F.Cu" "F.Mask" "F.Paste")
			(net "M_H_CPU0_SA_DQS_DN<9>")
		)
		(pad "DH57" smd circle
			(at 9.752838 13.916914 270)
			(size 0.4318 0.4318)
			(layers "F.Cu" "F.Mask" "F.Paste")
			(net "GND")
		)
		(pad "DH59" smd circle
			(at 11.380724 13.916914 270)
			(size 0.4318 0.4318)
			(layers "F.Cu" "F.Mask" "F.Paste")
			(net "GND")
		)
		(pad "DH61" smd circle
			(at 13.008356 13.916914 270)
			(size 0.4318 0.4318)
			(layers "F.Cu" "F.Mask" "F.Paste")
			(net "M_H_CPU0_SA_DQS_DN<8>")
		)
		(pad "DH63" smd circle
			(at 14.635988 13.916914 270)
			(size 0.4318 0.4318)
			(layers "F.Cu" "F.Mask" "F.Paste")
			(net "GND")
		)
		(pad "DH65" smd circle
			(at 16.263874 13.916914 270)
			(size 0.4318 0.4318)
			(layers "F.Cu" "F.Mask" "F.Paste")
			(net "GND")
		)
		(pad "DH67" smd circle
			(at 17.89176 13.916914 270)
			(size 0.4318 0.4318)
			(layers "F.Cu" "F.Mask" "F.Paste")
			(net "M_H_CPU0_SA_DQS_DN<7>")
		)
		(pad "DH69" smd circle
			(at 19.519392 13.916914 270)
			(size 0.4318 0.4318)
			(layers "F.Cu" "F.Mask" "F.Paste")
			(net "GND")
		)
		(pad "DH71" smd circle
			(at 21.147278 13.916914 270)
			(size 0.4318 0.4318)
			(layers "F.Cu" "F.Mask" "F.Paste")
			(net "GND")
		)
		(pad "DH73" smd circle
			(at 22.77491 13.916914 270)
			(size 0.4318 0.4318)
			(layers "F.Cu" "F.Mask" "F.Paste")
			(net "M_H_CPU0_SA_DQS_DN<6>")
		)
		(pad "DH75" smd circle
			(at 24.402796 13.916914 270)
			(size 0.4318 0.4318)
			(layers "F.Cu" "F.Mask" "F.Paste")
			(net "GND")
		)
		(pad "DH77" smd circle
			(at 26.030682 13.916914 270)
			(size 0.4318 0.4318)
			(layers "F.Cu" "F.Mask" "F.Paste")
			(net "GND")
		)
		(pad "DH79" smd circle
			(at 27.658314 13.916914 270)
			(size 0.4318 0.4318)
			(layers "F.Cu" "F.Mask" "F.Paste")
			(net "GND")
		)
		(pad "DH81" smd circle
			(at 29.2862 13.916914 270)
			(size 0.4318 0.4318)
			(layers "F.Cu" "F.Mask" "F.Paste")
			(net "GND")
		)
		(pad "DH83" smd circle
			(at 30.914086 13.916914 270)
			(size 0.4318 0.4318)
			(layers "F.Cu" "F.Mask" "F.Paste")
			(net "GND")
		)
		(pad "DH85" smd circle
			(at 32.541718 13.916914 270)
			(size 0.4318 0.4318)
			(layers "F.Cu" "F.Mask" "F.Paste")
			(net "GND")
		)
		(pad "DH87" smd circle
			(at 34.169604 13.916914 270)
			(size 0.4318 0.4318)
			(layers "F.Cu" "F.Mask" "F.Paste")
			(net "P5E_CPU0_PE3_TX_DN<8>")
		)
		(pad "DH89" smd circle
			(at 35.797236 13.916914 270)
			(size 0.4318 0.4318)
			(layers "F.Cu" "F.Mask" "F.Paste")
			(net "PVCCFA_EHV_FIVRA_CPU0")
		)
		(pad "DH91" smd oval
			(at 37.425122 13.916914)
			(size 0.381 0.4826)
			(drill
				(offset 0 -0.0508)
			)
			(layers "F.Cu" "F.Mask" "F.Paste")
			(net "P5E_CPU0_PE3_RX_DN<9>")
		)
		(pad "DJ1" smd oval
			(at -37.425122 14.277086 180)
			(size 0.381 0.4826)
			(drill
				(offset 0 -0.0508)
			)
			(layers "F.Cu" "F.Mask" "F.Paste")
			(net "UPI_CPU1_CPU0_P0P1_DN<9>")
		)
		(pad "DJ3" smd circle
			(at -35.797236 14.277086 270)
			(size 0.4318 0.4318)
			(layers "F.Cu" "F.Mask" "F.Paste")
			(net "PVCCINFAON_CPU0")
		)
		(pad "DJ5" smd circle
			(at -34.169604 14.277086 270)
			(size 0.4318 0.4318)
			(layers "F.Cu" "F.Mask" "F.Paste")
			(net "UPI_CPU0_CPU1_P1P0_DP<8>")
		)
		(pad "DJ7" smd circle
			(at -32.541718 14.277086 270)
			(size 0.4318 0.4318)
			(layers "F.Cu" "F.Mask" "F.Paste")
			(net "PVCCINFAON_CPU0")
		)
		(pad "DJ9" smd circle
			(at -30.914086 14.277086 270)
			(size 0.4318 0.4318)
			(layers "F.Cu" "F.Mask" "F.Paste")
			(net "P5E_CPU0_PE2_RX_DN<6>")
		)
		(pad "DJ11" smd circle
			(at -29.2862 14.277086 270)
			(size 0.4318 0.4318)
			(layers "F.Cu" "F.Mask" "F.Paste")
			(net "PVCCINFAON_CPU0")
		)
		(pad "DJ13" smd circle
			(at -27.658314 14.277086 270)
			(size 0.4318 0.4318)
			(layers "F.Cu" "F.Mask" "F.Paste")
			(net "P5E_CPU0_PE2_TX_DN<6>")
		)
		(pad "DJ15" smd circle
			(at -26.030682 14.277086 270)
			(size 0.4318 0.4318)
			(layers "F.Cu" "F.Mask" "F.Paste")
			(net "PVCCINFAON_CPU0")
		)
		(pad "DJ17" smd circle
			(at -24.402796 14.277086 270)
			(size 0.4318 0.4318)
			(layers "F.Cu" "F.Mask" "F.Paste")
			(net "M_H_CPU0_SB_DQ<30>")
		)
		(pad "DJ19" smd circle
			(at -22.77491 14.277086 270)
			(size 0.4318 0.4318)
			(layers "F.Cu" "F.Mask" "F.Paste")
			(net "GND")
		)
		(pad "DJ21" smd circle
			(at -21.147278 14.277086 270)
			(size 0.4318 0.4318)
			(layers "F.Cu" "F.Mask" "F.Paste")
			(net "M_H_CPU0_SB_DQS_DP<2>")
		)
		(pad "DJ23" smd circle
			(at -19.519392 14.277086 270)
			(size 0.4318 0.4318)
			(layers "F.Cu" "F.Mask" "F.Paste")
			(net "GND")
		)
		(pad "DJ25" smd circle
			(at -17.89176 14.277086 270)
			(size 0.4318 0.4318)
			(layers "F.Cu" "F.Mask" "F.Paste")
			(net "GND")
		)
		(pad "DJ27" smd circle
			(at -16.263874 14.277086 270)
			(size 0.4318 0.4318)
			(layers "F.Cu" "F.Mask" "F.Paste")
			(net "M_G_CPU0_SB_DQS_DN<1>")
		)
		(pad "DJ29" smd circle
			(at -14.635988 14.277086 270)
			(size 0.4318 0.4318)
			(layers "F.Cu" "F.Mask" "F.Paste")
			(net "GND")
		)
		(pad "DJ31" smd circle
			(at -13.008356 14.277086 270)
			(size 0.4318 0.4318)
			(layers "F.Cu" "F.Mask" "F.Paste")
			(net "GND")
		)
		(pad "DJ33" smd circle
			(at -11.380724 14.277086 270)
			(size 0.4318 0.4318)
			(layers "F.Cu" "F.Mask" "F.Paste")
			(net "M_G_CPU0_SB_DQS_DN<0>")
		)
		(pad "DJ35" smd circle
			(at -9.752838 14.277086 270)
			(size 0.4318 0.4318)
			(layers "F.Cu" "F.Mask" "F.Paste")
			(net "GND")
		)
		(pad "DJ37" smd circle
			(at -8.124952 14.277086 270)
			(size 0.4318 0.4318)
			(layers "F.Cu" "F.Mask" "F.Paste")
			(net "GND")
		)
		(pad "DJ39" smd circle
			(at -6.49732 14.277086 270)
			(size 0.4318 0.4318)
			(layers "F.Cu" "F.Mask" "F.Paste")
			(net "M_H_CPU0_SB_CA<6>")
		)
		(pad "DJ41" smd circle
			(at -4.869434 14.277086 270)
			(size 0.4318 0.4318)
			(layers "F.Cu" "F.Mask" "F.Paste")
			(net "GND")
		)
		(pad "DJ43" smd circle
			(at -3.241802 14.277086 270)
			(size 0.4318 0.4318)
			(layers "F.Cu" "F.Mask" "F.Paste")
			(net "GND")
		)
		(pad "DJ45" smd circle
			(at -1.613916 14.277086 270)
			(size 0.4318 0.4318)
			(layers "F.Cu" "F.Mask" "F.Paste")
			(net "M_G_CPU0_CLK_DP<1>")
		)
		(pad "DJ48" smd circle
			(at 2.427732 14.387068 270)
			(size 0.4318 0.4318)
			(layers "F.Cu" "F.Mask" "F.Paste")
			(net "GND")
		)
		(pad "DJ50" smd circle
			(at 4.055618 14.387068 270)
			(size 0.4318 0.4318)
			(layers "F.Cu" "F.Mask" "F.Paste")
			(net "GND")
		)
		(pad "DJ52" smd circle
			(at 5.68325 14.387068 270)
			(size 0.4318 0.4318)
			(layers "F.Cu" "F.Mask" "F.Paste")
			(net "M_G_CPU0_SA_CA<0>")
		)
		(pad "DJ54" smd circle
			(at 7.311136 14.387068 270)
			(size 0.4318 0.4318)
			(layers "F.Cu" "F.Mask" "F.Paste")
			(net "GND")
		)
		(pad "DJ56" smd circle
			(at 8.939022 14.387068 270)
			(size 0.4318 0.4318)
			(layers "F.Cu" "F.Mask" "F.Paste")
			(net "GND")
		)
		(pad "DJ58" smd circle
			(at 10.566654 14.387068 270)
			(size 0.4318 0.4318)
			(layers "F.Cu" "F.Mask" "F.Paste")
			(net "M_G_CPU0_SA_DQS_DP<4>")
		)
		(pad "DJ60" smd circle
			(at 12.19454 14.387068 270)
			(size 0.4318 0.4318)
			(layers "F.Cu" "F.Mask" "F.Paste")
			(net "GND")
		)
		(pad "DJ62" smd circle
			(at 13.822426 14.387068 270)
			(size 0.4318 0.4318)
			(layers "F.Cu" "F.Mask" "F.Paste")
			(net "GND")
		)
		(pad "DJ64" smd circle
			(at 15.450058 14.387068 270)
			(size 0.4318 0.4318)
			(layers "F.Cu" "F.Mask" "F.Paste")
			(net "M_G_CPU0_SA_DQS_DP<3>")
		)
		(pad "DJ66" smd circle
			(at 17.07769 14.387068 270)
			(size 0.4318 0.4318)
			(layers "F.Cu" "F.Mask" "F.Paste")
			(net "GND")
		)
		(pad "DJ68" smd circle
			(at 18.705576 14.387068 270)
			(size 0.4318 0.4318)
			(layers "F.Cu" "F.Mask" "F.Paste")
			(net "GND")
		)
		(pad "DJ70" smd circle
			(at 20.333462 14.387068 270)
			(size 0.4318 0.4318)
			(layers "F.Cu" "F.Mask" "F.Paste")
			(net "M_G_CPU0_SA_DQS_DN<1>")
		)
		(pad "DJ72" smd circle
			(at 21.961094 14.387068 270)
			(size 0.4318 0.4318)
			(layers "F.Cu" "F.Mask" "F.Paste")
			(net "GND")
		)
		(pad "DJ74" smd circle
			(at 23.58898 14.387068 270)
			(size 0.4318 0.4318)
			(layers "F.Cu" "F.Mask" "F.Paste")
			(net "GND")
		)
		(pad "DJ76" smd circle
			(at 25.216612 14.387068 270)
			(size 0.4318 0.4318)
			(layers "F.Cu" "F.Mask" "F.Paste")
			(net "M_H_CPU0_SA_DQS_DN<0>")
		)
		(pad "DJ78" smd circle
			(at 26.844498 14.387068 270)
			(size 0.4318 0.4318)
			(layers "F.Cu" "F.Mask" "F.Paste")
			(net "GND")
		)
		(pad "DJ80" smd circle
			(at 28.472384 14.387068 270)
			(size 0.4318 0.4318)
			(layers "F.Cu" "F.Mask" "F.Paste")
			(net "GND")
		)
		(pad "DJ82" smd circle
			(at 30.100016 14.387068 270)
			(size 0.4318 0.4318)
			(layers "F.Cu" "F.Mask" "F.Paste")
			(net "GND")
		)
		(pad "DJ84" smd circle
			(at 31.727902 14.387068 270)
			(size 0.4318 0.4318)
			(layers "F.Cu" "F.Mask" "F.Paste")
			(net "GND")
		)
		(pad "DJ86" smd circle
			(at 33.355534 14.387068 270)
			(size 0.4318 0.4318)
			(layers "F.Cu" "F.Mask" "F.Paste")
			(net "P5E_CPU0_PE3_TX_DP<8>")
		)
		(pad "DJ88" smd circle
			(at 34.98342 14.387068 270)
			(size 0.4318 0.4318)
			(layers "F.Cu" "F.Mask" "F.Paste")
			(net "GND")
		)
		(pad "DJ90" smd circle
			(at 36.611306 14.387068 270)
			(size 0.4318 0.4318)
			(layers "F.Cu" "F.Mask" "F.Paste")
			(net "P5E_CPU0_PE3_RX_DP<9>")
		)
		(pad "DK2" smd circle
			(at -36.611306 14.746732 270)
			(size 0.4318 0.4318)
			(layers "F.Cu" "F.Mask" "F.Paste")
			(net "UPI_CPU1_CPU0_P0P1_DP<9>")
		)
		(pad "DK4" smd circle
			(at -34.98342 14.746732 270)
			(size 0.4318 0.4318)
			(layers "F.Cu" "F.Mask" "F.Paste")
			(net "GND")
		)
		(pad "DK6" smd circle
			(at -33.355534 14.746732 270)
			(size 0.4318 0.4318)
			(layers "F.Cu" "F.Mask" "F.Paste")
			(net "UPI_CPU0_CPU1_P1P0_DN<8>")
		)
		(pad "DK8" smd circle
			(at -31.727902 14.746732 270)
			(size 0.4318 0.4318)
			(layers "F.Cu" "F.Mask" "F.Paste")
			(net "GND")
		)
		(pad "DK10" smd circle
			(at -30.100016 14.746732 270)
			(size 0.4318 0.4318)
			(layers "F.Cu" "F.Mask" "F.Paste")
			(net "P5E_CPU0_PE2_RX_DP<6>")
		)
		(pad "DK12" smd circle
			(at -28.472384 14.746732 270)
			(size 0.4318 0.4318)
			(layers "F.Cu" "F.Mask" "F.Paste")
			(net "GND")
		)
		(pad "DK14" smd circle
			(at -26.844498 14.746732 270)
			(size 0.4318 0.4318)
			(layers "F.Cu" "F.Mask" "F.Paste")
			(net "P5E_CPU0_PE2_TX_DN<7>")
		)
		(pad "DK16" smd circle
			(at -25.216612 14.746732 270)
			(size 0.4318 0.4318)
			(layers "F.Cu" "F.Mask" "F.Paste")
			(net "GND")
		)
		(pad "DK18" smd circle
			(at -23.58898 14.746732 270)
			(size 0.4318 0.4318)
			(layers "F.Cu" "F.Mask" "F.Paste")
			(net "GND")
		)
		(pad "DK20" smd circle
			(at -21.961094 14.746732 270)
			(size 0.4318 0.4318)
			(layers "F.Cu" "F.Mask" "F.Paste")
			(net "M_H_CPU0_SB_DQ<20>")
		)
		(pad "DK22" smd circle
			(at -20.333462 14.746732 270)
			(size 0.4318 0.4318)
			(layers "F.Cu" "F.Mask" "F.Paste")
			(net "M_H_CPU0_SB_DQ<17>")
		)
		(pad "DK24" smd circle
			(at -18.705576 14.746732 270)
			(size 0.4318 0.4318)
			(layers "F.Cu" "F.Mask" "F.Paste")
			(net "GND")
		)
		(pad "DK26" smd circle
			(at -17.07769 14.746732 270)
			(size 0.4318 0.4318)
			(layers "F.Cu" "F.Mask" "F.Paste")
			(net "M_G_CPU0_SB_DQ<12>")
		)
		(pad "DK28" smd circle
			(at -15.450058 14.746732 270)
			(size 0.4318 0.4318)
			(layers "F.Cu" "F.Mask" "F.Paste")
			(net "M_G_CPU0_SB_DQ<9>")
		)
		(pad "DK30" smd circle
			(at -13.822426 14.746732 270)
			(size 0.4318 0.4318)
			(layers "F.Cu" "F.Mask" "F.Paste")
			(net "GND")
		)
		(pad "DK32" smd circle
			(at -12.19454 14.746732 270)
			(size 0.4318 0.4318)
			(layers "F.Cu" "F.Mask" "F.Paste")
			(net "M_G_CPU0_SB_DQ<4>")
		)
		(pad "DK34" smd circle
			(at -10.566654 14.746732 270)
			(size 0.4318 0.4318)
			(layers "F.Cu" "F.Mask" "F.Paste")
			(net "M_G_CPU0_SB_DQ<1>")
		)
		(pad "DK36" smd circle
			(at -8.939022 14.746732 270)
			(size 0.4318 0.4318)
			(layers "F.Cu" "F.Mask" "F.Paste")
			(net "GND")
		)
		(pad "DK38" smd circle
			(at -7.311136 14.746732 270)
			(size 0.4318 0.4318)
			(layers "F.Cu" "F.Mask" "F.Paste")
			(net "M_H_CPU0_SB_CS_N<2>")
		)
		(pad "DK40" smd circle
			(at -5.68325 14.746732 270)
			(size 0.4318 0.4318)
			(layers "F.Cu" "F.Mask" "F.Paste")
			(net "M_H_CPU0_SB_CA<4>")
		)
		(pad "DK42" smd circle
			(at -4.055618 14.746732 270)
			(size 0.4318 0.4318)
			(layers "F.Cu" "F.Mask" "F.Paste")
			(net "GND")
		)
		(pad "DK44" smd circle
			(at -2.427732 14.746732 270)
			(size 0.4318 0.4318)
			(layers "F.Cu" "F.Mask" "F.Paste")
			(net "M_G_CPU0_SA_CA<6>")
		)
		(pad "DK47" smd circle
			(at 1.613916 14.856714 270)
			(size 0.4318 0.4318)
			(layers "F.Cu" "F.Mask" "F.Paste")
			(net "M_F_CPU0_SB_RSP<1>")
		)
		(pad "DK49" smd circle
			(at 3.241802 14.856714 270)
			(size 0.4318 0.4318)
			(layers "F.Cu" "F.Mask" "F.Paste")
			(net "GND")
		)
		(pad "DK51" smd circle
			(at 4.869434 14.856714 270)
			(size 0.4318 0.4318)
			(layers "F.Cu" "F.Mask" "F.Paste")
			(net "M_G_CPU0_SA_CA<2>")
		)
		(pad "DK53" smd circle
			(at 6.49732 14.856714 270)
			(size 0.4318 0.4318)
			(layers "F.Cu" "F.Mask" "F.Paste")
			(net "M_G_CPU0_SA_CS_N<3>")
		)
		(pad "DK55" smd circle
			(at 8.124952 14.856714 270)
			(size 0.4318 0.4318)
			(layers "F.Cu" "F.Mask" "F.Paste")
			(net "GND")
		)
		(pad "DK57" smd circle
			(at 9.752838 14.856714 270)
			(size 0.4318 0.4318)
			(layers "F.Cu" "F.Mask" "F.Paste")
			(net "M_G_CPU0_SA_CB<4>")
		)
		(pad "DK59" smd circle
			(at 11.380724 14.856714 270)
			(size 0.4318 0.4318)
			(layers "F.Cu" "F.Mask" "F.Paste")
			(net "M_G_CPU0_SA_CB<1>")
		)
		(pad "DK61" smd circle
			(at 13.008356 14.856714 270)
			(size 0.4318 0.4318)
			(layers "F.Cu" "F.Mask" "F.Paste")
			(net "GND")
		)
		(pad "DK63" smd circle
			(at 14.635988 14.856714 270)
			(size 0.4318 0.4318)
			(layers "F.Cu" "F.Mask" "F.Paste")
			(net "M_G_CPU0_SA_DQ<28>")
		)
		(pad "DK65" smd circle
			(at 16.263874 14.856714 270)
			(size 0.4318 0.4318)
			(layers "F.Cu" "F.Mask" "F.Paste")
			(net "M_G_CPU0_SA_DQ<25>")
		)
		(pad "DK67" smd circle
			(at 17.89176 14.856714 270)
			(size 0.4318 0.4318)
			(layers "F.Cu" "F.Mask" "F.Paste")
			(net "GND")
		)
		(pad "DK69" smd circle
			(at 19.519392 14.856714 270)
			(size 0.4318 0.4318)
			(layers "F.Cu" "F.Mask" "F.Paste")
			(net "M_G_CPU0_SA_DQ<12>")
		)
		(pad "DK71" smd circle
			(at 21.147278 14.856714 270)
			(size 0.4318 0.4318)
			(layers "F.Cu" "F.Mask" "F.Paste")
			(net "M_G_CPU0_SA_DQ<9>")
		)
		(pad "DK73" smd circle
			(at 22.77491 14.856714 270)
			(size 0.4318 0.4318)
			(layers "F.Cu" "F.Mask" "F.Paste")
			(net "GND")
		)
		(pad "DK75" smd circle
			(at 24.402796 14.856714 270)
			(size 0.4318 0.4318)
			(layers "F.Cu" "F.Mask" "F.Paste")
			(net "M_H_CPU0_SA_DQ<4>")
		)
		(pad "DK77" smd circle
			(at 26.030682 14.856714 270)
			(size 0.4318 0.4318)
			(layers "F.Cu" "F.Mask" "F.Paste")
			(net "GND")
		)
		(pad "DK79" smd circle
			(at 27.658314 14.856714 270)
			(size 0.4318 0.4318)
			(layers "F.Cu" "F.Mask" "F.Paste")
			(net "GND")
		)
		(pad "DK81" smd circle
			(at 29.2862 14.856714 270)
			(size 0.4318 0.4318)
			(layers "F.Cu" "F.Mask" "F.Paste")
			(net "GND")
		)
		(pad "DK83" smd circle
			(at 30.914086 14.856714 270)
			(size 0.4318 0.4318)
			(layers "F.Cu" "F.Mask" "F.Paste")
			(net "GND")
		)
		(pad "DK85" smd circle
			(at 32.541718 14.856714 270)
			(size 0.4318 0.4318)
			(layers "F.Cu" "F.Mask" "F.Paste")
			(net "P5E_CPU0_PE3_TX_DN<7>")
		)
		(pad "DK87" smd circle
			(at 34.169604 14.856714 270)
			(size 0.4318 0.4318)
			(layers "F.Cu" "F.Mask" "F.Paste")
			(net "GND")
		)
		(pad "DK89" smd circle
			(at 35.797236 14.856714 270)
			(size 0.4318 0.4318)
			(layers "F.Cu" "F.Mask" "F.Paste")
			(net "P5E_CPU0_PE3_RX_DP<8>")
		)
		(pad "DK91" smd oval
			(at 37.425122 14.856714)
			(size 0.381 0.4826)
			(drill
				(offset 0 -0.0508)
			)
			(layers "F.Cu" "F.Mask" "F.Paste")
			(net "GND")
		)
		(pad "DL1" smd oval
			(at -37.425122 15.216886 180)
			(size 0.381 0.4826)
			(drill
				(offset 0 -0.0508)
			)
			(layers "F.Cu" "F.Mask" "F.Paste")
			(net "GND")
		)
		(pad "DL3" smd circle
			(at -35.797236 15.216886 270)
			(size 0.4318 0.4318)
			(layers "F.Cu" "F.Mask" "F.Paste")
			(net "UPI_CPU1_CPU0_P0P1_DN<8>")
		)
		(pad "DL5" smd circle
			(at -34.169604 15.216886 270)
			(size 0.4318 0.4318)
			(layers "F.Cu" "F.Mask" "F.Paste")
			(net "GND")
		)
		(pad "DL7" smd circle
			(at -32.541718 15.216886 270)
			(size 0.4318 0.4318)
			(layers "F.Cu" "F.Mask" "F.Paste")
			(net "UPI_CPU0_CPU1_P1P0_DN<7>")
		)
		(pad "DL9" smd circle
			(at -30.914086 15.216886 270)
			(size 0.4318 0.4318)
			(layers "F.Cu" "F.Mask" "F.Paste")
			(net "GND")
		)
		(pad "DL11" smd circle
			(at -29.2862 15.216886 270)
			(size 0.4318 0.4318)
			(layers "F.Cu" "F.Mask" "F.Paste")
			(net "P5E_CPU0_PE2_RX_DP<7>")
		)
		(pad "DL13" smd circle
			(at -27.658314 15.216886 270)
			(size 0.4318 0.4318)
			(layers "F.Cu" "F.Mask" "F.Paste")
			(net "GND")
		)
		(pad "DL15" smd circle
			(at -26.030682 15.216886 270)
			(size 0.4318 0.4318)
			(layers "F.Cu" "F.Mask" "F.Paste")
			(net "P5E_CPU0_PE2_TX_DP<7>")
		)
		(pad "DL17" smd circle
			(at -24.402796 15.216886 270)
			(size 0.4318 0.4318)
			(layers "F.Cu" "F.Mask" "F.Paste")
			(net "GND")
		)
		(pad "DL19" smd circle
			(at -22.77491 15.216886 270)
			(size 0.4318 0.4318)
			(layers "F.Cu" "F.Mask" "F.Paste")
			(net "M_H_CPU0_SB_DQ<21>")
		)
		(pad "DL21" smd circle
			(at -21.147278 15.216886 270)
			(size 0.4318 0.4318)
			(layers "F.Cu" "F.Mask" "F.Paste")
			(net "M_H_CPU0_SB_DQS_DN<2>")
		)
		(pad "DL23" smd circle
			(at -19.519392 15.216886 270)
			(size 0.4318 0.4318)
			(layers "F.Cu" "F.Mask" "F.Paste")
			(net "M_H_CPU0_SB_DQ<16>")
		)
		(pad "DL25" smd circle
			(at -17.89176 15.216886 270)
			(size 0.4318 0.4318)
			(layers "F.Cu" "F.Mask" "F.Paste")
			(net "M_G_CPU0_SB_DQ<13>")
		)
		(pad "DL27" smd circle
			(at -16.263874 15.216886 270)
			(size 0.4318 0.4318)
			(layers "F.Cu" "F.Mask" "F.Paste")
			(net "M_G_CPU0_SB_DQS_DP<1>")
		)
		(pad "DL29" smd circle
			(at -14.635988 15.216886 270)
			(size 0.4318 0.4318)
			(layers "F.Cu" "F.Mask" "F.Paste")
			(net "M_G_CPU0_SB_DQ<10>")
		)
		(pad "DL31" smd circle
			(at -13.008356 15.216886 270)
			(size 0.4318 0.4318)
			(layers "F.Cu" "F.Mask" "F.Paste")
			(net "M_G_CPU0_SB_DQ<5>")
		)
		(pad "DL33" smd circle
			(at -11.380724 15.216886 270)
			(size 0.4318 0.4318)
			(layers "F.Cu" "F.Mask" "F.Paste")
			(net "M_G_CPU0_SB_DQS_DP<0>")
		)
		(pad "DL35" smd circle
			(at -9.752838 15.216886 270)
			(size 0.4318 0.4318)
			(layers "F.Cu" "F.Mask" "F.Paste")
			(net "M_G_CPU0_SB_DQ<0>")
		)
		(pad "DL37" smd circle
			(at -8.124952 15.216886 270)
			(size 0.4318 0.4318)
			(layers "F.Cu" "F.Mask" "F.Paste")
			(net "M_H_CPU0_SB_CS_N<0>")
		)
		(pad "DL39" smd circle
			(at -6.49732 15.216886 270)
			(size 0.4318 0.4318)
			(layers "F.Cu" "F.Mask" "F.Paste")
			(net "GND")
		)
		(pad "DL41" smd circle
			(at -4.869434 15.216886 270)
			(size 0.4318 0.4318)
			(layers "F.Cu" "F.Mask" "F.Paste")
			(net "M_H_CPU0_SB_CA<2>")
		)
		(pad "DL43" smd circle
			(at -3.241802 15.216886 270)
			(size 0.4318 0.4318)
			(layers "F.Cu" "F.Mask" "F.Paste")
			(net "M_G_CPU0_SA_PAR")
		)
		(pad "DL45" smd circle
			(at -1.613916 15.216886 270)
			(size 0.4318 0.4318)
			(layers "F.Cu" "F.Mask" "F.Paste")
			(net "M_G_CPU0_CLK_DN<1>")
		)
		(pad "DL48" smd circle
			(at 2.427732 15.326868 270)
			(size 0.4318 0.4318)
			(layers "F.Cu" "F.Mask" "F.Paste")
			(net "M_F_CPU0_SB_RSP<0>")
		)
		(pad "DL50" smd circle
			(at 4.055618 15.326868 270)
			(size 0.4318 0.4318)
			(layers "F.Cu" "F.Mask" "F.Paste")
			(net "M_G_CPU0_SA_CA<4>")
		)
		(pad "DL52" smd circle
			(at 5.68325 15.326868 270)
			(size 0.4318 0.4318)
			(layers "F.Cu" "F.Mask" "F.Paste")
			(net "GND")
		)
		(pad "DL54" smd circle
			(at 7.311136 15.326868 270)
			(size 0.4318 0.4318)
			(layers "F.Cu" "F.Mask" "F.Paste")
			(net "M_G_CPU0_SA_CS_N<2>")
		)
		(pad "DL56" smd circle
			(at 8.939022 15.326868 270)
			(size 0.4318 0.4318)
			(layers "F.Cu" "F.Mask" "F.Paste")
			(net "M_G_CPU0_SA_CB<5>")
		)
		(pad "DL58" smd circle
			(at 10.566654 15.326868 270)
			(size 0.4318 0.4318)
			(layers "F.Cu" "F.Mask" "F.Paste")
			(net "M_G_CPU0_SA_DQS_DN<4>")
		)
		(pad "DL60" smd circle
			(at 12.19454 15.326868 270)
			(size 0.4318 0.4318)
			(layers "F.Cu" "F.Mask" "F.Paste")
			(net "M_G_CPU0_SA_CB<0>")
		)
		(pad "DL62" smd circle
			(at 13.822426 15.326868 270)
			(size 0.4318 0.4318)
			(layers "F.Cu" "F.Mask" "F.Paste")
			(net "M_G_CPU0_SA_DQ<29>")
		)
		(pad "DL64" smd circle
			(at 15.450058 15.326868 270)
			(size 0.4318 0.4318)
			(layers "F.Cu" "F.Mask" "F.Paste")
			(net "M_G_CPU0_SA_DQS_DN<3>")
		)
		(pad "DL66" smd circle
			(at 17.07769 15.326868 270)
			(size 0.4318 0.4318)
			(layers "F.Cu" "F.Mask" "F.Paste")
			(net "M_G_CPU0_SA_DQ<24>")
		)
		(pad "DL68" smd circle
			(at 18.705576 15.326868 270)
			(size 0.4318 0.4318)
			(layers "F.Cu" "F.Mask" "F.Paste")
			(net "M_G_CPU0_SA_DQ<13>")
		)
		(pad "DL70" smd circle
			(at 20.333462 15.326868 270)
			(size 0.4318 0.4318)
			(layers "F.Cu" "F.Mask" "F.Paste")
			(net "M_G_CPU0_SA_DQS_DP<1>")
		)
		(pad "DL72" smd circle
			(at 21.961094 15.326868 270)
			(size 0.4318 0.4318)
			(layers "F.Cu" "F.Mask" "F.Paste")
			(net "M_G_CPU0_SA_DQ<8>")
		)
		(pad "DL74" smd circle
			(at 23.58898 15.326868 270)
			(size 0.4318 0.4318)
			(layers "F.Cu" "F.Mask" "F.Paste")
			(net "M_H_CPU0_SA_DQ<5>")
		)
		(pad "DL76" smd circle
			(at 25.216612 15.326868 270)
			(size 0.4318 0.4318)
			(layers "F.Cu" "F.Mask" "F.Paste")
			(net "M_H_CPU0_SA_DQS_DP<0>")
		)
		(pad "DL78" smd circle
			(at 26.844498 15.326868 270)
			(size 0.4318 0.4318)
			(layers "F.Cu" "F.Mask" "F.Paste")
			(net "GND")
		)
		(pad "DL80" smd circle
			(at 28.472384 15.326868 270)
			(size 0.4318 0.4318)
			(layers "F.Cu" "F.Mask" "F.Paste")
			(net "Net_698")
		)
		(pad "DL82" smd circle
			(at 30.100016 15.326868 270)
			(size 0.4318 0.4318)
			(layers "F.Cu" "F.Mask" "F.Paste")
			(net "Net_675")
		)
		(pad "DL84" smd circle
			(at 31.727902 15.326868 270)
			(size 0.4318 0.4318)
			(layers "F.Cu" "F.Mask" "F.Paste")
			(net "GND")
		)
		(pad "DL86" smd circle
			(at 33.355534 15.326868 270)
			(size 0.4318 0.4318)
			(layers "F.Cu" "F.Mask" "F.Paste")
			(net "P5E_CPU0_PE3_TX_DP<7>")
		)
		(pad "DL88" smd circle
			(at 34.98342 15.326868 270)
			(size 0.4318 0.4318)
			(layers "F.Cu" "F.Mask" "F.Paste")
			(net "GND")
		)
		(pad "DL90" smd circle
			(at 36.611306 15.326868 270)
			(size 0.4318 0.4318)
			(layers "F.Cu" "F.Mask" "F.Paste")
			(net "P5E_CPU0_PE3_RX_DN<8>")
		)
		(pad "DM2" smd circle
			(at -36.611306 15.686532 270)
			(size 0.4318 0.4318)
			(layers "F.Cu" "F.Mask" "F.Paste")
			(net "UPI_CPU1_CPU0_P0P1_DP<8>")
		)
		(pad "DM4" smd circle
			(at -34.98342 15.686532 270)
			(size 0.4318 0.4318)
			(layers "F.Cu" "F.Mask" "F.Paste")
			(net "GND")
		)
		(pad "DM6" smd circle
			(at -33.355534 15.686532 270)
			(size 0.4318 0.4318)
			(layers "F.Cu" "F.Mask" "F.Paste")
			(net "UPI_CPU0_CPU1_P1P0_DP<7>")
		)
		(pad "DM8" smd circle
			(at -31.727902 15.686532 270)
			(size 0.4318 0.4318)
			(layers "F.Cu" "F.Mask" "F.Paste")
			(net "GND")
		)
		(pad "DM10" smd circle
			(at -30.100016 15.686532 270)
			(size 0.4318 0.4318)
			(layers "F.Cu" "F.Mask" "F.Paste")
			(net "P5E_CPU0_PE2_RX_DN<7>")
		)
		(pad "DM12" smd circle
			(at -28.472384 15.686532 270)
			(size 0.4318 0.4318)
			(layers "F.Cu" "F.Mask" "F.Paste")
			(net "GND")
		)
		(pad "DM14" smd circle
			(at -26.844498 15.686532 270)
			(size 0.4318 0.4318)
			(layers "F.Cu" "F.Mask" "F.Paste")
			(net "P5E_CPU0_PE2_TX_DP<8>")
		)
		(pad "DM16" smd circle
			(at -25.216612 15.686532 270)
			(size 0.4318 0.4318)
			(layers "F.Cu" "F.Mask" "F.Paste")
			(net "GND")
		)
		(pad "DM18" smd circle
			(at -23.58898 15.686532 270)
			(size 0.4318 0.4318)
			(layers "F.Cu" "F.Mask" "F.Paste")
			(net "GND")
		)
		(pad "DM20" smd circle
			(at -21.961094 15.686532 270)
			(size 0.4318 0.4318)
			(layers "F.Cu" "F.Mask" "F.Paste")
			(net "GND")
		)
		(pad "DM22" smd circle
			(at -20.333462 15.686532 270)
			(size 0.4318 0.4318)
			(layers "F.Cu" "F.Mask" "F.Paste")
			(net "GND")
		)
		(pad "DM24" smd circle
			(at -18.705576 15.686532 270)
			(size 0.4318 0.4318)
			(layers "F.Cu" "F.Mask" "F.Paste")
			(net "GND")
		)
		(pad "DM26" smd circle
			(at -17.07769 15.686532 270)
			(size 0.4318 0.4318)
			(layers "F.Cu" "F.Mask" "F.Paste")
			(net "GND")
		)
		(pad "DM28" smd circle
			(at -15.450058 15.686532 270)
			(size 0.4318 0.4318)
			(layers "F.Cu" "F.Mask" "F.Paste")
			(net "GND")
		)
		(pad "DM30" smd circle
			(at -13.822426 15.686532 270)
			(size 0.4318 0.4318)
			(layers "F.Cu" "F.Mask" "F.Paste")
			(net "GND")
		)
		(pad "DM32" smd circle
			(at -12.19454 15.686532 270)
			(size 0.4318 0.4318)
			(layers "F.Cu" "F.Mask" "F.Paste")
			(net "GND")
		)
		(pad "DM34" smd circle
			(at -10.566654 15.686532 270)
			(size 0.4318 0.4318)
			(layers "F.Cu" "F.Mask" "F.Paste")
			(net "GND")
		)
		(pad "DM36" smd circle
			(at -8.939022 15.686532 270)
			(size 0.4318 0.4318)
			(layers "F.Cu" "F.Mask" "F.Paste")
			(net "GND")
		)
		(pad "DM38" smd circle
			(at -7.311136 15.686532 270)
			(size 0.4318 0.4318)
			(layers "F.Cu" "F.Mask" "F.Paste")
			(net "GND")
		)
		(pad "DM40" smd circle
			(at -5.68325 15.686532 270)
			(size 0.4318 0.4318)
			(layers "F.Cu" "F.Mask" "F.Paste")
			(net "GND")
		)
		(pad "DM42" smd circle
			(at -4.055618 15.686532 270)
			(size 0.4318 0.4318)
			(layers "F.Cu" "F.Mask" "F.Paste")
			(net "GND")
		)
		(pad "DM44" smd circle
			(at -2.427732 15.686532 270)
			(size 0.4318 0.4318)
			(layers "F.Cu" "F.Mask" "F.Paste")
			(net "GND")
		)
		(pad "DM47" smd circle
			(at 1.613916 15.796514 270)
			(size 0.4318 0.4318)
			(layers "F.Cu" "F.Mask" "F.Paste")
			(net "GND")
		)
		(pad "DM49" smd circle
			(at 3.241802 15.796514 270)
			(size 0.4318 0.4318)
			(layers "F.Cu" "F.Mask" "F.Paste")
			(net "GND")
		)
		(pad "DM51" smd circle
			(at 4.869434 15.796514 270)
			(size 0.4318 0.4318)
			(layers "F.Cu" "F.Mask" "F.Paste")
			(net "GND")
		)
		(pad "DM53" smd circle
			(at 6.49732 15.796514 270)
			(size 0.4318 0.4318)
			(layers "F.Cu" "F.Mask" "F.Paste")
			(net "GND")
		)
		(pad "DM55" smd circle
			(at 8.124952 15.796514 270)
			(size 0.4318 0.4318)
			(layers "F.Cu" "F.Mask" "F.Paste")
			(net "GND")
		)
		(pad "DM57" smd circle
			(at 9.752838 15.796514 270)
			(size 0.4318 0.4318)
			(layers "F.Cu" "F.Mask" "F.Paste")
			(net "GND")
		)
		(pad "DM59" smd circle
			(at 11.380724 15.796514 270)
			(size 0.4318 0.4318)
			(layers "F.Cu" "F.Mask" "F.Paste")
			(net "GND")
		)
		(pad "DM61" smd circle
			(at 13.008356 15.796514 270)
			(size 0.4318 0.4318)
			(layers "F.Cu" "F.Mask" "F.Paste")
			(net "GND")
		)
		(pad "DM63" smd circle
			(at 14.635988 15.796514 270)
			(size 0.4318 0.4318)
			(layers "F.Cu" "F.Mask" "F.Paste")
			(net "GND")
		)
		(pad "DM65" smd circle
			(at 16.263874 15.796514 270)
			(size 0.4318 0.4318)
			(layers "F.Cu" "F.Mask" "F.Paste")
			(net "GND")
		)
		(pad "DM67" smd circle
			(at 17.89176 15.796514 270)
			(size 0.4318 0.4318)
			(layers "F.Cu" "F.Mask" "F.Paste")
			(net "GND")
		)
		(pad "DM69" smd circle
			(at 19.519392 15.796514 270)
			(size 0.4318 0.4318)
			(layers "F.Cu" "F.Mask" "F.Paste")
			(net "GND")
		)
		(pad "DM71" smd circle
			(at 21.147278 15.796514 270)
			(size 0.4318 0.4318)
			(layers "F.Cu" "F.Mask" "F.Paste")
			(net "GND")
		)
		(pad "DM73" smd circle
			(at 22.77491 15.796514 270)
			(size 0.4318 0.4318)
			(layers "F.Cu" "F.Mask" "F.Paste")
			(net "GND")
		)
		(pad "DM75" smd circle
			(at 24.402796 15.796514 270)
			(size 0.4318 0.4318)
			(layers "F.Cu" "F.Mask" "F.Paste")
			(net "GND")
		)
		(pad "DM77" smd circle
			(at 26.030682 15.796514 270)
			(size 0.4318 0.4318)
			(layers "F.Cu" "F.Mask" "F.Paste")
			(net "GND")
		)
		(pad "DM79" smd circle
			(at 27.658314 15.796514 270)
			(size 0.4318 0.4318)
			(layers "F.Cu" "F.Mask" "F.Paste")
			(net "GND")
		)
		(pad "DM81" smd circle
			(at 29.2862 15.796514 270)
			(size 0.4318 0.4318)
			(layers "F.Cu" "F.Mask" "F.Paste")
			(net "Net_699")
		)
		(pad "DM83" smd circle
			(at 30.914086 15.796514 270)
			(size 0.4318 0.4318)
			(layers "F.Cu" "F.Mask" "F.Paste")
			(net "PVCCFA_EHV_FIVRA_CPU0")
		)
		(pad "DM85" smd circle
			(at 32.541718 15.796514 270)
			(size 0.4318 0.4318)
			(layers "F.Cu" "F.Mask" "F.Paste")
			(net "PVCCFA_EHV_FIVRA_CPU0")
		)
		(pad "DM87" smd circle
			(at 34.169604 15.796514 270)
			(size 0.4318 0.4318)
			(layers "F.Cu" "F.Mask" "F.Paste")
			(net "P5E_CPU0_PE3_TX_DN<6>")
		)
		(pad "DM89" smd circle
			(at 35.797236 15.796514 270)
			(size 0.4318 0.4318)
			(layers "F.Cu" "F.Mask" "F.Paste")
			(net "PVCCFA_EHV_FIVRA_CPU0")
		)
		(pad "DM91" smd oval
			(at 37.425122 15.796514)
			(size 0.381 0.4826)
			(drill
				(offset 0 -0.0508)
			)
			(layers "F.Cu" "F.Mask" "F.Paste")
			(net "P5E_CPU0_PE3_RX_DP<7>")
		)
		(pad "DN1" smd oval
			(at -37.425122 16.156686 180)
			(size 0.381 0.4826)
			(drill
				(offset 0 -0.0508)
			)
			(layers "F.Cu" "F.Mask" "F.Paste")
			(net "UPI_CPU1_CPU0_P0P1_DN<7>")
		)
		(pad "DN3" smd circle
			(at -35.797236 16.156686 270)
			(size 0.4318 0.4318)
			(layers "F.Cu" "F.Mask" "F.Paste")
			(net "PVCCFA_EHV_FIVRA_CPU0")
		)
		(pad "DN5" smd circle
			(at -34.169604 16.156686 270)
			(size 0.4318 0.4318)
			(layers "F.Cu" "F.Mask" "F.Paste")
			(net "UPI_CPU0_CPU1_P1P0_DP<6>")
		)
		(pad "DN7" smd circle
			(at -32.541718 16.156686 270)
			(size 0.4318 0.4318)
			(layers "F.Cu" "F.Mask" "F.Paste")
			(net "PVCCFA_EHV_FIVRA_CPU0")
		)
		(pad "DN9" smd circle
			(at -30.914086 16.156686 270)
			(size 0.4318 0.4318)
			(layers "F.Cu" "F.Mask" "F.Paste")
			(net "P5E_CPU0_PE2_RX_DN<8>")
		)
		(pad "DN11" smd circle
			(at -29.2862 16.156686 270)
			(size 0.4318 0.4318)
			(layers "F.Cu" "F.Mask" "F.Paste")
			(net "PVCCFA_EHV_FIVRA_CPU0")
		)
		(pad "DN13" smd circle
			(at -27.658314 16.156686 270)
			(size 0.4318 0.4318)
			(layers "F.Cu" "F.Mask" "F.Paste")
			(net "P5E_CPU0_PE2_TX_DN<8>")
		)
		(pad "DN15" smd circle
			(at -26.030682 16.156686 270)
			(size 0.4318 0.4318)
			(layers "F.Cu" "F.Mask" "F.Paste")
			(net "PVCCFA_EHV_FIVRA_CPU0")
		)
		(pad "DN17" smd circle
			(at -24.402796 16.156686 270)
			(size 0.4318 0.4318)
			(layers "F.Cu" "F.Mask" "F.Paste")
			(net "GND")
		)
		(pad "DN19" smd circle
			(at -22.77491 16.156686 270)
			(size 0.4318 0.4318)
			(layers "F.Cu" "F.Mask" "F.Paste")
			(net "M_H_CPU0_SB_DQ<23>")
		)
		(pad "DN21" smd circle
			(at -21.147278 16.156686 270)
			(size 0.4318 0.4318)
			(layers "F.Cu" "F.Mask" "F.Paste")
			(net "M_H_CPU0_SB_DQS_DP<7>")
		)
		(pad "DN23" smd circle
			(at -19.519392 16.156686 270)
			(size 0.4318 0.4318)
			(layers "F.Cu" "F.Mask" "F.Paste")
			(net "M_H_CPU0_SB_DQ<18>")
		)
		(pad "DN25" smd circle
			(at -17.89176 16.156686 270)
			(size 0.4318 0.4318)
			(layers "F.Cu" "F.Mask" "F.Paste")
			(net "M_G_CPU0_SB_DQ<15>")
		)
		(pad "DN27" smd circle
			(at -16.263874 16.156686 270)
			(size 0.4318 0.4318)
			(layers "F.Cu" "F.Mask" "F.Paste")
			(net "M_G_CPU0_SB_DQS_DN<6>")
		)
		(pad "DN29" smd circle
			(at -14.635988 16.156686 270)
			(size 0.4318 0.4318)
			(layers "F.Cu" "F.Mask" "F.Paste")
			(net "M_G_CPU0_SB_DQ<8>")
		)
		(pad "DN31" smd circle
			(at -13.008356 16.156686 270)
			(size 0.4318 0.4318)
			(layers "F.Cu" "F.Mask" "F.Paste")
			(net "M_G_CPU0_SB_DQ<7>")
		)
		(pad "DN33" smd circle
			(at -11.380724 16.156686 270)
			(size 0.4318 0.4318)
			(layers "F.Cu" "F.Mask" "F.Paste")
			(net "M_G_CPU0_SB_DQS_DP<5>")
		)
		(pad "DN35" smd circle
			(at -9.752838 16.156686 270)
			(size 0.4318 0.4318)
			(layers "F.Cu" "F.Mask" "F.Paste")
			(net "M_G_CPU0_SB_DQ<2>")
		)
		(pad "DN37" smd circle
			(at -8.124952 16.156686 270)
			(size 0.4318 0.4318)
			(layers "F.Cu" "F.Mask" "F.Paste")
			(net "M_H_CPU0_SB_CS_N<1>")
		)
		(pad "DN39" smd circle
			(at -6.49732 16.156686 270)
			(size 0.4318 0.4318)
			(layers "F.Cu" "F.Mask" "F.Paste")
			(net "GND")
		)
		(pad "DN41" smd circle
			(at -4.869434 16.156686 270)
			(size 0.4318 0.4318)
			(layers "F.Cu" "F.Mask" "F.Paste")
			(net "M_H_CPU0_SB_CA<3>")
		)
		(pad "DN43" smd circle
			(at -3.241802 16.156686 270)
			(size 0.4318 0.4318)
			(layers "F.Cu" "F.Mask" "F.Paste")
			(net "M_G_CPU0_SB_CA<0>")
		)
		(pad "DN45" smd circle
			(at -1.613916 16.156686 270)
			(size 0.4318 0.4318)
			(layers "F.Cu" "F.Mask" "F.Paste")
			(net "M_G_CPU0_CLK_DP<0>")
		)
		(pad "DN48" smd circle
			(at 2.427732 16.266668 270)
			(size 0.4318 0.4318)
			(layers "F.Cu" "F.Mask" "F.Paste")
			(net "M_F_CPU0_SA_RSP<0>")
		)
		(pad "DN50" smd circle
			(at 4.055618 16.266668 270)
			(size 0.4318 0.4318)
			(layers "F.Cu" "F.Mask" "F.Paste")
			(net "M_G_CPU0_SA_CA<5>")
		)
		(pad "DN52" smd circle
			(at 5.68325 16.266668 270)
			(size 0.4318 0.4318)
			(layers "F.Cu" "F.Mask" "F.Paste")
			(net "GND")
		)
		(pad "DN54" smd circle
			(at 7.311136 16.266668 270)
			(size 0.4318 0.4318)
			(layers "F.Cu" "F.Mask" "F.Paste")
			(net "M_G_CPU0_SA_CS_N<0>")
		)
		(pad "DN56" smd circle
			(at 8.939022 16.266668 270)
			(size 0.4318 0.4318)
			(layers "F.Cu" "F.Mask" "F.Paste")
			(net "M_G_CPU0_SA_CB<7>")
		)
		(pad "DN58" smd circle
			(at 10.566654 16.266668 270)
			(size 0.4318 0.4318)
			(layers "F.Cu" "F.Mask" "F.Paste")
			(net "M_G_CPU0_SA_DQS_DP<9>")
		)
		(pad "DN60" smd circle
			(at 12.19454 16.266668 270)
			(size 0.4318 0.4318)
			(layers "F.Cu" "F.Mask" "F.Paste")
			(net "M_G_CPU0_SA_CB<2>")
		)
		(pad "DN62" smd circle
			(at 13.822426 16.266668 270)
			(size 0.4318 0.4318)
			(layers "F.Cu" "F.Mask" "F.Paste")
			(net "M_G_CPU0_SA_DQ<31>")
		)
		(pad "DN64" smd circle
			(at 15.450058 16.266668 270)
			(size 0.4318 0.4318)
			(layers "F.Cu" "F.Mask" "F.Paste")
			(net "M_G_CPU0_SA_DQS_DP<8>")
		)
		(pad "DN66" smd circle
			(at 17.07769 16.266668 270)
			(size 0.4318 0.4318)
			(layers "F.Cu" "F.Mask" "F.Paste")
			(net "M_G_CPU0_SA_DQ<26>")
		)
		(pad "DN68" smd circle
			(at 18.705576 16.266668 270)
			(size 0.4318 0.4318)
			(layers "F.Cu" "F.Mask" "F.Paste")
			(net "M_G_CPU0_SA_DQ<15>")
		)
		(pad "DN70" smd circle
			(at 20.333462 16.266668 270)
			(size 0.4318 0.4318)
			(layers "F.Cu" "F.Mask" "F.Paste")
			(net "M_G_CPU0_SA_DQS_DP<6>")
		)
		(pad "DN72" smd circle
			(at 21.961094 16.266668 270)
			(size 0.4318 0.4318)
			(layers "F.Cu" "F.Mask" "F.Paste")
			(net "M_G_CPU0_SA_DQ<10>")
		)
		(pad "DN74" smd circle
			(at 23.58898 16.266668 270)
			(size 0.4318 0.4318)
			(layers "F.Cu" "F.Mask" "F.Paste")
			(net "M_H_CPU0_SA_DQ<7>")
		)
		(pad "DN76" smd circle
			(at 25.216612 16.266668 270)
			(size 0.4318 0.4318)
			(layers "F.Cu" "F.Mask" "F.Paste")
			(net "M_H_CPU0_SA_DQS_DP<5>")
		)
		(pad "DN78" smd circle
			(at 26.844498 16.266668 270)
			(size 0.4318 0.4318)
			(layers "F.Cu" "F.Mask" "F.Paste")
			(net "GND")
		)
		(pad "DN80" smd circle
			(at 28.472384 16.266668 270)
			(size 0.4318 0.4318)
			(layers "F.Cu" "F.Mask" "F.Paste")
			(net "Net_674")
		)
		(pad "DN82" smd circle
			(at 30.100016 16.266668 270)
			(size 0.4318 0.4318)
			(layers "F.Cu" "F.Mask" "F.Paste")
			(net "Net_678")
		)
		(pad "DN84" smd circle
			(at 31.727902 16.266668 270)
			(size 0.4318 0.4318)
			(layers "F.Cu" "F.Mask" "F.Paste")
			(net "GND")
		)
		(pad "DN86" smd circle
			(at 33.355534 16.266668 270)
			(size 0.4318 0.4318)
			(layers "F.Cu" "F.Mask" "F.Paste")
			(net "P5E_CPU0_PE3_TX_DP<6>")
		)
		(pad "DN88" smd circle
			(at 34.98342 16.266668 270)
			(size 0.4318 0.4318)
			(layers "F.Cu" "F.Mask" "F.Paste")
			(net "GND")
		)
		(pad "DN90" smd circle
			(at 36.611306 16.266668 270)
			(size 0.4318 0.4318)
			(layers "F.Cu" "F.Mask" "F.Paste")
			(net "P5E_CPU0_PE3_RX_DN<7>")
		)
		(pad "DP2" smd circle
			(at -36.611306 16.626332 270)
			(size 0.4318 0.4318)
			(layers "F.Cu" "F.Mask" "F.Paste")
			(net "UPI_CPU1_CPU0_P0P1_DP<7>")
		)
		(pad "DP4" smd circle
			(at -34.98342 16.626332 270)
			(size 0.4318 0.4318)
			(layers "F.Cu" "F.Mask" "F.Paste")
			(net "GND")
		)
		(pad "DP6" smd circle
			(at -33.355534 16.626332 270)
			(size 0.4318 0.4318)
			(layers "F.Cu" "F.Mask" "F.Paste")
			(net "UPI_CPU0_CPU1_P1P0_DN<6>")
		)
		(pad "DP8" smd circle
			(at -31.727902 16.626332 270)
			(size 0.4318 0.4318)
			(layers "F.Cu" "F.Mask" "F.Paste")
			(net "GND")
		)
		(pad "DP10" smd circle
			(at -30.100016 16.626332 270)
			(size 0.4318 0.4318)
			(layers "F.Cu" "F.Mask" "F.Paste")
			(net "P5E_CPU0_PE2_RX_DP<8>")
		)
		(pad "DP12" smd circle
			(at -28.472384 16.626332 270)
			(size 0.4318 0.4318)
			(layers "F.Cu" "F.Mask" "F.Paste")
			(net "GND")
		)
		(pad "DP14" smd circle
			(at -26.844498 16.626332 270)
			(size 0.4318 0.4318)
			(layers "F.Cu" "F.Mask" "F.Paste")
			(net "P5E_CPU0_PE2_TX_DN<9>")
		)
		(pad "DP16" smd circle
			(at -25.216612 16.626332 270)
			(size 0.4318 0.4318)
			(layers "F.Cu" "F.Mask" "F.Paste")
			(net "GND")
		)
		(pad "DP18" smd circle
			(at -23.58898 16.626332 270)
			(size 0.4318 0.4318)
			(layers "F.Cu" "F.Mask" "F.Paste")
			(net "GND")
		)
		(pad "DP20" smd circle
			(at -21.961094 16.626332 270)
			(size 0.4318 0.4318)
			(layers "F.Cu" "F.Mask" "F.Paste")
			(net "M_H_CPU0_SB_DQ<22>")
		)
		(pad "DP22" smd circle
			(at -20.333462 16.626332 270)
			(size 0.4318 0.4318)
			(layers "F.Cu" "F.Mask" "F.Paste")
			(net "M_H_CPU0_SB_DQ<19>")
		)
		(pad "DP24" smd circle
			(at -18.705576 16.626332 270)
			(size 0.4318 0.4318)
			(layers "F.Cu" "F.Mask" "F.Paste")
			(net "GND")
		)
		(pad "DP26" smd circle
			(at -17.07769 16.626332 270)
			(size 0.4318 0.4318)
			(layers "F.Cu" "F.Mask" "F.Paste")
			(net "M_G_CPU0_SB_DQ<14>")
		)
		(pad "DP28" smd circle
			(at -15.450058 16.626332 270)
			(size 0.4318 0.4318)
			(layers "F.Cu" "F.Mask" "F.Paste")
			(net "M_G_CPU0_SB_DQ<11>")
		)
		(pad "DP30" smd circle
			(at -13.822426 16.626332 270)
			(size 0.4318 0.4318)
			(layers "F.Cu" "F.Mask" "F.Paste")
			(net "GND")
		)
		(pad "DP32" smd circle
			(at -12.19454 16.626332 270)
			(size 0.4318 0.4318)
			(layers "F.Cu" "F.Mask" "F.Paste")
			(net "M_G_CPU0_SB_DQ<6>")
		)
		(pad "DP34" smd circle
			(at -10.566654 16.626332 270)
			(size 0.4318 0.4318)
			(layers "F.Cu" "F.Mask" "F.Paste")
			(net "M_G_CPU0_SB_DQ<3>")
		)
		(pad "DP36" smd circle
			(at -8.939022 16.626332 270)
			(size 0.4318 0.4318)
			(layers "F.Cu" "F.Mask" "F.Paste")
			(net "GND")
		)
		(pad "DP38" smd circle
			(at -7.311136 16.626332 270)
			(size 0.4318 0.4318)
			(layers "F.Cu" "F.Mask" "F.Paste")
			(net "M_H_CPU0_SB_CS_N<3>")
		)
		(pad "DP40" smd circle
			(at -5.68325 16.626332 270)
			(size 0.4318 0.4318)
			(layers "F.Cu" "F.Mask" "F.Paste")
			(net "M_H_CPU0_SB_CA<5>")
		)
		(pad "DP42" smd circle
			(at -4.055618 16.626332 270)
			(size 0.4318 0.4318)
			(layers "F.Cu" "F.Mask" "F.Paste")
			(net "GND")
		)
		(pad "DP44" smd circle
			(at -2.427732 16.626332 270)
			(size 0.4318 0.4318)
			(layers "F.Cu" "F.Mask" "F.Paste")
			(net "M_G_CPU0_SB_CA<1>")
		)
		(pad "DP47" smd circle
			(at 1.613916 16.736314 270)
			(size 0.4318 0.4318)
			(layers "F.Cu" "F.Mask" "F.Paste")
			(net "M_F_CPU0_SA_RSP<1>")
		)
		(pad "DP49" smd circle
			(at 3.241802 16.736314 270)
			(size 0.4318 0.4318)
			(layers "F.Cu" "F.Mask" "F.Paste")
			(net "GND")
		)
		(pad "DP51" smd circle
			(at 4.869434 16.736314 270)
			(size 0.4318 0.4318)
			(layers "F.Cu" "F.Mask" "F.Paste")
			(net "M_G_CPU0_SA_CA<3>")
		)
		(pad "DP53" smd circle
			(at 6.49732 16.736314 270)
			(size 0.4318 0.4318)
			(layers "F.Cu" "F.Mask" "F.Paste")
			(net "M_G_CPU0_SA_CS_N<1>")
		)
		(pad "DP55" smd circle
			(at 8.124952 16.736314 270)
			(size 0.4318 0.4318)
			(layers "F.Cu" "F.Mask" "F.Paste")
			(net "GND")
		)
		(pad "DP57" smd circle
			(at 9.752838 16.736314 270)
			(size 0.4318 0.4318)
			(layers "F.Cu" "F.Mask" "F.Paste")
			(net "M_G_CPU0_SA_CB<6>")
		)
		(pad "DP59" smd circle
			(at 11.380724 16.736314 270)
			(size 0.4318 0.4318)
			(layers "F.Cu" "F.Mask" "F.Paste")
			(net "M_G_CPU0_SA_CB<3>")
		)
		(pad "DP61" smd circle
			(at 13.008356 16.736314 270)
			(size 0.4318 0.4318)
			(layers "F.Cu" "F.Mask" "F.Paste")
			(net "GND")
		)
		(pad "DP63" smd circle
			(at 14.635988 16.736314 270)
			(size 0.4318 0.4318)
			(layers "F.Cu" "F.Mask" "F.Paste")
			(net "M_G_CPU0_SA_DQ<30>")
		)
		(pad "DP65" smd circle
			(at 16.263874 16.736314 270)
			(size 0.4318 0.4318)
			(layers "F.Cu" "F.Mask" "F.Paste")
			(net "M_G_CPU0_SA_DQ<27>")
		)
		(pad "DP67" smd circle
			(at 17.89176 16.736314 270)
			(size 0.4318 0.4318)
			(layers "F.Cu" "F.Mask" "F.Paste")
			(net "GND")
		)
		(pad "DP69" smd circle
			(at 19.519392 16.736314 270)
			(size 0.4318 0.4318)
			(layers "F.Cu" "F.Mask" "F.Paste")
			(net "M_G_CPU0_SA_DQ<14>")
		)
		(pad "DP71" smd circle
			(at 21.147278 16.736314 270)
			(size 0.4318 0.4318)
			(layers "F.Cu" "F.Mask" "F.Paste")
			(net "M_G_CPU0_SA_DQ<11>")
		)
		(pad "DP73" smd circle
			(at 22.77491 16.736314 270)
			(size 0.4318 0.4318)
			(layers "F.Cu" "F.Mask" "F.Paste")
			(net "GND")
		)
		(pad "DP75" smd circle
			(at 24.402796 16.736314 270)
			(size 0.4318 0.4318)
			(layers "F.Cu" "F.Mask" "F.Paste")
			(net "M_H_CPU0_SA_DQ<6>")
		)
		(pad "DP77" smd circle
			(at 26.030682 16.736314 270)
			(size 0.4318 0.4318)
			(layers "F.Cu" "F.Mask" "F.Paste")
			(net "M_H_CPU0_SA_DQ<3>")
		)
		(pad "DP79" smd circle
			(at 27.658314 16.736314 270)
			(size 0.4318 0.4318)
			(layers "F.Cu" "F.Mask" "F.Paste")
			(net "Net_679")
		)
		(pad "DP81" smd circle
			(at 29.2862 16.736314 270)
			(size 0.4318 0.4318)
			(layers "F.Cu" "F.Mask" "F.Paste")
			(net "GND")
		)
		(pad "DP83" smd circle
			(at 30.914086 16.736314 270)
			(size 0.4318 0.4318)
			(layers "F.Cu" "F.Mask" "F.Paste")
			(net "Net_654")
		)
		(pad "DP85" smd circle
			(at 32.541718 16.736314 270)
			(size 0.4318 0.4318)
			(layers "F.Cu" "F.Mask" "F.Paste")
			(net "P5E_CPU0_PE3_TX_DN<5>")
		)
		(pad "DP87" smd circle
			(at 34.169604 16.736314 270)
			(size 0.4318 0.4318)
			(layers "F.Cu" "F.Mask" "F.Paste")
			(net "GND")
		)
		(pad "DP89" smd circle
			(at 35.797236 16.736314 270)
			(size 0.4318 0.4318)
			(layers "F.Cu" "F.Mask" "F.Paste")
			(net "P5E_CPU0_PE3_RX_DN<6>")
		)
		(pad "DP91" smd oval
			(at 37.425122 16.736314)
			(size 0.381 0.4826)
			(drill
				(offset 0 -0.0508)
			)
			(layers "F.Cu" "F.Mask" "F.Paste")
			(net "GND")
		)
		(pad "DR1" smd oval
			(at -37.425122 17.096486 180)
			(size 0.381 0.4826)
			(drill
				(offset 0 -0.0508)
			)
			(layers "F.Cu" "F.Mask" "F.Paste")
			(net "GND")
		)
		(pad "DR3" smd circle
			(at -35.797236 17.096486 270)
			(size 0.4318 0.4318)
			(layers "F.Cu" "F.Mask" "F.Paste")
			(net "UPI_CPU1_CPU0_P0P1_DP<6>")
		)
		(pad "DR5" smd circle
			(at -34.169604 17.096486 270)
			(size 0.4318 0.4318)
			(layers "F.Cu" "F.Mask" "F.Paste")
			(net "GND")
		)
		(pad "DR7" smd circle
			(at -32.541718 17.096486 270)
			(size 0.4318 0.4318)
			(layers "F.Cu" "F.Mask" "F.Paste")
			(net "UPI_CPU0_CPU1_P1P0_DN<5>")
		)
		(pad "DR9" smd circle
			(at -30.914086 17.096486 270)
			(size 0.4318 0.4318)
			(layers "F.Cu" "F.Mask" "F.Paste")
			(net "GND")
		)
		(pad "DR11" smd circle
			(at -29.2862 17.096486 270)
			(size 0.4318 0.4318)
			(layers "F.Cu" "F.Mask" "F.Paste")
			(net "P5E_CPU0_PE2_RX_DP<9>")
		)
		(pad "DR13" smd circle
			(at -27.658314 17.096486 270)
			(size 0.4318 0.4318)
			(layers "F.Cu" "F.Mask" "F.Paste")
			(net "GND")
		)
		(pad "DR15" smd circle
			(at -26.030682 17.096486 270)
			(size 0.4318 0.4318)
			(layers "F.Cu" "F.Mask" "F.Paste")
			(net "P5E_CPU0_PE2_TX_DP<9>")
		)
		(pad "DR17" smd circle
			(at -24.402796 17.096486 270)
			(size 0.4318 0.4318)
			(layers "F.Cu" "F.Mask" "F.Paste")
			(net "M_F_CPU0_SB_DQ<31>")
		)
		(pad "DR19" smd circle
			(at -22.77491 17.096486 270)
			(size 0.4318 0.4318)
			(layers "F.Cu" "F.Mask" "F.Paste")
			(net "GND")
		)
		(pad "DR21" smd circle
			(at -21.147278 17.096486 270)
			(size 0.4318 0.4318)
			(layers "F.Cu" "F.Mask" "F.Paste")
			(net "M_H_CPU0_SB_DQS_DN<7>")
		)
		(pad "DR23" smd circle
			(at -19.519392 17.096486 270)
			(size 0.4318 0.4318)
			(layers "F.Cu" "F.Mask" "F.Paste")
			(net "GND")
		)
		(pad "DR25" smd circle
			(at -17.89176 17.096486 270)
			(size 0.4318 0.4318)
			(layers "F.Cu" "F.Mask" "F.Paste")
			(net "GND")
		)
		(pad "DR27" smd circle
			(at -16.263874 17.096486 270)
			(size 0.4318 0.4318)
			(layers "F.Cu" "F.Mask" "F.Paste")
			(net "M_G_CPU0_SB_DQS_DP<6>")
		)
		(pad "DR29" smd circle
			(at -14.635988 17.096486 270)
			(size 0.4318 0.4318)
			(layers "F.Cu" "F.Mask" "F.Paste")
			(net "GND")
		)
		(pad "DR31" smd circle
			(at -13.008356 17.096486 270)
			(size 0.4318 0.4318)
			(layers "F.Cu" "F.Mask" "F.Paste")
			(net "GND")
		)
		(pad "DR33" smd circle
			(at -11.380724 17.096486 270)
			(size 0.4318 0.4318)
			(layers "F.Cu" "F.Mask" "F.Paste")
			(net "M_G_CPU0_SB_DQS_DN<5>")
		)
		(pad "DR35" smd circle
			(at -9.752838 17.096486 270)
			(size 0.4318 0.4318)
			(layers "F.Cu" "F.Mask" "F.Paste")
			(net "GND")
		)
		(pad "DR37" smd circle
			(at -8.124952 17.096486 270)
			(size 0.4318 0.4318)
			(layers "F.Cu" "F.Mask" "F.Paste")
			(net "GND")
		)
		(pad "DR39" smd circle
			(at -6.49732 17.096486 270)
			(size 0.4318 0.4318)
			(layers "F.Cu" "F.Mask" "F.Paste")
			(net "M_H_CPU0_SB_PAR")
		)
		(pad "DR41" smd circle
			(at -4.869434 17.096486 270)
			(size 0.4318 0.4318)
			(layers "F.Cu" "F.Mask" "F.Paste")
			(net "GND")
		)
		(pad "DR43" smd circle
			(at -3.241802 17.096486 270)
			(size 0.4318 0.4318)
			(layers "F.Cu" "F.Mask" "F.Paste")
			(net "GND")
		)
		(pad "DR45" smd circle
			(at -1.613916 17.096486 270)
			(size 0.4318 0.4318)
			(layers "F.Cu" "F.Mask" "F.Paste")
			(net "M_G_CPU0_CLK_DN<0>")
		)
		(pad "DR48" smd circle
			(at 2.427732 17.206468 270)
			(size 0.4318 0.4318)
			(layers "F.Cu" "F.Mask" "F.Paste")
			(net "GND")
		)
		(pad "DR50" smd circle
			(at 4.055618 17.206468 270)
			(size 0.4318 0.4318)
			(layers "F.Cu" "F.Mask" "F.Paste")
			(net "GND")
		)
		(pad "DR52" smd circle
			(at 5.68325 17.206468 270)
			(size 0.4318 0.4318)
			(layers "F.Cu" "F.Mask" "F.Paste")
			(net "M_G_CPU0_SA_CA<1>")
		)
		(pad "DR54" smd circle
			(at 7.311136 17.206468 270)
			(size 0.4318 0.4318)
			(layers "F.Cu" "F.Mask" "F.Paste")
			(net "GND")
		)
		(pad "DR56" smd circle
			(at 8.939022 17.206468 270)
			(size 0.4318 0.4318)
			(layers "F.Cu" "F.Mask" "F.Paste")
			(net "GND")
		)
		(pad "DR58" smd circle
			(at 10.566654 17.206468 270)
			(size 0.4318 0.4318)
			(layers "F.Cu" "F.Mask" "F.Paste")
			(net "M_G_CPU0_SA_DQS_DN<9>")
		)
		(pad "DR60" smd circle
			(at 12.19454 17.206468 270)
			(size 0.4318 0.4318)
			(layers "F.Cu" "F.Mask" "F.Paste")
			(net "GND")
		)
		(pad "DR62" smd circle
			(at 13.822426 17.206468 270)
			(size 0.4318 0.4318)
			(layers "F.Cu" "F.Mask" "F.Paste")
			(net "GND")
		)
		(pad "DR64" smd circle
			(at 15.450058 17.206468 270)
			(size 0.4318 0.4318)
			(layers "F.Cu" "F.Mask" "F.Paste")
			(net "M_G_CPU0_SA_DQS_DN<8>")
		)
		(pad "DR66" smd circle
			(at 17.07769 17.206468 270)
			(size 0.4318 0.4318)
			(layers "F.Cu" "F.Mask" "F.Paste")
			(net "GND")
		)
		(pad "DR68" smd circle
			(at 18.705576 17.206468 270)
			(size 0.4318 0.4318)
			(layers "F.Cu" "F.Mask" "F.Paste")
			(net "GND")
		)
		(pad "DR70" smd circle
			(at 20.333462 17.206468 270)
			(size 0.4318 0.4318)
			(layers "F.Cu" "F.Mask" "F.Paste")
			(net "M_G_CPU0_SA_DQS_DN<6>")
		)
		(pad "DR72" smd circle
			(at 21.961094 17.206468 270)
			(size 0.4318 0.4318)
			(layers "F.Cu" "F.Mask" "F.Paste")
			(net "GND")
		)
		(pad "DR74" smd circle
			(at 23.58898 17.206468 270)
			(size 0.4318 0.4318)
			(layers "F.Cu" "F.Mask" "F.Paste")
			(net "GND")
		)
		(pad "DR76" smd circle
			(at 25.216612 17.206468 270)
			(size 0.4318 0.4318)
			(layers "F.Cu" "F.Mask" "F.Paste")
			(net "M_H_CPU0_SA_DQS_DN<5>")
		)
		(pad "DR78" smd circle
			(at 26.844498 17.206468 270)
			(size 0.4318 0.4318)
			(layers "F.Cu" "F.Mask" "F.Paste")
			(net "GND")
		)
		(pad "DR80" smd circle
			(at 28.472384 17.206468 270)
			(size 0.4318 0.4318)
			(layers "F.Cu" "F.Mask" "F.Paste")
			(net "Net_655")
		)
		(pad "DR82" smd circle
			(at 30.100016 17.206468 270)
			(size 0.4318 0.4318)
			(layers "F.Cu" "F.Mask" "F.Paste")
			(net "Net_680")
		)
		(pad "DR84" smd circle
			(at 31.727902 17.206468 270)
			(size 0.4318 0.4318)
			(layers "F.Cu" "F.Mask" "F.Paste")
			(net "GND")
		)
		(pad "DR86" smd circle
			(at 33.355534 17.206468 270)
			(size 0.4318 0.4318)
			(layers "F.Cu" "F.Mask" "F.Paste")
			(net "P5E_CPU0_PE3_TX_DP<5>")
		)
		(pad "DR88" smd circle
			(at 34.98342 17.206468 270)
			(size 0.4318 0.4318)
			(layers "F.Cu" "F.Mask" "F.Paste")
			(net "GND")
		)
		(pad "DR90" smd circle
			(at 36.611306 17.206468 270)
			(size 0.4318 0.4318)
			(layers "F.Cu" "F.Mask" "F.Paste")
			(net "P5E_CPU0_PE3_RX_DP<6>")
		)
		(pad "DT2" smd circle
			(at -36.611306 17.566132 270)
			(size 0.4318 0.4318)
			(layers "F.Cu" "F.Mask" "F.Paste")
			(net "UPI_CPU1_CPU0_P0P1_DN<6>")
		)
		(pad "DT4" smd circle
			(at -34.98342 17.566132 270)
			(size 0.4318 0.4318)
			(layers "F.Cu" "F.Mask" "F.Paste")
			(net "GND")
		)
		(pad "DT6" smd circle
			(at -33.355534 17.566132 270)
			(size 0.4318 0.4318)
			(layers "F.Cu" "F.Mask" "F.Paste")
			(net "UPI_CPU0_CPU1_P1P0_DP<5>")
		)
		(pad "DT8" smd circle
			(at -31.727902 17.566132 270)
			(size 0.4318 0.4318)
			(layers "F.Cu" "F.Mask" "F.Paste")
			(net "GND")
		)
		(pad "DT10" smd circle
			(at -30.100016 17.566132 270)
			(size 0.4318 0.4318)
			(layers "F.Cu" "F.Mask" "F.Paste")
			(net "P5E_CPU0_PE2_RX_DN<9>")
		)
		(pad "DT12" smd circle
			(at -28.472384 17.566132 270)
			(size 0.4318 0.4318)
			(layers "F.Cu" "F.Mask" "F.Paste")
			(net "GND")
		)
		(pad "DT14" smd circle
			(at -26.844498 17.566132 270)
			(size 0.4318 0.4318)
			(layers "F.Cu" "F.Mask" "F.Paste")
			(net "P5E_CPU0_PE2_TX_DP<10>")
		)
		(pad "DT16" smd circle
			(at -25.216612 17.566132 270)
			(size 0.4318 0.4318)
			(layers "F.Cu" "F.Mask" "F.Paste")
			(net "GND")
		)
		(pad "DT18" smd circle
			(at -23.58898 17.566132 270)
			(size 0.4318 0.4318)
			(layers "F.Cu" "F.Mask" "F.Paste")
			(net "M_F_CPU0_SB_DQS_DN<3>")
		)
		(pad "DT20" smd circle
			(at -21.961094 17.566132 270)
			(size 0.4318 0.4318)
			(layers "F.Cu" "F.Mask" "F.Paste")
			(net "GND")
		)
		(pad "DT22" smd circle
			(at -20.333462 17.566132 270)
			(size 0.4318 0.4318)
			(layers "F.Cu" "F.Mask" "F.Paste")
			(net "GND")
		)
		(pad "DT24" smd circle
			(at -18.705576 17.566132 270)
			(size 0.4318 0.4318)
			(layers "F.Cu" "F.Mask" "F.Paste")
			(net "M_G_CPU0_SB_DQS_DP<2>")
		)
		(pad "DT26" smd circle
			(at -17.07769 17.566132 270)
			(size 0.4318 0.4318)
			(layers "F.Cu" "F.Mask" "F.Paste")
			(net "GND")
		)
		(pad "DT28" smd circle
			(at -15.450058 17.566132 270)
			(size 0.4318 0.4318)
			(layers "F.Cu" "F.Mask" "F.Paste")
			(net "GND")
		)
		(pad "DT30" smd circle
			(at -13.822426 17.566132 270)
			(size 0.4318 0.4318)
			(layers "F.Cu" "F.Mask" "F.Paste")
			(net "M_F_CPU0_SB_DQS_DP<0>")
		)
		(pad "DT32" smd circle
			(at -12.19454 17.566132 270)
			(size 0.4318 0.4318)
			(layers "F.Cu" "F.Mask" "F.Paste")
			(net "GND")
		)
		(pad "DT34" smd circle
			(at -10.566654 17.566132 270)
			(size 0.4318 0.4318)
			(layers "F.Cu" "F.Mask" "F.Paste")
			(net "GND")
		)
		(pad "DT36" smd circle
			(at -8.939022 17.566132 270)
			(size 0.4318 0.4318)
			(layers "F.Cu" "F.Mask" "F.Paste")
			(net "M_G_CPU0_SB_DQS_DP<9>")
		)
		(pad "DT38" smd circle
			(at -7.311136 17.566132 270)
			(size 0.4318 0.4318)
			(layers "F.Cu" "F.Mask" "F.Paste")
			(net "GND")
		)
		(pad "DT40" smd circle
			(at -5.68325 17.566132 270)
			(size 0.4318 0.4318)
			(layers "F.Cu" "F.Mask" "F.Paste")
			(net "GND")
		)
		(pad "DT42" smd circle
			(at -4.055618 17.566132 270)
			(size 0.4318 0.4318)
			(layers "F.Cu" "F.Mask" "F.Paste")
			(net "M_G_CPU0_SB_CA<6>")
		)
		(pad "DT44" smd circle
			(at -2.427732 17.566132 270)
			(size 0.4318 0.4318)
			(layers "F.Cu" "F.Mask" "F.Paste")
			(net "GND")
		)
		(pad "DT47" smd circle
			(at 1.613916 17.676114 270)
			(size 0.4318 0.4318)
			(layers "F.Cu" "F.Mask" "F.Paste")
			(net "GND")
		)
		(pad "DT49" smd circle
			(at 3.241802 17.676114 270)
			(size 0.4318 0.4318)
			(layers "F.Cu" "F.Mask" "F.Paste")
			(net "M_F_CPU0_CLK_DP<1>")
		)
		(pad "DT51" smd circle
			(at 4.869434 17.676114 270)
			(size 0.4318 0.4318)
			(layers "F.Cu" "F.Mask" "F.Paste")
			(net "GND")
		)
		(pad "DT53" smd circle
			(at 6.49732 17.676114 270)
			(size 0.4318 0.4318)
			(layers "F.Cu" "F.Mask" "F.Paste")
			(net "GND")
		)
		(pad "DT55" smd circle
			(at 8.124952 17.676114 270)
			(size 0.4318 0.4318)
			(layers "F.Cu" "F.Mask" "F.Paste")
			(net "M_F_CPU0_SA_DQS_DP<3>")
		)
		(pad "DT57" smd circle
			(at 9.752838 17.676114 270)
			(size 0.4318 0.4318)
			(layers "F.Cu" "F.Mask" "F.Paste")
			(net "GND")
		)
		(pad "DT59" smd circle
			(at 11.380724 17.676114 270)
			(size 0.4318 0.4318)
			(layers "F.Cu" "F.Mask" "F.Paste")
			(net "GND")
		)
		(pad "DT61" smd circle
			(at 13.008356 17.676114 270)
			(size 0.4318 0.4318)
			(layers "F.Cu" "F.Mask" "F.Paste")
			(net "M_G_CPU0_SA_DQS_DN<2>")
		)
		(pad "DT63" smd circle
			(at 14.635988 17.676114 270)
			(size 0.4318 0.4318)
			(layers "F.Cu" "F.Mask" "F.Paste")
			(net "GND")
		)
		(pad "DT65" smd circle
			(at 16.263874 17.676114 270)
			(size 0.4318 0.4318)
			(layers "F.Cu" "F.Mask" "F.Paste")
			(net "GND")
		)
		(pad "DT67" smd circle
			(at 17.89176 17.676114 270)
			(size 0.4318 0.4318)
			(layers "F.Cu" "F.Mask" "F.Paste")
			(net "M_F_CPU0_SA_DQS_DN<1>")
		)
		(pad "DT69" smd circle
			(at 19.519392 17.676114 270)
			(size 0.4318 0.4318)
			(layers "F.Cu" "F.Mask" "F.Paste")
			(net "GND")
		)
		(pad "DT71" smd circle
			(at 21.147278 17.676114 270)
			(size 0.4318 0.4318)
			(layers "F.Cu" "F.Mask" "F.Paste")
			(net "GND")
		)
		(pad "DT73" smd circle
			(at 22.77491 17.676114 270)
			(size 0.4318 0.4318)
			(layers "F.Cu" "F.Mask" "F.Paste")
			(net "M_G_CPU0_SA_DQS_DP<0>")
		)
		(pad "DT75" smd circle
			(at 24.402796 17.676114 270)
			(size 0.4318 0.4318)
			(layers "F.Cu" "F.Mask" "F.Paste")
			(net "GND")
		)
		(pad "DT77" smd circle
			(at 26.030682 17.676114 270)
			(size 0.4318 0.4318)
			(layers "F.Cu" "F.Mask" "F.Paste")
			(net "M_H_CPU0_SA_DQ<1>")
		)
		(pad "DT79" smd circle
			(at 27.658314 17.676114 270)
			(size 0.4318 0.4318)
			(layers "F.Cu" "F.Mask" "F.Paste")
			(net "PVCCFA_EHV_FIVRA_CPU0")
		)
		(pad "DT81" smd circle
			(at 29.2862 17.676114 270)
			(size 0.4318 0.4318)
			(layers "F.Cu" "F.Mask" "F.Paste")
			(net "Net_657")
		)
		(pad "DT83" smd circle
			(at 30.914086 17.676114 270)
			(size 0.4318 0.4318)
			(layers "F.Cu" "F.Mask" "F.Paste")
			(net "GND")
		)
		(pad "DT85" smd circle
			(at 32.541718 17.676114 270)
			(size 0.4318 0.4318)
			(layers "F.Cu" "F.Mask" "F.Paste")
			(net "PVCCFA_EHV_FIVRA_CPU0")
		)
		(pad "DT87" smd circle
			(at 34.169604 17.676114 270)
			(size 0.4318 0.4318)
			(layers "F.Cu" "F.Mask" "F.Paste")
			(net "P5E_CPU0_PE3_TX_DN<4>")
		)
		(pad "DT89" smd circle
			(at 35.797236 17.676114 270)
			(size 0.4318 0.4318)
			(layers "F.Cu" "F.Mask" "F.Paste")
			(net "PVCCFA_EHV_FIVRA_CPU0")
		)
		(pad "DT91" smd oval
			(at 37.425122 17.676114)
			(size 0.381 0.4826)
			(drill
				(offset 0 -0.0508)
			)
			(layers "F.Cu" "F.Mask" "F.Paste")
			(net "P5E_CPU0_PE3_RX_DP<5>")
		)
		(pad "DU1" smd oval
			(at -37.425122 18.036286 180)
			(size 0.381 0.4826)
			(drill
				(offset 0 -0.0508)
			)
			(layers "F.Cu" "F.Mask" "F.Paste")
			(net "UPI_CPU1_CPU0_P0P1_DN<5>")
		)
		(pad "DU3" smd circle
			(at -35.797236 18.036286 270)
			(size 0.4318 0.4318)
			(layers "F.Cu" "F.Mask" "F.Paste")
			(net "PVCCFA_EHV_FIVRA_CPU0")
		)
		(pad "DU5" smd circle
			(at -34.169604 18.036286 270)
			(size 0.4318 0.4318)
			(layers "F.Cu" "F.Mask" "F.Paste")
			(net "UPI_CPU0_CPU1_P1P0_DP<4>")
		)
		(pad "DU7" smd circle
			(at -32.541718 18.036286 270)
			(size 0.4318 0.4318)
			(layers "F.Cu" "F.Mask" "F.Paste")
			(net "PVCCFA_EHV_FIVRA_CPU0")
		)
		(pad "DU9" smd circle
			(at -30.914086 18.036286 270)
			(size 0.4318 0.4318)
			(layers "F.Cu" "F.Mask" "F.Paste")
			(net "P5E_CPU0_PE2_RX_DN<10>")
		)
		(pad "DU11" smd circle
			(at -29.2862 18.036286 270)
			(size 0.4318 0.4318)
			(layers "F.Cu" "F.Mask" "F.Paste")
			(net "PVCCFA_EHV_FIVRA_CPU0")
		)
		(pad "DU13" smd circle
			(at -27.658314 18.036286 270)
			(size 0.4318 0.4318)
			(layers "F.Cu" "F.Mask" "F.Paste")
			(net "P5E_CPU0_PE2_TX_DN<10>")
		)
		(pad "DU15" smd circle
			(at -26.030682 18.036286 270)
			(size 0.4318 0.4318)
			(layers "F.Cu" "F.Mask" "F.Paste")
			(net "PVCCFA_EHV_FIVRA_CPU0")
		)
		(pad "DU17" smd circle
			(at -24.402796 18.036286 270)
			(size 0.4318 0.4318)
			(layers "F.Cu" "F.Mask" "F.Paste")
			(net "M_F_CPU0_SB_DQ<29>")
		)
		(pad "DU19" smd circle
			(at -22.77491 18.036286 270)
			(size 0.4318 0.4318)
			(layers "F.Cu" "F.Mask" "F.Paste")
			(net "M_F_CPU0_SB_DQ<25>")
		)
		(pad "DU21" smd circle
			(at -21.147278 18.036286 270)
			(size 0.4318 0.4318)
			(layers "F.Cu" "F.Mask" "F.Paste")
			(net "GND")
		)
		(pad "DU23" smd circle
			(at -19.519392 18.036286 270)
			(size 0.4318 0.4318)
			(layers "F.Cu" "F.Mask" "F.Paste")
			(net "M_G_CPU0_SB_DQ<20>")
		)
		(pad "DU25" smd circle
			(at -17.89176 18.036286 270)
			(size 0.4318 0.4318)
			(layers "F.Cu" "F.Mask" "F.Paste")
			(net "M_G_CPU0_SB_DQ<17>")
		)
		(pad "DU27" smd circle
			(at -16.263874 18.036286 270)
			(size 0.4318 0.4318)
			(layers "F.Cu" "F.Mask" "F.Paste")
			(net "GND")
		)
		(pad "DU29" smd circle
			(at -14.635988 18.036286 270)
			(size 0.4318 0.4318)
			(layers "F.Cu" "F.Mask" "F.Paste")
			(net "M_F_CPU0_SB_DQ<4>")
		)
		(pad "DU31" smd circle
			(at -13.008356 18.036286 270)
			(size 0.4318 0.4318)
			(layers "F.Cu" "F.Mask" "F.Paste")
			(net "M_F_CPU0_SB_DQ<1>")
		)
		(pad "DU33" smd circle
			(at -11.380724 18.036286 270)
			(size 0.4318 0.4318)
			(layers "F.Cu" "F.Mask" "F.Paste")
			(net "GND")
		)
		(pad "DU35" smd circle
			(at -9.752838 18.036286 270)
			(size 0.4318 0.4318)
			(layers "F.Cu" "F.Mask" "F.Paste")
			(net "M_G_CPU0_SB_CB<0>")
		)
		(pad "DU37" smd circle
			(at -8.124952 18.036286 270)
			(size 0.4318 0.4318)
			(layers "F.Cu" "F.Mask" "F.Paste")
			(net "M_G_CPU0_SB_CB<5>")
		)
		(pad "DU39" smd circle
			(at -6.49732 18.036286 270)
			(size 0.4318 0.4318)
			(layers "F.Cu" "F.Mask" "F.Paste")
			(net "GND")
		)
		(pad "DU41" smd circle
			(at -4.869434 18.036286 270)
			(size 0.4318 0.4318)
			(layers "F.Cu" "F.Mask" "F.Paste")
			(net "M_G_CPU0_SB_CS_N<2>")
		)
		(pad "DU43" smd circle
			(at -3.241802 18.036286 270)
			(size 0.4318 0.4318)
			(layers "F.Cu" "F.Mask" "F.Paste")
			(net "M_G_CPU0_SB_CA<4>")
		)
		(pad "DU45" smd circle
			(at -1.613916 18.036286 270)
			(size 0.4318 0.4318)
			(layers "F.Cu" "F.Mask" "F.Paste")
			(net "GND")
		)
		(pad "DU48" smd circle
			(at 2.427732 18.146268 270)
			(size 0.4318 0.4318)
			(layers "F.Cu" "F.Mask" "F.Paste")
			(net "M_G_CPU0_SB_RSP<0>")
		)
		(pad "DU50" smd circle
			(at 4.055618 18.146268 270)
			(size 0.4318 0.4318)
			(layers "F.Cu" "F.Mask" "F.Paste")
			(net "M_F_CPU0_SB_CA<1>")
		)
		(pad "DU52" smd circle
			(at 5.68325 18.146268 270)
			(size 0.4318 0.4318)
			(layers "F.Cu" "F.Mask" "F.Paste")
			(net "GND")
		)
		(pad "DU54" smd circle
			(at 7.311136 18.146268 270)
			(size 0.4318 0.4318)
			(layers "F.Cu" "F.Mask" "F.Paste")
			(net "M_F_CPU0_SA_DQ<28>")
		)
		(pad "DU56" smd circle
			(at 8.939022 18.146268 270)
			(size 0.4318 0.4318)
			(layers "F.Cu" "F.Mask" "F.Paste")
			(net "M_F_CPU0_SA_DQ<25>")
		)
		(pad "DU58" smd circle
			(at 10.566654 18.146268 270)
			(size 0.4318 0.4318)
			(layers "F.Cu" "F.Mask" "F.Paste")
			(net "GND")
		)
		(pad "DU60" smd circle
			(at 12.19454 18.146268 270)
			(size 0.4318 0.4318)
			(layers "F.Cu" "F.Mask" "F.Paste")
			(net "M_G_CPU0_SA_DQ<20>")
		)
		(pad "DU62" smd circle
			(at 13.822426 18.146268 270)
			(size 0.4318 0.4318)
			(layers "F.Cu" "F.Mask" "F.Paste")
			(net "M_G_CPU0_SA_DQ<17>")
		)
		(pad "DU64" smd circle
			(at 15.450058 18.146268 270)
			(size 0.4318 0.4318)
			(layers "F.Cu" "F.Mask" "F.Paste")
			(net "GND")
		)
		(pad "DU66" smd circle
			(at 17.07769 18.146268 270)
			(size 0.4318 0.4318)
			(layers "F.Cu" "F.Mask" "F.Paste")
			(net "M_F_CPU0_SA_DQ<12>")
		)
		(pad "DU68" smd circle
			(at 18.705576 18.146268 270)
			(size 0.4318 0.4318)
			(layers "F.Cu" "F.Mask" "F.Paste")
			(net "M_F_CPU0_SA_DQ<9>")
		)
		(pad "DU70" smd circle
			(at 20.333462 18.146268 270)
			(size 0.4318 0.4318)
			(layers "F.Cu" "F.Mask" "F.Paste")
			(net "GND")
		)
		(pad "DU72" smd circle
			(at 21.961094 18.146268 270)
			(size 0.4318 0.4318)
			(layers "F.Cu" "F.Mask" "F.Paste")
			(net "M_G_CPU0_SA_DQ<4>")
		)
		(pad "DU74" smd circle
			(at 23.58898 18.146268 270)
			(size 0.4318 0.4318)
			(layers "F.Cu" "F.Mask" "F.Paste")
			(net "M_G_CPU0_SA_DQ<1>")
		)
		(pad "DU76" smd circle
			(at 25.216612 18.146268 270)
			(size 0.4318 0.4318)
			(layers "F.Cu" "F.Mask" "F.Paste")
			(net "GND")
		)
		(pad "DU78" smd circle
			(at 26.844498 18.146268 270)
			(size 0.4318 0.4318)
			(layers "F.Cu" "F.Mask" "F.Paste")
			(net "GND")
		)
		(pad "DU80" smd circle
			(at 28.472384 18.146268 270)
			(size 0.4318 0.4318)
			(layers "F.Cu" "F.Mask" "F.Paste")
			(net "Net_681")
		)
		(pad "DU82" smd circle
			(at 30.100016 18.146268 270)
			(size 0.4318 0.4318)
			(layers "F.Cu" "F.Mask" "F.Paste")
			(net "Net_656")
		)
		(pad "DU84" smd circle
			(at 31.727902 18.146268 270)
			(size 0.4318 0.4318)
			(layers "F.Cu" "F.Mask" "F.Paste")
			(net "GND")
		)
		(pad "DU86" smd circle
			(at 33.355534 18.146268 270)
			(size 0.4318 0.4318)
			(layers "F.Cu" "F.Mask" "F.Paste")
			(net "P5E_CPU0_PE3_TX_DP<4>")
		)
		(pad "DU88" smd circle
			(at 34.98342 18.146268 270)
			(size 0.4318 0.4318)
			(layers "F.Cu" "F.Mask" "F.Paste")
			(net "GND")
		)
		(pad "DU90" smd circle
			(at 36.611306 18.146268 270)
			(size 0.4318 0.4318)
			(layers "F.Cu" "F.Mask" "F.Paste")
			(net "P5E_CPU0_PE3_RX_DN<5>")
		)
		(pad "DV2" smd circle
			(at -36.611306 18.505932 270)
			(size 0.4318 0.4318)
			(layers "F.Cu" "F.Mask" "F.Paste")
			(net "UPI_CPU1_CPU0_P0P1_DP<5>")
		)
		(pad "DV4" smd circle
			(at -34.98342 18.505932 270)
			(size 0.4318 0.4318)
			(layers "F.Cu" "F.Mask" "F.Paste")
			(net "GND")
		)
		(pad "DV6" smd circle
			(at -33.355534 18.505932 270)
			(size 0.4318 0.4318)
			(layers "F.Cu" "F.Mask" "F.Paste")
			(net "UPI_CPU0_CPU1_P1P0_DN<4>")
		)
		(pad "DV8" smd circle
			(at -31.727902 18.505932 270)
			(size 0.4318 0.4318)
			(layers "F.Cu" "F.Mask" "F.Paste")
			(net "GND")
		)
		(pad "DV10" smd circle
			(at -30.100016 18.505932 270)
			(size 0.4318 0.4318)
			(layers "F.Cu" "F.Mask" "F.Paste")
			(net "P5E_CPU0_PE2_RX_DP<10>")
		)
		(pad "DV12" smd circle
			(at -28.472384 18.505932 270)
			(size 0.4318 0.4318)
			(layers "F.Cu" "F.Mask" "F.Paste")
			(net "GND")
		)
		(pad "DV14" smd circle
			(at -26.844498 18.505932 270)
			(size 0.4318 0.4318)
			(layers "F.Cu" "F.Mask" "F.Paste")
			(net "P5E_CPU0_PE2_TX_DN<11>")
		)
		(pad "DV16" smd circle
			(at -25.216612 18.505932 270)
			(size 0.4318 0.4318)
			(layers "F.Cu" "F.Mask" "F.Paste")
			(net "GND")
		)
		(pad "DV18" smd circle
			(at -23.58898 18.505932 270)
			(size 0.4318 0.4318)
			(layers "F.Cu" "F.Mask" "F.Paste")
			(net "M_F_CPU0_SB_DQS_DP<3>")
		)
		(pad "DV20" smd circle
			(at -21.961094 18.505932 270)
			(size 0.4318 0.4318)
			(layers "F.Cu" "F.Mask" "F.Paste")
			(net "M_F_CPU0_SB_DQ<24>")
		)
		(pad "DV22" smd circle
			(at -20.333462 18.505932 270)
			(size 0.4318 0.4318)
			(layers "F.Cu" "F.Mask" "F.Paste")
			(net "M_G_CPU0_SB_DQ<21>")
		)
		(pad "DV24" smd circle
			(at -18.705576 18.505932 270)
			(size 0.4318 0.4318)
			(layers "F.Cu" "F.Mask" "F.Paste")
			(net "M_G_CPU0_SB_DQS_DN<2>")
		)
		(pad "DV26" smd circle
			(at -17.07769 18.505932 270)
			(size 0.4318 0.4318)
			(layers "F.Cu" "F.Mask" "F.Paste")
			(net "M_G_CPU0_SB_DQ<16>")
		)
		(pad "DV28" smd circle
			(at -15.450058 18.505932 270)
			(size 0.4318 0.4318)
			(layers "F.Cu" "F.Mask" "F.Paste")
			(net "M_F_CPU0_SB_DQ<5>")
		)
		(pad "DV30" smd circle
			(at -13.822426 18.505932 270)
			(size 0.4318 0.4318)
			(layers "F.Cu" "F.Mask" "F.Paste")
			(net "M_F_CPU0_SB_DQS_DN<0>")
		)
		(pad "DV32" smd circle
			(at -12.19454 18.505932 270)
			(size 0.4318 0.4318)
			(layers "F.Cu" "F.Mask" "F.Paste")
			(net "M_F_CPU0_SB_DQ<0>")
		)
		(pad "DV34" smd circle
			(at -10.566654 18.505932 270)
			(size 0.4318 0.4318)
			(layers "F.Cu" "F.Mask" "F.Paste")
			(net "M_G_CPU0_SB_CB<1>")
		)
		(pad "DV36" smd circle
			(at -8.939022 18.505932 270)
			(size 0.4318 0.4318)
			(layers "F.Cu" "F.Mask" "F.Paste")
			(net "M_G_CPU0_SB_DQS_DN<9>")
		)
		(pad "DV38" smd circle
			(at -7.311136 18.505932 270)
			(size 0.4318 0.4318)
			(layers "F.Cu" "F.Mask" "F.Paste")
			(net "M_G_CPU0_SB_CB<4>")
		)
		(pad "DV40" smd circle
			(at -5.68325 18.505932 270)
			(size 0.4318 0.4318)
			(layers "F.Cu" "F.Mask" "F.Paste")
			(net "M_G_CPU0_SB_CS_N<3>")
		)
		(pad "DV42" smd circle
			(at -4.055618 18.505932 270)
			(size 0.4318 0.4318)
			(layers "F.Cu" "F.Mask" "F.Paste")
			(net "GND")
		)
		(pad "DV44" smd circle
			(at -2.427732 18.505932 270)
			(size 0.4318 0.4318)
			(layers "F.Cu" "F.Mask" "F.Paste")
			(net "M_G_CPU0_SB_CA<2>")
		)
		(pad "DV47" smd circle
			(at 1.613916 18.615914 270)
			(size 0.4318 0.4318)
			(layers "F.Cu" "F.Mask" "F.Paste")
			(net "M_G_CPU0_SB_RSP<1>")
		)
		(pad "DV49" smd circle
			(at 3.241802 18.615914 270)
			(size 0.4318 0.4318)
			(layers "F.Cu" "F.Mask" "F.Paste")
			(net "M_F_CPU0_CLK_DN<1>")
		)
		(pad "DV51" smd circle
			(at 4.869434 18.615914 270)
			(size 0.4318 0.4318)
			(layers "F.Cu" "F.Mask" "F.Paste")
			(net "M_F_CPU0_SB_CA<0>")
		)
		(pad "DV53" smd circle
			(at 6.49732 18.615914 270)
			(size 0.4318 0.4318)
			(layers "F.Cu" "F.Mask" "F.Paste")
			(net "M_F_CPU0_SA_DQ<29>")
		)
		(pad "DV55" smd circle
			(at 8.124952 18.615914 270)
			(size 0.4318 0.4318)
			(layers "F.Cu" "F.Mask" "F.Paste")
			(net "M_F_CPU0_SA_DQS_DN<3>")
		)
		(pad "DV57" smd circle
			(at 9.752838 18.615914 270)
			(size 0.4318 0.4318)
			(layers "F.Cu" "F.Mask" "F.Paste")
			(net "M_F_CPU0_SA_DQ<24>")
		)
		(pad "DV59" smd circle
			(at 11.380724 18.615914 270)
			(size 0.4318 0.4318)
			(layers "F.Cu" "F.Mask" "F.Paste")
			(net "M_G_CPU0_SA_DQ<21>")
		)
		(pad "DV61" smd circle
			(at 13.008356 18.615914 270)
			(size 0.4318 0.4318)
			(layers "F.Cu" "F.Mask" "F.Paste")
			(net "M_G_CPU0_SA_DQS_DP<2>")
		)
		(pad "DV63" smd circle
			(at 14.635988 18.615914 270)
			(size 0.4318 0.4318)
			(layers "F.Cu" "F.Mask" "F.Paste")
			(net "M_G_CPU0_SA_DQ<16>")
		)
		(pad "DV65" smd circle
			(at 16.263874 18.615914 270)
			(size 0.4318 0.4318)
			(layers "F.Cu" "F.Mask" "F.Paste")
			(net "M_F_CPU0_SA_DQ<13>")
		)
		(pad "DV67" smd circle
			(at 17.89176 18.615914 270)
			(size 0.4318 0.4318)
			(layers "F.Cu" "F.Mask" "F.Paste")
			(net "M_F_CPU0_SA_DQS_DP<1>")
		)
		(pad "DV69" smd circle
			(at 19.519392 18.615914 270)
			(size 0.4318 0.4318)
			(layers "F.Cu" "F.Mask" "F.Paste")
			(net "M_F_CPU0_SA_DQ<8>")
		)
		(pad "DV71" smd circle
			(at 21.147278 18.615914 270)
			(size 0.4318 0.4318)
			(layers "F.Cu" "F.Mask" "F.Paste")
			(net "M_G_CPU0_SA_DQ<5>")
		)
		(pad "DV73" smd circle
			(at 22.77491 18.615914 270)
			(size 0.4318 0.4318)
			(layers "F.Cu" "F.Mask" "F.Paste")
			(net "M_G_CPU0_SA_DQS_DN<0>")
		)
		(pad "DV75" smd circle
			(at 24.402796 18.615914 270)
			(size 0.4318 0.4318)
			(layers "F.Cu" "F.Mask" "F.Paste")
			(net "M_G_CPU0_SA_DQ<0>")
		)
		(pad "DV77" smd circle
			(at 26.030682 18.615914 270)
			(size 0.4318 0.4318)
			(layers "F.Cu" "F.Mask" "F.Paste")
			(net "GND")
		)
		(pad "DV79" smd circle
			(at 27.658314 18.615914 270)
			(size 0.4318 0.4318)
			(layers "F.Cu" "F.Mask" "F.Paste")
			(net "GND")
		)
		(pad "DV81" smd circle
			(at 29.2862 18.615914 270)
			(size 0.4318 0.4318)
			(layers "F.Cu" "F.Mask" "F.Paste")
			(net "GND")
		)
		(pad "DV83" smd circle
			(at 30.914086 18.615914 270)
			(size 0.4318 0.4318)
			(layers "F.Cu" "F.Mask" "F.Paste")
			(net "GND")
		)
		(pad "DV85" smd circle
			(at 32.541718 18.615914 270)
			(size 0.4318 0.4318)
			(layers "F.Cu" "F.Mask" "F.Paste")
			(net "P5E_CPU0_PE3_TX_DN<3>")
		)
		(pad "DV87" smd circle
			(at 34.169604 18.615914 270)
			(size 0.4318 0.4318)
			(layers "F.Cu" "F.Mask" "F.Paste")
			(net "GND")
		)
		(pad "DV89" smd circle
			(at 35.797236 18.615914 270)
			(size 0.4318 0.4318)
			(layers "F.Cu" "F.Mask" "F.Paste")
			(net "P5E_CPU0_PE3_RX_DN<4>")
		)
		(pad "DV91" smd oval
			(at 37.425122 18.615914)
			(size 0.381 0.4826)
			(drill
				(offset 0 -0.0508)
			)
			(layers "F.Cu" "F.Mask" "F.Paste")
			(net "GND")
		)
		(pad "DW1" smd oval
			(at -37.425122 18.976086 180)
			(size 0.381 0.4826)
			(drill
				(offset 0 -0.0508)
			)
			(layers "F.Cu" "F.Mask" "F.Paste")
			(net "GND")
		)
		(pad "DW3" smd circle
			(at -35.797236 18.976086 270)
			(size 0.4318 0.4318)
			(layers "F.Cu" "F.Mask" "F.Paste")
			(net "UPI_CPU1_CPU0_P0P1_DP<4>")
		)
		(pad "DW5" smd circle
			(at -34.169604 18.976086 270)
			(size 0.4318 0.4318)
			(layers "F.Cu" "F.Mask" "F.Paste")
			(net "GND")
		)
		(pad "DW7" smd circle
			(at -32.541718 18.976086 270)
			(size 0.4318 0.4318)
			(layers "F.Cu" "F.Mask" "F.Paste")
			(net "UPI_CPU0_CPU1_P1P0_DN<3>")
		)
		(pad "DW9" smd circle
			(at -30.914086 18.976086 270)
			(size 0.4318 0.4318)
			(layers "F.Cu" "F.Mask" "F.Paste")
			(net "GND")
		)
		(pad "DW11" smd circle
			(at -29.2862 18.976086 270)
			(size 0.4318 0.4318)
			(layers "F.Cu" "F.Mask" "F.Paste")
			(net "P5E_CPU0_PE2_RX_DP<11>")
		)
		(pad "DW13" smd circle
			(at -27.658314 18.976086 270)
			(size 0.4318 0.4318)
			(layers "F.Cu" "F.Mask" "F.Paste")
			(net "GND")
		)
		(pad "DW15" smd circle
			(at -26.030682 18.976086 270)
			(size 0.4318 0.4318)
			(layers "F.Cu" "F.Mask" "F.Paste")
			(net "P5E_CPU0_PE2_TX_DP<11>")
		)
		(pad "DW17" smd circle
			(at -24.402796 18.976086 270)
			(size 0.4318 0.4318)
			(layers "F.Cu" "F.Mask" "F.Paste")
			(net "GND")
		)
		(pad "DW19" smd circle
			(at -22.77491 18.976086 270)
			(size 0.4318 0.4318)
			(layers "F.Cu" "F.Mask" "F.Paste")
			(net "GND")
		)
		(pad "DW21" smd circle
			(at -21.147278 18.976086 270)
			(size 0.4318 0.4318)
			(layers "F.Cu" "F.Mask" "F.Paste")
			(net "GND")
		)
		(pad "DW23" smd circle
			(at -19.519392 18.976086 270)
			(size 0.4318 0.4318)
			(layers "F.Cu" "F.Mask" "F.Paste")
			(net "GND")
		)
		(pad "DW25" smd circle
			(at -17.89176 18.976086 270)
			(size 0.4318 0.4318)
			(layers "F.Cu" "F.Mask" "F.Paste")
			(net "GND")
		)
		(pad "DW27" smd circle
			(at -16.263874 18.976086 270)
			(size 0.4318 0.4318)
			(layers "F.Cu" "F.Mask" "F.Paste")
			(net "GND")
		)
		(pad "DW29" smd circle
			(at -14.635988 18.976086 270)
			(size 0.4318 0.4318)
			(layers "F.Cu" "F.Mask" "F.Paste")
			(net "GND")
		)
		(pad "DW31" smd circle
			(at -13.008356 18.976086 270)
			(size 0.4318 0.4318)
			(layers "F.Cu" "F.Mask" "F.Paste")
			(net "GND")
		)
		(pad "DW33" smd circle
			(at -11.380724 18.976086 270)
			(size 0.4318 0.4318)
			(layers "F.Cu" "F.Mask" "F.Paste")
			(net "GND")
		)
		(pad "DW35" smd circle
			(at -9.752838 18.976086 270)
			(size 0.4318 0.4318)
			(layers "F.Cu" "F.Mask" "F.Paste")
			(net "GND")
		)
		(pad "DW37" smd circle
			(at -8.124952 18.976086 270)
			(size 0.4318 0.4318)
			(layers "F.Cu" "F.Mask" "F.Paste")
			(net "GND")
		)
		(pad "DW39" smd circle
			(at -6.49732 18.976086 270)
			(size 0.4318 0.4318)
			(layers "F.Cu" "F.Mask" "F.Paste")
			(net "GND")
		)
		(pad "DW41" smd circle
			(at -4.869434 18.976086 270)
			(size 0.4318 0.4318)
			(layers "F.Cu" "F.Mask" "F.Paste")
			(net "GND")
		)
		(pad "DW43" smd circle
			(at -3.241802 18.976086 270)
			(size 0.4318 0.4318)
			(layers "F.Cu" "F.Mask" "F.Paste")
			(net "GND")
		)
		(pad "DW45" smd circle
			(at -1.613916 18.976086 270)
			(size 0.4318 0.4318)
			(layers "F.Cu" "F.Mask" "F.Paste")
			(net "GND")
		)
		(pad "DW48" smd circle
			(at 2.427732 19.086068 270)
			(size 0.4318 0.4318)
			(layers "F.Cu" "F.Mask" "F.Paste")
			(net "GND")
		)
		(pad "DW50" smd circle
			(at 4.055618 19.086068 270)
			(size 0.4318 0.4318)
			(layers "F.Cu" "F.Mask" "F.Paste")
			(net "GND")
		)
		(pad "DW52" smd circle
			(at 5.68325 19.086068 270)
			(size 0.4318 0.4318)
			(layers "F.Cu" "F.Mask" "F.Paste")
			(net "GND")
		)
		(pad "DW54" smd circle
			(at 7.311136 19.086068 270)
			(size 0.4318 0.4318)
			(layers "F.Cu" "F.Mask" "F.Paste")
			(net "GND")
		)
		(pad "DW56" smd circle
			(at 8.939022 19.086068 270)
			(size 0.4318 0.4318)
			(layers "F.Cu" "F.Mask" "F.Paste")
			(net "GND")
		)
		(pad "DW58" smd circle
			(at 10.566654 19.086068 270)
			(size 0.4318 0.4318)
			(layers "F.Cu" "F.Mask" "F.Paste")
			(net "GND")
		)
		(pad "DW60" smd circle
			(at 12.19454 19.086068 270)
			(size 0.4318 0.4318)
			(layers "F.Cu" "F.Mask" "F.Paste")
			(net "GND")
		)
		(pad "DW62" smd circle
			(at 13.822426 19.086068 270)
			(size 0.4318 0.4318)
			(layers "F.Cu" "F.Mask" "F.Paste")
			(net "GND")
		)
		(pad "DW64" smd circle
			(at 15.450058 19.086068 270)
			(size 0.4318 0.4318)
			(layers "F.Cu" "F.Mask" "F.Paste")
			(net "GND")
		)
		(pad "DW66" smd circle
			(at 17.07769 19.086068 270)
			(size 0.4318 0.4318)
			(layers "F.Cu" "F.Mask" "F.Paste")
			(net "GND")
		)
		(pad "DW68" smd circle
			(at 18.705576 19.086068 270)
			(size 0.4318 0.4318)
			(layers "F.Cu" "F.Mask" "F.Paste")
			(net "GND")
		)
		(pad "DW70" smd circle
			(at 20.333462 19.086068 270)
			(size 0.4318 0.4318)
			(layers "F.Cu" "F.Mask" "F.Paste")
			(net "GND")
		)
		(pad "DW72" smd circle
			(at 21.961094 19.086068 270)
			(size 0.4318 0.4318)
			(layers "F.Cu" "F.Mask" "F.Paste")
			(net "GND")
		)
		(pad "DW74" smd circle
			(at 23.58898 19.086068 270)
			(size 0.4318 0.4318)
			(layers "F.Cu" "F.Mask" "F.Paste")
			(net "GND")
		)
		(pad "DW76" smd circle
			(at 25.216612 19.086068 270)
			(size 0.4318 0.4318)
			(layers "F.Cu" "F.Mask" "F.Paste")
			(net "GND")
		)
		(pad "DW78" smd circle
			(at 26.844498 19.086068 270)
			(size 0.4318 0.4318)
			(layers "F.Cu" "F.Mask" "F.Paste")
			(net "M_H_CPU0_SA_DQ<2>")
		)
		(pad "DW80" smd circle
			(at 28.472384 19.086068 270)
			(size 0.4318 0.4318)
			(layers "F.Cu" "F.Mask" "F.Paste")
			(net "GND")
		)
		(pad "DW82" smd circle
			(at 30.100016 19.086068 270)
			(size 0.4318 0.4318)
			(layers "F.Cu" "F.Mask" "F.Paste")
			(net "GND")
		)
		(pad "DW84" smd circle
			(at 31.727902 19.086068 270)
			(size 0.4318 0.4318)
			(layers "F.Cu" "F.Mask" "F.Paste")
			(net "GND")
		)
		(pad "DW86" smd circle
			(at 33.355534 19.086068 270)
			(size 0.4318 0.4318)
			(layers "F.Cu" "F.Mask" "F.Paste")
			(net "P5E_CPU0_PE3_TX_DP<3>")
		)
		(pad "DW88" smd circle
			(at 34.98342 19.086068 270)
			(size 0.4318 0.4318)
			(layers "F.Cu" "F.Mask" "F.Paste")
			(net "GND")
		)
		(pad "DW90" smd circle
			(at 36.611306 19.086068 270)
			(size 0.4318 0.4318)
			(layers "F.Cu" "F.Mask" "F.Paste")
			(net "P5E_CPU0_PE3_RX_DP<4>")
		)
		(pad "DY2" smd circle
			(at -36.611306 19.445732 270)
			(size 0.4318 0.4318)
			(layers "F.Cu" "F.Mask" "F.Paste")
			(net "UPI_CPU1_CPU0_P0P1_DN<4>")
		)
		(pad "DY4" smd circle
			(at -34.98342 19.445732 270)
			(size 0.4318 0.4318)
			(layers "F.Cu" "F.Mask" "F.Paste")
			(net "GND")
		)
		(pad "DY6" smd circle
			(at -33.355534 19.445732 270)
			(size 0.4318 0.4318)
			(layers "F.Cu" "F.Mask" "F.Paste")
			(net "UPI_CPU0_CPU1_P1P0_DP<3>")
		)
		(pad "DY8" smd circle
			(at -31.727902 19.445732 270)
			(size 0.4318 0.4318)
			(layers "F.Cu" "F.Mask" "F.Paste")
			(net "GND")
		)
		(pad "DY10" smd circle
			(at -30.100016 19.445732 270)
			(size 0.4318 0.4318)
			(layers "F.Cu" "F.Mask" "F.Paste")
			(net "P5E_CPU0_PE2_RX_DN<11>")
		)
		(pad "DY12" smd circle
			(at -28.472384 19.445732 270)
			(size 0.4318 0.4318)
			(layers "F.Cu" "F.Mask" "F.Paste")
			(net "GND")
		)
		(pad "DY14" smd circle
			(at -26.844498 19.445732 270)
			(size 0.4318 0.4318)
			(layers "F.Cu" "F.Mask" "F.Paste")
			(net "P5E_CPU0_PE2_TX_DP<12>")
		)
		(pad "DY16" smd circle
			(at -25.216612 19.445732 270)
			(size 0.4318 0.4318)
			(layers "F.Cu" "F.Mask" "F.Paste")
			(net "GND")
		)
		(pad "DY18" smd circle
			(at -23.58898 19.445732 270)
			(size 0.4318 0.4318)
			(layers "F.Cu" "F.Mask" "F.Paste")
			(net "M_F_CPU0_SB_DQS_DN<8>")
		)
		(pad "DY20" smd circle
			(at -21.961094 19.445732 270)
			(size 0.4318 0.4318)
			(layers "F.Cu" "F.Mask" "F.Paste")
			(net "M_F_CPU0_SB_DQ<26>")
		)
		(pad "DY22" smd circle
			(at -20.333462 19.445732 270)
			(size 0.4318 0.4318)
			(layers "F.Cu" "F.Mask" "F.Paste")
			(net "M_G_CPU0_SB_DQ<23>")
		)
		(pad "DY24" smd circle
			(at -18.705576 19.445732 270)
			(size 0.4318 0.4318)
			(layers "F.Cu" "F.Mask" "F.Paste")
			(net "M_G_CPU0_SB_DQS_DP<7>")
		)
		(pad "DY26" smd circle
			(at -17.07769 19.445732 270)
			(size 0.4318 0.4318)
			(layers "F.Cu" "F.Mask" "F.Paste")
			(net "M_G_CPU0_SB_DQ<18>")
		)
		(pad "DY28" smd circle
			(at -15.450058 19.445732 270)
			(size 0.4318 0.4318)
			(layers "F.Cu" "F.Mask" "F.Paste")
			(net "M_F_CPU0_SB_DQ<7>")
		)
		(pad "DY30" smd circle
			(at -13.822426 19.445732 270)
			(size 0.4318 0.4318)
			(layers "F.Cu" "F.Mask" "F.Paste")
			(net "M_F_CPU0_SB_DQS_DP<5>")
		)
		(pad "DY32" smd circle
			(at -12.19454 19.445732 270)
			(size 0.4318 0.4318)
			(layers "F.Cu" "F.Mask" "F.Paste")
			(net "M_F_CPU0_SB_DQ<2>")
		)
		(pad "DY34" smd circle
			(at -10.566654 19.445732 270)
			(size 0.4318 0.4318)
			(layers "F.Cu" "F.Mask" "F.Paste")
			(net "M_G_CPU0_SB_CB<3>")
		)
		(pad "DY36" smd circle
			(at -8.939022 19.445732 270)
			(size 0.4318 0.4318)
			(layers "F.Cu" "F.Mask" "F.Paste")
			(net "M_G_CPU0_SB_DQS_DP<4>")
		)
		(pad "DY38" smd circle
			(at -7.311136 19.445732 270)
			(size 0.4318 0.4318)
			(layers "F.Cu" "F.Mask" "F.Paste")
			(net "M_G_CPU0_SB_CB<6>")
		)
		(pad "DY40" smd circle
			(at -5.68325 19.445732 270)
			(size 0.4318 0.4318)
			(layers "F.Cu" "F.Mask" "F.Paste")
			(net "M_G_CPU0_SB_CS_N<1>")
		)
		(pad "DY42" smd circle
			(at -4.055618 19.445732 270)
			(size 0.4318 0.4318)
			(layers "F.Cu" "F.Mask" "F.Paste")
			(net "GND")
		)
		(pad "DY44" smd circle
			(at -2.427732 19.445732 270)
			(size 0.4318 0.4318)
			(layers "F.Cu" "F.Mask" "F.Paste")
			(net "M_G_CPU0_SB_CA<3>")
		)
		(pad "DY47" smd circle
			(at 1.613916 19.555714 270)
			(size 0.4318 0.4318)
			(layers "F.Cu" "F.Mask" "F.Paste")
			(net "M_G_CPU0_SA_RSP<1>")
		)
		(pad "DY49" smd circle
			(at 3.241802 19.555714 270)
			(size 0.4318 0.4318)
			(layers "F.Cu" "F.Mask" "F.Paste")
			(net "M_F_CPU0_CLK_DN<0>")
		)
		(pad "DY51" smd circle
			(at 4.869434 19.555714 270)
			(size 0.4318 0.4318)
			(layers "F.Cu" "F.Mask" "F.Paste")
			(net "M_F_CPU0_SA_CA<6>")
		)
		(pad "DY53" smd circle
			(at 6.49732 19.555714 270)
			(size 0.4318 0.4318)
			(layers "F.Cu" "F.Mask" "F.Paste")
			(net "M_F_CPU0_SA_DQ<31>")
		)
		(pad "DY55" smd circle
			(at 8.124952 19.555714 270)
			(size 0.4318 0.4318)
			(layers "F.Cu" "F.Mask" "F.Paste")
			(net "M_F_CPU0_SA_DQS_DP<8>")
		)
		(pad "DY57" smd circle
			(at 9.752838 19.555714 270)
			(size 0.4318 0.4318)
			(layers "F.Cu" "F.Mask" "F.Paste")
			(net "M_F_CPU0_SA_DQ<26>")
		)
		(pad "DY59" smd circle
			(at 11.380724 19.555714 270)
			(size 0.4318 0.4318)
			(layers "F.Cu" "F.Mask" "F.Paste")
			(net "M_G_CPU0_SA_DQ<23>")
		)
		(pad "DY61" smd circle
			(at 13.008356 19.555714 270)
			(size 0.4318 0.4318)
			(layers "F.Cu" "F.Mask" "F.Paste")
			(net "M_G_CPU0_SA_DQS_DP<7>")
		)
		(pad "DY63" smd circle
			(at 14.635988 19.555714 270)
			(size 0.4318 0.4318)
			(layers "F.Cu" "F.Mask" "F.Paste")
			(net "M_G_CPU0_SA_DQ<18>")
		)
		(pad "DY65" smd circle
			(at 16.263874 19.555714 270)
			(size 0.4318 0.4318)
			(layers "F.Cu" "F.Mask" "F.Paste")
			(net "M_F_CPU0_SA_DQ<15>")
		)
		(pad "DY67" smd circle
			(at 17.89176 19.555714 270)
			(size 0.4318 0.4318)
			(layers "F.Cu" "F.Mask" "F.Paste")
			(net "M_F_CPU0_SA_DQS_DP<6>")
		)
		(pad "DY69" smd circle
			(at 19.519392 19.555714 270)
			(size 0.4318 0.4318)
			(layers "F.Cu" "F.Mask" "F.Paste")
			(net "M_F_CPU0_SA_DQ<10>")
		)
		(pad "DY71" smd circle
			(at 21.147278 19.555714 270)
			(size 0.4318 0.4318)
			(layers "F.Cu" "F.Mask" "F.Paste")
			(net "M_G_CPU0_SA_DQ<7>")
		)
		(pad "DY73" smd circle
			(at 22.77491 19.555714 270)
			(size 0.4318 0.4318)
			(layers "F.Cu" "F.Mask" "F.Paste")
			(net "M_G_CPU0_SA_DQS_DP<5>")
		)
		(pad "DY75" smd circle
			(at 24.402796 19.555714 270)
			(size 0.4318 0.4318)
			(layers "F.Cu" "F.Mask" "F.Paste")
			(net "M_G_CPU0_SA_DQ<2>")
		)
		(pad "DY77" smd circle
			(at 26.030682 19.555714 270)
			(size 0.4318 0.4318)
			(layers "F.Cu" "F.Mask" "F.Paste")
			(net "GND")
		)
		(pad "DY79" smd circle
			(at 27.658314 19.555714 270)
			(size 0.4318 0.4318)
			(layers "F.Cu" "F.Mask" "F.Paste")
			(net "M_H_CPU0_SA_DQ<0>")
		)
		(pad "DY81" smd circle
			(at 29.2862 19.555714 270)
			(size 0.4318 0.4318)
			(layers "F.Cu" "F.Mask" "F.Paste")
			(net "GND")
		)
		(pad "DY83" smd circle
			(at 30.914086 19.555714 270)
			(size 0.4318 0.4318)
			(layers "F.Cu" "F.Mask" "F.Paste")
			(net "GND")
		)
		(pad "DY85" smd circle
			(at 32.541718 19.555714 270)
			(size 0.4318 0.4318)
			(layers "F.Cu" "F.Mask" "F.Paste")
			(net "PVCCFA_EHV_FIVRA_CPU0")
		)
		(pad "DY87" smd circle
			(at 34.169604 19.555714 270)
			(size 0.4318 0.4318)
			(layers "F.Cu" "F.Mask" "F.Paste")
			(net "P5E_CPU0_PE3_TX_DN<2>")
		)
		(pad "DY89" smd circle
			(at 35.797236 19.555714 270)
			(size 0.4318 0.4318)
			(layers "F.Cu" "F.Mask" "F.Paste")
			(net "PVCCFA_EHV_FIVRA_CPU0")
		)
		(pad "DY91" smd oval
			(at 37.425122 19.555714)
			(size 0.381 0.4826)
			(drill
				(offset 0 -0.0508)
			)
			(layers "F.Cu" "F.Mask" "F.Paste")
			(net "P5E_CPU0_PE3_RX_DN<3>")
		)
		(pad "E5" smd oval
			(at -34.169604 -25.194514 135)
			(size 0.381 0.4826)
			(drill
				(offset 0 -0.0508)
			)
			(layers "F.Cu" "F.Mask" "F.Paste")
			(net "GND")
		)
		(pad "E7" smd oval
			(at -32.541718 -25.194514 135)
			(size 0.381 0.4826)
			(drill
				(offset 0 -0.0508)
			)
			(layers "F.Cu" "F.Mask" "F.Paste")
			(net "M_A_CPU0_SB_DQ<31>")
		)
		(pad "E9" smd circle
			(at -30.914086 -25.194514 270)
			(size 0.4318 0.4318)
			(layers "F.Cu" "F.Mask" "F.Paste")
			(net "M_A_CPU0_SB_DQS_DP<8>")
		)
		(pad "E11" smd circle
			(at -29.2862 -25.194514 270)
			(size 0.4318 0.4318)
			(layers "F.Cu" "F.Mask" "F.Paste")
			(net "M_A_CPU0_SB_DQ<26>")
		)
		(pad "E13" smd circle
			(at -27.658314 -25.194514 270)
			(size 0.4318 0.4318)
			(layers "F.Cu" "F.Mask" "F.Paste")
			(net "M_B_CPU0_SB_DQ<29>")
		)
		(pad "E15" smd circle
			(at -26.030682 -25.194514 270)
			(size 0.4318 0.4318)
			(layers "F.Cu" "F.Mask" "F.Paste")
			(net "M_B_CPU0_SB_DQS_DN<8>")
		)
		(pad "E17" smd circle
			(at -24.402796 -25.194514 270)
			(size 0.4318 0.4318)
			(layers "F.Cu" "F.Mask" "F.Paste")
			(net "M_B_CPU0_SB_DQ<26>")
		)
		(pad "E19" smd circle
			(at -22.77491 -25.194514 270)
			(size 0.4318 0.4318)
			(layers "F.Cu" "F.Mask" "F.Paste")
			(net "M_A_CPU0_SB_DQ<23>")
		)
		(pad "E21" smd circle
			(at -21.147278 -25.194514 270)
			(size 0.4318 0.4318)
			(layers "F.Cu" "F.Mask" "F.Paste")
			(net "M_A_CPU0_SB_DQS_DP<7>")
		)
		(pad "E23" smd circle
			(at -19.519392 -25.194514 270)
			(size 0.4318 0.4318)
			(layers "F.Cu" "F.Mask" "F.Paste")
			(net "M_A_CPU0_SB_DQ<18>")
		)
		(pad "E25" smd circle
			(at -17.89176 -25.194514 270)
			(size 0.4318 0.4318)
			(layers "F.Cu" "F.Mask" "F.Paste")
			(net "M_A_CPU0_SB_DQ<15>")
		)
		(pad "E27" smd circle
			(at -16.263874 -25.194514 270)
			(size 0.4318 0.4318)
			(layers "F.Cu" "F.Mask" "F.Paste")
			(net "M_A_CPU0_SB_DQS_DP<6>")
		)
		(pad "E29" smd circle
			(at -14.635988 -25.194514 270)
			(size 0.4318 0.4318)
			(layers "F.Cu" "F.Mask" "F.Paste")
			(net "M_A_CPU0_SB_DQ<10>")
		)
		(pad "E31" smd circle
			(at -13.008356 -25.194514 270)
			(size 0.4318 0.4318)
			(layers "F.Cu" "F.Mask" "F.Paste")
			(net "M_A_CPU0_SB_CB<3>")
		)
		(pad "E33" smd circle
			(at -11.380724 -25.194514 270)
			(size 0.4318 0.4318)
			(layers "F.Cu" "F.Mask" "F.Paste")
			(net "M_A_CPU0_SB_DQS_DP<4>")
		)
		(pad "E35" smd circle
			(at -9.752838 -25.194514 270)
			(size 0.4318 0.4318)
			(layers "F.Cu" "F.Mask" "F.Paste")
			(net "M_A_CPU0_SB_CB<6>")
		)
		(pad "E37" smd circle
			(at -8.124952 -25.194514 270)
			(size 0.4318 0.4318)
			(layers "F.Cu" "F.Mask" "F.Paste")
			(net "M_A_CPU0_SB_CS_N<3>")
		)
		(pad "E39" smd circle
			(at -6.49732 -25.194514 270)
			(size 0.4318 0.4318)
			(layers "F.Cu" "F.Mask" "F.Paste")
			(net "GND")
		)
		(pad "E41" smd circle
			(at -4.869434 -25.194514 270)
			(size 0.4318 0.4318)
			(layers "F.Cu" "F.Mask" "F.Paste")
			(net "M_A_CPU0_SB_CA<3>")
		)
		(pad "E43" smd circle
			(at -3.241802 -25.194514 270)
			(size 0.4318 0.4318)
			(layers "F.Cu" "F.Mask" "F.Paste")
			(net "M_A_CPU0_SB_CA<0>")
		)
		(pad "E45" smd circle
			(at -1.613916 -25.194514 270)
			(size 0.4318 0.4318)
			(layers "F.Cu" "F.Mask" "F.Paste")
			(net "M_A_CPU0_CLK_DP<1>")
		)
		(pad "E48" smd circle
			(at 2.427732 -25.084532 270)
			(size 0.4318 0.4318)
			(layers "F.Cu" "F.Mask" "F.Paste")
			(net "M_A_CPU0_SA_PAR")
		)
		(pad "E50" smd circle
			(at 4.055618 -25.084532 270)
			(size 0.4318 0.4318)
			(layers "F.Cu" "F.Mask" "F.Paste")
			(net "M_A_CPU0_SA_CA<5>")
		)
		(pad "E52" smd circle
			(at 5.68325 -25.084532 270)
			(size 0.4318 0.4318)
			(layers "F.Cu" "F.Mask" "F.Paste")
			(net "GND")
		)
		(pad "E54" smd circle
			(at 7.311136 -25.084532 270)
			(size 0.4318 0.4318)
			(layers "F.Cu" "F.Mask" "F.Paste")
			(net "M_A_CPU0_SA_CS_N<2>")
		)
		(pad "E56" smd circle
			(at 8.939022 -25.084532 270)
			(size 0.4318 0.4318)
			(layers "F.Cu" "F.Mask" "F.Paste")
			(net "M_A_CPU0_SA_CB<7>")
		)
		(pad "E58" smd circle
			(at 10.566654 -25.084532 270)
			(size 0.4318 0.4318)
			(layers "F.Cu" "F.Mask" "F.Paste")
			(net "M_A_CPU0_SA_DQS_DP<9>")
		)
		(pad "E60" smd circle
			(at 12.19454 -25.084532 270)
			(size 0.4318 0.4318)
			(layers "F.Cu" "F.Mask" "F.Paste")
			(net "M_A_CPU0_SA_CB<2>")
		)
		(pad "E62" smd circle
			(at 13.822426 -25.084532 270)
			(size 0.4318 0.4318)
			(layers "F.Cu" "F.Mask" "F.Paste")
			(net "M_A_CPU0_SA_DQ<31>")
		)
		(pad "E64" smd circle
			(at 15.450058 -25.084532 270)
			(size 0.4318 0.4318)
			(layers "F.Cu" "F.Mask" "F.Paste")
			(net "M_A_CPU0_SA_DQS_DP<8>")
		)
		(pad "E66" smd circle
			(at 17.07769 -25.084532 270)
			(size 0.4318 0.4318)
			(layers "F.Cu" "F.Mask" "F.Paste")
			(net "M_A_CPU0_SA_DQ<26>")
		)
		(pad "E68" smd circle
			(at 18.705576 -25.084532 270)
			(size 0.4318 0.4318)
			(layers "F.Cu" "F.Mask" "F.Paste")
			(net "M_A_CPU0_SA_DQ<23>")
		)
		(pad "E70" smd circle
			(at 20.333462 -25.084532 270)
			(size 0.4318 0.4318)
			(layers "F.Cu" "F.Mask" "F.Paste")
			(net "M_A_CPU0_SA_DQS_DP<7>")
		)
		(pad "E72" smd circle
			(at 21.961094 -25.084532 270)
			(size 0.4318 0.4318)
			(layers "F.Cu" "F.Mask" "F.Paste")
			(net "M_A_CPU0_SA_DQ<17>")
		)
		(pad "E74" smd circle
			(at 23.58898 -25.084532 270)
			(size 0.4318 0.4318)
			(layers "F.Cu" "F.Mask" "F.Paste")
			(net "GND")
		)
		(pad "E76" smd circle
			(at 25.216612 -25.084532 270)
			(size 0.4318 0.4318)
			(layers "F.Cu" "F.Mask" "F.Paste")
			(net "GND")
		)
		(pad "E78" smd circle
			(at 26.844498 -25.084532 270)
			(size 0.4318 0.4318)
			(layers "F.Cu" "F.Mask" "F.Paste")
			(net "GND")
		)
		(pad "E80" smd circle
			(at 28.472384 -25.084532 270)
			(size 0.4318 0.4318)
			(layers "F.Cu" "F.Mask" "F.Paste")
			(net "UPI_CPU1_CPU0_P2P2_DN<23>")
		)
		(pad "E82" smd circle
			(at 30.100016 -25.084532 270)
			(size 0.4318 0.4318)
			(layers "F.Cu" "F.Mask" "F.Paste")
			(net "UPI_CPU1_CPU0_P2P2_DN<22>")
		)
		(pad "E84" smd circle
			(at 31.727902 -25.084532 270)
			(size 0.4318 0.4318)
			(layers "F.Cu" "F.Mask" "F.Paste")
			(net "UPI_CPU0_CPU1_P2P2_DN<22>")
		)
		(pad "E86" smd oval
			(at 33.355534 -25.084532 45)
			(size 0.381 0.4826)
			(drill
				(offset 0 -0.0508)
			)
			(layers "F.Cu" "F.Mask" "F.Paste")
			(net "GND")
		)
		(pad "E88" smd oval
			(at 34.98342 -25.084532 45)
			(size 0.381 0.4826)
			(drill
				(offset 0 -0.0508)
			)
			(layers "F.Cu" "F.Mask" "F.Paste")
			(net "UPI_CPU0_CPU1_P2P2_DP<21>")
		)
		(pad "EA1" smd oval
			(at -37.425122 19.915886 180)
			(size 0.381 0.4826)
			(drill
				(offset 0 -0.0508)
			)
			(layers "F.Cu" "F.Mask" "F.Paste")
			(net "UPI_CPU1_CPU0_P0P1_DN<3>")
		)
		(pad "EA3" smd circle
			(at -35.797236 19.915886 270)
			(size 0.4318 0.4318)
			(layers "F.Cu" "F.Mask" "F.Paste")
			(net "PVCCFA_EHV_FIVRA_CPU0")
		)
		(pad "EA5" smd circle
			(at -34.169604 19.915886 270)
			(size 0.4318 0.4318)
			(layers "F.Cu" "F.Mask" "F.Paste")
			(net "UPI_CPU0_CPU1_P1P0_DP<2>")
		)
		(pad "EA7" smd circle
			(at -32.541718 19.915886 270)
			(size 0.4318 0.4318)
			(layers "F.Cu" "F.Mask" "F.Paste")
			(net "PVCCFA_EHV_FIVRA_CPU0")
		)
		(pad "EA9" smd circle
			(at -30.914086 19.915886 270)
			(size 0.4318 0.4318)
			(layers "F.Cu" "F.Mask" "F.Paste")
			(net "P5E_CPU0_PE2_RX_DN<12>")
		)
		(pad "EA11" smd circle
			(at -29.2862 19.915886 270)
			(size 0.4318 0.4318)
			(layers "F.Cu" "F.Mask" "F.Paste")
			(net "PVCCFA_EHV_FIVRA_CPU0")
		)
		(pad "EA13" smd circle
			(at -27.658314 19.915886 270)
			(size 0.4318 0.4318)
			(layers "F.Cu" "F.Mask" "F.Paste")
			(net "P5E_CPU0_PE2_TX_DN<12>")
		)
		(pad "EA15" smd circle
			(at -26.030682 19.915886 270)
			(size 0.4318 0.4318)
			(layers "F.Cu" "F.Mask" "F.Paste")
			(net "PVCCFA_EHV_FIVRA_CPU0")
		)
		(pad "EA17" smd circle
			(at -24.402796 19.915886 270)
			(size 0.4318 0.4318)
			(layers "F.Cu" "F.Mask" "F.Paste")
			(net "M_F_CPU0_SB_DQ<28>")
		)
		(pad "EA19" smd circle
			(at -22.77491 19.915886 270)
			(size 0.4318 0.4318)
			(layers "F.Cu" "F.Mask" "F.Paste")
			(net "M_F_CPU0_SB_DQ<27>")
		)
		(pad "EA21" smd circle
			(at -21.147278 19.915886 270)
			(size 0.4318 0.4318)
			(layers "F.Cu" "F.Mask" "F.Paste")
			(net "GND")
		)
		(pad "EA23" smd circle
			(at -19.519392 19.915886 270)
			(size 0.4318 0.4318)
			(layers "F.Cu" "F.Mask" "F.Paste")
			(net "M_G_CPU0_SB_DQ<22>")
		)
		(pad "EA25" smd circle
			(at -17.89176 19.915886 270)
			(size 0.4318 0.4318)
			(layers "F.Cu" "F.Mask" "F.Paste")
			(net "M_G_CPU0_SB_DQ<19>")
		)
		(pad "EA27" smd circle
			(at -16.263874 19.915886 270)
			(size 0.4318 0.4318)
			(layers "F.Cu" "F.Mask" "F.Paste")
			(net "GND")
		)
		(pad "EA29" smd circle
			(at -14.635988 19.915886 270)
			(size 0.4318 0.4318)
			(layers "F.Cu" "F.Mask" "F.Paste")
			(net "M_F_CPU0_SB_DQ<6>")
		)
		(pad "EA31" smd circle
			(at -13.008356 19.915886 270)
			(size 0.4318 0.4318)
			(layers "F.Cu" "F.Mask" "F.Paste")
			(net "M_F_CPU0_SB_DQ<3>")
		)
		(pad "EA33" smd circle
			(at -11.380724 19.915886 270)
			(size 0.4318 0.4318)
			(layers "F.Cu" "F.Mask" "F.Paste")
			(net "GND")
		)
		(pad "EA35" smd circle
			(at -9.752838 19.915886 270)
			(size 0.4318 0.4318)
			(layers "F.Cu" "F.Mask" "F.Paste")
			(net "M_G_CPU0_SB_CB<2>")
		)
		(pad "EA37" smd circle
			(at -8.124952 19.915886 270)
			(size 0.4318 0.4318)
			(layers "F.Cu" "F.Mask" "F.Paste")
			(net "M_G_CPU0_SB_CB<7>")
		)
		(pad "EA39" smd circle
			(at -6.49732 19.915886 270)
			(size 0.4318 0.4318)
			(layers "F.Cu" "F.Mask" "F.Paste")
			(net "GND")
		)
		(pad "EA41" smd circle
			(at -4.869434 19.915886 270)
			(size 0.4318 0.4318)
			(layers "F.Cu" "F.Mask" "F.Paste")
			(net "M_G_CPU0_SB_CS_N<0>")
		)
		(pad "EA43" smd circle
			(at -3.241802 19.915886 270)
			(size 0.4318 0.4318)
			(layers "F.Cu" "F.Mask" "F.Paste")
			(net "M_G_CPU0_SB_CA<5>")
		)
		(pad "EA45" smd circle
			(at -1.613916 19.915886 270)
			(size 0.4318 0.4318)
			(layers "F.Cu" "F.Mask" "F.Paste")
			(net "GND")
		)
		(pad "EA48" smd circle
			(at 2.427732 20.025868 270)
			(size 0.4318 0.4318)
			(layers "F.Cu" "F.Mask" "F.Paste")
			(net "M_G_CPU0_SA_RSP<0>")
		)
		(pad "EA50" smd circle
			(at 4.055618 20.025868 270)
			(size 0.4318 0.4318)
			(layers "F.Cu" "F.Mask" "F.Paste")
			(net "M_F_CPU0_SA_PAR")
		)
		(pad "EA52" smd circle
			(at 5.68325 20.025868 270)
			(size 0.4318 0.4318)
			(layers "F.Cu" "F.Mask" "F.Paste")
			(net "GND")
		)
		(pad "EA54" smd circle
			(at 7.311136 20.025868 270)
			(size 0.4318 0.4318)
			(layers "F.Cu" "F.Mask" "F.Paste")
			(net "M_F_CPU0_SA_DQ<30>")
		)
		(pad "EA56" smd circle
			(at 8.939022 20.025868 270)
			(size 0.4318 0.4318)
			(layers "F.Cu" "F.Mask" "F.Paste")
			(net "M_F_CPU0_SA_DQ<27>")
		)
		(pad "EA58" smd circle
			(at 10.566654 20.025868 270)
			(size 0.4318 0.4318)
			(layers "F.Cu" "F.Mask" "F.Paste")
			(net "GND")
		)
		(pad "EA60" smd circle
			(at 12.19454 20.025868 270)
			(size 0.4318 0.4318)
			(layers "F.Cu" "F.Mask" "F.Paste")
			(net "M_G_CPU0_SA_DQ<22>")
		)
		(pad "EA62" smd circle
			(at 13.822426 20.025868 270)
			(size 0.4318 0.4318)
			(layers "F.Cu" "F.Mask" "F.Paste")
			(net "M_G_CPU0_SA_DQ<19>")
		)
		(pad "EA64" smd circle
			(at 15.450058 20.025868 270)
			(size 0.4318 0.4318)
			(layers "F.Cu" "F.Mask" "F.Paste")
			(net "GND")
		)
		(pad "EA66" smd circle
			(at 17.07769 20.025868 270)
			(size 0.4318 0.4318)
			(layers "F.Cu" "F.Mask" "F.Paste")
			(net "M_F_CPU0_SA_DQ<14>")
		)
		(pad "EA68" smd circle
			(at 18.705576 20.025868 270)
			(size 0.4318 0.4318)
			(layers "F.Cu" "F.Mask" "F.Paste")
			(net "M_F_CPU0_SA_DQ<11>")
		)
		(pad "EA70" smd circle
			(at 20.333462 20.025868 270)
			(size 0.4318 0.4318)
			(layers "F.Cu" "F.Mask" "F.Paste")
			(net "GND")
		)
		(pad "EA72" smd circle
			(at 21.961094 20.025868 270)
			(size 0.4318 0.4318)
			(layers "F.Cu" "F.Mask" "F.Paste")
			(net "M_G_CPU0_SA_DQ<6>")
		)
		(pad "EA74" smd circle
			(at 23.58898 20.025868 270)
			(size 0.4318 0.4318)
			(layers "F.Cu" "F.Mask" "F.Paste")
			(net "M_G_CPU0_SA_DQ<3>")
		)
		(pad "EA76" smd circle
			(at 25.216612 20.025868 270)
			(size 0.4318 0.4318)
			(layers "F.Cu" "F.Mask" "F.Paste")
			(net "GND")
		)
		(pad "EA78" smd circle
			(at 26.844498 20.025868 270)
			(size 0.4318 0.4318)
			(layers "F.Cu" "F.Mask" "F.Paste")
			(net "GND")
		)
		(pad "EA80" smd circle
			(at 28.472384 20.025868 270)
			(size 0.4318 0.4318)
			(layers "F.Cu" "F.Mask" "F.Paste")
			(net "GND")
		)
		(pad "EA82" smd circle
			(at 30.100016 20.025868 270)
			(size 0.4318 0.4318)
			(layers "F.Cu" "F.Mask" "F.Paste")
			(net "GND")
		)
		(pad "EA84" smd circle
			(at 31.727902 20.025868 270)
			(size 0.4318 0.4318)
			(layers "F.Cu" "F.Mask" "F.Paste")
			(net "GND")
		)
		(pad "EA86" smd circle
			(at 33.355534 20.025868 270)
			(size 0.4318 0.4318)
			(layers "F.Cu" "F.Mask" "F.Paste")
			(net "P5E_CPU0_PE3_TX_DP<2>")
		)
		(pad "EA88" smd circle
			(at 34.98342 20.025868 270)
			(size 0.4318 0.4318)
			(layers "F.Cu" "F.Mask" "F.Paste")
			(net "GND")
		)
		(pad "EA90" smd circle
			(at 36.611306 20.025868 270)
			(size 0.4318 0.4318)
			(layers "F.Cu" "F.Mask" "F.Paste")
			(net "P5E_CPU0_PE3_RX_DP<3>")
		)
		(pad "EB2" smd circle
			(at -36.611306 20.385532 270)
			(size 0.4318 0.4318)
			(layers "F.Cu" "F.Mask" "F.Paste")
			(net "UPI_CPU1_CPU0_P0P1_DP<3>")
		)
		(pad "EB4" smd circle
			(at -34.98342 20.385532 270)
			(size 0.4318 0.4318)
			(layers "F.Cu" "F.Mask" "F.Paste")
			(net "GND")
		)
		(pad "EB6" smd circle
			(at -33.355534 20.385532 270)
			(size 0.4318 0.4318)
			(layers "F.Cu" "F.Mask" "F.Paste")
			(net "UPI_CPU0_CPU1_P1P0_DN<2>")
		)
		(pad "EB8" smd circle
			(at -31.727902 20.385532 270)
			(size 0.4318 0.4318)
			(layers "F.Cu" "F.Mask" "F.Paste")
			(net "GND")
		)
		(pad "EB10" smd circle
			(at -30.100016 20.385532 270)
			(size 0.4318 0.4318)
			(layers "F.Cu" "F.Mask" "F.Paste")
			(net "P5E_CPU0_PE2_RX_DP<12>")
		)
		(pad "EB12" smd circle
			(at -28.472384 20.385532 270)
			(size 0.4318 0.4318)
			(layers "F.Cu" "F.Mask" "F.Paste")
			(net "GND")
		)
		(pad "EB14" smd circle
			(at -26.844498 20.385532 270)
			(size 0.4318 0.4318)
			(layers "F.Cu" "F.Mask" "F.Paste")
			(net "P5E_CPU0_PE2_TX_DN<13>")
		)
		(pad "EB16" smd circle
			(at -25.216612 20.385532 270)
			(size 0.4318 0.4318)
			(layers "F.Cu" "F.Mask" "F.Paste")
			(net "GND")
		)
		(pad "EB18" smd circle
			(at -23.58898 20.385532 270)
			(size 0.4318 0.4318)
			(layers "F.Cu" "F.Mask" "F.Paste")
			(net "M_F_CPU0_SB_DQS_DP<8>")
		)
		(pad "EB20" smd circle
			(at -21.961094 20.385532 270)
			(size 0.4318 0.4318)
			(layers "F.Cu" "F.Mask" "F.Paste")
			(net "GND")
		)
		(pad "EB22" smd circle
			(at -20.333462 20.385532 270)
			(size 0.4318 0.4318)
			(layers "F.Cu" "F.Mask" "F.Paste")
			(net "GND")
		)
		(pad "EB24" smd circle
			(at -18.705576 20.385532 270)
			(size 0.4318 0.4318)
			(layers "F.Cu" "F.Mask" "F.Paste")
			(net "M_G_CPU0_SB_DQS_DN<7>")
		)
		(pad "EB26" smd circle
			(at -17.07769 20.385532 270)
			(size 0.4318 0.4318)
			(layers "F.Cu" "F.Mask" "F.Paste")
			(net "GND")
		)
		(pad "EB28" smd circle
			(at -15.450058 20.385532 270)
			(size 0.4318 0.4318)
			(layers "F.Cu" "F.Mask" "F.Paste")
			(net "GND")
		)
		(pad "EB30" smd circle
			(at -13.822426 20.385532 270)
			(size 0.4318 0.4318)
			(layers "F.Cu" "F.Mask" "F.Paste")
			(net "M_F_CPU0_SB_DQS_DN<5>")
		)
		(pad "EB32" smd circle
			(at -12.19454 20.385532 270)
			(size 0.4318 0.4318)
			(layers "F.Cu" "F.Mask" "F.Paste")
			(net "GND")
		)
		(pad "EB34" smd circle
			(at -10.566654 20.385532 270)
			(size 0.4318 0.4318)
			(layers "F.Cu" "F.Mask" "F.Paste")
			(net "GND")
		)
		(pad "EB36" smd circle
			(at -8.939022 20.385532 270)
			(size 0.4318 0.4318)
			(layers "F.Cu" "F.Mask" "F.Paste")
			(net "M_G_CPU0_SB_DQS_DN<4>")
		)
		(pad "EB38" smd circle
			(at -7.311136 20.385532 270)
			(size 0.4318 0.4318)
			(layers "F.Cu" "F.Mask" "F.Paste")
			(net "GND")
		)
		(pad "EB40" smd circle
			(at -5.68325 20.385532 270)
			(size 0.4318 0.4318)
			(layers "F.Cu" "F.Mask" "F.Paste")
			(net "GND")
		)
		(pad "EB42" smd circle
			(at -4.055618 20.385532 270)
			(size 0.4318 0.4318)
			(layers "F.Cu" "F.Mask" "F.Paste")
			(net "M_G_CPU0_SB_PAR")
		)
		(pad "EB44" smd circle
			(at -2.427732 20.385532 270)
			(size 0.4318 0.4318)
			(layers "F.Cu" "F.Mask" "F.Paste")
			(net "GND")
		)
		(pad "EB47" smd circle
			(at 1.613916 20.495514 270)
			(size 0.4318 0.4318)
			(layers "F.Cu" "F.Mask" "F.Paste")
			(net "GND")
		)
		(pad "EB49" smd circle
			(at 3.241802 20.495514 270)
			(size 0.4318 0.4318)
			(layers "F.Cu" "F.Mask" "F.Paste")
			(net "M_F_CPU0_CLK_DP<0>")
		)
		(pad "EB51" smd circle
			(at 4.869434 20.495514 270)
			(size 0.4318 0.4318)
			(layers "F.Cu" "F.Mask" "F.Paste")
			(net "GND")
		)
		(pad "EB53" smd circle
			(at 6.49732 20.495514 270)
			(size 0.4318 0.4318)
			(layers "F.Cu" "F.Mask" "F.Paste")
			(net "GND")
		)
		(pad "EB55" smd circle
			(at 8.124952 20.495514 270)
			(size 0.4318 0.4318)
			(layers "F.Cu" "F.Mask" "F.Paste")
			(net "M_F_CPU0_SA_DQS_DN<8>")
		)
		(pad "EB57" smd circle
			(at 9.752838 20.495514 270)
			(size 0.4318 0.4318)
			(layers "F.Cu" "F.Mask" "F.Paste")
			(net "GND")
		)
		(pad "EB59" smd circle
			(at 11.380724 20.495514 270)
			(size 0.4318 0.4318)
			(layers "F.Cu" "F.Mask" "F.Paste")
			(net "GND")
		)
		(pad "EB61" smd circle
			(at 13.008356 20.495514 270)
			(size 0.4318 0.4318)
			(layers "F.Cu" "F.Mask" "F.Paste")
			(net "M_G_CPU0_SA_DQS_DN<7>")
		)
		(pad "EB63" smd circle
			(at 14.635988 20.495514 270)
			(size 0.4318 0.4318)
			(layers "F.Cu" "F.Mask" "F.Paste")
			(net "GND")
		)
		(pad "EB65" smd circle
			(at 16.263874 20.495514 270)
			(size 0.4318 0.4318)
			(layers "F.Cu" "F.Mask" "F.Paste")
			(net "GND")
		)
		(pad "EB67" smd circle
			(at 17.89176 20.495514 270)
			(size 0.4318 0.4318)
			(layers "F.Cu" "F.Mask" "F.Paste")
			(net "M_F_CPU0_SA_DQS_DN<6>")
		)
		(pad "EB69" smd circle
			(at 19.519392 20.495514 270)
			(size 0.4318 0.4318)
			(layers "F.Cu" "F.Mask" "F.Paste")
			(net "GND")
		)
		(pad "EB71" smd circle
			(at 21.147278 20.495514 270)
			(size 0.4318 0.4318)
			(layers "F.Cu" "F.Mask" "F.Paste")
			(net "GND")
		)
		(pad "EB73" smd circle
			(at 22.77491 20.495514 270)
			(size 0.4318 0.4318)
			(layers "F.Cu" "F.Mask" "F.Paste")
			(net "M_G_CPU0_SA_DQS_DN<5>")
		)
		(pad "EB75" smd circle
			(at 24.402796 20.495514 270)
			(size 0.4318 0.4318)
			(layers "F.Cu" "F.Mask" "F.Paste")
			(net "GND")
		)
		(pad "EB77" smd circle
			(at 26.030682 20.495514 270)
			(size 0.4318 0.4318)
			(layers "F.Cu" "F.Mask" "F.Paste")
			(net "M_F_CPU0_SA_DQ<0>")
		)
		(pad "EB79" smd circle
			(at 27.658314 20.495514 270)
			(size 0.4318 0.4318)
			(layers "F.Cu" "F.Mask" "F.Paste")
			(net "GND")
		)
		(pad "EB81" smd circle
			(at 29.2862 20.495514 270)
			(size 0.4318 0.4318)
			(layers "F.Cu" "F.Mask" "F.Paste")
			(net "GND")
		)
		(pad "EB83" smd circle
			(at 30.914086 20.495514 270)
			(size 0.4318 0.4318)
			(layers "F.Cu" "F.Mask" "F.Paste")
			(net "GND")
		)
		(pad "EB85" smd circle
			(at 32.541718 20.495514 270)
			(size 0.4318 0.4318)
			(layers "F.Cu" "F.Mask" "F.Paste")
			(net "P5E_CPU0_PE3_TX_DN<1>")
		)
		(pad "EB87" smd circle
			(at 34.169604 20.495514 270)
			(size 0.4318 0.4318)
			(layers "F.Cu" "F.Mask" "F.Paste")
			(net "GND")
		)
		(pad "EB89" smd circle
			(at 35.797236 20.495514 270)
			(size 0.4318 0.4318)
			(layers "F.Cu" "F.Mask" "F.Paste")
			(net "P5E_CPU0_PE3_RX_DP<2>")
		)
		(pad "EB91" smd oval
			(at 37.425122 20.495514)
			(size 0.381 0.4826)
			(drill
				(offset 0 -0.0508)
			)
			(layers "F.Cu" "F.Mask" "F.Paste")
			(net "GND")
		)
		(pad "EC1" smd oval
			(at -37.425122 20.855686 180)
			(size 0.381 0.4826)
			(drill
				(offset 0 -0.0508)
			)
			(layers "F.Cu" "F.Mask" "F.Paste")
			(net "GND")
		)
		(pad "EC3" smd circle
			(at -35.797236 20.855686 270)
			(size 0.4318 0.4318)
			(layers "F.Cu" "F.Mask" "F.Paste")
			(net "UPI_CPU1_CPU0_P0P1_DN<2>")
		)
		(pad "EC5" smd circle
			(at -34.169604 20.855686 270)
			(size 0.4318 0.4318)
			(layers "F.Cu" "F.Mask" "F.Paste")
			(net "GND")
		)
		(pad "EC7" smd circle
			(at -32.541718 20.855686 270)
			(size 0.4318 0.4318)
			(layers "F.Cu" "F.Mask" "F.Paste")
			(net "UPI_CPU0_CPU1_P1P0_DN<1>")
		)
		(pad "EC9" smd circle
			(at -30.914086 20.855686 270)
			(size 0.4318 0.4318)
			(layers "F.Cu" "F.Mask" "F.Paste")
			(net "GND")
		)
		(pad "EC11" smd circle
			(at -29.2862 20.855686 270)
			(size 0.4318 0.4318)
			(layers "F.Cu" "F.Mask" "F.Paste")
			(net "P5E_CPU0_PE2_RX_DP<13>")
		)
		(pad "EC13" smd circle
			(at -27.658314 20.855686 270)
			(size 0.4318 0.4318)
			(layers "F.Cu" "F.Mask" "F.Paste")
			(net "GND")
		)
		(pad "EC15" smd circle
			(at -26.030682 20.855686 270)
			(size 0.4318 0.4318)
			(layers "F.Cu" "F.Mask" "F.Paste")
			(net "P5E_CPU0_PE2_TX_DP<13>")
		)
		(pad "EC17" smd circle
			(at -24.402796 20.855686 270)
			(size 0.4318 0.4318)
			(layers "F.Cu" "F.Mask" "F.Paste")
			(net "M_F_CPU0_SB_DQ<30>")
		)
		(pad "EC19" smd circle
			(at -22.77491 20.855686 270)
			(size 0.4318 0.4318)
			(layers "F.Cu" "F.Mask" "F.Paste")
			(net "GND")
		)
		(pad "EC21" smd circle
			(at -21.147278 20.855686 270)
			(size 0.4318 0.4318)
			(layers "F.Cu" "F.Mask" "F.Paste")
			(net "M_F_CPU0_SB_DQS_DP<1>")
		)
		(pad "EC23" smd circle
			(at -19.519392 20.855686 270)
			(size 0.4318 0.4318)
			(layers "F.Cu" "F.Mask" "F.Paste")
			(net "GND")
		)
		(pad "EC25" smd circle
			(at -17.89176 20.855686 270)
			(size 0.4318 0.4318)
			(layers "F.Cu" "F.Mask" "F.Paste")
			(net "GND")
		)
		(pad "EC27" smd circle
			(at -16.263874 20.855686 270)
			(size 0.4318 0.4318)
			(layers "F.Cu" "F.Mask" "F.Paste")
			(net "M_E_CPU0_SB_DQS_DP<0>")
		)
		(pad "EC29" smd circle
			(at -14.635988 20.855686 270)
			(size 0.4318 0.4318)
			(layers "F.Cu" "F.Mask" "F.Paste")
			(net "GND")
		)
		(pad "EC31" smd circle
			(at -13.008356 20.855686 270)
			(size 0.4318 0.4318)
			(layers "F.Cu" "F.Mask" "F.Paste")
			(net "GND")
		)
		(pad "EC33" smd circle
			(at -11.380724 20.855686 270)
			(size 0.4318 0.4318)
			(layers "F.Cu" "F.Mask" "F.Paste")
			(net "M_F_CPU0_SB_DQS_DP<9>")
		)
		(pad "EC35" smd circle
			(at -9.752838 20.855686 270)
			(size 0.4318 0.4318)
			(layers "F.Cu" "F.Mask" "F.Paste")
			(net "GND")
		)
		(pad "EC37" smd circle
			(at -8.124952 20.855686 270)
			(size 0.4318 0.4318)
			(layers "F.Cu" "F.Mask" "F.Paste")
			(net "GND")
		)
		(pad "EC39" smd circle
			(at -6.49732 20.855686 270)
			(size 0.4318 0.4318)
			(layers "F.Cu" "F.Mask" "F.Paste")
			(net "M_F_CPU0_SB_CA<6>")
		)
		(pad "EC41" smd circle
			(at -4.869434 20.855686 270)
			(size 0.4318 0.4318)
			(layers "F.Cu" "F.Mask" "F.Paste")
			(net "GND")
		)
		(pad "EC43" smd circle
			(at -3.241802 20.855686 270)
			(size 0.4318 0.4318)
			(layers "F.Cu" "F.Mask" "F.Paste")
			(net "GND")
		)
		(pad "EC45" smd circle
			(at -1.613916 20.855686 270)
			(size 0.4318 0.4318)
			(layers "F.Cu" "F.Mask" "F.Paste")
			(net "M_E_CPU0_CLK_DP<1>")
		)
		(pad "EC48" smd circle
			(at 2.427732 20.965668 270)
			(size 0.4318 0.4318)
			(layers "F.Cu" "F.Mask" "F.Paste")
			(net "GND")
		)
		(pad "EC50" smd circle
			(at 4.055618 20.965668 270)
			(size 0.4318 0.4318)
			(layers "F.Cu" "F.Mask" "F.Paste")
			(net "GND")
		)
		(pad "EC52" smd circle
			(at 5.68325 20.965668 270)
			(size 0.4318 0.4318)
			(layers "F.Cu" "F.Mask" "F.Paste")
			(net "M_F_CPU0_SA_CA<0>")
		)
		(pad "EC54" smd circle
			(at 7.311136 20.965668 270)
			(size 0.4318 0.4318)
			(layers "F.Cu" "F.Mask" "F.Paste")
			(net "GND")
		)
		(pad "EC56" smd circle
			(at 8.939022 20.965668 270)
			(size 0.4318 0.4318)
			(layers "F.Cu" "F.Mask" "F.Paste")
			(net "GND")
		)
		(pad "EC58" smd circle
			(at 10.566654 20.965668 270)
			(size 0.4318 0.4318)
			(layers "F.Cu" "F.Mask" "F.Paste")
			(net "M_F_CPU0_SA_DQS_DP<4>")
		)
		(pad "EC60" smd circle
			(at 12.19454 20.965668 270)
			(size 0.4318 0.4318)
			(layers "F.Cu" "F.Mask" "F.Paste")
			(net "GND")
		)
		(pad "EC62" smd circle
			(at 13.822426 20.965668 270)
			(size 0.4318 0.4318)
			(layers "F.Cu" "F.Mask" "F.Paste")
			(net "GND")
		)
		(pad "EC64" smd circle
			(at 15.450058 20.965668 270)
			(size 0.4318 0.4318)
			(layers "F.Cu" "F.Mask" "F.Paste")
			(net "M_F_CPU0_SA_DQS_DN<2>")
		)
		(pad "EC66" smd circle
			(at 17.07769 20.965668 270)
			(size 0.4318 0.4318)
			(layers "F.Cu" "F.Mask" "F.Paste")
			(net "GND")
		)
		(pad "EC68" smd circle
			(at 18.705576 20.965668 270)
			(size 0.4318 0.4318)
			(layers "F.Cu" "F.Mask" "F.Paste")
			(net "GND")
		)
		(pad "EC70" smd circle
			(at 20.333462 20.965668 270)
			(size 0.4318 0.4318)
			(layers "F.Cu" "F.Mask" "F.Paste")
			(net "M_E_CPU0_SA_DQS_DN<1>")
		)
		(pad "EC72" smd circle
			(at 21.961094 20.965668 270)
			(size 0.4318 0.4318)
			(layers "F.Cu" "F.Mask" "F.Paste")
			(net "GND")
		)
		(pad "EC74" smd circle
			(at 23.58898 20.965668 270)
			(size 0.4318 0.4318)
			(layers "F.Cu" "F.Mask" "F.Paste")
			(net "GND")
		)
		(pad "EC76" smd circle
			(at 25.216612 20.965668 270)
			(size 0.4318 0.4318)
			(layers "F.Cu" "F.Mask" "F.Paste")
			(net "M_F_CPU0_SA_DQS_DP<0>")
		)
		(pad "EC78" smd circle
			(at 26.844498 20.965668 270)
			(size 0.4318 0.4318)
			(layers "F.Cu" "F.Mask" "F.Paste")
			(net "PVCCFA_EHV_FIVRA_CPU0")
		)
		(pad "EC80" smd circle
			(at 28.472384 20.965668 270)
			(size 0.4318 0.4318)
			(layers "F.Cu" "F.Mask" "F.Paste")
			(net "GND")
		)
		(pad "EC82" smd circle
			(at 30.100016 20.965668 270)
			(size 0.4318 0.4318)
			(layers "F.Cu" "F.Mask" "F.Paste")
			(net "GND")
		)
		(pad "EC84" smd circle
			(at 31.727902 20.965668 270)
			(size 0.4318 0.4318)
			(layers "F.Cu" "F.Mask" "F.Paste")
			(net "GND")
		)
		(pad "EC86" smd circle
			(at 33.355534 20.965668 270)
			(size 0.4318 0.4318)
			(layers "F.Cu" "F.Mask" "F.Paste")
			(net "P5E_CPU0_PE3_TX_DP<1>")
		)
		(pad "EC88" smd circle
			(at 34.98342 20.965668 270)
			(size 0.4318 0.4318)
			(layers "F.Cu" "F.Mask" "F.Paste")
			(net "GND")
		)
		(pad "EC90" smd circle
			(at 36.611306 20.965668 270)
			(size 0.4318 0.4318)
			(layers "F.Cu" "F.Mask" "F.Paste")
			(net "P5E_CPU0_PE3_RX_DN<2>")
		)
		(pad "ED2" smd oval
			(at -36.611306 21.325332 180)
			(size 0.381 0.4826)
			(drill
				(offset 0 -0.0508)
			)
			(layers "F.Cu" "F.Mask" "F.Paste")
			(net "UPI_CPU1_CPU0_P0P1_DP<2>")
		)
		(pad "ED4" smd circle
			(at -34.98342 21.325332 270)
			(size 0.4318 0.4318)
			(layers "F.Cu" "F.Mask" "F.Paste")
			(net "GND")
		)
		(pad "ED6" smd circle
			(at -33.355534 21.325332 270)
			(size 0.4318 0.4318)
			(layers "F.Cu" "F.Mask" "F.Paste")
			(net "UPI_CPU0_CPU1_P1P0_DP<1>")
		)
		(pad "ED8" smd circle
			(at -31.727902 21.325332 270)
			(size 0.4318 0.4318)
			(layers "F.Cu" "F.Mask" "F.Paste")
			(net "GND")
		)
		(pad "ED10" smd circle
			(at -30.100016 21.325332 270)
			(size 0.4318 0.4318)
			(layers "F.Cu" "F.Mask" "F.Paste")
			(net "P5E_CPU0_PE2_RX_DN<13>")
		)
		(pad "ED12" smd circle
			(at -28.472384 21.325332 270)
			(size 0.4318 0.4318)
			(layers "F.Cu" "F.Mask" "F.Paste")
			(net "GND")
		)
		(pad "ED14" smd circle
			(at -26.844498 21.325332 270)
			(size 0.4318 0.4318)
			(layers "F.Cu" "F.Mask" "F.Paste")
			(net "P5E_CPU0_PE2_TX_DP<14>")
		)
		(pad "ED16" smd circle
			(at -25.216612 21.325332 270)
			(size 0.4318 0.4318)
			(layers "F.Cu" "F.Mask" "F.Paste")
			(net "GND")
		)
		(pad "ED18" smd circle
			(at -23.58898 21.325332 270)
			(size 0.4318 0.4318)
			(layers "F.Cu" "F.Mask" "F.Paste")
			(net "GND")
		)
		(pad "ED20" smd circle
			(at -21.961094 21.325332 270)
			(size 0.4318 0.4318)
			(layers "F.Cu" "F.Mask" "F.Paste")
			(net "M_F_CPU0_SB_DQ<12>")
		)
		(pad "ED22" smd circle
			(at -20.333462 21.325332 270)
			(size 0.4318 0.4318)
			(layers "F.Cu" "F.Mask" "F.Paste")
			(net "M_F_CPU0_SB_DQ<9>")
		)
		(pad "ED24" smd circle
			(at -18.705576 21.325332 270)
			(size 0.4318 0.4318)
			(layers "F.Cu" "F.Mask" "F.Paste")
			(net "GND")
		)
		(pad "ED26" smd circle
			(at -17.07769 21.325332 270)
			(size 0.4318 0.4318)
			(layers "F.Cu" "F.Mask" "F.Paste")
			(net "M_E_CPU0_SB_DQ<4>")
		)
		(pad "ED28" smd circle
			(at -15.450058 21.325332 270)
			(size 0.4318 0.4318)
			(layers "F.Cu" "F.Mask" "F.Paste")
			(net "M_E_CPU0_SB_DQ<1>")
		)
		(pad "ED30" smd circle
			(at -13.822426 21.325332 270)
			(size 0.4318 0.4318)
			(layers "F.Cu" "F.Mask" "F.Paste")
			(net "GND")
		)
		(pad "ED32" smd circle
			(at -12.19454 21.325332 270)
			(size 0.4318 0.4318)
			(layers "F.Cu" "F.Mask" "F.Paste")
			(net "M_F_CPU0_SB_CB<0>")
		)
		(pad "ED34" smd circle
			(at -10.566654 21.325332 270)
			(size 0.4318 0.4318)
			(layers "F.Cu" "F.Mask" "F.Paste")
			(net "M_F_CPU0_SB_CB<5>")
		)
		(pad "ED36" smd circle
			(at -8.939022 21.325332 270)
			(size 0.4318 0.4318)
			(layers "F.Cu" "F.Mask" "F.Paste")
			(net "GND")
		)
		(pad "ED38" smd circle
			(at -7.311136 21.325332 270)
			(size 0.4318 0.4318)
			(layers "F.Cu" "F.Mask" "F.Paste")
			(net "M_F_CPU0_SB_CS_N<2>")
		)
		(pad "ED40" smd circle
			(at -5.68325 21.325332 270)
			(size 0.4318 0.4318)
			(layers "F.Cu" "F.Mask" "F.Paste")
			(net "M_F_CPU0_SB_CA<4>")
		)
		(pad "ED42" smd circle
			(at -4.055618 21.325332 270)
			(size 0.4318 0.4318)
			(layers "F.Cu" "F.Mask" "F.Paste")
			(net "GND")
		)
		(pad "ED44" smd circle
			(at -2.427732 21.325332 270)
			(size 0.4318 0.4318)
			(layers "F.Cu" "F.Mask" "F.Paste")
			(net "M_E_CPU0_SA_CA<6>")
		)
		(pad "ED47" smd circle
			(at 1.613916 21.435314 270)
			(size 0.4318 0.4318)
			(layers "F.Cu" "F.Mask" "F.Paste")
			(net "M_H_CPU0_SB_RSP<1>")
		)
		(pad "ED49" smd circle
			(at 3.241802 21.435314 270)
			(size 0.4318 0.4318)
			(layers "F.Cu" "F.Mask" "F.Paste")
			(net "GND")
		)
		(pad "ED51" smd circle
			(at 4.869434 21.435314 270)
			(size 0.4318 0.4318)
			(layers "F.Cu" "F.Mask" "F.Paste")
			(net "M_F_CPU0_SA_CA<2>")
		)
		(pad "ED53" smd circle
			(at 6.49732 21.435314 270)
			(size 0.4318 0.4318)
			(layers "F.Cu" "F.Mask" "F.Paste")
			(net "M_F_CPU0_SA_CS_N<3>")
		)
		(pad "ED55" smd circle
			(at 8.124952 21.435314 270)
			(size 0.4318 0.4318)
			(layers "F.Cu" "F.Mask" "F.Paste")
			(net "GND")
		)
		(pad "ED57" smd circle
			(at 9.752838 21.435314 270)
			(size 0.4318 0.4318)
			(layers "F.Cu" "F.Mask" "F.Paste")
			(net "M_F_CPU0_SA_CB<4>")
		)
		(pad "ED59" smd circle
			(at 11.380724 21.435314 270)
			(size 0.4318 0.4318)
			(layers "F.Cu" "F.Mask" "F.Paste")
			(net "M_F_CPU0_SA_CB<1>")
		)
		(pad "ED61" smd circle
			(at 13.008356 21.435314 270)
			(size 0.4318 0.4318)
			(layers "F.Cu" "F.Mask" "F.Paste")
			(net "GND")
		)
		(pad "ED63" smd circle
			(at 14.635988 21.435314 270)
			(size 0.4318 0.4318)
			(layers "F.Cu" "F.Mask" "F.Paste")
			(net "M_F_CPU0_SA_DQ<20>")
		)
		(pad "ED65" smd circle
			(at 16.263874 21.435314 270)
			(size 0.4318 0.4318)
			(layers "F.Cu" "F.Mask" "F.Paste")
			(net "M_F_CPU0_SA_DQ<17>")
		)
		(pad "ED67" smd circle
			(at 17.89176 21.435314 270)
			(size 0.4318 0.4318)
			(layers "F.Cu" "F.Mask" "F.Paste")
			(net "GND")
		)
		(pad "ED69" smd circle
			(at 19.519392 21.435314 270)
			(size 0.4318 0.4318)
			(layers "F.Cu" "F.Mask" "F.Paste")
			(net "M_E_CPU0_SA_DQ<12>")
		)
		(pad "ED71" smd circle
			(at 21.147278 21.435314 270)
			(size 0.4318 0.4318)
			(layers "F.Cu" "F.Mask" "F.Paste")
			(net "M_E_CPU0_SA_DQ<9>")
		)
		(pad "ED73" smd circle
			(at 22.77491 21.435314 270)
			(size 0.4318 0.4318)
			(layers "F.Cu" "F.Mask" "F.Paste")
			(net "GND")
		)
		(pad "ED75" smd circle
			(at 24.402796 21.435314 270)
			(size 0.4318 0.4318)
			(layers "F.Cu" "F.Mask" "F.Paste")
			(net "M_F_CPU0_SA_DQ<4>")
		)
		(pad "ED77" smd circle
			(at 26.030682 21.435314 270)
			(size 0.4318 0.4318)
			(layers "F.Cu" "F.Mask" "F.Paste")
			(net "M_F_CPU0_SA_DQ<2>")
		)
		(pad "ED79" smd circle
			(at 27.658314 21.435314 270)
			(size 0.4318 0.4318)
			(layers "F.Cu" "F.Mask" "F.Paste")
			(net "PVCCFA_EHV_FIVRA_CPU0")
		)
		(pad "ED81" smd circle
			(at 29.2862 21.435314 270)
			(size 0.4318 0.4318)
			(layers "F.Cu" "F.Mask" "F.Paste")
			(net "GND")
		)
		(pad "ED83" smd circle
			(at 30.914086 21.435314 270)
			(size 0.4318 0.4318)
			(layers "F.Cu" "F.Mask" "F.Paste")
			(net "GND")
		)
		(pad "ED85" smd circle
			(at 32.541718 21.435314 270)
			(size 0.4318 0.4318)
			(layers "F.Cu" "F.Mask" "F.Paste")
			(net "PVCCFA_EHV_FIVRA_CPU0")
		)
		(pad "ED87" smd circle
			(at 34.169604 21.435314 270)
			(size 0.4318 0.4318)
			(layers "F.Cu" "F.Mask" "F.Paste")
			(net "P5E_CPU0_PE3_TX_DP<0>")
		)
		(pad "ED89" smd circle
			(at 35.797236 21.435314 270)
			(size 0.4318 0.4318)
			(layers "F.Cu" "F.Mask" "F.Paste")
			(net "PVCCFA_EHV_FIVRA_CPU0")
		)
		(pad "ED91" smd oval
			(at 37.425122 21.435314)
			(size 0.381 0.4826)
			(drill
				(offset 0 -0.0508)
			)
			(layers "F.Cu" "F.Mask" "F.Paste")
			(net "P5E_CPU0_PE3_RX_DN<1>")
		)
		(pad "EE3" smd circle
			(at -35.797236 21.795486 270)
			(size 0.4318 0.4318)
			(layers "F.Cu" "F.Mask" "F.Paste")
			(net "UPI_CPU1_CPU0_P0P1_DN<1>")
		)
		(pad "EE5" smd circle
			(at -34.169604 21.795486 270)
			(size 0.4318 0.4318)
			(layers "F.Cu" "F.Mask" "F.Paste")
			(net "UPI_CPU0_CPU1_P1P0_DP<0>")
		)
		(pad "EE7" smd circle
			(at -32.541718 21.795486 270)
			(size 0.4318 0.4318)
			(layers "F.Cu" "F.Mask" "F.Paste")
			(net "PVCCFA_EHV_FIVRA_CPU0")
		)
		(pad "EE9" smd circle
			(at -30.914086 21.795486 270)
			(size 0.4318 0.4318)
			(layers "F.Cu" "F.Mask" "F.Paste")
			(net "P5E_CPU0_PE2_RX_DN<14>")
		)
		(pad "EE11" smd circle
			(at -29.2862 21.795486 270)
			(size 0.4318 0.4318)
			(layers "F.Cu" "F.Mask" "F.Paste")
			(net "PVCCFA_EHV_FIVRA_CPU0")
		)
		(pad "EE13" smd circle
			(at -27.658314 21.795486 270)
			(size 0.4318 0.4318)
			(layers "F.Cu" "F.Mask" "F.Paste")
			(net "P5E_CPU0_PE2_TX_DN<14>")
		)
		(pad "EE15" smd circle
			(at -26.030682 21.795486 270)
			(size 0.4318 0.4318)
			(layers "F.Cu" "F.Mask" "F.Paste")
			(net "PVCCFA_EHV_FIVRA_CPU0")
		)
		(pad "EE17" smd circle
			(at -24.402796 21.795486 270)
			(size 0.4318 0.4318)
			(layers "F.Cu" "F.Mask" "F.Paste")
			(net "GND")
		)
		(pad "EE19" smd circle
			(at -22.77491 21.795486 270)
			(size 0.4318 0.4318)
			(layers "F.Cu" "F.Mask" "F.Paste")
			(net "M_F_CPU0_SB_DQ<13>")
		)
		(pad "EE21" smd circle
			(at -21.147278 21.795486 270)
			(size 0.4318 0.4318)
			(layers "F.Cu" "F.Mask" "F.Paste")
			(net "M_F_CPU0_SB_DQS_DN<1>")
		)
		(pad "EE23" smd circle
			(at -19.519392 21.795486 270)
			(size 0.4318 0.4318)
			(layers "F.Cu" "F.Mask" "F.Paste")
			(net "M_F_CPU0_SB_DQ<8>")
		)
		(pad "EE25" smd circle
			(at -17.89176 21.795486 270)
			(size 0.4318 0.4318)
			(layers "F.Cu" "F.Mask" "F.Paste")
			(net "M_E_CPU0_SB_DQ<5>")
		)
		(pad "EE27" smd circle
			(at -16.263874 21.795486 270)
			(size 0.4318 0.4318)
			(layers "F.Cu" "F.Mask" "F.Paste")
			(net "M_E_CPU0_SB_DQS_DN<0>")
		)
		(pad "EE29" smd circle
			(at -14.635988 21.795486 270)
			(size 0.4318 0.4318)
			(layers "F.Cu" "F.Mask" "F.Paste")
			(net "M_E_CPU0_SB_DQ<0>")
		)
		(pad "EE31" smd circle
			(at -13.008356 21.795486 270)
			(size 0.4318 0.4318)
			(layers "F.Cu" "F.Mask" "F.Paste")
			(net "M_F_CPU0_SB_CB<1>")
		)
		(pad "EE33" smd circle
			(at -11.380724 21.795486 270)
			(size 0.4318 0.4318)
			(layers "F.Cu" "F.Mask" "F.Paste")
			(net "M_F_CPU0_SB_DQS_DN<9>")
		)
		(pad "EE35" smd circle
			(at -9.752838 21.795486 270)
			(size 0.4318 0.4318)
			(layers "F.Cu" "F.Mask" "F.Paste")
			(net "M_F_CPU0_SB_CB<4>")
		)
		(pad "EE37" smd circle
			(at -8.124952 21.795486 270)
			(size 0.4318 0.4318)
			(layers "F.Cu" "F.Mask" "F.Paste")
			(net "M_F_CPU0_SB_CS_N<3>")
		)
		(pad "EE39" smd circle
			(at -6.49732 21.795486 270)
			(size 0.4318 0.4318)
			(layers "F.Cu" "F.Mask" "F.Paste")
			(net "GND")
		)
		(pad "EE41" smd circle
			(at -4.869434 21.795486 270)
			(size 0.4318 0.4318)
			(layers "F.Cu" "F.Mask" "F.Paste")
			(net "M_F_CPU0_SB_CA<2>")
		)
		(pad "EE43" smd circle
			(at -3.241802 21.795486 270)
			(size 0.4318 0.4318)
			(layers "F.Cu" "F.Mask" "F.Paste")
			(net "M_E_CPU0_SA_PAR")
		)
		(pad "EE45" smd circle
			(at -1.613916 21.795486 270)
			(size 0.4318 0.4318)
			(layers "F.Cu" "F.Mask" "F.Paste")
			(net "M_E_CPU0_CLK_DN<1>")
		)
		(pad "EE48" smd circle
			(at 2.427732 21.905468 270)
			(size 0.4318 0.4318)
			(layers "F.Cu" "F.Mask" "F.Paste")
			(net "M_H_CPU0_SB_RSP<0>")
		)
		(pad "EE50" smd circle
			(at 4.055618 21.905468 270)
			(size 0.4318 0.4318)
			(layers "F.Cu" "F.Mask" "F.Paste")
			(net "M_F_CPU0_SA_CA<4>")
		)
		(pad "EE52" smd circle
			(at 5.68325 21.905468 270)
			(size 0.4318 0.4318)
			(layers "F.Cu" "F.Mask" "F.Paste")
			(net "GND")
		)
		(pad "EE54" smd circle
			(at 7.311136 21.905468 270)
			(size 0.4318 0.4318)
			(layers "F.Cu" "F.Mask" "F.Paste")
			(net "M_F_CPU0_SA_CS_N<2>")
		)
		(pad "EE56" smd circle
			(at 8.939022 21.905468 270)
			(size 0.4318 0.4318)
			(layers "F.Cu" "F.Mask" "F.Paste")
			(net "M_F_CPU0_SA_CB<5>")
		)
		(pad "EE58" smd circle
			(at 10.566654 21.905468 270)
			(size 0.4318 0.4318)
			(layers "F.Cu" "F.Mask" "F.Paste")
			(net "M_F_CPU0_SA_DQS_DN<4>")
		)
		(pad "EE60" smd circle
			(at 12.19454 21.905468 270)
			(size 0.4318 0.4318)
			(layers "F.Cu" "F.Mask" "F.Paste")
			(net "M_F_CPU0_SA_CB<0>")
		)
		(pad "EE62" smd circle
			(at 13.822426 21.905468 270)
			(size 0.4318 0.4318)
			(layers "F.Cu" "F.Mask" "F.Paste")
			(net "M_F_CPU0_SA_DQ<21>")
		)
		(pad "EE64" smd circle
			(at 15.450058 21.905468 270)
			(size 0.4318 0.4318)
			(layers "F.Cu" "F.Mask" "F.Paste")
			(net "M_F_CPU0_SA_DQS_DP<2>")
		)
		(pad "EE66" smd circle
			(at 17.07769 21.905468 270)
			(size 0.4318 0.4318)
			(layers "F.Cu" "F.Mask" "F.Paste")
			(net "M_F_CPU0_SA_DQ<16>")
		)
		(pad "EE68" smd circle
			(at 18.705576 21.905468 270)
			(size 0.4318 0.4318)
			(layers "F.Cu" "F.Mask" "F.Paste")
			(net "M_E_CPU0_SA_DQ<13>")
		)
		(pad "EE70" smd circle
			(at 20.333462 21.905468 270)
			(size 0.4318 0.4318)
			(layers "F.Cu" "F.Mask" "F.Paste")
			(net "M_E_CPU0_SA_DQS_DP<1>")
		)
		(pad "EE72" smd circle
			(at 21.961094 21.905468 270)
			(size 0.4318 0.4318)
			(layers "F.Cu" "F.Mask" "F.Paste")
			(net "M_E_CPU0_SA_DQ<8>")
		)
		(pad "EE74" smd circle
			(at 23.58898 21.905468 270)
			(size 0.4318 0.4318)
			(layers "F.Cu" "F.Mask" "F.Paste")
			(net "M_F_CPU0_SA_DQ<5>")
		)
		(pad "EE76" smd circle
			(at 25.216612 21.905468 270)
			(size 0.4318 0.4318)
			(layers "F.Cu" "F.Mask" "F.Paste")
			(net "M_F_CPU0_SA_DQS_DN<0>")
		)
		(pad "EE78" smd circle
			(at 26.844498 21.905468 270)
			(size 0.4318 0.4318)
			(layers "F.Cu" "F.Mask" "F.Paste")
			(net "GND")
		)
		(pad "EE80" smd circle
			(at 28.472384 21.905468 270)
			(size 0.4318 0.4318)
			(layers "F.Cu" "F.Mask" "F.Paste")
			(net "GND")
		)
		(pad "EE82" smd circle
			(at 30.100016 21.905468 270)
			(size 0.4318 0.4318)
			(layers "F.Cu" "F.Mask" "F.Paste")
			(net "GND")
		)
		(pad "EE84" smd circle
			(at 31.727902 21.905468 270)
			(size 0.4318 0.4318)
			(layers "F.Cu" "F.Mask" "F.Paste")
			(net "PVCCFA_EHV_FIVRA_CPU0")
		)
		(pad "EE86" smd circle
			(at 33.355534 21.905468 270)
			(size 0.4318 0.4318)
			(layers "F.Cu" "F.Mask" "F.Paste")
			(net "P5E_CPU0_PE3_TX_DN<0>")
		)
		(pad "EE88" smd circle
			(at 34.98342 21.905468 270)
			(size 0.4318 0.4318)
			(layers "F.Cu" "F.Mask" "F.Paste")
			(net "GND")
		)
		(pad "EE90" smd oval
			(at 36.611306 21.905468)
			(size 0.381 0.4826)
			(drill
				(offset 0 -0.0508)
			)
			(layers "F.Cu" "F.Mask" "F.Paste")
			(net "P5E_CPU0_PE3_RX_DP<1>")
		)
		(pad "EF2" smd oval
			(at -36.611306 22.265386 180)
			(size 0.381 0.4826)
			(drill
				(offset 0 -0.0508)
			)
			(layers "F.Cu" "F.Mask" "F.Paste")
			(net "GND")
		)
		(pad "EF4" smd circle
			(at -34.98342 22.265386 270)
			(size 0.4318 0.4318)
			(layers "F.Cu" "F.Mask" "F.Paste")
			(net "GND")
		)
		(pad "EF6" smd circle
			(at -33.355534 22.265386 270)
			(size 0.4318 0.4318)
			(layers "F.Cu" "F.Mask" "F.Paste")
			(net "UPI_CPU0_CPU1_P1P0_DN<0>")
		)
		(pad "EF8" smd circle
			(at -31.727902 22.265386 270)
			(size 0.4318 0.4318)
			(layers "F.Cu" "F.Mask" "F.Paste")
			(net "GND")
		)
		(pad "EF10" smd circle
			(at -30.100016 22.265386 270)
			(size 0.4318 0.4318)
			(layers "F.Cu" "F.Mask" "F.Paste")
			(net "P5E_CPU0_PE2_RX_DP<14>")
		)
		(pad "EF12" smd circle
			(at -28.472384 22.265386 270)
			(size 0.4318 0.4318)
			(layers "F.Cu" "F.Mask" "F.Paste")
			(net "GND")
		)
		(pad "EF14" smd circle
			(at -26.844498 22.265386 270)
			(size 0.4318 0.4318)
			(layers "F.Cu" "F.Mask" "F.Paste")
			(net "P5E_CPU0_PE2_TX_DN<15>")
		)
		(pad "EF16" smd circle
			(at -25.216612 22.265386 270)
			(size 0.4318 0.4318)
			(layers "F.Cu" "F.Mask" "F.Paste")
			(net "GND")
		)
		(pad "EF18" smd circle
			(at -23.58898 22.265386 270)
			(size 0.4318 0.4318)
			(layers "F.Cu" "F.Mask" "F.Paste")
			(net "GND")
		)
		(pad "EF20" smd circle
			(at -21.961094 22.265386 270)
			(size 0.4318 0.4318)
			(layers "F.Cu" "F.Mask" "F.Paste")
			(net "GND")
		)
		(pad "EF22" smd circle
			(at -20.333462 22.265386 270)
			(size 0.4318 0.4318)
			(layers "F.Cu" "F.Mask" "F.Paste")
			(net "GND")
		)
		(pad "EF24" smd circle
			(at -18.705576 22.265386 270)
			(size 0.4318 0.4318)
			(layers "F.Cu" "F.Mask" "F.Paste")
			(net "GND")
		)
		(pad "EF26" smd circle
			(at -17.07769 22.265386 270)
			(size 0.4318 0.4318)
			(layers "F.Cu" "F.Mask" "F.Paste")
			(net "GND")
		)
		(pad "EF28" smd circle
			(at -15.450058 22.265386 270)
			(size 0.4318 0.4318)
			(layers "F.Cu" "F.Mask" "F.Paste")
			(net "GND")
		)
		(pad "EF30" smd circle
			(at -13.822426 22.265386 270)
			(size 0.4318 0.4318)
			(layers "F.Cu" "F.Mask" "F.Paste")
			(net "GND")
		)
		(pad "EF32" smd circle
			(at -12.19454 22.265386 270)
			(size 0.4318 0.4318)
			(layers "F.Cu" "F.Mask" "F.Paste")
			(net "GND")
		)
		(pad "EF34" smd circle
			(at -10.566654 22.265386 270)
			(size 0.4318 0.4318)
			(layers "F.Cu" "F.Mask" "F.Paste")
			(net "GND")
		)
		(pad "EF36" smd circle
			(at -8.939022 22.265386 270)
			(size 0.4318 0.4318)
			(layers "F.Cu" "F.Mask" "F.Paste")
			(net "GND")
		)
		(pad "EF38" smd circle
			(at -7.311136 22.265386 270)
			(size 0.4318 0.4318)
			(layers "F.Cu" "F.Mask" "F.Paste")
			(net "GND")
		)
		(pad "EF40" smd circle
			(at -5.68325 22.265386 270)
			(size 0.4318 0.4318)
			(layers "F.Cu" "F.Mask" "F.Paste")
			(net "GND")
		)
		(pad "EF42" smd circle
			(at -4.055618 22.265386 270)
			(size 0.4318 0.4318)
			(layers "F.Cu" "F.Mask" "F.Paste")
			(net "GND")
		)
		(pad "EF44" smd circle
			(at -2.427732 22.265386 270)
			(size 0.4318 0.4318)
			(layers "F.Cu" "F.Mask" "F.Paste")
			(net "GND")
		)
		(pad "EF47" smd circle
			(at 1.613916 22.375114 270)
			(size 0.4318 0.4318)
			(layers "F.Cu" "F.Mask" "F.Paste")
			(net "GND")
		)
		(pad "EF49" smd circle
			(at 3.241802 22.375114 270)
			(size 0.4318 0.4318)
			(layers "F.Cu" "F.Mask" "F.Paste")
			(net "GND")
		)
		(pad "EF51" smd circle
			(at 4.869434 22.375114 270)
			(size 0.4318 0.4318)
			(layers "F.Cu" "F.Mask" "F.Paste")
			(net "GND")
		)
		(pad "EF53" smd circle
			(at 6.49732 22.375114 270)
			(size 0.4318 0.4318)
			(layers "F.Cu" "F.Mask" "F.Paste")
			(net "GND")
		)
		(pad "EF55" smd circle
			(at 8.124952 22.375114 270)
			(size 0.4318 0.4318)
			(layers "F.Cu" "F.Mask" "F.Paste")
			(net "GND")
		)
		(pad "EF57" smd circle
			(at 9.752838 22.375114 270)
			(size 0.4318 0.4318)
			(layers "F.Cu" "F.Mask" "F.Paste")
			(net "GND")
		)
		(pad "EF59" smd circle
			(at 11.380724 22.375114 270)
			(size 0.4318 0.4318)
			(layers "F.Cu" "F.Mask" "F.Paste")
			(net "GND")
		)
		(pad "EF61" smd circle
			(at 13.008356 22.375114 270)
			(size 0.4318 0.4318)
			(layers "F.Cu" "F.Mask" "F.Paste")
			(net "GND")
		)
		(pad "EF63" smd circle
			(at 14.635988 22.375114 270)
			(size 0.4318 0.4318)
			(layers "F.Cu" "F.Mask" "F.Paste")
			(net "GND")
		)
		(pad "EF65" smd circle
			(at 16.263874 22.375114 270)
			(size 0.4318 0.4318)
			(layers "F.Cu" "F.Mask" "F.Paste")
			(net "GND")
		)
		(pad "EF67" smd circle
			(at 17.89176 22.375114 270)
			(size 0.4318 0.4318)
			(layers "F.Cu" "F.Mask" "F.Paste")
			(net "GND")
		)
		(pad "EF69" smd circle
			(at 19.519392 22.375114 270)
			(size 0.4318 0.4318)
			(layers "F.Cu" "F.Mask" "F.Paste")
			(net "GND")
		)
		(pad "EF71" smd circle
			(at 21.147278 22.375114 270)
			(size 0.4318 0.4318)
			(layers "F.Cu" "F.Mask" "F.Paste")
			(net "GND")
		)
		(pad "EF73" smd circle
			(at 22.77491 22.375114 270)
			(size 0.4318 0.4318)
			(layers "F.Cu" "F.Mask" "F.Paste")
			(net "GND")
		)
		(pad "EF75" smd circle
			(at 24.402796 22.375114 270)
			(size 0.4318 0.4318)
			(layers "F.Cu" "F.Mask" "F.Paste")
			(net "GND")
		)
		(pad "EF77" smd circle
			(at 26.030682 22.375114 270)
			(size 0.4318 0.4318)
			(layers "F.Cu" "F.Mask" "F.Paste")
			(net "GND")
		)
		(pad "EF79" smd circle
			(at 27.658314 22.375114 270)
			(size 0.4318 0.4318)
			(layers "F.Cu" "F.Mask" "F.Paste")
			(net "PVCCFA_EHV_FIVRA_CPU0")
		)
		(pad "EF81" smd circle
			(at 29.2862 22.375114 270)
			(size 0.4318 0.4318)
			(layers "F.Cu" "F.Mask" "F.Paste")
			(net "GND")
		)
		(pad "EF83" smd circle
			(at 30.914086 22.375114 270)
			(size 0.4318 0.4318)
			(layers "F.Cu" "F.Mask" "F.Paste")
			(net "GND")
		)
		(pad "EF85" smd circle
			(at 32.541718 22.375114 270)
			(size 0.4318 0.4318)
			(layers "F.Cu" "F.Mask" "F.Paste")
			(net "GND")
		)
		(pad "EF87" smd circle
			(at 34.169604 22.375114 270)
			(size 0.4318 0.4318)
			(layers "F.Cu" "F.Mask" "F.Paste")
			(net "GND")
		)
		(pad "EF89" smd circle
			(at 35.797236 22.375114 270)
			(size 0.4318 0.4318)
			(layers "F.Cu" "F.Mask" "F.Paste")
			(net "GND")
		)
		(pad "EG3" smd circle
			(at -35.797236 22.735286 270)
			(size 0.4318 0.4318)
			(layers "F.Cu" "F.Mask" "F.Paste")
			(net "UPI_CPU1_CPU0_P0P1_DP<1>")
		)
		(pad "EG5" smd circle
			(at -34.169604 22.735286 270)
			(size 0.4318 0.4318)
			(layers "F.Cu" "F.Mask" "F.Paste")
			(net "GND")
		)
		(pad "EG7" smd circle
			(at -32.541718 22.735286 270)
			(size 0.4318 0.4318)
			(layers "F.Cu" "F.Mask" "F.Paste")
			(net "GND")
		)
		(pad "EG9" smd circle
			(at -30.914086 22.735286 270)
			(size 0.4318 0.4318)
			(layers "F.Cu" "F.Mask" "F.Paste")
			(net "GND")
		)
		(pad "EG11" smd circle
			(at -29.2862 22.735286 270)
			(size 0.4318 0.4318)
			(layers "F.Cu" "F.Mask" "F.Paste")
			(net "P5E_CPU0_PE2_RX_DP<15>")
		)
		(pad "EG13" smd circle
			(at -27.658314 22.735286 270)
			(size 0.4318 0.4318)
			(layers "F.Cu" "F.Mask" "F.Paste")
			(net "GND")
		)
		(pad "EG15" smd circle
			(at -26.030682 22.735286 270)
			(size 0.4318 0.4318)
			(layers "F.Cu" "F.Mask" "F.Paste")
			(net "P5E_CPU0_PE2_TX_DP<15>")
		)
		(pad "EG17" smd circle
			(at -24.402796 22.735286 270)
			(size 0.4318 0.4318)
			(layers "F.Cu" "F.Mask" "F.Paste")
			(net "NC_CPU0_HBM0_VIEWDIG1")
		)
		(pad "EG19" smd circle
			(at -22.77491 22.735286 270)
			(size 0.4318 0.4318)
			(layers "F.Cu" "F.Mask" "F.Paste")
			(net "M_F_CPU0_SB_DQ<15>")
		)
		(pad "EG21" smd circle
			(at -21.147278 22.735286 270)
			(size 0.4318 0.4318)
			(layers "F.Cu" "F.Mask" "F.Paste")
			(net "M_F_CPU0_SB_DQS_DP<6>")
		)
		(pad "EG23" smd circle
			(at -19.519392 22.735286 270)
			(size 0.4318 0.4318)
			(layers "F.Cu" "F.Mask" "F.Paste")
			(net "M_F_CPU0_SB_DQ<10>")
		)
		(pad "EG25" smd circle
			(at -17.89176 22.735286 270)
			(size 0.4318 0.4318)
			(layers "F.Cu" "F.Mask" "F.Paste")
			(net "M_E_CPU0_SB_DQ<7>")
		)
		(pad "EG27" smd circle
			(at -16.263874 22.735286 270)
			(size 0.4318 0.4318)
			(layers "F.Cu" "F.Mask" "F.Paste")
			(net "M_E_CPU0_SB_DQS_DP<5>")
		)
		(pad "EG29" smd circle
			(at -14.635988 22.735286 270)
			(size 0.4318 0.4318)
			(layers "F.Cu" "F.Mask" "F.Paste")
			(net "M_E_CPU0_SB_DQ<2>")
		)
		(pad "EG31" smd circle
			(at -13.008356 22.735286 270)
			(size 0.4318 0.4318)
			(layers "F.Cu" "F.Mask" "F.Paste")
			(net "M_F_CPU0_SB_CB<3>")
		)
		(pad "EG33" smd circle
			(at -11.380724 22.735286 270)
			(size 0.4318 0.4318)
			(layers "F.Cu" "F.Mask" "F.Paste")
			(net "M_F_CPU0_SB_DQS_DP<4>")
		)
		(pad "EG35" smd circle
			(at -9.752838 22.735286 270)
			(size 0.4318 0.4318)
			(layers "F.Cu" "F.Mask" "F.Paste")
			(net "M_F_CPU0_SB_CB<6>")
		)
		(pad "EG37" smd circle
			(at -8.124952 22.735286 270)
			(size 0.4318 0.4318)
			(layers "F.Cu" "F.Mask" "F.Paste")
			(net "M_F_CPU0_SB_CS_N<1>")
		)
		(pad "EG39" smd circle
			(at -6.49732 22.735286 270)
			(size 0.4318 0.4318)
			(layers "F.Cu" "F.Mask" "F.Paste")
			(net "GND")
		)
		(pad "EG41" smd circle
			(at -4.869434 22.735286 270)
			(size 0.4318 0.4318)
			(layers "F.Cu" "F.Mask" "F.Paste")
			(net "M_F_CPU0_SB_CA<3>")
		)
		(pad "EG43" smd circle
			(at -3.241802 22.735286 270)
			(size 0.4318 0.4318)
			(layers "F.Cu" "F.Mask" "F.Paste")
			(net "M_E_CPU0_SB_CA<0>")
		)
		(pad "EG45" smd circle
			(at -1.613916 22.735286 270)
			(size 0.4318 0.4318)
			(layers "F.Cu" "F.Mask" "F.Paste")
			(net "M_E_CPU0_CLK_DP<0>")
		)
		(pad "EG48" smd circle
			(at 2.427732 22.845268 270)
			(size 0.4318 0.4318)
			(layers "F.Cu" "F.Mask" "F.Paste")
			(net "M_H_CPU0_SA_RSP<0>")
		)
		(pad "EG50" smd circle
			(at 4.055618 22.845268 270)
			(size 0.4318 0.4318)
			(layers "F.Cu" "F.Mask" "F.Paste")
			(net "M_F_CPU0_SA_CA<5>")
		)
		(pad "EG52" smd circle
			(at 5.68325 22.845268 270)
			(size 0.4318 0.4318)
			(layers "F.Cu" "F.Mask" "F.Paste")
			(net "GND")
		)
		(pad "EG54" smd circle
			(at 7.311136 22.845268 270)
			(size 0.4318 0.4318)
			(layers "F.Cu" "F.Mask" "F.Paste")
			(net "M_F_CPU0_SA_CS_N<0>")
		)
		(pad "EG56" smd circle
			(at 8.939022 22.845268 270)
			(size 0.4318 0.4318)
			(layers "F.Cu" "F.Mask" "F.Paste")
			(net "M_F_CPU0_SA_CB<7>")
		)
		(pad "EG58" smd circle
			(at 10.566654 22.845268 270)
			(size 0.4318 0.4318)
			(layers "F.Cu" "F.Mask" "F.Paste")
			(net "M_F_CPU0_SA_DQS_DP<9>")
		)
		(pad "EG60" smd circle
			(at 12.19454 22.845268 270)
			(size 0.4318 0.4318)
			(layers "F.Cu" "F.Mask" "F.Paste")
			(net "M_F_CPU0_SA_CB<2>")
		)
		(pad "EG62" smd circle
			(at 13.822426 22.845268 270)
			(size 0.4318 0.4318)
			(layers "F.Cu" "F.Mask" "F.Paste")
			(net "M_F_CPU0_SA_DQ<23>")
		)
		(pad "EG64" smd circle
			(at 15.450058 22.845268 270)
			(size 0.4318 0.4318)
			(layers "F.Cu" "F.Mask" "F.Paste")
			(net "M_F_CPU0_SA_DQS_DP<7>")
		)
		(pad "EG66" smd circle
			(at 17.07769 22.845268 270)
			(size 0.4318 0.4318)
			(layers "F.Cu" "F.Mask" "F.Paste")
			(net "M_F_CPU0_SA_DQ<18>")
		)
		(pad "EG68" smd circle
			(at 18.705576 22.845268 270)
			(size 0.4318 0.4318)
			(layers "F.Cu" "F.Mask" "F.Paste")
			(net "M_E_CPU0_SA_DQ<15>")
		)
		(pad "EG70" smd circle
			(at 20.333462 22.845268 270)
			(size 0.4318 0.4318)
			(layers "F.Cu" "F.Mask" "F.Paste")
			(net "M_E_CPU0_SA_DQS_DP<6>")
		)
		(pad "EG72" smd circle
			(at 21.961094 22.845268 270)
			(size 0.4318 0.4318)
			(layers "F.Cu" "F.Mask" "F.Paste")
			(net "M_E_CPU0_SA_DQ<10>")
		)
		(pad "EG74" smd circle
			(at 23.58898 22.845268 270)
			(size 0.4318 0.4318)
			(layers "F.Cu" "F.Mask" "F.Paste")
			(net "M_F_CPU0_SA_DQ<7>")
		)
		(pad "EG76" smd circle
			(at 25.216612 22.845268 270)
			(size 0.4318 0.4318)
			(layers "F.Cu" "F.Mask" "F.Paste")
			(net "M_F_CPU0_SA_DQS_DP<5>")
		)
		(pad "EG78" smd circle
			(at 26.844498 22.845268 270)
			(size 0.4318 0.4318)
			(layers "F.Cu" "F.Mask" "F.Paste")
			(net "M_F_CPU0_SA_DQ<3>")
		)
		(pad "EG80" smd circle
			(at 28.472384 22.845268 270)
			(size 0.4318 0.4318)
			(layers "F.Cu" "F.Mask" "F.Paste")
			(net "PVCCFA_EHV_FIVRA_CPU0")
		)
		(pad "EG82" smd circle
			(at 30.100016 22.845268 270)
			(size 0.4318 0.4318)
			(layers "F.Cu" "F.Mask" "F.Paste")
			(net "GND")
		)
		(pad "EG84" smd circle
			(at 31.727902 22.845268 270)
			(size 0.4318 0.4318)
			(layers "F.Cu" "F.Mask" "F.Paste")
			(net "GND")
		)
		(pad "EG86" smd circle
			(at 33.355534 22.845268 270)
			(size 0.4318 0.4318)
			(layers "F.Cu" "F.Mask" "F.Paste")
			(net "GND")
		)
		(pad "EG88" smd circle
			(at 34.98342 22.845268 270)
			(size 0.4318 0.4318)
			(layers "F.Cu" "F.Mask" "F.Paste")
			(net "GND")
		)
		(pad "EG90" smd oval
			(at 36.611306 22.845268 315)
			(size 0.381 0.4826)
			(drill
				(offset 0 -0.0508)
			)
			(layers "F.Cu" "F.Mask" "F.Paste")
			(net "GND")
		)
		(pad "EH2" smd oval
			(at -36.611306 23.204932 225)
			(size 0.381 0.4826)
			(drill
				(offset 0 -0.0508)
			)
			(layers "F.Cu" "F.Mask" "F.Paste")
			(net "UPI_CPU1_CPU0_P0P1_DN<0>")
		)
		(pad "EH4" smd circle
			(at -34.98342 23.204932 270)
			(size 0.4318 0.4318)
			(layers "F.Cu" "F.Mask" "F.Paste")
			(net "GND")
		)
		(pad "EH6" smd circle
			(at -33.355534 23.204932 270)
			(size 0.4318 0.4318)
			(layers "F.Cu" "F.Mask" "F.Paste")
			(net "GND")
		)
		(pad "EH8" smd circle
			(at -31.727902 23.204932 270)
			(size 0.4318 0.4318)
			(layers "F.Cu" "F.Mask" "F.Paste")
			(net "M_G_CPU0_SB_DQ<25>")
		)
		(pad "EH10" smd circle
			(at -30.100016 23.204932 270)
			(size 0.4318 0.4318)
			(layers "F.Cu" "F.Mask" "F.Paste")
			(net "P5E_CPU0_PE2_RX_DN<15>")
		)
		(pad "EH12" smd circle
			(at -28.472384 23.204932 270)
			(size 0.4318 0.4318)
			(layers "F.Cu" "F.Mask" "F.Paste")
			(net "GND")
		)
		(pad "EH14" smd circle
			(at -26.844498 23.204932 270)
			(size 0.4318 0.4318)
			(layers "F.Cu" "F.Mask" "F.Paste")
			(net "GND")
		)
		(pad "EH16" smd circle
			(at -25.216612 23.204932 270)
			(size 0.4318 0.4318)
			(layers "F.Cu" "F.Mask" "F.Paste")
			(net "GND")
		)
		(pad "EH18" smd circle
			(at -23.58898 23.204932 270)
			(size 0.4318 0.4318)
			(layers "F.Cu" "F.Mask" "F.Paste")
			(net "GND")
		)
		(pad "EH20" smd circle
			(at -21.961094 23.204932 270)
			(size 0.4318 0.4318)
			(layers "F.Cu" "F.Mask" "F.Paste")
			(net "M_F_CPU0_SB_DQ<14>")
		)
		(pad "EH22" smd circle
			(at -20.333462 23.204932 270)
			(size 0.4318 0.4318)
			(layers "F.Cu" "F.Mask" "F.Paste")
			(net "M_F_CPU0_SB_DQ<11>")
		)
		(pad "EH24" smd circle
			(at -18.705576 23.204932 270)
			(size 0.4318 0.4318)
			(layers "F.Cu" "F.Mask" "F.Paste")
			(net "GND")
		)
		(pad "EH26" smd circle
			(at -17.07769 23.204932 270)
			(size 0.4318 0.4318)
			(layers "F.Cu" "F.Mask" "F.Paste")
			(net "M_E_CPU0_SB_DQ<6>")
		)
		(pad "EH28" smd circle
			(at -15.450058 23.204932 270)
			(size 0.4318 0.4318)
			(layers "F.Cu" "F.Mask" "F.Paste")
			(net "M_E_CPU0_SB_DQ<3>")
		)
		(pad "EH30" smd circle
			(at -13.822426 23.204932 270)
			(size 0.4318 0.4318)
			(layers "F.Cu" "F.Mask" "F.Paste")
			(net "GND")
		)
		(pad "EH32" smd circle
			(at -12.19454 23.204932 270)
			(size 0.4318 0.4318)
			(layers "F.Cu" "F.Mask" "F.Paste")
			(net "M_F_CPU0_SB_CB<2>")
		)
		(pad "EH34" smd circle
			(at -10.566654 23.204932 270)
			(size 0.4318 0.4318)
			(layers "F.Cu" "F.Mask" "F.Paste")
			(net "M_F_CPU0_SB_CB<7>")
		)
		(pad "EH36" smd circle
			(at -8.939022 23.204932 270)
			(size 0.4318 0.4318)
			(layers "F.Cu" "F.Mask" "F.Paste")
			(net "GND")
		)
		(pad "EH38" smd circle
			(at -7.311136 23.204932 270)
			(size 0.4318 0.4318)
			(layers "F.Cu" "F.Mask" "F.Paste")
			(net "M_F_CPU0_SB_CS_N<0>")
		)
		(pad "EH40" smd circle
			(at -5.68325 23.204932 270)
			(size 0.4318 0.4318)
			(layers "F.Cu" "F.Mask" "F.Paste")
			(net "M_F_CPU0_SB_CA<5>")
		)
		(pad "EH42" smd circle
			(at -4.055618 23.204932 270)
			(size 0.4318 0.4318)
			(layers "F.Cu" "F.Mask" "F.Paste")
			(net "GND")
		)
		(pad "EH44" smd circle
			(at -2.427732 23.204932 270)
			(size 0.4318 0.4318)
			(layers "F.Cu" "F.Mask" "F.Paste")
			(net "M_E_CPU0_SB_CA<1>")
		)
		(pad "EH47" smd circle
			(at 1.613916 23.314914 270)
			(size 0.4318 0.4318)
			(layers "F.Cu" "F.Mask" "F.Paste")
			(net "M_H_CPU0_SA_RSP<1>")
		)
		(pad "EH49" smd circle
			(at 3.241802 23.314914 270)
			(size 0.4318 0.4318)
			(layers "F.Cu" "F.Mask" "F.Paste")
			(net "GND")
		)
		(pad "EH51" smd circle
			(at 4.869434 23.314914 270)
			(size 0.4318 0.4318)
			(layers "F.Cu" "F.Mask" "F.Paste")
			(net "M_F_CPU0_SA_CA<3>")
		)
		(pad "EH53" smd circle
			(at 6.49732 23.314914 270)
			(size 0.4318 0.4318)
			(layers "F.Cu" "F.Mask" "F.Paste")
			(net "M_F_CPU0_SA_CS_N<1>")
		)
		(pad "EH55" smd circle
			(at 8.124952 23.314914 270)
			(size 0.4318 0.4318)
			(layers "F.Cu" "F.Mask" "F.Paste")
			(net "GND")
		)
		(pad "EH57" smd circle
			(at 9.752838 23.314914 270)
			(size 0.4318 0.4318)
			(layers "F.Cu" "F.Mask" "F.Paste")
			(net "M_F_CPU0_SA_CB<6>")
		)
		(pad "EH59" smd circle
			(at 11.380724 23.314914 270)
			(size 0.4318 0.4318)
			(layers "F.Cu" "F.Mask" "F.Paste")
			(net "M_F_CPU0_SA_CB<3>")
		)
		(pad "EH61" smd circle
			(at 13.008356 23.314914 270)
			(size 0.4318 0.4318)
			(layers "F.Cu" "F.Mask" "F.Paste")
			(net "GND")
		)
		(pad "EH63" smd circle
			(at 14.635988 23.314914 270)
			(size 0.4318 0.4318)
			(layers "F.Cu" "F.Mask" "F.Paste")
			(net "M_F_CPU0_SA_DQ<22>")
		)
		(pad "EH65" smd circle
			(at 16.263874 23.314914 270)
			(size 0.4318 0.4318)
			(layers "F.Cu" "F.Mask" "F.Paste")
			(net "M_F_CPU0_SA_DQ<19>")
		)
		(pad "EH67" smd circle
			(at 17.89176 23.314914 270)
			(size 0.4318 0.4318)
			(layers "F.Cu" "F.Mask" "F.Paste")
			(net "GND")
		)
		(pad "EH69" smd circle
			(at 19.519392 23.314914 270)
			(size 0.4318 0.4318)
			(layers "F.Cu" "F.Mask" "F.Paste")
			(net "M_E_CPU0_SA_DQ<14>")
		)
		(pad "EH71" smd circle
			(at 21.147278 23.314914 270)
			(size 0.4318 0.4318)
			(layers "F.Cu" "F.Mask" "F.Paste")
			(net "M_E_CPU0_SA_DQ<11>")
		)
		(pad "EH73" smd circle
			(at 22.77491 23.314914 270)
			(size 0.4318 0.4318)
			(layers "F.Cu" "F.Mask" "F.Paste")
			(net "GND")
		)
		(pad "EH75" smd circle
			(at 24.402796 23.314914 270)
			(size 0.4318 0.4318)
			(layers "F.Cu" "F.Mask" "F.Paste")
			(net "M_F_CPU0_SA_DQ<6>")
		)
		(pad "EH77" smd circle
			(at 26.030682 23.314914 270)
			(size 0.4318 0.4318)
			(layers "F.Cu" "F.Mask" "F.Paste")
			(net "M_F_CPU0_SA_DQ<1>")
		)
		(pad "EH79" smd circle
			(at 27.658314 23.314914 270)
			(size 0.4318 0.4318)
			(layers "F.Cu" "F.Mask" "F.Paste")
			(net "GND")
		)
		(pad "EH81" smd circle
			(at 29.2862 23.314914 270)
			(size 0.4318 0.4318)
			(layers "F.Cu" "F.Mask" "F.Paste")
			(net "GND")
		)
		(pad "EH83" smd circle
			(at 30.914086 23.314914 270)
			(size 0.4318 0.4318)
			(layers "F.Cu" "F.Mask" "F.Paste")
			(net "GND")
		)
		(pad "EH85" smd circle
			(at 32.541718 23.314914 270)
			(size 0.4318 0.4318)
			(layers "F.Cu" "F.Mask" "F.Paste")
			(net "Net_701")
		)
		(pad "EH87" smd circle
			(at 34.169604 23.314914 270)
			(size 0.4318 0.4318)
			(layers "F.Cu" "F.Mask" "F.Paste")
			(net "Net_659")
		)
		(pad "EH89" smd oval
			(at 35.797236 23.314914 315)
			(size 0.381 0.4826)
			(drill
				(offset 0 -0.0508)
			)
			(layers "F.Cu" "F.Mask" "F.Paste")
			(net "P5E_CPU0_PE3_RX_DN<0>")
		)
		(pad "EJ3" smd oval
			(at -35.797236 23.675086 225)
			(size 0.381 0.4826)
			(drill
				(offset 0 -0.0508)
			)
			(layers "F.Cu" "F.Mask" "F.Paste")
			(net "UPI_CPU1_CPU0_P0P1_DP<0>")
		)
		(pad "EJ5" smd circle
			(at -34.169604 23.675086 270)
			(size 0.4318 0.4318)
			(layers "F.Cu" "F.Mask" "F.Paste")
			(net "M_G_CPU0_SB_DQ<29>")
		)
		(pad "EJ7" smd circle
			(at -32.541718 23.675086 270)
			(size 0.4318 0.4318)
			(layers "F.Cu" "F.Mask" "F.Paste")
			(net "GND")
		)
		(pad "EJ9" smd circle
			(at -30.914086 23.675086 270)
			(size 0.4318 0.4318)
			(layers "F.Cu" "F.Mask" "F.Paste")
			(net "GND")
		)
		(pad "EJ11" smd circle
			(at -29.2862 23.675086 270)
			(size 0.4318 0.4318)
			(layers "F.Cu" "F.Mask" "F.Paste")
			(net "GND")
		)
		(pad "EJ13" smd circle
			(at -27.658314 23.675086 270)
			(size 0.4318 0.4318)
			(layers "F.Cu" "F.Mask" "F.Paste")
			(net "GND")
		)
		(pad "EJ15" smd circle
			(at -26.030682 23.675086 270)
			(size 0.4318 0.4318)
			(layers "F.Cu" "F.Mask" "F.Paste")
			(net "PVCCFA_EHV_FIVRA_CPU0")
		)
		(pad "EJ17" smd circle
			(at -24.402796 23.675086 270)
			(size 0.4318 0.4318)
			(layers "F.Cu" "F.Mask" "F.Paste")
			(net "GND")
		)
		(pad "EJ19" smd circle
			(at -22.77491 23.675086 270)
			(size 0.4318 0.4318)
			(layers "F.Cu" "F.Mask" "F.Paste")
			(net "GND")
		)
		(pad "EJ21" smd circle
			(at -21.147278 23.675086 270)
			(size 0.4318 0.4318)
			(layers "F.Cu" "F.Mask" "F.Paste")
			(net "M_F_CPU0_SB_DQS_DN<6>")
		)
		(pad "EJ23" smd circle
			(at -19.519392 23.675086 270)
			(size 0.4318 0.4318)
			(layers "F.Cu" "F.Mask" "F.Paste")
			(net "GND")
		)
		(pad "EJ25" smd circle
			(at -17.89176 23.675086 270)
			(size 0.4318 0.4318)
			(layers "F.Cu" "F.Mask" "F.Paste")
			(net "GND")
		)
		(pad "EJ27" smd circle
			(at -16.263874 23.675086 270)
			(size 0.4318 0.4318)
			(layers "F.Cu" "F.Mask" "F.Paste")
			(net "M_E_CPU0_SB_DQS_DN<5>")
		)
		(pad "EJ29" smd circle
			(at -14.635988 23.675086 270)
			(size 0.4318 0.4318)
			(layers "F.Cu" "F.Mask" "F.Paste")
			(net "GND")
		)
		(pad "EJ31" smd circle
			(at -13.008356 23.675086 270)
			(size 0.4318 0.4318)
			(layers "F.Cu" "F.Mask" "F.Paste")
			(net "GND")
		)
		(pad "EJ33" smd circle
			(at -11.380724 23.675086 270)
			(size 0.4318 0.4318)
			(layers "F.Cu" "F.Mask" "F.Paste")
			(net "M_F_CPU0_SB_DQS_DN<4>")
		)
		(pad "EJ35" smd circle
			(at -9.752838 23.675086 270)
			(size 0.4318 0.4318)
			(layers "F.Cu" "F.Mask" "F.Paste")
			(net "GND")
		)
		(pad "EJ37" smd circle
			(at -8.124952 23.675086 270)
			(size 0.4318 0.4318)
			(layers "F.Cu" "F.Mask" "F.Paste")
			(net "GND")
		)
		(pad "EJ39" smd circle
			(at -6.49732 23.675086 270)
			(size 0.4318 0.4318)
			(layers "F.Cu" "F.Mask" "F.Paste")
			(net "M_F_CPU0_SB_PAR")
		)
		(pad "EJ41" smd circle
			(at -4.869434 23.675086 270)
			(size 0.4318 0.4318)
			(layers "F.Cu" "F.Mask" "F.Paste")
			(net "GND")
		)
		(pad "EJ43" smd circle
			(at -3.241802 23.675086 270)
			(size 0.4318 0.4318)
			(layers "F.Cu" "F.Mask" "F.Paste")
			(net "GND")
		)
		(pad "EJ45" smd circle
			(at -1.613916 23.675086 270)
			(size 0.4318 0.4318)
			(layers "F.Cu" "F.Mask" "F.Paste")
			(net "M_E_CPU0_CLK_DN<0>")
		)
		(pad "EJ48" smd circle
			(at 2.427732 23.784814 270)
			(size 0.4318 0.4318)
			(layers "F.Cu" "F.Mask" "F.Paste")
			(net "GND")
		)
		(pad "EJ50" smd circle
			(at 4.055618 23.784814 270)
			(size 0.4318 0.4318)
			(layers "F.Cu" "F.Mask" "F.Paste")
			(net "GND")
		)
		(pad "EJ52" smd circle
			(at 5.68325 23.784814 270)
			(size 0.4318 0.4318)
			(layers "F.Cu" "F.Mask" "F.Paste")
			(net "M_F_CPU0_SA_CA<1>")
		)
		(pad "EJ54" smd circle
			(at 7.311136 23.784814 270)
			(size 0.4318 0.4318)
			(layers "F.Cu" "F.Mask" "F.Paste")
			(net "GND")
		)
		(pad "EJ56" smd circle
			(at 8.939022 23.784814 270)
			(size 0.4318 0.4318)
			(layers "F.Cu" "F.Mask" "F.Paste")
			(net "GND")
		)
		(pad "EJ58" smd circle
			(at 10.566654 23.784814 270)
			(size 0.4318 0.4318)
			(layers "F.Cu" "F.Mask" "F.Paste")
			(net "M_F_CPU0_SA_DQS_DN<9>")
		)
		(pad "EJ60" smd circle
			(at 12.19454 23.784814 270)
			(size 0.4318 0.4318)
			(layers "F.Cu" "F.Mask" "F.Paste")
			(net "GND")
		)
		(pad "EJ62" smd circle
			(at 13.822426 23.784814 270)
			(size 0.4318 0.4318)
			(layers "F.Cu" "F.Mask" "F.Paste")
			(net "GND")
		)
		(pad "EJ64" smd circle
			(at 15.450058 23.784814 270)
			(size 0.4318 0.4318)
			(layers "F.Cu" "F.Mask" "F.Paste")
			(net "M_F_CPU0_SA_DQS_DN<7>")
		)
		(pad "EJ66" smd circle
			(at 17.07769 23.784814 270)
			(size 0.4318 0.4318)
			(layers "F.Cu" "F.Mask" "F.Paste")
			(net "GND")
		)
		(pad "EJ68" smd circle
			(at 18.705576 23.784814 270)
			(size 0.4318 0.4318)
			(layers "F.Cu" "F.Mask" "F.Paste")
			(net "GND")
		)
		(pad "EJ70" smd circle
			(at 20.333462 23.784814 270)
			(size 0.4318 0.4318)
			(layers "F.Cu" "F.Mask" "F.Paste")
			(net "M_E_CPU0_SA_DQS_DN<6>")
		)
		(pad "EJ72" smd circle
			(at 21.961094 23.784814 270)
			(size 0.4318 0.4318)
			(layers "F.Cu" "F.Mask" "F.Paste")
			(net "GND")
		)
		(pad "EJ74" smd circle
			(at 23.58898 23.784814 270)
			(size 0.4318 0.4318)
			(layers "F.Cu" "F.Mask" "F.Paste")
			(net "GND")
		)
		(pad "EJ76" smd circle
			(at 25.216612 23.784814 270)
			(size 0.4318 0.4318)
			(layers "F.Cu" "F.Mask" "F.Paste")
			(net "M_F_CPU0_SA_DQS_DN<5>")
		)
		(pad "EJ78" smd circle
			(at 26.844498 23.784814 270)
			(size 0.4318 0.4318)
			(layers "F.Cu" "F.Mask" "F.Paste")
			(net "GND")
		)
		(pad "EJ80" smd circle
			(at 28.472384 23.784814 270)
			(size 0.4318 0.4318)
			(layers "F.Cu" "F.Mask" "F.Paste")
			(net "GND")
		)
		(pad "EJ82" smd circle
			(at 30.100016 23.784814 270)
			(size 0.4318 0.4318)
			(layers "F.Cu" "F.Mask" "F.Paste")
			(net "GND")
		)
		(pad "EJ84" smd circle
			(at 31.727902 23.784814 270)
			(size 0.4318 0.4318)
			(layers "F.Cu" "F.Mask" "F.Paste")
			(net "PVCCFA_EHV_FIVRA_CPU0")
		)
		(pad "EJ86" smd circle
			(at 33.355534 23.784814 270)
			(size 0.4318 0.4318)
			(layers "F.Cu" "F.Mask" "F.Paste")
			(net "Net_683")
		)
		(pad "EJ88" smd oval
			(at 34.98342 23.784814 315)
			(size 0.381 0.4826)
			(drill
				(offset 0 -0.0508)
			)
			(layers "F.Cu" "F.Mask" "F.Paste")
			(net "GND")
		)
		(pad "EJ90" smd oval
			(at 36.611306 23.784814 315)
			(size 0.381 0.4826)
			(drill
				(offset 0 -0.0508)
			)
			(layers "F.Cu" "F.Mask" "F.Paste")
			(net "P5E_CPU0_PE3_RX_DP<0>")
		)
		(pad "EK2" smd oval
			(at -36.611306 24.144986 225)
			(size 0.381 0.4826)
			(drill
				(offset 0 -0.0508)
			)
			(layers "F.Cu" "F.Mask" "F.Paste")
			(net "GND")
		)
		(pad "EK4" smd oval
			(at -34.98342 24.144986 225)
			(size 0.381 0.4826)
			(drill
				(offset 0 -0.0508)
			)
			(layers "F.Cu" "F.Mask" "F.Paste")
			(net "GND")
		)
		(pad "EK6" smd circle
			(at -33.355534 24.144986 270)
			(size 0.4318 0.4318)
			(layers "F.Cu" "F.Mask" "F.Paste")
			(net "M_G_CPU0_SB_DQ<28>")
		)
		(pad "EK8" smd circle
			(at -31.727902 24.144986 270)
			(size 0.4318 0.4318)
			(layers "F.Cu" "F.Mask" "F.Paste")
			(net "M_G_CPU0_SB_DQ<24>")
		)
		(pad "EK10" smd circle
			(at -30.100016 24.144986 270)
			(size 0.4318 0.4318)
			(layers "F.Cu" "F.Mask" "F.Paste")
			(net "GND")
		)
		(pad "EK12" smd circle
			(at -28.472384 24.144986 270)
			(size 0.4318 0.4318)
			(layers "F.Cu" "F.Mask" "F.Paste")
			(net "M_F_CPU0_SB_DQS_DP<2>")
		)
		(pad "EK14" smd circle
			(at -26.844498 24.144986 270)
			(size 0.4318 0.4318)
			(layers "F.Cu" "F.Mask" "F.Paste")
			(net "GND")
		)
		(pad "EK16" smd circle
			(at -25.216612 24.144986 270)
			(size 0.4318 0.4318)
			(layers "F.Cu" "F.Mask" "F.Paste")
			(net "GND")
		)
		(pad "EK18" smd circle
			(at -23.58898 24.144986 270)
			(size 0.4318 0.4318)
			(layers "F.Cu" "F.Mask" "F.Paste")
			(net "M_E_CPU0_SB_DQS_DN<3>")
		)
		(pad "EK20" smd circle
			(at -21.961094 24.144986 270)
			(size 0.4318 0.4318)
			(layers "F.Cu" "F.Mask" "F.Paste")
			(net "GND")
		)
		(pad "EK22" smd circle
			(at -20.333462 24.144986 270)
			(size 0.4318 0.4318)
			(layers "F.Cu" "F.Mask" "F.Paste")
			(net "GND")
		)
		(pad "EK24" smd circle
			(at -18.705576 24.144986 270)
			(size 0.4318 0.4318)
			(layers "F.Cu" "F.Mask" "F.Paste")
			(net "M_E_CPU0_SB_DQS_DN<2>")
		)
		(pad "EK26" smd circle
			(at -17.07769 24.144986 270)
			(size 0.4318 0.4318)
			(layers "F.Cu" "F.Mask" "F.Paste")
			(net "GND")
		)
		(pad "EK28" smd circle
			(at -15.450058 24.144986 270)
			(size 0.4318 0.4318)
			(layers "F.Cu" "F.Mask" "F.Paste")
			(net "GND")
		)
		(pad "EK30" smd circle
			(at -13.822426 24.144986 270)
			(size 0.4318 0.4318)
			(layers "F.Cu" "F.Mask" "F.Paste")
			(net "M_E_CPU0_SB_DQS_DN<1>")
		)
		(pad "EK32" smd circle
			(at -12.19454 24.144986 270)
			(size 0.4318 0.4318)
			(layers "F.Cu" "F.Mask" "F.Paste")
			(net "GND")
		)
		(pad "EK34" smd circle
			(at -10.566654 24.144986 270)
			(size 0.4318 0.4318)
			(layers "F.Cu" "F.Mask" "F.Paste")
			(net "GND")
		)
		(pad "EK36" smd circle
			(at -8.939022 24.144986 270)
			(size 0.4318 0.4318)
			(layers "F.Cu" "F.Mask" "F.Paste")
			(net "M_E_CPU0_SB_DQS_DN<9>")
		)
		(pad "EK38" smd circle
			(at -7.311136 24.144986 270)
			(size 0.4318 0.4318)
			(layers "F.Cu" "F.Mask" "F.Paste")
			(net "GND")
		)
		(pad "EK40" smd circle
			(at -5.68325 24.144986 270)
			(size 0.4318 0.4318)
			(layers "F.Cu" "F.Mask" "F.Paste")
			(net "GND")
		)
		(pad "EK42" smd circle
			(at -4.055618 24.144986 270)
			(size 0.4318 0.4318)
			(layers "F.Cu" "F.Mask" "F.Paste")
			(net "M_E_CPU0_SB_CA<6>")
		)
		(pad "EK44" smd circle
			(at -2.427732 24.144986 270)
			(size 0.4318 0.4318)
			(layers "F.Cu" "F.Mask" "F.Paste")
			(net "GND")
		)
		(pad "EK47" smd circle
			(at 1.613916 24.254714 270)
			(size 0.4318 0.4318)
			(layers "F.Cu" "F.Mask" "F.Paste")
			(net "GND")
		)
		(pad "EK49" smd circle
			(at 3.241802 24.254714 270)
			(size 0.4318 0.4318)
			(layers "F.Cu" "F.Mask" "F.Paste")
			(net "M_E_CPU0_SA_CA<2>")
		)
		(pad "EK51" smd circle
			(at 4.869434 24.254714 270)
			(size 0.4318 0.4318)
			(layers "F.Cu" "F.Mask" "F.Paste")
			(net "GND")
		)
		(pad "EK53" smd circle
			(at 6.49732 24.254714 270)
			(size 0.4318 0.4318)
			(layers "F.Cu" "F.Mask" "F.Paste")
			(net "GND")
		)
		(pad "EK55" smd circle
			(at 8.124952 24.254714 270)
			(size 0.4318 0.4318)
			(layers "F.Cu" "F.Mask" "F.Paste")
			(net "M_E_CPU0_SA_DQS_DP<4>")
		)
		(pad "EK57" smd circle
			(at 9.752838 24.254714 270)
			(size 0.4318 0.4318)
			(layers "F.Cu" "F.Mask" "F.Paste")
			(net "GND")
		)
		(pad "EK59" smd circle
			(at 11.380724 24.254714 270)
			(size 0.4318 0.4318)
			(layers "F.Cu" "F.Mask" "F.Paste")
			(net "GND")
		)
		(pad "EK61" smd circle
			(at 13.008356 24.254714 270)
			(size 0.4318 0.4318)
			(layers "F.Cu" "F.Mask" "F.Paste")
			(net "M_E_CPU0_SA_DQS_DN<3>")
		)
		(pad "EK63" smd circle
			(at 14.635988 24.254714 270)
			(size 0.4318 0.4318)
			(layers "F.Cu" "F.Mask" "F.Paste")
			(net "GND")
		)
		(pad "EK65" smd circle
			(at 16.263874 24.254714 270)
			(size 0.4318 0.4318)
			(layers "F.Cu" "F.Mask" "F.Paste")
			(net "GND")
		)
		(pad "EK67" smd circle
			(at 17.89176 24.254714 270)
			(size 0.4318 0.4318)
			(layers "F.Cu" "F.Mask" "F.Paste")
			(net "M_E_CPU0_SA_DQS_DN<2>")
		)
		(pad "EK69" smd circle
			(at 19.519392 24.254714 270)
			(size 0.4318 0.4318)
			(layers "F.Cu" "F.Mask" "F.Paste")
			(net "GND")
		)
		(pad "EK71" smd circle
			(at 21.147278 24.254714 270)
			(size 0.4318 0.4318)
			(layers "F.Cu" "F.Mask" "F.Paste")
			(net "GND")
		)
		(pad "EK73" smd circle
			(at 22.77491 24.254714 270)
			(size 0.4318 0.4318)
			(layers "F.Cu" "F.Mask" "F.Paste")
			(net "M_E_CPU0_SA_DQ<5>")
		)
		(pad "EK75" smd circle
			(at 24.402796 24.254714 270)
			(size 0.4318 0.4318)
			(layers "F.Cu" "F.Mask" "F.Paste")
			(net "GND")
		)
		(pad "EK77" smd circle
			(at 26.030682 24.254714 270)
			(size 0.4318 0.4318)
			(layers "F.Cu" "F.Mask" "F.Paste")
			(net "GND")
		)
		(pad "EK79" smd circle
			(at 27.658314 24.254714 270)
			(size 0.4318 0.4318)
			(layers "F.Cu" "F.Mask" "F.Paste")
			(net "GND")
		)
		(pad "EK81" smd circle
			(at 29.2862 24.254714 270)
			(size 0.4318 0.4318)
			(layers "F.Cu" "F.Mask" "F.Paste")
			(net "GND")
		)
		(pad "EK83" smd circle
			(at 30.914086 24.254714 270)
			(size 0.4318 0.4318)
			(layers "F.Cu" "F.Mask" "F.Paste")
			(net "GND")
		)
		(pad "EK85" smd circle
			(at 32.541718 24.254714 270)
			(size 0.4318 0.4318)
			(layers "F.Cu" "F.Mask" "F.Paste")
			(net "Net_677")
		)
		(pad "EK87" smd oval
			(at 34.169604 24.254714 315)
			(size 0.381 0.4826)
			(drill
				(offset 0 -0.0508)
			)
			(layers "F.Cu" "F.Mask" "F.Paste")
			(net "Net_682")
		)
		(pad "EK89" smd oval
			(at 35.797236 24.254714 315)
			(size 0.381 0.4826)
			(drill
				(offset 0 -0.0508)
			)
			(layers "F.Cu" "F.Mask" "F.Paste")
			(net "GND")
		)
		(pad "EL3" smd oval
			(at -35.797236 24.614886 225)
			(size 0.381 0.4826)
			(drill
				(offset 0 -0.0508)
			)
			(layers "F.Cu" "F.Mask" "F.Paste")
			(net "GND")
		)
		(pad "EL5" smd oval
			(at -34.169604 24.614886 225)
			(size 0.381 0.4826)
			(drill
				(offset 0 -0.0508)
			)
			(layers "F.Cu" "F.Mask" "F.Paste")
			(net "GND")
		)
		(pad "EL7" smd circle
			(at -32.541718 24.614886 270)
			(size 0.4318 0.4318)
			(layers "F.Cu" "F.Mask" "F.Paste")
			(net "GND")
		)
		(pad "EL9" smd circle
			(at -30.914086 24.614886 270)
			(size 0.4318 0.4318)
			(layers "F.Cu" "F.Mask" "F.Paste")
			(net "GND")
		)
		(pad "EL11" smd circle
			(at -29.2862 24.614886 270)
			(size 0.4318 0.4318)
			(layers "F.Cu" "F.Mask" "F.Paste")
			(net "M_F_CPU0_SB_DQ<20>")
		)
		(pad "EL13" smd circle
			(at -27.658314 24.614886 270)
			(size 0.4318 0.4318)
			(layers "F.Cu" "F.Mask" "F.Paste")
			(net "M_F_CPU0_SB_DQ<17>")
		)
		(pad "EL15" smd circle
			(at -26.030682 24.614886 270)
			(size 0.4318 0.4318)
			(layers "F.Cu" "F.Mask" "F.Paste")
			(net "GND")
		)
		(pad "EL17" smd circle
			(at -24.402796 24.614886 270)
			(size 0.4318 0.4318)
			(layers "F.Cu" "F.Mask" "F.Paste")
			(net "M_E_CPU0_SB_DQ<28>")
		)
		(pad "EL19" smd circle
			(at -22.77491 24.614886 270)
			(size 0.4318 0.4318)
			(layers "F.Cu" "F.Mask" "F.Paste")
			(net "M_E_CPU0_SB_DQ<25>")
		)
		(pad "EL21" smd circle
			(at -21.147278 24.614886 270)
			(size 0.4318 0.4318)
			(layers "F.Cu" "F.Mask" "F.Paste")
			(net "GND")
		)
		(pad "EL23" smd circle
			(at -19.519392 24.614886 270)
			(size 0.4318 0.4318)
			(layers "F.Cu" "F.Mask" "F.Paste")
			(net "M_E_CPU0_SB_DQ<20>")
		)
		(pad "EL25" smd circle
			(at -17.89176 24.614886 270)
			(size 0.4318 0.4318)
			(layers "F.Cu" "F.Mask" "F.Paste")
			(net "M_E_CPU0_SB_DQ<17>")
		)
		(pad "EL27" smd circle
			(at -16.263874 24.614886 270)
			(size 0.4318 0.4318)
			(layers "F.Cu" "F.Mask" "F.Paste")
			(net "GND")
		)
		(pad "EL29" smd circle
			(at -14.635988 24.614886 270)
			(size 0.4318 0.4318)
			(layers "F.Cu" "F.Mask" "F.Paste")
			(net "M_E_CPU0_SB_DQ<12>")
		)
		(pad "EL31" smd circle
			(at -13.008356 24.614886 270)
			(size 0.4318 0.4318)
			(layers "F.Cu" "F.Mask" "F.Paste")
			(net "M_E_CPU0_SB_DQ<9>")
		)
		(pad "EL33" smd circle
			(at -11.380724 24.614886 270)
			(size 0.4318 0.4318)
			(layers "F.Cu" "F.Mask" "F.Paste")
			(net "GND")
		)
		(pad "EL35" smd circle
			(at -9.752838 24.614886 270)
			(size 0.4318 0.4318)
			(layers "F.Cu" "F.Mask" "F.Paste")
			(net "M_E_CPU0_SB_CB<0>")
		)
		(pad "EL37" smd circle
			(at -8.124952 24.614886 270)
			(size 0.4318 0.4318)
			(layers "F.Cu" "F.Mask" "F.Paste")
			(net "M_E_CPU0_SB_CB<5>")
		)
		(pad "EL39" smd circle
			(at -6.49732 24.614886 270)
			(size 0.4318 0.4318)
			(layers "F.Cu" "F.Mask" "F.Paste")
			(net "GND")
		)
		(pad "EL41" smd circle
			(at -4.869434 24.614886 270)
			(size 0.4318 0.4318)
			(layers "F.Cu" "F.Mask" "F.Paste")
			(net "M_E_CPU0_SB_CS_N<3>")
		)
		(pad "EL43" smd circle
			(at -3.241802 24.614886 270)
			(size 0.4318 0.4318)
			(layers "F.Cu" "F.Mask" "F.Paste")
			(net "M_E_CPU0_SB_CA<4>")
		)
		(pad "EL45" smd circle
			(at -1.613916 24.614886 270)
			(size 0.4318 0.4318)
			(layers "F.Cu" "F.Mask" "F.Paste")
			(net "GND")
		)
		(pad "EL48" smd circle
			(at 2.427732 24.724868 270)
			(size 0.4318 0.4318)
			(layers "F.Cu" "F.Mask" "F.Paste")
			(net "M_E_CPU0_SA_CA<3>")
		)
		(pad "EL50" smd circle
			(at 4.055618 24.724868 270)
			(size 0.4318 0.4318)
			(layers "F.Cu" "F.Mask" "F.Paste")
			(net "M_E_CPU0_SA_CS_N<3>")
		)
		(pad "EL52" smd circle
			(at 5.68325 24.724868 270)
			(size 0.4318 0.4318)
			(layers "F.Cu" "F.Mask" "F.Paste")
			(net "GND")
		)
		(pad "EL54" smd circle
			(at 7.311136 24.724868 270)
			(size 0.4318 0.4318)
			(layers "F.Cu" "F.Mask" "F.Paste")
			(net "M_E_CPU0_SA_CB<4>")
		)
		(pad "EL56" smd circle
			(at 8.939022 24.724868 270)
			(size 0.4318 0.4318)
			(layers "F.Cu" "F.Mask" "F.Paste")
			(net "M_E_CPU0_SA_CB<1>")
		)
		(pad "EL58" smd circle
			(at 10.566654 24.724868 270)
			(size 0.4318 0.4318)
			(layers "F.Cu" "F.Mask" "F.Paste")
			(net "GND")
		)
		(pad "EL60" smd circle
			(at 12.19454 24.724868 270)
			(size 0.4318 0.4318)
			(layers "F.Cu" "F.Mask" "F.Paste")
			(net "M_E_CPU0_SA_DQ<28>")
		)
		(pad "EL62" smd circle
			(at 13.822426 24.724868 270)
			(size 0.4318 0.4318)
			(layers "F.Cu" "F.Mask" "F.Paste")
			(net "M_E_CPU0_SA_DQ<25>")
		)
		(pad "EL64" smd circle
			(at 15.450058 24.724868 270)
			(size 0.4318 0.4318)
			(layers "F.Cu" "F.Mask" "F.Paste")
			(net "GND")
		)
		(pad "EL66" smd circle
			(at 17.07769 24.724868 270)
			(size 0.4318 0.4318)
			(layers "F.Cu" "F.Mask" "F.Paste")
			(net "M_E_CPU0_SA_DQ<22>")
		)
		(pad "EL68" smd circle
			(at 18.705576 24.724868 270)
			(size 0.4318 0.4318)
			(layers "F.Cu" "F.Mask" "F.Paste")
			(net "M_E_CPU0_SA_DQS_DP<2>")
		)
		(pad "EL70" smd circle
			(at 20.333462 24.724868 270)
			(size 0.4318 0.4318)
			(layers "F.Cu" "F.Mask" "F.Paste")
			(net "GND")
		)
		(pad "EL72" smd circle
			(at 21.961094 24.724868 270)
			(size 0.4318 0.4318)
			(layers "F.Cu" "F.Mask" "F.Paste")
			(net "GND")
		)
		(pad "EL74" smd circle
			(at 23.58898 24.724868 270)
			(size 0.4318 0.4318)
			(layers "F.Cu" "F.Mask" "F.Paste")
			(net "M_E_CPU0_SA_DQ<4>")
		)
		(pad "EL76" smd circle
			(at 25.216612 24.724868 270)
			(size 0.4318 0.4318)
			(layers "F.Cu" "F.Mask" "F.Paste")
			(net "GND")
		)
		(pad "EL78" smd circle
			(at 26.844498 24.724868 270)
			(size 0.4318 0.4318)
			(layers "F.Cu" "F.Mask" "F.Paste")
			(net "M_E_CPU0_SA_DQ<0>")
		)
		(pad "EL80" smd circle
			(at 28.472384 24.724868 270)
			(size 0.4318 0.4318)
			(layers "F.Cu" "F.Mask" "F.Paste")
			(net "GND")
		)
		(pad "EL82" smd circle
			(at 30.100016 24.724868 270)
			(size 0.4318 0.4318)
			(layers "F.Cu" "F.Mask" "F.Paste")
			(net "GND")
		)
		(pad "EL84" smd circle
			(at 31.727902 24.724868 270)
			(size 0.4318 0.4318)
			(layers "F.Cu" "F.Mask" "F.Paste")
			(net "Net_700")
		)
		(pad "EL86" smd oval
			(at 33.355534 24.724868 315)
			(size 0.381 0.4826)
			(drill
				(offset 0 -0.0508)
			)
			(layers "F.Cu" "F.Mask" "F.Paste")
			(net "GND")
		)
		(pad "EL88" smd oval
			(at 34.98342 24.724868 315)
			(size 0.381 0.4826)
			(drill
				(offset 0 -0.0508)
			)
			(layers "F.Cu" "F.Mask" "F.Paste")
			(net "Net_658")
		)
		(pad "EM4" smd oval
			(at -34.98342 25.084532 225)
			(size 0.381 0.4826)
			(drill
				(offset 0 -0.0508)
			)
			(layers "F.Cu" "F.Mask" "F.Paste")
			(net "M_G_CPU0_SB_DQ<31>")
		)
		(pad "EM6" smd oval
			(at -33.355534 25.084532 225)
			(size 0.381 0.4826)
			(drill
				(offset 0 -0.0508)
			)
			(layers "F.Cu" "F.Mask" "F.Paste")
			(net "M_G_CPU0_SB_DQS_DN<8>")
		)
		(pad "EM8" smd circle
			(at -31.727902 25.084532 270)
			(size 0.4318 0.4318)
			(layers "F.Cu" "F.Mask" "F.Paste")
			(net "GND")
		)
		(pad "EM10" smd circle
			(at -30.100016 25.084532 270)
			(size 0.4318 0.4318)
			(layers "F.Cu" "F.Mask" "F.Paste")
			(net "M_F_CPU0_SB_DQ<21>")
		)
		(pad "EM12" smd circle
			(at -28.472384 25.084532 270)
			(size 0.4318 0.4318)
			(layers "F.Cu" "F.Mask" "F.Paste")
			(net "M_F_CPU0_SB_DQS_DN<2>")
		)
		(pad "EM14" smd circle
			(at -26.844498 25.084532 270)
			(size 0.4318 0.4318)
			(layers "F.Cu" "F.Mask" "F.Paste")
			(net "M_F_CPU0_SB_DQ<16>")
		)
		(pad "EM16" smd circle
			(at -25.216612 25.084532 270)
			(size 0.4318 0.4318)
			(layers "F.Cu" "F.Mask" "F.Paste")
			(net "M_E_CPU0_SB_DQ<29>")
		)
		(pad "EM18" smd circle
			(at -23.58898 25.084532 270)
			(size 0.4318 0.4318)
			(layers "F.Cu" "F.Mask" "F.Paste")
			(net "M_E_CPU0_SB_DQS_DP<3>")
		)
		(pad "EM20" smd circle
			(at -21.961094 25.084532 270)
			(size 0.4318 0.4318)
			(layers "F.Cu" "F.Mask" "F.Paste")
			(net "M_E_CPU0_SB_DQ<24>")
		)
		(pad "EM22" smd circle
			(at -20.333462 25.084532 270)
			(size 0.4318 0.4318)
			(layers "F.Cu" "F.Mask" "F.Paste")
			(net "M_E_CPU0_SB_DQ<21>")
		)
		(pad "EM24" smd circle
			(at -18.705576 25.084532 270)
			(size 0.4318 0.4318)
			(layers "F.Cu" "F.Mask" "F.Paste")
			(net "M_E_CPU0_SB_DQS_DP<2>")
		)
		(pad "EM26" smd circle
			(at -17.07769 25.084532 270)
			(size 0.4318 0.4318)
			(layers "F.Cu" "F.Mask" "F.Paste")
			(net "M_E_CPU0_SB_DQ<16>")
		)
		(pad "EM28" smd circle
			(at -15.450058 25.084532 270)
			(size 0.4318 0.4318)
			(layers "F.Cu" "F.Mask" "F.Paste")
			(net "M_E_CPU0_SB_DQ<13>")
		)
		(pad "EM30" smd circle
			(at -13.822426 25.084532 270)
			(size 0.4318 0.4318)
			(layers "F.Cu" "F.Mask" "F.Paste")
			(net "M_E_CPU0_SB_DQS_DP<1>")
		)
		(pad "EM32" smd circle
			(at -12.19454 25.084532 270)
			(size 0.4318 0.4318)
			(layers "F.Cu" "F.Mask" "F.Paste")
			(net "M_E_CPU0_SB_DQ<8>")
		)
		(pad "EM34" smd circle
			(at -10.566654 25.084532 270)
			(size 0.4318 0.4318)
			(layers "F.Cu" "F.Mask" "F.Paste")
			(net "M_E_CPU0_SB_CB<1>")
		)
		(pad "EM36" smd circle
			(at -8.939022 25.084532 270)
			(size 0.4318 0.4318)
			(layers "F.Cu" "F.Mask" "F.Paste")
			(net "M_E_CPU0_SB_DQS_DP<9>")
		)
		(pad "EM38" smd circle
			(at -7.311136 25.084532 270)
			(size 0.4318 0.4318)
			(layers "F.Cu" "F.Mask" "F.Paste")
			(net "M_E_CPU0_SB_CB<4>")
		)
		(pad "EM40" smd circle
			(at -5.68325 25.084532 270)
			(size 0.4318 0.4318)
			(layers "F.Cu" "F.Mask" "F.Paste")
			(net "M_E_CPU0_SB_CS_N<2>")
		)
		(pad "EM42" smd circle
			(at -4.055618 25.084532 270)
			(size 0.4318 0.4318)
			(layers "F.Cu" "F.Mask" "F.Paste")
			(net "GND")
		)
		(pad "EM44" smd circle
			(at -2.427732 25.084532 270)
			(size 0.4318 0.4318)
			(layers "F.Cu" "F.Mask" "F.Paste")
			(net "M_E_CPU0_SB_CA<2>")
		)
		(pad "EM47" smd circle
			(at 1.613916 25.194514 270)
			(size 0.4318 0.4318)
			(layers "F.Cu" "F.Mask" "F.Paste")
			(net "M_E_CPU0_SA_CA<4>")
		)
		(pad "EM49" smd circle
			(at 3.241802 25.194514 270)
			(size 0.4318 0.4318)
			(layers "F.Cu" "F.Mask" "F.Paste")
			(net "GND")
		)
		(pad "EM51" smd circle
			(at 4.869434 25.194514 270)
			(size 0.4318 0.4318)
			(layers "F.Cu" "F.Mask" "F.Paste")
			(net "M_E_CPU0_SA_CS_N<2>")
		)
		(pad "EM53" smd circle
			(at 6.49732 25.194514 270)
			(size 0.4318 0.4318)
			(layers "F.Cu" "F.Mask" "F.Paste")
			(net "M_E_CPU0_SA_CB<5>")
		)
		(pad "EM55" smd circle
			(at 8.124952 25.194514 270)
			(size 0.4318 0.4318)
			(layers "F.Cu" "F.Mask" "F.Paste")
			(net "M_E_CPU0_SA_DQS_DN<4>")
		)
		(pad "EM57" smd circle
			(at 9.752838 25.194514 270)
			(size 0.4318 0.4318)
			(layers "F.Cu" "F.Mask" "F.Paste")
			(net "M_E_CPU0_SA_CB<0>")
		)
		(pad "EM59" smd circle
			(at 11.380724 25.194514 270)
			(size 0.4318 0.4318)
			(layers "F.Cu" "F.Mask" "F.Paste")
			(net "M_E_CPU0_SA_DQ<29>")
		)
		(pad "EM61" smd circle
			(at 13.008356 25.194514 270)
			(size 0.4318 0.4318)
			(layers "F.Cu" "F.Mask" "F.Paste")
			(net "M_E_CPU0_SA_DQS_DP<3>")
		)
		(pad "EM63" smd circle
			(at 14.635988 25.194514 270)
			(size 0.4318 0.4318)
			(layers "F.Cu" "F.Mask" "F.Paste")
			(net "M_E_CPU0_SA_DQ<24>")
		)
		(pad "EM65" smd circle
			(at 16.263874 25.194514 270)
			(size 0.4318 0.4318)
			(layers "F.Cu" "F.Mask" "F.Paste")
			(net "M_E_CPU0_SA_DQ<21>")
		)
		(pad "EM67" smd circle
			(at 17.89176 25.194514 270)
			(size 0.4318 0.4318)
			(layers "F.Cu" "F.Mask" "F.Paste")
			(net "M_E_CPU0_SA_DQS_DP<7>")
		)
		(pad "EM69" smd circle
			(at 19.519392 25.194514 270)
			(size 0.4318 0.4318)
			(layers "F.Cu" "F.Mask" "F.Paste")
			(net "M_E_CPU0_SA_DQ<17>")
		)
		(pad "EM71" smd circle
			(at 21.147278 25.194514 270)
			(size 0.4318 0.4318)
			(layers "F.Cu" "F.Mask" "F.Paste")
			(net "M_E_CPU0_SA_DQ<16>")
		)
		(pad "EM73" smd circle
			(at 22.77491 25.194514 270)
			(size 0.4318 0.4318)
			(layers "F.Cu" "F.Mask" "F.Paste")
			(net "GND")
		)
		(pad "EM75" smd circle
			(at 24.402796 25.194514 270)
			(size 0.4318 0.4318)
			(layers "F.Cu" "F.Mask" "F.Paste")
			(net "M_E_CPU0_SA_DQS_DN<5>")
		)
		(pad "EM77" smd circle
			(at 26.030682 25.194514 270)
			(size 0.4318 0.4318)
			(layers "F.Cu" "F.Mask" "F.Paste")
			(net "M_E_CPU0_SA_DQ<1>")
		)
		(pad "EM79" smd circle
			(at 27.658314 25.194514 270)
			(size 0.4318 0.4318)
			(layers "F.Cu" "F.Mask" "F.Paste")
			(net "GND")
		)
		(pad "EM81" smd circle
			(at 29.2862 25.194514 270)
			(size 0.4318 0.4318)
			(layers "F.Cu" "F.Mask" "F.Paste")
			(net "GND")
		)
		(pad "EM83" smd circle
			(at 30.914086 25.194514 270)
			(size 0.4318 0.4318)
			(layers "F.Cu" "F.Mask" "F.Paste")
			(net "GND")
		)
		(pad "EM85" smd oval
			(at 32.541718 25.194514 315)
			(size 0.381 0.4826)
			(drill
				(offset 0 -0.0508)
			)
			(layers "F.Cu" "F.Mask" "F.Paste")
			(net "Net_676")
		)
		(pad "EM87" smd oval
			(at 34.169604 25.194514 315)
			(size 0.381 0.4826)
			(drill
				(offset 0 -0.0508)
			)
			(layers "F.Cu" "F.Mask" "F.Paste")
			(net "Net_684")
		)
		(pad "EN5" smd oval
			(at -34.169604 25.554686 225)
			(size 0.381 0.4826)
			(drill
				(offset 0 -0.0508)
			)
			(layers "F.Cu" "F.Mask" "F.Paste")
			(net "M_G_CPU0_SB_DQS_DP<8>")
		)
		(pad "EN7" smd oval
			(at -32.541718 25.554686 225)
			(size 0.381 0.4826)
			(drill
				(offset 0 -0.0508)
			)
			(layers "F.Cu" "F.Mask" "F.Paste")
			(net "M_G_CPU0_SB_DQS_DP<3>")
		)
		(pad "EN9" smd circle
			(at -30.914086 25.554686 270)
			(size 0.4318 0.4318)
			(layers "F.Cu" "F.Mask" "F.Paste")
			(net "GND")
		)
		(pad "EN11" smd circle
			(at -29.2862 25.554686 270)
			(size 0.4318 0.4318)
			(layers "F.Cu" "F.Mask" "F.Paste")
			(net "GND")
		)
		(pad "EN13" smd circle
			(at -27.658314 25.554686 270)
			(size 0.4318 0.4318)
			(layers "F.Cu" "F.Mask" "F.Paste")
			(net "GND")
		)
		(pad "EN15" smd circle
			(at -26.030682 25.554686 270)
			(size 0.4318 0.4318)
			(layers "F.Cu" "F.Mask" "F.Paste")
			(net "GND")
		)
		(pad "EN17" smd circle
			(at -24.402796 25.554686 270)
			(size 0.4318 0.4318)
			(layers "F.Cu" "F.Mask" "F.Paste")
			(net "GND")
		)
		(pad "EN19" smd circle
			(at -22.77491 25.554686 270)
			(size 0.4318 0.4318)
			(layers "F.Cu" "F.Mask" "F.Paste")
			(net "GND")
		)
		(pad "EN21" smd circle
			(at -21.147278 25.554686 270)
			(size 0.4318 0.4318)
			(layers "F.Cu" "F.Mask" "F.Paste")
			(net "GND")
		)
		(pad "EN23" smd circle
			(at -19.519392 25.554686 270)
			(size 0.4318 0.4318)
			(layers "F.Cu" "F.Mask" "F.Paste")
			(net "GND")
		)
		(pad "EN25" smd circle
			(at -17.89176 25.554686 270)
			(size 0.4318 0.4318)
			(layers "F.Cu" "F.Mask" "F.Paste")
			(net "GND")
		)
		(pad "EN27" smd circle
			(at -16.263874 25.554686 270)
			(size 0.4318 0.4318)
			(layers "F.Cu" "F.Mask" "F.Paste")
			(net "GND")
		)
		(pad "EN29" smd circle
			(at -14.635988 25.554686 270)
			(size 0.4318 0.4318)
			(layers "F.Cu" "F.Mask" "F.Paste")
			(net "GND")
		)
		(pad "EN31" smd circle
			(at -13.008356 25.554686 270)
			(size 0.4318 0.4318)
			(layers "F.Cu" "F.Mask" "F.Paste")
			(net "GND")
		)
		(pad "EN33" smd circle
			(at -11.380724 25.554686 270)
			(size 0.4318 0.4318)
			(layers "F.Cu" "F.Mask" "F.Paste")
			(net "GND")
		)
		(pad "EN35" smd circle
			(at -9.752838 25.554686 270)
			(size 0.4318 0.4318)
			(layers "F.Cu" "F.Mask" "F.Paste")
			(net "GND")
		)
		(pad "EN37" smd circle
			(at -8.124952 25.554686 270)
			(size 0.4318 0.4318)
			(layers "F.Cu" "F.Mask" "F.Paste")
			(net "GND")
		)
		(pad "EN39" smd circle
			(at -6.49732 25.554686 270)
			(size 0.4318 0.4318)
			(layers "F.Cu" "F.Mask" "F.Paste")
			(net "GND")
		)
		(pad "EN41" smd circle
			(at -4.869434 25.554686 270)
			(size 0.4318 0.4318)
			(layers "F.Cu" "F.Mask" "F.Paste")
			(net "GND")
		)
		(pad "EN43" smd circle
			(at -3.241802 25.554686 270)
			(size 0.4318 0.4318)
			(layers "F.Cu" "F.Mask" "F.Paste")
			(net "GND")
		)
		(pad "EN45" smd oval
			(at -1.613916 25.554686 270)
			(size 0.381 0.4826)
			(drill
				(offset 0 -0.0508)
			)
			(layers "F.Cu" "F.Mask" "F.Paste")
			(net "GND")
		)
		(pad "EN48" smd circle
			(at 2.427732 25.664414 270)
			(size 0.4318 0.4318)
			(layers "F.Cu" "F.Mask" "F.Paste")
			(net "GND")
		)
		(pad "EN50" smd circle
			(at 4.055618 25.664414 270)
			(size 0.4318 0.4318)
			(layers "F.Cu" "F.Mask" "F.Paste")
			(net "GND")
		)
		(pad "EN52" smd circle
			(at 5.68325 25.664414 270)
			(size 0.4318 0.4318)
			(layers "F.Cu" "F.Mask" "F.Paste")
			(net "GND")
		)
		(pad "EN54" smd circle
			(at 7.311136 25.664414 270)
			(size 0.4318 0.4318)
			(layers "F.Cu" "F.Mask" "F.Paste")
			(net "GND")
		)
		(pad "EN56" smd circle
			(at 8.939022 25.664414 270)
			(size 0.4318 0.4318)
			(layers "F.Cu" "F.Mask" "F.Paste")
			(net "GND")
		)
		(pad "EN58" smd circle
			(at 10.566654 25.664414 270)
			(size 0.4318 0.4318)
			(layers "F.Cu" "F.Mask" "F.Paste")
			(net "GND")
		)
		(pad "EN60" smd circle
			(at 12.19454 25.664414 270)
			(size 0.4318 0.4318)
			(layers "F.Cu" "F.Mask" "F.Paste")
			(net "GND")
		)
		(pad "EN62" smd circle
			(at 13.822426 25.664414 270)
			(size 0.4318 0.4318)
			(layers "F.Cu" "F.Mask" "F.Paste")
			(net "GND")
		)
		(pad "EN64" smd circle
			(at 15.450058 25.664414 270)
			(size 0.4318 0.4318)
			(layers "F.Cu" "F.Mask" "F.Paste")
			(net "GND")
		)
		(pad "EN66" smd circle
			(at 17.07769 25.664414 270)
			(size 0.4318 0.4318)
			(layers "F.Cu" "F.Mask" "F.Paste")
			(net "GND")
		)
		(pad "EN68" smd circle
			(at 18.705576 25.664414 270)
			(size 0.4318 0.4318)
			(layers "F.Cu" "F.Mask" "F.Paste")
			(net "M_E_CPU0_SA_DQS_DN<7>")
		)
		(pad "EN70" smd circle
			(at 20.333462 25.664414 270)
			(size 0.4318 0.4318)
			(layers "F.Cu" "F.Mask" "F.Paste")
			(net "M_E_CPU0_SA_DQ<18>")
		)
		(pad "EN72" smd circle
			(at 21.961094 25.664414 270)
			(size 0.4318 0.4318)
			(layers "F.Cu" "F.Mask" "F.Paste")
			(net "GND")
		)
		(pad "EN74" smd circle
			(at 23.58898 25.664414 270)
			(size 0.4318 0.4318)
			(layers "F.Cu" "F.Mask" "F.Paste")
			(net "M_E_CPU0_SA_DQS_DP<5>")
		)
		(pad "EN76" smd circle
			(at 25.216612 25.664414 270)
			(size 0.4318 0.4318)
			(layers "F.Cu" "F.Mask" "F.Paste")
			(net "M_E_CPU0_SA_DQS_DP<0>")
		)
		(pad "EN78" smd circle
			(at 26.844498 25.664414 270)
			(size 0.4318 0.4318)
			(layers "F.Cu" "F.Mask" "F.Paste")
			(net "GND")
		)
		(pad "EN80" smd circle
			(at 28.472384 25.664414 270)
			(size 0.4318 0.4318)
			(layers "F.Cu" "F.Mask" "F.Paste")
			(net "GND")
		)
		(pad "EN82" smd circle
			(at 30.100016 25.664414 270)
			(size 0.4318 0.4318)
			(layers "F.Cu" "F.Mask" "F.Paste")
			(net "GND")
		)
		(pad "EN84" smd oval
			(at 31.727902 25.664414 315)
			(size 0.381 0.4826)
			(drill
				(offset 0 -0.0508)
			)
			(layers "F.Cu" "F.Mask" "F.Paste")
			(net "PVCCFA_EHV_FIVRA_CPU0")
		)
		(pad "EN86" smd oval
			(at 33.355534 25.664414 315)
			(size 0.381 0.4826)
			(drill
				(offset 0 -0.0508)
			)
			(layers "F.Cu" "F.Mask" "F.Paste")
			(net "Net_665")
		)
		(pad "EN88" smd oval
			(at 34.98342 25.664414 315)
			(size 0.381 0.4826)
			(drill
				(offset 0 -0.0508)
			)
			(layers "F.Cu" "F.Mask" "F.Paste")
			(net "GND")
		)
		(pad "EP4" smd oval
			(at -34.98342 26.024586 225)
			(size 0.381 0.4826)
			(drill
				(offset 0 -0.0508)
			)
			(layers "F.Cu" "F.Mask" "F.Paste")
			(net "M_G_CPU0_SB_DQ<30>")
		)
		(pad "EP6" smd oval
			(at -33.355534 26.024586 225)
			(size 0.381 0.4826)
			(drill
				(offset 0 -0.0508)
			)
			(layers "F.Cu" "F.Mask" "F.Paste")
			(net "M_G_CPU0_SB_DQS_DN<3>")
		)
		(pad "EP8" smd oval
			(at -31.727902 26.024586 225)
			(size 0.381 0.4826)
			(drill
				(offset 0 -0.0508)
			)
			(layers "F.Cu" "F.Mask" "F.Paste")
			(net "M_G_CPU0_SB_DQ<26>")
		)
		(pad "EP10" smd circle
			(at -30.100016 26.024586 270)
			(size 0.4318 0.4318)
			(layers "F.Cu" "F.Mask" "F.Paste")
			(net "M_F_CPU0_SB_DQ<23>")
		)
		(pad "EP12" smd circle
			(at -28.472384 26.024586 270)
			(size 0.4318 0.4318)
			(layers "F.Cu" "F.Mask" "F.Paste")
			(net "M_F_CPU0_SB_DQS_DP<7>")
		)
		(pad "EP14" smd circle
			(at -26.844498 26.024586 270)
			(size 0.4318 0.4318)
			(layers "F.Cu" "F.Mask" "F.Paste")
			(net "M_F_CPU0_SB_DQ<18>")
		)
		(pad "EP16" smd circle
			(at -25.216612 26.024586 270)
			(size 0.4318 0.4318)
			(layers "F.Cu" "F.Mask" "F.Paste")
			(net "M_E_CPU0_SB_DQ<31>")
		)
		(pad "EP18" smd circle
			(at -23.58898 26.024586 270)
			(size 0.4318 0.4318)
			(layers "F.Cu" "F.Mask" "F.Paste")
			(net "M_E_CPU0_SB_DQS_DP<8>")
		)
		(pad "EP20" smd circle
			(at -21.961094 26.024586 270)
			(size 0.4318 0.4318)
			(layers "F.Cu" "F.Mask" "F.Paste")
			(net "M_E_CPU0_SB_DQ<26>")
		)
		(pad "EP22" smd circle
			(at -20.333462 26.024586 270)
			(size 0.4318 0.4318)
			(layers "F.Cu" "F.Mask" "F.Paste")
			(net "M_E_CPU0_SB_DQ<23>")
		)
		(pad "EP24" smd circle
			(at -18.705576 26.024586 270)
			(size 0.4318 0.4318)
			(layers "F.Cu" "F.Mask" "F.Paste")
			(net "M_E_CPU0_SB_DQS_DP<7>")
		)
		(pad "EP26" smd circle
			(at -17.07769 26.024586 270)
			(size 0.4318 0.4318)
			(layers "F.Cu" "F.Mask" "F.Paste")
			(net "M_E_CPU0_SB_DQ<18>")
		)
		(pad "EP28" smd circle
			(at -15.450058 26.024586 270)
			(size 0.4318 0.4318)
			(layers "F.Cu" "F.Mask" "F.Paste")
			(net "M_E_CPU0_SB_DQ<15>")
		)
		(pad "EP30" smd circle
			(at -13.822426 26.024586 270)
			(size 0.4318 0.4318)
			(layers "F.Cu" "F.Mask" "F.Paste")
			(net "M_E_CPU0_SB_DQS_DP<6>")
		)
		(pad "EP32" smd circle
			(at -12.19454 26.024586 270)
			(size 0.4318 0.4318)
			(layers "F.Cu" "F.Mask" "F.Paste")
			(net "M_E_CPU0_SB_DQ<10>")
		)
		(pad "EP34" smd circle
			(at -10.566654 26.024586 270)
			(size 0.4318 0.4318)
			(layers "F.Cu" "F.Mask" "F.Paste")
			(net "M_E_CPU0_SB_CB<3>")
		)
		(pad "EP36" smd circle
			(at -8.939022 26.024586 270)
			(size 0.4318 0.4318)
			(layers "F.Cu" "F.Mask" "F.Paste")
			(net "M_E_CPU0_SB_DQS_DP<4>")
		)
		(pad "EP38" smd circle
			(at -7.311136 26.024586 270)
			(size 0.4318 0.4318)
			(layers "F.Cu" "F.Mask" "F.Paste")
			(net "M_E_CPU0_SB_CB<6>")
		)
		(pad "EP40" smd circle
			(at -5.68325 26.024586 270)
			(size 0.4318 0.4318)
			(layers "F.Cu" "F.Mask" "F.Paste")
			(net "M_E_CPU0_SB_CS_N<0>")
		)
		(pad "EP42" smd circle
			(at -4.055618 26.024586 270)
			(size 0.4318 0.4318)
			(layers "F.Cu" "F.Mask" "F.Paste")
			(net "M_E_CPU0_SB_PAR")
		)
		(pad "EP44" smd oval
			(at -2.427732 26.024586 270)
			(size 0.381 0.4826)
			(drill
				(offset 0 -0.0508)
			)
			(layers "F.Cu" "F.Mask" "F.Paste")
			(net "M_E_CPU0_SB_CA<3>")
		)
		(pad "EP47" smd oval
			(at 1.613916 26.134314 270)
			(size 0.381 0.4826)
			(drill
				(offset 0 -0.0508)
			)
			(layers "F.Cu" "F.Mask" "F.Paste")
			(net "M_E_CPU0_SA_CA<5>")
		)
		(pad "EP49" smd circle
			(at 3.241802 26.134314 270)
			(size 0.4318 0.4318)
			(layers "F.Cu" "F.Mask" "F.Paste")
			(net "M_E_CPU0_SA_CA<0>")
		)
		(pad "EP51" smd circle
			(at 4.869434 26.134314 270)
			(size 0.4318 0.4318)
			(layers "F.Cu" "F.Mask" "F.Paste")
			(net "M_E_CPU0_SA_CS_N<0>")
		)
		(pad "EP53" smd circle
			(at 6.49732 26.134314 270)
			(size 0.4318 0.4318)
			(layers "F.Cu" "F.Mask" "F.Paste")
			(net "M_E_CPU0_SA_CB<7>")
		)
		(pad "EP55" smd circle
			(at 8.124952 26.134314 270)
			(size 0.4318 0.4318)
			(layers "F.Cu" "F.Mask" "F.Paste")
			(net "M_E_CPU0_SA_DQS_DP<9>")
		)
		(pad "EP57" smd circle
			(at 9.752838 26.134314 270)
			(size 0.4318 0.4318)
			(layers "F.Cu" "F.Mask" "F.Paste")
			(net "M_E_CPU0_SA_CB<2>")
		)
		(pad "EP59" smd circle
			(at 11.380724 26.134314 270)
			(size 0.4318 0.4318)
			(layers "F.Cu" "F.Mask" "F.Paste")
			(net "M_E_CPU0_SA_DQ<31>")
		)
		(pad "EP61" smd circle
			(at 13.008356 26.134314 270)
			(size 0.4318 0.4318)
			(layers "F.Cu" "F.Mask" "F.Paste")
			(net "M_E_CPU0_SA_DQS_DP<8>")
		)
		(pad "EP63" smd circle
			(at 14.635988 26.134314 270)
			(size 0.4318 0.4318)
			(layers "F.Cu" "F.Mask" "F.Paste")
			(net "M_E_CPU0_SA_DQ<26>")
		)
		(pad "EP65" smd circle
			(at 16.263874 26.134314 270)
			(size 0.4318 0.4318)
			(layers "F.Cu" "F.Mask" "F.Paste")
			(net "M_E_CPU0_SA_DQ<23>")
		)
		(pad "EP67" smd circle
			(at 17.89176 26.134314 270)
			(size 0.4318 0.4318)
			(layers "F.Cu" "F.Mask" "F.Paste")
			(net "GND")
		)
		(pad "EP69" smd circle
			(at 19.519392 26.134314 270)
			(size 0.4318 0.4318)
			(layers "F.Cu" "F.Mask" "F.Paste")
			(net "GND")
		)
		(pad "EP71" smd circle
			(at 21.147278 26.134314 270)
			(size 0.4318 0.4318)
			(layers "F.Cu" "F.Mask" "F.Paste")
			(net "GND")
		)
		(pad "EP73" smd circle
			(at 22.77491 26.134314 270)
			(size 0.4318 0.4318)
			(layers "F.Cu" "F.Mask" "F.Paste")
			(net "M_E_CPU0_SA_DQ<6>")
		)
		(pad "EP75" smd circle
			(at 24.402796 26.134314 270)
			(size 0.4318 0.4318)
			(layers "F.Cu" "F.Mask" "F.Paste")
			(net "M_E_CPU0_SA_DQS_DN<0>")
		)
		(pad "EP77" smd circle
			(at 26.030682 26.134314 270)
			(size 0.4318 0.4318)
			(layers "F.Cu" "F.Mask" "F.Paste")
			(net "GND")
		)
		(pad "EP79" smd circle
			(at 27.658314 26.134314 270)
			(size 0.4318 0.4318)
			(layers "F.Cu" "F.Mask" "F.Paste")
			(net "M_E_CPU0_SA_DQ<2>")
		)
		(pad "EP81" smd circle
			(at 29.2862 26.134314 270)
			(size 0.4318 0.4318)
			(layers "F.Cu" "F.Mask" "F.Paste")
			(net "GND")
		)
		(pad "EP83" smd oval
			(at 30.914086 26.134314 315)
			(size 0.381 0.4826)
			(drill
				(offset 0 -0.0508)
			)
			(layers "F.Cu" "F.Mask" "F.Paste")
			(net "GND")
		)
		(pad "EP85" smd oval
			(at 32.541718 26.134314 315)
			(size 0.381 0.4826)
			(drill
				(offset 0 -0.0508)
			)
			(layers "F.Cu" "F.Mask" "F.Paste")
			(net "Net_689")
		)
		(pad "EP87" smd oval
			(at 34.169604 26.134314 315)
			(size 0.381 0.4826)
			(drill
				(offset 0 -0.0508)
			)
			(layers "F.Cu" "F.Mask" "F.Paste")
			(net "Net_660")
		)
		(pad "ER5" smd oval
			(at -34.169604 26.494486 225)
			(size 0.381 0.4826)
			(drill
				(offset 0 -0.0508)
			)
			(layers "F.Cu" "F.Mask" "F.Paste")
			(net "GND")
		)
		(pad "ER7" smd oval
			(at -32.541718 26.494486 225)
			(size 0.381 0.4826)
			(drill
				(offset 0 -0.0508)
			)
			(layers "F.Cu" "F.Mask" "F.Paste")
			(net "GND")
		)
		(pad "ER9" smd oval
			(at -30.914086 26.494486 225)
			(size 0.381 0.4826)
			(drill
				(offset 0 -0.0508)
			)
			(layers "F.Cu" "F.Mask" "F.Paste")
			(net "GND")
		)
		(pad "ER11" smd circle
			(at -29.2862 26.494486 270)
			(size 0.4318 0.4318)
			(layers "F.Cu" "F.Mask" "F.Paste")
			(net "M_F_CPU0_SB_DQ<22>")
		)
		(pad "ER13" smd circle
			(at -27.658314 26.494486 270)
			(size 0.4318 0.4318)
			(layers "F.Cu" "F.Mask" "F.Paste")
			(net "M_F_CPU0_SB_DQ<19>")
		)
		(pad "ER15" smd circle
			(at -26.030682 26.494486 270)
			(size 0.4318 0.4318)
			(layers "F.Cu" "F.Mask" "F.Paste")
			(net "GND")
		)
		(pad "ER17" smd circle
			(at -24.402796 26.494486 270)
			(size 0.4318 0.4318)
			(layers "F.Cu" "F.Mask" "F.Paste")
			(net "M_E_CPU0_SB_DQ<30>")
		)
		(pad "ER19" smd circle
			(at -22.77491 26.494486 270)
			(size 0.4318 0.4318)
			(layers "F.Cu" "F.Mask" "F.Paste")
			(net "M_E_CPU0_SB_DQ<27>")
		)
		(pad "ER21" smd circle
			(at -21.147278 26.494486 270)
			(size 0.4318 0.4318)
			(layers "F.Cu" "F.Mask" "F.Paste")
			(net "GND")
		)
		(pad "ER23" smd circle
			(at -19.519392 26.494486 270)
			(size 0.4318 0.4318)
			(layers "F.Cu" "F.Mask" "F.Paste")
			(net "M_E_CPU0_SB_DQ<22>")
		)
		(pad "ER25" smd circle
			(at -17.89176 26.494486 270)
			(size 0.4318 0.4318)
			(layers "F.Cu" "F.Mask" "F.Paste")
			(net "M_E_CPU0_SB_DQ<19>")
		)
		(pad "ER27" smd circle
			(at -16.263874 26.494486 270)
			(size 0.4318 0.4318)
			(layers "F.Cu" "F.Mask" "F.Paste")
			(net "GND")
		)
		(pad "ER29" smd circle
			(at -14.635988 26.494486 270)
			(size 0.4318 0.4318)
			(layers "F.Cu" "F.Mask" "F.Paste")
			(net "M_E_CPU0_SB_DQ<14>")
		)
		(pad "ER31" smd circle
			(at -13.008356 26.494486 270)
			(size 0.4318 0.4318)
			(layers "F.Cu" "F.Mask" "F.Paste")
			(net "M_E_CPU0_SB_DQ<11>")
		)
		(pad "ER33" smd circle
			(at -11.380724 26.494486 270)
			(size 0.4318 0.4318)
			(layers "F.Cu" "F.Mask" "F.Paste")
			(net "GND")
		)
		(pad "ER35" smd circle
			(at -9.752838 26.494486 270)
			(size 0.4318 0.4318)
			(layers "F.Cu" "F.Mask" "F.Paste")
			(net "M_E_CPU0_SB_CB<2>")
		)
		(pad "ER37" smd circle
			(at -8.124952 26.494486 270)
			(size 0.4318 0.4318)
			(layers "F.Cu" "F.Mask" "F.Paste")
			(net "M_E_CPU0_SB_CB<7>")
		)
		(pad "ER39" smd circle
			(at -6.49732 26.494486 270)
			(size 0.4318 0.4318)
			(layers "F.Cu" "F.Mask" "F.Paste")
			(net "GND")
		)
		(pad "ER41" smd circle
			(at -4.869434 26.494486 270)
			(size 0.4318 0.4318)
			(layers "F.Cu" "F.Mask" "F.Paste")
			(net "GND")
		)
		(pad "ER43" smd oval
			(at -3.241802 26.494486 270)
			(size 0.381 0.4826)
			(drill
				(offset 0 -0.0508)
			)
			(layers "F.Cu" "F.Mask" "F.Paste")
			(net "GND")
		)
		(pad "ER48" smd oval
			(at 2.427732 26.604468 270)
			(size 0.381 0.4826)
			(drill
				(offset 0 -0.0508)
			)
			(layers "F.Cu" "F.Mask" "F.Paste")
			(net "GND")
		)
		(pad "ER50" smd circle
			(at 4.055618 26.604468 270)
			(size 0.4318 0.4318)
			(layers "F.Cu" "F.Mask" "F.Paste")
			(net "GND")
		)
		(pad "ER52" smd circle
			(at 5.68325 26.604468 270)
			(size 0.4318 0.4318)
			(layers "F.Cu" "F.Mask" "F.Paste")
			(net "GND")
		)
		(pad "ER54" smd circle
			(at 7.311136 26.604468 270)
			(size 0.4318 0.4318)
			(layers "F.Cu" "F.Mask" "F.Paste")
			(net "M_E_CPU0_SA_CB<6>")
		)
		(pad "ER56" smd circle
			(at 8.939022 26.604468 270)
			(size 0.4318 0.4318)
			(layers "F.Cu" "F.Mask" "F.Paste")
			(net "M_E_CPU0_SA_CB<3>")
		)
		(pad "ER58" smd circle
			(at 10.566654 26.604468 270)
			(size 0.4318 0.4318)
			(layers "F.Cu" "F.Mask" "F.Paste")
			(net "GND")
		)
		(pad "ER60" smd circle
			(at 12.19454 26.604468 270)
			(size 0.4318 0.4318)
			(layers "F.Cu" "F.Mask" "F.Paste")
			(net "M_E_CPU0_SA_DQ<30>")
		)
		(pad "ER62" smd oval
			(at 13.822426 26.604468 270)
			(size 0.381 0.4826)
			(drill
				(offset 0 -0.0508)
			)
			(layers "F.Cu" "F.Mask" "F.Paste")
			(net "M_E_CPU0_SA_DQ<27>")
		)
		(pad "ER64" smd oval
			(at 15.450058 26.604468 270)
			(size 0.381 0.4826)
			(drill
				(offset 0 -0.0508)
			)
			(layers "F.Cu" "F.Mask" "F.Paste")
			(net "GND")
		)
		(pad "ER66" smd oval
			(at 17.07769 26.604468 270)
			(size 0.381 0.4826)
			(drill
				(offset 0 -0.0508)
			)
			(layers "F.Cu" "F.Mask" "F.Paste")
			(net "M_E_CPU0_SA_DQ<20>")
		)
		(pad "ER68" smd oval
			(at 18.705576 26.604468 270)
			(size 0.381 0.4826)
			(drill
				(offset 0 -0.0508)
			)
			(layers "F.Cu" "F.Mask" "F.Paste")
			(net "M_E_CPU0_SA_DQ<19>")
		)
		(pad "ER70" smd oval
			(at 20.333462 26.604468 270)
			(size 0.381 0.4826)
			(drill
				(offset 0 -0.0508)
			)
			(layers "F.Cu" "F.Mask" "F.Paste")
			(net "GND")
		)
		(pad "ER72" smd oval
			(at 21.961094 26.604468 270)
			(size 0.381 0.4826)
			(drill
				(offset 0 -0.0508)
			)
			(layers "F.Cu" "F.Mask" "F.Paste")
			(net "M_E_CPU0_SA_DQ<7>")
		)
		(pad "ER74" smd oval
			(at 23.58898 26.604468 270)
			(size 0.381 0.4826)
			(drill
				(offset 0 -0.0508)
			)
			(layers "F.Cu" "F.Mask" "F.Paste")
			(net "GND")
		)
		(pad "ER76" smd oval
			(at 25.216612 26.604468 270)
			(size 0.381 0.4826)
			(drill
				(offset 0 -0.0508)
			)
			(layers "F.Cu" "F.Mask" "F.Paste")
			(net "M_E_CPU0_SA_DQ<3>")
		)
		(pad "ER78" smd oval
			(at 26.844498 26.604468 270)
			(size 0.381 0.4826)
			(drill
				(offset 0 -0.0508)
			)
			(layers "F.Cu" "F.Mask" "F.Paste")
			(net "GND")
		)
		(pad "ER80" smd oval
			(at 28.472384 26.604468 270)
			(size 0.381 0.4826)
			(drill
				(offset 0 -0.0508)
			)
			(layers "F.Cu" "F.Mask" "F.Paste")
			(net "GND")
		)
		(pad "ER82" smd oval
			(at 30.100016 26.604468 315)
			(size 0.381 0.4826)
			(drill
				(offset 0 -0.0508)
			)
			(layers "F.Cu" "F.Mask" "F.Paste")
			(net "GND")
		)
		(pad "ER84" smd oval
			(at 31.727902 26.604468 315)
			(size 0.381 0.4826)
			(drill
				(offset 0 -0.0508)
			)
			(layers "F.Cu" "F.Mask" "F.Paste")
			(net "GND")
		)
		(pad "ER86" smd oval
			(at 33.355534 26.604468 315)
			(size 0.381 0.4826)
			(drill
				(offset 0 -0.0508)
			)
			(layers "F.Cu" "F.Mask" "F.Paste")
			(net "GND")
		)
		(pad "ET8" smd oval
			(at -31.727902 26.964132 225)
			(size 0.381 0.4826)
			(drill
				(offset 0 -0.0508)
			)
			(layers "F.Cu" "F.Mask" "F.Paste")
			(net "M_G_CPU0_SB_DQ<27>")
		)
		(pad "ET10" smd oval
			(at -30.100016 26.964132 225)
			(size 0.381 0.4826)
			(drill
				(offset 0 -0.0508)
			)
			(layers "F.Cu" "F.Mask" "F.Paste")
			(net "GND")
		)
		(pad "ET12" smd oval
			(at -28.472384 26.964132 270)
			(size 0.381 0.4826)
			(drill
				(offset 0 -0.0508)
			)
			(layers "F.Cu" "F.Mask" "F.Paste")
			(net "M_F_CPU0_SB_DQS_DN<7>")
		)
		(pad "ET14" smd oval
			(at -26.844498 26.964132 270)
			(size 0.381 0.4826)
			(drill
				(offset 0 -0.0508)
			)
			(layers "F.Cu" "F.Mask" "F.Paste")
			(net "GND")
		)
		(pad "ET16" smd oval
			(at -25.216612 26.964132 270)
			(size 0.381 0.4826)
			(drill
				(offset 0 -0.0508)
			)
			(layers "F.Cu" "F.Mask" "F.Paste")
			(net "GND")
		)
		(pad "ET18" smd oval
			(at -23.58898 26.964132 270)
			(size 0.381 0.4826)
			(drill
				(offset 0 -0.0508)
			)
			(layers "F.Cu" "F.Mask" "F.Paste")
			(net "M_E_CPU0_SB_DQS_DN<8>")
		)
		(pad "ET20" smd oval
			(at -21.961094 26.964132 270)
			(size 0.381 0.4826)
			(drill
				(offset 0 -0.0508)
			)
			(layers "F.Cu" "F.Mask" "F.Paste")
			(net "GND")
		)
		(pad "ET22" smd oval
			(at -20.333462 26.964132 270)
			(size 0.381 0.4826)
			(drill
				(offset 0 -0.0508)
			)
			(layers "F.Cu" "F.Mask" "F.Paste")
			(net "GND")
		)
		(pad "ET24" smd oval
			(at -18.705576 26.964132 270)
			(size 0.381 0.4826)
			(drill
				(offset 0 -0.0508)
			)
			(layers "F.Cu" "F.Mask" "F.Paste")
			(net "M_E_CPU0_SB_DQS_DN<7>")
		)
		(pad "ET26" smd oval
			(at -17.07769 26.964132 270)
			(size 0.381 0.4826)
			(drill
				(offset 0 -0.0508)
			)
			(layers "F.Cu" "F.Mask" "F.Paste")
			(net "GND")
		)
		(pad "ET28" smd oval
			(at -15.450058 26.964132 270)
			(size 0.381 0.4826)
			(drill
				(offset 0 -0.0508)
			)
			(layers "F.Cu" "F.Mask" "F.Paste")
			(net "GND")
		)
		(pad "ET30" smd oval
			(at -13.822426 26.964132 270)
			(size 0.381 0.4826)
			(drill
				(offset 0 -0.0508)
			)
			(layers "F.Cu" "F.Mask" "F.Paste")
			(net "M_E_CPU0_SB_DQS_DN<6>")
		)
		(pad "ET32" smd oval
			(at -12.19454 26.964132 270)
			(size 0.381 0.4826)
			(drill
				(offset 0 -0.0508)
			)
			(layers "F.Cu" "F.Mask" "F.Paste")
			(net "GND")
		)
		(pad "ET34" smd oval
			(at -10.566654 26.964132 270)
			(size 0.381 0.4826)
			(drill
				(offset 0 -0.0508)
			)
			(layers "F.Cu" "F.Mask" "F.Paste")
			(net "GND")
		)
		(pad "ET36" smd oval
			(at -8.939022 26.964132 270)
			(size 0.381 0.4826)
			(drill
				(offset 0 -0.0508)
			)
			(layers "F.Cu" "F.Mask" "F.Paste")
			(net "M_E_CPU0_SB_DQS_DN<4>")
		)
		(pad "ET38" smd oval
			(at -7.311136 26.964132 270)
			(size 0.381 0.4826)
			(drill
				(offset 0 -0.0508)
			)
			(layers "F.Cu" "F.Mask" "F.Paste")
			(net "GND")
		)
		(pad "ET40" smd oval
			(at -5.68325 26.964132 270)
			(size 0.381 0.4826)
			(drill
				(offset 0 -0.0508)
			)
			(layers "F.Cu" "F.Mask" "F.Paste")
			(net "M_E_CPU0_SB_CS_N<1>")
		)
		(pad "ET42" smd oval
			(at -4.055618 26.964132 270)
			(size 0.381 0.4826)
			(drill
				(offset 0 -0.0508)
			)
			(layers "F.Cu" "F.Mask" "F.Paste")
			(net "M_E_CPU0_SB_CA<5>")
		)
		(pad "ET49" smd oval
			(at 3.241802 27.074114 270)
			(size 0.381 0.4826)
			(drill
				(offset 0 -0.0508)
			)
			(layers "F.Cu" "F.Mask" "F.Paste")
			(net "M_E_CPU0_SA_CA<1>")
		)
		(pad "ET51" smd oval
			(at 4.869434 27.074114 270)
			(size 0.381 0.4826)
			(drill
				(offset 0 -0.0508)
			)
			(layers "F.Cu" "F.Mask" "F.Paste")
			(net "M_E_CPU0_SA_CS_N<1>")
		)
		(pad "ET53" smd oval
			(at 6.49732 27.074114 270)
			(size 0.381 0.4826)
			(drill
				(offset 0 -0.0508)
			)
			(layers "F.Cu" "F.Mask" "F.Paste")
			(net "GND")
		)
		(pad "ET55" smd oval
			(at 8.124952 27.074114 270)
			(size 0.381 0.4826)
			(drill
				(offset 0 -0.0508)
			)
			(layers "F.Cu" "F.Mask" "F.Paste")
			(net "M_E_CPU0_SA_DQS_DN<9>")
		)
		(pad "ET57" smd oval
			(at 9.752838 27.074114 270)
			(size 0.381 0.4826)
			(drill
				(offset 0 -0.0508)
			)
			(layers "F.Cu" "F.Mask" "F.Paste")
			(net "GND")
		)
		(pad "ET59" smd oval
			(at 11.380724 27.074114 270)
			(size 0.381 0.4826)
			(drill
				(offset 0 -0.0508)
			)
			(layers "F.Cu" "F.Mask" "F.Paste")
			(net "GND")
		)
		(pad "ET61" smd oval
			(at 13.008356 27.074114 270)
			(size 0.381 0.4826)
			(drill
				(offset 0 -0.0508)
			)
			(layers "F.Cu" "F.Mask" "F.Paste")
			(net "M_E_CPU0_SA_DQS_DN<8>")
		)
		(pad "F4" smd oval
			(at -34.98342 -24.724868 135)
			(size 0.381 0.4826)
			(drill
				(offset 0 -0.0508)
			)
			(layers "F.Cu" "F.Mask" "F.Paste")
			(net "GND")
		)
		(pad "F6" smd oval
			(at -33.355534 -24.724868 135)
			(size 0.381 0.4826)
			(drill
				(offset 0 -0.0508)
			)
			(layers "F.Cu" "F.Mask" "F.Paste")
			(net "GND")
		)
		(pad "F8" smd circle
			(at -31.727902 -24.724868 270)
			(size 0.4318 0.4318)
			(layers "F.Cu" "F.Mask" "F.Paste")
			(net "M_A_CPU0_SB_DQ<30>")
		)
		(pad "F10" smd circle
			(at -30.100016 -24.724868 270)
			(size 0.4318 0.4318)
			(layers "F.Cu" "F.Mask" "F.Paste")
			(net "M_A_CPU0_SB_DQ<27>")
		)
		(pad "F12" smd circle
			(at -28.472384 -24.724868 270)
			(size 0.4318 0.4318)
			(layers "F.Cu" "F.Mask" "F.Paste")
			(net "GND")
		)
		(pad "F14" smd circle
			(at -26.844498 -24.724868 270)
			(size 0.4318 0.4318)
			(layers "F.Cu" "F.Mask" "F.Paste")
			(net "M_B_CPU0_SB_DQ<31>")
		)
		(pad "F16" smd circle
			(at -25.216612 -24.724868 270)
			(size 0.4318 0.4318)
			(layers "F.Cu" "F.Mask" "F.Paste")
			(net "M_B_CPU0_SB_DQ<27>")
		)
		(pad "F18" smd circle
			(at -23.58898 -24.724868 270)
			(size 0.4318 0.4318)
			(layers "F.Cu" "F.Mask" "F.Paste")
			(net "GND")
		)
		(pad "F20" smd circle
			(at -21.961094 -24.724868 270)
			(size 0.4318 0.4318)
			(layers "F.Cu" "F.Mask" "F.Paste")
			(net "M_A_CPU0_SB_DQ<22>")
		)
		(pad "F22" smd circle
			(at -20.333462 -24.724868 270)
			(size 0.4318 0.4318)
			(layers "F.Cu" "F.Mask" "F.Paste")
			(net "M_A_CPU0_SB_DQ<19>")
		)
		(pad "F24" smd circle
			(at -18.705576 -24.724868 270)
			(size 0.4318 0.4318)
			(layers "F.Cu" "F.Mask" "F.Paste")
			(net "GND")
		)
		(pad "F26" smd circle
			(at -17.07769 -24.724868 270)
			(size 0.4318 0.4318)
			(layers "F.Cu" "F.Mask" "F.Paste")
			(net "M_A_CPU0_SB_DQ<14>")
		)
		(pad "F28" smd circle
			(at -15.450058 -24.724868 270)
			(size 0.4318 0.4318)
			(layers "F.Cu" "F.Mask" "F.Paste")
			(net "M_A_CPU0_SB_DQ<11>")
		)
		(pad "F30" smd circle
			(at -13.822426 -24.724868 270)
			(size 0.4318 0.4318)
			(layers "F.Cu" "F.Mask" "F.Paste")
			(net "GND")
		)
		(pad "F32" smd circle
			(at -12.19454 -24.724868 270)
			(size 0.4318 0.4318)
			(layers "F.Cu" "F.Mask" "F.Paste")
			(net "M_A_CPU0_SB_CB<2>")
		)
		(pad "F34" smd circle
			(at -10.566654 -24.724868 270)
			(size 0.4318 0.4318)
			(layers "F.Cu" "F.Mask" "F.Paste")
			(net "M_A_CPU0_SB_CB<7>")
		)
		(pad "F36" smd circle
			(at -8.939022 -24.724868 270)
			(size 0.4318 0.4318)
			(layers "F.Cu" "F.Mask" "F.Paste")
			(net "GND")
		)
		(pad "F38" smd circle
			(at -7.311136 -24.724868 270)
			(size 0.4318 0.4318)
			(layers "F.Cu" "F.Mask" "F.Paste")
			(net "M_A_CPU0_SB_CS_N<2>")
		)
		(pad "F40" smd circle
			(at -5.68325 -24.724868 270)
			(size 0.4318 0.4318)
			(layers "F.Cu" "F.Mask" "F.Paste")
			(net "M_A_CPU0_SB_CA<5>")
		)
		(pad "F42" smd circle
			(at -4.055618 -24.724868 270)
			(size 0.4318 0.4318)
			(layers "F.Cu" "F.Mask" "F.Paste")
			(net "GND")
		)
		(pad "F44" smd circle
			(at -2.427732 -24.724868 270)
			(size 0.4318 0.4318)
			(layers "F.Cu" "F.Mask" "F.Paste")
			(net "M_A_CPU0_SB_CA<1>")
		)
		(pad "F47" smd circle
			(at 1.613916 -24.614886 270)
			(size 0.4318 0.4318)
			(layers "F.Cu" "F.Mask" "F.Paste")
			(net "PWRGD_DRAMPWRGD_CPU0_CD_LVC1_R")
		)
		(pad "F49" smd circle
			(at 3.241802 -24.614886 270)
			(size 0.4318 0.4318)
			(layers "F.Cu" "F.Mask" "F.Paste")
			(net "GND")
		)
		(pad "F51" smd circle
			(at 4.869434 -24.614886 270)
			(size 0.4318 0.4318)
			(layers "F.Cu" "F.Mask" "F.Paste")
			(net "M_A_CPU0_SA_CA<3>")
		)
		(pad "F53" smd circle
			(at 6.49732 -24.614886 270)
			(size 0.4318 0.4318)
			(layers "F.Cu" "F.Mask" "F.Paste")
			(net "M_A_CPU0_SA_CS_N<3>")
		)
		(pad "F55" smd circle
			(at 8.124952 -24.614886 270)
			(size 0.4318 0.4318)
			(layers "F.Cu" "F.Mask" "F.Paste")
			(net "GND")
		)
		(pad "F57" smd circle
			(at 9.752838 -24.614886 270)
			(size 0.4318 0.4318)
			(layers "F.Cu" "F.Mask" "F.Paste")
			(net "M_A_CPU0_SA_CB<6>")
		)
		(pad "F59" smd circle
			(at 11.380724 -24.614886 270)
			(size 0.4318 0.4318)
			(layers "F.Cu" "F.Mask" "F.Paste")
			(net "M_A_CPU0_SA_CB<3>")
		)
		(pad "F61" smd circle
			(at 13.008356 -24.614886 270)
			(size 0.4318 0.4318)
			(layers "F.Cu" "F.Mask" "F.Paste")
			(net "GND")
		)
		(pad "F63" smd circle
			(at 14.635988 -24.614886 270)
			(size 0.4318 0.4318)
			(layers "F.Cu" "F.Mask" "F.Paste")
			(net "M_A_CPU0_SA_DQ<30>")
		)
		(pad "F65" smd circle
			(at 16.263874 -24.614886 270)
			(size 0.4318 0.4318)
			(layers "F.Cu" "F.Mask" "F.Paste")
			(net "M_A_CPU0_SA_DQ<27>")
		)
		(pad "F67" smd circle
			(at 17.89176 -24.614886 270)
			(size 0.4318 0.4318)
			(layers "F.Cu" "F.Mask" "F.Paste")
			(net "GND")
		)
		(pad "F69" smd circle
			(at 19.519392 -24.614886 270)
			(size 0.4318 0.4318)
			(layers "F.Cu" "F.Mask" "F.Paste")
			(net "M_A_CPU0_SA_DQ<22>")
		)
		(pad "F71" smd circle
			(at 21.147278 -24.614886 270)
			(size 0.4318 0.4318)
			(layers "F.Cu" "F.Mask" "F.Paste")
			(net "M_A_CPU0_SA_DQ<19>")
		)
		(pad "F73" smd circle
			(at 22.77491 -24.614886 270)
			(size 0.4318 0.4318)
			(layers "F.Cu" "F.Mask" "F.Paste")
			(net "GND")
		)
		(pad "F75" smd circle
			(at 24.402796 -24.614886 270)
			(size 0.4318 0.4318)
			(layers "F.Cu" "F.Mask" "F.Paste")
			(net "M_A_CPU0_SA_DQ<7>")
		)
		(pad "F77" smd circle
			(at 26.030682 -24.614886 270)
			(size 0.4318 0.4318)
			(layers "F.Cu" "F.Mask" "F.Paste")
			(net "M_A_CPU0_SA_DQS_DP<5>")
		)
		(pad "F79" smd circle
			(at 27.658314 -24.614886 270)
			(size 0.4318 0.4318)
			(layers "F.Cu" "F.Mask" "F.Paste")
			(net "GND")
		)
		(pad "F81" smd circle
			(at 29.2862 -24.614886 270)
			(size 0.4318 0.4318)
			(layers "F.Cu" "F.Mask" "F.Paste")
			(net "UPI_CPU1_CPU0_P2P2_DP<22>")
		)
		(pad "F83" smd circle
			(at 30.914086 -24.614886 270)
			(size 0.4318 0.4318)
			(layers "F.Cu" "F.Mask" "F.Paste")
			(net "GND")
		)
		(pad "F85" smd circle
			(at 32.541718 -24.614886 270)
			(size 0.4318 0.4318)
			(layers "F.Cu" "F.Mask" "F.Paste")
			(net "UPI_CPU0_CPU1_P2P2_DP<22>")
		)
		(pad "F87" smd oval
			(at 34.169604 -24.614886 45)
			(size 0.381 0.4826)
			(drill
				(offset 0 -0.0508)
			)
			(layers "F.Cu" "F.Mask" "F.Paste")
			(net "UPI_CPU0_CPU1_P2P2_DN<20>")
		)
		(pad "F89" smd oval
			(at 35.797236 -24.614886 45)
			(size 0.381 0.4826)
			(drill
				(offset 0 -0.0508)
			)
			(layers "F.Cu" "F.Mask" "F.Paste")
			(net "GND")
		)
		(pad "G3" smd oval
			(at -35.797236 -24.254714 135)
			(size 0.381 0.4826)
			(drill
				(offset 0 -0.0508)
			)
			(layers "F.Cu" "F.Mask" "F.Paste")
			(net "GND")
		)
		(pad "G5" smd oval
			(at -34.169604 -24.254714 135)
			(size 0.381 0.4826)
			(drill
				(offset 0 -0.0508)
			)
			(layers "F.Cu" "F.Mask" "F.Paste")
			(net "NC_XTAL_CPU0_25M_IN")
		)
		(pad "G7" smd circle
			(at -32.541718 -24.254714 270)
			(size 0.4318 0.4318)
			(layers "F.Cu" "F.Mask" "F.Paste")
			(net "GND")
		)
		(pad "G9" smd circle
			(at -30.914086 -24.254714 270)
			(size 0.4318 0.4318)
			(layers "F.Cu" "F.Mask" "F.Paste")
			(net "M_A_CPU0_SB_DQS_DN<8>")
		)
		(pad "G11" smd circle
			(at -29.2862 -24.254714 270)
			(size 0.4318 0.4318)
			(layers "F.Cu" "F.Mask" "F.Paste")
			(net "GND")
		)
		(pad "G13" smd circle
			(at -27.658314 -24.254714 270)
			(size 0.4318 0.4318)
			(layers "F.Cu" "F.Mask" "F.Paste")
			(net "GND")
		)
		(pad "G15" smd circle
			(at -26.030682 -24.254714 270)
			(size 0.4318 0.4318)
			(layers "F.Cu" "F.Mask" "F.Paste")
			(net "M_B_CPU0_SB_DQS_DP<8>")
		)
		(pad "G17" smd circle
			(at -24.402796 -24.254714 270)
			(size 0.4318 0.4318)
			(layers "F.Cu" "F.Mask" "F.Paste")
			(net "GND")
		)
		(pad "G19" smd circle
			(at -22.77491 -24.254714 270)
			(size 0.4318 0.4318)
			(layers "F.Cu" "F.Mask" "F.Paste")
			(net "GND")
		)
		(pad "G21" smd circle
			(at -21.147278 -24.254714 270)
			(size 0.4318 0.4318)
			(layers "F.Cu" "F.Mask" "F.Paste")
			(net "M_A_CPU0_SB_DQS_DN<7>")
		)
		(pad "G23" smd circle
			(at -19.519392 -24.254714 270)
			(size 0.4318 0.4318)
			(layers "F.Cu" "F.Mask" "F.Paste")
			(net "GND")
		)
		(pad "G25" smd circle
			(at -17.89176 -24.254714 270)
			(size 0.4318 0.4318)
			(layers "F.Cu" "F.Mask" "F.Paste")
			(net "GND")
		)
		(pad "G27" smd circle
			(at -16.263874 -24.254714 270)
			(size 0.4318 0.4318)
			(layers "F.Cu" "F.Mask" "F.Paste")
			(net "M_A_CPU0_SB_DQS_DN<6>")
		)
		(pad "G29" smd circle
			(at -14.635988 -24.254714 270)
			(size 0.4318 0.4318)
			(layers "F.Cu" "F.Mask" "F.Paste")
			(net "GND")
		)
		(pad "G31" smd circle
			(at -13.008356 -24.254714 270)
			(size 0.4318 0.4318)
			(layers "F.Cu" "F.Mask" "F.Paste")
			(net "GND")
		)
		(pad "G33" smd circle
			(at -11.380724 -24.254714 270)
			(size 0.4318 0.4318)
			(layers "F.Cu" "F.Mask" "F.Paste")
			(net "M_A_CPU0_SB_DQS_DN<4>")
		)
		(pad "G35" smd circle
			(at -9.752838 -24.254714 270)
			(size 0.4318 0.4318)
			(layers "F.Cu" "F.Mask" "F.Paste")
			(net "GND")
		)
		(pad "G37" smd circle
			(at -8.124952 -24.254714 270)
			(size 0.4318 0.4318)
			(layers "F.Cu" "F.Mask" "F.Paste")
			(net "GND")
		)
		(pad "G39" smd circle
			(at -6.49732 -24.254714 270)
			(size 0.4318 0.4318)
			(layers "F.Cu" "F.Mask" "F.Paste")
			(net "M_A_CPU0_SB_PAR")
		)
		(pad "G41" smd circle
			(at -4.869434 -24.254714 270)
			(size 0.4318 0.4318)
			(layers "F.Cu" "F.Mask" "F.Paste")
			(net "GND")
		)
		(pad "G43" smd circle
			(at -3.241802 -24.254714 270)
			(size 0.4318 0.4318)
			(layers "F.Cu" "F.Mask" "F.Paste")
			(net "GND")
		)
		(pad "G45" smd circle
			(at -1.613916 -24.254714 270)
			(size 0.4318 0.4318)
			(layers "F.Cu" "F.Mask" "F.Paste")
			(net "M_A_CPU0_CLK_DN<1>")
		)
		(pad "G48" smd circle
			(at 2.427732 -24.144986 270)
			(size 0.4318 0.4318)
			(layers "F.Cu" "F.Mask" "F.Paste")
			(net "GND")
		)
		(pad "G50" smd circle
			(at 4.055618 -24.144986 270)
			(size 0.4318 0.4318)
			(layers "F.Cu" "F.Mask" "F.Paste")
			(net "GND")
		)
		(pad "G52" smd circle
			(at 5.68325 -24.144986 270)
			(size 0.4318 0.4318)
			(layers "F.Cu" "F.Mask" "F.Paste")
			(net "M_A_CPU0_SA_CA<1>")
		)
		(pad "G54" smd circle
			(at 7.311136 -24.144986 270)
			(size 0.4318 0.4318)
			(layers "F.Cu" "F.Mask" "F.Paste")
			(net "GND")
		)
		(pad "G56" smd circle
			(at 8.939022 -24.144986 270)
			(size 0.4318 0.4318)
			(layers "F.Cu" "F.Mask" "F.Paste")
			(net "GND")
		)
		(pad "G58" smd circle
			(at 10.566654 -24.144986 270)
			(size 0.4318 0.4318)
			(layers "F.Cu" "F.Mask" "F.Paste")
			(net "M_A_CPU0_SA_DQS_DN<9>")
		)
		(pad "G60" smd circle
			(at 12.19454 -24.144986 270)
			(size 0.4318 0.4318)
			(layers "F.Cu" "F.Mask" "F.Paste")
			(net "GND")
		)
		(pad "G62" smd circle
			(at 13.822426 -24.144986 270)
			(size 0.4318 0.4318)
			(layers "F.Cu" "F.Mask" "F.Paste")
			(net "GND")
		)
		(pad "G64" smd circle
			(at 15.450058 -24.144986 270)
			(size 0.4318 0.4318)
			(layers "F.Cu" "F.Mask" "F.Paste")
			(net "M_A_CPU0_SA_DQS_DN<8>")
		)
		(pad "G66" smd circle
			(at 17.07769 -24.144986 270)
			(size 0.4318 0.4318)
			(layers "F.Cu" "F.Mask" "F.Paste")
			(net "GND")
		)
		(pad "G68" smd circle
			(at 18.705576 -24.144986 270)
			(size 0.4318 0.4318)
			(layers "F.Cu" "F.Mask" "F.Paste")
			(net "GND")
		)
		(pad "G70" smd circle
			(at 20.333462 -24.144986 270)
			(size 0.4318 0.4318)
			(layers "F.Cu" "F.Mask" "F.Paste")
			(net "M_A_CPU0_SA_DQS_DN<7>")
		)
		(pad "G72" smd circle
			(at 21.961094 -24.144986 270)
			(size 0.4318 0.4318)
			(layers "F.Cu" "F.Mask" "F.Paste")
			(net "GND")
		)
		(pad "G74" smd circle
			(at 23.58898 -24.144986 270)
			(size 0.4318 0.4318)
			(layers "F.Cu" "F.Mask" "F.Paste")
			(net "GND")
		)
		(pad "G76" smd circle
			(at 25.216612 -24.144986 270)
			(size 0.4318 0.4318)
			(layers "F.Cu" "F.Mask" "F.Paste")
			(net "M_A_CPU0_SA_DQ<6>")
		)
		(pad "G78" smd circle
			(at 26.844498 -24.144986 270)
			(size 0.4318 0.4318)
			(layers "F.Cu" "F.Mask" "F.Paste")
			(net "M_A_CPU0_SA_DQ<3>")
		)
		(pad "G80" smd circle
			(at 28.472384 -24.144986 270)
			(size 0.4318 0.4318)
			(layers "F.Cu" "F.Mask" "F.Paste")
			(net "UPI_CPU1_CPU0_P2P2_DP<23>")
		)
		(pad "G82" smd circle
			(at 30.100016 -24.144986 270)
			(size 0.4318 0.4318)
			(layers "F.Cu" "F.Mask" "F.Paste")
			(net "UPI_CPU1_CPU0_P2P2_DN<21>")
		)
		(pad "G84" smd circle
			(at 31.727902 -24.144986 270)
			(size 0.4318 0.4318)
			(layers "F.Cu" "F.Mask" "F.Paste")
			(net "GND")
		)
		(pad "G86" smd circle
			(at 33.355534 -24.144986 270)
			(size 0.4318 0.4318)
			(layers "F.Cu" "F.Mask" "F.Paste")
			(net "UPI_CPU0_CPU1_P2P2_DP<19>")
		)
		(pad "G88" smd oval
			(at 34.98342 -24.144986 45)
			(size 0.381 0.4826)
			(drill
				(offset 0 -0.0508)
			)
			(layers "F.Cu" "F.Mask" "F.Paste")
			(net "GND")
		)
		(pad "G90" smd oval
			(at 36.611306 -24.144986 45)
			(size 0.381 0.4826)
			(drill
				(offset 0 -0.0508)
			)
			(layers "F.Cu" "F.Mask" "F.Paste")
			(net "GND")
		)
		(pad "H2" smd oval
			(at -36.611306 -23.784814 135)
			(size 0.381 0.4826)
			(drill
				(offset 0 -0.0508)
			)
			(layers "F.Cu" "F.Mask" "F.Paste")
			(net "GND")
		)
		(pad "H4" smd oval
			(at -34.98342 -23.784814 135)
			(size 0.381 0.4826)
			(drill
				(offset 0 -0.0508)
			)
			(layers "F.Cu" "F.Mask" "F.Paste")
			(net "GND")
		)
		(pad "H6" smd circle
			(at -33.355534 -23.784814 270)
			(size 0.4318 0.4318)
			(layers "F.Cu" "F.Mask" "F.Paste")
			(net "GND")
		)
		(pad "H8" smd circle
			(at -31.727902 -23.784814 270)
			(size 0.4318 0.4318)
			(layers "F.Cu" "F.Mask" "F.Paste")
			(net "GND")
		)
		(pad "H10" smd circle
			(at -30.100016 -23.784814 270)
			(size 0.4318 0.4318)
			(layers "F.Cu" "F.Mask" "F.Paste")
			(net "GND")
		)
		(pad "H12" smd circle
			(at -28.472384 -23.784814 270)
			(size 0.4318 0.4318)
			(layers "F.Cu" "F.Mask" "F.Paste")
			(net "TP_CPU0_A0_DEBUG_EN")
		)
		(pad "H14" smd circle
			(at -26.844498 -23.784814 270)
			(size 0.4318 0.4318)
			(layers "F.Cu" "F.Mask" "F.Paste")
			(net "GND")
		)
		(pad "H16" smd circle
			(at -25.216612 -23.784814 270)
			(size 0.4318 0.4318)
			(layers "F.Cu" "F.Mask" "F.Paste")
			(net "GND")
		)
		(pad "H18" smd circle
			(at -23.58898 -23.784814 270)
			(size 0.4318 0.4318)
			(layers "F.Cu" "F.Mask" "F.Paste")
			(net "M_B_CPU0_SB_DQS_DN<2>")
		)
		(pad "H20" smd circle
			(at -21.961094 -23.784814 270)
			(size 0.4318 0.4318)
			(layers "F.Cu" "F.Mask" "F.Paste")
			(net "GND")
		)
		(pad "H22" smd circle
			(at -20.333462 -23.784814 270)
			(size 0.4318 0.4318)
			(layers "F.Cu" "F.Mask" "F.Paste")
			(net "GND")
		)
		(pad "H24" smd circle
			(at -18.705576 -23.784814 270)
			(size 0.4318 0.4318)
			(layers "F.Cu" "F.Mask" "F.Paste")
			(net "M_B_CPU0_SB_DQS_DN<1>")
		)
		(pad "H26" smd circle
			(at -17.07769 -23.784814 270)
			(size 0.4318 0.4318)
			(layers "F.Cu" "F.Mask" "F.Paste")
			(net "GND")
		)
		(pad "H28" smd circle
			(at -15.450058 -23.784814 270)
			(size 0.4318 0.4318)
			(layers "F.Cu" "F.Mask" "F.Paste")
			(net "GND")
		)
		(pad "H30" smd circle
			(at -13.822426 -23.784814 270)
			(size 0.4318 0.4318)
			(layers "F.Cu" "F.Mask" "F.Paste")
			(net "M_A_CPU0_SB_DQS_DN<0>")
		)
		(pad "H32" smd circle
			(at -12.19454 -23.784814 270)
			(size 0.4318 0.4318)
			(layers "F.Cu" "F.Mask" "F.Paste")
			(net "GND")
		)
		(pad "H34" smd circle
			(at -10.566654 -23.784814 270)
			(size 0.4318 0.4318)
			(layers "F.Cu" "F.Mask" "F.Paste")
			(net "GND")
		)
		(pad "H36" smd circle
			(at -8.939022 -23.784814 270)
			(size 0.4318 0.4318)
			(layers "F.Cu" "F.Mask" "F.Paste")
			(net "M_B_CPU0_SB_DQS_DP<9>")
		)
		(pad "H38" smd circle
			(at -7.311136 -23.784814 270)
			(size 0.4318 0.4318)
			(layers "F.Cu" "F.Mask" "F.Paste")
			(net "GND")
		)
		(pad "H40" smd circle
			(at -5.68325 -23.784814 270)
			(size 0.4318 0.4318)
			(layers "F.Cu" "F.Mask" "F.Paste")
			(net "GND")
		)
		(pad "H42" smd circle
			(at -4.055618 -23.784814 270)
			(size 0.4318 0.4318)
			(layers "F.Cu" "F.Mask" "F.Paste")
			(net "M_B_CPU0_SB_CA<6>")
		)
		(pad "H44" smd circle
			(at -2.427732 -23.784814 270)
			(size 0.4318 0.4318)
			(layers "F.Cu" "F.Mask" "F.Paste")
			(net "GND")
		)
		(pad "H47" smd circle
			(at 1.613916 -23.675086 270)
			(size 0.4318 0.4318)
			(layers "F.Cu" "F.Mask" "F.Paste")
			(net "GND")
		)
		(pad "H49" smd circle
			(at 3.241802 -23.675086 270)
			(size 0.4318 0.4318)
			(layers "F.Cu" "F.Mask" "F.Paste")
			(net "M_B_CPU0_SA_CA<0>")
		)
		(pad "H51" smd circle
			(at 4.869434 -23.675086 270)
			(size 0.4318 0.4318)
			(layers "F.Cu" "F.Mask" "F.Paste")
			(net "GND")
		)
		(pad "H53" smd circle
			(at 6.49732 -23.675086 270)
			(size 0.4318 0.4318)
			(layers "F.Cu" "F.Mask" "F.Paste")
			(net "GND")
		)
		(pad "H55" smd circle
			(at 8.124952 -23.675086 270)
			(size 0.4318 0.4318)
			(layers "F.Cu" "F.Mask" "F.Paste")
			(net "M_B_CPU0_SA_DQS_DN<4>")
		)
		(pad "H57" smd circle
			(at 9.752838 -23.675086 270)
			(size 0.4318 0.4318)
			(layers "F.Cu" "F.Mask" "F.Paste")
			(net "GND")
		)
		(pad "H59" smd circle
			(at 11.380724 -23.675086 270)
			(size 0.4318 0.4318)
			(layers "F.Cu" "F.Mask" "F.Paste")
			(net "GND")
		)
		(pad "H61" smd circle
			(at 13.008356 -23.675086 270)
			(size 0.4318 0.4318)
			(layers "F.Cu" "F.Mask" "F.Paste")
			(net "M_B_CPU0_SA_DQS_DN<2>")
		)
		(pad "H63" smd circle
			(at 14.635988 -23.675086 270)
			(size 0.4318 0.4318)
			(layers "F.Cu" "F.Mask" "F.Paste")
			(net "GND")
		)
		(pad "H65" smd circle
			(at 16.263874 -23.675086 270)
			(size 0.4318 0.4318)
			(layers "F.Cu" "F.Mask" "F.Paste")
			(net "GND")
		)
		(pad "H67" smd circle
			(at 17.89176 -23.675086 270)
			(size 0.4318 0.4318)
			(layers "F.Cu" "F.Mask" "F.Paste")
			(net "M_A_CPU0_SA_DQS_DN<1>")
		)
		(pad "H69" smd circle
			(at 19.519392 -23.675086 270)
			(size 0.4318 0.4318)
			(layers "F.Cu" "F.Mask" "F.Paste")
			(net "GND")
		)
		(pad "H71" smd circle
			(at 21.147278 -23.675086 270)
			(size 0.4318 0.4318)
			(layers "F.Cu" "F.Mask" "F.Paste")
			(net "GND")
		)
		(pad "H73" smd circle
			(at 22.77491 -23.675086 270)
			(size 0.4318 0.4318)
			(layers "F.Cu" "F.Mask" "F.Paste")
			(net "M_B_CPU0_SA_DQS_DN<0>")
		)
		(pad "H75" smd circle
			(at 24.402796 -23.675086 270)
			(size 0.4318 0.4318)
			(layers "F.Cu" "F.Mask" "F.Paste")
			(net "GND")
		)
		(pad "H77" smd circle
			(at 26.030682 -23.675086 270)
			(size 0.4318 0.4318)
			(layers "F.Cu" "F.Mask" "F.Paste")
			(net "M_A_CPU0_SA_DQS_DN<5>")
		)
		(pad "H79" smd circle
			(at 27.658314 -23.675086 270)
			(size 0.4318 0.4318)
			(layers "F.Cu" "F.Mask" "F.Paste")
			(net "GND")
		)
		(pad "H81" smd circle
			(at 29.2862 -23.675086 270)
			(size 0.4318 0.4318)
			(layers "F.Cu" "F.Mask" "F.Paste")
			(net "GND")
		)
		(pad "H83" smd circle
			(at 30.914086 -23.675086 270)
			(size 0.4318 0.4318)
			(layers "F.Cu" "F.Mask" "F.Paste")
			(net "UPI_CPU1_CPU0_P2P2_DP<21>")
		)
		(pad "H85" smd circle
			(at 32.541718 -23.675086 270)
			(size 0.4318 0.4318)
			(layers "F.Cu" "F.Mask" "F.Paste")
			(net "UPI_CPU0_CPU1_P2P2_DN<19>")
		)
		(pad "H87" smd circle
			(at 34.169604 -23.675086 270)
			(size 0.4318 0.4318)
			(layers "F.Cu" "F.Mask" "F.Paste")
			(net "UPI_CPU0_CPU1_P2P2_DP<20>")
		)
		(pad "H89" smd oval
			(at 35.797236 -23.675086 45)
			(size 0.381 0.4826)
			(drill
				(offset 0 -0.0508)
			)
			(layers "F.Cu" "F.Mask" "F.Paste")
			(net "PVCCFA_EHV_FIVRA_CPU0")
		)
		(pad "J3" smd oval
			(at -35.797236 -23.314914 135)
			(size 0.381 0.4826)
			(drill
				(offset 0 -0.0508)
			)
			(layers "F.Cu" "F.Mask" "F.Paste")
			(net "UPI_CPU0_CPU1_P0P1_DP<0>")
		)
		(pad "J5" smd circle
			(at -34.169604 -23.314914 270)
			(size 0.4318 0.4318)
			(layers "F.Cu" "F.Mask" "F.Paste")
			(net "GND")
		)
		(pad "J7" smd circle
			(at -32.541718 -23.314914 270)
			(size 0.4318 0.4318)
			(layers "F.Cu" "F.Mask" "F.Paste")
			(net "PVCCFA_EHV_FIVRA_CPU0")
		)
		(pad "J9" smd circle
			(at -30.914086 -23.314914 270)
			(size 0.4318 0.4318)
			(layers "F.Cu" "F.Mask" "F.Paste")
			(net "GND")
		)
		(pad "J11" smd circle
			(at -29.2862 -23.314914 270)
			(size 0.4318 0.4318)
			(layers "F.Cu" "F.Mask" "F.Paste")
			(net "PVCCFA_EHV_FIVRA_CPU0")
		)
		(pad "J13" smd circle
			(at -27.658314 -23.314914 270)
			(size 0.4318 0.4318)
			(layers "F.Cu" "F.Mask" "F.Paste")
			(net "TP_CPU0_PPD")
		)
		(pad "J15" smd circle
			(at -26.030682 -23.314914 270)
			(size 0.4318 0.4318)
			(layers "F.Cu" "F.Mask" "F.Paste")
			(net "GND")
		)
		(pad "J17" smd circle
			(at -24.402796 -23.314914 270)
			(size 0.4318 0.4318)
			(layers "F.Cu" "F.Mask" "F.Paste")
			(net "M_B_CPU0_SB_DQ<20>")
		)
		(pad "J19" smd circle
			(at -22.77491 -23.314914 270)
			(size 0.4318 0.4318)
			(layers "F.Cu" "F.Mask" "F.Paste")
			(net "M_B_CPU0_SB_DQ<17>")
		)
		(pad "J21" smd circle
			(at -21.147278 -23.314914 270)
			(size 0.4318 0.4318)
			(layers "F.Cu" "F.Mask" "F.Paste")
			(net "GND")
		)
		(pad "J23" smd circle
			(at -19.519392 -23.314914 270)
			(size 0.4318 0.4318)
			(layers "F.Cu" "F.Mask" "F.Paste")
			(net "M_B_CPU0_SB_DQ<12>")
		)
		(pad "J25" smd circle
			(at -17.89176 -23.314914 270)
			(size 0.4318 0.4318)
			(layers "F.Cu" "F.Mask" "F.Paste")
			(net "M_B_CPU0_SB_DQ<9>")
		)
		(pad "J27" smd circle
			(at -16.263874 -23.314914 270)
			(size 0.4318 0.4318)
			(layers "F.Cu" "F.Mask" "F.Paste")
			(net "GND")
		)
		(pad "J29" smd circle
			(at -14.635988 -23.314914 270)
			(size 0.4318 0.4318)
			(layers "F.Cu" "F.Mask" "F.Paste")
			(net "M_A_CPU0_SB_DQ<4>")
		)
		(pad "J31" smd circle
			(at -13.008356 -23.314914 270)
			(size 0.4318 0.4318)
			(layers "F.Cu" "F.Mask" "F.Paste")
			(net "M_A_CPU0_SB_DQ<1>")
		)
		(pad "J33" smd circle
			(at -11.380724 -23.314914 270)
			(size 0.4318 0.4318)
			(layers "F.Cu" "F.Mask" "F.Paste")
			(net "GND")
		)
		(pad "J35" smd circle
			(at -9.752838 -23.314914 270)
			(size 0.4318 0.4318)
			(layers "F.Cu" "F.Mask" "F.Paste")
			(net "M_B_CPU0_SB_CB<0>")
		)
		(pad "J37" smd circle
			(at -8.124952 -23.314914 270)
			(size 0.4318 0.4318)
			(layers "F.Cu" "F.Mask" "F.Paste")
			(net "M_B_CPU0_SB_CB<5>")
		)
		(pad "J39" smd circle
			(at -6.49732 -23.314914 270)
			(size 0.4318 0.4318)
			(layers "F.Cu" "F.Mask" "F.Paste")
			(net "GND")
		)
		(pad "J41" smd circle
			(at -4.869434 -23.314914 270)
			(size 0.4318 0.4318)
			(layers "F.Cu" "F.Mask" "F.Paste")
			(net "M_B_CPU0_SB_CS_N<0>")
		)
		(pad "J43" smd circle
			(at -3.241802 -23.314914 270)
			(size 0.4318 0.4318)
			(layers "F.Cu" "F.Mask" "F.Paste")
			(net "M_B_CPU0_SB_CA<4>")
		)
		(pad "J45" smd circle
			(at -1.613916 -23.314914 270)
			(size 0.4318 0.4318)
			(layers "F.Cu" "F.Mask" "F.Paste")
			(net "GND")
		)
		(pad "J48" smd circle
			(at 2.427732 -23.204932 270)
			(size 0.4318 0.4318)
			(layers "F.Cu" "F.Mask" "F.Paste")
			(net "M_B_CPU0_SA_CA<2>")
		)
		(pad "J50" smd circle
			(at 4.055618 -23.204932 270)
			(size 0.4318 0.4318)
			(layers "F.Cu" "F.Mask" "F.Paste")
			(net "M_B_CPU0_SA_CS_N<1>")
		)
		(pad "J52" smd circle
			(at 5.68325 -23.204932 270)
			(size 0.4318 0.4318)
			(layers "F.Cu" "F.Mask" "F.Paste")
			(net "GND")
		)
		(pad "J54" smd circle
			(at 7.311136 -23.204932 270)
			(size 0.4318 0.4318)
			(layers "F.Cu" "F.Mask" "F.Paste")
			(net "M_B_CPU0_SA_CB<4>")
		)
		(pad "J56" smd circle
			(at 8.939022 -23.204932 270)
			(size 0.4318 0.4318)
			(layers "F.Cu" "F.Mask" "F.Paste")
			(net "M_B_CPU0_SA_CB<1>")
		)
		(pad "J58" smd circle
			(at 10.566654 -23.204932 270)
			(size 0.4318 0.4318)
			(layers "F.Cu" "F.Mask" "F.Paste")
			(net "GND")
		)
		(pad "J60" smd circle
			(at 12.19454 -23.204932 270)
			(size 0.4318 0.4318)
			(layers "F.Cu" "F.Mask" "F.Paste")
			(net "M_B_CPU0_SA_DQ<20>")
		)
		(pad "J62" smd circle
			(at 13.822426 -23.204932 270)
			(size 0.4318 0.4318)
			(layers "F.Cu" "F.Mask" "F.Paste")
			(net "M_B_CPU0_SA_DQ<17>")
		)
		(pad "J64" smd circle
			(at 15.450058 -23.204932 270)
			(size 0.4318 0.4318)
			(layers "F.Cu" "F.Mask" "F.Paste")
			(net "GND")
		)
		(pad "J66" smd circle
			(at 17.07769 -23.204932 270)
			(size 0.4318 0.4318)
			(layers "F.Cu" "F.Mask" "F.Paste")
			(net "M_A_CPU0_SA_DQ<12>")
		)
		(pad "J68" smd circle
			(at 18.705576 -23.204932 270)
			(size 0.4318 0.4318)
			(layers "F.Cu" "F.Mask" "F.Paste")
			(net "M_A_CPU0_SA_DQ<9>")
		)
		(pad "J70" smd circle
			(at 20.333462 -23.204932 270)
			(size 0.4318 0.4318)
			(layers "F.Cu" "F.Mask" "F.Paste")
			(net "GND")
		)
		(pad "J72" smd circle
			(at 21.961094 -23.204932 270)
			(size 0.4318 0.4318)
			(layers "F.Cu" "F.Mask" "F.Paste")
			(net "M_B_CPU0_SA_DQ<4>")
		)
		(pad "J74" smd circle
			(at 23.58898 -23.204932 270)
			(size 0.4318 0.4318)
			(layers "F.Cu" "F.Mask" "F.Paste")
			(net "M_B_CPU0_SA_DQ<1>")
		)
		(pad "J76" smd circle
			(at 25.216612 -23.204932 270)
			(size 0.4318 0.4318)
			(layers "F.Cu" "F.Mask" "F.Paste")
			(net "GND")
		)
		(pad "J78" smd circle
			(at 26.844498 -23.204932 270)
			(size 0.4318 0.4318)
			(layers "F.Cu" "F.Mask" "F.Paste")
			(net "GND")
		)
		(pad "J80" smd circle
			(at 28.472384 -23.204932 270)
			(size 0.4318 0.4318)
			(layers "F.Cu" "F.Mask" "F.Paste")
			(net "PVCCFA_EHV_FIVRA_CPU0")
		)
		(pad "J82" smd circle
			(at 30.100016 -23.204932 270)
			(size 0.4318 0.4318)
			(layers "F.Cu" "F.Mask" "F.Paste")
			(net "UPI_CPU1_CPU0_P2P2_DN<19>")
		)
		(pad "J84" smd circle
			(at 31.727902 -23.204932 270)
			(size 0.4318 0.4318)
			(layers "F.Cu" "F.Mask" "F.Paste")
			(net "GND")
		)
		(pad "J86" smd circle
			(at 33.355534 -23.204932 270)
			(size 0.4318 0.4318)
			(layers "F.Cu" "F.Mask" "F.Paste")
			(net "GND")
		)
		(pad "J88" smd circle
			(at 34.98342 -23.204932 270)
			(size 0.4318 0.4318)
			(layers "F.Cu" "F.Mask" "F.Paste")
			(net "GND")
		)
		(pad "J90" smd oval
			(at 36.611306 -23.204932 45)
			(size 0.381 0.4826)
			(drill
				(offset 0 -0.0508)
			)
			(layers "F.Cu" "F.Mask" "F.Paste")
			(net "P5E_CPU0_PE4_RX_DN<0>")
		)
		(pad "K2" smd oval
			(at -36.611306 -22.845268 135)
			(size 0.381 0.4826)
			(drill
				(offset 0 -0.0508)
			)
			(layers "F.Cu" "F.Mask" "F.Paste")
			(net "GND")
		)
		(pad "K4" smd circle
			(at -34.98342 -22.845268 270)
			(size 0.4318 0.4318)
			(layers "F.Cu" "F.Mask" "F.Paste")
			(net "UPI_CPU0_CPU1_P0P1_DN<0>")
		)
		(pad "K6" smd circle
			(at -33.355534 -22.845268 270)
			(size 0.4318 0.4318)
			(layers "F.Cu" "F.Mask" "F.Paste")
			(net "UPI_CPU1_CPU0_P1P0_DN<0>")
		)
		(pad "K8" smd circle
			(at -31.727902 -22.845268 270)
			(size 0.4318 0.4318)
			(layers "F.Cu" "F.Mask" "F.Paste")
			(net "GND")
		)
		(pad "K10" smd circle
			(at -30.100016 -22.845268 270)
			(size 0.4318 0.4318)
			(layers "F.Cu" "F.Mask" "F.Paste")
			(net "P5E_CPU0_PE0_RX_DN<0>")
		)
		(pad "K12" smd circle
			(at -28.472384 -22.845268 270)
			(size 0.4318 0.4318)
			(layers "F.Cu" "F.Mask" "F.Paste")
			(net "GND")
		)
		(pad "K14" smd circle
			(at -26.844498 -22.845268 270)
			(size 0.4318 0.4318)
			(layers "F.Cu" "F.Mask" "F.Paste")
			(net "GND")
		)
		(pad "K16" smd circle
			(at -25.216612 -22.845268 270)
			(size 0.4318 0.4318)
			(layers "F.Cu" "F.Mask" "F.Paste")
			(net "M_B_CPU0_SB_DQ<21>")
		)
		(pad "K18" smd circle
			(at -23.58898 -22.845268 270)
			(size 0.4318 0.4318)
			(layers "F.Cu" "F.Mask" "F.Paste")
			(net "M_B_CPU0_SB_DQS_DP<2>")
		)
		(pad "K20" smd circle
			(at -21.961094 -22.845268 270)
			(size 0.4318 0.4318)
			(layers "F.Cu" "F.Mask" "F.Paste")
			(net "M_B_CPU0_SB_DQ<16>")
		)
		(pad "K22" smd circle
			(at -20.333462 -22.845268 270)
			(size 0.4318 0.4318)
			(layers "F.Cu" "F.Mask" "F.Paste")
			(net "M_B_CPU0_SB_DQ<13>")
		)
		(pad "K24" smd circle
			(at -18.705576 -22.845268 270)
			(size 0.4318 0.4318)
			(layers "F.Cu" "F.Mask" "F.Paste")
			(net "M_B_CPU0_SB_DQS_DP<1>")
		)
		(pad "K26" smd circle
			(at -17.07769 -22.845268 270)
			(size 0.4318 0.4318)
			(layers "F.Cu" "F.Mask" "F.Paste")
			(net "M_B_CPU0_SB_DQ<8>")
		)
		(pad "K28" smd circle
			(at -15.450058 -22.845268 270)
			(size 0.4318 0.4318)
			(layers "F.Cu" "F.Mask" "F.Paste")
			(net "M_A_CPU0_SB_DQ<5>")
		)
		(pad "K30" smd circle
			(at -13.822426 -22.845268 270)
			(size 0.4318 0.4318)
			(layers "F.Cu" "F.Mask" "F.Paste")
			(net "M_A_CPU0_SB_DQS_DP<0>")
		)
		(pad "K32" smd circle
			(at -12.19454 -22.845268 270)
			(size 0.4318 0.4318)
			(layers "F.Cu" "F.Mask" "F.Paste")
			(net "M_A_CPU0_SB_DQ<0>")
		)
		(pad "K34" smd circle
			(at -10.566654 -22.845268 270)
			(size 0.4318 0.4318)
			(layers "F.Cu" "F.Mask" "F.Paste")
			(net "M_B_CPU0_SB_CB<1>")
		)
		(pad "K36" smd circle
			(at -8.939022 -22.845268 270)
			(size 0.4318 0.4318)
			(layers "F.Cu" "F.Mask" "F.Paste")
			(net "M_B_CPU0_SB_DQS_DN<9>")
		)
		(pad "K38" smd circle
			(at -7.311136 -22.845268 270)
			(size 0.4318 0.4318)
			(layers "F.Cu" "F.Mask" "F.Paste")
			(net "M_B_CPU0_SB_CB<4>")
		)
		(pad "K40" smd circle
			(at -5.68325 -22.845268 270)
			(size 0.4318 0.4318)
			(layers "F.Cu" "F.Mask" "F.Paste")
			(net "M_B_CPU0_SB_CS_N<1>")
		)
		(pad "K42" smd circle
			(at -4.055618 -22.845268 270)
			(size 0.4318 0.4318)
			(layers "F.Cu" "F.Mask" "F.Paste")
			(net "GND")
		)
		(pad "K44" smd circle
			(at -2.427732 -22.845268 270)
			(size 0.4318 0.4318)
			(layers "F.Cu" "F.Mask" "F.Paste")
			(net "M_B_CPU0_SB_CA<2>")
		)
		(pad "K47" smd circle
			(at 1.613916 -22.735286 270)
			(size 0.4318 0.4318)
			(layers "F.Cu" "F.Mask" "F.Paste")
			(net "M_B_CPU0_SA_CA<4>")
		)
		(pad "K49" smd circle
			(at 3.241802 -22.735286 270)
			(size 0.4318 0.4318)
			(layers "F.Cu" "F.Mask" "F.Paste")
			(net "GND")
		)
		(pad "K51" smd circle
			(at 4.869434 -22.735286 270)
			(size 0.4318 0.4318)
			(layers "F.Cu" "F.Mask" "F.Paste")
			(net "M_B_CPU0_SA_CS_N<0>")
		)
		(pad "K53" smd circle
			(at 6.49732 -22.735286 270)
			(size 0.4318 0.4318)
			(layers "F.Cu" "F.Mask" "F.Paste")
			(net "M_B_CPU0_SA_CB<5>")
		)
		(pad "K55" smd circle
			(at 8.124952 -22.735286 270)
			(size 0.4318 0.4318)
			(layers "F.Cu" "F.Mask" "F.Paste")
			(net "M_B_CPU0_SA_DQS_DP<4>")
		)
		(pad "K57" smd circle
			(at 9.752838 -22.735286 270)
			(size 0.4318 0.4318)
			(layers "F.Cu" "F.Mask" "F.Paste")
			(net "M_B_CPU0_SA_CB<0>")
		)
		(pad "K59" smd circle
			(at 11.380724 -22.735286 270)
			(size 0.4318 0.4318)
			(layers "F.Cu" "F.Mask" "F.Paste")
			(net "M_B_CPU0_SA_DQ<21>")
		)
		(pad "K61" smd circle
			(at 13.008356 -22.735286 270)
			(size 0.4318 0.4318)
			(layers "F.Cu" "F.Mask" "F.Paste")
			(net "M_B_CPU0_SA_DQS_DP<2>")
		)
		(pad "K63" smd circle
			(at 14.635988 -22.735286 270)
			(size 0.4318 0.4318)
			(layers "F.Cu" "F.Mask" "F.Paste")
			(net "M_B_CPU0_SA_DQ<16>")
		)
		(pad "K65" smd circle
			(at 16.263874 -22.735286 270)
			(size 0.4318 0.4318)
			(layers "F.Cu" "F.Mask" "F.Paste")
			(net "M_A_CPU0_SA_DQ<13>")
		)
		(pad "K67" smd circle
			(at 17.89176 -22.735286 270)
			(size 0.4318 0.4318)
			(layers "F.Cu" "F.Mask" "F.Paste")
			(net "M_A_CPU0_SA_DQS_DP<1>")
		)
		(pad "K69" smd circle
			(at 19.519392 -22.735286 270)
			(size 0.4318 0.4318)
			(layers "F.Cu" "F.Mask" "F.Paste")
			(net "M_A_CPU0_SA_DQ<8>")
		)
		(pad "K71" smd circle
			(at 21.147278 -22.735286 270)
			(size 0.4318 0.4318)
			(layers "F.Cu" "F.Mask" "F.Paste")
			(net "M_B_CPU0_SA_DQ<5>")
		)
		(pad "K73" smd circle
			(at 22.77491 -22.735286 270)
			(size 0.4318 0.4318)
			(layers "F.Cu" "F.Mask" "F.Paste")
			(net "M_B_CPU0_SA_DQS_DP<0>")
		)
		(pad "K75" smd circle
			(at 24.402796 -22.735286 270)
			(size 0.4318 0.4318)
			(layers "F.Cu" "F.Mask" "F.Paste")
			(net "M_B_CPU0_SA_DQ<0>")
		)
		(pad "K77" smd circle
			(at 26.030682 -22.735286 270)
			(size 0.4318 0.4318)
			(layers "F.Cu" "F.Mask" "F.Paste")
			(net "GND")
		)
		(pad "K79" smd circle
			(at 27.658314 -22.735286 270)
			(size 0.4318 0.4318)
			(layers "F.Cu" "F.Mask" "F.Paste")
			(net "UPI_CPU1_CPU0_P2P2_DN<20>")
		)
		(pad "K81" smd circle
			(at 29.2862 -22.735286 270)
			(size 0.4318 0.4318)
			(layers "F.Cu" "F.Mask" "F.Paste")
			(net "UPI_CPU1_CPU0_P2P2_DP<18>")
		)
		(pad "K83" smd circle
			(at 30.914086 -22.735286 270)
			(size 0.4318 0.4318)
			(layers "F.Cu" "F.Mask" "F.Paste")
			(net "GND")
		)
		(pad "K85" smd circle
			(at 32.541718 -22.735286 270)
			(size 0.4318 0.4318)
			(layers "F.Cu" "F.Mask" "F.Paste")
			(net "GND")
		)
		(pad "K87" smd circle
			(at 34.169604 -22.735286 270)
			(size 0.4318 0.4318)
			(layers "F.Cu" "F.Mask" "F.Paste")
			(net "PVCCFA_EHV_FIVRA_CPU0")
		)
		(pad "K89" smd circle
			(at 35.797236 -22.735286 270)
			(size 0.4318 0.4318)
			(layers "F.Cu" "F.Mask" "F.Paste")
			(net "P5E_CPU0_PE4_RX_DP<0>")
		)
		(pad "L3" smd circle
			(at -35.797236 -22.375114 270)
			(size 0.4318 0.4318)
			(layers "F.Cu" "F.Mask" "F.Paste")
			(net "UPI_CPU0_CPU1_P0P1_DP<1>")
		)
		(pad "L5" smd circle
			(at -34.169604 -22.375114 270)
			(size 0.4318 0.4318)
			(layers "F.Cu" "F.Mask" "F.Paste")
			(net "GND")
		)
		(pad "L7" smd circle
			(at -32.541718 -22.375114 270)
			(size 0.4318 0.4318)
			(layers "F.Cu" "F.Mask" "F.Paste")
			(net "UPI_CPU1_CPU0_P1P0_DP<0>")
		)
		(pad "L9" smd circle
			(at -30.914086 -22.375114 270)
			(size 0.4318 0.4318)
			(layers "F.Cu" "F.Mask" "F.Paste")
			(net "GND")
		)
		(pad "L11" smd circle
			(at -29.2862 -22.375114 270)
			(size 0.4318 0.4318)
			(layers "F.Cu" "F.Mask" "F.Paste")
			(net "P5E_CPU0_PE0_RX_DP<0>")
		)
		(pad "L13" smd circle
			(at -27.658314 -22.375114 270)
			(size 0.4318 0.4318)
			(layers "F.Cu" "F.Mask" "F.Paste")
			(net "GND")
		)
		(pad "L15" smd circle
			(at -26.030682 -22.375114 270)
			(size 0.4318 0.4318)
			(layers "F.Cu" "F.Mask" "F.Paste")
			(net "GND")
		)
		(pad "L17" smd circle
			(at -24.402796 -22.375114 270)
			(size 0.4318 0.4318)
			(layers "F.Cu" "F.Mask" "F.Paste")
			(net "GND")
		)
		(pad "L19" smd circle
			(at -22.77491 -22.375114 270)
			(size 0.4318 0.4318)
			(layers "F.Cu" "F.Mask" "F.Paste")
			(net "GND")
		)
		(pad "L21" smd circle
			(at -21.147278 -22.375114 270)
			(size 0.4318 0.4318)
			(layers "F.Cu" "F.Mask" "F.Paste")
			(net "GND")
		)
		(pad "L23" smd circle
			(at -19.519392 -22.375114 270)
			(size 0.4318 0.4318)
			(layers "F.Cu" "F.Mask" "F.Paste")
			(net "GND")
		)
		(pad "L25" smd circle
			(at -17.89176 -22.375114 270)
			(size 0.4318 0.4318)
			(layers "F.Cu" "F.Mask" "F.Paste")
			(net "GND")
		)
		(pad "L27" smd circle
			(at -16.263874 -22.375114 270)
			(size 0.4318 0.4318)
			(layers "F.Cu" "F.Mask" "F.Paste")
			(net "GND")
		)
		(pad "L29" smd circle
			(at -14.635988 -22.375114 270)
			(size 0.4318 0.4318)
			(layers "F.Cu" "F.Mask" "F.Paste")
			(net "GND")
		)
		(pad "L31" smd circle
			(at -13.008356 -22.375114 270)
			(size 0.4318 0.4318)
			(layers "F.Cu" "F.Mask" "F.Paste")
			(net "GND")
		)
		(pad "L33" smd circle
			(at -11.380724 -22.375114 270)
			(size 0.4318 0.4318)
			(layers "F.Cu" "F.Mask" "F.Paste")
			(net "GND")
		)
		(pad "L35" smd circle
			(at -9.752838 -22.375114 270)
			(size 0.4318 0.4318)
			(layers "F.Cu" "F.Mask" "F.Paste")
			(net "GND")
		)
		(pad "L37" smd circle
			(at -8.124952 -22.375114 270)
			(size 0.4318 0.4318)
			(layers "F.Cu" "F.Mask" "F.Paste")
			(net "GND")
		)
		(pad "L39" smd circle
			(at -6.49732 -22.375114 270)
			(size 0.4318 0.4318)
			(layers "F.Cu" "F.Mask" "F.Paste")
			(net "GND")
		)
		(pad "L41" smd circle
			(at -4.869434 -22.375114 270)
			(size 0.4318 0.4318)
			(layers "F.Cu" "F.Mask" "F.Paste")
			(net "GND")
		)
		(pad "L43" smd circle
			(at -3.241802 -22.375114 270)
			(size 0.4318 0.4318)
			(layers "F.Cu" "F.Mask" "F.Paste")
			(net "GND")
		)
		(pad "L45" smd circle
			(at -1.613916 -22.375114 270)
			(size 0.4318 0.4318)
			(layers "F.Cu" "F.Mask" "F.Paste")
			(net "GND")
		)
		(pad "L48" smd circle
			(at 2.427732 -22.265386 270)
			(size 0.4318 0.4318)
			(layers "F.Cu" "F.Mask" "F.Paste")
			(net "GND")
		)
		(pad "L50" smd circle
			(at 4.055618 -22.265386 270)
			(size 0.4318 0.4318)
			(layers "F.Cu" "F.Mask" "F.Paste")
			(net "GND")
		)
		(pad "L52" smd circle
			(at 5.68325 -22.265386 270)
			(size 0.4318 0.4318)
			(layers "F.Cu" "F.Mask" "F.Paste")
			(net "GND")
		)
		(pad "L54" smd circle
			(at 7.311136 -22.265386 270)
			(size 0.4318 0.4318)
			(layers "F.Cu" "F.Mask" "F.Paste")
			(net "GND")
		)
		(pad "L56" smd circle
			(at 8.939022 -22.265386 270)
			(size 0.4318 0.4318)
			(layers "F.Cu" "F.Mask" "F.Paste")
			(net "GND")
		)
		(pad "L58" smd circle
			(at 10.566654 -22.265386 270)
			(size 0.4318 0.4318)
			(layers "F.Cu" "F.Mask" "F.Paste")
			(net "GND")
		)
		(pad "L60" smd circle
			(at 12.19454 -22.265386 270)
			(size 0.4318 0.4318)
			(layers "F.Cu" "F.Mask" "F.Paste")
			(net "GND")
		)
		(pad "L62" smd circle
			(at 13.822426 -22.265386 270)
			(size 0.4318 0.4318)
			(layers "F.Cu" "F.Mask" "F.Paste")
			(net "GND")
		)
		(pad "L64" smd circle
			(at 15.450058 -22.265386 270)
			(size 0.4318 0.4318)
			(layers "F.Cu" "F.Mask" "F.Paste")
			(net "GND")
		)
		(pad "L66" smd circle
			(at 17.07769 -22.265386 270)
			(size 0.4318 0.4318)
			(layers "F.Cu" "F.Mask" "F.Paste")
			(net "GND")
		)
		(pad "L68" smd circle
			(at 18.705576 -22.265386 270)
			(size 0.4318 0.4318)
			(layers "F.Cu" "F.Mask" "F.Paste")
			(net "GND")
		)
		(pad "L70" smd circle
			(at 20.333462 -22.265386 270)
			(size 0.4318 0.4318)
			(layers "F.Cu" "F.Mask" "F.Paste")
			(net "GND")
		)
		(pad "L72" smd circle
			(at 21.961094 -22.265386 270)
			(size 0.4318 0.4318)
			(layers "F.Cu" "F.Mask" "F.Paste")
			(net "GND")
		)
		(pad "L74" smd circle
			(at 23.58898 -22.265386 270)
			(size 0.4318 0.4318)
			(layers "F.Cu" "F.Mask" "F.Paste")
			(net "GND")
		)
		(pad "L76" smd circle
			(at 25.216612 -22.265386 270)
			(size 0.4318 0.4318)
			(layers "F.Cu" "F.Mask" "F.Paste")
			(net "GND")
		)
		(pad "L78" smd circle
			(at 26.844498 -22.265386 270)
			(size 0.4318 0.4318)
			(layers "F.Cu" "F.Mask" "F.Paste")
			(net "GND")
		)
		(pad "L80" smd circle
			(at 28.472384 -22.265386 270)
			(size 0.4318 0.4318)
			(layers "F.Cu" "F.Mask" "F.Paste")
			(net "UPI_CPU1_CPU0_P2P2_DN<18>")
		)
		(pad "L82" smd circle
			(at 30.100016 -22.265386 270)
			(size 0.4318 0.4318)
			(layers "F.Cu" "F.Mask" "F.Paste")
			(net "UPI_CPU1_CPU0_P2P2_DP<19>")
		)
		(pad "L84" smd circle
			(at 31.727902 -22.265386 270)
			(size 0.4318 0.4318)
			(layers "F.Cu" "F.Mask" "F.Paste")
			(net "PVCCFA_EHV_FIVRA_CPU0")
		)
		(pad "L86" smd circle
			(at 33.355534 -22.265386 270)
			(size 0.4318 0.4318)
			(layers "F.Cu" "F.Mask" "F.Paste")
			(net "P5E_CPU0_PE4_TX_DN<0>")
		)
		(pad "L88" smd circle
			(at 34.98342 -22.265386 270)
			(size 0.4318 0.4318)
			(layers "F.Cu" "F.Mask" "F.Paste")
			(net "GND")
		)
		(pad "L90" smd oval
			(at 36.611306 -22.265386)
			(size 0.381 0.4826)
			(drill
				(offset 0 -0.0508)
			)
			(layers "F.Cu" "F.Mask" "F.Paste")
			(net "GND")
		)
		(pad "M2" smd oval
			(at -36.611306 -21.905468 180)
			(size 0.381 0.4826)
			(drill
				(offset 0 -0.0508)
			)
			(layers "F.Cu" "F.Mask" "F.Paste")
			(net "UPI_CPU0_CPU1_P0P1_DN<1>")
		)
		(pad "M4" smd circle
			(at -34.98342 -21.905468 270)
			(size 0.4318 0.4318)
			(layers "F.Cu" "F.Mask" "F.Paste")
			(net "GND")
		)
		(pad "M6" smd circle
			(at -33.355534 -21.905468 270)
			(size 0.4318 0.4318)
			(layers "F.Cu" "F.Mask" "F.Paste")
			(net "UPI_CPU1_CPU0_P1P0_DP<1>")
		)
		(pad "M8" smd circle
			(at -31.727902 -21.905468 270)
			(size 0.4318 0.4318)
			(layers "F.Cu" "F.Mask" "F.Paste")
			(net "GND")
		)
		(pad "M10" smd circle
			(at -30.100016 -21.905468 270)
			(size 0.4318 0.4318)
			(layers "F.Cu" "F.Mask" "F.Paste")
			(net "P5E_CPU0_PE0_RX_DN<1>")
		)
		(pad "M12" smd circle
			(at -28.472384 -21.905468 270)
			(size 0.4318 0.4318)
			(layers "F.Cu" "F.Mask" "F.Paste")
			(net "GND")
		)
		(pad "M14" smd circle
			(at -26.844498 -21.905468 270)
			(size 0.4318 0.4318)
			(layers "F.Cu" "F.Mask" "F.Paste")
			(net "P5E_CPU0_PE0_TX_DP<0>")
		)
		(pad "M16" smd circle
			(at -25.216612 -21.905468 270)
			(size 0.4318 0.4318)
			(layers "F.Cu" "F.Mask" "F.Paste")
			(net "M_B_CPU0_SB_DQ<23>")
		)
		(pad "M18" smd circle
			(at -23.58898 -21.905468 270)
			(size 0.4318 0.4318)
			(layers "F.Cu" "F.Mask" "F.Paste")
			(net "M_B_CPU0_SB_DQS_DN<7>")
		)
		(pad "M20" smd circle
			(at -21.961094 -21.905468 270)
			(size 0.4318 0.4318)
			(layers "F.Cu" "F.Mask" "F.Paste")
			(net "M_B_CPU0_SB_DQ<18>")
		)
		(pad "M22" smd circle
			(at -20.333462 -21.905468 270)
			(size 0.4318 0.4318)
			(layers "F.Cu" "F.Mask" "F.Paste")
			(net "M_B_CPU0_SB_DQ<15>")
		)
		(pad "M24" smd circle
			(at -18.705576 -21.905468 270)
			(size 0.4318 0.4318)
			(layers "F.Cu" "F.Mask" "F.Paste")
			(net "M_B_CPU0_SB_DQS_DN<6>")
		)
		(pad "M26" smd circle
			(at -17.07769 -21.905468 270)
			(size 0.4318 0.4318)
			(layers "F.Cu" "F.Mask" "F.Paste")
			(net "M_B_CPU0_SB_DQ<10>")
		)
		(pad "M28" smd circle
			(at -15.450058 -21.905468 270)
			(size 0.4318 0.4318)
			(layers "F.Cu" "F.Mask" "F.Paste")
			(net "M_A_CPU0_SB_DQ<7>")
		)
		(pad "M30" smd circle
			(at -13.822426 -21.905468 270)
			(size 0.4318 0.4318)
			(layers "F.Cu" "F.Mask" "F.Paste")
			(net "M_A_CPU0_SB_DQS_DN<5>")
		)
		(pad "M32" smd circle
			(at -12.19454 -21.905468 270)
			(size 0.4318 0.4318)
			(layers "F.Cu" "F.Mask" "F.Paste")
			(net "M_A_CPU0_SB_DQ<2>")
		)
		(pad "M34" smd circle
			(at -10.566654 -21.905468 270)
			(size 0.4318 0.4318)
			(layers "F.Cu" "F.Mask" "F.Paste")
			(net "M_B_CPU0_SB_CB<3>")
		)
		(pad "M36" smd circle
			(at -8.939022 -21.905468 270)
			(size 0.4318 0.4318)
			(layers "F.Cu" "F.Mask" "F.Paste")
			(net "M_B_CPU0_SB_DQS_DP<4>")
		)
		(pad "M38" smd circle
			(at -7.311136 -21.905468 270)
			(size 0.4318 0.4318)
			(layers "F.Cu" "F.Mask" "F.Paste")
			(net "M_B_CPU0_SB_CB<6>")
		)
		(pad "M40" smd circle
			(at -5.68325 -21.905468 270)
			(size 0.4318 0.4318)
			(layers "F.Cu" "F.Mask" "F.Paste")
			(net "M_B_CPU0_SB_CS_N<3>")
		)
		(pad "M42" smd circle
			(at -4.055618 -21.905468 270)
			(size 0.4318 0.4318)
			(layers "F.Cu" "F.Mask" "F.Paste")
			(net "GND")
		)
		(pad "M44" smd circle
			(at -2.427732 -21.905468 270)
			(size 0.4318 0.4318)
			(layers "F.Cu" "F.Mask" "F.Paste")
			(net "M_B_CPU0_SB_CA<3>")
		)
		(pad "M47" smd circle
			(at 1.613916 -21.795486 270)
			(size 0.4318 0.4318)
			(layers "F.Cu" "F.Mask" "F.Paste")
			(net "M_B_CPU0_SA_CA<5>")
		)
		(pad "M49" smd circle
			(at 3.241802 -21.795486 270)
			(size 0.4318 0.4318)
			(layers "F.Cu" "F.Mask" "F.Paste")
			(net "GND")
		)
		(pad "M51" smd circle
			(at 4.869434 -21.795486 270)
			(size 0.4318 0.4318)
			(layers "F.Cu" "F.Mask" "F.Paste")
			(net "M_B_CPU0_SA_CS_N<2>")
		)
		(pad "M53" smd circle
			(at 6.49732 -21.795486 270)
			(size 0.4318 0.4318)
			(layers "F.Cu" "F.Mask" "F.Paste")
			(net "M_B_CPU0_SA_CB<7>")
		)
		(pad "M55" smd circle
			(at 8.124952 -21.795486 270)
			(size 0.4318 0.4318)
			(layers "F.Cu" "F.Mask" "F.Paste")
			(net "M_B_CPU0_SA_DQS_DN<9>")
		)
		(pad "M57" smd circle
			(at 9.752838 -21.795486 270)
			(size 0.4318 0.4318)
			(layers "F.Cu" "F.Mask" "F.Paste")
			(net "M_B_CPU0_SA_CB<2>")
		)
		(pad "M59" smd circle
			(at 11.380724 -21.795486 270)
			(size 0.4318 0.4318)
			(layers "F.Cu" "F.Mask" "F.Paste")
			(net "M_B_CPU0_SA_DQ<23>")
		)
		(pad "M61" smd circle
			(at 13.008356 -21.795486 270)
			(size 0.4318 0.4318)
			(layers "F.Cu" "F.Mask" "F.Paste")
			(net "M_B_CPU0_SA_DQS_DN<7>")
		)
		(pad "M63" smd circle
			(at 14.635988 -21.795486 270)
			(size 0.4318 0.4318)
			(layers "F.Cu" "F.Mask" "F.Paste")
			(net "M_B_CPU0_SA_DQ<18>")
		)
		(pad "M65" smd circle
			(at 16.263874 -21.795486 270)
			(size 0.4318 0.4318)
			(layers "F.Cu" "F.Mask" "F.Paste")
			(net "M_A_CPU0_SA_DQ<15>")
		)
		(pad "M67" smd circle
			(at 17.89176 -21.795486 270)
			(size 0.4318 0.4318)
			(layers "F.Cu" "F.Mask" "F.Paste")
			(net "M_A_CPU0_SA_DQS_DP<6>")
		)
		(pad "M69" smd circle
			(at 19.519392 -21.795486 270)
			(size 0.4318 0.4318)
			(layers "F.Cu" "F.Mask" "F.Paste")
			(net "M_A_CPU0_SA_DQ<10>")
		)
		(pad "M71" smd circle
			(at 21.147278 -21.795486 270)
			(size 0.4318 0.4318)
			(layers "F.Cu" "F.Mask" "F.Paste")
			(net "M_B_CPU0_SA_DQ<7>")
		)
		(pad "M73" smd circle
			(at 22.77491 -21.795486 270)
			(size 0.4318 0.4318)
			(layers "F.Cu" "F.Mask" "F.Paste")
			(net "M_B_CPU0_SA_DQS_DN<5>")
		)
		(pad "M75" smd circle
			(at 24.402796 -21.795486 270)
			(size 0.4318 0.4318)
			(layers "F.Cu" "F.Mask" "F.Paste")
			(net "M_B_CPU0_SA_DQ<2>")
		)
		(pad "M77" smd circle
			(at 26.030682 -21.795486 270)
			(size 0.4318 0.4318)
			(layers "F.Cu" "F.Mask" "F.Paste")
			(net "M_A_CPU0_SA_DQ<2>")
		)
		(pad "M79" smd circle
			(at 27.658314 -21.795486 270)
			(size 0.4318 0.4318)
			(layers "F.Cu" "F.Mask" "F.Paste")
			(net "UPI_CPU1_CPU0_P2P2_DP<20>")
		)
		(pad "M81" smd circle
			(at 29.2862 -21.795486 270)
			(size 0.4318 0.4318)
			(layers "F.Cu" "F.Mask" "F.Paste")
			(net "GND")
		)
		(pad "M83" smd circle
			(at 30.914086 -21.795486 270)
			(size 0.4318 0.4318)
			(layers "F.Cu" "F.Mask" "F.Paste")
			(net "GND")
		)
		(pad "M85" smd circle
			(at 32.541718 -21.795486 270)
			(size 0.4318 0.4318)
			(layers "F.Cu" "F.Mask" "F.Paste")
			(net "PVCCFA_EHV_FIVRA_CPU0")
		)
		(pad "M87" smd circle
			(at 34.169604 -21.795486 270)
			(size 0.4318 0.4318)
			(layers "F.Cu" "F.Mask" "F.Paste")
			(net "P5E_CPU0_PE4_TX_DP<0>")
		)
		(pad "M89" smd circle
			(at 35.797236 -21.795486 270)
			(size 0.4318 0.4318)
			(layers "F.Cu" "F.Mask" "F.Paste")
			(net "PVCCFA_EHV_FIVRA_CPU0")
		)
		(pad "N1" smd oval
			(at -37.425122 -21.435314 180)
			(size 0.381 0.4826)
			(drill
				(offset 0 -0.0508)
			)
			(layers "F.Cu" "F.Mask" "F.Paste")
			(net "UPI_CPU0_CPU1_P0P1_DN<2>")
		)
		(pad "N3" smd circle
			(at -35.797236 -21.435314 270)
			(size 0.4318 0.4318)
			(layers "F.Cu" "F.Mask" "F.Paste")
			(net "PVCCFA_EHV_CPU0")
		)
		(pad "N5" smd circle
			(at -34.169604 -21.435314 270)
			(size 0.4318 0.4318)
			(layers "F.Cu" "F.Mask" "F.Paste")
			(net "UPI_CPU1_CPU0_P1P0_DN<1>")
		)
		(pad "N7" smd circle
			(at -32.541718 -21.435314 270)
			(size 0.4318 0.4318)
			(layers "F.Cu" "F.Mask" "F.Paste")
			(net "PVCCFA_EHV_FIVRA_CPU0")
		)
		(pad "N9" smd circle
			(at -30.914086 -21.435314 270)
			(size 0.4318 0.4318)
			(layers "F.Cu" "F.Mask" "F.Paste")
			(net "P5E_CPU0_PE0_RX_DP<1>")
		)
		(pad "N11" smd circle
			(at -29.2862 -21.435314 270)
			(size 0.4318 0.4318)
			(layers "F.Cu" "F.Mask" "F.Paste")
			(net "PVCCFA_EHV_FIVRA_CPU0")
		)
		(pad "N13" smd circle
			(at -27.658314 -21.435314 270)
			(size 0.4318 0.4318)
			(layers "F.Cu" "F.Mask" "F.Paste")
			(net "P5E_CPU0_PE0_TX_DN<0>")
		)
		(pad "N15" smd circle
			(at -26.030682 -21.435314 270)
			(size 0.4318 0.4318)
			(layers "F.Cu" "F.Mask" "F.Paste")
			(net "GND")
		)
		(pad "N17" smd circle
			(at -24.402796 -21.435314 270)
			(size 0.4318 0.4318)
			(layers "F.Cu" "F.Mask" "F.Paste")
			(net "M_B_CPU0_SB_DQ<22>")
		)
		(pad "N19" smd circle
			(at -22.77491 -21.435314 270)
			(size 0.4318 0.4318)
			(layers "F.Cu" "F.Mask" "F.Paste")
			(net "M_B_CPU0_SB_DQ<19>")
		)
		(pad "N21" smd circle
			(at -21.147278 -21.435314 270)
			(size 0.4318 0.4318)
			(layers "F.Cu" "F.Mask" "F.Paste")
			(net "GND")
		)
		(pad "N23" smd circle
			(at -19.519392 -21.435314 270)
			(size 0.4318 0.4318)
			(layers "F.Cu" "F.Mask" "F.Paste")
			(net "M_B_CPU0_SB_DQ<14>")
		)
		(pad "N25" smd circle
			(at -17.89176 -21.435314 270)
			(size 0.4318 0.4318)
			(layers "F.Cu" "F.Mask" "F.Paste")
			(net "M_B_CPU0_SB_DQ<11>")
		)
		(pad "N27" smd circle
			(at -16.263874 -21.435314 270)
			(size 0.4318 0.4318)
			(layers "F.Cu" "F.Mask" "F.Paste")
			(net "GND")
		)
		(pad "N29" smd circle
			(at -14.635988 -21.435314 270)
			(size 0.4318 0.4318)
			(layers "F.Cu" "F.Mask" "F.Paste")
			(net "M_A_CPU0_SB_DQ<6>")
		)
		(pad "N31" smd circle
			(at -13.008356 -21.435314 270)
			(size 0.4318 0.4318)
			(layers "F.Cu" "F.Mask" "F.Paste")
			(net "M_A_CPU0_SB_DQ<3>")
		)
		(pad "N33" smd circle
			(at -11.380724 -21.435314 270)
			(size 0.4318 0.4318)
			(layers "F.Cu" "F.Mask" "F.Paste")
			(net "GND")
		)
		(pad "N35" smd circle
			(at -9.752838 -21.435314 270)
			(size 0.4318 0.4318)
			(layers "F.Cu" "F.Mask" "F.Paste")
			(net "M_B_CPU0_SB_CB<2>")
		)
		(pad "N37" smd circle
			(at -8.124952 -21.435314 270)
			(size 0.4318 0.4318)
			(layers "F.Cu" "F.Mask" "F.Paste")
			(net "M_B_CPU0_SB_CB<7>")
		)
		(pad "N39" smd circle
			(at -6.49732 -21.435314 270)
			(size 0.4318 0.4318)
			(layers "F.Cu" "F.Mask" "F.Paste")
			(net "GND")
		)
		(pad "N41" smd circle
			(at -4.869434 -21.435314 270)
			(size 0.4318 0.4318)
			(layers "F.Cu" "F.Mask" "F.Paste")
			(net "M_B_CPU0_SB_CS_N<2>")
		)
		(pad "N43" smd circle
			(at -3.241802 -21.435314 270)
			(size 0.4318 0.4318)
			(layers "F.Cu" "F.Mask" "F.Paste")
			(net "M_B_CPU0_SB_CA<5>")
		)
		(pad "N45" smd circle
			(at -1.613916 -21.435314 270)
			(size 0.4318 0.4318)
			(layers "F.Cu" "F.Mask" "F.Paste")
			(net "GND")
		)
		(pad "N48" smd circle
			(at 2.427732 -21.325332 270)
			(size 0.4318 0.4318)
			(layers "F.Cu" "F.Mask" "F.Paste")
			(net "M_B_CPU0_SA_CA<3>")
		)
		(pad "N50" smd circle
			(at 4.055618 -21.325332 270)
			(size 0.4318 0.4318)
			(layers "F.Cu" "F.Mask" "F.Paste")
			(net "M_B_CPU0_SA_CS_N<3>")
		)
		(pad "N52" smd circle
			(at 5.68325 -21.325332 270)
			(size 0.4318 0.4318)
			(layers "F.Cu" "F.Mask" "F.Paste")
			(net "GND")
		)
		(pad "N54" smd circle
			(at 7.311136 -21.325332 270)
			(size 0.4318 0.4318)
			(layers "F.Cu" "F.Mask" "F.Paste")
			(net "M_B_CPU0_SA_CB<6>")
		)
		(pad "N56" smd circle
			(at 8.939022 -21.325332 270)
			(size 0.4318 0.4318)
			(layers "F.Cu" "F.Mask" "F.Paste")
			(net "M_B_CPU0_SA_CB<3>")
		)
		(pad "N58" smd circle
			(at 10.566654 -21.325332 270)
			(size 0.4318 0.4318)
			(layers "F.Cu" "F.Mask" "F.Paste")
			(net "GND")
		)
		(pad "N60" smd circle
			(at 12.19454 -21.325332 270)
			(size 0.4318 0.4318)
			(layers "F.Cu" "F.Mask" "F.Paste")
			(net "M_B_CPU0_SA_DQ<22>")
		)
		(pad "N62" smd circle
			(at 13.822426 -21.325332 270)
			(size 0.4318 0.4318)
			(layers "F.Cu" "F.Mask" "F.Paste")
			(net "M_B_CPU0_SA_DQ<19>")
		)
		(pad "N64" smd circle
			(at 15.450058 -21.325332 270)
			(size 0.4318 0.4318)
			(layers "F.Cu" "F.Mask" "F.Paste")
			(net "GND")
		)
		(pad "N66" smd circle
			(at 17.07769 -21.325332 270)
			(size 0.4318 0.4318)
			(layers "F.Cu" "F.Mask" "F.Paste")
			(net "M_A_CPU0_SA_DQ<14>")
		)
		(pad "N68" smd circle
			(at 18.705576 -21.325332 270)
			(size 0.4318 0.4318)
			(layers "F.Cu" "F.Mask" "F.Paste")
			(net "M_A_CPU0_SA_DQ<11>")
		)
		(pad "N70" smd circle
			(at 20.333462 -21.325332 270)
			(size 0.4318 0.4318)
			(layers "F.Cu" "F.Mask" "F.Paste")
			(net "GND")
		)
		(pad "N72" smd circle
			(at 21.961094 -21.325332 270)
			(size 0.4318 0.4318)
			(layers "F.Cu" "F.Mask" "F.Paste")
			(net "M_B_CPU0_SA_DQ<6>")
		)
		(pad "N74" smd circle
			(at 23.58898 -21.325332 270)
			(size 0.4318 0.4318)
			(layers "F.Cu" "F.Mask" "F.Paste")
			(net "M_B_CPU0_SA_DQ<3>")
		)
		(pad "N76" smd circle
			(at 25.216612 -21.325332 270)
			(size 0.4318 0.4318)
			(layers "F.Cu" "F.Mask" "F.Paste")
			(net "GND")
		)
		(pad "N78" smd circle
			(at 26.844498 -21.325332 270)
			(size 0.4318 0.4318)
			(layers "F.Cu" "F.Mask" "F.Paste")
			(net "GND")
		)
		(pad "N80" smd circle
			(at 28.472384 -21.325332 270)
			(size 0.4318 0.4318)
			(layers "F.Cu" "F.Mask" "F.Paste")
			(net "GND")
		)
		(pad "N82" smd circle
			(at 30.100016 -21.325332 270)
			(size 0.4318 0.4318)
			(layers "F.Cu" "F.Mask" "F.Paste")
			(net "GND")
		)
		(pad "N84" smd circle
			(at 31.727902 -21.325332 270)
			(size 0.4318 0.4318)
			(layers "F.Cu" "F.Mask" "F.Paste")
			(net "GND")
		)
		(pad "N86" smd circle
			(at 33.355534 -21.325332 270)
			(size 0.4318 0.4318)
			(layers "F.Cu" "F.Mask" "F.Paste")
			(net "P5E_CPU0_PE4_TX_DP<1>")
		)
		(pad "N88" smd circle
			(at 34.98342 -21.325332 270)
			(size 0.4318 0.4318)
			(layers "F.Cu" "F.Mask" "F.Paste")
			(net "GND")
		)
		(pad "N90" smd oval
			(at 36.611306 -21.325332)
			(size 0.381 0.4826)
			(drill
				(offset 0 -0.0508)
			)
			(layers "F.Cu" "F.Mask" "F.Paste")
			(net "P5E_CPU0_PE4_RX_DP<1>")
		)
		(pad "P2" smd circle
			(at -36.611306 -20.965668 270)
			(size 0.4318 0.4318)
			(layers "F.Cu" "F.Mask" "F.Paste")
			(net "UPI_CPU0_CPU1_P0P1_DP<2>")
		)
		(pad "P4" smd circle
			(at -34.98342 -20.965668 270)
			(size 0.4318 0.4318)
			(layers "F.Cu" "F.Mask" "F.Paste")
			(net "GND")
		)
		(pad "P6" smd circle
			(at -33.355534 -20.965668 270)
			(size 0.4318 0.4318)
			(layers "F.Cu" "F.Mask" "F.Paste")
			(net "UPI_CPU1_CPU0_P1P0_DN<2>")
		)
		(pad "P8" smd circle
			(at -31.727902 -20.965668 270)
			(size 0.4318 0.4318)
			(layers "F.Cu" "F.Mask" "F.Paste")
			(net "GND")
		)
		(pad "P10" smd circle
			(at -30.100016 -20.965668 270)
			(size 0.4318 0.4318)
			(layers "F.Cu" "F.Mask" "F.Paste")
			(net "P5E_CPU0_PE0_RX_DN<2>")
		)
		(pad "P12" smd circle
			(at -28.472384 -20.965668 270)
			(size 0.4318 0.4318)
			(layers "F.Cu" "F.Mask" "F.Paste")
			(net "GND")
		)
		(pad "P14" smd circle
			(at -26.844498 -20.965668 270)
			(size 0.4318 0.4318)
			(layers "F.Cu" "F.Mask" "F.Paste")
			(net "P5E_CPU0_PE0_TX_DN<1>")
		)
		(pad "P16" smd circle
			(at -25.216612 -20.965668 270)
			(size 0.4318 0.4318)
			(layers "F.Cu" "F.Mask" "F.Paste")
			(net "GND")
		)
		(pad "P18" smd circle
			(at -23.58898 -20.965668 270)
			(size 0.4318 0.4318)
			(layers "F.Cu" "F.Mask" "F.Paste")
			(net "M_B_CPU0_SB_DQS_DP<7>")
		)
		(pad "P20" smd circle
			(at -21.961094 -20.965668 270)
			(size 0.4318 0.4318)
			(layers "F.Cu" "F.Mask" "F.Paste")
			(net "GND")
		)
		(pad "P22" smd circle
			(at -20.333462 -20.965668 270)
			(size 0.4318 0.4318)
			(layers "F.Cu" "F.Mask" "F.Paste")
			(net "GND")
		)
		(pad "P24" smd circle
			(at -18.705576 -20.965668 270)
			(size 0.4318 0.4318)
			(layers "F.Cu" "F.Mask" "F.Paste")
			(net "M_B_CPU0_SB_DQS_DP<6>")
		)
		(pad "P26" smd circle
			(at -17.07769 -20.965668 270)
			(size 0.4318 0.4318)
			(layers "F.Cu" "F.Mask" "F.Paste")
			(net "GND")
		)
		(pad "P28" smd circle
			(at -15.450058 -20.965668 270)
			(size 0.4318 0.4318)
			(layers "F.Cu" "F.Mask" "F.Paste")
			(net "GND")
		)
		(pad "P30" smd circle
			(at -13.822426 -20.965668 270)
			(size 0.4318 0.4318)
			(layers "F.Cu" "F.Mask" "F.Paste")
			(net "M_A_CPU0_SB_DQS_DP<5>")
		)
		(pad "P32" smd circle
			(at -12.19454 -20.965668 270)
			(size 0.4318 0.4318)
			(layers "F.Cu" "F.Mask" "F.Paste")
			(net "GND")
		)
		(pad "P34" smd circle
			(at -10.566654 -20.965668 270)
			(size 0.4318 0.4318)
			(layers "F.Cu" "F.Mask" "F.Paste")
			(net "GND")
		)
		(pad "P36" smd circle
			(at -8.939022 -20.965668 270)
			(size 0.4318 0.4318)
			(layers "F.Cu" "F.Mask" "F.Paste")
			(net "M_B_CPU0_SB_DQS_DN<4>")
		)
		(pad "P38" smd circle
			(at -7.311136 -20.965668 270)
			(size 0.4318 0.4318)
			(layers "F.Cu" "F.Mask" "F.Paste")
			(net "GND")
		)
		(pad "P40" smd circle
			(at -5.68325 -20.965668 270)
			(size 0.4318 0.4318)
			(layers "F.Cu" "F.Mask" "F.Paste")
			(net "GND")
		)
		(pad "P42" smd circle
			(at -4.055618 -20.965668 270)
			(size 0.4318 0.4318)
			(layers "F.Cu" "F.Mask" "F.Paste")
			(net "M_B_CPU0_SB_PAR")
		)
		(pad "P44" smd circle
			(at -2.427732 -20.965668 270)
			(size 0.4318 0.4318)
			(layers "F.Cu" "F.Mask" "F.Paste")
			(net "GND")
		)
		(pad "P47" smd circle
			(at 1.613916 -20.855686 270)
			(size 0.4318 0.4318)
			(layers "F.Cu" "F.Mask" "F.Paste")
			(net "GND")
		)
		(pad "P49" smd circle
			(at 3.241802 -20.855686 270)
			(size 0.4318 0.4318)
			(layers "F.Cu" "F.Mask" "F.Paste")
			(net "M_B_CPU0_SA_CA<1>")
		)
		(pad "P51" smd circle
			(at 4.869434 -20.855686 270)
			(size 0.4318 0.4318)
			(layers "F.Cu" "F.Mask" "F.Paste")
			(net "GND")
		)
		(pad "P53" smd circle
			(at 6.49732 -20.855686 270)
			(size 0.4318 0.4318)
			(layers "F.Cu" "F.Mask" "F.Paste")
			(net "GND")
		)
		(pad "P55" smd circle
			(at 8.124952 -20.855686 270)
			(size 0.4318 0.4318)
			(layers "F.Cu" "F.Mask" "F.Paste")
			(net "M_B_CPU0_SA_DQS_DP<9>")
		)
		(pad "P57" smd circle
			(at 9.752838 -20.855686 270)
			(size 0.4318 0.4318)
			(layers "F.Cu" "F.Mask" "F.Paste")
			(net "GND")
		)
		(pad "P59" smd circle
			(at 11.380724 -20.855686 270)
			(size 0.4318 0.4318)
			(layers "F.Cu" "F.Mask" "F.Paste")
			(net "GND")
		)
		(pad "P61" smd circle
			(at 13.008356 -20.855686 270)
			(size 0.4318 0.4318)
			(layers "F.Cu" "F.Mask" "F.Paste")
			(net "M_B_CPU0_SA_DQS_DP<7>")
		)
		(pad "P63" smd circle
			(at 14.635988 -20.855686 270)
			(size 0.4318 0.4318)
			(layers "F.Cu" "F.Mask" "F.Paste")
			(net "GND")
		)
		(pad "P65" smd circle
			(at 16.263874 -20.855686 270)
			(size 0.4318 0.4318)
			(layers "F.Cu" "F.Mask" "F.Paste")
			(net "GND")
		)
		(pad "P67" smd circle
			(at 17.89176 -20.855686 270)
			(size 0.4318 0.4318)
			(layers "F.Cu" "F.Mask" "F.Paste")
			(net "M_A_CPU0_SA_DQS_DN<6>")
		)
		(pad "P69" smd circle
			(at 19.519392 -20.855686 270)
			(size 0.4318 0.4318)
			(layers "F.Cu" "F.Mask" "F.Paste")
			(net "GND")
		)
		(pad "P71" smd circle
			(at 21.147278 -20.855686 270)
			(size 0.4318 0.4318)
			(layers "F.Cu" "F.Mask" "F.Paste")
			(net "GND")
		)
		(pad "P73" smd circle
			(at 22.77491 -20.855686 270)
			(size 0.4318 0.4318)
			(layers "F.Cu" "F.Mask" "F.Paste")
			(net "M_B_CPU0_SA_DQS_DP<5>")
		)
		(pad "P75" smd circle
			(at 24.402796 -20.855686 270)
			(size 0.4318 0.4318)
			(layers "F.Cu" "F.Mask" "F.Paste")
			(net "GND")
		)
		(pad "P77" smd circle
			(at 26.030682 -20.855686 270)
			(size 0.4318 0.4318)
			(layers "F.Cu" "F.Mask" "F.Paste")
			(net "GND")
		)
		(pad "P79" smd circle
			(at 27.658314 -20.855686 270)
			(size 0.4318 0.4318)
			(layers "F.Cu" "F.Mask" "F.Paste")
			(net "PVCCFA_EHV_FIVRA_CPU0")
		)
		(pad "P81" smd circle
			(at 29.2862 -20.855686 270)
			(size 0.4318 0.4318)
			(layers "F.Cu" "F.Mask" "F.Paste")
			(net "UPI_CPU0_CPU1_P2P2_DN<18>")
		)
		(pad "P83" smd circle
			(at 30.914086 -20.855686 270)
			(size 0.4318 0.4318)
			(layers "F.Cu" "F.Mask" "F.Paste")
			(net "UPI_CPU0_CPU1_P2P2_DP<17>")
		)
		(pad "P85" smd circle
			(at 32.541718 -20.855686 270)
			(size 0.4318 0.4318)
			(layers "F.Cu" "F.Mask" "F.Paste")
			(net "P5E_CPU0_PE4_TX_DN<1>")
		)
		(pad "P87" smd circle
			(at 34.169604 -20.855686 270)
			(size 0.4318 0.4318)
			(layers "F.Cu" "F.Mask" "F.Paste")
			(net "GND")
		)
		(pad "P89" smd circle
			(at 35.797236 -20.855686 270)
			(size 0.4318 0.4318)
			(layers "F.Cu" "F.Mask" "F.Paste")
			(net "P5E_CPU0_PE4_RX_DN<1>")
		)
		(pad "P91" smd oval
			(at 37.425122 -20.855686)
			(size 0.381 0.4826)
			(drill
				(offset 0 -0.0508)
			)
			(layers "F.Cu" "F.Mask" "F.Paste")
			(net "GND")
		)
		(pad "R1" smd oval
			(at -37.425122 -20.495514 180)
			(size 0.381 0.4826)
			(drill
				(offset 0 -0.0508)
			)
			(layers "F.Cu" "F.Mask" "F.Paste")
			(net "GND")
		)
		(pad "R3" smd circle
			(at -35.797236 -20.495514 270)
			(size 0.4318 0.4318)
			(layers "F.Cu" "F.Mask" "F.Paste")
			(net "UPI_CPU0_CPU1_P0P1_DP<3>")
		)
		(pad "R5" smd circle
			(at -34.169604 -20.495514 270)
			(size 0.4318 0.4318)
			(layers "F.Cu" "F.Mask" "F.Paste")
			(net "GND")
		)
		(pad "R7" smd circle
			(at -32.541718 -20.495514 270)
			(size 0.4318 0.4318)
			(layers "F.Cu" "F.Mask" "F.Paste")
			(net "UPI_CPU1_CPU0_P1P0_DP<2>")
		)
		(pad "R9" smd circle
			(at -30.914086 -20.495514 270)
			(size 0.4318 0.4318)
			(layers "F.Cu" "F.Mask" "F.Paste")
			(net "GND")
		)
		(pad "R11" smd circle
			(at -29.2862 -20.495514 270)
			(size 0.4318 0.4318)
			(layers "F.Cu" "F.Mask" "F.Paste")
			(net "P5E_CPU0_PE0_RX_DP<2>")
		)
		(pad "R13" smd circle
			(at -27.658314 -20.495514 270)
			(size 0.4318 0.4318)
			(layers "F.Cu" "F.Mask" "F.Paste")
			(net "GND")
		)
		(pad "R15" smd circle
			(at -26.030682 -20.495514 270)
			(size 0.4318 0.4318)
			(layers "F.Cu" "F.Mask" "F.Paste")
			(net "P5E_CPU0_PE0_TX_DP<1>")
		)
		(pad "R17" smd circle
			(at -24.402796 -20.495514 270)
			(size 0.4318 0.4318)
			(layers "F.Cu" "F.Mask" "F.Paste")
			(net "GND")
		)
		(pad "R19" smd circle
			(at -22.77491 -20.495514 270)
			(size 0.4318 0.4318)
			(layers "F.Cu" "F.Mask" "F.Paste")
			(net "GND")
		)
		(pad "R21" smd circle
			(at -21.147278 -20.495514 270)
			(size 0.4318 0.4318)
			(layers "F.Cu" "F.Mask" "F.Paste")
			(net "M_C_CPU0_SB_DQS_DN<2>")
		)
		(pad "R23" smd circle
			(at -19.519392 -20.495514 270)
			(size 0.4318 0.4318)
			(layers "F.Cu" "F.Mask" "F.Paste")
			(net "GND")
		)
		(pad "R25" smd circle
			(at -17.89176 -20.495514 270)
			(size 0.4318 0.4318)
			(layers "F.Cu" "F.Mask" "F.Paste")
			(net "GND")
		)
		(pad "R27" smd circle
			(at -16.263874 -20.495514 270)
			(size 0.4318 0.4318)
			(layers "F.Cu" "F.Mask" "F.Paste")
			(net "M_B_CPU0_SB_DQS_DN<0>")
		)
		(pad "R29" smd circle
			(at -14.635988 -20.495514 270)
			(size 0.4318 0.4318)
			(layers "F.Cu" "F.Mask" "F.Paste")
			(net "GND")
		)
		(pad "R31" smd circle
			(at -13.008356 -20.495514 270)
			(size 0.4318 0.4318)
			(layers "F.Cu" "F.Mask" "F.Paste")
			(net "GND")
		)
		(pad "R33" smd circle
			(at -11.380724 -20.495514 270)
			(size 0.4318 0.4318)
			(layers "F.Cu" "F.Mask" "F.Paste")
			(net "M_C_CPU0_SB_DQS_DN<9>")
		)
		(pad "R35" smd circle
			(at -9.752838 -20.495514 270)
			(size 0.4318 0.4318)
			(layers "F.Cu" "F.Mask" "F.Paste")
			(net "GND")
		)
		(pad "R37" smd circle
			(at -8.124952 -20.495514 270)
			(size 0.4318 0.4318)
			(layers "F.Cu" "F.Mask" "F.Paste")
			(net "GND")
		)
		(pad "R39" smd circle
			(at -6.49732 -20.495514 270)
			(size 0.4318 0.4318)
			(layers "F.Cu" "F.Mask" "F.Paste")
			(net "M_C_CPU0_SB_CA<6>")
		)
		(pad "R41" smd circle
			(at -4.869434 -20.495514 270)
			(size 0.4318 0.4318)
			(layers "F.Cu" "F.Mask" "F.Paste")
			(net "GND")
		)
		(pad "R43" smd circle
			(at -3.241802 -20.495514 270)
			(size 0.4318 0.4318)
			(layers "F.Cu" "F.Mask" "F.Paste")
			(net "GND")
		)
		(pad "R45" smd circle
			(at -1.613916 -20.495514 270)
			(size 0.4318 0.4318)
			(layers "F.Cu" "F.Mask" "F.Paste")
			(net "M_B_CPU0_CLK_DN<0>")
		)
		(pad "R48" smd circle
			(at 2.427732 -20.385532 270)
			(size 0.4318 0.4318)
			(layers "F.Cu" "F.Mask" "F.Paste")
			(net "GND")
		)
		(pad "R50" smd circle
			(at 4.055618 -20.385532 270)
			(size 0.4318 0.4318)
			(layers "F.Cu" "F.Mask" "F.Paste")
			(net "GND")
		)
		(pad "R52" smd circle
			(at 5.68325 -20.385532 270)
			(size 0.4318 0.4318)
			(layers "F.Cu" "F.Mask" "F.Paste")
			(net "M_C_CPU0_SA_CA<0>")
		)
		(pad "R54" smd circle
			(at 7.311136 -20.385532 270)
			(size 0.4318 0.4318)
			(layers "F.Cu" "F.Mask" "F.Paste")
			(net "GND")
		)
		(pad "R56" smd circle
			(at 8.939022 -20.385532 270)
			(size 0.4318 0.4318)
			(layers "F.Cu" "F.Mask" "F.Paste")
			(net "GND")
		)
		(pad "R58" smd circle
			(at 10.566654 -20.385532 270)
			(size 0.4318 0.4318)
			(layers "F.Cu" "F.Mask" "F.Paste")
			(net "M_B_CPU0_SA_DQS_DN<3>")
		)
		(pad "R60" smd circle
			(at 12.19454 -20.385532 270)
			(size 0.4318 0.4318)
			(layers "F.Cu" "F.Mask" "F.Paste")
			(net "GND")
		)
		(pad "R62" smd circle
			(at 13.822426 -20.385532 270)
			(size 0.4318 0.4318)
			(layers "F.Cu" "F.Mask" "F.Paste")
			(net "GND")
		)
		(pad "R64" smd circle
			(at 15.450058 -20.385532 270)
			(size 0.4318 0.4318)
			(layers "F.Cu" "F.Mask" "F.Paste")
			(net "M_C_CPU0_SA_DQS_DN<2>")
		)
		(pad "R66" smd circle
			(at 17.07769 -20.385532 270)
			(size 0.4318 0.4318)
			(layers "F.Cu" "F.Mask" "F.Paste")
			(net "GND")
		)
		(pad "R68" smd circle
			(at 18.705576 -20.385532 270)
			(size 0.4318 0.4318)
			(layers "F.Cu" "F.Mask" "F.Paste")
			(net "GND")
		)
		(pad "R70" smd circle
			(at 20.333462 -20.385532 270)
			(size 0.4318 0.4318)
			(layers "F.Cu" "F.Mask" "F.Paste")
			(net "M_B_CPU0_SA_DQS_DN<1>")
		)
		(pad "R72" smd circle
			(at 21.961094 -20.385532 270)
			(size 0.4318 0.4318)
			(layers "F.Cu" "F.Mask" "F.Paste")
			(net "GND")
		)
		(pad "R74" smd circle
			(at 23.58898 -20.385532 270)
			(size 0.4318 0.4318)
			(layers "F.Cu" "F.Mask" "F.Paste")
			(net "GND")
		)
		(pad "R76" smd circle
			(at 25.216612 -20.385532 270)
			(size 0.4318 0.4318)
			(layers "F.Cu" "F.Mask" "F.Paste")
			(net "M_C_CPU0_SA_DQS_DN<0>")
		)
		(pad "R78" smd circle
			(at 26.844498 -20.385532 270)
			(size 0.4318 0.4318)
			(layers "F.Cu" "F.Mask" "F.Paste")
			(net "GND")
		)
		(pad "R80" smd circle
			(at 28.472384 -20.385532 270)
			(size 0.4318 0.4318)
			(layers "F.Cu" "F.Mask" "F.Paste")
			(net "PVCCFA_EHV_FIVRA_CPU0")
		)
		(pad "R82" smd circle
			(at 30.100016 -20.385532 270)
			(size 0.4318 0.4318)
			(layers "F.Cu" "F.Mask" "F.Paste")
			(net "UPI_CPU0_CPU1_P2P2_DN<17>")
		)
		(pad "R84" smd circle
			(at 31.727902 -20.385532 270)
			(size 0.4318 0.4318)
			(layers "F.Cu" "F.Mask" "F.Paste")
			(net "GND")
		)
		(pad "R86" smd circle
			(at 33.355534 -20.385532 270)
			(size 0.4318 0.4318)
			(layers "F.Cu" "F.Mask" "F.Paste")
			(net "P5E_CPU0_PE4_TX_DN<2>")
		)
		(pad "R88" smd circle
			(at 34.98342 -20.385532 270)
			(size 0.4318 0.4318)
			(layers "F.Cu" "F.Mask" "F.Paste")
			(net "GND")
		)
		(pad "R90" smd circle
			(at 36.611306 -20.385532 270)
			(size 0.4318 0.4318)
			(layers "F.Cu" "F.Mask" "F.Paste")
			(net "P5E_CPU0_PE4_RX_DP<2>")
		)
		(pad "T2" smd circle
			(at -36.611306 -20.025868 270)
			(size 0.4318 0.4318)
			(layers "F.Cu" "F.Mask" "F.Paste")
			(net "UPI_CPU0_CPU1_P0P1_DN<3>")
		)
		(pad "T4" smd circle
			(at -34.98342 -20.025868 270)
			(size 0.4318 0.4318)
			(layers "F.Cu" "F.Mask" "F.Paste")
			(net "GND")
		)
		(pad "T6" smd circle
			(at -33.355534 -20.025868 270)
			(size 0.4318 0.4318)
			(layers "F.Cu" "F.Mask" "F.Paste")
			(net "UPI_CPU1_CPU0_P1P0_DN<3>")
		)
		(pad "T8" smd circle
			(at -31.727902 -20.025868 270)
			(size 0.4318 0.4318)
			(layers "F.Cu" "F.Mask" "F.Paste")
			(net "GND")
		)
		(pad "T10" smd circle
			(at -30.100016 -20.025868 270)
			(size 0.4318 0.4318)
			(layers "F.Cu" "F.Mask" "F.Paste")
			(net "P5E_CPU0_PE0_RX_DN<3>")
		)
		(pad "T12" smd circle
			(at -28.472384 -20.025868 270)
			(size 0.4318 0.4318)
			(layers "F.Cu" "F.Mask" "F.Paste")
			(net "GND")
		)
		(pad "T14" smd circle
			(at -26.844498 -20.025868 270)
			(size 0.4318 0.4318)
			(layers "F.Cu" "F.Mask" "F.Paste")
			(net "P5E_CPU0_PE0_TX_DP<2>")
		)
		(pad "T16" smd circle
			(at -25.216612 -20.025868 270)
			(size 0.4318 0.4318)
			(layers "F.Cu" "F.Mask" "F.Paste")
			(net "GND")
		)
		(pad "T18" smd circle
			(at -23.58898 -20.025868 270)
			(size 0.4318 0.4318)
			(layers "F.Cu" "F.Mask" "F.Paste")
			(net "GND")
		)
		(pad "T20" smd circle
			(at -21.961094 -20.025868 270)
			(size 0.4318 0.4318)
			(layers "F.Cu" "F.Mask" "F.Paste")
			(net "M_C_CPU0_SB_DQ<20>")
		)
		(pad "T22" smd circle
			(at -20.333462 -20.025868 270)
			(size 0.4318 0.4318)
			(layers "F.Cu" "F.Mask" "F.Paste")
			(net "M_C_CPU0_SB_DQ<17>")
		)
		(pad "T24" smd circle
			(at -18.705576 -20.025868 270)
			(size 0.4318 0.4318)
			(layers "F.Cu" "F.Mask" "F.Paste")
			(net "GND")
		)
		(pad "T26" smd circle
			(at -17.07769 -20.025868 270)
			(size 0.4318 0.4318)
			(layers "F.Cu" "F.Mask" "F.Paste")
			(net "M_B_CPU0_SB_DQ<4>")
		)
		(pad "T28" smd circle
			(at -15.450058 -20.025868 270)
			(size 0.4318 0.4318)
			(layers "F.Cu" "F.Mask" "F.Paste")
			(net "M_B_CPU0_SB_DQ<1>")
		)
		(pad "T30" smd circle
			(at -13.822426 -20.025868 270)
			(size 0.4318 0.4318)
			(layers "F.Cu" "F.Mask" "F.Paste")
			(net "GND")
		)
		(pad "T32" smd circle
			(at -12.19454 -20.025868 270)
			(size 0.4318 0.4318)
			(layers "F.Cu" "F.Mask" "F.Paste")
			(net "M_C_CPU0_SB_CB<0>")
		)
		(pad "T34" smd circle
			(at -10.566654 -20.025868 270)
			(size 0.4318 0.4318)
			(layers "F.Cu" "F.Mask" "F.Paste")
			(net "M_C_CPU0_SB_CB<5>")
		)
		(pad "T36" smd circle
			(at -8.939022 -20.025868 270)
			(size 0.4318 0.4318)
			(layers "F.Cu" "F.Mask" "F.Paste")
			(net "GND")
		)
		(pad "T38" smd circle
			(at -7.311136 -20.025868 270)
			(size 0.4318 0.4318)
			(layers "F.Cu" "F.Mask" "F.Paste")
			(net "M_C_CPU0_SB_CS_N<0>")
		)
		(pad "T40" smd circle
			(at -5.68325 -20.025868 270)
			(size 0.4318 0.4318)
			(layers "F.Cu" "F.Mask" "F.Paste")
			(net "M_C_CPU0_SB_CA<4>")
		)
		(pad "T42" smd circle
			(at -4.055618 -20.025868 270)
			(size 0.4318 0.4318)
			(layers "F.Cu" "F.Mask" "F.Paste")
			(net "GND")
		)
		(pad "T44" smd circle
			(at -2.427732 -20.025868 270)
			(size 0.4318 0.4318)
			(layers "F.Cu" "F.Mask" "F.Paste")
			(net "M_B_CPU0_SB_CA<0>")
		)
		(pad "T47" smd circle
			(at 1.613916 -19.915886 270)
			(size 0.4318 0.4318)
			(layers "F.Cu" "F.Mask" "F.Paste")
			(net "M_C_CPU0_SA_PAR")
		)
		(pad "T49" smd circle
			(at 3.241802 -19.915886 270)
			(size 0.4318 0.4318)
			(layers "F.Cu" "F.Mask" "F.Paste")
			(net "GND")
		)
		(pad "T51" smd circle
			(at 4.869434 -19.915886 270)
			(size 0.4318 0.4318)
			(layers "F.Cu" "F.Mask" "F.Paste")
			(net "M_C_CPU0_SA_CA<2>")
		)
		(pad "T53" smd circle
			(at 6.49732 -19.915886 270)
			(size 0.4318 0.4318)
			(layers "F.Cu" "F.Mask" "F.Paste")
			(net "M_C_CPU0_SA_CS_N<1>")
		)
		(pad "T55" smd circle
			(at 8.124952 -19.915886 270)
			(size 0.4318 0.4318)
			(layers "F.Cu" "F.Mask" "F.Paste")
			(net "GND")
		)
		(pad "T57" smd circle
			(at 9.752838 -19.915886 270)
			(size 0.4318 0.4318)
			(layers "F.Cu" "F.Mask" "F.Paste")
			(net "M_B_CPU0_SA_DQ<28>")
		)
		(pad "T59" smd circle
			(at 11.380724 -19.915886 270)
			(size 0.4318 0.4318)
			(layers "F.Cu" "F.Mask" "F.Paste")
			(net "M_B_CPU0_SA_DQ<25>")
		)
		(pad "T61" smd circle
			(at 13.008356 -19.915886 270)
			(size 0.4318 0.4318)
			(layers "F.Cu" "F.Mask" "F.Paste")
			(net "GND")
		)
		(pad "T63" smd circle
			(at 14.635988 -19.915886 270)
			(size 0.4318 0.4318)
			(layers "F.Cu" "F.Mask" "F.Paste")
			(net "M_C_CPU0_SA_DQ<20>")
		)
		(pad "T65" smd circle
			(at 16.263874 -19.915886 270)
			(size 0.4318 0.4318)
			(layers "F.Cu" "F.Mask" "F.Paste")
			(net "M_C_CPU0_SA_DQ<17>")
		)
		(pad "T67" smd circle
			(at 17.89176 -19.915886 270)
			(size 0.4318 0.4318)
			(layers "F.Cu" "F.Mask" "F.Paste")
			(net "GND")
		)
		(pad "T69" smd circle
			(at 19.519392 -19.915886 270)
			(size 0.4318 0.4318)
			(layers "F.Cu" "F.Mask" "F.Paste")
			(net "M_B_CPU0_SA_DQ<12>")
		)
		(pad "T71" smd circle
			(at 21.147278 -19.915886 270)
			(size 0.4318 0.4318)
			(layers "F.Cu" "F.Mask" "F.Paste")
			(net "M_B_CPU0_SA_DQ<9>")
		)
		(pad "T73" smd circle
			(at 22.77491 -19.915886 270)
			(size 0.4318 0.4318)
			(layers "F.Cu" "F.Mask" "F.Paste")
			(net "GND")
		)
		(pad "T75" smd circle
			(at 24.402796 -19.915886 270)
			(size 0.4318 0.4318)
			(layers "F.Cu" "F.Mask" "F.Paste")
			(net "M_C_CPU0_SA_DQ<4>")
		)
		(pad "T77" smd circle
			(at 26.030682 -19.915886 270)
			(size 0.4318 0.4318)
			(layers "F.Cu" "F.Mask" "F.Paste")
			(net "M_C_CPU0_SA_DQ<1>")
		)
		(pad "T79" smd circle
			(at 27.658314 -19.915886 270)
			(size 0.4318 0.4318)
			(layers "F.Cu" "F.Mask" "F.Paste")
			(net "GND")
		)
		(pad "T81" smd circle
			(at 29.2862 -19.915886 270)
			(size 0.4318 0.4318)
			(layers "F.Cu" "F.Mask" "F.Paste")
			(net "UPI_CPU0_CPU1_P2P2_DP<18>")
		)
		(pad "T83" smd circle
			(at 30.914086 -19.915886 270)
			(size 0.4318 0.4318)
			(layers "F.Cu" "F.Mask" "F.Paste")
			(net "GND")
		)
		(pad "T85" smd circle
			(at 32.541718 -19.915886 270)
			(size 0.4318 0.4318)
			(layers "F.Cu" "F.Mask" "F.Paste")
			(net "PVCCFA_EHV_FIVRA_CPU0")
		)
		(pad "T87" smd circle
			(at 34.169604 -19.915886 270)
			(size 0.4318 0.4318)
			(layers "F.Cu" "F.Mask" "F.Paste")
			(net "P5E_CPU0_PE4_TX_DP<2>")
		)
		(pad "T89" smd circle
			(at 35.797236 -19.915886 270)
			(size 0.4318 0.4318)
			(layers "F.Cu" "F.Mask" "F.Paste")
			(net "PVCCFA_EHV_FIVRA_CPU0")
		)
		(pad "T91" smd oval
			(at 37.425122 -19.915886)
			(size 0.381 0.4826)
			(drill
				(offset 0 -0.0508)
			)
			(layers "F.Cu" "F.Mask" "F.Paste")
			(net "P5E_CPU0_PE4_RX_DN<2>")
		)
		(pad "U1" smd oval
			(at -37.425122 -19.555714 180)
			(size 0.381 0.4826)
			(drill
				(offset 0 -0.0508)
			)
			(layers "F.Cu" "F.Mask" "F.Paste")
			(net "UPI_CPU0_CPU1_P0P1_DN<4>")
		)
		(pad "U3" smd circle
			(at -35.797236 -19.555714 270)
			(size 0.4318 0.4318)
			(layers "F.Cu" "F.Mask" "F.Paste")
			(net "PVCCFA_EHV_CPU0")
		)
		(pad "U5" smd circle
			(at -34.169604 -19.555714 270)
			(size 0.4318 0.4318)
			(layers "F.Cu" "F.Mask" "F.Paste")
			(net "UPI_CPU1_CPU0_P1P0_DP<3>")
		)
		(pad "U7" smd circle
			(at -32.541718 -19.555714 270)
			(size 0.4318 0.4318)
			(layers "F.Cu" "F.Mask" "F.Paste")
			(net "PVCCFA_EHV_FIVRA_CPU0")
		)
		(pad "U9" smd circle
			(at -30.914086 -19.555714 270)
			(size 0.4318 0.4318)
			(layers "F.Cu" "F.Mask" "F.Paste")
			(net "P5E_CPU0_PE0_RX_DP<3>")
		)
		(pad "U11" smd circle
			(at -29.2862 -19.555714 270)
			(size 0.4318 0.4318)
			(layers "F.Cu" "F.Mask" "F.Paste")
			(net "PVCCFA_EHV_FIVRA_CPU0")
		)
		(pad "U13" smd circle
			(at -27.658314 -19.555714 270)
			(size 0.4318 0.4318)
			(layers "F.Cu" "F.Mask" "F.Paste")
			(net "P5E_CPU0_PE0_TX_DN<2>")
		)
		(pad "U15" smd circle
			(at -26.030682 -19.555714 270)
			(size 0.4318 0.4318)
			(layers "F.Cu" "F.Mask" "F.Paste")
			(net "PVCCFA_EHV_FIVRA_CPU0")
		)
		(pad "U17" smd circle
			(at -24.402796 -19.555714 270)
			(size 0.4318 0.4318)
			(layers "F.Cu" "F.Mask" "F.Paste")
			(net "NC_CPU0_HBM0_VIEWDIG0")
		)
		(pad "U19" smd circle
			(at -22.77491 -19.555714 270)
			(size 0.4318 0.4318)
			(layers "F.Cu" "F.Mask" "F.Paste")
			(net "M_C_CPU0_SB_DQ<21>")
		)
		(pad "U21" smd circle
			(at -21.147278 -19.555714 270)
			(size 0.4318 0.4318)
			(layers "F.Cu" "F.Mask" "F.Paste")
			(net "M_C_CPU0_SB_DQS_DP<2>")
		)
		(pad "U23" smd circle
			(at -19.519392 -19.555714 270)
			(size 0.4318 0.4318)
			(layers "F.Cu" "F.Mask" "F.Paste")
			(net "M_C_CPU0_SB_DQ<16>")
		)
		(pad "U25" smd circle
			(at -17.89176 -19.555714 270)
			(size 0.4318 0.4318)
			(layers "F.Cu" "F.Mask" "F.Paste")
			(net "M_B_CPU0_SB_DQ<5>")
		)
		(pad "U27" smd circle
			(at -16.263874 -19.555714 270)
			(size 0.4318 0.4318)
			(layers "F.Cu" "F.Mask" "F.Paste")
			(net "M_B_CPU0_SB_DQS_DP<0>")
		)
		(pad "U29" smd circle
			(at -14.635988 -19.555714 270)
			(size 0.4318 0.4318)
			(layers "F.Cu" "F.Mask" "F.Paste")
			(net "M_B_CPU0_SB_DQ<0>")
		)
		(pad "U31" smd circle
			(at -13.008356 -19.555714 270)
			(size 0.4318 0.4318)
			(layers "F.Cu" "F.Mask" "F.Paste")
			(net "M_C_CPU0_SB_CB<1>")
		)
		(pad "U33" smd circle
			(at -11.380724 -19.555714 270)
			(size 0.4318 0.4318)
			(layers "F.Cu" "F.Mask" "F.Paste")
			(net "M_C_CPU0_SB_DQS_DP<9>")
		)
		(pad "U35" smd circle
			(at -9.752838 -19.555714 270)
			(size 0.4318 0.4318)
			(layers "F.Cu" "F.Mask" "F.Paste")
			(net "M_C_CPU0_SB_CB<4>")
		)
		(pad "U37" smd circle
			(at -8.124952 -19.555714 270)
			(size 0.4318 0.4318)
			(layers "F.Cu" "F.Mask" "F.Paste")
			(net "M_C_CPU0_SB_CS_N<1>")
		)
		(pad "U39" smd circle
			(at -6.49732 -19.555714 270)
			(size 0.4318 0.4318)
			(layers "F.Cu" "F.Mask" "F.Paste")
			(net "GND")
		)
		(pad "U41" smd circle
			(at -4.869434 -19.555714 270)
			(size 0.4318 0.4318)
			(layers "F.Cu" "F.Mask" "F.Paste")
			(net "M_C_CPU0_SB_CA<2>")
		)
		(pad "U43" smd circle
			(at -3.241802 -19.555714 270)
			(size 0.4318 0.4318)
			(layers "F.Cu" "F.Mask" "F.Paste")
			(net "M_B_CPU0_SB_CA<1>")
		)
		(pad "U45" smd circle
			(at -1.613916 -19.555714 270)
			(size 0.4318 0.4318)
			(layers "F.Cu" "F.Mask" "F.Paste")
			(net "M_B_CPU0_CLK_DP<0>")
		)
		(pad "U48" smd circle
			(at 2.427732 -19.445732 270)
			(size 0.4318 0.4318)
			(layers "F.Cu" "F.Mask" "F.Paste")
			(net "M_C_CPU0_SA_CA<6>")
		)
		(pad "U50" smd circle
			(at 4.055618 -19.445732 270)
			(size 0.4318 0.4318)
			(layers "F.Cu" "F.Mask" "F.Paste")
			(net "M_C_CPU0_SA_CA<4>")
		)
		(pad "U52" smd circle
			(at 5.68325 -19.445732 270)
			(size 0.4318 0.4318)
			(layers "F.Cu" "F.Mask" "F.Paste")
			(net "GND")
		)
		(pad "U54" smd circle
			(at 7.311136 -19.445732 270)
			(size 0.4318 0.4318)
			(layers "F.Cu" "F.Mask" "F.Paste")
			(net "M_C_CPU0_SA_CS_N<0>")
		)
		(pad "U56" smd circle
			(at 8.939022 -19.445732 270)
			(size 0.4318 0.4318)
			(layers "F.Cu" "F.Mask" "F.Paste")
			(net "M_B_CPU0_SA_DQ<29>")
		)
		(pad "U58" smd circle
			(at 10.566654 -19.445732 270)
			(size 0.4318 0.4318)
			(layers "F.Cu" "F.Mask" "F.Paste")
			(net "M_B_CPU0_SA_DQS_DP<3>")
		)
		(pad "U60" smd circle
			(at 12.19454 -19.445732 270)
			(size 0.4318 0.4318)
			(layers "F.Cu" "F.Mask" "F.Paste")
			(net "M_B_CPU0_SA_DQ<24>")
		)
		(pad "U62" smd circle
			(at 13.822426 -19.445732 270)
			(size 0.4318 0.4318)
			(layers "F.Cu" "F.Mask" "F.Paste")
			(net "M_C_CPU0_SA_DQ<21>")
		)
		(pad "U64" smd circle
			(at 15.450058 -19.445732 270)
			(size 0.4318 0.4318)
			(layers "F.Cu" "F.Mask" "F.Paste")
			(net "M_C_CPU0_SA_DQS_DP<2>")
		)
		(pad "U66" smd circle
			(at 17.07769 -19.445732 270)
			(size 0.4318 0.4318)
			(layers "F.Cu" "F.Mask" "F.Paste")
			(net "M_C_CPU0_SA_DQ<16>")
		)
		(pad "U68" smd circle
			(at 18.705576 -19.445732 270)
			(size 0.4318 0.4318)
			(layers "F.Cu" "F.Mask" "F.Paste")
			(net "M_B_CPU0_SA_DQ<13>")
		)
		(pad "U70" smd circle
			(at 20.333462 -19.445732 270)
			(size 0.4318 0.4318)
			(layers "F.Cu" "F.Mask" "F.Paste")
			(net "M_B_CPU0_SA_DQS_DP<1>")
		)
		(pad "U72" smd circle
			(at 21.961094 -19.445732 270)
			(size 0.4318 0.4318)
			(layers "F.Cu" "F.Mask" "F.Paste")
			(net "M_B_CPU0_SA_DQ<8>")
		)
		(pad "U74" smd circle
			(at 23.58898 -19.445732 270)
			(size 0.4318 0.4318)
			(layers "F.Cu" "F.Mask" "F.Paste")
			(net "M_C_CPU0_SA_DQ<5>")
		)
		(pad "U76" smd circle
			(at 25.216612 -19.445732 270)
			(size 0.4318 0.4318)
			(layers "F.Cu" "F.Mask" "F.Paste")
			(net "M_C_CPU0_SA_DQS_DP<0>")
		)
		(pad "U78" smd circle
			(at 26.844498 -19.445732 270)
			(size 0.4318 0.4318)
			(layers "F.Cu" "F.Mask" "F.Paste")
			(net "M_C_CPU0_SA_DQ<0>")
		)
		(pad "U80" smd circle
			(at 28.472384 -19.445732 270)
			(size 0.4318 0.4318)
			(layers "F.Cu" "F.Mask" "F.Paste")
			(net "UPI_CPU0_CPU1_P2P2_DN<16>")
		)
		(pad "U82" smd circle
			(at 30.100016 -19.445732 270)
			(size 0.4318 0.4318)
			(layers "F.Cu" "F.Mask" "F.Paste")
			(net "GND")
		)
		(pad "U84" smd circle
			(at 31.727902 -19.445732 270)
			(size 0.4318 0.4318)
			(layers "F.Cu" "F.Mask" "F.Paste")
			(net "GND")
		)
		(pad "U86" smd circle
			(at 33.355534 -19.445732 270)
			(size 0.4318 0.4318)
			(layers "F.Cu" "F.Mask" "F.Paste")
			(net "P5E_CPU0_PE4_TX_DN<3>")
		)
		(pad "U88" smd circle
			(at 34.98342 -19.445732 270)
			(size 0.4318 0.4318)
			(layers "F.Cu" "F.Mask" "F.Paste")
			(net "GND")
		)
		(pad "U90" smd circle
			(at 36.611306 -19.445732 270)
			(size 0.4318 0.4318)
			(layers "F.Cu" "F.Mask" "F.Paste")
			(net "P5E_CPU0_PE4_RX_DP<3>")
		)
		(pad "V2" smd circle
			(at -36.611306 -19.086068 270)
			(size 0.4318 0.4318)
			(layers "F.Cu" "F.Mask" "F.Paste")
			(net "UPI_CPU0_CPU1_P0P1_DP<4>")
		)
		(pad "V4" smd circle
			(at -34.98342 -19.086068 270)
			(size 0.4318 0.4318)
			(layers "F.Cu" "F.Mask" "F.Paste")
			(net "GND")
		)
		(pad "V6" smd circle
			(at -33.355534 -19.086068 270)
			(size 0.4318 0.4318)
			(layers "F.Cu" "F.Mask" "F.Paste")
			(net "UPI_CPU1_CPU0_P1P0_DN<4>")
		)
		(pad "V8" smd circle
			(at -31.727902 -19.086068 270)
			(size 0.4318 0.4318)
			(layers "F.Cu" "F.Mask" "F.Paste")
			(net "GND")
		)
		(pad "V10" smd circle
			(at -30.100016 -19.086068 270)
			(size 0.4318 0.4318)
			(layers "F.Cu" "F.Mask" "F.Paste")
			(net "P5E_CPU0_PE0_RX_DN<4>")
		)
		(pad "V12" smd circle
			(at -28.472384 -19.086068 270)
			(size 0.4318 0.4318)
			(layers "F.Cu" "F.Mask" "F.Paste")
			(net "GND")
		)
		(pad "V14" smd circle
			(at -26.844498 -19.086068 270)
			(size 0.4318 0.4318)
			(layers "F.Cu" "F.Mask" "F.Paste")
			(net "P5E_CPU0_PE0_TX_DN<3>")
		)
		(pad "V16" smd circle
			(at -25.216612 -19.086068 270)
			(size 0.4318 0.4318)
			(layers "F.Cu" "F.Mask" "F.Paste")
			(net "GND")
		)
		(pad "V18" smd circle
			(at -23.58898 -19.086068 270)
			(size 0.4318 0.4318)
			(layers "F.Cu" "F.Mask" "F.Paste")
			(net "GND")
		)
		(pad "V20" smd circle
			(at -21.961094 -19.086068 270)
			(size 0.4318 0.4318)
			(layers "F.Cu" "F.Mask" "F.Paste")
			(net "GND")
		)
		(pad "V22" smd circle
			(at -20.333462 -19.086068 270)
			(size 0.4318 0.4318)
			(layers "F.Cu" "F.Mask" "F.Paste")
			(net "GND")
		)
		(pad "V24" smd circle
			(at -18.705576 -19.086068 270)
			(size 0.4318 0.4318)
			(layers "F.Cu" "F.Mask" "F.Paste")
			(net "GND")
		)
		(pad "V26" smd circle
			(at -17.07769 -19.086068 270)
			(size 0.4318 0.4318)
			(layers "F.Cu" "F.Mask" "F.Paste")
			(net "GND")
		)
		(pad "V28" smd circle
			(at -15.450058 -19.086068 270)
			(size 0.4318 0.4318)
			(layers "F.Cu" "F.Mask" "F.Paste")
			(net "GND")
		)
		(pad "V30" smd circle
			(at -13.822426 -19.086068 270)
			(size 0.4318 0.4318)
			(layers "F.Cu" "F.Mask" "F.Paste")
			(net "GND")
		)
		(pad "V32" smd circle
			(at -12.19454 -19.086068 270)
			(size 0.4318 0.4318)
			(layers "F.Cu" "F.Mask" "F.Paste")
			(net "GND")
		)
		(pad "V34" smd circle
			(at -10.566654 -19.086068 270)
			(size 0.4318 0.4318)
			(layers "F.Cu" "F.Mask" "F.Paste")
			(net "GND")
		)
		(pad "V36" smd circle
			(at -8.939022 -19.086068 270)
			(size 0.4318 0.4318)
			(layers "F.Cu" "F.Mask" "F.Paste")
			(net "GND")
		)
		(pad "V38" smd circle
			(at -7.311136 -19.086068 270)
			(size 0.4318 0.4318)
			(layers "F.Cu" "F.Mask" "F.Paste")
			(net "GND")
		)
		(pad "V40" smd circle
			(at -5.68325 -19.086068 270)
			(size 0.4318 0.4318)
			(layers "F.Cu" "F.Mask" "F.Paste")
			(net "GND")
		)
		(pad "V42" smd circle
			(at -4.055618 -19.086068 270)
			(size 0.4318 0.4318)
			(layers "F.Cu" "F.Mask" "F.Paste")
			(net "GND")
		)
		(pad "V44" smd circle
			(at -2.427732 -19.086068 270)
			(size 0.4318 0.4318)
			(layers "F.Cu" "F.Mask" "F.Paste")
			(net "GND")
		)
		(pad "V47" smd circle
			(at 1.613916 -18.976086 270)
			(size 0.4318 0.4318)
			(layers "F.Cu" "F.Mask" "F.Paste")
			(net "GND")
		)
		(pad "V49" smd circle
			(at 3.241802 -18.976086 270)
			(size 0.4318 0.4318)
			(layers "F.Cu" "F.Mask" "F.Paste")
			(net "GND")
		)
		(pad "V51" smd circle
			(at 4.869434 -18.976086 270)
			(size 0.4318 0.4318)
			(layers "F.Cu" "F.Mask" "F.Paste")
			(net "GND")
		)
		(pad "V53" smd circle
			(at 6.49732 -18.976086 270)
			(size 0.4318 0.4318)
			(layers "F.Cu" "F.Mask" "F.Paste")
			(net "GND")
		)
		(pad "V55" smd circle
			(at 8.124952 -18.976086 270)
			(size 0.4318 0.4318)
			(layers "F.Cu" "F.Mask" "F.Paste")
			(net "GND")
		)
		(pad "V57" smd circle
			(at 9.752838 -18.976086 270)
			(size 0.4318 0.4318)
			(layers "F.Cu" "F.Mask" "F.Paste")
			(net "GND")
		)
		(pad "V59" smd circle
			(at 11.380724 -18.976086 270)
			(size 0.4318 0.4318)
			(layers "F.Cu" "F.Mask" "F.Paste")
			(net "GND")
		)
		(pad "V61" smd circle
			(at 13.008356 -18.976086 270)
			(size 0.4318 0.4318)
			(layers "F.Cu" "F.Mask" "F.Paste")
			(net "GND")
		)
		(pad "V63" smd circle
			(at 14.635988 -18.976086 270)
			(size 0.4318 0.4318)
			(layers "F.Cu" "F.Mask" "F.Paste")
			(net "GND")
		)
		(pad "V65" smd circle
			(at 16.263874 -18.976086 270)
			(size 0.4318 0.4318)
			(layers "F.Cu" "F.Mask" "F.Paste")
			(net "GND")
		)
		(pad "V67" smd circle
			(at 17.89176 -18.976086 270)
			(size 0.4318 0.4318)
			(layers "F.Cu" "F.Mask" "F.Paste")
			(net "GND")
		)
		(pad "V69" smd circle
			(at 19.519392 -18.976086 270)
			(size 0.4318 0.4318)
			(layers "F.Cu" "F.Mask" "F.Paste")
			(net "GND")
		)
		(pad "V71" smd circle
			(at 21.147278 -18.976086 270)
			(size 0.4318 0.4318)
			(layers "F.Cu" "F.Mask" "F.Paste")
			(net "GND")
		)
		(pad "V73" smd circle
			(at 22.77491 -18.976086 270)
			(size 0.4318 0.4318)
			(layers "F.Cu" "F.Mask" "F.Paste")
			(net "GND")
		)
		(pad "V75" smd circle
			(at 24.402796 -18.976086 270)
			(size 0.4318 0.4318)
			(layers "F.Cu" "F.Mask" "F.Paste")
			(net "GND")
		)
		(pad "V77" smd circle
			(at 26.030682 -18.976086 270)
			(size 0.4318 0.4318)
			(layers "F.Cu" "F.Mask" "F.Paste")
			(net "GND")
		)
		(pad "V79" smd circle
			(at 27.658314 -18.976086 270)
			(size 0.4318 0.4318)
			(layers "F.Cu" "F.Mask" "F.Paste")
			(net "GND")
		)
		(pad "V81" smd circle
			(at 29.2862 -18.976086 270)
			(size 0.4318 0.4318)
			(layers "F.Cu" "F.Mask" "F.Paste")
			(net "UPI_CPU0_CPU1_P2P2_DP<16>")
		)
		(pad "V83" smd circle
			(at 30.914086 -18.976086 270)
			(size 0.4318 0.4318)
			(layers "F.Cu" "F.Mask" "F.Paste")
			(net "UPI_CPU0_CPU1_P2P2_DN<15>")
		)
		(pad "V85" smd circle
			(at 32.541718 -18.976086 270)
			(size 0.4318 0.4318)
			(layers "F.Cu" "F.Mask" "F.Paste")
			(net "P5E_CPU0_PE4_TX_DP<3>")
		)
		(pad "V87" smd circle
			(at 34.169604 -18.976086 270)
			(size 0.4318 0.4318)
			(layers "F.Cu" "F.Mask" "F.Paste")
			(net "GND")
		)
		(pad "V89" smd circle
			(at 35.797236 -18.976086 270)
			(size 0.4318 0.4318)
			(layers "F.Cu" "F.Mask" "F.Paste")
			(net "P5E_CPU0_PE4_RX_DN<3>")
		)
		(pad "V91" smd oval
			(at 37.425122 -18.976086)
			(size 0.381 0.4826)
			(drill
				(offset 0 -0.0508)
			)
			(layers "F.Cu" "F.Mask" "F.Paste")
			(net "GND")
		)
		(pad "W1" smd oval
			(at -37.425122 -18.615914 180)
			(size 0.381 0.4826)
			(drill
				(offset 0 -0.0508)
			)
			(layers "F.Cu" "F.Mask" "F.Paste")
			(net "GND")
		)
		(pad "W3" smd circle
			(at -35.797236 -18.615914 270)
			(size 0.4318 0.4318)
			(layers "F.Cu" "F.Mask" "F.Paste")
			(net "UPI_CPU0_CPU1_P0P1_DP<5>")
		)
		(pad "W5" smd circle
			(at -34.169604 -18.615914 270)
			(size 0.4318 0.4318)
			(layers "F.Cu" "F.Mask" "F.Paste")
			(net "GND")
		)
		(pad "W7" smd circle
			(at -32.541718 -18.615914 270)
			(size 0.4318 0.4318)
			(layers "F.Cu" "F.Mask" "F.Paste")
			(net "UPI_CPU1_CPU0_P1P0_DP<4>")
		)
		(pad "W9" smd circle
			(at -30.914086 -18.615914 270)
			(size 0.4318 0.4318)
			(layers "F.Cu" "F.Mask" "F.Paste")
			(net "GND")
		)
		(pad "W11" smd circle
			(at -29.2862 -18.615914 270)
			(size 0.4318 0.4318)
			(layers "F.Cu" "F.Mask" "F.Paste")
			(net "P5E_CPU0_PE0_RX_DP<4>")
		)
		(pad "W13" smd circle
			(at -27.658314 -18.615914 270)
			(size 0.4318 0.4318)
			(layers "F.Cu" "F.Mask" "F.Paste")
			(net "GND")
		)
		(pad "W15" smd circle
			(at -26.030682 -18.615914 270)
			(size 0.4318 0.4318)
			(layers "F.Cu" "F.Mask" "F.Paste")
			(net "P5E_CPU0_PE0_TX_DP<3>")
		)
		(pad "W17" smd circle
			(at -24.402796 -18.615914 270)
			(size 0.4318 0.4318)
			(layers "F.Cu" "F.Mask" "F.Paste")
			(net "NC_CPU0_HBM1_VIEWDIG0")
		)
		(pad "W19" smd circle
			(at -22.77491 -18.615914 270)
			(size 0.4318 0.4318)
			(layers "F.Cu" "F.Mask" "F.Paste")
			(net "M_C_CPU0_SB_DQ<23>")
		)
		(pad "W21" smd circle
			(at -21.147278 -18.615914 270)
			(size 0.4318 0.4318)
			(layers "F.Cu" "F.Mask" "F.Paste")
			(net "M_C_CPU0_SB_DQS_DN<7>")
		)
		(pad "W23" smd circle
			(at -19.519392 -18.615914 270)
			(size 0.4318 0.4318)
			(layers "F.Cu" "F.Mask" "F.Paste")
			(net "M_C_CPU0_SB_DQ<18>")
		)
		(pad "W25" smd circle
			(at -17.89176 -18.615914 270)
			(size 0.4318 0.4318)
			(layers "F.Cu" "F.Mask" "F.Paste")
			(net "M_B_CPU0_SB_DQ<7>")
		)
		(pad "W27" smd circle
			(at -16.263874 -18.615914 270)
			(size 0.4318 0.4318)
			(layers "F.Cu" "F.Mask" "F.Paste")
			(net "M_B_CPU0_SB_DQS_DN<5>")
		)
		(pad "W29" smd circle
			(at -14.635988 -18.615914 270)
			(size 0.4318 0.4318)
			(layers "F.Cu" "F.Mask" "F.Paste")
			(net "M_B_CPU0_SB_DQ<2>")
		)
		(pad "W31" smd circle
			(at -13.008356 -18.615914 270)
			(size 0.4318 0.4318)
			(layers "F.Cu" "F.Mask" "F.Paste")
			(net "M_C_CPU0_SB_CB<3>")
		)
		(pad "W33" smd circle
			(at -11.380724 -18.615914 270)
			(size 0.4318 0.4318)
			(layers "F.Cu" "F.Mask" "F.Paste")
			(net "M_C_CPU0_SB_DQS_DN<4>")
		)
		(pad "W35" smd circle
			(at -9.752838 -18.615914 270)
			(size 0.4318 0.4318)
			(layers "F.Cu" "F.Mask" "F.Paste")
			(net "M_C_CPU0_SB_CB<6>")
		)
		(pad "W37" smd circle
			(at -8.124952 -18.615914 270)
			(size 0.4318 0.4318)
			(layers "F.Cu" "F.Mask" "F.Paste")
			(net "M_C_CPU0_SB_CS_N<3>")
		)
		(pad "W39" smd circle
			(at -6.49732 -18.615914 270)
			(size 0.4318 0.4318)
			(layers "F.Cu" "F.Mask" "F.Paste")
			(net "GND")
		)
		(pad "W41" smd circle
			(at -4.869434 -18.615914 270)
			(size 0.4318 0.4318)
			(layers "F.Cu" "F.Mask" "F.Paste")
			(net "M_C_CPU0_SB_CA<3>")
		)
		(pad "W43" smd circle
			(at -3.241802 -18.615914 270)
			(size 0.4318 0.4318)
			(layers "F.Cu" "F.Mask" "F.Paste")
			(net "M_B_CPU0_SA_PAR")
		)
		(pad "W45" smd circle
			(at -1.613916 -18.615914 270)
			(size 0.4318 0.4318)
			(layers "F.Cu" "F.Mask" "F.Paste")
			(net "M_B_CPU0_CLK_DN<1>")
		)
		(pad "W48" smd circle
			(at 2.427732 -18.505932 270)
			(size 0.4318 0.4318)
			(layers "F.Cu" "F.Mask" "F.Paste")
			(net "M_C_CPU0_SB_CA<0>")
		)
		(pad "W50" smd circle
			(at 4.055618 -18.505932 270)
			(size 0.4318 0.4318)
			(layers "F.Cu" "F.Mask" "F.Paste")
			(net "M_C_CPU0_SA_CA<5>")
		)
		(pad "W52" smd circle
			(at 5.68325 -18.505932 270)
			(size 0.4318 0.4318)
			(layers "F.Cu" "F.Mask" "F.Paste")
			(net "GND")
		)
		(pad "W54" smd circle
			(at 7.311136 -18.505932 270)
			(size 0.4318 0.4318)
			(layers "F.Cu" "F.Mask" "F.Paste")
			(net "M_C_CPU0_SA_CS_N<2>")
		)
		(pad "W56" smd circle
			(at 8.939022 -18.505932 270)
			(size 0.4318 0.4318)
			(layers "F.Cu" "F.Mask" "F.Paste")
			(net "M_B_CPU0_SA_DQ<31>")
		)
		(pad "W58" smd circle
			(at 10.566654 -18.505932 270)
			(size 0.4318 0.4318)
			(layers "F.Cu" "F.Mask" "F.Paste")
			(net "M_B_CPU0_SA_DQS_DP<8>")
		)
		(pad "W60" smd circle
			(at 12.19454 -18.505932 270)
			(size 0.4318 0.4318)
			(layers "F.Cu" "F.Mask" "F.Paste")
			(net "M_B_CPU0_SA_DQ<26>")
		)
		(pad "W62" smd circle
			(at 13.822426 -18.505932 270)
			(size 0.4318 0.4318)
			(layers "F.Cu" "F.Mask" "F.Paste")
			(net "M_C_CPU0_SA_DQ<23>")
		)
		(pad "W64" smd circle
			(at 15.450058 -18.505932 270)
			(size 0.4318 0.4318)
			(layers "F.Cu" "F.Mask" "F.Paste")
			(net "M_C_CPU0_SA_DQS_DP<7>")
		)
		(pad "W66" smd circle
			(at 17.07769 -18.505932 270)
			(size 0.4318 0.4318)
			(layers "F.Cu" "F.Mask" "F.Paste")
			(net "M_C_CPU0_SA_DQ<18>")
		)
		(pad "W68" smd circle
			(at 18.705576 -18.505932 270)
			(size 0.4318 0.4318)
			(layers "F.Cu" "F.Mask" "F.Paste")
			(net "M_B_CPU0_SA_DQ<15>")
		)
		(pad "W70" smd circle
			(at 20.333462 -18.505932 270)
			(size 0.4318 0.4318)
			(layers "F.Cu" "F.Mask" "F.Paste")
			(net "M_B_CPU0_SA_DQS_DP<6>")
		)
		(pad "W72" smd circle
			(at 21.961094 -18.505932 270)
			(size 0.4318 0.4318)
			(layers "F.Cu" "F.Mask" "F.Paste")
			(net "M_B_CPU0_SA_DQ<10>")
		)
		(pad "W74" smd circle
			(at 23.58898 -18.505932 270)
			(size 0.4318 0.4318)
			(layers "F.Cu" "F.Mask" "F.Paste")
			(net "M_C_CPU0_SA_DQ<7>")
		)
		(pad "W76" smd circle
			(at 25.216612 -18.505932 270)
			(size 0.4318 0.4318)
			(layers "F.Cu" "F.Mask" "F.Paste")
			(net "M_C_CPU0_SA_DQS_DN<5>")
		)
		(pad "W78" smd circle
			(at 26.844498 -18.505932 270)
			(size 0.4318 0.4318)
			(layers "F.Cu" "F.Mask" "F.Paste")
			(net "M_C_CPU0_SA_DQ<2>")
		)
		(pad "W80" smd circle
			(at 28.472384 -18.505932 270)
			(size 0.4318 0.4318)
			(layers "F.Cu" "F.Mask" "F.Paste")
			(net "PVCCFA_EHV_FIVRA_CPU0")
		)
		(pad "W82" smd circle
			(at 30.100016 -18.505932 270)
			(size 0.4318 0.4318)
			(layers "F.Cu" "F.Mask" "F.Paste")
			(net "UPI_CPU0_CPU1_P2P2_DP<14>")
		)
		(pad "W84" smd circle
			(at 31.727902 -18.505932 270)
			(size 0.4318 0.4318)
			(layers "F.Cu" "F.Mask" "F.Paste")
			(net "GND")
		)
		(pad "W86" smd circle
			(at 33.355534 -18.505932 270)
			(size 0.4318 0.4318)
			(layers "F.Cu" "F.Mask" "F.Paste")
			(net "P5E_CPU0_PE4_TX_DN<4>")
		)
		(pad "W88" smd circle
			(at 34.98342 -18.505932 270)
			(size 0.4318 0.4318)
			(layers "F.Cu" "F.Mask" "F.Paste")
			(net "GND")
		)
		(pad "W90" smd circle
			(at 36.611306 -18.505932 270)
			(size 0.4318 0.4318)
			(layers "F.Cu" "F.Mask" "F.Paste")
			(net "P5E_CPU0_PE4_RX_DP<4>")
		)
		(pad "Y2" smd circle
			(at -36.611306 -18.146268 270)
			(size 0.4318 0.4318)
			(layers "F.Cu" "F.Mask" "F.Paste")
			(net "UPI_CPU0_CPU1_P0P1_DN<5>")
		)
		(pad "Y4" smd circle
			(at -34.98342 -18.146268 270)
			(size 0.4318 0.4318)
			(layers "F.Cu" "F.Mask" "F.Paste")
			(net "GND")
		)
		(pad "Y6" smd circle
			(at -33.355534 -18.146268 270)
			(size 0.4318 0.4318)
			(layers "F.Cu" "F.Mask" "F.Paste")
			(net "UPI_CPU1_CPU0_P1P0_DN<5>")
		)
		(pad "Y8" smd circle
			(at -31.727902 -18.146268 270)
			(size 0.4318 0.4318)
			(layers "F.Cu" "F.Mask" "F.Paste")
			(net "GND")
		)
		(pad "Y10" smd circle
			(at -30.100016 -18.146268 270)
			(size 0.4318 0.4318)
			(layers "F.Cu" "F.Mask" "F.Paste")
			(net "P5E_CPU0_PE0_RX_DP<5>")
		)
		(pad "Y12" smd circle
			(at -28.472384 -18.146268 270)
			(size 0.4318 0.4318)
			(layers "F.Cu" "F.Mask" "F.Paste")
			(net "GND")
		)
		(pad "Y14" smd circle
			(at -26.844498 -18.146268 270)
			(size 0.4318 0.4318)
			(layers "F.Cu" "F.Mask" "F.Paste")
			(net "P5E_CPU0_PE0_TX_DP<4>")
		)
		(pad "Y16" smd circle
			(at -25.216612 -18.146268 270)
			(size 0.4318 0.4318)
			(layers "F.Cu" "F.Mask" "F.Paste")
			(net "GND")
		)
		(pad "Y18" smd circle
			(at -23.58898 -18.146268 270)
			(size 0.4318 0.4318)
			(layers "F.Cu" "F.Mask" "F.Paste")
			(net "GND")
		)
		(pad "Y20" smd circle
			(at -21.961094 -18.146268 270)
			(size 0.4318 0.4318)
			(layers "F.Cu" "F.Mask" "F.Paste")
			(net "M_C_CPU0_SB_DQ<22>")
		)
		(pad "Y22" smd circle
			(at -20.333462 -18.146268 270)
			(size 0.4318 0.4318)
			(layers "F.Cu" "F.Mask" "F.Paste")
			(net "M_C_CPU0_SB_DQ<19>")
		)
		(pad "Y24" smd circle
			(at -18.705576 -18.146268 270)
			(size 0.4318 0.4318)
			(layers "F.Cu" "F.Mask" "F.Paste")
			(net "GND")
		)
		(pad "Y26" smd circle
			(at -17.07769 -18.146268 270)
			(size 0.4318 0.4318)
			(layers "F.Cu" "F.Mask" "F.Paste")
			(net "M_B_CPU0_SB_DQ<6>")
		)
		(pad "Y28" smd circle
			(at -15.450058 -18.146268 270)
			(size 0.4318 0.4318)
			(layers "F.Cu" "F.Mask" "F.Paste")
			(net "M_B_CPU0_SB_DQ<3>")
		)
		(pad "Y30" smd circle
			(at -13.822426 -18.146268 270)
			(size 0.4318 0.4318)
			(layers "F.Cu" "F.Mask" "F.Paste")
			(net "GND")
		)
		(pad "Y32" smd circle
			(at -12.19454 -18.146268 270)
			(size 0.4318 0.4318)
			(layers "F.Cu" "F.Mask" "F.Paste")
			(net "M_C_CPU0_SB_CB<2>")
		)
		(pad "Y34" smd circle
			(at -10.566654 -18.146268 270)
			(size 0.4318 0.4318)
			(layers "F.Cu" "F.Mask" "F.Paste")
			(net "M_C_CPU0_SB_CB<7>")
		)
		(pad "Y36" smd circle
			(at -8.939022 -18.146268 270)
			(size 0.4318 0.4318)
			(layers "F.Cu" "F.Mask" "F.Paste")
			(net "GND")
		)
		(pad "Y38" smd circle
			(at -7.311136 -18.146268 270)
			(size 0.4318 0.4318)
			(layers "F.Cu" "F.Mask" "F.Paste")
			(net "M_C_CPU0_SB_CS_N<2>")
		)
		(pad "Y40" smd circle
			(at -5.68325 -18.146268 270)
			(size 0.4318 0.4318)
			(layers "F.Cu" "F.Mask" "F.Paste")
			(net "M_C_CPU0_SB_CA<5>")
		)
		(pad "Y42" smd circle
			(at -4.055618 -18.146268 270)
			(size 0.4318 0.4318)
			(layers "F.Cu" "F.Mask" "F.Paste")
			(net "GND")
		)
		(pad "Y44" smd circle
			(at -2.427732 -18.146268 270)
			(size 0.4318 0.4318)
			(layers "F.Cu" "F.Mask" "F.Paste")
			(net "M_B_CPU0_SA_CA<6>")
		)
		(pad "Y47" smd circle
			(at 1.613916 -18.036286 270)
			(size 0.4318 0.4318)
			(layers "F.Cu" "F.Mask" "F.Paste")
			(net "M_C_CPU0_SB_CA<1>")
		)
		(pad "Y49" smd circle
			(at 3.241802 -18.036286 270)
			(size 0.4318 0.4318)
			(layers "F.Cu" "F.Mask" "F.Paste")
			(net "GND")
		)
		(pad "Y51" smd circle
			(at 4.869434 -18.036286 270)
			(size 0.4318 0.4318)
			(layers "F.Cu" "F.Mask" "F.Paste")
			(net "M_C_CPU0_SA_CA<3>")
		)
		(pad "Y53" smd circle
			(at 6.49732 -18.036286 270)
			(size 0.4318 0.4318)
			(layers "F.Cu" "F.Mask" "F.Paste")
			(net "M_C_CPU0_SA_CS_N<3>")
		)
		(pad "Y55" smd circle
			(at 8.124952 -18.036286 270)
			(size 0.4318 0.4318)
			(layers "F.Cu" "F.Mask" "F.Paste")
			(net "GND")
		)
		(pad "Y57" smd circle
			(at 9.752838 -18.036286 270)
			(size 0.4318 0.4318)
			(layers "F.Cu" "F.Mask" "F.Paste")
			(net "M_B_CPU0_SA_DQ<30>")
		)
		(pad "Y59" smd circle
			(at 11.380724 -18.036286 270)
			(size 0.4318 0.4318)
			(layers "F.Cu" "F.Mask" "F.Paste")
			(net "M_B_CPU0_SA_DQ<27>")
		)
		(pad "Y61" smd circle
			(at 13.008356 -18.036286 270)
			(size 0.4318 0.4318)
			(layers "F.Cu" "F.Mask" "F.Paste")
			(net "GND")
		)
		(pad "Y63" smd circle
			(at 14.635988 -18.036286 270)
			(size 0.4318 0.4318)
			(layers "F.Cu" "F.Mask" "F.Paste")
			(net "M_C_CPU0_SA_DQ<22>")
		)
		(pad "Y65" smd circle
			(at 16.263874 -18.036286 270)
			(size 0.4318 0.4318)
			(layers "F.Cu" "F.Mask" "F.Paste")
			(net "M_C_CPU0_SA_DQ<19>")
		)
		(pad "Y67" smd circle
			(at 17.89176 -18.036286 270)
			(size 0.4318 0.4318)
			(layers "F.Cu" "F.Mask" "F.Paste")
			(net "GND")
		)
		(pad "Y69" smd circle
			(at 19.519392 -18.036286 270)
			(size 0.4318 0.4318)
			(layers "F.Cu" "F.Mask" "F.Paste")
			(net "M_B_CPU0_SA_DQ<14>")
		)
		(pad "Y71" smd circle
			(at 21.147278 -18.036286 270)
			(size 0.4318 0.4318)
			(layers "F.Cu" "F.Mask" "F.Paste")
			(net "M_B_CPU0_SA_DQ<11>")
		)
		(pad "Y73" smd circle
			(at 22.77491 -18.036286 270)
			(size 0.4318 0.4318)
			(layers "F.Cu" "F.Mask" "F.Paste")
			(net "GND")
		)
		(pad "Y75" smd circle
			(at 24.402796 -18.036286 270)
			(size 0.4318 0.4318)
			(layers "F.Cu" "F.Mask" "F.Paste")
			(net "M_C_CPU0_SA_DQ<6>")
		)
		(pad "Y77" smd circle
			(at 26.030682 -18.036286 270)
			(size 0.4318 0.4318)
			(layers "F.Cu" "F.Mask" "F.Paste")
			(net "M_C_CPU0_SA_DQ<3>")
		)
		(pad "Y79" smd circle
			(at 27.658314 -18.036286 270)
			(size 0.4318 0.4318)
			(layers "F.Cu" "F.Mask" "F.Paste")
			(net "PVCCFA_EHV_FIVRA_CPU0")
		)
		(pad "Y81" smd circle
			(at 29.2862 -18.036286 270)
			(size 0.4318 0.4318)
			(layers "F.Cu" "F.Mask" "F.Paste")
			(net "UPI_CPU0_CPU1_P2P2_DN<14>")
		)
		(pad "Y83" smd circle
			(at 30.914086 -18.036286 270)
			(size 0.4318 0.4318)
			(layers "F.Cu" "F.Mask" "F.Paste")
			(net "UPI_CPU0_CPU1_P2P2_DP<15>")
		)
		(pad "Y85" smd circle
			(at 32.541718 -18.036286 270)
			(size 0.4318 0.4318)
			(layers "F.Cu" "F.Mask" "F.Paste")
			(net "PVCCFA_EHV_FIVRA_CPU0")
		)
		(pad "Y87" smd circle
			(at 34.169604 -18.036286 270)
			(size 0.4318 0.4318)
			(layers "F.Cu" "F.Mask" "F.Paste")
			(net "P5E_CPU0_PE4_TX_DP<4>")
		)
		(pad "Y89" smd circle
			(at 35.797236 -18.036286 270)
			(size 0.4318 0.4318)
			(layers "F.Cu" "F.Mask" "F.Paste")
			(net "PVCCFA_EHV_FIVRA_CPU0")
		)
		(pad "Y91" smd oval
			(at 37.425122 -18.036286)
			(size 0.381 0.4826)
			(drill
				(offset 0 -0.0508)
			)
			(layers "F.Cu" "F.Mask" "F.Paste")
			(net "P5E_CPU0_PE4_RX_DN<4>")
		)
		(zone
			(layer "F.Cu")
			(hatch none 0.5)
			(connect_pads
				(clearance 0)
			)
			(min_thickness 0.25)
			(keepout
				(tracks not_allowed)
				(vias allowed)
				(pads allowed)
				(copperpour not_allowed)
				(footprints allowed)
			)
			(placement
				(enabled no)
				(sheetname "")
			)
			(fill
				(thermal_gap 0.5)
				(thermal_bridge_width 0.5)
				(island_removal_mode 0)
			)
			(polygon
				(pts
					(arc
						(start 332.617318 -220.9673)
						(mid 332.581397 -220.982179)
						(end 332.566518 -221.0181)
					)
					(arc
						(start 332.566518 -221.0181)
						(mid 332.570629 -221.038119)
						(end 332.582266 -221.05493)
					)
					(arc
						(start 332.582266 -221.05493)
						(mid 332.679526 -221.123652)
						(end 332.796134 -221.147894)
					)
					(arc
						(start 332.796134 -221.147894)
						(mid 333.00268 -221.06234)
						(end 333.088234 -220.855794)
					)
					(arc
						(start 333.088234 -220.855794)
						(mid 333.064412 -220.740509)
						(end 332.997048 -220.643958)
					)
					(arc
						(start 332.997048 -220.643958)
						(mid 332.97982 -220.631389)
						(end 332.958948 -220.62694)
					)
					(arc
						(start 332.958948 -220.62694)
						(mid 332.923027 -220.641819)
						(end 332.908148 -220.67774)
					)
					(arc
						(start 332.908148 -220.67774)
						(mid 332.910323 -220.692194)
						(end 332.91653 -220.705426)
					)
					(xy 332.931262 -220.720158) (xy 332.931516 -220.720412)
					(arc
						(start 332.932278 -220.721174)
						(mid 332.973257 -220.783022)
						(end 332.98765 -220.855794)
					)
					(arc
						(start 332.98765 -220.855794)
						(mid 332.931556 -220.991216)
						(end 332.796134 -221.04731)
					)
					(arc
						(start 332.796134 -221.04731)
						(mid 332.722512 -221.032594)
						(end 332.660244 -220.990668)
					)
					(xy 332.659736 -220.99016)
					(arc
						(start 332.645258 -220.975682)
						(mid 332.631902 -220.969446)
						(end 332.617318 -220.9673)
					)
				)
			)
		)
		(zone
			(layer "F.Cu")
			(hatch none 0.5)
			(connect_pads
				(clearance 0)
			)
			(min_thickness 0.25)
			(keepout
				(tracks not_allowed)
				(vias allowed)
				(pads allowed)
				(copperpour not_allowed)
				(footprints allowed)
			)
			(placement
				(enabled no)
				(sheetname "")
			)
			(fill
				(thermal_gap 0.5)
				(thermal_bridge_width 0.5)
				(island_removal_mode 0)
			)
			(polygon
				(pts
					(arc
						(start 332.748382 -248.73331)
						(mid 332.733368 -248.769288)
						(end 332.748382 -248.805192)
					)
					(arc
						(start 332.748382 -248.805192)
						(mid 332.765504 -248.816543)
						(end 332.78572 -248.820178)
					)
					(arc
						(start 332.78572 -248.820178)
						(mid 332.903088 -248.799963)
						(end 333.002636 -248.73458)
					)
					(arc
						(start 333.002636 -248.73458)
						(mid 333.088172 -248.528078)
						(end 333.002636 -248.321576)
					)
					(arc
						(start 333.002636 -248.321576)
						(mid 332.904243 -248.256787)
						(end 332.78826 -248.236232)
					)
					(arc
						(start 332.78826 -248.236232)
						(mid 332.767251 -248.239432)
						(end 332.749398 -248.250964)
					)
					(arc
						(start 332.749398 -248.250964)
						(mid 332.734384 -248.286942)
						(end 332.749398 -248.322846)
					)
					(arc
						(start 332.749398 -248.322846)
						(mid 332.761219 -248.331588)
						(end 332.775052 -248.336562)
					)
					(xy 332.795626 -248.336562) (xy 332.796134 -248.336562)
					(arc
						(start 332.79715 -248.336562)
						(mid 332.869855 -248.3514)
						(end 332.931516 -248.392696)
					)
					(arc
						(start 332.931516 -248.392696)
						(mid 332.987593 -248.528078)
						(end 332.931516 -248.66346)
					)
					(arc
						(start 332.931516 -248.66346)
						(mid 332.86905 -248.705109)
						(end 332.795372 -248.719594)
					)
					(xy 332.79461 -248.719594)
					(arc
						(start 332.774036 -248.719594)
						(mid 332.760212 -248.724585)
						(end 332.748382 -248.73331)
					)
				)
			)
		)
		(zone
			(layer "F.Cu")
			(hatch none 0.5)
			(connect_pads
				(clearance 0)
			)
			(min_thickness 0.25)
			(keepout
				(tracks not_allowed)
				(vias allowed)
				(pads allowed)
				(copperpour not_allowed)
				(footprints allowed)
			)
			(placement
				(enabled no)
				(sheetname "")
			)
			(fill
				(thermal_gap 0.5)
				(thermal_bridge_width 0.5)
				(island_removal_mode 0)
			)
			(polygon
				(pts
					(arc
						(start 332.748382 -247.105678)
						(mid 332.733621 -247.141492)
						(end 332.748382 -247.177306)
					)
					(arc
						(start 332.748382 -247.177306)
						(mid 332.765504 -247.188657)
						(end 332.78572 -247.192292)
					)
					(arc
						(start 332.78572 -247.192292)
						(mid 332.903061 -247.172198)
						(end 333.002636 -247.106948)
					)
					(arc
						(start 333.002636 -247.106948)
						(mid 333.088172 -246.900446)
						(end 333.002636 -246.693944)
					)
					(arc
						(start 333.002636 -246.693944)
						(mid 332.904274 -246.629015)
						(end 332.78826 -246.608346)
					)
					(arc
						(start 332.78826 -246.608346)
						(mid 332.767238 -246.611534)
						(end 332.749398 -246.623078)
					)
					(arc
						(start 332.749398 -246.623078)
						(mid 332.734384 -246.659056)
						(end 332.749398 -246.69496)
					)
					(arc
						(start 332.749398 -246.69496)
						(mid 332.761203 -246.703743)
						(end 332.775052 -246.708676)
					)
					(xy 332.795626 -246.708676) (xy 332.796134 -246.708676)
					(arc
						(start 332.79715 -246.708676)
						(mid 332.869885 -246.72363)
						(end 332.931516 -246.765064)
					)
					(arc
						(start 332.931516 -246.765064)
						(mid 332.987593 -246.900446)
						(end 332.931516 -247.035828)
					)
					(arc
						(start 332.931516 -247.035828)
						(mid 332.869051 -247.077506)
						(end 332.795372 -247.091962)
					)
					(xy 332.79461 -247.091708)
					(arc
						(start 332.774036 -247.091708)
						(mid 332.760174 -247.096798)
						(end 332.748382 -247.105678)
					)
				)
			)
		)
		(zone
			(layer "F.Cu")
			(hatch none 0.5)
			(connect_pads
				(clearance 0)
			)
			(min_thickness 0.25)
			(keepout
				(tracks not_allowed)
				(vias allowed)
				(pads allowed)
				(copperpour not_allowed)
				(footprints allowed)
			)
			(placement
				(enabled no)
				(sheetname "")
			)
			(fill
				(thermal_gap 0.5)
				(thermal_bridge_width 0.5)
				(island_removal_mode 0)
			)
			(polygon
				(pts
					(arc
						(start 332.748382 -245.477792)
						(mid 332.733368 -245.51377)
						(end 332.748382 -245.549674)
					)
					(arc
						(start 332.748382 -245.549674)
						(mid 332.765504 -245.561025)
						(end 332.78572 -245.56466)
					)
					(arc
						(start 332.78572 -245.56466)
						(mid 332.903088 -245.544445)
						(end 333.002636 -245.479062)
					)
					(arc
						(start 333.002636 -245.479062)
						(mid 333.088172 -245.27256)
						(end 333.002636 -245.066058)
					)
					(arc
						(start 333.002636 -245.066058)
						(mid 332.904243 -245.001269)
						(end 332.78826 -244.980714)
					)
					(arc
						(start 332.78826 -244.980714)
						(mid 332.767251 -244.983914)
						(end 332.749398 -244.995446)
					)
					(arc
						(start 332.749398 -244.995446)
						(mid 332.734384 -245.031424)
						(end 332.749398 -245.067328)
					)
					(arc
						(start 332.749398 -245.067328)
						(mid 332.761203 -245.076111)
						(end 332.775052 -245.081044)
					)
					(xy 332.795626 -245.081044) (xy 332.796134 -245.081044)
					(arc
						(start 332.79715 -245.081044)
						(mid 332.869855 -245.095882)
						(end 332.931516 -245.137178)
					)
					(arc
						(start 332.931516 -245.137178)
						(mid 332.987773 -245.272724)
						(end 332.931516 -245.408196)
					)
					(arc
						(start 332.931516 -245.408196)
						(mid 332.869021 -245.449707)
						(end 332.795372 -245.464076)
					)
					(xy 332.79461 -245.464076)
					(arc
						(start 332.774036 -245.464076)
						(mid 332.760212 -245.469067)
						(end 332.748382 -245.477792)
					)
				)
			)
		)
		(zone
			(layer "F.Cu")
			(hatch none 0.5)
			(connect_pads
				(clearance 0)
			)
			(min_thickness 0.25)
			(keepout
				(tracks not_allowed)
				(vias allowed)
				(pads allowed)
				(copperpour not_allowed)
				(footprints allowed)
			)
			(placement
				(enabled no)
				(sheetname "")
			)
			(fill
				(thermal_gap 0.5)
				(thermal_bridge_width 0.5)
				(island_removal_mode 0)
			)
			(polygon
				(pts
					(arc
						(start 332.748382 -243.85016)
						(mid 332.733621 -243.885974)
						(end 332.748382 -243.921788)
					)
					(arc
						(start 332.748382 -243.921788)
						(mid 332.765504 -243.933139)
						(end 332.78572 -243.936774)
					)
					(arc
						(start 332.78572 -243.936774)
						(mid 332.903061 -243.91668)
						(end 333.002636 -243.85143)
					)
					(arc
						(start 333.002636 -243.85143)
						(mid 333.088172 -243.644928)
						(end 333.002636 -243.438426)
					)
					(arc
						(start 333.002636 -243.438426)
						(mid 332.904274 -243.373497)
						(end 332.78826 -243.352828)
					)
					(arc
						(start 332.78826 -243.352828)
						(mid 332.767238 -243.356016)
						(end 332.749398 -243.36756)
					)
					(arc
						(start 332.749398 -243.36756)
						(mid 332.734383 -243.403628)
						(end 332.749398 -243.439696)
					)
					(arc
						(start 332.749398 -243.439696)
						(mid 332.761252 -243.448272)
						(end 332.775052 -243.453158)
					)
					(xy 332.795626 -243.453158) (xy 332.796134 -243.453158)
					(arc
						(start 332.79715 -243.453158)
						(mid 332.869885 -243.468112)
						(end 332.931516 -243.509546)
					)
					(arc
						(start 332.931516 -243.509546)
						(mid 332.987593 -243.644928)
						(end 332.931516 -243.78031)
					)
					(arc
						(start 332.931516 -243.78031)
						(mid 332.869065 -243.822042)
						(end 332.795372 -243.836444)
					)
					(xy 332.79461 -243.83619)
					(arc
						(start 332.774036 -243.83619)
						(mid 332.760174 -243.84128)
						(end 332.748382 -243.85016)
					)
				)
			)
		)
		(zone
			(layer "F.Cu")
			(hatch none 0.5)
			(connect_pads
				(clearance 0)
			)
			(min_thickness 0.25)
			(keepout
				(tracks not_allowed)
				(vias allowed)
				(pads allowed)
				(copperpour not_allowed)
				(footprints allowed)
			)
			(placement
				(enabled no)
				(sheetname "")
			)
			(fill
				(thermal_gap 0.5)
				(thermal_bridge_width 0.5)
				(island_removal_mode 0)
			)
			(polygon
				(pts
					(arc
						(start 332.748382 -242.222274)
						(mid 332.733368 -242.258252)
						(end 332.748382 -242.294156)
					)
					(arc
						(start 332.748382 -242.294156)
						(mid 332.765535 -242.305367)
						(end 332.78572 -242.308888)
					)
					(arc
						(start 332.78572 -242.308888)
						(mid 332.903061 -242.288794)
						(end 333.002636 -242.223544)
					)
					(arc
						(start 333.002636 -242.223544)
						(mid 333.088172 -242.017042)
						(end 333.002636 -241.81054)
					)
					(arc
						(start 333.002636 -241.81054)
						(mid 332.904243 -241.745751)
						(end 332.78826 -241.725196)
					)
					(arc
						(start 332.78826 -241.725196)
						(mid 332.767251 -241.728396)
						(end 332.749398 -241.739928)
					)
					(arc
						(start 332.749398 -241.739928)
						(mid 332.734384 -241.775906)
						(end 332.749398 -241.81181)
					)
					(arc
						(start 332.749398 -241.81181)
						(mid 332.761219 -241.820552)
						(end 332.775052 -241.825526)
					)
					(xy 332.795626 -241.825526) (xy 332.796134 -241.825526)
					(arc
						(start 332.79715 -241.825526)
						(mid 332.869855 -241.840364)
						(end 332.931516 -241.88166)
					)
					(arc
						(start 332.931516 -241.88166)
						(mid 332.987593 -242.017042)
						(end 332.931516 -242.152424)
					)
					(arc
						(start 332.931516 -242.152424)
						(mid 332.86905 -242.194073)
						(end 332.795372 -242.208558)
					)
					(xy 332.79461 -242.208304)
					(arc
						(start 332.774036 -242.208304)
						(mid 332.760174 -242.213394)
						(end 332.748382 -242.222274)
					)
				)
			)
		)
		(zone
			(layer "F.Cu")
			(hatch none 0.5)
			(connect_pads
				(clearance 0)
			)
			(min_thickness 0.25)
			(keepout
				(tracks not_allowed)
				(vias allowed)
				(pads allowed)
				(copperpour not_allowed)
				(footprints allowed)
			)
			(placement
				(enabled no)
				(sheetname "")
			)
			(fill
				(thermal_gap 0.5)
				(thermal_bridge_width 0.5)
				(island_removal_mode 0)
			)
			(polygon
				(pts
					(arc
						(start 332.748382 -240.594388)
						(mid 332.733368 -240.630366)
						(end 332.748382 -240.66627)
					)
					(arc
						(start 332.748382 -240.66627)
						(mid 332.765504 -240.677621)
						(end 332.78572 -240.681256)
					)
					(arc
						(start 332.78572 -240.681256)
						(mid 332.903088 -240.661041)
						(end 333.002636 -240.595658)
					)
					(arc
						(start 333.002636 -240.595658)
						(mid 333.088172 -240.389156)
						(end 333.002636 -240.182654)
					)
					(arc
						(start 333.002636 -240.182654)
						(mid 332.904243 -240.117865)
						(end 332.78826 -240.09731)
					)
					(arc
						(start 332.78826 -240.09731)
						(mid 332.767251 -240.10051)
						(end 332.749398 -240.112042)
					)
					(arc
						(start 332.749398 -240.112042)
						(mid 332.734384 -240.14802)
						(end 332.749398 -240.183924)
					)
					(arc
						(start 332.749398 -240.183924)
						(mid 332.761203 -240.192707)
						(end 332.775052 -240.19764)
					)
					(xy 332.795626 -240.19764) (xy 332.796134 -240.19764)
					(arc
						(start 332.79715 -240.19764)
						(mid 332.869855 -240.212478)
						(end 332.931516 -240.253774)
					)
					(arc
						(start 332.931516 -240.253774)
						(mid 332.987773 -240.38932)
						(end 332.931516 -240.524792)
					)
					(arc
						(start 332.931516 -240.524792)
						(mid 332.869021 -240.566303)
						(end 332.795372 -240.580672)
					)
					(xy 332.79461 -240.580672)
					(arc
						(start 332.774036 -240.580672)
						(mid 332.760212 -240.585663)
						(end 332.748382 -240.594388)
					)
				)
			)
		)
		(zone
			(layer "F.Cu")
			(hatch none 0.5)
			(connect_pads
				(clearance 0)
			)
			(min_thickness 0.25)
			(keepout
				(tracks not_allowed)
				(vias allowed)
				(pads allowed)
				(copperpour not_allowed)
				(footprints allowed)
			)
			(placement
				(enabled no)
				(sheetname "")
			)
			(fill
				(thermal_gap 0.5)
				(thermal_bridge_width 0.5)
				(island_removal_mode 0)
			)
			(polygon
				(pts
					(arc
						(start 332.748382 -238.966756)
						(mid 332.733368 -239.002734)
						(end 332.748382 -239.038638)
					)
					(arc
						(start 332.748382 -239.038638)
						(mid 332.765535 -239.049849)
						(end 332.78572 -239.05337)
					)
					(arc
						(start 332.78572 -239.05337)
						(mid 332.903061 -239.033276)
						(end 333.002636 -238.968026)
					)
					(arc
						(start 333.002636 -238.968026)
						(mid 333.088172 -238.761524)
						(end 333.002636 -238.555022)
					)
					(arc
						(start 333.002636 -238.555022)
						(mid 332.904243 -238.490233)
						(end 332.78826 -238.469678)
					)
					(arc
						(start 332.78826 -238.469678)
						(mid 332.767251 -238.472878)
						(end 332.749398 -238.48441)
					)
					(arc
						(start 332.749398 -238.48441)
						(mid 332.734384 -238.520388)
						(end 332.749398 -238.556292)
					)
					(arc
						(start 332.749398 -238.556292)
						(mid 332.761219 -238.565034)
						(end 332.775052 -238.570008)
					)
					(xy 332.795626 -238.570008) (xy 332.796134 -238.570008)
					(arc
						(start 332.79715 -238.570008)
						(mid 332.869855 -238.584846)
						(end 332.931516 -238.626142)
					)
					(arc
						(start 332.931516 -238.626142)
						(mid 332.987593 -238.761524)
						(end 332.931516 -238.896906)
					)
					(arc
						(start 332.931516 -238.896906)
						(mid 332.86905 -238.938555)
						(end 332.795372 -238.95304)
					)
					(xy 332.79461 -238.952786)
					(arc
						(start 332.774036 -238.952786)
						(mid 332.760174 -238.957876)
						(end 332.748382 -238.966756)
					)
				)
			)
		)
		(zone
			(layer "F.Cu")
			(hatch none 0.5)
			(connect_pads
				(clearance 0)
			)
			(min_thickness 0.25)
			(keepout
				(tracks not_allowed)
				(vias allowed)
				(pads allowed)
				(copperpour not_allowed)
				(footprints allowed)
			)
			(placement
				(enabled no)
				(sheetname "")
			)
			(fill
				(thermal_gap 0.5)
				(thermal_bridge_width 0.5)
				(island_removal_mode 0)
			)
			(polygon
				(pts
					(arc
						(start 332.748382 -237.33887)
						(mid 332.733368 -237.374848)
						(end 332.748382 -237.410752)
					)
					(arc
						(start 332.748382 -237.410752)
						(mid 332.765504 -237.422103)
						(end 332.78572 -237.425738)
					)
					(arc
						(start 332.78572 -237.425738)
						(mid 332.903061 -237.405644)
						(end 333.002636 -237.340394)
					)
					(arc
						(start 333.002636 -237.340394)
						(mid 333.088172 -237.133892)
						(end 333.002636 -236.92739)
					)
					(arc
						(start 333.002636 -236.92739)
						(mid 332.904274 -236.862461)
						(end 332.78826 -236.841792)
					)
					(arc
						(start 332.78826 -236.841792)
						(mid 332.767238 -236.84498)
						(end 332.749398 -236.856524)
					)
					(arc
						(start 332.749398 -236.856524)
						(mid 332.734384 -236.892502)
						(end 332.749398 -236.928406)
					)
					(arc
						(start 332.749398 -236.928406)
						(mid 332.761203 -236.937189)
						(end 332.775052 -236.942122)
					)
					(xy 332.795626 -236.942122) (xy 332.796134 -236.942122)
					(arc
						(start 332.79715 -236.942122)
						(mid 332.869855 -236.95696)
						(end 332.931516 -236.998256)
					)
					(arc
						(start 332.931516 -236.998256)
						(mid 332.987773 -237.133802)
						(end 332.931516 -237.269274)
					)
					(arc
						(start 332.931516 -237.269274)
						(mid 332.869021 -237.310785)
						(end 332.795372 -237.325154)
					)
					(xy 332.79461 -237.325154)
					(arc
						(start 332.774036 -237.325154)
						(mid 332.760212 -237.330145)
						(end 332.748382 -237.33887)
					)
				)
			)
		)
		(zone
			(layer "F.Cu")
			(hatch none 0.5)
			(connect_pads
				(clearance 0)
			)
			(min_thickness 0.25)
			(keepout
				(tracks not_allowed)
				(vias allowed)
				(pads allowed)
				(copperpour not_allowed)
				(footprints allowed)
			)
			(placement
				(enabled no)
				(sheetname "")
			)
			(fill
				(thermal_gap 0.5)
				(thermal_bridge_width 0.5)
				(island_removal_mode 0)
			)
			(polygon
				(pts
					(arc
						(start 332.748382 -235.711238)
						(mid 332.733621 -235.747052)
						(end 332.748382 -235.782866)
					)
					(arc
						(start 332.748382 -235.782866)
						(mid 332.765504 -235.794217)
						(end 332.78572 -235.797852)
					)
					(arc
						(start 332.78572 -235.797852)
						(mid 332.903061 -235.777758)
						(end 333.002636 -235.712508)
					)
					(arc
						(start 333.002636 -235.712508)
						(mid 333.088172 -235.506006)
						(end 333.002636 -235.299504)
					)
					(arc
						(start 333.002636 -235.299504)
						(mid 332.904274 -235.234575)
						(end 332.78826 -235.213906)
					)
					(arc
						(start 332.78826 -235.213906)
						(mid 332.767211 -235.217217)
						(end 332.749398 -235.228892)
					)
					(arc
						(start 332.749398 -235.228892)
						(mid 332.734384 -235.26487)
						(end 332.749398 -235.300774)
					)
					(arc
						(start 332.749398 -235.300774)
						(mid 332.761219 -235.309516)
						(end 332.775052 -235.31449)
					)
					(xy 332.795626 -235.31449) (xy 332.796134 -235.31449)
					(arc
						(start 332.79715 -235.31449)
						(mid 332.869855 -235.329328)
						(end 332.931516 -235.370624)
					)
					(arc
						(start 332.931516 -235.370624)
						(mid 332.987593 -235.506006)
						(end 332.931516 -235.641388)
					)
					(arc
						(start 332.931516 -235.641388)
						(mid 332.869065 -235.68312)
						(end 332.795372 -235.697522)
					)
					(xy 332.79461 -235.697268)
					(arc
						(start 332.774036 -235.697268)
						(mid 332.760174 -235.702358)
						(end 332.748382 -235.711238)
					)
				)
			)
		)
		(zone
			(layer "F.Cu")
			(hatch none 0.5)
			(connect_pads
				(clearance 0)
			)
			(min_thickness 0.25)
			(keepout
				(tracks not_allowed)
				(vias allowed)
				(pads allowed)
				(copperpour not_allowed)
				(footprints allowed)
			)
			(placement
				(enabled no)
				(sheetname "")
			)
			(fill
				(thermal_gap 0.5)
				(thermal_bridge_width 0.5)
				(island_removal_mode 0)
			)
			(polygon
				(pts
					(arc
						(start 332.748382 -234.083352)
						(mid 332.733368 -234.11933)
						(end 332.748382 -234.155234)
					)
					(arc
						(start 332.748382 -234.155234)
						(mid 332.765535 -234.166445)
						(end 332.78572 -234.169966)
					)
					(arc
						(start 332.78572 -234.169966)
						(mid 332.903061 -234.149872)
						(end 333.002636 -234.084622)
					)
					(arc
						(start 333.002636 -234.084622)
						(mid 333.088172 -233.87812)
						(end 333.002636 -233.671618)
					)
					(arc
						(start 333.002636 -233.671618)
						(mid 332.904243 -233.606829)
						(end 332.78826 -233.586274)
					)
					(arc
						(start 332.78826 -233.586274)
						(mid 332.767251 -233.589474)
						(end 332.749398 -233.601006)
					)
					(arc
						(start 332.749398 -233.601006)
						(mid 332.734384 -233.636984)
						(end 332.749398 -233.672888)
					)
					(arc
						(start 332.749398 -233.672888)
						(mid 332.761219 -233.68163)
						(end 332.775052 -233.686604)
					)
					(xy 332.795626 -233.686604) (xy 332.796134 -233.686604)
					(arc
						(start 332.79715 -233.686604)
						(mid 332.869855 -233.701442)
						(end 332.931516 -233.742738)
					)
					(arc
						(start 332.931516 -233.742738)
						(mid 332.987593 -233.87812)
						(end 332.931516 -234.013502)
					)
					(arc
						(start 332.931516 -234.013502)
						(mid 332.86905 -234.055151)
						(end 332.795372 -234.069636)
					)
					(xy 332.79461 -234.069382)
					(arc
						(start 332.774036 -234.069382)
						(mid 332.760174 -234.074472)
						(end 332.748382 -234.083352)
					)
				)
			)
		)
		(zone
			(layer "F.Cu")
			(hatch none 0.5)
			(connect_pads
				(clearance 0)
			)
			(min_thickness 0.25)
			(keepout
				(tracks not_allowed)
				(vias allowed)
				(pads allowed)
				(copperpour not_allowed)
				(footprints allowed)
			)
			(placement
				(enabled no)
				(sheetname "")
			)
			(fill
				(thermal_gap 0.5)
				(thermal_bridge_width 0.5)
				(island_removal_mode 0)
			)
			(polygon
				(pts
					(arc
						(start 332.748382 -232.455466)
						(mid 332.733368 -232.491444)
						(end 332.748382 -232.527348)
					)
					(arc
						(start 332.748382 -232.527348)
						(mid 332.765504 -232.538699)
						(end 332.78572 -232.542334)
					)
					(arc
						(start 332.78572 -232.542334)
						(mid 332.903061 -232.52224)
						(end 333.002636 -232.45699)
					)
					(arc
						(start 333.002636 -232.45699)
						(mid 333.088172 -232.250488)
						(end 333.002636 -232.043986)
					)
					(arc
						(start 333.002636 -232.043986)
						(mid 332.904274 -231.979057)
						(end 332.78826 -231.958388)
					)
					(arc
						(start 332.78826 -231.958388)
						(mid 332.767238 -231.961576)
						(end 332.749398 -231.97312)
					)
					(arc
						(start 332.749398 -231.97312)
						(mid 332.734384 -232.009098)
						(end 332.749398 -232.045002)
					)
					(arc
						(start 332.749398 -232.045002)
						(mid 332.761203 -232.053785)
						(end 332.775052 -232.058718)
					)
					(xy 332.795626 -232.058718) (xy 332.796134 -232.058718)
					(arc
						(start 332.79715 -232.058718)
						(mid 332.869885 -232.073672)
						(end 332.931516 -232.115106)
					)
					(arc
						(start 332.931516 -232.115106)
						(mid 332.987593 -232.250488)
						(end 332.931516 -232.38587)
					)
					(arc
						(start 332.931516 -232.38587)
						(mid 332.869051 -232.427548)
						(end 332.795372 -232.442004)
					)
					(xy 332.79461 -232.44175)
					(arc
						(start 332.774036 -232.44175)
						(mid 332.760212 -232.446741)
						(end 332.748382 -232.455466)
					)
				)
			)
		)
		(zone
			(layer "F.Cu")
			(hatch none 0.5)
			(connect_pads
				(clearance 0)
			)
			(min_thickness 0.25)
			(keepout
				(tracks not_allowed)
				(vias allowed)
				(pads allowed)
				(copperpour not_allowed)
				(footprints allowed)
			)
			(placement
				(enabled no)
				(sheetname "")
			)
			(fill
				(thermal_gap 0.5)
				(thermal_bridge_width 0.5)
				(island_removal_mode 0)
			)
			(polygon
				(pts
					(arc
						(start 332.748382 -230.827834)
						(mid 332.733368 -230.863812)
						(end 332.748382 -230.899716)
					)
					(arc
						(start 332.748382 -230.899716)
						(mid 332.765504 -230.911067)
						(end 332.78572 -230.914702)
					)
					(arc
						(start 332.78572 -230.914702)
						(mid 332.903088 -230.894487)
						(end 333.002636 -230.829104)
					)
					(arc
						(start 333.002636 -230.829104)
						(mid 333.088172 -230.622602)
						(end 333.002636 -230.4161)
					)
					(arc
						(start 333.002636 -230.4161)
						(mid 332.904243 -230.351311)
						(end 332.78826 -230.330756)
					)
					(arc
						(start 332.78826 -230.330756)
						(mid 332.767251 -230.333956)
						(end 332.749398 -230.345488)
					)
					(arc
						(start 332.749398 -230.345488)
						(mid 332.734384 -230.381466)
						(end 332.749398 -230.41737)
					)
					(arc
						(start 332.749398 -230.41737)
						(mid 332.761219 -230.426112)
						(end 332.775052 -230.431086)
					)
					(xy 332.795626 -230.431086) (xy 332.796134 -230.431086)
					(arc
						(start 332.79715 -230.431086)
						(mid 332.869855 -230.445924)
						(end 332.931516 -230.48722)
					)
					(arc
						(start 332.931516 -230.48722)
						(mid 332.987593 -230.622602)
						(end 332.931516 -230.757984)
					)
					(arc
						(start 332.931516 -230.757984)
						(mid 332.86905 -230.799633)
						(end 332.795372 -230.814118)
					)
					(xy 332.79461 -230.813864)
					(arc
						(start 332.774036 -230.813864)
						(mid 332.760174 -230.818954)
						(end 332.748382 -230.827834)
					)
				)
			)
		)
		(zone
			(layer "F.Cu")
			(hatch none 0.5)
			(connect_pads
				(clearance 0)
			)
			(min_thickness 0.25)
			(keepout
				(tracks not_allowed)
				(vias allowed)
				(pads allowed)
				(copperpour not_allowed)
				(footprints allowed)
			)
			(placement
				(enabled no)
				(sheetname "")
			)
			(fill
				(thermal_gap 0.5)
				(thermal_bridge_width 0.5)
				(island_removal_mode 0)
			)
			(polygon
				(pts
					(arc
						(start 332.748382 -229.200202)
						(mid 332.733621 -229.236016)
						(end 332.748382 -229.27183)
					)
					(arc
						(start 332.748382 -229.27183)
						(mid 332.765504 -229.283181)
						(end 332.78572 -229.286816)
					)
					(arc
						(start 332.78572 -229.286816)
						(mid 332.903061 -229.266722)
						(end 333.002636 -229.201472)
					)
					(arc
						(start 333.002636 -229.201472)
						(mid 333.088172 -228.99497)
						(end 333.002636 -228.788468)
					)
					(arc
						(start 333.002636 -228.788468)
						(mid 332.904274 -228.723539)
						(end 332.78826 -228.70287)
					)
					(arc
						(start 332.78826 -228.70287)
						(mid 332.767238 -228.706058)
						(end 332.749398 -228.717602)
					)
					(arc
						(start 332.749398 -228.717602)
						(mid 332.734384 -228.75358)
						(end 332.749398 -228.789484)
					)
					(arc
						(start 332.749398 -228.789484)
						(mid 332.761203 -228.798267)
						(end 332.775052 -228.8032)
					)
					(xy 332.795626 -228.8032) (xy 332.796134 -228.8032)
					(arc
						(start 332.79715 -228.8032)
						(mid 332.869885 -228.818154)
						(end 332.931516 -228.859588)
					)
					(arc
						(start 332.931516 -228.859588)
						(mid 332.987593 -228.99497)
						(end 332.931516 -229.130352)
					)
					(arc
						(start 332.931516 -229.130352)
						(mid 332.869051 -229.17203)
						(end 332.795372 -229.186486)
					)
					(xy 332.79461 -229.186232)
					(arc
						(start 332.774036 -229.186232)
						(mid 332.760174 -229.191322)
						(end 332.748382 -229.200202)
					)
				)
			)
		)
		(zone
			(layer "F.Cu")
			(hatch none 0.5)
			(connect_pads
				(clearance 0)
			)
			(min_thickness 0.25)
			(keepout
				(tracks not_allowed)
				(vias allowed)
				(pads allowed)
				(copperpour not_allowed)
				(footprints allowed)
			)
			(placement
				(enabled no)
				(sheetname "")
			)
			(fill
				(thermal_gap 0.5)
				(thermal_bridge_width 0.5)
				(island_removal_mode 0)
			)
			(polygon
				(pts
					(arc
						(start 332.748382 -227.572316)
						(mid 332.733368 -227.608294)
						(end 332.748382 -227.644198)
					)
					(arc
						(start 332.748382 -227.644198)
						(mid 332.765535 -227.655409)
						(end 332.78572 -227.65893)
					)
					(arc
						(start 332.78572 -227.65893)
						(mid 332.903061 -227.638836)
						(end 333.002636 -227.573586)
					)
					(arc
						(start 333.002636 -227.573586)
						(mid 333.088172 -227.367084)
						(end 333.002636 -227.160582)
					)
					(arc
						(start 333.002636 -227.160582)
						(mid 332.904274 -227.095653)
						(end 332.78826 -227.074984)
					)
					(arc
						(start 332.78826 -227.074984)
						(mid 332.767211 -227.078295)
						(end 332.749398 -227.08997)
					)
					(arc
						(start 332.749398 -227.08997)
						(mid 332.734384 -227.125948)
						(end 332.749398 -227.161852)
					)
					(arc
						(start 332.749398 -227.161852)
						(mid 332.761219 -227.170594)
						(end 332.775052 -227.175568)
					)
					(xy 332.795626 -227.175568) (xy 332.796134 -227.175568)
					(arc
						(start 332.79715 -227.175568)
						(mid 332.869855 -227.190406)
						(end 332.931516 -227.231702)
					)
					(arc
						(start 332.931516 -227.231702)
						(mid 332.987593 -227.367084)
						(end 332.931516 -227.502466)
					)
					(arc
						(start 332.931516 -227.502466)
						(mid 332.86905 -227.544115)
						(end 332.795372 -227.5586)
					)
					(xy 332.79461 -227.558346)
					(arc
						(start 332.774036 -227.558346)
						(mid 332.760174 -227.563436)
						(end 332.748382 -227.572316)
					)
				)
			)
		)
		(zone
			(layer "F.Cu")
			(hatch none 0.5)
			(connect_pads
				(clearance 0)
			)
			(min_thickness 0.25)
			(keepout
				(tracks not_allowed)
				(vias allowed)
				(pads allowed)
				(copperpour not_allowed)
				(footprints allowed)
			)
			(placement
				(enabled no)
				(sheetname "")
			)
			(fill
				(thermal_gap 0.5)
				(thermal_bridge_width 0.5)
				(island_removal_mode 0)
			)
			(polygon
				(pts
					(arc
						(start 332.748382 -225.94443)
						(mid 332.733368 -225.980408)
						(end 332.748382 -226.016312)
					)
					(arc
						(start 332.748382 -226.016312)
						(mid 332.765504 -226.027663)
						(end 332.78572 -226.031298)
					)
					(arc
						(start 332.78572 -226.031298)
						(mid 332.903088 -226.011083)
						(end 333.002636 -225.9457)
					)
					(arc
						(start 333.002636 -225.9457)
						(mid 333.088172 -225.739198)
						(end 333.002636 -225.532696)
					)
					(arc
						(start 333.002636 -225.532696)
						(mid 332.904243 -225.467907)
						(end 332.78826 -225.447352)
					)
					(arc
						(start 332.78826 -225.447352)
						(mid 332.767251 -225.450552)
						(end 332.749398 -225.462084)
					)
					(arc
						(start 332.749398 -225.462084)
						(mid 332.734384 -225.498062)
						(end 332.749398 -225.533966)
					)
					(arc
						(start 332.749398 -225.533966)
						(mid 332.761219 -225.542708)
						(end 332.775052 -225.547682)
					)
					(xy 332.795626 -225.547682) (xy 332.796134 -225.547682)
					(arc
						(start 332.79715 -225.547682)
						(mid 332.869855 -225.56252)
						(end 332.931516 -225.603816)
					)
					(arc
						(start 332.931516 -225.603816)
						(mid 332.987593 -225.739198)
						(end 332.931516 -225.87458)
					)
					(arc
						(start 332.931516 -225.87458)
						(mid 332.86905 -225.916229)
						(end 332.795372 -225.930714)
					)
					(xy 332.79461 -225.93046)
					(arc
						(start 332.774036 -225.93046)
						(mid 332.760174 -225.93555)
						(end 332.748382 -225.94443)
					)
				)
			)
		)
		(zone
			(layer "F.Cu")
			(hatch none 0.5)
			(connect_pads
				(clearance 0)
			)
			(min_thickness 0.25)
			(keepout
				(tracks not_allowed)
				(vias allowed)
				(pads allowed)
				(copperpour not_allowed)
				(footprints allowed)
			)
			(placement
				(enabled no)
				(sheetname "")
			)
			(fill
				(thermal_gap 0.5)
				(thermal_bridge_width 0.5)
				(island_removal_mode 0)
			)
			(polygon
				(pts
					(arc
						(start 332.748382 -224.316798)
						(mid 332.733621 -224.352612)
						(end 332.748382 -224.388426)
					)
					(arc
						(start 332.748382 -224.388426)
						(mid 332.765504 -224.399777)
						(end 332.78572 -224.403412)
					)
					(arc
						(start 332.78572 -224.403412)
						(mid 332.903061 -224.383318)
						(end 333.002636 -224.318068)
					)
					(arc
						(start 333.002636 -224.318068)
						(mid 333.088172 -224.111566)
						(end 333.002636 -223.905064)
					)
					(arc
						(start 333.002636 -223.905064)
						(mid 332.904274 -223.840135)
						(end 332.78826 -223.819466)
					)
					(arc
						(start 332.78826 -223.819466)
						(mid 332.767238 -223.822654)
						(end 332.749398 -223.834198)
					)
					(arc
						(start 332.749398 -223.834198)
						(mid 332.734384 -223.870176)
						(end 332.749398 -223.90608)
					)
					(arc
						(start 332.749398 -223.90608)
						(mid 332.761203 -223.914863)
						(end 332.775052 -223.919796)
					)
					(xy 332.795626 -223.919796) (xy 332.796134 -223.919796)
					(arc
						(start 332.79715 -223.919796)
						(mid 332.869885 -223.93475)
						(end 332.931516 -223.976184)
					)
					(arc
						(start 332.931516 -223.976184)
						(mid 332.987593 -224.111566)
						(end 332.931516 -224.246948)
					)
					(arc
						(start 332.931516 -224.246948)
						(mid 332.869051 -224.288626)
						(end 332.795372 -224.303082)
					)
					(xy 332.79461 -224.302828)
					(arc
						(start 332.774036 -224.302828)
						(mid 332.760174 -224.307918)
						(end 332.748382 -224.316798)
					)
				)
			)
		)
		(zone
			(layer "F.Cu")
			(hatch none 0.5)
			(connect_pads
				(clearance 0)
			)
			(min_thickness 0.25)
			(keepout
				(tracks not_allowed)
				(vias allowed)
				(pads allowed)
				(copperpour not_allowed)
				(footprints allowed)
			)
			(placement
				(enabled no)
				(sheetname "")
			)
			(fill
				(thermal_gap 0.5)
				(thermal_bridge_width 0.5)
				(island_removal_mode 0)
			)
			(polygon
				(pts
					(arc
						(start 332.748382 -222.688912)
						(mid 332.733368 -222.72489)
						(end 332.748382 -222.760794)
					)
					(arc
						(start 332.748382 -222.760794)
						(mid 332.765535 -222.772005)
						(end 332.78572 -222.775526)
					)
					(arc
						(start 332.78572 -222.775526)
						(mid 332.903061 -222.755432)
						(end 333.002636 -222.690182)
					)
					(arc
						(start 333.002636 -222.690182)
						(mid 333.088172 -222.48368)
						(end 333.002636 -222.277178)
					)
					(arc
						(start 333.002636 -222.277178)
						(mid 332.904274 -222.212249)
						(end 332.78826 -222.19158)
					)
					(arc
						(start 332.78826 -222.19158)
						(mid 332.767211 -222.194891)
						(end 332.749398 -222.206566)
					)
					(arc
						(start 332.749398 -222.206566)
						(mid 332.734384 -222.242544)
						(end 332.749398 -222.278448)
					)
					(arc
						(start 332.749398 -222.278448)
						(mid 332.761219 -222.28719)
						(end 332.775052 -222.292164)
					)
					(xy 332.795626 -222.292164) (xy 332.796134 -222.292164)
					(arc
						(start 332.79715 -222.292164)
						(mid 332.869855 -222.307002)
						(end 332.931516 -222.348298)
					)
					(arc
						(start 332.931516 -222.348298)
						(mid 332.987593 -222.48368)
						(end 332.931516 -222.619062)
					)
					(arc
						(start 332.931516 -222.619062)
						(mid 332.86905 -222.660711)
						(end 332.795372 -222.675196)
					)
					(xy 332.79461 -222.674942)
					(arc
						(start 332.774036 -222.674942)
						(mid 332.760174 -222.680032)
						(end 332.748382 -222.688912)
					)
				)
			)
		)
		(zone
			(layer "F.Cu")
			(hatch none 0.5)
			(connect_pads
				(clearance 0)
			)
			(min_thickness 0.25)
			(keepout
				(tracks not_allowed)
				(vias allowed)
				(pads allowed)
				(copperpour not_allowed)
				(footprints allowed)
			)
			(placement
				(enabled no)
				(sheetname "")
			)
			(fill
				(thermal_gap 0.5)
				(thermal_bridge_width 0.5)
				(island_removal_mode 0)
			)
			(polygon
				(pts
					(arc
						(start 332.858364 -267.42517)
						(mid 332.843603 -267.460984)
						(end 332.858364 -267.496798)
					)
					(arc
						(start 332.858364 -267.496798)
						(mid 332.875486 -267.508149)
						(end 332.895702 -267.511784)
					)
					(arc
						(start 332.895702 -267.511784)
						(mid 333.013043 -267.49169)
						(end 333.112618 -267.42644)
					)
					(arc
						(start 333.112618 -267.42644)
						(mid 333.198154 -267.219938)
						(end 333.112618 -267.013436)
					)
					(arc
						(start 333.112618 -267.013436)
						(mid 333.014256 -266.948507)
						(end 332.898242 -266.927838)
					)
					(arc
						(start 332.898242 -266.927838)
						(mid 332.87722 -266.931026)
						(end 332.85938 -266.94257)
					)
					(arc
						(start 332.85938 -266.94257)
						(mid 332.844365 -266.978638)
						(end 332.85938 -267.014706)
					)
					(arc
						(start 332.85938 -267.014706)
						(mid 332.871234 -267.023282)
						(end 332.885034 -267.028168)
					)
					(xy 332.905608 -267.028168) (xy 332.906116 -267.028168)
					(arc
						(start 332.907132 -267.028168)
						(mid 332.979867 -267.043122)
						(end 333.041498 -267.084556)
					)
					(arc
						(start 333.041498 -267.084556)
						(mid 333.097575 -267.219938)
						(end 333.041498 -267.35532)
					)
					(arc
						(start 333.041498 -267.35532)
						(mid 332.979047 -267.397052)
						(end 332.905354 -267.411454)
					)
					(xy 332.904592 -267.4112)
					(arc
						(start 332.884272 -267.4112)
						(mid 332.87029 -267.416276)
						(end 332.858364 -267.42517)
					)
				)
			)
		)
		(zone
			(layer "F.Cu")
			(hatch none 0.5)
			(connect_pads
				(clearance 0)
			)
			(min_thickness 0.25)
			(keepout
				(tracks not_allowed)
				(vias allowed)
				(pads allowed)
				(copperpour not_allowed)
				(footprints allowed)
			)
			(placement
				(enabled no)
				(sheetname "")
			)
			(fill
				(thermal_gap 0.5)
				(thermal_bridge_width 0.5)
				(island_removal_mode 0)
			)
			(polygon
				(pts
					(arc
						(start 332.858364 -265.797284)
						(mid 332.84335 -265.833262)
						(end 332.858364 -265.869166)
					)
					(arc
						(start 332.858364 -265.869166)
						(mid 332.875517 -265.880377)
						(end 332.895702 -265.883898)
					)
					(arc
						(start 332.895702 -265.883898)
						(mid 333.013043 -265.863804)
						(end 333.112618 -265.798554)
					)
					(arc
						(start 333.112618 -265.798554)
						(mid 333.198154 -265.592052)
						(end 333.112618 -265.38555)
					)
					(arc
						(start 333.112618 -265.38555)
						(mid 333.014225 -265.320761)
						(end 332.898242 -265.300206)
					)
					(arc
						(start 332.898242 -265.300206)
						(mid 332.877233 -265.303406)
						(end 332.85938 -265.314938)
					)
					(arc
						(start 332.85938 -265.314938)
						(mid 332.844366 -265.350916)
						(end 332.85938 -265.38682)
					)
					(arc
						(start 332.85938 -265.38682)
						(mid 332.871201 -265.395562)
						(end 332.885034 -265.400536)
					)
					(xy 332.905608 -265.400536) (xy 332.906116 -265.400536)
					(arc
						(start 332.907132 -265.400536)
						(mid 332.979837 -265.415374)
						(end 333.041498 -265.45667)
					)
					(arc
						(start 333.041498 -265.45667)
						(mid 333.097575 -265.592052)
						(end 333.041498 -265.727434)
					)
					(arc
						(start 333.041498 -265.727434)
						(mid 332.979032 -265.769083)
						(end 332.905354 -265.783568)
					)
					(xy 332.904592 -265.783314)
					(arc
						(start 332.884272 -265.783314)
						(mid 332.87029 -265.78839)
						(end 332.858364 -265.797284)
					)
				)
			)
		)
		(zone
			(layer "F.Cu")
			(hatch none 0.5)
			(connect_pads
				(clearance 0)
			)
			(min_thickness 0.25)
			(keepout
				(tracks not_allowed)
				(vias allowed)
				(pads allowed)
				(copperpour not_allowed)
				(footprints allowed)
			)
			(placement
				(enabled no)
				(sheetname "")
			)
			(fill
				(thermal_gap 0.5)
				(thermal_bridge_width 0.5)
				(island_removal_mode 0)
			)
			(polygon
				(pts
					(arc
						(start 332.858364 -264.169398)
						(mid 332.84335 -264.205376)
						(end 332.858364 -264.24128)
					)
					(arc
						(start 332.858364 -264.24128)
						(mid 332.875486 -264.252631)
						(end 332.895702 -264.256266)
					)
					(arc
						(start 332.895702 -264.256266)
						(mid 333.01307 -264.236051)
						(end 333.112618 -264.170668)
					)
					(arc
						(start 333.112618 -264.170668)
						(mid 333.198154 -263.964166)
						(end 333.112618 -263.757664)
					)
					(arc
						(start 333.112618 -263.757664)
						(mid 333.014225 -263.692875)
						(end 332.898242 -263.67232)
					)
					(arc
						(start 332.898242 -263.67232)
						(mid 332.877233 -263.67552)
						(end 332.85938 -263.687052)
					)
					(arc
						(start 332.85938 -263.687052)
						(mid 332.844366 -263.72303)
						(end 332.85938 -263.758934)
					)
					(arc
						(start 332.85938 -263.758934)
						(mid 332.871201 -263.767676)
						(end 332.885034 -263.77265)
					)
					(xy 332.905608 -263.77265) (xy 332.906116 -263.77265)
					(arc
						(start 332.907132 -263.77265)
						(mid 332.979837 -263.787488)
						(end 333.041498 -263.828784)
					)
					(arc
						(start 333.041498 -263.828784)
						(mid 333.097755 -263.96433)
						(end 333.041498 -264.099802)
					)
					(arc
						(start 333.041498 -264.099802)
						(mid 332.979003 -264.141313)
						(end 332.905354 -264.155682)
					)
					(xy 332.904592 -264.155682)
					(arc
						(start 332.884272 -264.155682)
						(mid 332.870328 -264.160658)
						(end 332.858364 -264.169398)
					)
				)
			)
		)
		(zone
			(layer "F.Cu")
			(hatch none 0.5)
			(connect_pads
				(clearance 0)
			)
			(min_thickness 0.25)
			(keepout
				(tracks not_allowed)
				(vias allowed)
				(pads allowed)
				(copperpour not_allowed)
				(footprints allowed)
			)
			(placement
				(enabled no)
				(sheetname "")
			)
			(fill
				(thermal_gap 0.5)
				(thermal_bridge_width 0.5)
				(island_removal_mode 0)
			)
			(polygon
				(pts
					(arc
						(start 332.858364 -262.541766)
						(mid 332.843529 -262.57758)
						(end 332.858364 -262.613394)
					)
					(arc
						(start 332.858364 -262.613394)
						(mid 332.875486 -262.624745)
						(end 332.895702 -262.62838)
					)
					(arc
						(start 332.895702 -262.62838)
						(mid 333.013043 -262.608286)
						(end 333.112618 -262.543036)
					)
					(arc
						(start 333.112618 -262.543036)
						(mid 333.198154 -262.336534)
						(end 333.112618 -262.130032)
					)
					(arc
						(start 333.112618 -262.130032)
						(mid 333.014256 -262.065103)
						(end 332.898242 -262.044434)
					)
					(arc
						(start 332.898242 -262.044434)
						(mid 332.87722 -262.047622)
						(end 332.85938 -262.059166)
					)
					(arc
						(start 332.85938 -262.059166)
						(mid 332.844365 -262.095234)
						(end 332.85938 -262.131302)
					)
					(arc
						(start 332.85938 -262.131302)
						(mid 332.871234 -262.139878)
						(end 332.885034 -262.144764)
					)
					(xy 332.905608 -262.144764) (xy 332.906116 -262.144764)
					(arc
						(start 332.907132 -262.144764)
						(mid 332.979867 -262.159718)
						(end 333.041498 -262.201152)
					)
					(arc
						(start 333.041498 -262.201152)
						(mid 333.097575 -262.336534)
						(end 333.041498 -262.471916)
					)
					(arc
						(start 333.041498 -262.471916)
						(mid 332.979047 -262.513648)
						(end 332.905354 -262.52805)
					)
					(xy 332.904592 -262.527796)
					(arc
						(start 332.884272 -262.527796)
						(mid 332.87029 -262.532872)
						(end 332.858364 -262.541766)
					)
				)
			)
		)
		(zone
			(layer "F.Cu")
			(hatch none 0.5)
			(connect_pads
				(clearance 0)
			)
			(min_thickness 0.25)
			(keepout
				(tracks not_allowed)
				(vias allowed)
				(pads allowed)
				(copperpour not_allowed)
				(footprints allowed)
			)
			(placement
				(enabled no)
				(sheetname "")
			)
			(fill
				(thermal_gap 0.5)
				(thermal_bridge_width 0.5)
				(island_removal_mode 0)
			)
			(polygon
				(pts
					(arc
						(start 332.858364 -260.91388)
						(mid 332.84335 -260.949858)
						(end 332.858364 -260.985762)
					)
					(arc
						(start 332.858364 -260.985762)
						(mid 332.875486 -260.997113)
						(end 332.895702 -261.000748)
					)
					(arc
						(start 332.895702 -261.000748)
						(mid 333.013043 -260.980654)
						(end 333.112618 -260.915404)
					)
					(arc
						(start 333.112618 -260.915404)
						(mid 333.198154 -260.708902)
						(end 333.112618 -260.5024)
					)
					(arc
						(start 333.112618 -260.5024)
						(mid 333.014256 -260.437471)
						(end 332.898242 -260.416802)
					)
					(arc
						(start 332.898242 -260.416802)
						(mid 332.87722 -260.41999)
						(end 332.85938 -260.431534)
					)
					(arc
						(start 332.85938 -260.431534)
						(mid 332.844366 -260.467512)
						(end 332.85938 -260.503416)
					)
					(arc
						(start 332.85938 -260.503416)
						(mid 332.871185 -260.512199)
						(end 332.885034 -260.517132)
					)
					(xy 332.905608 -260.517132) (xy 332.906116 -260.517132)
					(arc
						(start 332.907132 -260.517132)
						(mid 332.979837 -260.53197)
						(end 333.041498 -260.573266)
					)
					(arc
						(start 333.041498 -260.573266)
						(mid 333.097755 -260.708812)
						(end 333.041498 -260.844284)
					)
					(arc
						(start 333.041498 -260.844284)
						(mid 332.979003 -260.885795)
						(end 332.905354 -260.900164)
					)
					(xy 332.904592 -260.900164)
					(arc
						(start 332.884272 -260.900164)
						(mid 332.870311 -260.905121)
						(end 332.858364 -260.91388)
					)
				)
			)
		)
		(zone
			(layer "F.Cu")
			(hatch none 0.5)
			(connect_pads
				(clearance 0)
			)
			(min_thickness 0.25)
			(keepout
				(tracks not_allowed)
				(vias allowed)
				(pads allowed)
				(copperpour not_allowed)
				(footprints allowed)
			)
			(placement
				(enabled no)
				(sheetname "")
			)
			(fill
				(thermal_gap 0.5)
				(thermal_bridge_width 0.5)
				(island_removal_mode 0)
			)
			(polygon
				(pts
					(arc
						(start 332.858364 -259.286248)
						(mid 332.843603 -259.322062)
						(end 332.858364 -259.357876)
					)
					(arc
						(start 332.858364 -259.357876)
						(mid 332.875486 -259.369227)
						(end 332.895702 -259.372862)
					)
					(arc
						(start 332.895702 -259.372862)
						(mid 333.013043 -259.352768)
						(end 333.112618 -259.287518)
					)
					(arc
						(start 333.112618 -259.287518)
						(mid 333.198154 -259.081016)
						(end 333.112618 -258.874514)
					)
					(arc
						(start 333.112618 -258.874514)
						(mid 333.014256 -258.809585)
						(end 332.898242 -258.788916)
					)
					(arc
						(start 332.898242 -258.788916)
						(mid 332.877193 -258.792227)
						(end 332.85938 -258.803902)
					)
					(arc
						(start 332.85938 -258.803902)
						(mid 332.844366 -258.83988)
						(end 332.85938 -258.875784)
					)
					(arc
						(start 332.85938 -258.875784)
						(mid 332.871201 -258.884526)
						(end 332.885034 -258.8895)
					)
					(xy 332.905608 -258.8895) (xy 332.906116 -258.8895)
					(arc
						(start 332.907132 -258.8895)
						(mid 332.979837 -258.904338)
						(end 333.041498 -258.945634)
					)
					(arc
						(start 333.041498 -258.945634)
						(mid 333.097575 -259.081016)
						(end 333.041498 -259.216398)
					)
					(arc
						(start 333.041498 -259.216398)
						(mid 332.979047 -259.25813)
						(end 332.905354 -259.272532)
					)
					(xy 332.904592 -259.272278)
					(arc
						(start 332.884272 -259.272278)
						(mid 332.87029 -259.277354)
						(end 332.858364 -259.286248)
					)
				)
			)
		)
		(zone
			(layer "F.Cu")
			(hatch none 0.5)
			(connect_pads
				(clearance 0)
			)
			(min_thickness 0.25)
			(keepout
				(tracks not_allowed)
				(vias allowed)
				(pads allowed)
				(copperpour not_allowed)
				(footprints allowed)
			)
			(placement
				(enabled no)
				(sheetname "")
			)
			(fill
				(thermal_gap 0.5)
				(thermal_bridge_width 0.5)
				(island_removal_mode 0)
			)
			(polygon
				(pts
					(arc
						(start 332.858364 -257.658362)
						(mid 332.84335 -257.69434)
						(end 332.858364 -257.730244)
					)
					(arc
						(start 332.858364 -257.730244)
						(mid 332.875517 -257.741455)
						(end 332.895702 -257.744976)
					)
					(arc
						(start 332.895702 -257.744976)
						(mid 333.013043 -257.724882)
						(end 333.112618 -257.659632)
					)
					(arc
						(start 333.112618 -257.659632)
						(mid 333.198154 -257.45313)
						(end 333.112618 -257.246628)
					)
					(arc
						(start 333.112618 -257.246628)
						(mid 333.014225 -257.181839)
						(end 332.898242 -257.161284)
					)
					(arc
						(start 332.898242 -257.161284)
						(mid 332.877233 -257.164484)
						(end 332.85938 -257.176016)
					)
					(arc
						(start 332.85938 -257.176016)
						(mid 332.844366 -257.211994)
						(end 332.85938 -257.247898)
					)
					(arc
						(start 332.85938 -257.247898)
						(mid 332.871201 -257.25664)
						(end 332.885034 -257.261614)
					)
					(xy 332.905608 -257.261614) (xy 332.906116 -257.261614)
					(arc
						(start 332.907132 -257.261614)
						(mid 332.979837 -257.276452)
						(end 333.041498 -257.317748)
					)
					(arc
						(start 333.041498 -257.317748)
						(mid 333.097575 -257.45313)
						(end 333.041498 -257.588512)
					)
					(arc
						(start 333.041498 -257.588512)
						(mid 332.979032 -257.630161)
						(end 332.905354 -257.644646)
					)
					(xy 332.904592 -257.644392)
					(arc
						(start 332.884272 -257.644392)
						(mid 332.87029 -257.649468)
						(end 332.858364 -257.658362)
					)
				)
			)
		)
		(zone
			(layer "F.Cu")
			(hatch none 0.5)
			(connect_pads
				(clearance 0)
			)
			(min_thickness 0.25)
			(keepout
				(tracks not_allowed)
				(vias allowed)
				(pads allowed)
				(copperpour not_allowed)
				(footprints allowed)
			)
			(placement
				(enabled no)
				(sheetname "")
			)
			(fill
				(thermal_gap 0.5)
				(thermal_bridge_width 0.5)
				(island_removal_mode 0)
			)
			(polygon
				(pts
					(arc
						(start 332.858364 -256.030476)
						(mid 332.84335 -256.066454)
						(end 332.858364 -256.102358)
					)
					(arc
						(start 332.858364 -256.102358)
						(mid 332.875486 -256.113709)
						(end 332.895702 -256.117344)
					)
					(arc
						(start 332.895702 -256.117344)
						(mid 333.013043 -256.09725)
						(end 333.112618 -256.032)
					)
					(arc
						(start 333.112618 -256.032)
						(mid 333.198154 -255.825498)
						(end 333.112618 -255.618996)
					)
					(arc
						(start 333.112618 -255.618996)
						(mid 333.014256 -255.554067)
						(end 332.898242 -255.533398)
					)
					(arc
						(start 332.898242 -255.533398)
						(mid 332.87722 -255.536586)
						(end 332.85938 -255.54813)
					)
					(arc
						(start 332.85938 -255.54813)
						(mid 332.844366 -255.584108)
						(end 332.85938 -255.620012)
					)
					(arc
						(start 332.85938 -255.620012)
						(mid 332.871185 -255.628795)
						(end 332.885034 -255.633728)
					)
					(xy 332.905608 -255.633728) (xy 332.906116 -255.633728)
					(arc
						(start 332.907132 -255.633728)
						(mid 332.979837 -255.648566)
						(end 333.041498 -255.689862)
					)
					(arc
						(start 333.041498 -255.689862)
						(mid 333.097755 -255.825408)
						(end 333.041498 -255.96088)
					)
					(arc
						(start 333.041498 -255.96088)
						(mid 332.979003 -256.002391)
						(end 332.905354 -256.01676)
					)
					(xy 332.904592 -256.01676)
					(arc
						(start 332.884272 -256.01676)
						(mid 332.870311 -256.021717)
						(end 332.858364 -256.030476)
					)
				)
			)
		)
		(zone
			(layer "F.Cu")
			(hatch none 0.5)
			(connect_pads
				(clearance 0)
			)
			(min_thickness 0.25)
			(keepout
				(tracks not_allowed)
				(vias allowed)
				(pads allowed)
				(copperpour not_allowed)
				(footprints allowed)
			)
			(placement
				(enabled no)
				(sheetname "")
			)
			(fill
				(thermal_gap 0.5)
				(thermal_bridge_width 0.5)
				(island_removal_mode 0)
			)
			(polygon
				(pts
					(arc
						(start 333.086964 -220.153484)
						(mid 333.051043 -220.168363)
						(end 333.036164 -220.204284)
					)
					(arc
						(start 333.036164 -220.204284)
						(mid 333.040396 -220.224331)
						(end 333.052166 -220.241114)
					)
					(arc
						(start 333.052166 -220.241114)
						(mid 333.149293 -220.309843)
						(end 333.26578 -220.334078)
					)
					(arc
						(start 333.26578 -220.334078)
						(mid 333.472326 -220.248524)
						(end 333.55788 -220.041978)
					)
					(arc
						(start 333.55788 -220.041978)
						(mid 333.534043 -219.926709)
						(end 333.466694 -219.830142)
					)
					(arc
						(start 333.466694 -219.830142)
						(mid 333.449599 -219.817563)
						(end 333.428848 -219.813124)
					)
					(arc
						(start 333.428848 -219.813124)
						(mid 333.392927 -219.828003)
						(end 333.378048 -219.863924)
					)
					(arc
						(start 333.378048 -219.863924)
						(mid 333.380233 -219.878372)
						(end 333.38643 -219.89161)
					)
					(xy 333.401162 -219.906342) (xy 333.401416 -219.906596)
					(arc
						(start 333.401924 -219.907358)
						(mid 333.442903 -219.969206)
						(end 333.457296 -220.041978)
					)
					(arc
						(start 333.457296 -220.041978)
						(mid 333.401202 -220.1774)
						(end 333.26578 -220.233494)
					)
					(arc
						(start 333.26578 -220.233494)
						(mid 333.192187 -220.218896)
						(end 333.12989 -220.177106)
					)
					(xy 333.129636 -220.176344)
					(arc
						(start 333.115158 -220.161866)
						(mid 333.10168 -220.155593)
						(end 333.086964 -220.153484)
					)
				)
			)
		)
		(zone
			(layer "F.Cu")
			(hatch none 0.5)
			(connect_pads
				(clearance 0)
			)
			(min_thickness 0.25)
			(keepout
				(tracks not_allowed)
				(vias allowed)
				(pads allowed)
				(copperpour not_allowed)
				(footprints allowed)
			)
			(placement
				(enabled no)
				(sheetname "")
			)
			(fill
				(thermal_gap 0.5)
				(thermal_bridge_width 0.5)
				(island_removal_mode 0)
			)
			(polygon
				(pts
					(arc
						(start 333.086964 -218.525598)
						(mid 333.051043 -218.540477)
						(end 333.036164 -218.576398)
					)
					(arc
						(start 333.036164 -218.576398)
						(mid 333.040346 -218.596582)
						(end 333.052166 -218.613482)
					)
					(arc
						(start 333.052166 -218.613482)
						(mid 333.149309 -218.682153)
						(end 333.26578 -218.706446)
					)
					(arc
						(start 333.26578 -218.706446)
						(mid 333.472326 -218.620892)
						(end 333.55788 -218.414346)
					)
					(arc
						(start 333.55788 -218.414346)
						(mid 333.534109 -218.298924)
						(end 333.466694 -218.202256)
					)
					(arc
						(start 333.466694 -218.202256)
						(mid 333.449599 -218.189677)
						(end 333.428848 -218.185238)
					)
					(arc
						(start 333.428848 -218.185238)
						(mid 333.392927 -218.200117)
						(end 333.378048 -218.236038)
					)
					(arc
						(start 333.378048 -218.236038)
						(mid 333.380187 -218.250624)
						(end 333.38643 -218.263978)
					)
					(xy 333.401162 -218.278456) (xy 333.401416 -218.278964)
					(arc
						(start 333.401924 -218.279472)
						(mid 333.442951 -218.341437)
						(end 333.457296 -218.414346)
					)
					(arc
						(start 333.457296 -218.414346)
						(mid 333.401202 -218.549768)
						(end 333.26578 -218.605862)
					)
					(arc
						(start 333.26578 -218.605862)
						(mid 333.192198 -218.591078)
						(end 333.12989 -218.54922)
					)
					(xy 333.129636 -218.548458)
					(arc
						(start 333.115158 -218.53398)
						(mid 333.101675 -218.527738)
						(end 333.086964 -218.525598)
					)
				)
			)
		)
		(zone
			(layer "F.Cu")
			(hatch none 0.5)
			(connect_pads
				(clearance 0)
			)
			(min_thickness 0.25)
			(keepout
				(tracks not_allowed)
				(vias allowed)
				(pads allowed)
				(copperpour not_allowed)
				(footprints allowed)
			)
			(placement
				(enabled no)
				(sheetname "")
			)
			(fill
				(thermal_gap 0.5)
				(thermal_bridge_width 0.5)
				(island_removal_mode 0)
			)
			(polygon
				(pts
					(arc
						(start 333.196946 -255.122934)
						(mid 333.161025 -255.137813)
						(end 333.146146 -255.173734)
					)
					(arc
						(start 333.146146 -255.173734)
						(mid 333.150378 -255.193781)
						(end 333.162148 -255.210564)
					)
					(arc
						(start 333.162148 -255.210564)
						(mid 333.259275 -255.279293)
						(end 333.375762 -255.303528)
					)
					(arc
						(start 333.375762 -255.303528)
						(mid 333.582218 -255.218064)
						(end 333.667862 -255.011682)
					)
					(arc
						(start 333.667862 -255.011682)
						(mid 333.644212 -254.896288)
						(end 333.57693 -254.799592)
					)
					(arc
						(start 333.57693 -254.799592)
						(mid 333.559702 -254.787023)
						(end 333.53883 -254.782574)
					)
					(arc
						(start 333.53883 -254.782574)
						(mid 333.502909 -254.797453)
						(end 333.48803 -254.833374)
					)
					(arc
						(start 333.48803 -254.833374)
						(mid 333.490215 -254.847822)
						(end 333.496412 -254.86106)
					)
					(xy 333.511144 -254.875792) (xy 333.511398 -254.8763)
					(arc
						(start 333.51216 -254.876808)
						(mid 333.553052 -254.938802)
						(end 333.567278 -255.011682)
					)
					(arc
						(start 333.567278 -255.011682)
						(mid 333.511184 -255.147104)
						(end 333.375762 -255.203198)
					)
					(arc
						(start 333.375762 -255.203198)
						(mid 333.30218 -255.188414)
						(end 333.239872 -255.146556)
					)
					(xy 333.239618 -255.145794)
					(arc
						(start 333.22514 -255.131316)
						(mid 333.211662 -255.125043)
						(end 333.196946 -255.122934)
					)
				)
			)
		)
		(zone
			(layer "F.Cu")
			(hatch none 0.5)
			(connect_pads
				(clearance 0)
			)
			(min_thickness 0.25)
			(keepout
				(tracks not_allowed)
				(vias allowed)
				(pads allowed)
				(copperpour not_allowed)
				(footprints allowed)
			)
			(placement
				(enabled no)
				(sheetname "")
			)
			(fill
				(thermal_gap 0.5)
				(thermal_bridge_width 0.5)
				(island_removal_mode 0)
			)
			(polygon
				(pts
					(arc
						(start 333.212186 -221.873064)
						(mid 333.196078 -221.908445)
						(end 333.209646 -221.944946)
					)
					(arc
						(start 333.209646 -221.944946)
						(mid 333.22626 -221.956856)
						(end 333.246222 -221.961202)
					)
					(arc
						(start 333.246222 -221.961202)
						(mid 333.364284 -221.945395)
						(end 333.466186 -221.883732)
					)
					(arc
						(start 333.466186 -221.883732)
						(mid 333.559162 -221.680461)
						(end 333.481172 -221.470982)
					)
					(arc
						(start 333.481172 -221.470982)
						(mid 333.385107 -221.402626)
						(end 333.269844 -221.377764)
					)
					(arc
						(start 333.269844 -221.377764)
						(mid 333.24869 -221.380231)
						(end 333.230474 -221.391226)
					)
					(arc
						(start 333.230474 -221.391226)
						(mid 333.214369 -221.426514)
						(end 333.227934 -221.462854)
					)
					(arc
						(start 333.227934 -221.462854)
						(mid 333.239323 -221.471994)
						(end 333.252826 -221.477586)
					)
					(xy 333.273654 -221.478348) (xy 333.274162 -221.478348)
					(arc
						(start 333.275178 -221.478602)
						(mid 333.347175 -221.495979)
						(end 333.407258 -221.539308)
					)
					(arc
						(start 333.407258 -221.539308)
						(mid 333.458509 -221.676689)
						(end 333.397606 -221.810072)
					)
					(arc
						(start 333.397606 -221.810072)
						(mid 333.333613 -221.849364)
						(end 333.25943 -221.861126)
					)
					(xy 333.258922 -221.860872)
					(arc
						(start 333.238348 -221.860364)
						(mid 333.224323 -221.86478)
						(end 333.212186 -221.873064)
					)
				)
			)
		)
		(zone
			(layer "F.Cu")
			(hatch none 0.5)
			(connect_pads
				(clearance 0)
			)
			(min_thickness 0.25)
			(keepout
				(tracks not_allowed)
				(vias allowed)
				(pads allowed)
				(copperpour not_allowed)
				(footprints allowed)
			)
			(placement
				(enabled no)
				(sheetname "")
			)
			(fill
				(thermal_gap 0.5)
				(thermal_bridge_width 0.5)
				(island_removal_mode 0)
			)
			(polygon
				(pts
					(arc
						(start 333.328264 -281.261058)
						(mid 333.31325 -281.297036)
						(end 333.328264 -281.33294)
					)
					(arc
						(start 333.328264 -281.33294)
						(mid 333.345386 -281.344291)
						(end 333.365602 -281.347926)
					)
					(arc
						(start 333.365602 -281.347926)
						(mid 333.482803 -281.327777)
						(end 333.582264 -281.262582)
					)
					(arc
						(start 333.582264 -281.262582)
						(mid 333.6678 -281.05608)
						(end 333.582264 -280.849578)
					)
					(arc
						(start 333.582264 -280.849578)
						(mid 333.484006 -280.784783)
						(end 333.368142 -280.76398)
					)
					(arc
						(start 333.368142 -280.76398)
						(mid 333.346979 -280.767109)
						(end 333.329026 -280.778712)
					)
					(arc
						(start 333.329026 -280.778712)
						(mid 333.314086 -280.81469)
						(end 333.329026 -280.850594)
					)
					(arc
						(start 333.329026 -280.850594)
						(mid 333.340847 -280.859336)
						(end 333.35468 -280.86431)
					)
					(xy 333.375508 -280.86431) (xy 333.376016 -280.86431)
					(arc
						(start 333.377032 -280.86431)
						(mid 333.44963 -280.879312)
						(end 333.511144 -280.920698)
					)
					(arc
						(start 333.511144 -280.920698)
						(mid 333.567221 -281.05608)
						(end 333.511144 -281.191462)
					)
					(arc
						(start 333.511144 -281.191462)
						(mid 333.448811 -281.233145)
						(end 333.375254 -281.247596)
					)
					(xy 333.374492 -281.247342)
					(arc
						(start 333.353918 -281.247342)
						(mid 333.340094 -281.252333)
						(end 333.328264 -281.261058)
					)
				)
			)
		)
		(zone
			(layer "F.Cu")
			(hatch none 0.5)
			(connect_pads
				(clearance 0)
			)
			(min_thickness 0.25)
			(keepout
				(tracks not_allowed)
				(vias allowed)
				(pads allowed)
				(copperpour not_allowed)
				(footprints allowed)
			)
			(placement
				(enabled no)
				(sheetname "")
			)
			(fill
				(thermal_gap 0.5)
				(thermal_bridge_width 0.5)
				(island_removal_mode 0)
			)
			(polygon
				(pts
					(arc
						(start 333.328264 -279.633426)
						(mid 333.313429 -279.66924)
						(end 333.328264 -279.705054)
					)
					(arc
						(start 333.328264 -279.705054)
						(mid 333.345386 -279.716405)
						(end 333.365602 -279.72004)
					)
					(arc
						(start 333.365602 -279.72004)
						(mid 333.482803 -279.699891)
						(end 333.582264 -279.634696)
					)
					(arc
						(start 333.582264 -279.634696)
						(mid 333.6678 -279.428194)
						(end 333.582264 -279.221692)
					)
					(arc
						(start 333.582264 -279.221692)
						(mid 333.48402 -279.15681)
						(end 333.368142 -279.136094)
					)
					(arc
						(start 333.368142 -279.136094)
						(mid 333.346952 -279.139346)
						(end 333.329026 -279.15108)
					)
					(arc
						(start 333.329026 -279.15108)
						(mid 333.314086 -279.187058)
						(end 333.329026 -279.222962)
					)
					(arc
						(start 333.329026 -279.222962)
						(mid 333.340847 -279.231704)
						(end 333.35468 -279.236678)
					)
					(xy 333.375508 -279.236678) (xy 333.376016 -279.236678)
					(arc
						(start 333.377032 -279.236678)
						(mid 333.449587 -279.251578)
						(end 333.511144 -279.292812)
					)
					(arc
						(start 333.511144 -279.292812)
						(mid 333.567221 -279.428194)
						(end 333.511144 -279.563576)
					)
					(arc
						(start 333.511144 -279.563576)
						(mid 333.448796 -279.605176)
						(end 333.375254 -279.61971)
					)
					(xy 333.374492 -279.619456)
					(arc
						(start 333.353918 -279.619456)
						(mid 333.340056 -279.624546)
						(end 333.328264 -279.633426)
					)
				)
			)
		)
		(zone
			(layer "F.Cu")
			(hatch none 0.5)
			(connect_pads
				(clearance 0)
			)
			(min_thickness 0.25)
			(keepout
				(tracks not_allowed)
				(vias allowed)
				(pads allowed)
				(copperpour not_allowed)
				(footprints allowed)
			)
			(placement
				(enabled no)
				(sheetname "")
			)
			(fill
				(thermal_gap 0.5)
				(thermal_bridge_width 0.5)
				(island_removal_mode 0)
			)
			(polygon
				(pts
					(arc
						(start 333.328264 -278.00554)
						(mid 333.31325 -278.041518)
						(end 333.328264 -278.077422)
					)
					(arc
						(start 333.328264 -278.077422)
						(mid 333.345417 -278.088633)
						(end 333.365602 -278.092154)
					)
					(arc
						(start 333.365602 -278.092154)
						(mid 333.482803 -278.072005)
						(end 333.582264 -278.00681)
					)
					(arc
						(start 333.582264 -278.00681)
						(mid 333.6678 -277.800308)
						(end 333.582264 -277.593806)
					)
					(arc
						(start 333.582264 -277.593806)
						(mid 333.483989 -277.529065)
						(end 333.368142 -277.508462)
					)
					(arc
						(start 333.368142 -277.508462)
						(mid 333.346992 -277.511603)
						(end 333.329026 -277.523194)
					)
					(arc
						(start 333.329026 -277.523194)
						(mid 333.314086 -277.559172)
						(end 333.329026 -277.595076)
					)
					(arc
						(start 333.329026 -277.595076)
						(mid 333.340847 -277.603818)
						(end 333.35468 -277.608792)
					)
					(xy 333.375508 -277.608792) (xy 333.376016 -277.608792)
					(arc
						(start 333.377032 -277.608792)
						(mid 333.449601 -277.623677)
						(end 333.511144 -277.664926)
					)
					(arc
						(start 333.511144 -277.664926)
						(mid 333.567221 -277.800308)
						(end 333.511144 -277.93569)
					)
					(arc
						(start 333.511144 -277.93569)
						(mid 333.448796 -277.97729)
						(end 333.375254 -277.991824)
					)
					(xy 333.374492 -277.99157)
					(arc
						(start 333.353918 -277.99157)
						(mid 333.340056 -277.99666)
						(end 333.328264 -278.00554)
					)
				)
			)
		)
		(zone
			(layer "F.Cu")
			(hatch none 0.5)
			(connect_pads
				(clearance 0)
			)
			(min_thickness 0.25)
			(keepout
				(tracks not_allowed)
				(vias allowed)
				(pads allowed)
				(copperpour not_allowed)
				(footprints allowed)
			)
			(placement
				(enabled no)
				(sheetname "")
			)
			(fill
				(thermal_gap 0.5)
				(thermal_bridge_width 0.5)
				(island_removal_mode 0)
			)
			(polygon
				(pts
					(arc
						(start 333.328264 -276.377654)
						(mid 333.31325 -276.413632)
						(end 333.328264 -276.449536)
					)
					(arc
						(start 333.328264 -276.449536)
						(mid 333.345386 -276.460887)
						(end 333.365602 -276.464522)
					)
					(arc
						(start 333.365602 -276.464522)
						(mid 333.482803 -276.444373)
						(end 333.582264 -276.379178)
					)
					(arc
						(start 333.582264 -276.379178)
						(mid 333.6678 -276.172676)
						(end 333.582264 -275.966174)
					)
					(arc
						(start 333.582264 -275.966174)
						(mid 333.484006 -275.901379)
						(end 333.368142 -275.880576)
					)
					(arc
						(start 333.368142 -275.880576)
						(mid 333.346979 -275.883705)
						(end 333.329026 -275.895308)
					)
					(arc
						(start 333.329026 -275.895308)
						(mid 333.314086 -275.931286)
						(end 333.329026 -275.96719)
					)
					(arc
						(start 333.329026 -275.96719)
						(mid 333.340847 -275.975932)
						(end 333.35468 -275.980906)
					)
					(xy 333.375508 -275.980906) (xy 333.376016 -275.980906)
					(arc
						(start 333.377032 -275.980906)
						(mid 333.44963 -275.995908)
						(end 333.511144 -276.037294)
					)
					(arc
						(start 333.511144 -276.037294)
						(mid 333.567221 -276.172676)
						(end 333.511144 -276.308058)
					)
					(arc
						(start 333.511144 -276.308058)
						(mid 333.448811 -276.349741)
						(end 333.375254 -276.364192)
					)
					(xy 333.374492 -276.363938)
					(arc
						(start 333.353918 -276.363938)
						(mid 333.340094 -276.368929)
						(end 333.328264 -276.377654)
					)
				)
			)
		)
		(zone
			(layer "F.Cu")
			(hatch none 0.5)
			(connect_pads
				(clearance 0)
			)
			(min_thickness 0.25)
			(keepout
				(tracks not_allowed)
				(vias allowed)
				(pads allowed)
				(copperpour not_allowed)
				(footprints allowed)
			)
			(placement
				(enabled no)
				(sheetname "")
			)
			(fill
				(thermal_gap 0.5)
				(thermal_bridge_width 0.5)
				(island_removal_mode 0)
			)
			(polygon
				(pts
					(arc
						(start 333.328264 -274.750022)
						(mid 333.31325 -274.786)
						(end 333.328264 -274.821904)
					)
					(arc
						(start 333.328264 -274.821904)
						(mid 333.345386 -274.833255)
						(end 333.365602 -274.83689)
					)
					(arc
						(start 333.365602 -274.83689)
						(mid 333.482831 -274.816621)
						(end 333.582264 -274.751292)
					)
					(arc
						(start 333.582264 -274.751292)
						(mid 333.6678 -274.54479)
						(end 333.582264 -274.338288)
					)
					(arc
						(start 333.582264 -274.338288)
						(mid 333.483989 -274.273547)
						(end 333.368142 -274.252944)
					)
					(arc
						(start 333.368142 -274.252944)
						(mid 333.346979 -274.256073)
						(end 333.329026 -274.267676)
					)
					(arc
						(start 333.329026 -274.267676)
						(mid 333.314086 -274.303654)
						(end 333.329026 -274.339558)
					)
					(arc
						(start 333.329026 -274.339558)
						(mid 333.340847 -274.3483)
						(end 333.35468 -274.353274)
					)
					(xy 333.375508 -274.353274) (xy 333.376016 -274.353274)
					(arc
						(start 333.377032 -274.353274)
						(mid 333.449601 -274.368159)
						(end 333.511144 -274.409408)
					)
					(arc
						(start 333.511144 -274.409408)
						(mid 333.567221 -274.54479)
						(end 333.511144 -274.680172)
					)
					(arc
						(start 333.511144 -274.680172)
						(mid 333.448796 -274.721772)
						(end 333.375254 -274.736306)
					)
					(xy 333.374492 -274.736306)
					(arc
						(start 333.353918 -274.736306)
						(mid 333.340094 -274.741297)
						(end 333.328264 -274.750022)
					)
				)
			)
		)
		(zone
			(layer "F.Cu")
			(hatch none 0.5)
			(connect_pads
				(clearance 0)
			)
			(min_thickness 0.25)
			(keepout
				(tracks not_allowed)
				(vias allowed)
				(pads allowed)
				(copperpour not_allowed)
				(footprints allowed)
			)
			(placement
				(enabled no)
				(sheetname "")
			)
			(fill
				(thermal_gap 0.5)
				(thermal_bridge_width 0.5)
				(island_removal_mode 0)
			)
			(polygon
				(pts
					(arc
						(start 333.328264 -273.12239)
						(mid 333.313429 -273.158204)
						(end 333.328264 -273.194018)
					)
					(arc
						(start 333.328264 -273.194018)
						(mid 333.345386 -273.205369)
						(end 333.365602 -273.209004)
					)
					(arc
						(start 333.365602 -273.209004)
						(mid 333.482803 -273.188855)
						(end 333.582264 -273.12366)
					)
					(arc
						(start 333.582264 -273.12366)
						(mid 333.6678 -272.917158)
						(end 333.582264 -272.710656)
					)
					(arc
						(start 333.582264 -272.710656)
						(mid 333.484006 -272.645861)
						(end 333.368142 -272.625058)
					)
					(arc
						(start 333.368142 -272.625058)
						(mid 333.346979 -272.628187)
						(end 333.329026 -272.63979)
					)
					(arc
						(start 333.329026 -272.63979)
						(mid 333.314086 -272.675768)
						(end 333.329026 -272.711672)
					)
					(arc
						(start 333.329026 -272.711672)
						(mid 333.340847 -272.720414)
						(end 333.35468 -272.725388)
					)
					(xy 333.375508 -272.725388) (xy 333.376016 -272.725388)
					(arc
						(start 333.377032 -272.725388)
						(mid 333.44963 -272.74039)
						(end 333.511144 -272.781776)
					)
					(arc
						(start 333.511144 -272.781776)
						(mid 333.567221 -272.917158)
						(end 333.511144 -273.05254)
					)
					(arc
						(start 333.511144 -273.05254)
						(mid 333.448796 -273.09414)
						(end 333.375254 -273.108674)
					)
					(xy 333.374492 -273.10842)
					(arc
						(start 333.353918 -273.10842)
						(mid 333.340056 -273.11351)
						(end 333.328264 -273.12239)
					)
				)
			)
		)
		(zone
			(layer "F.Cu")
			(hatch none 0.5)
			(connect_pads
				(clearance 0)
			)
			(min_thickness 0.25)
			(keepout
				(tracks not_allowed)
				(vias allowed)
				(pads allowed)
				(copperpour not_allowed)
				(footprints allowed)
			)
			(placement
				(enabled no)
				(sheetname "")
			)
			(fill
				(thermal_gap 0.5)
				(thermal_bridge_width 0.5)
				(island_removal_mode 0)
			)
			(polygon
				(pts
					(arc
						(start 333.328264 -271.494504)
						(mid 333.31325 -271.530482)
						(end 333.328264 -271.566386)
					)
					(arc
						(start 333.328264 -271.566386)
						(mid 333.345417 -271.577597)
						(end 333.365602 -271.581118)
					)
					(arc
						(start 333.365602 -271.581118)
						(mid 333.482803 -271.560969)
						(end 333.582264 -271.495774)
					)
					(arc
						(start 333.582264 -271.495774)
						(mid 333.6678 -271.289272)
						(end 333.582264 -271.08277)
					)
					(arc
						(start 333.582264 -271.08277)
						(mid 333.48402 -271.017888)
						(end 333.368142 -270.997172)
					)
					(arc
						(start 333.368142 -270.997172)
						(mid 333.346952 -271.000424)
						(end 333.329026 -271.012158)
					)
					(arc
						(start 333.329026 -271.012158)
						(mid 333.314086 -271.048136)
						(end 333.329026 -271.08404)
					)
					(arc
						(start 333.329026 -271.08404)
						(mid 333.340847 -271.092782)
						(end 333.35468 -271.097756)
					)
					(xy 333.375508 -271.097756) (xy 333.376016 -271.097756)
					(arc
						(start 333.377032 -271.097756)
						(mid 333.449601 -271.112641)
						(end 333.511144 -271.15389)
					)
					(arc
						(start 333.511144 -271.15389)
						(mid 333.567221 -271.289272)
						(end 333.511144 -271.424654)
					)
					(arc
						(start 333.511144 -271.424654)
						(mid 333.448796 -271.466254)
						(end 333.375254 -271.480788)
					)
					(xy 333.374492 -271.480534)
					(arc
						(start 333.353918 -271.480534)
						(mid 333.340056 -271.485624)
						(end 333.328264 -271.494504)
					)
				)
			)
		)
		(zone
			(layer "F.Cu")
			(hatch none 0.5)
			(connect_pads
				(clearance 0)
			)
			(min_thickness 0.25)
			(keepout
				(tracks not_allowed)
				(vias allowed)
				(pads allowed)
				(copperpour not_allowed)
				(footprints allowed)
			)
			(placement
				(enabled no)
				(sheetname "")
			)
			(fill
				(thermal_gap 0.5)
				(thermal_bridge_width 0.5)
				(island_removal_mode 0)
			)
			(polygon
				(pts
					(arc
						(start 333.328264 -269.866618)
						(mid 333.31325 -269.902596)
						(end 333.328264 -269.9385)
					)
					(arc
						(start 333.328264 -269.9385)
						(mid 333.345386 -269.949851)
						(end 333.365602 -269.953486)
					)
					(arc
						(start 333.365602 -269.953486)
						(mid 333.482831 -269.933217)
						(end 333.582264 -269.867888)
					)
					(arc
						(start 333.582264 -269.867888)
						(mid 333.6678 -269.661386)
						(end 333.582264 -269.454884)
					)
					(arc
						(start 333.582264 -269.454884)
						(mid 333.483989 -269.390143)
						(end 333.368142 -269.36954)
					)
					(arc
						(start 333.368142 -269.36954)
						(mid 333.346979 -269.372669)
						(end 333.329026 -269.384272)
					)
					(arc
						(start 333.329026 -269.384272)
						(mid 333.314086 -269.42025)
						(end 333.329026 -269.456154)
					)
					(arc
						(start 333.329026 -269.456154)
						(mid 333.340847 -269.464896)
						(end 333.35468 -269.46987)
					)
					(xy 333.375508 -269.46987) (xy 333.376016 -269.46987)
					(arc
						(start 333.377032 -269.46987)
						(mid 333.449601 -269.484755)
						(end 333.511144 -269.526004)
					)
					(arc
						(start 333.511144 -269.526004)
						(mid 333.567221 -269.661386)
						(end 333.511144 -269.796768)
					)
					(arc
						(start 333.511144 -269.796768)
						(mid 333.448796 -269.838368)
						(end 333.375254 -269.852902)
					)
					(xy 333.374492 -269.852902)
					(arc
						(start 333.353918 -269.852902)
						(mid 333.340094 -269.857893)
						(end 333.328264 -269.866618)
					)
				)
			)
		)
		(zone
			(layer "F.Cu")
			(hatch none 0.5)
			(connect_pads
				(clearance 0)
			)
			(min_thickness 0.25)
			(keepout
				(tracks not_allowed)
				(vias allowed)
				(pads allowed)
				(copperpour not_allowed)
				(footprints allowed)
			)
			(placement
				(enabled no)
				(sheetname "")
			)
			(fill
				(thermal_gap 0.5)
				(thermal_bridge_width 0.5)
				(island_removal_mode 0)
			)
			(polygon
				(pts
					(arc
						(start 333.328264 -268.238986)
						(mid 333.31325 -268.274964)
						(end 333.328264 -268.310868)
					)
					(arc
						(start 333.328264 -268.310868)
						(mid 333.345417 -268.322079)
						(end 333.365602 -268.3256)
					)
					(arc
						(start 333.365602 -268.3256)
						(mid 333.482803 -268.305451)
						(end 333.582264 -268.240256)
					)
					(arc
						(start 333.582264 -268.240256)
						(mid 333.6678 -268.033754)
						(end 333.582264 -267.827252)
					)
					(arc
						(start 333.582264 -267.827252)
						(mid 333.48402 -267.76237)
						(end 333.368142 -267.741654)
					)
					(arc
						(start 333.368142 -267.741654)
						(mid 333.346952 -267.744906)
						(end 333.329026 -267.75664)
					)
					(arc
						(start 333.329026 -267.75664)
						(mid 333.314086 -267.792618)
						(end 333.329026 -267.828522)
					)
					(arc
						(start 333.329026 -267.828522)
						(mid 333.340847 -267.837264)
						(end 333.35468 -267.842238)
					)
					(xy 333.375508 -267.842238) (xy 333.376016 -267.842238)
					(arc
						(start 333.377032 -267.842238)
						(mid 333.449601 -267.857123)
						(end 333.511144 -267.898372)
					)
					(arc
						(start 333.511144 -267.898372)
						(mid 333.567221 -268.033754)
						(end 333.511144 -268.169136)
					)
					(arc
						(start 333.511144 -268.169136)
						(mid 333.448796 -268.210736)
						(end 333.375254 -268.22527)
					)
					(xy 333.374492 -268.225016)
					(arc
						(start 333.353918 -268.225016)
						(mid 333.340056 -268.230106)
						(end 333.328264 -268.238986)
					)
				)
			)
		)
		(zone
			(layer "F.Cu")
			(hatch none 0.5)
			(connect_pads
				(clearance 0)
			)
			(min_thickness 0.25)
			(keepout
				(tracks not_allowed)
				(vias allowed)
				(pads allowed)
				(copperpour not_allowed)
				(footprints allowed)
			)
			(placement
				(enabled no)
				(sheetname "")
			)
			(fill
				(thermal_gap 0.5)
				(thermal_bridge_width 0.5)
				(island_removal_mode 0)
			)
			(polygon
				(pts
					(arc
						(start 333.377286 -249.520964)
						(mid 333.392075 -249.556795)
						(end 333.427832 -249.571764)
					)
					(arc
						(start 333.427832 -249.571764)
						(mid 333.448016 -249.567582)
						(end 333.464916 -249.555762)
					)
					(arc
						(start 333.464916 -249.555762)
						(mid 333.533587 -249.458619)
						(end 333.55788 -249.342148)
					)
					(arc
						(start 333.55788 -249.342148)
						(mid 333.472326 -249.135602)
						(end 333.26578 -249.050048)
					)
					(arc
						(start 333.26578 -249.050048)
						(mid 333.150523 -249.073749)
						(end 333.053944 -249.14098)
					)
					(arc
						(start 333.053944 -249.14098)
						(mid 333.041375 -249.158208)
						(end 333.036926 -249.17908)
					)
					(arc
						(start 333.036926 -249.17908)
						(mid 333.051805 -249.215001)
						(end 333.087726 -249.22988)
					)
					(arc
						(start 333.087726 -249.22988)
						(mid 333.10218 -249.227705)
						(end 333.115412 -249.221498)
					)
					(xy 333.130144 -249.206766) (xy 333.130398 -249.206512)
					(arc
						(start 333.13116 -249.20575)
						(mid 333.193037 -249.164906)
						(end 333.26578 -249.150632)
					)
					(arc
						(start 333.26578 -249.150632)
						(mid 333.401202 -249.206726)
						(end 333.457296 -249.342148)
					)
					(arc
						(start 333.457296 -249.342148)
						(mid 333.44258 -249.41577)
						(end 333.400654 -249.478038)
					)
					(xy 333.400146 -249.478292)
					(arc
						(start 333.385668 -249.49277)
						(mid 333.379395 -249.506248)
						(end 333.377286 -249.520964)
					)
				)
			)
		)
		(zone
			(layer "F.Cu")
			(hatch none 0.5)
			(connect_pads
				(clearance 0)
			)
			(min_thickness 0.25)
			(keepout
				(tracks not_allowed)
				(vias allowed)
				(pads allowed)
				(copperpour not_allowed)
				(footprints allowed)
			)
			(placement
				(enabled no)
				(sheetname "")
			)
			(fill
				(thermal_gap 0.5)
				(thermal_bridge_width 0.5)
				(island_removal_mode 0)
			)
			(polygon
				(pts
					(arc
						(start 333.487268 -286.1183)
						(mid 333.502147 -286.154221)
						(end 333.538068 -286.1691)
					)
					(arc
						(start 333.538068 -286.1691)
						(mid 333.558115 -286.164868)
						(end 333.574898 -286.153098)
					)
					(arc
						(start 333.574898 -286.153098)
						(mid 333.643569 -286.055955)
						(end 333.667862 -285.939484)
					)
					(arc
						(start 333.667862 -285.939484)
						(mid 333.582308 -285.732938)
						(end 333.375762 -285.647384)
					)
					(arc
						(start 333.375762 -285.647384)
						(mid 333.260505 -285.671085)
						(end 333.163926 -285.738316)
					)
					(arc
						(start 333.163926 -285.738316)
						(mid 333.151357 -285.755544)
						(end 333.146908 -285.776416)
					)
					(arc
						(start 333.146908 -285.776416)
						(mid 333.161787 -285.812337)
						(end 333.197708 -285.827216)
					)
					(arc
						(start 333.197708 -285.827216)
						(mid 333.212162 -285.825041)
						(end 333.225394 -285.818834)
					)
					(xy 333.240126 -285.804102) (xy 333.24038 -285.803848)
					(arc
						(start 333.241142 -285.803086)
						(mid 333.303019 -285.762242)
						(end 333.375762 -285.747968)
					)
					(arc
						(start 333.375762 -285.747968)
						(mid 333.511184 -285.804062)
						(end 333.567278 -285.939484)
					)
					(arc
						(start 333.567278 -285.939484)
						(mid 333.552562 -286.013106)
						(end 333.510636 -286.075374)
					)
					(xy 333.510128 -286.075628)
					(arc
						(start 333.49565 -286.090106)
						(mid 333.489377 -286.103584)
						(end 333.487268 -286.1183)
					)
				)
			)
		)
		(zone
			(layer "F.Cu")
			(hatch none 0.5)
			(connect_pads
				(clearance 0)
			)
			(min_thickness 0.25)
			(keepout
				(tracks not_allowed)
				(vias allowed)
				(pads allowed)
				(copperpour not_allowed)
				(footprints allowed)
			)
			(placement
				(enabled no)
				(sheetname "")
			)
			(fill
				(thermal_gap 0.5)
				(thermal_bridge_width 0.5)
				(island_removal_mode 0)
			)
			(polygon
				(pts
					(arc
						(start 333.487268 -284.490414)
						(mid 333.502147 -284.526335)
						(end 333.538068 -284.541214)
					)
					(arc
						(start 333.538068 -284.541214)
						(mid 333.558115 -284.536982)
						(end 333.574898 -284.525212)
					)
					(arc
						(start 333.574898 -284.525212)
						(mid 333.643627 -284.428085)
						(end 333.667862 -284.311598)
					)
					(arc
						(start 333.667862 -284.311598)
						(mid 333.582308 -284.105052)
						(end 333.375762 -284.019498)
					)
					(arc
						(start 333.375762 -284.019498)
						(mid 333.260477 -284.04332)
						(end 333.163926 -284.110684)
					)
					(arc
						(start 333.163926 -284.110684)
						(mid 333.151408 -284.127796)
						(end 333.146908 -284.14853)
					)
					(arc
						(start 333.146908 -284.14853)
						(mid 333.161697 -284.184616)
						(end 333.197708 -284.199584)
					)
					(arc
						(start 333.197708 -284.199584)
						(mid 333.212198 -284.197322)
						(end 333.225394 -284.190948)
					)
					(xy 333.240126 -284.17647) (xy 333.24038 -284.175962)
					(arc
						(start 333.241142 -284.1752)
						(mid 333.303019 -284.134356)
						(end 333.375762 -284.120082)
					)
					(arc
						(start 333.375762 -284.120082)
						(mid 333.511184 -284.176176)
						(end 333.567278 -284.311598)
					)
					(arc
						(start 333.567278 -284.311598)
						(mid 333.552562 -284.38522)
						(end 333.510636 -284.447488)
					)
					(xy 333.510128 -284.447996)
					(arc
						(start 333.49565 -284.462474)
						(mid 333.489414 -284.47583)
						(end 333.487268 -284.490414)
					)
				)
			)
		)
		(zone
			(layer "F.Cu")
			(hatch none 0.5)
			(connect_pads
				(clearance 0)
			)
			(min_thickness 0.25)
			(keepout
				(tracks not_allowed)
				(vias allowed)
				(pads allowed)
				(copperpour not_allowed)
				(footprints allowed)
			)
			(placement
				(enabled no)
				(sheetname "")
			)
			(fill
				(thermal_gap 0.5)
				(thermal_bridge_width 0.5)
				(island_removal_mode 0)
			)
			(polygon
				(pts
					(arc
						(start 333.487268 -282.862782)
						(mid 333.502147 -282.898703)
						(end 333.538068 -282.913582)
					)
					(arc
						(start 333.538068 -282.913582)
						(mid 333.558115 -282.90935)
						(end 333.574898 -282.89758)
					)
					(arc
						(start 333.574898 -282.89758)
						(mid 333.643569 -282.800437)
						(end 333.667862 -282.683966)
					)
					(arc
						(start 333.667862 -282.683966)
						(mid 333.582308 -282.47742)
						(end 333.375762 -282.391866)
					)
					(arc
						(start 333.375762 -282.391866)
						(mid 333.260505 -282.415567)
						(end 333.163926 -282.482798)
					)
					(arc
						(start 333.163926 -282.482798)
						(mid 333.151357 -282.500026)
						(end 333.146908 -282.520898)
					)
					(arc
						(start 333.146908 -282.520898)
						(mid 333.161787 -282.556819)
						(end 333.197708 -282.571698)
					)
					(arc
						(start 333.197708 -282.571698)
						(mid 333.212162 -282.569523)
						(end 333.225394 -282.563316)
					)
					(xy 333.240126 -282.548584) (xy 333.24038 -282.54833)
					(arc
						(start 333.241142 -282.547568)
						(mid 333.303019 -282.506724)
						(end 333.375762 -282.49245)
					)
					(arc
						(start 333.375762 -282.49245)
						(mid 333.511184 -282.548544)
						(end 333.567278 -282.683966)
					)
					(arc
						(start 333.567278 -282.683966)
						(mid 333.552562 -282.757588)
						(end 333.510636 -282.819856)
					)
					(xy 333.510128 -282.82011)
					(arc
						(start 333.49565 -282.834588)
						(mid 333.489377 -282.848066)
						(end 333.487268 -282.862782)
					)
				)
			)
		)
		(zone
			(layer "F.Cu")
			(hatch none 0.5)
			(connect_pads
				(clearance 0)
			)
			(min_thickness 0.25)
			(keepout
				(tracks not_allowed)
				(vias allowed)
				(pads allowed)
				(copperpour not_allowed)
				(footprints allowed)
			)
			(placement
				(enabled no)
				(sheetname "")
			)
			(fill
				(thermal_gap 0.5)
				(thermal_bridge_width 0.5)
				(island_removal_mode 0)
			)
			(polygon
				(pts
					(arc
						(start 333.557118 -219.339668)
						(mid 333.521197 -219.354547)
						(end 333.506318 -219.390468)
					)
					(arc
						(start 333.506318 -219.390468)
						(mid 333.510429 -219.410487)
						(end 333.522066 -219.427298)
					)
					(arc
						(start 333.522066 -219.427298)
						(mid 333.619326 -219.49602)
						(end 333.735934 -219.520262)
					)
					(arc
						(start 333.735934 -219.520262)
						(mid 333.94248 -219.434708)
						(end 334.028034 -219.228162)
					)
					(arc
						(start 334.028034 -219.228162)
						(mid 334.004263 -219.11274)
						(end 333.936848 -219.016072)
					)
					(arc
						(start 333.936848 -219.016072)
						(mid 333.91962 -219.003503)
						(end 333.898748 -218.999054)
					)
					(arc
						(start 333.898748 -218.999054)
						(mid 333.862827 -219.013933)
						(end 333.847948 -219.049854)
					)
					(arc
						(start 333.847948 -219.049854)
						(mid 333.850087 -219.06444)
						(end 333.85633 -219.077794)
					)
					(xy 333.871062 -219.092526) (xy 333.871316 -219.09278)
					(arc
						(start 333.872078 -219.093542)
						(mid 333.913057 -219.15539)
						(end 333.92745 -219.228162)
					)
					(arc
						(start 333.92745 -219.228162)
						(mid 333.871356 -219.363584)
						(end 333.735934 -219.419678)
					)
					(arc
						(start 333.735934 -219.419678)
						(mid 333.662312 -219.404962)
						(end 333.600044 -219.363036)
					)
					(xy 333.599536 -219.362528)
					(arc
						(start 333.585058 -219.34805)
						(mid 333.571702 -219.341814)
						(end 333.557118 -219.339668)
					)
				)
			)
		)
		(zone
			(layer "F.Cu")
			(hatch none 0.5)
			(connect_pads
				(clearance 0)
			)
			(min_thickness 0.25)
			(keepout
				(tracks not_allowed)
				(vias allowed)
				(pads allowed)
				(copperpour not_allowed)
				(footprints allowed)
			)
			(placement
				(enabled no)
				(sheetname "")
			)
			(fill
				(thermal_gap 0.5)
				(thermal_bridge_width 0.5)
				(island_removal_mode 0)
			)
			(polygon
				(pts
					(arc
						(start 333.557118 -217.711782)
						(mid 333.521197 -217.726661)
						(end 333.506318 -217.762582)
					)
					(arc
						(start 333.506318 -217.762582)
						(mid 333.510429 -217.782601)
						(end 333.522066 -217.799412)
					)
					(arc
						(start 333.522066 -217.799412)
						(mid 333.619326 -217.868134)
						(end 333.735934 -217.892376)
					)
					(arc
						(start 333.735934 -217.892376)
						(mid 333.94248 -217.806822)
						(end 334.028034 -217.600276)
					)
					(arc
						(start 334.028034 -217.600276)
						(mid 334.004212 -217.484991)
						(end 333.936848 -217.38844)
					)
					(arc
						(start 333.936848 -217.38844)
						(mid 333.91962 -217.375871)
						(end 333.898748 -217.371422)
					)
					(arc
						(start 333.898748 -217.371422)
						(mid 333.862827 -217.386301)
						(end 333.847948 -217.422222)
					)
					(arc
						(start 333.847948 -217.422222)
						(mid 333.850123 -217.436676)
						(end 333.85633 -217.449908)
					)
					(xy 333.871062 -217.46464) (xy 333.871316 -217.464894)
					(arc
						(start 333.872078 -217.465656)
						(mid 333.913057 -217.527504)
						(end 333.92745 -217.600276)
					)
					(arc
						(start 333.92745 -217.600276)
						(mid 333.871356 -217.735698)
						(end 333.735934 -217.791792)
					)
					(arc
						(start 333.735934 -217.791792)
						(mid 333.662341 -217.777194)
						(end 333.600044 -217.735404)
					)
					(xy 333.599536 -217.734642)
					(arc
						(start 333.585058 -217.720164)
						(mid 333.571702 -217.713928)
						(end 333.557118 -217.711782)
					)
				)
			)
		)
		(zone
			(layer "F.Cu")
			(hatch none 0.5)
			(connect_pads
				(clearance 0)
			)
			(min_thickness 0.25)
			(keepout
				(tracks not_allowed)
				(vias allowed)
				(pads allowed)
				(copperpour not_allowed)
				(footprints allowed)
			)
			(placement
				(enabled no)
				(sheetname "")
			)
			(fill
				(thermal_gap 0.5)
				(thermal_bridge_width 0.5)
				(island_removal_mode 0)
			)
			(polygon
				(pts
					(arc
						(start 333.666846 -254.309118)
						(mid 333.631015 -254.323907)
						(end 333.616046 -254.359664)
					)
					(arc
						(start 333.616046 -254.359664)
						(mid 333.620228 -254.379848)
						(end 333.632048 -254.396748)
					)
					(arc
						(start 333.632048 -254.396748)
						(mid 333.729191 -254.465419)
						(end 333.845662 -254.489712)
					)
					(arc
						(start 333.845662 -254.489712)
						(mid 334.052208 -254.404158)
						(end 334.137762 -254.197612)
					)
					(arc
						(start 334.137762 -254.197612)
						(mid 334.114061 -254.082355)
						(end 334.04683 -253.985776)
					)
					(arc
						(start 334.04683 -253.985776)
						(mid 334.029602 -253.973207)
						(end 334.00873 -253.968758)
					)
					(arc
						(start 334.00873 -253.968758)
						(mid 333.972809 -253.983637)
						(end 333.95793 -254.019558)
					)
					(arc
						(start 333.95793 -254.019558)
						(mid 333.960105 -254.034012)
						(end 333.966312 -254.047244)
					)
					(xy 333.981044 -254.061976) (xy 333.981298 -254.06223)
					(arc
						(start 333.98206 -254.062992)
						(mid 334.022904 -254.124869)
						(end 334.037178 -254.197612)
					)
					(arc
						(start 334.037178 -254.197612)
						(mid 333.981084 -254.333034)
						(end 333.845662 -254.389128)
					)
					(arc
						(start 333.845662 -254.389128)
						(mid 333.77204 -254.374412)
						(end 333.709772 -254.332486)
					)
					(xy 333.709518 -254.331978)
					(arc
						(start 333.69504 -254.3175)
						(mid 333.681562 -254.311227)
						(end 333.666846 -254.309118)
					)
				)
			)
		)
		(zone
			(layer "F.Cu")
			(hatch none 0.5)
			(connect_pads
				(clearance 0)
			)
			(min_thickness 0.25)
			(keepout
				(tracks not_allowed)
				(vias allowed)
				(pads allowed)
				(copperpour not_allowed)
				(footprints allowed)
			)
			(placement
				(enabled no)
				(sheetname "")
			)
			(fill
				(thermal_gap 0.5)
				(thermal_bridge_width 0.5)
				(island_removal_mode 0)
			)
			(polygon
				(pts
					(arc
						(start 333.690722 -221.06128)
						(mid 333.676215 -221.097288)
						(end 333.69123 -221.133162)
					)
					(arc
						(start 333.69123 -221.133162)
						(mid 333.708501 -221.144419)
						(end 333.728822 -221.147894)
					)
					(arc
						(start 333.728822 -221.147894)
						(mid 333.845968 -221.12667)
						(end 333.944976 -221.060518)
					)
					(arc
						(start 333.944976 -221.060518)
						(mid 334.028734 -220.85328)
						(end 333.94142 -220.647514)
					)
					(arc
						(start 333.94142 -220.647514)
						(mid 333.84234 -220.583522)
						(end 333.726028 -220.563948)
					)
					(arc
						(start 333.726028 -220.563948)
						(mid 333.705246 -220.56751)
						(end 333.687674 -220.579188)
					)
					(arc
						(start 333.687674 -220.579188)
						(mid 333.673093 -220.615107)
						(end 333.688182 -220.650816)
					)
					(arc
						(start 333.688182 -220.650816)
						(mid 333.700003 -220.659558)
						(end 333.713836 -220.664532)
					)
					(xy 333.734664 -220.664278) (xy 333.734918 -220.664278)
					(arc
						(start 333.735934 -220.664278)
						(mid 333.808764 -220.678437)
						(end 333.870808 -220.719142)
					)
					(arc
						(start 333.870808 -220.719142)
						(mid 333.928157 -220.854178)
						(end 333.873094 -220.99016)
					)
					(arc
						(start 333.873094 -220.99016)
						(mid 333.810981 -221.03226)
						(end 333.737458 -221.04731)
					)
					(xy 333.73695 -221.047056)
					(arc
						(start 333.716376 -221.04731)
						(mid 333.702514 -221.0524)
						(end 333.690722 -221.06128)
					)
				)
			)
		)
		(zone
			(layer "F.Cu")
			(hatch none 0.5)
			(connect_pads
				(clearance 0)
			)
			(min_thickness 0.25)
			(keepout
				(tracks not_allowed)
				(vias allowed)
				(pads allowed)
				(copperpour not_allowed)
				(footprints allowed)
			)
			(placement
				(enabled no)
				(sheetname "")
			)
			(fill
				(thermal_gap 0.5)
				(thermal_bridge_width 0.5)
				(island_removal_mode 0)
			)
			(polygon
				(pts
					(arc
						(start 333.847186 -250.33478)
						(mid 333.862065 -250.370701)
						(end 333.897986 -250.38558)
					)
					(arc
						(start 333.897986 -250.38558)
						(mid 333.91817 -250.381398)
						(end 333.93507 -250.369578)
					)
					(arc
						(start 333.93507 -250.369578)
						(mid 334.003656 -250.272419)
						(end 334.02778 -250.155964)
					)
					(arc
						(start 334.02778 -250.155964)
						(mid 333.942316 -249.949508)
						(end 333.735934 -249.863864)
					)
					(arc
						(start 333.735934 -249.863864)
						(mid 333.620512 -249.887635)
						(end 333.523844 -249.95505)
					)
					(arc
						(start 333.523844 -249.95505)
						(mid 333.511326 -249.972162)
						(end 333.506826 -249.992896)
					)
					(arc
						(start 333.506826 -249.992896)
						(mid 333.521615 -250.028982)
						(end 333.557626 -250.04395)
					)
					(arc
						(start 333.557626 -250.04395)
						(mid 333.572248 -250.041724)
						(end 333.585566 -250.035314)
					)
					(xy 333.600044 -250.020836) (xy 333.600552 -250.020328)
					(arc
						(start 333.60106 -250.019566)
						(mid 333.663054 -249.978674)
						(end 333.735934 -249.964448)
					)
					(arc
						(start 333.735934 -249.964448)
						(mid 333.871356 -250.020542)
						(end 333.92745 -250.155964)
					)
					(arc
						(start 333.92745 -250.155964)
						(mid 333.912651 -250.229532)
						(end 333.870808 -250.291854)
					)
					(xy 333.870046 -250.292362)
					(arc
						(start 333.855568 -250.30684)
						(mid 333.849332 -250.320196)
						(end 333.847186 -250.33478)
					)
				)
			)
		)
		(zone
			(layer "F.Cu")
			(hatch none 0.5)
			(connect_pads
				(clearance 0)
			)
			(min_thickness 0.25)
			(keepout
				(tracks not_allowed)
				(vias allowed)
				(pads allowed)
				(copperpour not_allowed)
				(footprints allowed)
			)
			(placement
				(enabled no)
				(sheetname "")
			)
			(fill
				(thermal_gap 0.5)
				(thermal_bridge_width 0.5)
				(island_removal_mode 0)
			)
			(polygon
				(pts
					(arc
						(start 333.957168 -286.932116)
						(mid 333.972047 -286.968037)
						(end 334.007968 -286.982916)
					)
					(arc
						(start 334.007968 -286.982916)
						(mid 334.028015 -286.978684)
						(end 334.044798 -286.966914)
					)
					(arc
						(start 334.044798 -286.966914)
						(mid 334.113527 -286.869787)
						(end 334.137762 -286.7533)
					)
					(arc
						(start 334.137762 -286.7533)
						(mid 334.052208 -286.546754)
						(end 333.845662 -286.4612)
					)
					(arc
						(start 333.845662 -286.4612)
						(mid 333.730377 -286.485022)
						(end 333.633826 -286.552386)
					)
					(arc
						(start 333.633826 -286.552386)
						(mid 333.621308 -286.569498)
						(end 333.616808 -286.590232)
					)
					(arc
						(start 333.616808 -286.590232)
						(mid 333.631597 -286.626318)
						(end 333.667608 -286.641286)
					)
					(arc
						(start 333.667608 -286.641286)
						(mid 333.682098 -286.639024)
						(end 333.695294 -286.63265)
					)
					(xy 333.710026 -286.618172) (xy 333.71028 -286.617664)
					(arc
						(start 333.711042 -286.616902)
						(mid 333.772919 -286.576058)
						(end 333.845662 -286.561784)
					)
					(arc
						(start 333.845662 -286.561784)
						(mid 333.981084 -286.617878)
						(end 334.037178 -286.7533)
					)
					(arc
						(start 334.037178 -286.7533)
						(mid 334.022462 -286.826922)
						(end 333.980536 -286.88919)
					)
					(xy 333.980028 -286.889698)
					(arc
						(start 333.96555 -286.904176)
						(mid 333.959314 -286.917532)
						(end 333.957168 -286.932116)
					)
				)
			)
		)
		(zone
			(layer "F.Cu")
			(hatch none 0.5)
			(connect_pads
				(clearance 0)
			)
			(min_thickness 0.25)
			(keepout
				(tracks not_allowed)
				(vias allowed)
				(pads allowed)
				(copperpour not_allowed)
				(footprints allowed)
			)
			(placement
				(enabled no)
				(sheetname "")
			)
			(fill
				(thermal_gap 0.5)
				(thermal_bridge_width 0.5)
				(island_removal_mode 0)
			)
			(polygon
				(pts
					(arc
						(start 333.957168 -285.30423)
						(mid 333.972047 -285.340151)
						(end 334.007968 -285.35503)
					)
					(arc
						(start 334.007968 -285.35503)
						(mid 334.027987 -285.350919)
						(end 334.044798 -285.339282)
					)
					(arc
						(start 334.044798 -285.339282)
						(mid 334.11352 -285.242022)
						(end 334.137762 -285.125414)
					)
					(arc
						(start 334.137762 -285.125414)
						(mid 334.052118 -284.919032)
						(end 333.845662 -284.833568)
					)
					(arc
						(start 333.845662 -284.833568)
						(mid 333.730421 -284.857284)
						(end 333.633826 -284.9245)
					)
					(arc
						(start 333.633826 -284.9245)
						(mid 333.621257 -284.941728)
						(end 333.616808 -284.9626)
					)
					(arc
						(start 333.616808 -284.9626)
						(mid 333.631687 -284.998521)
						(end 333.667608 -285.0134)
					)
					(arc
						(start 333.667608 -285.0134)
						(mid 333.682092 -285.011128)
						(end 333.695294 -285.004764)
					)
					(xy 333.710026 -284.990286) (xy 333.71028 -284.989778)
					(arc
						(start 333.711042 -284.98927)
						(mid 333.77289 -284.948291)
						(end 333.845662 -284.933898)
					)
					(arc
						(start 333.845662 -284.933898)
						(mid 333.981084 -284.989992)
						(end 334.037178 -285.125414)
					)
					(arc
						(start 334.037178 -285.125414)
						(mid 334.022462 -285.199036)
						(end 333.980536 -285.261304)
					)
					(xy 333.980028 -285.261812)
					(arc
						(start 333.96555 -285.27629)
						(mid 333.959314 -285.289646)
						(end 333.957168 -285.30423)
					)
				)
			)
		)
		(zone
			(layer "F.Cu")
			(hatch none 0.5)
			(connect_pads
				(clearance 0)
			)
			(min_thickness 0.25)
			(keepout
				(tracks not_allowed)
				(vias allowed)
				(pads allowed)
				(copperpour not_allowed)
				(footprints allowed)
			)
			(placement
				(enabled no)
				(sheetname "")
			)
			(fill
				(thermal_gap 0.5)
				(thermal_bridge_width 0.5)
				(island_removal_mode 0)
			)
			(polygon
				(pts
					(arc
						(start 333.957168 -283.676598)
						(mid 333.972047 -283.712519)
						(end 334.007968 -283.727398)
					)
					(arc
						(start 334.007968 -283.727398)
						(mid 334.028015 -283.723166)
						(end 334.044798 -283.711396)
					)
					(arc
						(start 334.044798 -283.711396)
						(mid 334.113469 -283.614253)
						(end 334.137762 -283.497782)
					)
					(arc
						(start 334.137762 -283.497782)
						(mid 334.052208 -283.291236)
						(end 333.845662 -283.205682)
					)
					(arc
						(start 333.845662 -283.205682)
						(mid 333.730405 -283.229383)
						(end 333.633826 -283.296614)
					)
					(arc
						(start 333.633826 -283.296614)
						(mid 333.621257 -283.313842)
						(end 333.616808 -283.334714)
					)
					(arc
						(start 333.616808 -283.334714)
						(mid 333.631687 -283.370635)
						(end 333.667608 -283.385514)
					)
					(arc
						(start 333.667608 -283.385514)
						(mid 333.682062 -283.383339)
						(end 333.695294 -283.377132)
					)
					(xy 333.710026 -283.3624) (xy 333.71028 -283.362146)
					(arc
						(start 333.711042 -283.361384)
						(mid 333.772919 -283.32054)
						(end 333.845662 -283.306266)
					)
					(arc
						(start 333.845662 -283.306266)
						(mid 333.981084 -283.36236)
						(end 334.037178 -283.497782)
					)
					(arc
						(start 334.037178 -283.497782)
						(mid 334.022462 -283.571404)
						(end 333.980536 -283.633672)
					)
					(xy 333.980028 -283.633926)
					(arc
						(start 333.96555 -283.648404)
						(mid 333.959277 -283.661882)
						(end 333.957168 -283.676598)
					)
				)
			)
		)
		(zone
			(layer "F.Cu")
			(hatch none 0.5)
			(connect_pads
				(clearance 0)
			)
			(min_thickness 0.25)
			(keepout
				(tracks not_allowed)
				(vias allowed)
				(pads allowed)
				(copperpour not_allowed)
				(footprints allowed)
			)
			(placement
				(enabled no)
				(sheetname "")
			)
			(fill
				(thermal_gap 0.5)
				(thermal_bridge_width 0.5)
				(island_removal_mode 0)
			)
			(polygon
				(pts
					(arc
						(start 334.027018 -220.153484)
						(mid 333.991097 -220.168363)
						(end 333.976218 -220.204284)
					)
					(arc
						(start 333.976218 -220.204284)
						(mid 333.980329 -220.224303)
						(end 333.991966 -220.241114)
					)
					(arc
						(start 333.991966 -220.241114)
						(mid 334.089226 -220.309836)
						(end 334.205834 -220.334078)
					)
					(arc
						(start 334.205834 -220.334078)
						(mid 334.41238 -220.248524)
						(end 334.497934 -220.041978)
					)
					(arc
						(start 334.497934 -220.041978)
						(mid 334.474112 -219.926693)
						(end 334.406748 -219.830142)
					)
					(arc
						(start 334.406748 -219.830142)
						(mid 334.38952 -219.817573)
						(end 334.368648 -219.813124)
					)
					(arc
						(start 334.368648 -219.813124)
						(mid 334.332727 -219.828003)
						(end 334.317848 -219.863924)
					)
					(arc
						(start 334.317848 -219.863924)
						(mid 334.320023 -219.878378)
						(end 334.32623 -219.89161)
					)
					(xy 334.340962 -219.906342) (xy 334.341216 -219.906596)
					(arc
						(start 334.341978 -219.907358)
						(mid 334.382957 -219.969206)
						(end 334.39735 -220.041978)
					)
					(arc
						(start 334.39735 -220.041978)
						(mid 334.341256 -220.1774)
						(end 334.205834 -220.233494)
					)
					(arc
						(start 334.205834 -220.233494)
						(mid 334.132241 -220.218896)
						(end 334.069944 -220.177106)
					)
					(xy 334.069436 -220.176344)
					(arc
						(start 334.054958 -220.161866)
						(mid 334.041602 -220.15563)
						(end 334.027018 -220.153484)
					)
				)
			)
		)
		(zone
			(layer "F.Cu")
			(hatch none 0.5)
			(connect_pads
				(clearance 0)
			)
			(min_thickness 0.25)
			(keepout
				(tracks not_allowed)
				(vias allowed)
				(pads allowed)
				(copperpour not_allowed)
				(footprints allowed)
			)
			(placement
				(enabled no)
				(sheetname "")
			)
			(fill
				(thermal_gap 0.5)
				(thermal_bridge_width 0.5)
				(island_removal_mode 0)
			)
			(polygon
				(pts
					(arc
						(start 334.027018 -218.525598)
						(mid 333.991097 -218.540477)
						(end 333.976218 -218.576398)
					)
					(arc
						(start 333.976218 -218.576398)
						(mid 333.980278 -218.596555)
						(end 333.991966 -218.613482)
					)
					(arc
						(start 333.991966 -218.613482)
						(mid 334.089226 -218.682204)
						(end 334.205834 -218.706446)
					)
					(arc
						(start 334.205834 -218.706446)
						(mid 334.41238 -218.620892)
						(end 334.497934 -218.414346)
					)
					(arc
						(start 334.497934 -218.414346)
						(mid 334.474163 -218.298924)
						(end 334.406748 -218.202256)
					)
					(arc
						(start 334.406748 -218.202256)
						(mid 334.38952 -218.189687)
						(end 334.368648 -218.185238)
					)
					(arc
						(start 334.368648 -218.185238)
						(mid 334.332727 -218.200117)
						(end 334.317848 -218.236038)
					)
					(arc
						(start 334.317848 -218.236038)
						(mid 334.319987 -218.250624)
						(end 334.32623 -218.263978)
					)
					(xy 334.340962 -218.278456) (xy 334.341216 -218.278964)
					(arc
						(start 334.341978 -218.279472)
						(mid 334.383005 -218.341437)
						(end 334.39735 -218.414346)
					)
					(arc
						(start 334.39735 -218.414346)
						(mid 334.341256 -218.549768)
						(end 334.205834 -218.605862)
					)
					(arc
						(start 334.205834 -218.605862)
						(mid 334.132212 -218.591146)
						(end 334.069944 -218.54922)
					)
					(xy 334.069436 -218.548458)
					(arc
						(start 334.054958 -218.53398)
						(mid 334.041602 -218.527744)
						(end 334.027018 -218.525598)
					)
				)
			)
		)
		(zone
			(layer "F.Cu")
			(hatch none 0.5)
			(connect_pads
				(clearance 0)
			)
			(min_thickness 0.25)
			(keepout
				(tracks not_allowed)
				(vias allowed)
				(pads allowed)
				(copperpour not_allowed)
				(footprints allowed)
			)
			(placement
				(enabled no)
				(sheetname "")
			)
			(fill
				(thermal_gap 0.5)
				(thermal_bridge_width 0.5)
				(island_removal_mode 0)
			)
			(polygon
				(pts
					(arc
						(start 334.027018 -216.897966)
						(mid 333.991097 -216.912845)
						(end 333.976218 -216.948766)
					)
					(arc
						(start 333.976218 -216.948766)
						(mid 333.980329 -216.968785)
						(end 333.991966 -216.985596)
					)
					(arc
						(start 333.991966 -216.985596)
						(mid 334.089226 -217.054318)
						(end 334.205834 -217.07856)
					)
					(arc
						(start 334.205834 -217.07856)
						(mid 334.41238 -216.993006)
						(end 334.497934 -216.78646)
					)
					(arc
						(start 334.497934 -216.78646)
						(mid 334.474163 -216.671038)
						(end 334.406748 -216.57437)
					)
					(arc
						(start 334.406748 -216.57437)
						(mid 334.389486 -216.561949)
						(end 334.368648 -216.557606)
					)
					(arc
						(start 334.368648 -216.557606)
						(mid 334.332727 -216.572485)
						(end 334.317848 -216.608406)
					)
					(arc
						(start 334.317848 -216.608406)
						(mid 334.320023 -216.62286)
						(end 334.32623 -216.636092)
					)
					(xy 334.340962 -216.650824) (xy 334.341216 -216.651078)
					(arc
						(start 334.341978 -216.65184)
						(mid 334.382957 -216.713688)
						(end 334.39735 -216.78646)
					)
					(arc
						(start 334.39735 -216.78646)
						(mid 334.341256 -216.921882)
						(end 334.205834 -216.977976)
					)
					(arc
						(start 334.205834 -216.977976)
						(mid 334.132212 -216.96326)
						(end 334.069944 -216.921334)
					)
					(xy 334.069436 -216.920826)
					(arc
						(start 334.054958 -216.906348)
						(mid 334.041602 -216.900112)
						(end 334.027018 -216.897966)
					)
				)
			)
		)
		(zone
			(layer "F.Cu")
			(hatch none 0.5)
			(connect_pads
				(clearance 0)
			)
			(min_thickness 0.25)
			(keepout
				(tracks not_allowed)
				(vias allowed)
				(pads allowed)
				(copperpour not_allowed)
				(footprints allowed)
			)
			(placement
				(enabled no)
				(sheetname "")
			)
			(fill
				(thermal_gap 0.5)
				(thermal_bridge_width 0.5)
				(island_removal_mode 0)
			)
			(polygon
				(pts
					(arc
						(start 334.136746 -253.495302)
						(mid 334.100915 -253.510091)
						(end 334.085946 -253.545848)
					)
					(arc
						(start 334.085946 -253.545848)
						(mid 334.090128 -253.566032)
						(end 334.101948 -253.582932)
					)
					(arc
						(start 334.101948 -253.582932)
						(mid 334.199091 -253.651603)
						(end 334.315562 -253.675896)
					)
					(arc
						(start 334.315562 -253.675896)
						(mid 334.522108 -253.590342)
						(end 334.607662 -253.383796)
					)
					(arc
						(start 334.607662 -253.383796)
						(mid 334.584012 -253.268402)
						(end 334.51673 -253.171706)
					)
					(arc
						(start 334.51673 -253.171706)
						(mid 334.499502 -253.159137)
						(end 334.47863 -253.154688)
					)
					(arc
						(start 334.47863 -253.154688)
						(mid 334.442709 -253.169567)
						(end 334.42783 -253.205488)
					)
					(arc
						(start 334.42783 -253.205488)
						(mid 334.429969 -253.220074)
						(end 334.436212 -253.233428)
					)
					(xy 334.450944 -253.247906) (xy 334.451198 -253.248414)
					(arc
						(start 334.45196 -253.249176)
						(mid 334.492804 -253.311053)
						(end 334.507078 -253.383796)
					)
					(arc
						(start 334.507078 -253.383796)
						(mid 334.450984 -253.519218)
						(end 334.315562 -253.575312)
					)
					(arc
						(start 334.315562 -253.575312)
						(mid 334.24194 -253.560596)
						(end 334.179672 -253.51867)
					)
					(xy 334.179418 -253.518162)
					(arc
						(start 334.16494 -253.503684)
						(mid 334.151462 -253.497411)
						(end 334.136746 -253.495302)
					)
				)
			)
		)
		(zone
			(layer "F.Cu")
			(hatch none 0.5)
			(connect_pads
				(clearance 0)
			)
			(min_thickness 0.25)
			(keepout
				(tracks not_allowed)
				(vias allowed)
				(pads allowed)
				(copperpour not_allowed)
				(footprints allowed)
			)
			(placement
				(enabled no)
				(sheetname "")
			)
			(fill
				(thermal_gap 0.5)
				(thermal_bridge_width 0.5)
				(island_removal_mode 0)
			)
			(polygon
				(pts
					(arc
						(start 334.427068 -286.1183)
						(mid 334.441947 -286.154221)
						(end 334.477868 -286.1691)
					)
					(arc
						(start 334.477868 -286.1691)
						(mid 334.497915 -286.164868)
						(end 334.514698 -286.153098)
					)
					(arc
						(start 334.514698 -286.153098)
						(mid 334.583369 -286.055955)
						(end 334.607662 -285.939484)
					)
					(arc
						(start 334.607662 -285.939484)
						(mid 334.522108 -285.732938)
						(end 334.315562 -285.647384)
					)
					(arc
						(start 334.315562 -285.647384)
						(mid 334.200305 -285.671085)
						(end 334.103726 -285.738316)
					)
					(arc
						(start 334.103726 -285.738316)
						(mid 334.091157 -285.755544)
						(end 334.086708 -285.776416)
					)
					(arc
						(start 334.086708 -285.776416)
						(mid 334.101587 -285.812337)
						(end 334.137508 -285.827216)
					)
					(arc
						(start 334.137508 -285.827216)
						(mid 334.151962 -285.825041)
						(end 334.165194 -285.818834)
					)
					(xy 334.179926 -285.804102) (xy 334.18018 -285.803848)
					(arc
						(start 334.180942 -285.803086)
						(mid 334.242819 -285.762242)
						(end 334.315562 -285.747968)
					)
					(arc
						(start 334.315562 -285.747968)
						(mid 334.450984 -285.804062)
						(end 334.507078 -285.939484)
					)
					(arc
						(start 334.507078 -285.939484)
						(mid 334.492362 -286.013106)
						(end 334.450436 -286.075374)
					)
					(xy 334.449928 -286.075628)
					(arc
						(start 334.43545 -286.090106)
						(mid 334.429177 -286.103584)
						(end 334.427068 -286.1183)
					)
				)
			)
		)
		(zone
			(layer "F.Cu")
			(hatch none 0.5)
			(connect_pads
				(clearance 0)
			)
			(min_thickness 0.25)
			(keepout
				(tracks not_allowed)
				(vias allowed)
				(pads allowed)
				(copperpour not_allowed)
				(footprints allowed)
			)
			(placement
				(enabled no)
				(sheetname "")
			)
			(fill
				(thermal_gap 0.5)
				(thermal_bridge_width 0.5)
				(island_removal_mode 0)
			)
			(polygon
				(pts
					(arc
						(start 334.427068 -284.490414)
						(mid 334.441947 -284.526335)
						(end 334.477868 -284.541214)
					)
					(arc
						(start 334.477868 -284.541214)
						(mid 334.497915 -284.536982)
						(end 334.514698 -284.525212)
					)
					(arc
						(start 334.514698 -284.525212)
						(mid 334.583427 -284.428085)
						(end 334.607662 -284.311598)
					)
					(arc
						(start 334.607662 -284.311598)
						(mid 334.522108 -284.105052)
						(end 334.315562 -284.019498)
					)
					(arc
						(start 334.315562 -284.019498)
						(mid 334.200277 -284.04332)
						(end 334.103726 -284.110684)
					)
					(arc
						(start 334.103726 -284.110684)
						(mid 334.091208 -284.127796)
						(end 334.086708 -284.14853)
					)
					(arc
						(start 334.086708 -284.14853)
						(mid 334.101497 -284.184616)
						(end 334.137508 -284.199584)
					)
					(arc
						(start 334.137508 -284.199584)
						(mid 334.151998 -284.197322)
						(end 334.165194 -284.190948)
					)
					(xy 334.179926 -284.17647) (xy 334.18018 -284.175962)
					(arc
						(start 334.180942 -284.1752)
						(mid 334.242819 -284.134356)
						(end 334.315562 -284.120082)
					)
					(arc
						(start 334.315562 -284.120082)
						(mid 334.450984 -284.176176)
						(end 334.507078 -284.311598)
					)
					(arc
						(start 334.507078 -284.311598)
						(mid 334.492362 -284.38522)
						(end 334.450436 -284.447488)
					)
					(xy 334.449928 -284.447996)
					(arc
						(start 334.43545 -284.462474)
						(mid 334.429214 -284.47583)
						(end 334.427068 -284.490414)
					)
				)
			)
		)
		(zone
			(layer "F.Cu")
			(hatch none 0.5)
			(connect_pads
				(clearance 0)
			)
			(min_thickness 0.25)
			(keepout
				(tracks not_allowed)
				(vias allowed)
				(pads allowed)
				(copperpour not_allowed)
				(footprints allowed)
			)
			(placement
				(enabled no)
				(sheetname "")
			)
			(fill
				(thermal_gap 0.5)
				(thermal_bridge_width 0.5)
				(island_removal_mode 0)
			)
			(polygon
				(pts
					(arc
						(start 334.496918 -219.339668)
						(mid 334.460997 -219.354547)
						(end 334.446118 -219.390468)
					)
					(arc
						(start 334.446118 -219.390468)
						(mid 334.450229 -219.410487)
						(end 334.461866 -219.427298)
					)
					(arc
						(start 334.461866 -219.427298)
						(mid 334.559126 -219.49602)
						(end 334.675734 -219.520262)
					)
					(arc
						(start 334.675734 -219.520262)
						(mid 334.88228 -219.434708)
						(end 334.967834 -219.228162)
					)
					(arc
						(start 334.967834 -219.228162)
						(mid 334.944063 -219.11274)
						(end 334.876648 -219.016072)
					)
					(arc
						(start 334.876648 -219.016072)
						(mid 334.85942 -219.003503)
						(end 334.838548 -218.999054)
					)
					(arc
						(start 334.838548 -218.999054)
						(mid 334.802627 -219.013933)
						(end 334.787748 -219.049854)
					)
					(arc
						(start 334.787748 -219.049854)
						(mid 334.789887 -219.06444)
						(end 334.79613 -219.077794)
					)
					(xy 334.810862 -219.092526) (xy 334.811116 -219.09278)
					(arc
						(start 334.811878 -219.093542)
						(mid 334.852857 -219.15539)
						(end 334.86725 -219.228162)
					)
					(arc
						(start 334.86725 -219.228162)
						(mid 334.811156 -219.363584)
						(end 334.675734 -219.419678)
					)
					(arc
						(start 334.675734 -219.419678)
						(mid 334.602112 -219.404962)
						(end 334.539844 -219.363036)
					)
					(xy 334.539336 -219.362528)
					(arc
						(start 334.524858 -219.34805)
						(mid 334.511502 -219.341814)
						(end 334.496918 -219.339668)
					)
				)
			)
		)
		(zone
			(layer "F.Cu")
			(hatch none 0.5)
			(connect_pads
				(clearance 0)
			)
			(min_thickness 0.25)
			(keepout
				(tracks not_allowed)
				(vias allowed)
				(pads allowed)
				(copperpour not_allowed)
				(footprints allowed)
			)
			(placement
				(enabled no)
				(sheetname "")
			)
			(fill
				(thermal_gap 0.5)
				(thermal_bridge_width 0.5)
				(island_removal_mode 0)
			)
			(polygon
				(pts
					(arc
						(start 334.496918 -217.711782)
						(mid 334.460997 -217.726661)
						(end 334.446118 -217.762582)
					)
					(arc
						(start 334.446118 -217.762582)
						(mid 334.450229 -217.782601)
						(end 334.461866 -217.799412)
					)
					(arc
						(start 334.461866 -217.799412)
						(mid 334.559126 -217.868134)
						(end 334.675734 -217.892376)
					)
					(arc
						(start 334.675734 -217.892376)
						(mid 334.88228 -217.806822)
						(end 334.967834 -217.600276)
					)
					(arc
						(start 334.967834 -217.600276)
						(mid 334.944012 -217.484991)
						(end 334.876648 -217.38844)
					)
					(arc
						(start 334.876648 -217.38844)
						(mid 334.85942 -217.375871)
						(end 334.838548 -217.371422)
					)
					(arc
						(start 334.838548 -217.371422)
						(mid 334.802627 -217.386301)
						(end 334.787748 -217.422222)
					)
					(arc
						(start 334.787748 -217.422222)
						(mid 334.789923 -217.436676)
						(end 334.79613 -217.449908)
					)
					(xy 334.810862 -217.46464) (xy 334.811116 -217.464894)
					(arc
						(start 334.811878 -217.465656)
						(mid 334.852857 -217.527504)
						(end 334.86725 -217.600276)
					)
					(arc
						(start 334.86725 -217.600276)
						(mid 334.811156 -217.735698)
						(end 334.675734 -217.791792)
					)
					(arc
						(start 334.675734 -217.791792)
						(mid 334.602141 -217.777194)
						(end 334.539844 -217.735404)
					)
					(xy 334.539336 -217.734642)
					(arc
						(start 334.524858 -217.720164)
						(mid 334.511502 -217.713928)
						(end 334.496918 -217.711782)
					)
				)
			)
		)
		(zone
			(layer "F.Cu")
			(hatch none 0.5)
			(connect_pads
				(clearance 0)
			)
			(min_thickness 0.25)
			(keepout
				(tracks not_allowed)
				(vias allowed)
				(pads allowed)
				(copperpour not_allowed)
				(footprints allowed)
			)
			(placement
				(enabled no)
				(sheetname "")
			)
			(fill
				(thermal_gap 0.5)
				(thermal_bridge_width 0.5)
				(island_removal_mode 0)
			)
			(polygon
				(pts
					(arc
						(start 334.896968 -286.932116)
						(mid 334.911847 -286.968037)
						(end 334.947768 -286.982916)
					)
					(arc
						(start 334.947768 -286.982916)
						(mid 334.967952 -286.978734)
						(end 334.984852 -286.966914)
					)
					(arc
						(start 334.984852 -286.966914)
						(mid 335.053438 -286.869755)
						(end 335.077562 -286.7533)
					)
					(arc
						(start 335.077562 -286.7533)
						(mid 334.992098 -286.546844)
						(end 334.785716 -286.4612)
					)
					(arc
						(start 334.785716 -286.4612)
						(mid 334.670294 -286.484971)
						(end 334.573626 -286.552386)
					)
					(arc
						(start 334.573626 -286.552386)
						(mid 334.561108 -286.569498)
						(end 334.556608 -286.590232)
					)
					(arc
						(start 334.556608 -286.590232)
						(mid 334.571397 -286.626318)
						(end 334.607408 -286.641286)
					)
					(arc
						(start 334.607408 -286.641286)
						(mid 334.621999 -286.638993)
						(end 334.635348 -286.63265)
					)
					(xy 334.649826 -286.618172) (xy 334.650334 -286.617664)
					(arc
						(start 334.650842 -286.616902)
						(mid 334.712836 -286.57601)
						(end 334.785716 -286.561784)
					)
					(arc
						(start 334.785716 -286.561784)
						(mid 334.921138 -286.617878)
						(end 334.977232 -286.7533)
					)
					(arc
						(start 334.977232 -286.7533)
						(mid 334.962433 -286.826868)
						(end 334.92059 -286.88919)
					)
					(xy 334.919828 -286.889698)
					(arc
						(start 334.90535 -286.904176)
						(mid 334.899114 -286.917532)
						(end 334.896968 -286.932116)
					)
				)
			)
		)
		(zone
			(layer "F.Cu")
			(hatch none 0.5)
			(connect_pads
				(clearance 0)
			)
			(min_thickness 0.25)
			(keepout
				(tracks not_allowed)
				(vias allowed)
				(pads allowed)
				(copperpour not_allowed)
				(footprints allowed)
			)
			(placement
				(enabled no)
				(sheetname "")
			)
			(fill
				(thermal_gap 0.5)
				(thermal_bridge_width 0.5)
				(island_removal_mode 0)
			)
			(polygon
				(pts
					(arc
						(start 334.896968 -285.30423)
						(mid 334.911847 -285.340151)
						(end 334.947768 -285.35503)
					)
					(arc
						(start 334.947768 -285.35503)
						(mid 334.967925 -285.35097)
						(end 334.984852 -285.339282)
					)
					(arc
						(start 334.984852 -285.339282)
						(mid 335.05343 -285.24199)
						(end 335.077562 -285.125414)
					)
					(arc
						(start 335.077562 -285.125414)
						(mid 334.992082 -284.919048)
						(end 334.785716 -284.833568)
					)
					(arc
						(start 334.785716 -284.833568)
						(mid 334.670337 -284.857234)
						(end 334.573626 -284.9245)
					)
					(arc
						(start 334.573626 -284.9245)
						(mid 334.561057 -284.941728)
						(end 334.556608 -284.9626)
					)
					(arc
						(start 334.556608 -284.9626)
						(mid 334.571487 -284.998521)
						(end 334.607408 -285.0134)
					)
					(arc
						(start 334.607408 -285.0134)
						(mid 334.62203 -285.011174)
						(end 334.635348 -285.004764)
					)
					(xy 334.649826 -284.990286) (xy 334.650334 -284.989778)
					(arc
						(start 334.650842 -284.98927)
						(mid 334.712807 -284.948243)
						(end 334.785716 -284.933898)
					)
					(arc
						(start 334.785716 -284.933898)
						(mid 334.921138 -284.989992)
						(end 334.977232 -285.125414)
					)
					(arc
						(start 334.977232 -285.125414)
						(mid 334.962516 -285.199036)
						(end 334.92059 -285.261304)
					)
					(xy 334.919828 -285.261812)
					(arc
						(start 334.90535 -285.27629)
						(mid 334.899114 -285.289646)
						(end 334.896968 -285.30423)
					)
				)
			)
		)
		(zone
			(layer "F.Cu")
			(hatch none 0.5)
			(connect_pads
				(clearance 0)
			)
			(min_thickness 0.25)
			(keepout
				(tracks not_allowed)
				(vias allowed)
				(pads allowed)
				(copperpour not_allowed)
				(footprints allowed)
			)
			(placement
				(enabled no)
				(sheetname "")
			)
			(fill
				(thermal_gap 0.5)
				(thermal_bridge_width 0.5)
				(island_removal_mode 0)
			)
			(polygon
				(pts
					(arc
						(start 334.966564 -218.525598)
						(mid 334.930643 -218.540477)
						(end 334.915764 -218.576398)
					)
					(arc
						(start 334.915764 -218.576398)
						(mid 334.919946 -218.596582)
						(end 334.931766 -218.613482)
					)
					(arc
						(start 334.931766 -218.613482)
						(mid 335.028909 -218.682153)
						(end 335.14538 -218.706446)
					)
					(arc
						(start 335.14538 -218.706446)
						(mid 335.351926 -218.620892)
						(end 335.43748 -218.414346)
					)
					(arc
						(start 335.43748 -218.414346)
						(mid 335.413709 -218.298924)
						(end 335.346294 -218.202256)
					)
					(arc
						(start 335.346294 -218.202256)
						(mid 335.329199 -218.189677)
						(end 335.308448 -218.185238)
					)
					(arc
						(start 335.308448 -218.185238)
						(mid 335.272527 -218.200117)
						(end 335.257648 -218.236038)
					)
					(arc
						(start 335.257648 -218.236038)
						(mid 335.259787 -218.250624)
						(end 335.26603 -218.263978)
					)
					(xy 335.280762 -218.278456) (xy 335.281016 -218.278964)
					(arc
						(start 335.281524 -218.279472)
						(mid 335.322551 -218.341437)
						(end 335.336896 -218.414346)
					)
					(arc
						(start 335.336896 -218.414346)
						(mid 335.280802 -218.549768)
						(end 335.14538 -218.605862)
					)
					(arc
						(start 335.14538 -218.605862)
						(mid 335.071798 -218.591078)
						(end 335.00949 -218.54922)
					)
					(xy 335.009236 -218.548458)
					(arc
						(start 334.994758 -218.53398)
						(mid 334.981275 -218.527738)
						(end 334.966564 -218.525598)
					)
				)
			)
		)
		(zone
			(layer "F.Cu")
			(hatch none 0.5)
			(connect_pads
				(clearance 0)
			)
			(min_thickness 0.25)
			(keepout
				(tracks not_allowed)
				(vias allowed)
				(pads allowed)
				(copperpour not_allowed)
				(footprints allowed)
			)
			(placement
				(enabled no)
				(sheetname "")
			)
			(fill
				(thermal_gap 0.5)
				(thermal_bridge_width 0.5)
				(island_removal_mode 0)
			)
			(polygon
				(pts
					(arc
						(start 334.966564 -216.897966)
						(mid 334.930643 -216.912845)
						(end 334.915764 -216.948766)
					)
					(arc
						(start 334.915764 -216.948766)
						(mid 334.919996 -216.968813)
						(end 334.931766 -216.985596)
					)
					(arc
						(start 334.931766 -216.985596)
						(mid 335.028909 -217.054267)
						(end 335.14538 -217.07856)
					)
					(arc
						(start 335.14538 -217.07856)
						(mid 335.351926 -216.993006)
						(end 335.43748 -216.78646)
					)
					(arc
						(start 335.43748 -216.78646)
						(mid 335.413709 -216.671038)
						(end 335.346294 -216.57437)
					)
					(arc
						(start 335.346294 -216.57437)
						(mid 335.329148 -216.562)
						(end 335.308448 -216.557606)
					)
					(arc
						(start 335.308448 -216.557606)
						(mid 335.272527 -216.572485)
						(end 335.257648 -216.608406)
					)
					(arc
						(start 335.257648 -216.608406)
						(mid 335.259823 -216.62286)
						(end 335.26603 -216.636092)
					)
					(xy 335.280762 -216.650824) (xy 335.281016 -216.651078)
					(arc
						(start 335.281524 -216.65184)
						(mid 335.322556 -216.713674)
						(end 335.336896 -216.78646)
					)
					(arc
						(start 335.336896 -216.78646)
						(mid 335.280802 -216.921882)
						(end 335.14538 -216.977976)
					)
					(arc
						(start 335.14538 -216.977976)
						(mid 335.071758 -216.96326)
						(end 335.00949 -216.921334)
					)
					(xy 335.009236 -216.920826)
					(arc
						(start 334.994758 -216.906348)
						(mid 334.98128 -216.900075)
						(end 334.966564 -216.897966)
					)
				)
			)
		)
		(zone
			(layer "F.Cu")
			(hatch none 0.5)
			(connect_pads
				(clearance 0)
			)
			(min_thickness 0.25)
			(keepout
				(tracks not_allowed)
				(vias allowed)
				(pads allowed)
				(copperpour not_allowed)
				(footprints allowed)
			)
			(placement
				(enabled no)
				(sheetname "")
			)
			(fill
				(thermal_gap 0.5)
				(thermal_bridge_width 0.5)
				(island_removal_mode 0)
			)
			(polygon
				(pts
					(arc
						(start 335.366868 -287.745932)
						(mid 335.381747 -287.781853)
						(end 335.417668 -287.796732)
					)
					(arc
						(start 335.417668 -287.796732)
						(mid 335.437687 -287.792621)
						(end 335.454498 -287.780984)
					)
					(arc
						(start 335.454498 -287.780984)
						(mid 335.52322 -287.683724)
						(end 335.547462 -287.567116)
					)
					(arc
						(start 335.547462 -287.567116)
						(mid 335.461818 -287.360734)
						(end 335.255362 -287.27527)
					)
					(arc
						(start 335.255362 -287.27527)
						(mid 335.140121 -287.298986)
						(end 335.043526 -287.366202)
					)
					(arc
						(start 335.043526 -287.366202)
						(mid 335.030957 -287.38343)
						(end 335.026508 -287.404302)
					)
					(arc
						(start 335.026508 -287.404302)
						(mid 335.041387 -287.440223)
						(end 335.077308 -287.455102)
					)
					(arc
						(start 335.077308 -287.455102)
						(mid 335.091798 -287.45284)
						(end 335.104994 -287.446466)
					)
					(xy 335.119726 -287.431988) (xy 335.11998 -287.43148)
					(arc
						(start 335.120742 -287.430972)
						(mid 335.18259 -287.389993)
						(end 335.255362 -287.3756)
					)
					(arc
						(start 335.255362 -287.3756)
						(mid 335.390784 -287.431694)
						(end 335.446878 -287.567116)
					)
					(arc
						(start 335.446878 -287.567116)
						(mid 335.432162 -287.640738)
						(end 335.390236 -287.703006)
					)
					(xy 335.389728 -287.703514)
					(arc
						(start 335.37525 -287.717992)
						(mid 335.369014 -287.731348)
						(end 335.366868 -287.745932)
					)
				)
			)
		)
		(zone
			(layer "F.Cu")
			(hatch none 0.5)
			(connect_pads
				(clearance 0)
			)
			(min_thickness 0.25)
			(keepout
				(tracks not_allowed)
				(vias allowed)
				(pads allowed)
				(copperpour not_allowed)
				(footprints allowed)
			)
			(placement
				(enabled no)
				(sheetname "")
			)
			(fill
				(thermal_gap 0.5)
				(thermal_bridge_width 0.5)
				(island_removal_mode 0)
			)
			(polygon
				(pts
					(arc
						(start 335.366868 -286.1183)
						(mid 335.381747 -286.154221)
						(end 335.417668 -286.1691)
					)
					(arc
						(start 335.417668 -286.1691)
						(mid 335.437715 -286.164868)
						(end 335.454498 -286.153098)
					)
					(arc
						(start 335.454498 -286.153098)
						(mid 335.523169 -286.055955)
						(end 335.547462 -285.939484)
					)
					(arc
						(start 335.547462 -285.939484)
						(mid 335.461908 -285.732938)
						(end 335.255362 -285.647384)
					)
					(arc
						(start 335.255362 -285.647384)
						(mid 335.140105 -285.671085)
						(end 335.043526 -285.738316)
					)
					(arc
						(start 335.043526 -285.738316)
						(mid 335.030957 -285.755544)
						(end 335.026508 -285.776416)
					)
					(arc
						(start 335.026508 -285.776416)
						(mid 335.041387 -285.812337)
						(end 335.077308 -285.827216)
					)
					(arc
						(start 335.077308 -285.827216)
						(mid 335.091762 -285.825041)
						(end 335.104994 -285.818834)
					)
					(xy 335.119726 -285.804102) (xy 335.11998 -285.803848)
					(arc
						(start 335.120742 -285.803086)
						(mid 335.182619 -285.762242)
						(end 335.255362 -285.747968)
					)
					(arc
						(start 335.255362 -285.747968)
						(mid 335.390784 -285.804062)
						(end 335.446878 -285.939484)
					)
					(arc
						(start 335.446878 -285.939484)
						(mid 335.432162 -286.013106)
						(end 335.390236 -286.075374)
					)
					(xy 335.389728 -286.075628)
					(arc
						(start 335.37525 -286.090106)
						(mid 335.368977 -286.103584)
						(end 335.366868 -286.1183)
					)
				)
			)
		)
		(zone
			(layer "F.Cu")
			(hatch none 0.5)
			(connect_pads
				(clearance 0)
			)
			(min_thickness 0.25)
			(keepout
				(tracks not_allowed)
				(vias allowed)
				(pads allowed)
				(copperpour not_allowed)
				(footprints allowed)
			)
			(placement
				(enabled no)
				(sheetname "")
			)
			(fill
				(thermal_gap 0.5)
				(thermal_bridge_width 0.5)
				(island_removal_mode 0)
			)
			(polygon
				(pts
					(arc
						(start 335.436718 -217.711782)
						(mid 335.400797 -217.726661)
						(end 335.385918 -217.762582)
					)
					(arc
						(start 335.385918 -217.762582)
						(mid 335.390029 -217.782601)
						(end 335.401666 -217.799412)
					)
					(arc
						(start 335.401666 -217.799412)
						(mid 335.498926 -217.868134)
						(end 335.615534 -217.892376)
					)
					(arc
						(start 335.615534 -217.892376)
						(mid 335.82208 -217.806822)
						(end 335.907634 -217.600276)
					)
					(arc
						(start 335.907634 -217.600276)
						(mid 335.883812 -217.484991)
						(end 335.816448 -217.38844)
					)
					(arc
						(start 335.816448 -217.38844)
						(mid 335.79922 -217.375871)
						(end 335.778348 -217.371422)
					)
					(arc
						(start 335.778348 -217.371422)
						(mid 335.742427 -217.386301)
						(end 335.727548 -217.422222)
					)
					(arc
						(start 335.727548 -217.422222)
						(mid 335.729723 -217.436676)
						(end 335.73593 -217.449908)
					)
					(xy 335.750662 -217.46464) (xy 335.750916 -217.464894)
					(arc
						(start 335.751678 -217.465656)
						(mid 335.792657 -217.527504)
						(end 335.80705 -217.600276)
					)
					(arc
						(start 335.80705 -217.600276)
						(mid 335.750956 -217.735698)
						(end 335.615534 -217.791792)
					)
					(arc
						(start 335.615534 -217.791792)
						(mid 335.541941 -217.777194)
						(end 335.479644 -217.735404)
					)
					(xy 335.479136 -217.734642)
					(arc
						(start 335.464658 -217.720164)
						(mid 335.451302 -217.713928)
						(end 335.436718 -217.711782)
					)
				)
			)
		)
		(zone
			(layer "F.Cu")
			(hatch none 0.5)
			(connect_pads
				(clearance 0)
			)
			(min_thickness 0.25)
			(keepout
				(tracks not_allowed)
				(vias allowed)
				(pads allowed)
				(copperpour not_allowed)
				(footprints allowed)
			)
			(placement
				(enabled no)
				(sheetname "")
			)
			(fill
				(thermal_gap 0.5)
				(thermal_bridge_width 0.5)
				(island_removal_mode 0)
			)
			(polygon
				(pts
					(arc
						(start 335.436718 -216.083896)
						(mid 335.400797 -216.098775)
						(end 335.385918 -216.134696)
					)
					(arc
						(start 335.385918 -216.134696)
						(mid 335.389978 -216.154853)
						(end 335.401666 -216.17178)
					)
					(arc
						(start 335.401666 -216.17178)
						(mid 335.498926 -216.240502)
						(end 335.615534 -216.264744)
					)
					(arc
						(start 335.615534 -216.264744)
						(mid 335.82208 -216.17919)
						(end 335.907634 -215.972644)
					)
					(arc
						(start 335.907634 -215.972644)
						(mid 335.883863 -215.857222)
						(end 335.816448 -215.760554)
					)
					(arc
						(start 335.816448 -215.760554)
						(mid 335.79922 -215.747985)
						(end 335.778348 -215.743536)
					)
					(arc
						(start 335.778348 -215.743536)
						(mid 335.742427 -215.758415)
						(end 335.727548 -215.794336)
					)
					(arc
						(start 335.727548 -215.794336)
						(mid 335.729687 -215.808922)
						(end 335.73593 -215.822276)
					)
					(xy 335.750662 -215.836754) (xy 335.750916 -215.837262)
					(arc
						(start 335.751678 -215.83777)
						(mid 335.792705 -215.899735)
						(end 335.80705 -215.972644)
					)
					(arc
						(start 335.80705 -215.972644)
						(mid 335.750956 -216.108066)
						(end 335.615534 -216.16416)
					)
					(arc
						(start 335.615534 -216.16416)
						(mid 335.541912 -216.149444)
						(end 335.479644 -216.107518)
					)
					(xy 335.479136 -216.106756)
					(arc
						(start 335.464658 -216.092278)
						(mid 335.451302 -216.086042)
						(end 335.436718 -216.083896)
					)
				)
			)
		)
		(zone
			(layer "F.Cu")
			(hatch none 0.5)
			(connect_pads
				(clearance 0)
			)
			(min_thickness 0.25)
			(keepout
				(tracks not_allowed)
				(vias allowed)
				(pads allowed)
				(copperpour not_allowed)
				(footprints allowed)
			)
			(placement
				(enabled no)
				(sheetname "")
			)
			(fill
				(thermal_gap 0.5)
				(thermal_bridge_width 0.5)
				(island_removal_mode 0)
			)
			(polygon
				(pts
					(arc
						(start 335.836768 -288.560002)
						(mid 335.851647 -288.595923)
						(end 335.887568 -288.610802)
					)
					(arc
						(start 335.887568 -288.610802)
						(mid 335.907615 -288.60657)
						(end 335.924398 -288.5948)
					)
					(arc
						(start 335.924398 -288.5948)
						(mid 335.993069 -288.497657)
						(end 336.017362 -288.381186)
					)
					(arc
						(start 336.017362 -288.381186)
						(mid 335.931808 -288.17464)
						(end 335.725262 -288.089086)
					)
					(arc
						(start 335.725262 -288.089086)
						(mid 335.610005 -288.112787)
						(end 335.513426 -288.180018)
					)
					(arc
						(start 335.513426 -288.180018)
						(mid 335.500857 -288.197246)
						(end 335.496408 -288.218118)
					)
					(arc
						(start 335.496408 -288.218118)
						(mid 335.511287 -288.254039)
						(end 335.547208 -288.268918)
					)
					(arc
						(start 335.547208 -288.268918)
						(mid 335.561662 -288.266743)
						(end 335.574894 -288.260536)
					)
					(xy 335.589626 -288.245804) (xy 335.58988 -288.24555)
					(arc
						(start 335.590642 -288.244788)
						(mid 335.652519 -288.203944)
						(end 335.725262 -288.18967)
					)
					(arc
						(start 335.725262 -288.18967)
						(mid 335.860684 -288.245764)
						(end 335.916778 -288.381186)
					)
					(arc
						(start 335.916778 -288.381186)
						(mid 335.902062 -288.454808)
						(end 335.860136 -288.517076)
					)
					(xy 335.859628 -288.51733)
					(arc
						(start 335.84515 -288.531808)
						(mid 335.838877 -288.545286)
						(end 335.836768 -288.560002)
					)
				)
			)
		)
		(zone
			(layer "F.Cu")
			(hatch none 0.5)
			(connect_pads
				(clearance 0)
			)
			(min_thickness 0.25)
			(keepout
				(tracks not_allowed)
				(vias allowed)
				(pads allowed)
				(copperpour not_allowed)
				(footprints allowed)
			)
			(placement
				(enabled no)
				(sheetname "")
			)
			(fill
				(thermal_gap 0.5)
				(thermal_bridge_width 0.5)
				(island_removal_mode 0)
			)
			(polygon
				(pts
					(arc
						(start 335.836768 -286.932116)
						(mid 335.851647 -286.968037)
						(end 335.887568 -286.982916)
					)
					(arc
						(start 335.887568 -286.982916)
						(mid 335.907615 -286.978684)
						(end 335.924398 -286.966914)
					)
					(arc
						(start 335.924398 -286.966914)
						(mid 335.993127 -286.869787)
						(end 336.017362 -286.7533)
					)
					(arc
						(start 336.017362 -286.7533)
						(mid 335.931808 -286.546754)
						(end 335.725262 -286.4612)
					)
					(arc
						(start 335.725262 -286.4612)
						(mid 335.609977 -286.485022)
						(end 335.513426 -286.552386)
					)
					(arc
						(start 335.513426 -286.552386)
						(mid 335.500908 -286.569498)
						(end 335.496408 -286.590232)
					)
					(arc
						(start 335.496408 -286.590232)
						(mid 335.511197 -286.626318)
						(end 335.547208 -286.641286)
					)
					(arc
						(start 335.547208 -286.641286)
						(mid 335.561698 -286.639024)
						(end 335.574894 -286.63265)
					)
					(xy 335.589626 -286.618172) (xy 335.58988 -286.617664)
					(arc
						(start 335.590642 -286.616902)
						(mid 335.652519 -286.576058)
						(end 335.725262 -286.561784)
					)
					(arc
						(start 335.725262 -286.561784)
						(mid 335.860684 -286.617878)
						(end 335.916778 -286.7533)
					)
					(arc
						(start 335.916778 -286.7533)
						(mid 335.902062 -286.826922)
						(end 335.860136 -286.88919)
					)
					(xy 335.859628 -286.889698)
					(arc
						(start 335.84515 -286.904176)
						(mid 335.838914 -286.917532)
						(end 335.836768 -286.932116)
					)
				)
			)
		)
		(zone
			(layer "F.Cu")
			(hatch none 0.5)
			(connect_pads
				(clearance 0)
			)
			(min_thickness 0.25)
			(keepout
				(tracks not_allowed)
				(vias allowed)
				(pads allowed)
				(copperpour not_allowed)
				(footprints allowed)
			)
			(placement
				(enabled no)
				(sheetname "")
			)
			(fill
				(thermal_gap 0.5)
				(thermal_bridge_width 0.5)
				(island_removal_mode 0)
			)
			(polygon
				(pts
					(arc
						(start 335.906618 -216.897966)
						(mid 335.870697 -216.912845)
						(end 335.855818 -216.948766)
					)
					(arc
						(start 335.855818 -216.948766)
						(mid 335.859929 -216.968785)
						(end 335.871566 -216.985596)
					)
					(arc
						(start 335.871566 -216.985596)
						(mid 335.968826 -217.054318)
						(end 336.085434 -217.07856)
					)
					(arc
						(start 336.085434 -217.07856)
						(mid 336.29198 -216.993006)
						(end 336.377534 -216.78646)
					)
					(arc
						(start 336.377534 -216.78646)
						(mid 336.353763 -216.671038)
						(end 336.286348 -216.57437)
					)
					(arc
						(start 336.286348 -216.57437)
						(mid 336.269086 -216.561949)
						(end 336.248248 -216.557606)
					)
					(arc
						(start 336.248248 -216.557606)
						(mid 336.212327 -216.572485)
						(end 336.197448 -216.608406)
					)
					(arc
						(start 336.197448 -216.608406)
						(mid 336.199623 -216.62286)
						(end 336.20583 -216.636092)
					)
					(xy 336.220562 -216.650824) (xy 336.220816 -216.651078)
					(arc
						(start 336.221578 -216.65184)
						(mid 336.262557 -216.713688)
						(end 336.27695 -216.78646)
					)
					(arc
						(start 336.27695 -216.78646)
						(mid 336.220856 -216.921882)
						(end 336.085434 -216.977976)
					)
					(arc
						(start 336.085434 -216.977976)
						(mid 336.011812 -216.96326)
						(end 335.949544 -216.921334)
					)
					(xy 335.949036 -216.920826)
					(arc
						(start 335.934558 -216.906348)
						(mid 335.921202 -216.900112)
						(end 335.906618 -216.897966)
					)
				)
			)
		)
		(zone
			(layer "F.Cu")
			(hatch none 0.5)
			(connect_pads
				(clearance 0)
			)
			(min_thickness 0.25)
			(keepout
				(tracks not_allowed)
				(vias allowed)
				(pads allowed)
				(copperpour not_allowed)
				(footprints allowed)
			)
			(placement
				(enabled no)
				(sheetname "")
			)
			(fill
				(thermal_gap 0.5)
				(thermal_bridge_width 0.5)
				(island_removal_mode 0)
			)
			(polygon
				(pts
					(arc
						(start 335.906618 -215.27008)
						(mid 335.870697 -215.284959)
						(end 335.855818 -215.32088)
					)
					(arc
						(start 335.855818 -215.32088)
						(mid 335.859913 -215.340915)
						(end 335.871566 -215.35771)
					)
					(arc
						(start 335.871566 -215.35771)
						(mid 335.968826 -215.426432)
						(end 336.085434 -215.450674)
					)
					(arc
						(start 336.085434 -215.450674)
						(mid 336.29198 -215.36512)
						(end 336.377534 -215.158574)
					)
					(arc
						(start 336.377534 -215.158574)
						(mid 336.353712 -215.043289)
						(end 336.286348 -214.946738)
					)
					(arc
						(start 336.286348 -214.946738)
						(mid 336.26912 -214.934169)
						(end 336.248248 -214.92972)
					)
					(arc
						(start 336.248248 -214.92972)
						(mid 336.212327 -214.944599)
						(end 336.197448 -214.98052)
					)
					(arc
						(start 336.197448 -214.98052)
						(mid 336.199623 -214.994974)
						(end 336.20583 -215.008206)
					)
					(xy 336.220562 -215.022938) (xy 336.220816 -215.023192)
					(arc
						(start 336.221578 -215.023954)
						(mid 336.262557 -215.085802)
						(end 336.27695 -215.158574)
					)
					(arc
						(start 336.27695 -215.158574)
						(mid 336.220856 -215.293996)
						(end 336.085434 -215.35009)
					)
					(arc
						(start 336.085434 -215.35009)
						(mid 336.011841 -215.335492)
						(end 335.949544 -215.293702)
					)
					(xy 335.949036 -215.29294)
					(arc
						(start 335.934558 -215.278462)
						(mid 335.921202 -215.272226)
						(end 335.906618 -215.27008)
					)
				)
			)
		)
		(zone
			(layer "F.Cu")
			(hatch none 0.5)
			(connect_pads
				(clearance 0)
			)
			(min_thickness 0.25)
			(keepout
				(tracks not_allowed)
				(vias allowed)
				(pads allowed)
				(copperpour not_allowed)
				(footprints allowed)
			)
			(placement
				(enabled no)
				(sheetname "")
			)
			(fill
				(thermal_gap 0.5)
				(thermal_bridge_width 0.5)
				(island_removal_mode 0)
			)
			(polygon
				(pts
					(arc
						(start 336.306668 -287.745932)
						(mid 336.321547 -287.781853)
						(end 336.357468 -287.796732)
					)
					(arc
						(start 336.357468 -287.796732)
						(mid 336.377487 -287.792621)
						(end 336.394298 -287.780984)
					)
					(arc
						(start 336.394298 -287.780984)
						(mid 336.46302 -287.683724)
						(end 336.487262 -287.567116)
					)
					(arc
						(start 336.487262 -287.567116)
						(mid 336.401618 -287.360734)
						(end 336.195162 -287.27527)
					)
					(arc
						(start 336.195162 -287.27527)
						(mid 336.079921 -287.298986)
						(end 335.983326 -287.366202)
					)
					(arc
						(start 335.983326 -287.366202)
						(mid 335.970757 -287.38343)
						(end 335.966308 -287.404302)
					)
					(arc
						(start 335.966308 -287.404302)
						(mid 335.981187 -287.440223)
						(end 336.017108 -287.455102)
					)
					(arc
						(start 336.017108 -287.455102)
						(mid 336.031598 -287.45284)
						(end 336.044794 -287.446466)
					)
					(xy 336.059526 -287.431988) (xy 336.05978 -287.43148)
					(arc
						(start 336.060542 -287.430972)
						(mid 336.12239 -287.389993)
						(end 336.195162 -287.3756)
					)
					(arc
						(start 336.195162 -287.3756)
						(mid 336.330584 -287.431694)
						(end 336.386678 -287.567116)
					)
					(arc
						(start 336.386678 -287.567116)
						(mid 336.371962 -287.640738)
						(end 336.330036 -287.703006)
					)
					(xy 336.329528 -287.703514)
					(arc
						(start 336.31505 -287.717992)
						(mid 336.308814 -287.731348)
						(end 336.306668 -287.745932)
					)
				)
			)
		)
		(zone
			(layer "F.Cu")
			(hatch none 0.5)
			(connect_pads
				(clearance 0)
			)
			(min_thickness 0.25)
			(keepout
				(tracks not_allowed)
				(vias allowed)
				(pads allowed)
				(copperpour not_allowed)
				(footprints allowed)
			)
			(placement
				(enabled no)
				(sheetname "")
			)
			(fill
				(thermal_gap 0.5)
				(thermal_bridge_width 0.5)
				(island_removal_mode 0)
			)
			(polygon
				(pts
					(arc
						(start 336.376518 -216.083896)
						(mid 336.340597 -216.098775)
						(end 336.325718 -216.134696)
					)
					(arc
						(start 336.325718 -216.134696)
						(mid 336.329778 -216.154853)
						(end 336.341466 -216.17178)
					)
					(arc
						(start 336.341466 -216.17178)
						(mid 336.438726 -216.240502)
						(end 336.555334 -216.264744)
					)
					(arc
						(start 336.555334 -216.264744)
						(mid 336.76188 -216.17919)
						(end 336.847434 -215.972644)
					)
					(arc
						(start 336.847434 -215.972644)
						(mid 336.823663 -215.857222)
						(end 336.756248 -215.760554)
					)
					(arc
						(start 336.756248 -215.760554)
						(mid 336.73902 -215.747985)
						(end 336.718148 -215.743536)
					)
					(arc
						(start 336.718148 -215.743536)
						(mid 336.682227 -215.758415)
						(end 336.667348 -215.794336)
					)
					(arc
						(start 336.667348 -215.794336)
						(mid 336.669487 -215.808922)
						(end 336.67573 -215.822276)
					)
					(xy 336.690462 -215.836754) (xy 336.690716 -215.837262)
					(arc
						(start 336.691478 -215.83777)
						(mid 336.732505 -215.899735)
						(end 336.74685 -215.972644)
					)
					(arc
						(start 336.74685 -215.972644)
						(mid 336.690756 -216.108066)
						(end 336.555334 -216.16416)
					)
					(arc
						(start 336.555334 -216.16416)
						(mid 336.481712 -216.149444)
						(end 336.419444 -216.107518)
					)
					(xy 336.418936 -216.106756)
					(arc
						(start 336.404458 -216.092278)
						(mid 336.391102 -216.086042)
						(end 336.376518 -216.083896)
					)
				)
			)
		)
		(zone
			(layer "F.Cu")
			(hatch none 0.5)
			(connect_pads
				(clearance 0)
			)
			(min_thickness 0.25)
			(keepout
				(tracks not_allowed)
				(vias allowed)
				(pads allowed)
				(copperpour not_allowed)
				(footprints allowed)
			)
			(placement
				(enabled no)
				(sheetname "")
			)
			(fill
				(thermal_gap 0.5)
				(thermal_bridge_width 0.5)
				(island_removal_mode 0)
			)
			(polygon
				(pts
					(arc
						(start 336.776568 -288.560002)
						(mid 336.791447 -288.595923)
						(end 336.827368 -288.610802)
					)
					(arc
						(start 336.827368 -288.610802)
						(mid 336.847552 -288.60662)
						(end 336.864452 -288.5948)
					)
					(arc
						(start 336.864452 -288.5948)
						(mid 336.93298 -288.497625)
						(end 336.957162 -288.381186)
					)
					(arc
						(start 336.957162 -288.381186)
						(mid 336.871772 -288.174655)
						(end 336.665316 -288.089086)
					)
					(arc
						(start 336.665316 -288.089086)
						(mid 336.549922 -288.112736)
						(end 336.453226 -288.180018)
					)
					(arc
						(start 336.453226 -288.180018)
						(mid 336.440657 -288.197246)
						(end 336.436208 -288.218118)
					)
					(arc
						(start 336.436208 -288.218118)
						(mid 336.451087 -288.254039)
						(end 336.487008 -288.268918)
					)
					(arc
						(start 336.487008 -288.268918)
						(mid 336.501594 -288.266779)
						(end 336.514948 -288.260536)
					)
					(xy 336.529426 -288.245804) (xy 336.529934 -288.24555)
					(arc
						(start 336.530442 -288.244788)
						(mid 336.592436 -288.203896)
						(end 336.665316 -288.18967)
					)
					(arc
						(start 336.665316 -288.18967)
						(mid 336.800738 -288.245764)
						(end 336.856832 -288.381186)
					)
					(arc
						(start 336.856832 -288.381186)
						(mid 336.842048 -288.454768)
						(end 336.80019 -288.517076)
					)
					(xy 336.799428 -288.51733)
					(arc
						(start 336.78495 -288.531808)
						(mid 336.778708 -288.545291)
						(end 336.776568 -288.560002)
					)
				)
			)
		)
		(zone
			(layer "F.Cu")
			(hatch none 0.5)
			(connect_pads
				(clearance 0)
			)
			(min_thickness 0.25)
			(keepout
				(tracks not_allowed)
				(vias allowed)
				(pads allowed)
				(copperpour not_allowed)
				(footprints allowed)
			)
			(placement
				(enabled no)
				(sheetname "")
			)
			(fill
				(thermal_gap 0.5)
				(thermal_bridge_width 0.5)
				(island_removal_mode 0)
			)
			(polygon
				(pts
					(arc
						(start 336.846164 -215.27008)
						(mid 336.810243 -215.284959)
						(end 336.795364 -215.32088)
					)
					(arc
						(start 336.795364 -215.32088)
						(mid 336.799596 -215.340927)
						(end 336.811366 -215.35771)
					)
					(arc
						(start 336.811366 -215.35771)
						(mid 336.908493 -215.426439)
						(end 337.02498 -215.450674)
					)
					(arc
						(start 337.02498 -215.450674)
						(mid 337.231526 -215.36512)
						(end 337.31708 -215.158574)
					)
					(arc
						(start 337.31708 -215.158574)
						(mid 337.293243 -215.043305)
						(end 337.225894 -214.946738)
					)
					(arc
						(start 337.225894 -214.946738)
						(mid 337.208799 -214.934159)
						(end 337.188048 -214.92972)
					)
					(arc
						(start 337.188048 -214.92972)
						(mid 337.152127 -214.944599)
						(end 337.137248 -214.98052)
					)
					(arc
						(start 337.137248 -214.98052)
						(mid 337.139433 -214.994968)
						(end 337.14563 -215.008206)
					)
					(xy 337.160362 -215.022938) (xy 337.160616 -215.023192)
					(arc
						(start 337.161124 -215.023954)
						(mid 337.202103 -215.085802)
						(end 337.216496 -215.158574)
					)
					(arc
						(start 337.216496 -215.158574)
						(mid 337.160402 -215.293996)
						(end 337.02498 -215.35009)
					)
					(arc
						(start 337.02498 -215.35009)
						(mid 336.951387 -215.335492)
						(end 336.88909 -215.293702)
					)
					(xy 336.888836 -215.29294)
					(arc
						(start 336.874358 -215.278462)
						(mid 336.86088 -215.272189)
						(end 336.846164 -215.27008)
					)
				)
			)
		)
		(zone
			(layer "F.Cu")
			(hatch none 0.5)
			(connect_pads
				(clearance 0)
			)
			(min_thickness 0.25)
			(keepout
				(tracks not_allowed)
				(vias allowed)
				(pads allowed)
				(copperpour not_allowed)
				(footprints allowed)
			)
			(placement
				(enabled no)
				(sheetname "")
			)
			(fill
				(thermal_gap 0.5)
				(thermal_bridge_width 0.5)
				(island_removal_mode 0)
			)
			(polygon
				(pts
					(arc
						(start 337.759548 -215.111076)
						(mid 337.723734 -215.096241)
						(end 337.68792 -215.111076)
					)
					(arc
						(start 337.68792 -215.111076)
						(mid 337.676569 -215.128198)
						(end 337.672934 -215.148414)
					)
					(arc
						(start 337.672934 -215.148414)
						(mid 337.693083 -215.265615)
						(end 337.758278 -215.365076)
					)
					(arc
						(start 337.758278 -215.365076)
						(mid 337.96478 -215.450612)
						(end 338.171282 -215.365076)
					)
					(arc
						(start 338.171282 -215.365076)
						(mid 338.236164 -215.266832)
						(end 338.25688 -215.150954)
					)
					(arc
						(start 338.25688 -215.150954)
						(mid 338.253692 -215.129932)
						(end 338.242148 -215.112092)
					)
					(arc
						(start 338.242148 -215.112092)
						(mid 338.206245 -215.097257)
						(end 338.170266 -215.112092)
					)
					(arc
						(start 338.170266 -215.112092)
						(mid 338.161543 -215.123788)
						(end 338.15655 -215.137492)
					)
					(xy 338.15655 -215.15832) (xy 338.15655 -215.158828)
					(arc
						(start 338.15655 -215.159844)
						(mid 338.141548 -215.232442)
						(end 338.100162 -215.293956)
					)
					(arc
						(start 338.100162 -215.293956)
						(mid 337.96478 -215.350033)
						(end 337.829398 -215.293956)
					)
					(arc
						(start 337.829398 -215.293956)
						(mid 337.787798 -215.231608)
						(end 337.773264 -215.158066)
					)
					(xy 337.773518 -215.157304)
					(arc
						(start 337.773518 -215.13673)
						(mid 337.768428 -215.122868)
						(end 337.759548 -215.111076)
					)
				)
			)
		)
		(zone
			(layer "F.Cu")
			(hatch none 0.5)
			(connect_pads
				(clearance 0)
			)
			(min_thickness 0.25)
			(keepout
				(tracks not_allowed)
				(vias allowed)
				(pads allowed)
				(copperpour not_allowed)
				(footprints allowed)
			)
			(placement
				(enabled no)
				(sheetname "")
			)
			(fill
				(thermal_gap 0.5)
				(thermal_bridge_width 0.5)
				(island_removal_mode 0)
			)
			(polygon
				(pts
					(arc
						(start 337.810094 -288.428684)
						(mid 337.846072 -288.443698)
						(end 337.881976 -288.428684)
					)
					(arc
						(start 337.881976 -288.428684)
						(mid 337.893327 -288.411562)
						(end 337.896962 -288.391346)
					)
					(arc
						(start 337.896962 -288.391346)
						(mid 337.876693 -288.274117)
						(end 337.811364 -288.174684)
					)
					(arc
						(start 337.811364 -288.174684)
						(mid 337.604862 -288.089148)
						(end 337.39836 -288.174684)
					)
					(arc
						(start 337.39836 -288.174684)
						(mid 337.333619 -288.272959)
						(end 337.313016 -288.388806)
					)
					(arc
						(start 337.313016 -288.388806)
						(mid 337.316216 -288.409815)
						(end 337.327748 -288.427668)
					)
					(arc
						(start 337.327748 -288.427668)
						(mid 337.363726 -288.442682)
						(end 337.39963 -288.427668)
					)
					(arc
						(start 337.39963 -288.427668)
						(mid 337.408353 -288.415972)
						(end 337.413346 -288.402268)
					)
					(xy 337.413346 -288.38144) (xy 337.413346 -288.380932)
					(arc
						(start 337.413346 -288.379916)
						(mid 337.428231 -288.307347)
						(end 337.46948 -288.245804)
					)
					(arc
						(start 337.46948 -288.245804)
						(mid 337.604862 -288.189727)
						(end 337.740244 -288.245804)
					)
					(arc
						(start 337.740244 -288.245804)
						(mid 337.781844 -288.308152)
						(end 337.796378 -288.381694)
					)
					(xy 337.796124 -288.382456)
					(arc
						(start 337.796124 -288.40303)
						(mid 337.801214 -288.416892)
						(end 337.810094 -288.428684)
					)
				)
			)
		)
		(zone
			(layer "F.Cu")
			(hatch none 0.5)
			(connect_pads
				(clearance 0)
			)
			(min_thickness 0.25)
			(keepout
				(tracks not_allowed)
				(vias allowed)
				(pads allowed)
				(copperpour not_allowed)
				(footprints allowed)
			)
			(placement
				(enabled no)
				(sheetname "")
			)
			(fill
				(thermal_gap 0.5)
				(thermal_bridge_width 0.5)
				(island_removal_mode 0)
			)
			(polygon
				(pts
					(arc
						(start 338.229702 -214.297006)
						(mid 338.193798 -214.282246)
						(end 338.15782 -214.297006)
					)
					(arc
						(start 338.15782 -214.297006)
						(mid 338.146421 -214.314246)
						(end 338.142834 -214.334598)
					)
					(arc
						(start 338.142834 -214.334598)
						(mid 338.163103 -214.451827)
						(end 338.228432 -214.55126)
					)
					(arc
						(start 338.228432 -214.55126)
						(mid 338.434934 -214.636796)
						(end 338.641436 -214.55126)
					)
					(arc
						(start 338.641436 -214.55126)
						(mid 338.706225 -214.452867)
						(end 338.72678 -214.336884)
					)
					(arc
						(start 338.72678 -214.336884)
						(mid 338.72358 -214.315875)
						(end 338.712048 -214.298022)
					)
					(arc
						(start 338.712048 -214.298022)
						(mid 338.676144 -214.283262)
						(end 338.640166 -214.298022)
					)
					(arc
						(start 338.640166 -214.298022)
						(mid 338.631424 -214.309843)
						(end 338.62645 -214.323676)
					)
					(xy 338.62645 -214.344504) (xy 338.62645 -214.344758)
					(arc
						(start 338.62645 -214.345774)
						(mid 338.611612 -214.418479)
						(end 338.570316 -214.48014)
					)
					(arc
						(start 338.570316 -214.48014)
						(mid 338.434934 -214.536217)
						(end 338.299552 -214.48014)
					)
					(arc
						(start 338.299552 -214.48014)
						(mid 338.257903 -214.417674)
						(end 338.243418 -214.343996)
					)
					(xy 338.243672 -214.343488)
					(arc
						(start 338.243672 -214.322914)
						(mid 338.238616 -214.308916)
						(end 338.229702 -214.297006)
					)
				)
			)
		)
		(zone
			(layer "F.Cu")
			(hatch none 0.5)
			(connect_pads
				(clearance 0)
			)
			(min_thickness 0.25)
			(keepout
				(tracks not_allowed)
				(vias allowed)
				(pads allowed)
				(copperpour not_allowed)
				(footprints allowed)
			)
			(placement
				(enabled no)
				(sheetname "")
			)
			(fill
				(thermal_gap 0.5)
				(thermal_bridge_width 0.5)
				(island_removal_mode 0)
			)
			(polygon
				(pts
					(arc
						(start 338.750148 -288.428684)
						(mid 338.785962 -288.443519)
						(end 338.821776 -288.428684)
					)
					(arc
						(start 338.821776 -288.428684)
						(mid 338.833127 -288.411562)
						(end 338.836762 -288.391346)
					)
					(arc
						(start 338.836762 -288.391346)
						(mid 338.816613 -288.274145)
						(end 338.751418 -288.174684)
					)
					(arc
						(start 338.751418 -288.174684)
						(mid 338.544916 -288.089148)
						(end 338.338414 -288.174684)
					)
					(arc
						(start 338.338414 -288.174684)
						(mid 338.273532 -288.272928)
						(end 338.252816 -288.388806)
					)
					(arc
						(start 338.252816 -288.388806)
						(mid 338.256004 -288.409828)
						(end 338.267548 -288.427668)
					)
					(arc
						(start 338.267548 -288.427668)
						(mid 338.303526 -288.442682)
						(end 338.33943 -288.427668)
					)
					(arc
						(start 338.33943 -288.427668)
						(mid 338.348153 -288.415972)
						(end 338.353146 -288.402268)
					)
					(xy 338.353146 -288.38144) (xy 338.353146 -288.380932)
					(arc
						(start 338.353146 -288.379916)
						(mid 338.368148 -288.307318)
						(end 338.409534 -288.245804)
					)
					(arc
						(start 338.409534 -288.245804)
						(mid 338.544916 -288.189727)
						(end 338.680298 -288.245804)
					)
					(arc
						(start 338.680298 -288.245804)
						(mid 338.721898 -288.308152)
						(end 338.736432 -288.381694)
					)
					(xy 338.736178 -288.382456)
					(arc
						(start 338.736178 -288.40303)
						(mid 338.741268 -288.416892)
						(end 338.750148 -288.428684)
					)
				)
			)
		)
		(zone
			(layer "F.Cu")
			(hatch none 0.5)
			(connect_pads
				(clearance 0)
			)
			(min_thickness 0.25)
			(keepout
				(tracks not_allowed)
				(vias allowed)
				(pads allowed)
				(copperpour not_allowed)
				(footprints allowed)
			)
			(placement
				(enabled no)
				(sheetname "")
			)
			(fill
				(thermal_gap 0.5)
				(thermal_bridge_width 0.5)
				(island_removal_mode 0)
			)
			(polygon
				(pts
					(arc
						(start 339.169502 -214.297006)
						(mid 339.133598 -214.282246)
						(end 339.09762 -214.297006)
					)
					(arc
						(start 339.09762 -214.297006)
						(mid 339.086221 -214.314246)
						(end 339.082634 -214.334598)
					)
					(arc
						(start 339.082634 -214.334598)
						(mid 339.102903 -214.451827)
						(end 339.168232 -214.55126)
					)
					(arc
						(start 339.168232 -214.55126)
						(mid 339.374734 -214.636796)
						(end 339.581236 -214.55126)
					)
					(arc
						(start 339.581236 -214.55126)
						(mid 339.646025 -214.452867)
						(end 339.66658 -214.336884)
					)
					(arc
						(start 339.66658 -214.336884)
						(mid 339.66338 -214.315875)
						(end 339.651848 -214.298022)
					)
					(arc
						(start 339.651848 -214.298022)
						(mid 339.615944 -214.283262)
						(end 339.579966 -214.298022)
					)
					(arc
						(start 339.579966 -214.298022)
						(mid 339.571224 -214.309843)
						(end 339.56625 -214.323676)
					)
					(xy 339.56625 -214.344504) (xy 339.56625 -214.344758)
					(arc
						(start 339.56625 -214.345774)
						(mid 339.551412 -214.418479)
						(end 339.510116 -214.48014)
					)
					(arc
						(start 339.510116 -214.48014)
						(mid 339.374734 -214.536217)
						(end 339.239352 -214.48014)
					)
					(arc
						(start 339.239352 -214.48014)
						(mid 339.197703 -214.417674)
						(end 339.183218 -214.343996)
					)
					(xy 339.183472 -214.343488)
					(arc
						(start 339.183472 -214.322914)
						(mid 339.178416 -214.308916)
						(end 339.169502 -214.297006)
					)
				)
			)
		)
		(zone
			(layer "F.Cu")
			(hatch none 0.5)
			(connect_pads
				(clearance 0)
			)
			(min_thickness 0.25)
			(keepout
				(tracks not_allowed)
				(vias allowed)
				(pads allowed)
				(copperpour not_allowed)
				(footprints allowed)
			)
			(placement
				(enabled no)
				(sheetname "")
			)
			(fill
				(thermal_gap 0.5)
				(thermal_bridge_width 0.5)
				(island_removal_mode 0)
			)
			(polygon
				(pts
					(arc
						(start 339.219794 -289.242754)
						(mid 339.255772 -289.257694)
						(end 339.291676 -289.242754)
					)
					(arc
						(start 339.291676 -289.242754)
						(mid 339.303075 -289.225514)
						(end 339.306662 -289.205162)
					)
					(arc
						(start 339.306662 -289.205162)
						(mid 339.286393 -289.087933)
						(end 339.221064 -288.9885)
					)
					(arc
						(start 339.221064 -288.9885)
						(mid 339.014562 -288.902964)
						(end 338.80806 -288.9885)
					)
					(arc
						(start 338.80806 -288.9885)
						(mid 338.743271 -289.086893)
						(end 338.722716 -289.202876)
					)
					(arc
						(start 338.722716 -289.202876)
						(mid 338.725916 -289.223885)
						(end 338.737448 -289.241738)
					)
					(arc
						(start 338.737448 -289.241738)
						(mid 338.773426 -289.256678)
						(end 338.80933 -289.241738)
					)
					(arc
						(start 338.80933 -289.241738)
						(mid 338.818072 -289.229917)
						(end 338.823046 -289.216084)
					)
					(xy 338.823046 -289.195256) (xy 338.823046 -289.195002)
					(arc
						(start 338.823046 -289.193986)
						(mid 338.837884 -289.121281)
						(end 338.87918 -289.05962)
					)
					(arc
						(start 338.87918 -289.05962)
						(mid 339.014562 -289.003543)
						(end 339.149944 -289.05962)
					)
					(arc
						(start 339.149944 -289.05962)
						(mid 339.191593 -289.122086)
						(end 339.206078 -289.195764)
					)
					(xy 339.205824 -289.196272)
					(arc
						(start 339.205824 -289.216846)
						(mid 339.21088 -289.230844)
						(end 339.219794 -289.242754)
					)
				)
			)
		)
		(zone
			(layer "F.Cu")
			(hatch none 0.5)
			(connect_pads
				(clearance 0)
			)
			(min_thickness 0.25)
			(keepout
				(tracks not_allowed)
				(vias allowed)
				(pads allowed)
				(copperpour not_allowed)
				(footprints allowed)
			)
			(placement
				(enabled no)
				(sheetname "")
			)
			(fill
				(thermal_gap 0.5)
				(thermal_bridge_width 0.5)
				(island_removal_mode 0)
			)
			(polygon
				(pts
					(arc
						(start 340.109302 -214.297006)
						(mid 340.073398 -214.282246)
						(end 340.03742 -214.297006)
					)
					(arc
						(start 340.03742 -214.297006)
						(mid 340.026021 -214.314246)
						(end 340.022434 -214.334598)
					)
					(arc
						(start 340.022434 -214.334598)
						(mid 340.042703 -214.451827)
						(end 340.108032 -214.55126)
					)
					(arc
						(start 340.108032 -214.55126)
						(mid 340.314534 -214.636796)
						(end 340.521036 -214.55126)
					)
					(arc
						(start 340.521036 -214.55126)
						(mid 340.585825 -214.452867)
						(end 340.60638 -214.336884)
					)
					(arc
						(start 340.60638 -214.336884)
						(mid 340.60318 -214.315875)
						(end 340.591648 -214.298022)
					)
					(arc
						(start 340.591648 -214.298022)
						(mid 340.555744 -214.283262)
						(end 340.519766 -214.298022)
					)
					(arc
						(start 340.519766 -214.298022)
						(mid 340.511024 -214.309843)
						(end 340.50605 -214.323676)
					)
					(xy 340.50605 -214.344504) (xy 340.50605 -214.344758)
					(arc
						(start 340.50605 -214.345774)
						(mid 340.491212 -214.418479)
						(end 340.449916 -214.48014)
					)
					(arc
						(start 340.449916 -214.48014)
						(mid 340.314534 -214.536217)
						(end 340.179152 -214.48014)
					)
					(arc
						(start 340.179152 -214.48014)
						(mid 340.137503 -214.417674)
						(end 340.123018 -214.343996)
					)
					(xy 340.123272 -214.343488)
					(arc
						(start 340.123272 -214.322914)
						(mid 340.118216 -214.308916)
						(end 340.109302 -214.297006)
					)
				)
			)
		)
		(zone
			(layer "F.Cu")
			(hatch none 0.5)
			(connect_pads
				(clearance 0)
			)
			(min_thickness 0.25)
			(keepout
				(tracks not_allowed)
				(vias allowed)
				(pads allowed)
				(copperpour not_allowed)
				(footprints allowed)
			)
			(placement
				(enabled no)
				(sheetname "")
			)
			(fill
				(thermal_gap 0.5)
				(thermal_bridge_width 0.5)
				(island_removal_mode 0)
			)
			(polygon
				(pts
					(arc
						(start 340.159594 -289.242754)
						(mid 340.195572 -289.257694)
						(end 340.231476 -289.242754)
					)
					(arc
						(start 340.231476 -289.242754)
						(mid 340.242875 -289.225514)
						(end 340.246462 -289.205162)
					)
					(arc
						(start 340.246462 -289.205162)
						(mid 340.226193 -289.087933)
						(end 340.160864 -288.9885)
					)
					(arc
						(start 340.160864 -288.9885)
						(mid 339.954362 -288.902964)
						(end 339.74786 -288.9885)
					)
					(arc
						(start 339.74786 -288.9885)
						(mid 339.683071 -289.086893)
						(end 339.662516 -289.202876)
					)
					(arc
						(start 339.662516 -289.202876)
						(mid 339.665716 -289.223885)
						(end 339.677248 -289.241738)
					)
					(arc
						(start 339.677248 -289.241738)
						(mid 339.713226 -289.256678)
						(end 339.74913 -289.241738)
					)
					(arc
						(start 339.74913 -289.241738)
						(mid 339.757872 -289.229917)
						(end 339.762846 -289.216084)
					)
					(xy 339.762846 -289.195256) (xy 339.762846 -289.195002)
					(arc
						(start 339.762846 -289.193986)
						(mid 339.777684 -289.121281)
						(end 339.81898 -289.05962)
					)
					(arc
						(start 339.81898 -289.05962)
						(mid 339.954362 -289.003543)
						(end 340.089744 -289.05962)
					)
					(arc
						(start 340.089744 -289.05962)
						(mid 340.131393 -289.122086)
						(end 340.145878 -289.195764)
					)
					(xy 340.145624 -289.196272)
					(arc
						(start 340.145624 -289.216846)
						(mid 340.15068 -289.230844)
						(end 340.159594 -289.242754)
					)
				)
			)
		)
		(zone
			(layer "F.Cu")
			(hatch none 0.5)
			(connect_pads
				(clearance 0)
			)
			(min_thickness 0.25)
			(keepout
				(tracks not_allowed)
				(vias allowed)
				(pads allowed)
				(copperpour not_allowed)
				(footprints allowed)
			)
			(placement
				(enabled no)
				(sheetname "")
			)
			(fill
				(thermal_gap 0.5)
				(thermal_bridge_width 0.5)
				(island_removal_mode 0)
			)
			(polygon
				(pts
					(arc
						(start 341.049102 -214.297006)
						(mid 341.013198 -214.282246)
						(end 340.97722 -214.297006)
					)
					(arc
						(start 340.97722 -214.297006)
						(mid 340.965821 -214.314246)
						(end 340.962234 -214.334598)
					)
					(arc
						(start 340.962234 -214.334598)
						(mid 340.982503 -214.451827)
						(end 341.047832 -214.55126)
					)
					(arc
						(start 341.047832 -214.55126)
						(mid 341.254334 -214.636796)
						(end 341.460836 -214.55126)
					)
					(arc
						(start 341.460836 -214.55126)
						(mid 341.525625 -214.452867)
						(end 341.54618 -214.336884)
					)
					(arc
						(start 341.54618 -214.336884)
						(mid 341.54298 -214.315875)
						(end 341.531448 -214.298022)
					)
					(arc
						(start 341.531448 -214.298022)
						(mid 341.495544 -214.283262)
						(end 341.459566 -214.298022)
					)
					(arc
						(start 341.459566 -214.298022)
						(mid 341.450824 -214.309843)
						(end 341.44585 -214.323676)
					)
					(xy 341.44585 -214.344504) (xy 341.44585 -214.344758)
					(arc
						(start 341.44585 -214.345774)
						(mid 341.431012 -214.418479)
						(end 341.389716 -214.48014)
					)
					(arc
						(start 341.389716 -214.48014)
						(mid 341.254334 -214.536217)
						(end 341.118952 -214.48014)
					)
					(arc
						(start 341.118952 -214.48014)
						(mid 341.077303 -214.417674)
						(end 341.062818 -214.343996)
					)
					(xy 341.063072 -214.343488)
					(arc
						(start 341.063072 -214.322914)
						(mid 341.058016 -214.308916)
						(end 341.049102 -214.297006)
					)
				)
			)
		)
		(zone
			(layer "F.Cu")
			(hatch none 0.5)
			(connect_pads
				(clearance 0)
			)
			(min_thickness 0.25)
			(keepout
				(tracks not_allowed)
				(vias allowed)
				(pads allowed)
				(copperpour not_allowed)
				(footprints allowed)
			)
			(placement
				(enabled no)
				(sheetname "")
			)
			(fill
				(thermal_gap 0.5)
				(thermal_bridge_width 0.5)
				(island_removal_mode 0)
			)
			(polygon
				(pts
					(arc
						(start 341.099394 -289.242754)
						(mid 341.135372 -289.257694)
						(end 341.171276 -289.242754)
					)
					(arc
						(start 341.171276 -289.242754)
						(mid 341.182675 -289.225514)
						(end 341.186262 -289.205162)
					)
					(arc
						(start 341.186262 -289.205162)
						(mid 341.165993 -289.087933)
						(end 341.100664 -288.9885)
					)
					(arc
						(start 341.100664 -288.9885)
						(mid 340.894162 -288.902964)
						(end 340.68766 -288.9885)
					)
					(arc
						(start 340.68766 -288.9885)
						(mid 340.622871 -289.086893)
						(end 340.602316 -289.202876)
					)
					(arc
						(start 340.602316 -289.202876)
						(mid 340.605516 -289.223885)
						(end 340.617048 -289.241738)
					)
					(arc
						(start 340.617048 -289.241738)
						(mid 340.653026 -289.256678)
						(end 340.68893 -289.241738)
					)
					(arc
						(start 340.68893 -289.241738)
						(mid 340.697672 -289.229917)
						(end 340.702646 -289.216084)
					)
					(xy 340.702646 -289.195256) (xy 340.702646 -289.195002)
					(arc
						(start 340.702646 -289.193986)
						(mid 340.717484 -289.121281)
						(end 340.75878 -289.05962)
					)
					(arc
						(start 340.75878 -289.05962)
						(mid 340.894162 -289.003543)
						(end 341.029544 -289.05962)
					)
					(arc
						(start 341.029544 -289.05962)
						(mid 341.071193 -289.122086)
						(end 341.085678 -289.195764)
					)
					(xy 341.085424 -289.196272)
					(arc
						(start 341.085424 -289.216846)
						(mid 341.09048 -289.230844)
						(end 341.099394 -289.242754)
					)
				)
			)
		)
		(zone
			(layer "F.Cu")
			(hatch none 0.5)
			(connect_pads
				(clearance 0)
			)
			(min_thickness 0.25)
			(keepout
				(tracks not_allowed)
				(vias allowed)
				(pads allowed)
				(copperpour not_allowed)
				(footprints allowed)
			)
			(placement
				(enabled no)
				(sheetname "")
			)
			(fill
				(thermal_gap 0.5)
				(thermal_bridge_width 0.5)
				(island_removal_mode 0)
			)
			(polygon
				(pts
					(arc
						(start 341.988902 -214.297006)
						(mid 341.952998 -214.282246)
						(end 341.91702 -214.297006)
					)
					(arc
						(start 341.91702 -214.297006)
						(mid 341.905621 -214.314246)
						(end 341.902034 -214.334598)
					)
					(arc
						(start 341.902034 -214.334598)
						(mid 341.922303 -214.451827)
						(end 341.987632 -214.55126)
					)
					(arc
						(start 341.987632 -214.55126)
						(mid 342.194134 -214.636796)
						(end 342.400636 -214.55126)
					)
					(arc
						(start 342.400636 -214.55126)
						(mid 342.465425 -214.452867)
						(end 342.48598 -214.336884)
					)
					(arc
						(start 342.48598 -214.336884)
						(mid 342.48278 -214.315875)
						(end 342.471248 -214.298022)
					)
					(arc
						(start 342.471248 -214.298022)
						(mid 342.435344 -214.283262)
						(end 342.399366 -214.298022)
					)
					(arc
						(start 342.399366 -214.298022)
						(mid 342.390624 -214.309843)
						(end 342.38565 -214.323676)
					)
					(xy 342.38565 -214.344504) (xy 342.38565 -214.344758)
					(arc
						(start 342.38565 -214.345774)
						(mid 342.370812 -214.418479)
						(end 342.329516 -214.48014)
					)
					(arc
						(start 342.329516 -214.48014)
						(mid 342.194134 -214.536217)
						(end 342.058752 -214.48014)
					)
					(arc
						(start 342.058752 -214.48014)
						(mid 342.017103 -214.417674)
						(end 342.002618 -214.343996)
					)
					(xy 342.002872 -214.343488)
					(arc
						(start 342.002872 -214.322914)
						(mid 341.997816 -214.308916)
						(end 341.988902 -214.297006)
					)
				)
			)
		)
		(zone
			(layer "F.Cu")
			(hatch none 0.5)
			(connect_pads
				(clearance 0)
			)
			(min_thickness 0.25)
			(keepout
				(tracks not_allowed)
				(vias allowed)
				(pads allowed)
				(copperpour not_allowed)
				(footprints allowed)
			)
			(placement
				(enabled no)
				(sheetname "")
			)
			(fill
				(thermal_gap 0.5)
				(thermal_bridge_width 0.5)
				(island_removal_mode 0)
			)
			(polygon
				(pts
					(arc
						(start 342.039194 -289.242754)
						(mid 342.075172 -289.257694)
						(end 342.111076 -289.242754)
					)
					(arc
						(start 342.111076 -289.242754)
						(mid 342.122475 -289.225514)
						(end 342.126062 -289.205162)
					)
					(arc
						(start 342.126062 -289.205162)
						(mid 342.105793 -289.087933)
						(end 342.040464 -288.9885)
					)
					(arc
						(start 342.040464 -288.9885)
						(mid 341.833962 -288.902964)
						(end 341.62746 -288.9885)
					)
					(arc
						(start 341.62746 -288.9885)
						(mid 341.562671 -289.086893)
						(end 341.542116 -289.202876)
					)
					(arc
						(start 341.542116 -289.202876)
						(mid 341.545316 -289.223885)
						(end 341.556848 -289.241738)
					)
					(arc
						(start 341.556848 -289.241738)
						(mid 341.592826 -289.256678)
						(end 341.62873 -289.241738)
					)
					(arc
						(start 341.62873 -289.241738)
						(mid 341.637472 -289.229917)
						(end 341.642446 -289.216084)
					)
					(xy 341.642446 -289.195256) (xy 341.642446 -289.195002)
					(arc
						(start 341.642446 -289.193986)
						(mid 341.657284 -289.121281)
						(end 341.69858 -289.05962)
					)
					(arc
						(start 341.69858 -289.05962)
						(mid 341.833962 -289.003543)
						(end 341.969344 -289.05962)
					)
					(arc
						(start 341.969344 -289.05962)
						(mid 342.010993 -289.122086)
						(end 342.025478 -289.195764)
					)
					(xy 342.025224 -289.196272)
					(arc
						(start 342.025224 -289.216846)
						(mid 342.03028 -289.230844)
						(end 342.039194 -289.242754)
					)
				)
			)
		)
		(zone
			(layer "F.Cu")
			(hatch none 0.5)
			(connect_pads
				(clearance 0)
			)
			(min_thickness 0.25)
			(keepout
				(tracks not_allowed)
				(vias allowed)
				(pads allowed)
				(copperpour not_allowed)
				(footprints allowed)
			)
			(placement
				(enabled no)
				(sheetname "")
			)
			(fill
				(thermal_gap 0.5)
				(thermal_bridge_width 0.5)
				(island_removal_mode 0)
			)
			(polygon
				(pts
					(arc
						(start 342.928702 -214.297006)
						(mid 342.892798 -214.282246)
						(end 342.85682 -214.297006)
					)
					(arc
						(start 342.85682 -214.297006)
						(mid 342.845421 -214.314246)
						(end 342.841834 -214.334598)
					)
					(arc
						(start 342.841834 -214.334598)
						(mid 342.862103 -214.451827)
						(end 342.927432 -214.55126)
					)
					(arc
						(start 342.927432 -214.55126)
						(mid 343.133934 -214.636796)
						(end 343.340436 -214.55126)
					)
					(arc
						(start 343.340436 -214.55126)
						(mid 343.405225 -214.452867)
						(end 343.42578 -214.336884)
					)
					(arc
						(start 343.42578 -214.336884)
						(mid 343.42258 -214.315875)
						(end 343.411048 -214.298022)
					)
					(arc
						(start 343.411048 -214.298022)
						(mid 343.375144 -214.283262)
						(end 343.339166 -214.298022)
					)
					(arc
						(start 343.339166 -214.298022)
						(mid 343.330424 -214.309843)
						(end 343.32545 -214.323676)
					)
					(xy 343.32545 -214.344504) (xy 343.32545 -214.344758)
					(arc
						(start 343.32545 -214.345774)
						(mid 343.310612 -214.418479)
						(end 343.269316 -214.48014)
					)
					(arc
						(start 343.269316 -214.48014)
						(mid 343.133934 -214.536217)
						(end 342.998552 -214.48014)
					)
					(arc
						(start 342.998552 -214.48014)
						(mid 342.956903 -214.417674)
						(end 342.942418 -214.343996)
					)
					(xy 342.942672 -214.343488)
					(arc
						(start 342.942672 -214.322914)
						(mid 342.937616 -214.308916)
						(end 342.928702 -214.297006)
					)
				)
			)
		)
		(zone
			(layer "F.Cu")
			(hatch none 0.5)
			(connect_pads
				(clearance 0)
			)
			(min_thickness 0.25)
			(keepout
				(tracks not_allowed)
				(vias allowed)
				(pads allowed)
				(copperpour not_allowed)
				(footprints allowed)
			)
			(placement
				(enabled no)
				(sheetname "")
			)
			(fill
				(thermal_gap 0.5)
				(thermal_bridge_width 0.5)
				(island_removal_mode 0)
			)
			(polygon
				(pts
					(arc
						(start 342.978994 -289.242754)
						(mid 343.014972 -289.257694)
						(end 343.050876 -289.242754)
					)
					(arc
						(start 343.050876 -289.242754)
						(mid 343.062275 -289.225514)
						(end 343.065862 -289.205162)
					)
					(arc
						(start 343.065862 -289.205162)
						(mid 343.045593 -289.087933)
						(end 342.980264 -288.9885)
					)
					(arc
						(start 342.980264 -288.9885)
						(mid 342.773762 -288.902964)
						(end 342.56726 -288.9885)
					)
					(arc
						(start 342.56726 -288.9885)
						(mid 342.502471 -289.086893)
						(end 342.481916 -289.202876)
					)
					(arc
						(start 342.481916 -289.202876)
						(mid 342.485116 -289.223885)
						(end 342.496648 -289.241738)
					)
					(arc
						(start 342.496648 -289.241738)
						(mid 342.532626 -289.256678)
						(end 342.56853 -289.241738)
					)
					(arc
						(start 342.56853 -289.241738)
						(mid 342.577272 -289.229917)
						(end 342.582246 -289.216084)
					)
					(xy 342.582246 -289.195256) (xy 342.582246 -289.195002)
					(arc
						(start 342.582246 -289.193986)
						(mid 342.597084 -289.121281)
						(end 342.63838 -289.05962)
					)
					(arc
						(start 342.63838 -289.05962)
						(mid 342.773762 -289.003543)
						(end 342.909144 -289.05962)
					)
					(arc
						(start 342.909144 -289.05962)
						(mid 342.950793 -289.122086)
						(end 342.965278 -289.195764)
					)
					(xy 342.965024 -289.196272)
					(arc
						(start 342.965024 -289.216846)
						(mid 342.97008 -289.230844)
						(end 342.978994 -289.242754)
					)
				)
			)
		)
		(zone
			(layer "F.Cu")
			(hatch none 0.5)
			(connect_pads
				(clearance 0)
			)
			(min_thickness 0.25)
			(keepout
				(tracks not_allowed)
				(vias allowed)
				(pads allowed)
				(copperpour not_allowed)
				(footprints allowed)
			)
			(placement
				(enabled no)
				(sheetname "")
			)
			(fill
				(thermal_gap 0.5)
				(thermal_bridge_width 0.5)
				(island_removal_mode 0)
			)
			(polygon
				(pts
					(arc
						(start 343.868502 -214.297006)
						(mid 343.832598 -214.282246)
						(end 343.79662 -214.297006)
					)
					(arc
						(start 343.79662 -214.297006)
						(mid 343.785221 -214.314246)
						(end 343.781634 -214.334598)
					)
					(arc
						(start 343.781634 -214.334598)
						(mid 343.801903 -214.451827)
						(end 343.867232 -214.55126)
					)
					(arc
						(start 343.867232 -214.55126)
						(mid 344.073734 -214.636796)
						(end 344.280236 -214.55126)
					)
					(arc
						(start 344.280236 -214.55126)
						(mid 344.345025 -214.452867)
						(end 344.36558 -214.336884)
					)
					(arc
						(start 344.36558 -214.336884)
						(mid 344.36238 -214.315875)
						(end 344.350848 -214.298022)
					)
					(arc
						(start 344.350848 -214.298022)
						(mid 344.314944 -214.283262)
						(end 344.278966 -214.298022)
					)
					(arc
						(start 344.278966 -214.298022)
						(mid 344.270224 -214.309843)
						(end 344.26525 -214.323676)
					)
					(xy 344.26525 -214.344504) (xy 344.26525 -214.344758)
					(arc
						(start 344.26525 -214.345774)
						(mid 344.250412 -214.418479)
						(end 344.209116 -214.48014)
					)
					(arc
						(start 344.209116 -214.48014)
						(mid 344.073734 -214.536217)
						(end 343.938352 -214.48014)
					)
					(arc
						(start 343.938352 -214.48014)
						(mid 343.896703 -214.417674)
						(end 343.882218 -214.343996)
					)
					(xy 343.882472 -214.343488)
					(arc
						(start 343.882472 -214.322914)
						(mid 343.877416 -214.308916)
						(end 343.868502 -214.297006)
					)
				)
			)
		)
		(zone
			(layer "F.Cu")
			(hatch none 0.5)
			(connect_pads
				(clearance 0)
			)
			(min_thickness 0.25)
			(keepout
				(tracks not_allowed)
				(vias allowed)
				(pads allowed)
				(copperpour not_allowed)
				(footprints allowed)
			)
			(placement
				(enabled no)
				(sheetname "")
			)
			(fill
				(thermal_gap 0.5)
				(thermal_bridge_width 0.5)
				(island_removal_mode 0)
			)
			(polygon
				(pts
					(arc
						(start 343.918794 -289.242754)
						(mid 343.954772 -289.257694)
						(end 343.990676 -289.242754)
					)
					(arc
						(start 343.990676 -289.242754)
						(mid 344.002075 -289.225514)
						(end 344.005662 -289.205162)
					)
					(arc
						(start 344.005662 -289.205162)
						(mid 343.985393 -289.087933)
						(end 343.920064 -288.9885)
					)
					(arc
						(start 343.920064 -288.9885)
						(mid 343.713562 -288.902964)
						(end 343.50706 -288.9885)
					)
					(arc
						(start 343.50706 -288.9885)
						(mid 343.442271 -289.086893)
						(end 343.421716 -289.202876)
					)
					(arc
						(start 343.421716 -289.202876)
						(mid 343.424916 -289.223885)
						(end 343.436448 -289.241738)
					)
					(arc
						(start 343.436448 -289.241738)
						(mid 343.472426 -289.256678)
						(end 343.50833 -289.241738)
					)
					(arc
						(start 343.50833 -289.241738)
						(mid 343.517072 -289.229917)
						(end 343.522046 -289.216084)
					)
					(xy 343.522046 -289.195256) (xy 343.522046 -289.195002)
					(arc
						(start 343.522046 -289.193986)
						(mid 343.536884 -289.121281)
						(end 343.57818 -289.05962)
					)
					(arc
						(start 343.57818 -289.05962)
						(mid 343.713562 -289.003543)
						(end 343.848944 -289.05962)
					)
					(arc
						(start 343.848944 -289.05962)
						(mid 343.890593 -289.122086)
						(end 343.905078 -289.195764)
					)
					(xy 343.904824 -289.196272)
					(arc
						(start 343.904824 -289.216846)
						(mid 343.90988 -289.230844)
						(end 343.918794 -289.242754)
					)
				)
			)
		)
		(zone
			(layer "F.Cu")
			(hatch none 0.5)
			(connect_pads
				(clearance 0)
			)
			(min_thickness 0.25)
			(keepout
				(tracks not_allowed)
				(vias allowed)
				(pads allowed)
				(copperpour not_allowed)
				(footprints allowed)
			)
			(placement
				(enabled no)
				(sheetname "")
			)
			(fill
				(thermal_gap 0.5)
				(thermal_bridge_width 0.5)
				(island_removal_mode 0)
			)
			(polygon
				(pts
					(arc
						(start 344.808302 -214.297006)
						(mid 344.772398 -214.282246)
						(end 344.73642 -214.297006)
					)
					(arc
						(start 344.73642 -214.297006)
						(mid 344.725021 -214.314246)
						(end 344.721434 -214.334598)
					)
					(arc
						(start 344.721434 -214.334598)
						(mid 344.741703 -214.451827)
						(end 344.807032 -214.55126)
					)
					(arc
						(start 344.807032 -214.55126)
						(mid 345.013534 -214.636796)
						(end 345.220036 -214.55126)
					)
					(arc
						(start 345.220036 -214.55126)
						(mid 345.284825 -214.452867)
						(end 345.30538 -214.336884)
					)
					(arc
						(start 345.30538 -214.336884)
						(mid 345.30218 -214.315875)
						(end 345.290648 -214.298022)
					)
					(arc
						(start 345.290648 -214.298022)
						(mid 345.254744 -214.283262)
						(end 345.218766 -214.298022)
					)
					(arc
						(start 345.218766 -214.298022)
						(mid 345.210024 -214.309843)
						(end 345.20505 -214.323676)
					)
					(xy 345.20505 -214.344504) (xy 345.20505 -214.344758)
					(arc
						(start 345.20505 -214.345774)
						(mid 345.190212 -214.418479)
						(end 345.148916 -214.48014)
					)
					(arc
						(start 345.148916 -214.48014)
						(mid 345.013534 -214.536217)
						(end 344.878152 -214.48014)
					)
					(arc
						(start 344.878152 -214.48014)
						(mid 344.836503 -214.417674)
						(end 344.822018 -214.343996)
					)
					(xy 344.822272 -214.343488)
					(arc
						(start 344.822272 -214.322914)
						(mid 344.817216 -214.308916)
						(end 344.808302 -214.297006)
					)
				)
			)
		)
		(zone
			(layer "F.Cu")
			(hatch none 0.5)
			(connect_pads
				(clearance 0)
			)
			(min_thickness 0.25)
			(keepout
				(tracks not_allowed)
				(vias allowed)
				(pads allowed)
				(copperpour not_allowed)
				(footprints allowed)
			)
			(placement
				(enabled no)
				(sheetname "")
			)
			(fill
				(thermal_gap 0.5)
				(thermal_bridge_width 0.5)
				(island_removal_mode 0)
			)
			(polygon
				(pts
					(arc
						(start 344.858594 -289.242754)
						(mid 344.894572 -289.257694)
						(end 344.930476 -289.242754)
					)
					(arc
						(start 344.930476 -289.242754)
						(mid 344.941875 -289.225514)
						(end 344.945462 -289.205162)
					)
					(arc
						(start 344.945462 -289.205162)
						(mid 344.925193 -289.087933)
						(end 344.859864 -288.9885)
					)
					(arc
						(start 344.859864 -288.9885)
						(mid 344.653362 -288.902964)
						(end 344.44686 -288.9885)
					)
					(arc
						(start 344.44686 -288.9885)
						(mid 344.382071 -289.086893)
						(end 344.361516 -289.202876)
					)
					(arc
						(start 344.361516 -289.202876)
						(mid 344.364716 -289.223885)
						(end 344.376248 -289.241738)
					)
					(arc
						(start 344.376248 -289.241738)
						(mid 344.412226 -289.256678)
						(end 344.44813 -289.241738)
					)
					(arc
						(start 344.44813 -289.241738)
						(mid 344.456872 -289.229917)
						(end 344.461846 -289.216084)
					)
					(xy 344.461846 -289.195256) (xy 344.461846 -289.195002)
					(arc
						(start 344.461846 -289.193986)
						(mid 344.476684 -289.121281)
						(end 344.51798 -289.05962)
					)
					(arc
						(start 344.51798 -289.05962)
						(mid 344.653362 -289.003543)
						(end 344.788744 -289.05962)
					)
					(arc
						(start 344.788744 -289.05962)
						(mid 344.830393 -289.122086)
						(end 344.844878 -289.195764)
					)
					(xy 344.844624 -289.196272)
					(arc
						(start 344.844624 -289.216846)
						(mid 344.84968 -289.230844)
						(end 344.858594 -289.242754)
					)
				)
			)
		)
		(zone
			(layer "F.Cu")
			(hatch none 0.5)
			(connect_pads
				(clearance 0)
			)
			(min_thickness 0.25)
			(keepout
				(tracks not_allowed)
				(vias allowed)
				(pads allowed)
				(copperpour not_allowed)
				(footprints allowed)
			)
			(placement
				(enabled no)
				(sheetname "")
			)
			(fill
				(thermal_gap 0.5)
				(thermal_bridge_width 0.5)
				(island_removal_mode 0)
			)
			(polygon
				(pts
					(arc
						(start 345.748102 -214.297006)
						(mid 345.712198 -214.282246)
						(end 345.67622 -214.297006)
					)
					(arc
						(start 345.67622 -214.297006)
						(mid 345.664821 -214.314246)
						(end 345.661234 -214.334598)
					)
					(arc
						(start 345.661234 -214.334598)
						(mid 345.681503 -214.451827)
						(end 345.746832 -214.55126)
					)
					(arc
						(start 345.746832 -214.55126)
						(mid 345.953334 -214.636796)
						(end 346.159836 -214.55126)
					)
					(arc
						(start 346.159836 -214.55126)
						(mid 346.224625 -214.452867)
						(end 346.24518 -214.336884)
					)
					(arc
						(start 346.24518 -214.336884)
						(mid 346.24198 -214.315875)
						(end 346.230448 -214.298022)
					)
					(arc
						(start 346.230448 -214.298022)
						(mid 346.194544 -214.283262)
						(end 346.158566 -214.298022)
					)
					(arc
						(start 346.158566 -214.298022)
						(mid 346.149824 -214.309843)
						(end 346.14485 -214.323676)
					)
					(xy 346.14485 -214.344504) (xy 346.14485 -214.344758)
					(arc
						(start 346.14485 -214.345774)
						(mid 346.130012 -214.418479)
						(end 346.088716 -214.48014)
					)
					(arc
						(start 346.088716 -214.48014)
						(mid 345.953334 -214.536217)
						(end 345.817952 -214.48014)
					)
					(arc
						(start 345.817952 -214.48014)
						(mid 345.776303 -214.417674)
						(end 345.761818 -214.343996)
					)
					(xy 345.762072 -214.343488)
					(arc
						(start 345.762072 -214.322914)
						(mid 345.757016 -214.308916)
						(end 345.748102 -214.297006)
					)
				)
			)
		)
		(zone
			(layer "F.Cu")
			(hatch none 0.5)
			(connect_pads
				(clearance 0)
			)
			(min_thickness 0.25)
			(keepout
				(tracks not_allowed)
				(vias allowed)
				(pads allowed)
				(copperpour not_allowed)
				(footprints allowed)
			)
			(placement
				(enabled no)
				(sheetname "")
			)
			(fill
				(thermal_gap 0.5)
				(thermal_bridge_width 0.5)
				(island_removal_mode 0)
			)
			(polygon
				(pts
					(arc
						(start 345.798394 -289.242754)
						(mid 345.834372 -289.257694)
						(end 345.870276 -289.242754)
					)
					(arc
						(start 345.870276 -289.242754)
						(mid 345.881675 -289.225514)
						(end 345.885262 -289.205162)
					)
					(arc
						(start 345.885262 -289.205162)
						(mid 345.864993 -289.087933)
						(end 345.799664 -288.9885)
					)
					(arc
						(start 345.799664 -288.9885)
						(mid 345.593162 -288.902964)
						(end 345.38666 -288.9885)
					)
					(arc
						(start 345.38666 -288.9885)
						(mid 345.321871 -289.086893)
						(end 345.301316 -289.202876)
					)
					(arc
						(start 345.301316 -289.202876)
						(mid 345.304516 -289.223885)
						(end 345.316048 -289.241738)
					)
					(arc
						(start 345.316048 -289.241738)
						(mid 345.352026 -289.256678)
						(end 345.38793 -289.241738)
					)
					(arc
						(start 345.38793 -289.241738)
						(mid 345.396672 -289.229917)
						(end 345.401646 -289.216084)
					)
					(xy 345.401646 -289.195256) (xy 345.401646 -289.195002)
					(arc
						(start 345.401646 -289.193986)
						(mid 345.416484 -289.121281)
						(end 345.45778 -289.05962)
					)
					(arc
						(start 345.45778 -289.05962)
						(mid 345.593162 -289.003543)
						(end 345.728544 -289.05962)
					)
					(arc
						(start 345.728544 -289.05962)
						(mid 345.770193 -289.122086)
						(end 345.784678 -289.195764)
					)
					(xy 345.784424 -289.196272)
					(arc
						(start 345.784424 -289.216846)
						(mid 345.78948 -289.230844)
						(end 345.798394 -289.242754)
					)
				)
			)
		)
		(zone
			(layer "F.Cu")
			(hatch none 0.5)
			(connect_pads
				(clearance 0)
			)
			(min_thickness 0.25)
			(keepout
				(tracks not_allowed)
				(vias allowed)
				(pads allowed)
				(copperpour not_allowed)
				(footprints allowed)
			)
			(placement
				(enabled no)
				(sheetname "")
			)
			(fill
				(thermal_gap 0.5)
				(thermal_bridge_width 0.5)
				(island_removal_mode 0)
			)
			(polygon
				(pts
					(arc
						(start 346.687902 -214.297006)
						(mid 346.651998 -214.282246)
						(end 346.61602 -214.297006)
					)
					(arc
						(start 346.61602 -214.297006)
						(mid 346.604621 -214.314246)
						(end 346.601034 -214.334598)
					)
					(arc
						(start 346.601034 -214.334598)
						(mid 346.621303 -214.451827)
						(end 346.686632 -214.55126)
					)
					(arc
						(start 346.686632 -214.55126)
						(mid 346.893134 -214.636796)
						(end 347.099636 -214.55126)
					)
					(arc
						(start 347.099636 -214.55126)
						(mid 347.164425 -214.452867)
						(end 347.18498 -214.336884)
					)
					(arc
						(start 347.18498 -214.336884)
						(mid 347.18178 -214.315875)
						(end 347.170248 -214.298022)
					)
					(arc
						(start 347.170248 -214.298022)
						(mid 347.134344 -214.283262)
						(end 347.098366 -214.298022)
					)
					(arc
						(start 347.098366 -214.298022)
						(mid 347.089624 -214.309843)
						(end 347.08465 -214.323676)
					)
					(xy 347.08465 -214.344504) (xy 347.08465 -214.344758)
					(arc
						(start 347.08465 -214.345774)
						(mid 347.069812 -214.418479)
						(end 347.028516 -214.48014)
					)
					(arc
						(start 347.028516 -214.48014)
						(mid 346.893134 -214.536217)
						(end 346.757752 -214.48014)
					)
					(arc
						(start 346.757752 -214.48014)
						(mid 346.716103 -214.417674)
						(end 346.701618 -214.343996)
					)
					(xy 346.701872 -214.343488)
					(arc
						(start 346.701872 -214.322914)
						(mid 346.696816 -214.308916)
						(end 346.687902 -214.297006)
					)
				)
			)
		)
		(zone
			(layer "F.Cu")
			(hatch none 0.5)
			(connect_pads
				(clearance 0)
			)
			(min_thickness 0.25)
			(keepout
				(tracks not_allowed)
				(vias allowed)
				(pads allowed)
				(copperpour not_allowed)
				(footprints allowed)
			)
			(placement
				(enabled no)
				(sheetname "")
			)
			(fill
				(thermal_gap 0.5)
				(thermal_bridge_width 0.5)
				(island_removal_mode 0)
			)
			(polygon
				(pts
					(arc
						(start 346.738194 -289.242754)
						(mid 346.774172 -289.257694)
						(end 346.810076 -289.242754)
					)
					(arc
						(start 346.810076 -289.242754)
						(mid 346.821475 -289.225514)
						(end 346.825062 -289.205162)
					)
					(arc
						(start 346.825062 -289.205162)
						(mid 346.804793 -289.087933)
						(end 346.739464 -288.9885)
					)
					(arc
						(start 346.739464 -288.9885)
						(mid 346.532962 -288.902964)
						(end 346.32646 -288.9885)
					)
					(arc
						(start 346.32646 -288.9885)
						(mid 346.261671 -289.086893)
						(end 346.241116 -289.202876)
					)
					(arc
						(start 346.241116 -289.202876)
						(mid 346.244316 -289.223885)
						(end 346.255848 -289.241738)
					)
					(arc
						(start 346.255848 -289.241738)
						(mid 346.291826 -289.256678)
						(end 346.32773 -289.241738)
					)
					(arc
						(start 346.32773 -289.241738)
						(mid 346.336472 -289.229917)
						(end 346.341446 -289.216084)
					)
					(xy 346.341446 -289.195256) (xy 346.341446 -289.195002)
					(arc
						(start 346.341446 -289.193986)
						(mid 346.356284 -289.121281)
						(end 346.39758 -289.05962)
					)
					(arc
						(start 346.39758 -289.05962)
						(mid 346.532962 -289.003543)
						(end 346.668344 -289.05962)
					)
					(arc
						(start 346.668344 -289.05962)
						(mid 346.709993 -289.122086)
						(end 346.724478 -289.195764)
					)
					(xy 346.724224 -289.196272)
					(arc
						(start 346.724224 -289.216846)
						(mid 346.72928 -289.230844)
						(end 346.738194 -289.242754)
					)
				)
			)
		)
		(zone
			(layer "F.Cu")
			(hatch none 0.5)
			(connect_pads
				(clearance 0)
			)
			(min_thickness 0.25)
			(keepout
				(tracks not_allowed)
				(vias allowed)
				(pads allowed)
				(copperpour not_allowed)
				(footprints allowed)
			)
			(placement
				(enabled no)
				(sheetname "")
			)
			(fill
				(thermal_gap 0.5)
				(thermal_bridge_width 0.5)
				(island_removal_mode 0)
			)
			(polygon
				(pts
					(arc
						(start 347.627702 -214.297006)
						(mid 347.591798 -214.282246)
						(end 347.55582 -214.297006)
					)
					(arc
						(start 347.55582 -214.297006)
						(mid 347.544421 -214.314246)
						(end 347.540834 -214.334598)
					)
					(arc
						(start 347.540834 -214.334598)
						(mid 347.561103 -214.451827)
						(end 347.626432 -214.55126)
					)
					(arc
						(start 347.626432 -214.55126)
						(mid 347.832934 -214.636796)
						(end 348.039436 -214.55126)
					)
					(arc
						(start 348.039436 -214.55126)
						(mid 348.104225 -214.452867)
						(end 348.12478 -214.336884)
					)
					(arc
						(start 348.12478 -214.336884)
						(mid 348.12158 -214.315875)
						(end 348.110048 -214.298022)
					)
					(arc
						(start 348.110048 -214.298022)
						(mid 348.074144 -214.283262)
						(end 348.038166 -214.298022)
					)
					(arc
						(start 348.038166 -214.298022)
						(mid 348.029424 -214.309843)
						(end 348.02445 -214.323676)
					)
					(xy 348.02445 -214.344504) (xy 348.02445 -214.344758)
					(arc
						(start 348.02445 -214.345774)
						(mid 348.009612 -214.418479)
						(end 347.968316 -214.48014)
					)
					(arc
						(start 347.968316 -214.48014)
						(mid 347.832934 -214.536217)
						(end 347.697552 -214.48014)
					)
					(arc
						(start 347.697552 -214.48014)
						(mid 347.655903 -214.417674)
						(end 347.641418 -214.343996)
					)
					(xy 347.641672 -214.343488)
					(arc
						(start 347.641672 -214.322914)
						(mid 347.636616 -214.308916)
						(end 347.627702 -214.297006)
					)
				)
			)
		)
		(zone
			(layer "F.Cu")
			(hatch none 0.5)
			(connect_pads
				(clearance 0)
			)
			(min_thickness 0.25)
			(keepout
				(tracks not_allowed)
				(vias allowed)
				(pads allowed)
				(copperpour not_allowed)
				(footprints allowed)
			)
			(placement
				(enabled no)
				(sheetname "")
			)
			(fill
				(thermal_gap 0.5)
				(thermal_bridge_width 0.5)
				(island_removal_mode 0)
			)
			(polygon
				(pts
					(arc
						(start 347.677994 -289.242754)
						(mid 347.713972 -289.257694)
						(end 347.749876 -289.242754)
					)
					(arc
						(start 347.749876 -289.242754)
						(mid 347.761275 -289.225514)
						(end 347.764862 -289.205162)
					)
					(arc
						(start 347.764862 -289.205162)
						(mid 347.744593 -289.087933)
						(end 347.679264 -288.9885)
					)
					(arc
						(start 347.679264 -288.9885)
						(mid 347.472762 -288.902964)
						(end 347.26626 -288.9885)
					)
					(arc
						(start 347.26626 -288.9885)
						(mid 347.201471 -289.086893)
						(end 347.180916 -289.202876)
					)
					(arc
						(start 347.180916 -289.202876)
						(mid 347.184116 -289.223885)
						(end 347.195648 -289.241738)
					)
					(arc
						(start 347.195648 -289.241738)
						(mid 347.231626 -289.256678)
						(end 347.26753 -289.241738)
					)
					(arc
						(start 347.26753 -289.241738)
						(mid 347.276272 -289.229917)
						(end 347.281246 -289.216084)
					)
					(xy 347.281246 -289.195256) (xy 347.281246 -289.195002)
					(arc
						(start 347.281246 -289.193986)
						(mid 347.296084 -289.121281)
						(end 347.33738 -289.05962)
					)
					(arc
						(start 347.33738 -289.05962)
						(mid 347.472762 -289.003543)
						(end 347.608144 -289.05962)
					)
					(arc
						(start 347.608144 -289.05962)
						(mid 347.649793 -289.122086)
						(end 347.664278 -289.195764)
					)
					(xy 347.664024 -289.196272)
					(arc
						(start 347.664024 -289.216846)
						(mid 347.66908 -289.230844)
						(end 347.677994 -289.242754)
					)
				)
			)
		)
		(zone
			(layer "F.Cu")
			(hatch none 0.5)
			(connect_pads
				(clearance 0)
			)
			(min_thickness 0.25)
			(keepout
				(tracks not_allowed)
				(vias allowed)
				(pads allowed)
				(copperpour not_allowed)
				(footprints allowed)
			)
			(placement
				(enabled no)
				(sheetname "")
			)
			(fill
				(thermal_gap 0.5)
				(thermal_bridge_width 0.5)
				(island_removal_mode 0)
			)
			(polygon
				(pts
					(arc
						(start 348.567502 -214.297006)
						(mid 348.531598 -214.282246)
						(end 348.49562 -214.297006)
					)
					(arc
						(start 348.49562 -214.297006)
						(mid 348.484221 -214.314246)
						(end 348.480634 -214.334598)
					)
					(arc
						(start 348.480634 -214.334598)
						(mid 348.500903 -214.451827)
						(end 348.566232 -214.55126)
					)
					(arc
						(start 348.566232 -214.55126)
						(mid 348.772734 -214.636796)
						(end 348.979236 -214.55126)
					)
					(arc
						(start 348.979236 -214.55126)
						(mid 349.044025 -214.452867)
						(end 349.06458 -214.336884)
					)
					(arc
						(start 349.06458 -214.336884)
						(mid 349.06138 -214.315875)
						(end 349.049848 -214.298022)
					)
					(arc
						(start 349.049848 -214.298022)
						(mid 349.013944 -214.283262)
						(end 348.977966 -214.298022)
					)
					(arc
						(start 348.977966 -214.298022)
						(mid 348.969224 -214.309843)
						(end 348.96425 -214.323676)
					)
					(xy 348.96425 -214.344504) (xy 348.96425 -214.344758)
					(arc
						(start 348.96425 -214.345774)
						(mid 348.949412 -214.418479)
						(end 348.908116 -214.48014)
					)
					(arc
						(start 348.908116 -214.48014)
						(mid 348.772734 -214.536217)
						(end 348.637352 -214.48014)
					)
					(arc
						(start 348.637352 -214.48014)
						(mid 348.595703 -214.417674)
						(end 348.581218 -214.343996)
					)
					(xy 348.581472 -214.343488)
					(arc
						(start 348.581472 -214.322914)
						(mid 348.576416 -214.308916)
						(end 348.567502 -214.297006)
					)
				)
			)
		)
		(zone
			(layer "F.Cu")
			(hatch none 0.5)
			(connect_pads
				(clearance 0)
			)
			(min_thickness 0.25)
			(keepout
				(tracks not_allowed)
				(vias allowed)
				(pads allowed)
				(copperpour not_allowed)
				(footprints allowed)
			)
			(placement
				(enabled no)
				(sheetname "")
			)
			(fill
				(thermal_gap 0.5)
				(thermal_bridge_width 0.5)
				(island_removal_mode 0)
			)
			(polygon
				(pts
					(arc
						(start 348.617794 -289.242754)
						(mid 348.653772 -289.257694)
						(end 348.689676 -289.242754)
					)
					(arc
						(start 348.689676 -289.242754)
						(mid 348.701075 -289.225514)
						(end 348.704662 -289.205162)
					)
					(arc
						(start 348.704662 -289.205162)
						(mid 348.684393 -289.087933)
						(end 348.619064 -288.9885)
					)
					(arc
						(start 348.619064 -288.9885)
						(mid 348.412562 -288.902964)
						(end 348.20606 -288.9885)
					)
					(arc
						(start 348.20606 -288.9885)
						(mid 348.141271 -289.086893)
						(end 348.120716 -289.202876)
					)
					(arc
						(start 348.120716 -289.202876)
						(mid 348.123916 -289.223885)
						(end 348.135448 -289.241738)
					)
					(arc
						(start 348.135448 -289.241738)
						(mid 348.171426 -289.256678)
						(end 348.20733 -289.241738)
					)
					(arc
						(start 348.20733 -289.241738)
						(mid 348.216072 -289.229917)
						(end 348.221046 -289.216084)
					)
					(xy 348.221046 -289.195256) (xy 348.221046 -289.195002)
					(arc
						(start 348.221046 -289.193986)
						(mid 348.235884 -289.121281)
						(end 348.27718 -289.05962)
					)
					(arc
						(start 348.27718 -289.05962)
						(mid 348.412562 -289.003543)
						(end 348.547944 -289.05962)
					)
					(arc
						(start 348.547944 -289.05962)
						(mid 348.589593 -289.122086)
						(end 348.604078 -289.195764)
					)
					(xy 348.603824 -289.196272)
					(arc
						(start 348.603824 -289.216846)
						(mid 348.60888 -289.230844)
						(end 348.617794 -289.242754)
					)
				)
			)
		)
		(zone
			(layer "F.Cu")
			(hatch none 0.5)
			(connect_pads
				(clearance 0)
			)
			(min_thickness 0.25)
			(keepout
				(tracks not_allowed)
				(vias allowed)
				(pads allowed)
				(copperpour not_allowed)
				(footprints allowed)
			)
			(placement
				(enabled no)
				(sheetname "")
			)
			(fill
				(thermal_gap 0.5)
				(thermal_bridge_width 0.5)
				(island_removal_mode 0)
			)
			(polygon
				(pts
					(arc
						(start 349.507302 -214.297006)
						(mid 349.471398 -214.282246)
						(end 349.43542 -214.297006)
					)
					(arc
						(start 349.43542 -214.297006)
						(mid 349.424021 -214.314246)
						(end 349.420434 -214.334598)
					)
					(arc
						(start 349.420434 -214.334598)
						(mid 349.440703 -214.451827)
						(end 349.506032 -214.55126)
					)
					(arc
						(start 349.506032 -214.55126)
						(mid 349.712534 -214.636796)
						(end 349.919036 -214.55126)
					)
					(arc
						(start 349.919036 -214.55126)
						(mid 349.983825 -214.452867)
						(end 350.00438 -214.336884)
					)
					(arc
						(start 350.00438 -214.336884)
						(mid 350.00118 -214.315875)
						(end 349.989648 -214.298022)
					)
					(arc
						(start 349.989648 -214.298022)
						(mid 349.953744 -214.283262)
						(end 349.917766 -214.298022)
					)
					(arc
						(start 349.917766 -214.298022)
						(mid 349.909024 -214.309843)
						(end 349.90405 -214.323676)
					)
					(xy 349.90405 -214.344504) (xy 349.90405 -214.344758)
					(arc
						(start 349.90405 -214.345774)
						(mid 349.889212 -214.418479)
						(end 349.847916 -214.48014)
					)
					(arc
						(start 349.847916 -214.48014)
						(mid 349.712534 -214.536217)
						(end 349.577152 -214.48014)
					)
					(arc
						(start 349.577152 -214.48014)
						(mid 349.535503 -214.417674)
						(end 349.521018 -214.343996)
					)
					(xy 349.521272 -214.343488)
					(arc
						(start 349.521272 -214.322914)
						(mid 349.516216 -214.308916)
						(end 349.507302 -214.297006)
					)
				)
			)
		)
		(zone
			(layer "F.Cu")
			(hatch none 0.5)
			(connect_pads
				(clearance 0)
			)
			(min_thickness 0.25)
			(keepout
				(tracks not_allowed)
				(vias allowed)
				(pads allowed)
				(copperpour not_allowed)
				(footprints allowed)
			)
			(placement
				(enabled no)
				(sheetname "")
			)
			(fill
				(thermal_gap 0.5)
				(thermal_bridge_width 0.5)
				(island_removal_mode 0)
			)
			(polygon
				(pts
					(arc
						(start 349.557594 -289.242754)
						(mid 349.593572 -289.257694)
						(end 349.629476 -289.242754)
					)
					(arc
						(start 349.629476 -289.242754)
						(mid 349.640875 -289.225514)
						(end 349.644462 -289.205162)
					)
					(arc
						(start 349.644462 -289.205162)
						(mid 349.624193 -289.087933)
						(end 349.558864 -288.9885)
					)
					(arc
						(start 349.558864 -288.9885)
						(mid 349.352362 -288.902964)
						(end 349.14586 -288.9885)
					)
					(arc
						(start 349.14586 -288.9885)
						(mid 349.081071 -289.086893)
						(end 349.060516 -289.202876)
					)
					(arc
						(start 349.060516 -289.202876)
						(mid 349.063716 -289.223885)
						(end 349.075248 -289.241738)
					)
					(arc
						(start 349.075248 -289.241738)
						(mid 349.111226 -289.256678)
						(end 349.14713 -289.241738)
					)
					(arc
						(start 349.14713 -289.241738)
						(mid 349.155872 -289.229917)
						(end 349.160846 -289.216084)
					)
					(xy 349.160846 -289.195256) (xy 349.160846 -289.195002)
					(arc
						(start 349.160846 -289.193986)
						(mid 349.175684 -289.121281)
						(end 349.21698 -289.05962)
					)
					(arc
						(start 349.21698 -289.05962)
						(mid 349.352362 -289.003543)
						(end 349.487744 -289.05962)
					)
					(arc
						(start 349.487744 -289.05962)
						(mid 349.529393 -289.122086)
						(end 349.543878 -289.195764)
					)
					(xy 349.543624 -289.196272)
					(arc
						(start 349.543624 -289.216846)
						(mid 349.54868 -289.230844)
						(end 349.557594 -289.242754)
					)
				)
			)
		)
		(zone
			(layer "F.Cu")
			(hatch none 0.5)
			(connect_pads
				(clearance 0)
			)
			(min_thickness 0.25)
			(keepout
				(tracks not_allowed)
				(vias allowed)
				(pads allowed)
				(copperpour not_allowed)
				(footprints allowed)
			)
			(placement
				(enabled no)
				(sheetname "")
			)
			(fill
				(thermal_gap 0.5)
				(thermal_bridge_width 0.5)
				(island_removal_mode 0)
			)
			(polygon
				(pts
					(arc
						(start 350.447102 -214.297006)
						(mid 350.411198 -214.282246)
						(end 350.37522 -214.297006)
					)
					(arc
						(start 350.37522 -214.297006)
						(mid 350.363821 -214.314246)
						(end 350.360234 -214.334598)
					)
					(arc
						(start 350.360234 -214.334598)
						(mid 350.380503 -214.451827)
						(end 350.445832 -214.55126)
					)
					(arc
						(start 350.445832 -214.55126)
						(mid 350.652334 -214.636796)
						(end 350.858836 -214.55126)
					)
					(arc
						(start 350.858836 -214.55126)
						(mid 350.923625 -214.452867)
						(end 350.94418 -214.336884)
					)
					(arc
						(start 350.94418 -214.336884)
						(mid 350.94098 -214.315875)
						(end 350.929448 -214.298022)
					)
					(arc
						(start 350.929448 -214.298022)
						(mid 350.893544 -214.283262)
						(end 350.857566 -214.298022)
					)
					(arc
						(start 350.857566 -214.298022)
						(mid 350.848824 -214.309843)
						(end 350.84385 -214.323676)
					)
					(xy 350.84385 -214.344504) (xy 350.84385 -214.344758)
					(arc
						(start 350.84385 -214.345774)
						(mid 350.829012 -214.418479)
						(end 350.787716 -214.48014)
					)
					(arc
						(start 350.787716 -214.48014)
						(mid 350.652334 -214.536217)
						(end 350.516952 -214.48014)
					)
					(arc
						(start 350.516952 -214.48014)
						(mid 350.475303 -214.417674)
						(end 350.460818 -214.343996)
					)
					(xy 350.461072 -214.343488)
					(arc
						(start 350.461072 -214.322914)
						(mid 350.456016 -214.308916)
						(end 350.447102 -214.297006)
					)
				)
			)
		)
		(zone
			(layer "F.Cu")
			(hatch none 0.5)
			(connect_pads
				(clearance 0)
			)
			(min_thickness 0.25)
			(keepout
				(tracks not_allowed)
				(vias allowed)
				(pads allowed)
				(copperpour not_allowed)
				(footprints allowed)
			)
			(placement
				(enabled no)
				(sheetname "")
			)
			(fill
				(thermal_gap 0.5)
				(thermal_bridge_width 0.5)
				(island_removal_mode 0)
			)
			(polygon
				(pts
					(arc
						(start 350.497394 -289.242754)
						(mid 350.533372 -289.257694)
						(end 350.569276 -289.242754)
					)
					(arc
						(start 350.569276 -289.242754)
						(mid 350.580675 -289.225514)
						(end 350.584262 -289.205162)
					)
					(arc
						(start 350.584262 -289.205162)
						(mid 350.563993 -289.087933)
						(end 350.498664 -288.9885)
					)
					(arc
						(start 350.498664 -288.9885)
						(mid 350.292162 -288.902964)
						(end 350.08566 -288.9885)
					)
					(arc
						(start 350.08566 -288.9885)
						(mid 350.020871 -289.086893)
						(end 350.000316 -289.202876)
					)
					(arc
						(start 350.000316 -289.202876)
						(mid 350.003516 -289.223885)
						(end 350.015048 -289.241738)
					)
					(arc
						(start 350.015048 -289.241738)
						(mid 350.051026 -289.256678)
						(end 350.08693 -289.241738)
					)
					(arc
						(start 350.08693 -289.241738)
						(mid 350.095672 -289.229917)
						(end 350.100646 -289.216084)
					)
					(xy 350.100646 -289.195256) (xy 350.100646 -289.195002)
					(arc
						(start 350.100646 -289.193986)
						(mid 350.115484 -289.121281)
						(end 350.15678 -289.05962)
					)
					(arc
						(start 350.15678 -289.05962)
						(mid 350.292162 -289.003543)
						(end 350.427544 -289.05962)
					)
					(arc
						(start 350.427544 -289.05962)
						(mid 350.469193 -289.122086)
						(end 350.483678 -289.195764)
					)
					(xy 350.483424 -289.196272)
					(arc
						(start 350.483424 -289.216846)
						(mid 350.48848 -289.230844)
						(end 350.497394 -289.242754)
					)
				)
			)
		)
		(zone
			(layer "F.Cu")
			(hatch none 0.5)
			(connect_pads
				(clearance 0)
			)
			(min_thickness 0.25)
			(keepout
				(tracks not_allowed)
				(vias allowed)
				(pads allowed)
				(copperpour not_allowed)
				(footprints allowed)
			)
			(placement
				(enabled no)
				(sheetname "")
			)
			(fill
				(thermal_gap 0.5)
				(thermal_bridge_width 0.5)
				(island_removal_mode 0)
			)
			(polygon
				(pts
					(arc
						(start 351.386902 -214.297006)
						(mid 351.350998 -214.282246)
						(end 351.31502 -214.297006)
					)
					(arc
						(start 351.31502 -214.297006)
						(mid 351.303621 -214.314246)
						(end 351.300034 -214.334598)
					)
					(arc
						(start 351.300034 -214.334598)
						(mid 351.320303 -214.451827)
						(end 351.385632 -214.55126)
					)
					(arc
						(start 351.385632 -214.55126)
						(mid 351.592134 -214.636796)
						(end 351.798636 -214.55126)
					)
					(arc
						(start 351.798636 -214.55126)
						(mid 351.863425 -214.452867)
						(end 351.88398 -214.336884)
					)
					(arc
						(start 351.88398 -214.336884)
						(mid 351.88078 -214.315875)
						(end 351.869248 -214.298022)
					)
					(arc
						(start 351.869248 -214.298022)
						(mid 351.833344 -214.283262)
						(end 351.797366 -214.298022)
					)
					(arc
						(start 351.797366 -214.298022)
						(mid 351.788624 -214.309843)
						(end 351.78365 -214.323676)
					)
					(xy 351.78365 -214.344504) (xy 351.78365 -214.344758)
					(arc
						(start 351.78365 -214.345774)
						(mid 351.768812 -214.418479)
						(end 351.727516 -214.48014)
					)
					(arc
						(start 351.727516 -214.48014)
						(mid 351.592134 -214.536217)
						(end 351.456752 -214.48014)
					)
					(arc
						(start 351.456752 -214.48014)
						(mid 351.415103 -214.417674)
						(end 351.400618 -214.343996)
					)
					(xy 351.400872 -214.343488)
					(arc
						(start 351.400872 -214.322914)
						(mid 351.395816 -214.308916)
						(end 351.386902 -214.297006)
					)
				)
			)
		)
		(zone
			(layer "F.Cu")
			(hatch none 0.5)
			(connect_pads
				(clearance 0)
			)
			(min_thickness 0.25)
			(keepout
				(tracks not_allowed)
				(vias allowed)
				(pads allowed)
				(copperpour not_allowed)
				(footprints allowed)
			)
			(placement
				(enabled no)
				(sheetname "")
			)
			(fill
				(thermal_gap 0.5)
				(thermal_bridge_width 0.5)
				(island_removal_mode 0)
			)
			(polygon
				(pts
					(arc
						(start 351.437194 -289.242754)
						(mid 351.473172 -289.257694)
						(end 351.509076 -289.242754)
					)
					(arc
						(start 351.509076 -289.242754)
						(mid 351.520475 -289.225514)
						(end 351.524062 -289.205162)
					)
					(arc
						(start 351.524062 -289.205162)
						(mid 351.503793 -289.087933)
						(end 351.438464 -288.9885)
					)
					(arc
						(start 351.438464 -288.9885)
						(mid 351.231962 -288.902964)
						(end 351.02546 -288.9885)
					)
					(arc
						(start 351.02546 -288.9885)
						(mid 350.960671 -289.086893)
						(end 350.940116 -289.202876)
					)
					(arc
						(start 350.940116 -289.202876)
						(mid 350.943316 -289.223885)
						(end 350.954848 -289.241738)
					)
					(arc
						(start 350.954848 -289.241738)
						(mid 350.990826 -289.256678)
						(end 351.02673 -289.241738)
					)
					(arc
						(start 351.02673 -289.241738)
						(mid 351.035472 -289.229917)
						(end 351.040446 -289.216084)
					)
					(xy 351.040446 -289.195256) (xy 351.040446 -289.195002)
					(arc
						(start 351.040446 -289.193986)
						(mid 351.055284 -289.121281)
						(end 351.09658 -289.05962)
					)
					(arc
						(start 351.09658 -289.05962)
						(mid 351.231962 -289.003543)
						(end 351.367344 -289.05962)
					)
					(arc
						(start 351.367344 -289.05962)
						(mid 351.408993 -289.122086)
						(end 351.423478 -289.195764)
					)
					(xy 351.423224 -289.196272)
					(arc
						(start 351.423224 -289.216846)
						(mid 351.42828 -289.230844)
						(end 351.437194 -289.242754)
					)
				)
			)
		)
		(zone
			(layer "F.Cu")
			(hatch none 0.5)
			(connect_pads
				(clearance 0)
			)
			(min_thickness 0.25)
			(keepout
				(tracks not_allowed)
				(vias allowed)
				(pads allowed)
				(copperpour not_allowed)
				(footprints allowed)
			)
			(placement
				(enabled no)
				(sheetname "")
			)
			(fill
				(thermal_gap 0.5)
				(thermal_bridge_width 0.5)
				(island_removal_mode 0)
			)
			(polygon
				(pts
					(arc
						(start 352.326702 -214.297006)
						(mid 352.290798 -214.282246)
						(end 352.25482 -214.297006)
					)
					(arc
						(start 352.25482 -214.297006)
						(mid 352.243421 -214.314246)
						(end 352.239834 -214.334598)
					)
					(arc
						(start 352.239834 -214.334598)
						(mid 352.260103 -214.451827)
						(end 352.325432 -214.55126)
					)
					(arc
						(start 352.325432 -214.55126)
						(mid 352.531934 -214.636796)
						(end 352.738436 -214.55126)
					)
					(arc
						(start 352.738436 -214.55126)
						(mid 352.803225 -214.452867)
						(end 352.82378 -214.336884)
					)
					(arc
						(start 352.82378 -214.336884)
						(mid 352.82058 -214.315875)
						(end 352.809048 -214.298022)
					)
					(arc
						(start 352.809048 -214.298022)
						(mid 352.773144 -214.283262)
						(end 352.737166 -214.298022)
					)
					(arc
						(start 352.737166 -214.298022)
						(mid 352.728424 -214.309843)
						(end 352.72345 -214.323676)
					)
					(xy 352.72345 -214.344504) (xy 352.72345 -214.344758)
					(arc
						(start 352.72345 -214.345774)
						(mid 352.708612 -214.418479)
						(end 352.667316 -214.48014)
					)
					(arc
						(start 352.667316 -214.48014)
						(mid 352.531934 -214.536217)
						(end 352.396552 -214.48014)
					)
					(arc
						(start 352.396552 -214.48014)
						(mid 352.354903 -214.417674)
						(end 352.340418 -214.343996)
					)
					(xy 352.340672 -214.343488)
					(arc
						(start 352.340672 -214.322914)
						(mid 352.335616 -214.308916)
						(end 352.326702 -214.297006)
					)
				)
			)
		)
		(zone
			(layer "F.Cu")
			(hatch none 0.5)
			(connect_pads
				(clearance 0)
			)
			(min_thickness 0.25)
			(keepout
				(tracks not_allowed)
				(vias allowed)
				(pads allowed)
				(copperpour not_allowed)
				(footprints allowed)
			)
			(placement
				(enabled no)
				(sheetname "")
			)
			(fill
				(thermal_gap 0.5)
				(thermal_bridge_width 0.5)
				(island_removal_mode 0)
			)
			(polygon
				(pts
					(arc
						(start 352.376994 -289.242754)
						(mid 352.412972 -289.257694)
						(end 352.448876 -289.242754)
					)
					(arc
						(start 352.448876 -289.242754)
						(mid 352.460275 -289.225514)
						(end 352.463862 -289.205162)
					)
					(arc
						(start 352.463862 -289.205162)
						(mid 352.443593 -289.087933)
						(end 352.378264 -288.9885)
					)
					(arc
						(start 352.378264 -288.9885)
						(mid 352.171762 -288.902964)
						(end 351.96526 -288.9885)
					)
					(arc
						(start 351.96526 -288.9885)
						(mid 351.900471 -289.086893)
						(end 351.879916 -289.202876)
					)
					(arc
						(start 351.879916 -289.202876)
						(mid 351.883116 -289.223885)
						(end 351.894648 -289.241738)
					)
					(arc
						(start 351.894648 -289.241738)
						(mid 351.930626 -289.256678)
						(end 351.96653 -289.241738)
					)
					(arc
						(start 351.96653 -289.241738)
						(mid 351.975272 -289.229917)
						(end 351.980246 -289.216084)
					)
					(xy 351.980246 -289.195256) (xy 351.980246 -289.195002)
					(arc
						(start 351.980246 -289.193986)
						(mid 351.995084 -289.121281)
						(end 352.03638 -289.05962)
					)
					(arc
						(start 352.03638 -289.05962)
						(mid 352.171762 -289.003543)
						(end 352.307144 -289.05962)
					)
					(arc
						(start 352.307144 -289.05962)
						(mid 352.348793 -289.122086)
						(end 352.363278 -289.195764)
					)
					(xy 352.363024 -289.196272)
					(arc
						(start 352.363024 -289.216846)
						(mid 352.36808 -289.230844)
						(end 352.376994 -289.242754)
					)
				)
			)
		)
		(zone
			(layer "F.Cu")
			(hatch none 0.5)
			(connect_pads
				(clearance 0)
			)
			(min_thickness 0.25)
			(keepout
				(tracks not_allowed)
				(vias allowed)
				(pads allowed)
				(copperpour not_allowed)
				(footprints allowed)
			)
			(placement
				(enabled no)
				(sheetname "")
			)
			(fill
				(thermal_gap 0.5)
				(thermal_bridge_width 0.5)
				(island_removal_mode 0)
			)
			(polygon
				(pts
					(arc
						(start 353.266502 -214.297006)
						(mid 353.230598 -214.282246)
						(end 353.19462 -214.297006)
					)
					(arc
						(start 353.19462 -214.297006)
						(mid 353.183221 -214.314246)
						(end 353.179634 -214.334598)
					)
					(arc
						(start 353.179634 -214.334598)
						(mid 353.199903 -214.451827)
						(end 353.265232 -214.55126)
					)
					(arc
						(start 353.265232 -214.55126)
						(mid 353.471734 -214.636796)
						(end 353.678236 -214.55126)
					)
					(arc
						(start 353.678236 -214.55126)
						(mid 353.743025 -214.452867)
						(end 353.76358 -214.336884)
					)
					(arc
						(start 353.76358 -214.336884)
						(mid 353.76038 -214.315875)
						(end 353.748848 -214.298022)
					)
					(arc
						(start 353.748848 -214.298022)
						(mid 353.712944 -214.283262)
						(end 353.676966 -214.298022)
					)
					(arc
						(start 353.676966 -214.298022)
						(mid 353.668224 -214.309843)
						(end 353.66325 -214.323676)
					)
					(xy 353.66325 -214.344504) (xy 353.66325 -214.344758)
					(arc
						(start 353.66325 -214.345774)
						(mid 353.648412 -214.418479)
						(end 353.607116 -214.48014)
					)
					(arc
						(start 353.607116 -214.48014)
						(mid 353.471734 -214.536217)
						(end 353.336352 -214.48014)
					)
					(arc
						(start 353.336352 -214.48014)
						(mid 353.294703 -214.417674)
						(end 353.280218 -214.343996)
					)
					(xy 353.280472 -214.343488)
					(arc
						(start 353.280472 -214.322914)
						(mid 353.275416 -214.308916)
						(end 353.266502 -214.297006)
					)
				)
			)
		)
		(zone
			(layer "F.Cu")
			(hatch none 0.5)
			(connect_pads
				(clearance 0)
			)
			(min_thickness 0.25)
			(keepout
				(tracks not_allowed)
				(vias allowed)
				(pads allowed)
				(copperpour not_allowed)
				(footprints allowed)
			)
			(placement
				(enabled no)
				(sheetname "")
			)
			(fill
				(thermal_gap 0.5)
				(thermal_bridge_width 0.5)
				(island_removal_mode 0)
			)
			(polygon
				(pts
					(arc
						(start 353.316794 -289.242754)
						(mid 353.352772 -289.257694)
						(end 353.388676 -289.242754)
					)
					(arc
						(start 353.388676 -289.242754)
						(mid 353.400075 -289.225514)
						(end 353.403662 -289.205162)
					)
					(arc
						(start 353.403662 -289.205162)
						(mid 353.383393 -289.087933)
						(end 353.318064 -288.9885)
					)
					(arc
						(start 353.318064 -288.9885)
						(mid 353.111562 -288.902964)
						(end 352.90506 -288.9885)
					)
					(arc
						(start 352.90506 -288.9885)
						(mid 352.840271 -289.086893)
						(end 352.819716 -289.202876)
					)
					(arc
						(start 352.819716 -289.202876)
						(mid 352.822916 -289.223885)
						(end 352.834448 -289.241738)
					)
					(arc
						(start 352.834448 -289.241738)
						(mid 352.870426 -289.256678)
						(end 352.90633 -289.241738)
					)
					(arc
						(start 352.90633 -289.241738)
						(mid 352.915072 -289.229917)
						(end 352.920046 -289.216084)
					)
					(xy 352.920046 -289.195256) (xy 352.920046 -289.195002)
					(arc
						(start 352.920046 -289.193986)
						(mid 352.934884 -289.121281)
						(end 352.97618 -289.05962)
					)
					(arc
						(start 352.97618 -289.05962)
						(mid 353.111562 -289.003543)
						(end 353.246944 -289.05962)
					)
					(arc
						(start 353.246944 -289.05962)
						(mid 353.288593 -289.122086)
						(end 353.303078 -289.195764)
					)
					(xy 353.302824 -289.196272)
					(arc
						(start 353.302824 -289.216846)
						(mid 353.30788 -289.230844)
						(end 353.316794 -289.242754)
					)
				)
			)
		)
		(zone
			(layer "F.Cu")
			(hatch none 0.5)
			(connect_pads
				(clearance 0)
			)
			(min_thickness 0.25)
			(keepout
				(tracks not_allowed)
				(vias allowed)
				(pads allowed)
				(copperpour not_allowed)
				(footprints allowed)
			)
			(placement
				(enabled no)
				(sheetname "")
			)
			(fill
				(thermal_gap 0.5)
				(thermal_bridge_width 0.5)
				(island_removal_mode 0)
			)
			(polygon
				(pts
					(arc
						(start 354.206302 -214.297006)
						(mid 354.170398 -214.282246)
						(end 354.13442 -214.297006)
					)
					(arc
						(start 354.13442 -214.297006)
						(mid 354.123021 -214.314246)
						(end 354.119434 -214.334598)
					)
					(arc
						(start 354.119434 -214.334598)
						(mid 354.139703 -214.451827)
						(end 354.205032 -214.55126)
					)
					(arc
						(start 354.205032 -214.55126)
						(mid 354.411534 -214.636796)
						(end 354.618036 -214.55126)
					)
					(arc
						(start 354.618036 -214.55126)
						(mid 354.682825 -214.452867)
						(end 354.70338 -214.336884)
					)
					(arc
						(start 354.70338 -214.336884)
						(mid 354.70018 -214.315875)
						(end 354.688648 -214.298022)
					)
					(arc
						(start 354.688648 -214.298022)
						(mid 354.652744 -214.283262)
						(end 354.616766 -214.298022)
					)
					(arc
						(start 354.616766 -214.298022)
						(mid 354.608024 -214.309843)
						(end 354.60305 -214.323676)
					)
					(xy 354.60305 -214.344504) (xy 354.60305 -214.344758)
					(arc
						(start 354.60305 -214.345774)
						(mid 354.588212 -214.418479)
						(end 354.546916 -214.48014)
					)
					(arc
						(start 354.546916 -214.48014)
						(mid 354.411534 -214.536217)
						(end 354.276152 -214.48014)
					)
					(arc
						(start 354.276152 -214.48014)
						(mid 354.234503 -214.417674)
						(end 354.220018 -214.343996)
					)
					(xy 354.220272 -214.343488)
					(arc
						(start 354.220272 -214.322914)
						(mid 354.215216 -214.308916)
						(end 354.206302 -214.297006)
					)
				)
			)
		)
		(zone
			(layer "F.Cu")
			(hatch none 0.5)
			(connect_pads
				(clearance 0)
			)
			(min_thickness 0.25)
			(keepout
				(tracks not_allowed)
				(vias allowed)
				(pads allowed)
				(copperpour not_allowed)
				(footprints allowed)
			)
			(placement
				(enabled no)
				(sheetname "")
			)
			(fill
				(thermal_gap 0.5)
				(thermal_bridge_width 0.5)
				(island_removal_mode 0)
			)
			(polygon
				(pts
					(arc
						(start 354.256594 -289.242754)
						(mid 354.292572 -289.257694)
						(end 354.328476 -289.242754)
					)
					(arc
						(start 354.328476 -289.242754)
						(mid 354.339875 -289.225514)
						(end 354.343462 -289.205162)
					)
					(arc
						(start 354.343462 -289.205162)
						(mid 354.323193 -289.087933)
						(end 354.257864 -288.9885)
					)
					(arc
						(start 354.257864 -288.9885)
						(mid 354.051362 -288.902964)
						(end 353.84486 -288.9885)
					)
					(arc
						(start 353.84486 -288.9885)
						(mid 353.780071 -289.086893)
						(end 353.759516 -289.202876)
					)
					(arc
						(start 353.759516 -289.202876)
						(mid 353.762716 -289.223885)
						(end 353.774248 -289.241738)
					)
					(arc
						(start 353.774248 -289.241738)
						(mid 353.810226 -289.256678)
						(end 353.84613 -289.241738)
					)
					(arc
						(start 353.84613 -289.241738)
						(mid 353.854872 -289.229917)
						(end 353.859846 -289.216084)
					)
					(xy 353.859846 -289.195256) (xy 353.859846 -289.195002)
					(arc
						(start 353.859846 -289.193986)
						(mid 353.874684 -289.121281)
						(end 353.91598 -289.05962)
					)
					(arc
						(start 353.91598 -289.05962)
						(mid 354.051362 -289.003543)
						(end 354.186744 -289.05962)
					)
					(arc
						(start 354.186744 -289.05962)
						(mid 354.228393 -289.122086)
						(end 354.242878 -289.195764)
					)
					(xy 354.242624 -289.196272)
					(arc
						(start 354.242624 -289.216846)
						(mid 354.24768 -289.230844)
						(end 354.256594 -289.242754)
					)
				)
			)
		)
		(zone
			(layer "F.Cu")
			(hatch none 0.5)
			(connect_pads
				(clearance 0)
			)
			(min_thickness 0.25)
			(keepout
				(tracks not_allowed)
				(vias allowed)
				(pads allowed)
				(copperpour not_allowed)
				(footprints allowed)
			)
			(placement
				(enabled no)
				(sheetname "")
			)
			(fill
				(thermal_gap 0.5)
				(thermal_bridge_width 0.5)
				(island_removal_mode 0)
			)
			(polygon
				(pts
					(arc
						(start 355.146102 -214.297006)
						(mid 355.110198 -214.282246)
						(end 355.07422 -214.297006)
					)
					(arc
						(start 355.07422 -214.297006)
						(mid 355.062821 -214.314246)
						(end 355.059234 -214.334598)
					)
					(arc
						(start 355.059234 -214.334598)
						(mid 355.079503 -214.451827)
						(end 355.144832 -214.55126)
					)
					(arc
						(start 355.144832 -214.55126)
						(mid 355.351334 -214.636796)
						(end 355.557836 -214.55126)
					)
					(arc
						(start 355.557836 -214.55126)
						(mid 355.622625 -214.452867)
						(end 355.64318 -214.336884)
					)
					(arc
						(start 355.64318 -214.336884)
						(mid 355.63998 -214.315875)
						(end 355.628448 -214.298022)
					)
					(arc
						(start 355.628448 -214.298022)
						(mid 355.592544 -214.283262)
						(end 355.556566 -214.298022)
					)
					(arc
						(start 355.556566 -214.298022)
						(mid 355.547824 -214.309843)
						(end 355.54285 -214.323676)
					)
					(xy 355.54285 -214.344504) (xy 355.54285 -214.344758)
					(arc
						(start 355.54285 -214.345774)
						(mid 355.528012 -214.418479)
						(end 355.486716 -214.48014)
					)
					(arc
						(start 355.486716 -214.48014)
						(mid 355.351334 -214.536217)
						(end 355.215952 -214.48014)
					)
					(arc
						(start 355.215952 -214.48014)
						(mid 355.174303 -214.417674)
						(end 355.159818 -214.343996)
					)
					(xy 355.160072 -214.343488)
					(arc
						(start 355.160072 -214.322914)
						(mid 355.155016 -214.308916)
						(end 355.146102 -214.297006)
					)
				)
			)
		)
		(zone
			(layer "F.Cu")
			(hatch none 0.5)
			(connect_pads
				(clearance 0)
			)
			(min_thickness 0.25)
			(keepout
				(tracks not_allowed)
				(vias allowed)
				(pads allowed)
				(copperpour not_allowed)
				(footprints allowed)
			)
			(placement
				(enabled no)
				(sheetname "")
			)
			(fill
				(thermal_gap 0.5)
				(thermal_bridge_width 0.5)
				(island_removal_mode 0)
			)
			(polygon
				(pts
					(arc
						(start 355.196394 -289.242754)
						(mid 355.232372 -289.257694)
						(end 355.268276 -289.242754)
					)
					(arc
						(start 355.268276 -289.242754)
						(mid 355.279675 -289.225514)
						(end 355.283262 -289.205162)
					)
					(arc
						(start 355.283262 -289.205162)
						(mid 355.262993 -289.087933)
						(end 355.197664 -288.9885)
					)
					(arc
						(start 355.197664 -288.9885)
						(mid 354.991162 -288.902964)
						(end 354.78466 -288.9885)
					)
					(arc
						(start 354.78466 -288.9885)
						(mid 354.719871 -289.086893)
						(end 354.699316 -289.202876)
					)
					(arc
						(start 354.699316 -289.202876)
						(mid 354.702516 -289.223885)
						(end 354.714048 -289.241738)
					)
					(arc
						(start 354.714048 -289.241738)
						(mid 354.750026 -289.256678)
						(end 354.78593 -289.241738)
					)
					(arc
						(start 354.78593 -289.241738)
						(mid 354.794672 -289.229917)
						(end 354.799646 -289.216084)
					)
					(xy 354.799646 -289.195256) (xy 354.799646 -289.195002)
					(arc
						(start 354.799646 -289.193986)
						(mid 354.814484 -289.121281)
						(end 354.85578 -289.05962)
					)
					(arc
						(start 354.85578 -289.05962)
						(mid 354.991162 -289.003543)
						(end 355.126544 -289.05962)
					)
					(arc
						(start 355.126544 -289.05962)
						(mid 355.168193 -289.122086)
						(end 355.182678 -289.195764)
					)
					(xy 355.182424 -289.196272)
					(arc
						(start 355.182424 -289.216846)
						(mid 355.18748 -289.230844)
						(end 355.196394 -289.242754)
					)
				)
			)
		)
		(zone
			(layer "F.Cu")
			(hatch none 0.5)
			(connect_pads
				(clearance 0)
			)
			(min_thickness 0.25)
			(keepout
				(tracks not_allowed)
				(vias allowed)
				(pads allowed)
				(copperpour not_allowed)
				(footprints allowed)
			)
			(placement
				(enabled no)
				(sheetname "")
			)
			(fill
				(thermal_gap 0.5)
				(thermal_bridge_width 0.5)
				(island_removal_mode 0)
			)
			(polygon
				(pts
					(arc
						(start 356.085902 -214.297006)
						(mid 356.049998 -214.282246)
						(end 356.01402 -214.297006)
					)
					(arc
						(start 356.01402 -214.297006)
						(mid 356.002621 -214.314246)
						(end 355.999034 -214.334598)
					)
					(arc
						(start 355.999034 -214.334598)
						(mid 356.019303 -214.451827)
						(end 356.084632 -214.55126)
					)
					(arc
						(start 356.084632 -214.55126)
						(mid 356.291134 -214.636796)
						(end 356.497636 -214.55126)
					)
					(arc
						(start 356.497636 -214.55126)
						(mid 356.562425 -214.452867)
						(end 356.58298 -214.336884)
					)
					(arc
						(start 356.58298 -214.336884)
						(mid 356.57978 -214.315875)
						(end 356.568248 -214.298022)
					)
					(arc
						(start 356.568248 -214.298022)
						(mid 356.532344 -214.283262)
						(end 356.496366 -214.298022)
					)
					(arc
						(start 356.496366 -214.298022)
						(mid 356.487624 -214.309843)
						(end 356.48265 -214.323676)
					)
					(xy 356.48265 -214.344504) (xy 356.48265 -214.344758)
					(arc
						(start 356.48265 -214.345774)
						(mid 356.467812 -214.418479)
						(end 356.426516 -214.48014)
					)
					(arc
						(start 356.426516 -214.48014)
						(mid 356.291134 -214.536217)
						(end 356.155752 -214.48014)
					)
					(arc
						(start 356.155752 -214.48014)
						(mid 356.114103 -214.417674)
						(end 356.099618 -214.343996)
					)
					(xy 356.099872 -214.343488)
					(arc
						(start 356.099872 -214.322914)
						(mid 356.094816 -214.308916)
						(end 356.085902 -214.297006)
					)
				)
			)
		)
		(zone
			(layer "F.Cu")
			(hatch none 0.5)
			(connect_pads
				(clearance 0)
			)
			(min_thickness 0.25)
			(keepout
				(tracks not_allowed)
				(vias allowed)
				(pads allowed)
				(copperpour not_allowed)
				(footprints allowed)
			)
			(placement
				(enabled no)
				(sheetname "")
			)
			(fill
				(thermal_gap 0.5)
				(thermal_bridge_width 0.5)
				(island_removal_mode 0)
			)
			(polygon
				(pts
					(arc
						(start 356.136194 -289.242754)
						(mid 356.172172 -289.257694)
						(end 356.208076 -289.242754)
					)
					(arc
						(start 356.208076 -289.242754)
						(mid 356.219475 -289.225514)
						(end 356.223062 -289.205162)
					)
					(arc
						(start 356.223062 -289.205162)
						(mid 356.202793 -289.087933)
						(end 356.137464 -288.9885)
					)
					(arc
						(start 356.137464 -288.9885)
						(mid 355.930962 -288.902964)
						(end 355.72446 -288.9885)
					)
					(arc
						(start 355.72446 -288.9885)
						(mid 355.659671 -289.086893)
						(end 355.639116 -289.202876)
					)
					(arc
						(start 355.639116 -289.202876)
						(mid 355.642316 -289.223885)
						(end 355.653848 -289.241738)
					)
					(arc
						(start 355.653848 -289.241738)
						(mid 355.689826 -289.256678)
						(end 355.72573 -289.241738)
					)
					(arc
						(start 355.72573 -289.241738)
						(mid 355.734472 -289.229917)
						(end 355.739446 -289.216084)
					)
					(xy 355.739446 -289.195256) (xy 355.739446 -289.195002)
					(arc
						(start 355.739446 -289.193986)
						(mid 355.754284 -289.121281)
						(end 355.79558 -289.05962)
					)
					(arc
						(start 355.79558 -289.05962)
						(mid 355.930962 -289.003543)
						(end 356.066344 -289.05962)
					)
					(arc
						(start 356.066344 -289.05962)
						(mid 356.107993 -289.122086)
						(end 356.122478 -289.195764)
					)
					(xy 356.122224 -289.196272)
					(arc
						(start 356.122224 -289.216846)
						(mid 356.12728 -289.230844)
						(end 356.136194 -289.242754)
					)
				)
			)
		)
		(zone
			(layer "F.Cu")
			(hatch none 0.5)
			(connect_pads
				(clearance 0)
			)
			(min_thickness 0.25)
			(keepout
				(tracks not_allowed)
				(vias allowed)
				(pads allowed)
				(copperpour not_allowed)
				(footprints allowed)
			)
			(placement
				(enabled no)
				(sheetname "")
			)
			(fill
				(thermal_gap 0.5)
				(thermal_bridge_width 0.5)
				(island_removal_mode 0)
			)
			(polygon
				(pts
					(arc
						(start 356.555548 -215.111076)
						(mid 356.519734 -215.096241)
						(end 356.48392 -215.111076)
					)
					(arc
						(start 356.48392 -215.111076)
						(mid 356.472569 -215.128198)
						(end 356.468934 -215.148414)
					)
					(arc
						(start 356.468934 -215.148414)
						(mid 356.489083 -215.265615)
						(end 356.554278 -215.365076)
					)
					(arc
						(start 356.554278 -215.365076)
						(mid 356.76078 -215.450612)
						(end 356.967282 -215.365076)
					)
					(arc
						(start 356.967282 -215.365076)
						(mid 357.032164 -215.266832)
						(end 357.05288 -215.150954)
					)
					(arc
						(start 357.05288 -215.150954)
						(mid 357.049692 -215.129932)
						(end 357.038148 -215.112092)
					)
					(arc
						(start 357.038148 -215.112092)
						(mid 357.002245 -215.097257)
						(end 356.966266 -215.112092)
					)
					(arc
						(start 356.966266 -215.112092)
						(mid 356.957543 -215.123788)
						(end 356.95255 -215.137492)
					)
					(xy 356.95255 -215.15832) (xy 356.95255 -215.158828)
					(arc
						(start 356.95255 -215.159844)
						(mid 356.937548 -215.232442)
						(end 356.896162 -215.293956)
					)
					(arc
						(start 356.896162 -215.293956)
						(mid 356.76078 -215.350033)
						(end 356.625398 -215.293956)
					)
					(arc
						(start 356.625398 -215.293956)
						(mid 356.583798 -215.231608)
						(end 356.569264 -215.158066)
					)
					(xy 356.569518 -215.157304)
					(arc
						(start 356.569518 -215.13673)
						(mid 356.564428 -215.122868)
						(end 356.555548 -215.111076)
					)
				)
			)
		)
		(zone
			(layer "F.Cu")
			(hatch none 0.5)
			(connect_pads
				(clearance 0)
			)
			(min_thickness 0.25)
			(keepout
				(tracks not_allowed)
				(vias allowed)
				(pads allowed)
				(copperpour not_allowed)
				(footprints allowed)
			)
			(placement
				(enabled no)
				(sheetname "")
			)
			(fill
				(thermal_gap 0.5)
				(thermal_bridge_width 0.5)
				(island_removal_mode 0)
			)
			(polygon
				(pts
					(arc
						(start 357.075994 -289.242754)
						(mid 357.111972 -289.257694)
						(end 357.147876 -289.242754)
					)
					(arc
						(start 357.147876 -289.242754)
						(mid 357.159275 -289.225514)
						(end 357.162862 -289.205162)
					)
					(arc
						(start 357.162862 -289.205162)
						(mid 357.142593 -289.087933)
						(end 357.077264 -288.9885)
					)
					(arc
						(start 357.077264 -288.9885)
						(mid 356.870762 -288.902964)
						(end 356.66426 -288.9885)
					)
					(arc
						(start 356.66426 -288.9885)
						(mid 356.599471 -289.086893)
						(end 356.578916 -289.202876)
					)
					(arc
						(start 356.578916 -289.202876)
						(mid 356.582116 -289.223885)
						(end 356.593648 -289.241738)
					)
					(arc
						(start 356.593648 -289.241738)
						(mid 356.629626 -289.256678)
						(end 356.66553 -289.241738)
					)
					(arc
						(start 356.66553 -289.241738)
						(mid 356.674272 -289.229917)
						(end 356.679246 -289.216084)
					)
					(xy 356.679246 -289.195256) (xy 356.679246 -289.195002)
					(arc
						(start 356.679246 -289.193986)
						(mid 356.694084 -289.121281)
						(end 356.73538 -289.05962)
					)
					(arc
						(start 356.73538 -289.05962)
						(mid 356.870762 -289.003543)
						(end 357.006144 -289.05962)
					)
					(arc
						(start 357.006144 -289.05962)
						(mid 357.047793 -289.122086)
						(end 357.062278 -289.195764)
					)
					(xy 357.062024 -289.196272)
					(arc
						(start 357.062024 -289.216846)
						(mid 357.06708 -289.230844)
						(end 357.075994 -289.242754)
					)
				)
			)
		)
		(zone
			(layer "F.Cu")
			(hatch none 0.5)
			(connect_pads
				(clearance 0)
			)
			(min_thickness 0.25)
			(keepout
				(tracks not_allowed)
				(vias allowed)
				(pads allowed)
				(copperpour not_allowed)
				(footprints allowed)
			)
			(placement
				(enabled no)
				(sheetname "")
			)
			(fill
				(thermal_gap 0.5)
				(thermal_bridge_width 0.5)
				(island_removal_mode 0)
			)
			(polygon
				(pts
					(arc
						(start 357.495348 -215.111076)
						(mid 357.459534 -215.096241)
						(end 357.42372 -215.111076)
					)
					(arc
						(start 357.42372 -215.111076)
						(mid 357.412369 -215.128198)
						(end 357.408734 -215.148414)
					)
					(arc
						(start 357.408734 -215.148414)
						(mid 357.428883 -215.265615)
						(end 357.494078 -215.365076)
					)
					(arc
						(start 357.494078 -215.365076)
						(mid 357.70058 -215.450612)
						(end 357.907082 -215.365076)
					)
					(arc
						(start 357.907082 -215.365076)
						(mid 357.971964 -215.266832)
						(end 357.99268 -215.150954)
					)
					(arc
						(start 357.99268 -215.150954)
						(mid 357.989492 -215.129932)
						(end 357.977948 -215.112092)
					)
					(arc
						(start 357.977948 -215.112092)
						(mid 357.942045 -215.097257)
						(end 357.906066 -215.112092)
					)
					(arc
						(start 357.906066 -215.112092)
						(mid 357.897343 -215.123788)
						(end 357.89235 -215.137492)
					)
					(xy 357.89235 -215.15832) (xy 357.89235 -215.158828)
					(arc
						(start 357.89235 -215.159844)
						(mid 357.877348 -215.232442)
						(end 357.835962 -215.293956)
					)
					(arc
						(start 357.835962 -215.293956)
						(mid 357.70058 -215.350033)
						(end 357.565198 -215.293956)
					)
					(arc
						(start 357.565198 -215.293956)
						(mid 357.523598 -215.231608)
						(end 357.509064 -215.158066)
					)
					(xy 357.509318 -215.157304)
					(arc
						(start 357.509318 -215.13673)
						(mid 357.504228 -215.122868)
						(end 357.495348 -215.111076)
					)
				)
			)
		)
		(zone
			(layer "F.Cu")
			(hatch none 0.5)
			(connect_pads
				(clearance 0)
			)
			(min_thickness 0.25)
			(keepout
				(tracks not_allowed)
				(vias allowed)
				(pads allowed)
				(copperpour not_allowed)
				(footprints allowed)
			)
			(placement
				(enabled no)
				(sheetname "")
			)
			(fill
				(thermal_gap 0.5)
				(thermal_bridge_width 0.5)
				(island_removal_mode 0)
			)
			(polygon
				(pts
					(arc
						(start 357.545894 -288.428684)
						(mid 357.581872 -288.443698)
						(end 357.617776 -288.428684)
					)
					(arc
						(start 357.617776 -288.428684)
						(mid 357.629127 -288.411562)
						(end 357.632762 -288.391346)
					)
					(arc
						(start 357.632762 -288.391346)
						(mid 357.612493 -288.274117)
						(end 357.547164 -288.174684)
					)
					(arc
						(start 357.547164 -288.174684)
						(mid 357.340662 -288.089148)
						(end 357.13416 -288.174684)
					)
					(arc
						(start 357.13416 -288.174684)
						(mid 357.069419 -288.272959)
						(end 357.048816 -288.388806)
					)
					(arc
						(start 357.048816 -288.388806)
						(mid 357.052016 -288.409815)
						(end 357.063548 -288.427668)
					)
					(arc
						(start 357.063548 -288.427668)
						(mid 357.099526 -288.442682)
						(end 357.13543 -288.427668)
					)
					(arc
						(start 357.13543 -288.427668)
						(mid 357.144153 -288.415972)
						(end 357.149146 -288.402268)
					)
					(xy 357.149146 -288.38144) (xy 357.149146 -288.380932)
					(arc
						(start 357.149146 -288.379916)
						(mid 357.164031 -288.307347)
						(end 357.20528 -288.245804)
					)
					(arc
						(start 357.20528 -288.245804)
						(mid 357.340662 -288.189727)
						(end 357.476044 -288.245804)
					)
					(arc
						(start 357.476044 -288.245804)
						(mid 357.517644 -288.308152)
						(end 357.532178 -288.381694)
					)
					(xy 357.531924 -288.382456)
					(arc
						(start 357.531924 -288.40303)
						(mid 357.537014 -288.416892)
						(end 357.545894 -288.428684)
					)
				)
			)
		)
		(zone
			(layer "F.Cu")
			(hatch none 0.5)
			(connect_pads
				(clearance 0)
			)
			(min_thickness 0.25)
			(keepout
				(tracks not_allowed)
				(vias allowed)
				(pads allowed)
				(copperpour not_allowed)
				(footprints allowed)
			)
			(placement
				(enabled no)
				(sheetname "")
			)
			(fill
				(thermal_gap 0.5)
				(thermal_bridge_width 0.5)
				(island_removal_mode 0)
			)
			(polygon
				(pts
					(arc
						(start 358.435402 -215.111076)
						(mid 358.399499 -215.096241)
						(end 358.36352 -215.111076)
					)
					(arc
						(start 358.36352 -215.111076)
						(mid 358.352169 -215.128198)
						(end 358.348534 -215.148414)
					)
					(arc
						(start 358.348534 -215.148414)
						(mid 358.368803 -215.265643)
						(end 358.434132 -215.365076)
					)
					(arc
						(start 358.434132 -215.365076)
						(mid 358.640634 -215.450612)
						(end 358.847136 -215.365076)
					)
					(arc
						(start 358.847136 -215.365076)
						(mid 358.911877 -215.266801)
						(end 358.93248 -215.150954)
					)
					(arc
						(start 358.93248 -215.150954)
						(mid 358.92928 -215.129945)
						(end 358.917748 -215.112092)
					)
					(arc
						(start 358.917748 -215.112092)
						(mid 358.881845 -215.097257)
						(end 358.845866 -215.112092)
					)
					(arc
						(start 358.845866 -215.112092)
						(mid 358.837143 -215.123788)
						(end 358.83215 -215.137492)
					)
					(xy 358.83215 -215.15832) (xy 358.83215 -215.158828)
					(arc
						(start 358.83215 -215.159844)
						(mid 358.817265 -215.232413)
						(end 358.776016 -215.293956)
					)
					(arc
						(start 358.776016 -215.293956)
						(mid 358.640634 -215.350033)
						(end 358.505252 -215.293956)
					)
					(arc
						(start 358.505252 -215.293956)
						(mid 358.463652 -215.231608)
						(end 358.449118 -215.158066)
					)
					(xy 358.449372 -215.157304)
					(arc
						(start 358.449372 -215.13673)
						(mid 358.444282 -215.122868)
						(end 358.435402 -215.111076)
					)
				)
			)
		)
		(zone
			(layer "F.Cu")
			(hatch none 0.5)
			(connect_pads
				(clearance 0)
			)
			(min_thickness 0.25)
			(keepout
				(tracks not_allowed)
				(vias allowed)
				(pads allowed)
				(copperpour not_allowed)
				(footprints allowed)
			)
			(placement
				(enabled no)
				(sheetname "")
			)
			(fill
				(thermal_gap 0.5)
				(thermal_bridge_width 0.5)
				(island_removal_mode 0)
			)
			(polygon
				(pts
					(arc
						(start 358.485948 -288.428684)
						(mid 358.521762 -288.443519)
						(end 358.557576 -288.428684)
					)
					(arc
						(start 358.557576 -288.428684)
						(mid 358.568927 -288.411562)
						(end 358.572562 -288.391346)
					)
					(arc
						(start 358.572562 -288.391346)
						(mid 358.552413 -288.274145)
						(end 358.487218 -288.174684)
					)
					(arc
						(start 358.487218 -288.174684)
						(mid 358.280716 -288.089148)
						(end 358.074214 -288.174684)
					)
					(arc
						(start 358.074214 -288.174684)
						(mid 358.009332 -288.272928)
						(end 357.988616 -288.388806)
					)
					(arc
						(start 357.988616 -288.388806)
						(mid 357.991804 -288.409828)
						(end 358.003348 -288.427668)
					)
					(arc
						(start 358.003348 -288.427668)
						(mid 358.039326 -288.442682)
						(end 358.07523 -288.427668)
					)
					(arc
						(start 358.07523 -288.427668)
						(mid 358.083953 -288.415972)
						(end 358.088946 -288.402268)
					)
					(xy 358.088946 -288.38144) (xy 358.088946 -288.380932)
					(arc
						(start 358.088946 -288.379916)
						(mid 358.103948 -288.307318)
						(end 358.145334 -288.245804)
					)
					(arc
						(start 358.145334 -288.245804)
						(mid 358.280716 -288.189727)
						(end 358.416098 -288.245804)
					)
					(arc
						(start 358.416098 -288.245804)
						(mid 358.457698 -288.308152)
						(end 358.472232 -288.381694)
					)
					(xy 358.471978 -288.382456)
					(arc
						(start 358.471978 -288.40303)
						(mid 358.477068 -288.416892)
						(end 358.485948 -288.428684)
					)
				)
			)
		)
		(zone
			(layer "F.Cu")
			(hatch none 0.5)
			(connect_pads
				(clearance 0)
			)
			(min_thickness 0.25)
			(keepout
				(tracks not_allowed)
				(vias allowed)
				(pads allowed)
				(copperpour not_allowed)
				(footprints allowed)
			)
			(placement
				(enabled no)
				(sheetname "")
			)
			(fill
				(thermal_gap 0.5)
				(thermal_bridge_width 0.5)
				(island_removal_mode 0)
			)
			(polygon
				(pts
					(arc
						(start 359.374948 -215.111076)
						(mid 359.339134 -215.096241)
						(end 359.30332 -215.111076)
					)
					(arc
						(start 359.30332 -215.111076)
						(mid 359.291969 -215.128198)
						(end 359.288334 -215.148414)
					)
					(arc
						(start 359.288334 -215.148414)
						(mid 359.308483 -215.265615)
						(end 359.373678 -215.365076)
					)
					(arc
						(start 359.373678 -215.365076)
						(mid 359.58018 -215.450612)
						(end 359.786682 -215.365076)
					)
					(arc
						(start 359.786682 -215.365076)
						(mid 359.851564 -215.266832)
						(end 359.87228 -215.150954)
					)
					(arc
						(start 359.87228 -215.150954)
						(mid 359.869092 -215.129932)
						(end 359.857548 -215.112092)
					)
					(arc
						(start 359.857548 -215.112092)
						(mid 359.821645 -215.097257)
						(end 359.785666 -215.112092)
					)
					(arc
						(start 359.785666 -215.112092)
						(mid 359.776943 -215.123788)
						(end 359.77195 -215.137492)
					)
					(xy 359.77195 -215.15832) (xy 359.77195 -215.158828)
					(arc
						(start 359.77195 -215.159844)
						(mid 359.756948 -215.232442)
						(end 359.715562 -215.293956)
					)
					(arc
						(start 359.715562 -215.293956)
						(mid 359.58018 -215.350033)
						(end 359.444798 -215.293956)
					)
					(arc
						(start 359.444798 -215.293956)
						(mid 359.403198 -215.231608)
						(end 359.388664 -215.158066)
					)
					(xy 359.388918 -215.157304)
					(arc
						(start 359.388918 -215.13673)
						(mid 359.383828 -215.122868)
						(end 359.374948 -215.111076)
					)
				)
			)
		)
		(zone
			(layer "F.Cu")
			(hatch none 0.5)
			(connect_pads
				(clearance 0)
			)
			(min_thickness 0.25)
			(keepout
				(tracks not_allowed)
				(vias allowed)
				(pads allowed)
				(copperpour not_allowed)
				(footprints allowed)
			)
			(placement
				(enabled no)
				(sheetname "")
			)
			(fill
				(thermal_gap 0.5)
				(thermal_bridge_width 0.5)
				(island_removal_mode 0)
			)
			(polygon
				(pts
					(arc
						(start 359.425748 -288.428684)
						(mid 359.461562 -288.443519)
						(end 359.497376 -288.428684)
					)
					(arc
						(start 359.497376 -288.428684)
						(mid 359.508727 -288.411562)
						(end 359.512362 -288.391346)
					)
					(arc
						(start 359.512362 -288.391346)
						(mid 359.492213 -288.274145)
						(end 359.427018 -288.174684)
					)
					(arc
						(start 359.427018 -288.174684)
						(mid 359.220516 -288.089148)
						(end 359.014014 -288.174684)
					)
					(arc
						(start 359.014014 -288.174684)
						(mid 358.949132 -288.272928)
						(end 358.928416 -288.388806)
					)
					(arc
						(start 358.928416 -288.388806)
						(mid 358.931604 -288.409828)
						(end 358.943148 -288.427668)
					)
					(arc
						(start 358.943148 -288.427668)
						(mid 358.979126 -288.442682)
						(end 359.01503 -288.427668)
					)
					(arc
						(start 359.01503 -288.427668)
						(mid 359.023753 -288.415972)
						(end 359.028746 -288.402268)
					)
					(xy 359.028746 -288.38144) (xy 359.028746 -288.380932)
					(arc
						(start 359.028746 -288.379916)
						(mid 359.043748 -288.307318)
						(end 359.085134 -288.245804)
					)
					(arc
						(start 359.085134 -288.245804)
						(mid 359.220516 -288.189727)
						(end 359.355898 -288.245804)
					)
					(arc
						(start 359.355898 -288.245804)
						(mid 359.397498 -288.308152)
						(end 359.412032 -288.381694)
					)
					(xy 359.411778 -288.382456)
					(arc
						(start 359.411778 -288.40303)
						(mid 359.416868 -288.416892)
						(end 359.425748 -288.428684)
					)
				)
			)
		)
		(zone
			(layer "F.Cu")
			(hatch none 0.5)
			(connect_pads
				(clearance 0)
			)
			(min_thickness 0.25)
			(keepout
				(tracks not_allowed)
				(vias allowed)
				(pads allowed)
				(copperpour not_allowed)
				(footprints allowed)
			)
			(placement
				(enabled no)
				(sheetname "")
			)
			(fill
				(thermal_gap 0.5)
				(thermal_bridge_width 0.5)
				(island_removal_mode 0)
			)
			(polygon
				(pts
					(arc
						(start 360.314748 -215.111076)
						(mid 360.278934 -215.096241)
						(end 360.24312 -215.111076)
					)
					(arc
						(start 360.24312 -215.111076)
						(mid 360.231769 -215.128198)
						(end 360.228134 -215.148414)
					)
					(arc
						(start 360.228134 -215.148414)
						(mid 360.248283 -215.265615)
						(end 360.313478 -215.365076)
					)
					(arc
						(start 360.313478 -215.365076)
						(mid 360.51998 -215.450612)
						(end 360.726482 -215.365076)
					)
					(arc
						(start 360.726482 -215.365076)
						(mid 360.791364 -215.266832)
						(end 360.81208 -215.150954)
					)
					(arc
						(start 360.81208 -215.150954)
						(mid 360.808892 -215.129932)
						(end 360.797348 -215.112092)
					)
					(arc
						(start 360.797348 -215.112092)
						(mid 360.761445 -215.097257)
						(end 360.725466 -215.112092)
					)
					(arc
						(start 360.725466 -215.112092)
						(mid 360.716743 -215.123788)
						(end 360.71175 -215.137492)
					)
					(xy 360.71175 -215.15832) (xy 360.71175 -215.158828)
					(arc
						(start 360.71175 -215.159844)
						(mid 360.696748 -215.232442)
						(end 360.655362 -215.293956)
					)
					(arc
						(start 360.655362 -215.293956)
						(mid 360.51998 -215.350033)
						(end 360.384598 -215.293956)
					)
					(arc
						(start 360.384598 -215.293956)
						(mid 360.342998 -215.231608)
						(end 360.328464 -215.158066)
					)
					(xy 360.328718 -215.157304)
					(arc
						(start 360.328718 -215.13673)
						(mid 360.323628 -215.122868)
						(end 360.314748 -215.111076)
					)
				)
			)
		)
		(zone
			(layer "F.Cu")
			(hatch none 0.5)
			(connect_pads
				(clearance 0)
			)
			(min_thickness 0.25)
			(keepout
				(tracks not_allowed)
				(vias allowed)
				(pads allowed)
				(copperpour not_allowed)
				(footprints allowed)
			)
			(placement
				(enabled no)
				(sheetname "")
			)
			(fill
				(thermal_gap 0.5)
				(thermal_bridge_width 0.5)
				(island_removal_mode 0)
			)
			(polygon
				(pts
					(arc
						(start 360.365548 -288.428684)
						(mid 360.401362 -288.443519)
						(end 360.437176 -288.428684)
					)
					(arc
						(start 360.437176 -288.428684)
						(mid 360.448527 -288.411562)
						(end 360.452162 -288.391346)
					)
					(arc
						(start 360.452162 -288.391346)
						(mid 360.432013 -288.274145)
						(end 360.366818 -288.174684)
					)
					(arc
						(start 360.366818 -288.174684)
						(mid 360.160316 -288.089148)
						(end 359.953814 -288.174684)
					)
					(arc
						(start 359.953814 -288.174684)
						(mid 359.888932 -288.272928)
						(end 359.868216 -288.388806)
					)
					(arc
						(start 359.868216 -288.388806)
						(mid 359.871404 -288.409828)
						(end 359.882948 -288.427668)
					)
					(arc
						(start 359.882948 -288.427668)
						(mid 359.918926 -288.442682)
						(end 359.95483 -288.427668)
					)
					(arc
						(start 359.95483 -288.427668)
						(mid 359.963553 -288.415972)
						(end 359.968546 -288.402268)
					)
					(xy 359.968546 -288.38144) (xy 359.968546 -288.380932)
					(arc
						(start 359.968546 -288.379916)
						(mid 359.983548 -288.307318)
						(end 360.024934 -288.245804)
					)
					(arc
						(start 360.024934 -288.245804)
						(mid 360.160316 -288.189727)
						(end 360.295698 -288.245804)
					)
					(arc
						(start 360.295698 -288.245804)
						(mid 360.337298 -288.308152)
						(end 360.351832 -288.381694)
					)
					(xy 360.351578 -288.382456)
					(arc
						(start 360.351578 -288.40303)
						(mid 360.356668 -288.416892)
						(end 360.365548 -288.428684)
					)
				)
			)
		)
		(zone
			(layer "F.Cu")
			(hatch none 0.5)
			(connect_pads
				(clearance 0)
			)
			(min_thickness 0.25)
			(keepout
				(tracks not_allowed)
				(vias allowed)
				(pads allowed)
				(copperpour not_allowed)
				(footprints allowed)
			)
			(placement
				(enabled no)
				(sheetname "")
			)
			(fill
				(thermal_gap 0.5)
				(thermal_bridge_width 0.5)
				(island_removal_mode 0)
			)
			(polygon
				(pts
					(arc
						(start 361.254548 -215.111076)
						(mid 361.218734 -215.096241)
						(end 361.18292 -215.111076)
					)
					(arc
						(start 361.18292 -215.111076)
						(mid 361.171569 -215.128198)
						(end 361.167934 -215.148414)
					)
					(arc
						(start 361.167934 -215.148414)
						(mid 361.188083 -215.265615)
						(end 361.253278 -215.365076)
					)
					(arc
						(start 361.253278 -215.365076)
						(mid 361.45978 -215.450612)
						(end 361.666282 -215.365076)
					)
					(arc
						(start 361.666282 -215.365076)
						(mid 361.731164 -215.266832)
						(end 361.75188 -215.150954)
					)
					(arc
						(start 361.75188 -215.150954)
						(mid 361.748692 -215.129932)
						(end 361.737148 -215.112092)
					)
					(arc
						(start 361.737148 -215.112092)
						(mid 361.701245 -215.097257)
						(end 361.665266 -215.112092)
					)
					(arc
						(start 361.665266 -215.112092)
						(mid 361.656543 -215.123788)
						(end 361.65155 -215.137492)
					)
					(xy 361.65155 -215.15832) (xy 361.65155 -215.158828)
					(arc
						(start 361.65155 -215.159844)
						(mid 361.636548 -215.232442)
						(end 361.595162 -215.293956)
					)
					(arc
						(start 361.595162 -215.293956)
						(mid 361.45978 -215.350033)
						(end 361.324398 -215.293956)
					)
					(arc
						(start 361.324398 -215.293956)
						(mid 361.282798 -215.231608)
						(end 361.268264 -215.158066)
					)
					(xy 361.268518 -215.157304)
					(arc
						(start 361.268518 -215.13673)
						(mid 361.263428 -215.122868)
						(end 361.254548 -215.111076)
					)
				)
			)
		)
		(zone
			(layer "F.Cu")
			(hatch none 0.5)
			(connect_pads
				(clearance 0)
			)
			(min_thickness 0.25)
			(keepout
				(tracks not_allowed)
				(vias allowed)
				(pads allowed)
				(copperpour not_allowed)
				(footprints allowed)
			)
			(placement
				(enabled no)
				(sheetname "")
			)
			(fill
				(thermal_gap 0.5)
				(thermal_bridge_width 0.5)
				(island_removal_mode 0)
			)
			(polygon
				(pts
					(arc
						(start 361.305094 -288.428684)
						(mid 361.341072 -288.443698)
						(end 361.376976 -288.428684)
					)
					(arc
						(start 361.376976 -288.428684)
						(mid 361.388327 -288.411562)
						(end 361.391962 -288.391346)
					)
					(arc
						(start 361.391962 -288.391346)
						(mid 361.371693 -288.274117)
						(end 361.306364 -288.174684)
					)
					(arc
						(start 361.306364 -288.174684)
						(mid 361.099862 -288.089148)
						(end 360.89336 -288.174684)
					)
					(arc
						(start 360.89336 -288.174684)
						(mid 360.828619 -288.272959)
						(end 360.808016 -288.388806)
					)
					(arc
						(start 360.808016 -288.388806)
						(mid 360.811216 -288.409815)
						(end 360.822748 -288.427668)
					)
					(arc
						(start 360.822748 -288.427668)
						(mid 360.858726 -288.442682)
						(end 360.89463 -288.427668)
					)
					(arc
						(start 360.89463 -288.427668)
						(mid 360.903353 -288.415972)
						(end 360.908346 -288.402268)
					)
					(xy 360.908346 -288.38144) (xy 360.908346 -288.380932)
					(arc
						(start 360.908346 -288.379916)
						(mid 360.923231 -288.307347)
						(end 360.96448 -288.245804)
					)
					(arc
						(start 360.96448 -288.245804)
						(mid 361.099862 -288.189727)
						(end 361.235244 -288.245804)
					)
					(arc
						(start 361.235244 -288.245804)
						(mid 361.276844 -288.308152)
						(end 361.291378 -288.381694)
					)
					(xy 361.291124 -288.382456)
					(arc
						(start 361.291124 -288.40303)
						(mid 361.296214 -288.416892)
						(end 361.305094 -288.428684)
					)
				)
			)
		)
		(zone
			(layer "F.Cu")
			(hatch none 0.5)
			(connect_pads
				(clearance 0)
			)
			(min_thickness 0.25)
			(keepout
				(tracks not_allowed)
				(vias allowed)
				(pads allowed)
				(copperpour not_allowed)
				(footprints allowed)
			)
			(placement
				(enabled no)
				(sheetname "")
			)
			(fill
				(thermal_gap 0.5)
				(thermal_bridge_width 0.5)
				(island_removal_mode 0)
			)
			(polygon
				(pts
					(arc
						(start 362.194602 -215.111076)
						(mid 362.158699 -215.096241)
						(end 362.12272 -215.111076)
					)
					(arc
						(start 362.12272 -215.111076)
						(mid 362.111369 -215.128198)
						(end 362.107734 -215.148414)
					)
					(arc
						(start 362.107734 -215.148414)
						(mid 362.128003 -215.265643)
						(end 362.193332 -215.365076)
					)
					(arc
						(start 362.193332 -215.365076)
						(mid 362.399834 -215.450612)
						(end 362.606336 -215.365076)
					)
					(arc
						(start 362.606336 -215.365076)
						(mid 362.671077 -215.266801)
						(end 362.69168 -215.150954)
					)
					(arc
						(start 362.69168 -215.150954)
						(mid 362.68848 -215.129945)
						(end 362.676948 -215.112092)
					)
					(arc
						(start 362.676948 -215.112092)
						(mid 362.641045 -215.097257)
						(end 362.605066 -215.112092)
					)
					(arc
						(start 362.605066 -215.112092)
						(mid 362.596343 -215.123788)
						(end 362.59135 -215.137492)
					)
					(xy 362.59135 -215.15832) (xy 362.59135 -215.158828)
					(arc
						(start 362.59135 -215.159844)
						(mid 362.576465 -215.232413)
						(end 362.535216 -215.293956)
					)
					(arc
						(start 362.535216 -215.293956)
						(mid 362.399834 -215.350033)
						(end 362.264452 -215.293956)
					)
					(arc
						(start 362.264452 -215.293956)
						(mid 362.222852 -215.231608)
						(end 362.208318 -215.158066)
					)
					(xy 362.208572 -215.157304)
					(arc
						(start 362.208572 -215.13673)
						(mid 362.203482 -215.122868)
						(end 362.194602 -215.111076)
					)
				)
			)
		)
		(zone
			(layer "F.Cu")
			(hatch none 0.5)
			(connect_pads
				(clearance 0)
			)
			(min_thickness 0.25)
			(keepout
				(tracks not_allowed)
				(vias allowed)
				(pads allowed)
				(copperpour not_allowed)
				(footprints allowed)
			)
			(placement
				(enabled no)
				(sheetname "")
			)
			(fill
				(thermal_gap 0.5)
				(thermal_bridge_width 0.5)
				(island_removal_mode 0)
			)
			(polygon
				(pts
					(arc
						(start 362.245148 -288.428684)
						(mid 362.280962 -288.443519)
						(end 362.316776 -288.428684)
					)
					(arc
						(start 362.316776 -288.428684)
						(mid 362.328127 -288.411562)
						(end 362.331762 -288.391346)
					)
					(arc
						(start 362.331762 -288.391346)
						(mid 362.311613 -288.274145)
						(end 362.246418 -288.174684)
					)
					(arc
						(start 362.246418 -288.174684)
						(mid 362.039916 -288.089148)
						(end 361.833414 -288.174684)
					)
					(arc
						(start 361.833414 -288.174684)
						(mid 361.768532 -288.272928)
						(end 361.747816 -288.388806)
					)
					(arc
						(start 361.747816 -288.388806)
						(mid 361.751004 -288.409828)
						(end 361.762548 -288.427668)
					)
					(arc
						(start 361.762548 -288.427668)
						(mid 361.798526 -288.442682)
						(end 361.83443 -288.427668)
					)
					(arc
						(start 361.83443 -288.427668)
						(mid 361.843153 -288.415972)
						(end 361.848146 -288.402268)
					)
					(xy 361.848146 -288.38144) (xy 361.848146 -288.380932)
					(arc
						(start 361.848146 -288.379916)
						(mid 361.863148 -288.307318)
						(end 361.904534 -288.245804)
					)
					(arc
						(start 361.904534 -288.245804)
						(mid 362.039916 -288.189727)
						(end 362.175298 -288.245804)
					)
					(arc
						(start 362.175298 -288.245804)
						(mid 362.216898 -288.308152)
						(end 362.231432 -288.381694)
					)
					(xy 362.231178 -288.382456)
					(arc
						(start 362.231178 -288.40303)
						(mid 362.236268 -288.416892)
						(end 362.245148 -288.428684)
					)
				)
			)
		)
		(zone
			(layer "F.Cu")
			(hatch none 0.5)
			(connect_pads
				(clearance 0)
			)
			(min_thickness 0.25)
			(keepout
				(tracks not_allowed)
				(vias allowed)
				(pads allowed)
				(copperpour not_allowed)
				(footprints allowed)
			)
			(placement
				(enabled no)
				(sheetname "")
			)
			(fill
				(thermal_gap 0.5)
				(thermal_bridge_width 0.5)
				(island_removal_mode 0)
			)
			(polygon
				(pts
					(arc
						(start 362.664502 -214.297006)
						(mid 362.628598 -214.282246)
						(end 362.59262 -214.297006)
					)
					(arc
						(start 362.59262 -214.297006)
						(mid 362.581221 -214.314246)
						(end 362.577634 -214.334598)
					)
					(arc
						(start 362.577634 -214.334598)
						(mid 362.597903 -214.451827)
						(end 362.663232 -214.55126)
					)
					(arc
						(start 362.663232 -214.55126)
						(mid 362.869734 -214.636796)
						(end 363.076236 -214.55126)
					)
					(arc
						(start 363.076236 -214.55126)
						(mid 363.141025 -214.452867)
						(end 363.16158 -214.336884)
					)
					(arc
						(start 363.16158 -214.336884)
						(mid 363.15838 -214.315875)
						(end 363.146848 -214.298022)
					)
					(arc
						(start 363.146848 -214.298022)
						(mid 363.110944 -214.283262)
						(end 363.074966 -214.298022)
					)
					(arc
						(start 363.074966 -214.298022)
						(mid 363.066224 -214.309843)
						(end 363.06125 -214.323676)
					)
					(xy 363.06125 -214.344504) (xy 363.06125 -214.344758)
					(arc
						(start 363.06125 -214.345774)
						(mid 363.046412 -214.418479)
						(end 363.005116 -214.48014)
					)
					(arc
						(start 363.005116 -214.48014)
						(mid 362.869734 -214.536217)
						(end 362.734352 -214.48014)
					)
					(arc
						(start 362.734352 -214.48014)
						(mid 362.692703 -214.417674)
						(end 362.678218 -214.343996)
					)
					(xy 362.678472 -214.343488)
					(arc
						(start 362.678472 -214.322914)
						(mid 362.673416 -214.308916)
						(end 362.664502 -214.297006)
					)
				)
			)
		)
		(zone
			(layer "F.Cu")
			(hatch none 0.5)
			(connect_pads
				(clearance 0)
			)
			(min_thickness 0.25)
			(keepout
				(tracks not_allowed)
				(vias allowed)
				(pads allowed)
				(copperpour not_allowed)
				(footprints allowed)
			)
			(placement
				(enabled no)
				(sheetname "")
			)
			(fill
				(thermal_gap 0.5)
				(thermal_bridge_width 0.5)
				(island_removal_mode 0)
			)
			(polygon
				(pts
					(arc
						(start 363.184948 -288.428684)
						(mid 363.220762 -288.443519)
						(end 363.256576 -288.428684)
					)
					(arc
						(start 363.256576 -288.428684)
						(mid 363.267927 -288.411562)
						(end 363.271562 -288.391346)
					)
					(arc
						(start 363.271562 -288.391346)
						(mid 363.251413 -288.274145)
						(end 363.186218 -288.174684)
					)
					(arc
						(start 363.186218 -288.174684)
						(mid 362.979716 -288.089148)
						(end 362.773214 -288.174684)
					)
					(arc
						(start 362.773214 -288.174684)
						(mid 362.708332 -288.272928)
						(end 362.687616 -288.388806)
					)
					(arc
						(start 362.687616 -288.388806)
						(mid 362.690804 -288.409828)
						(end 362.702348 -288.427668)
					)
					(arc
						(start 362.702348 -288.427668)
						(mid 362.738326 -288.442682)
						(end 362.77423 -288.427668)
					)
					(arc
						(start 362.77423 -288.427668)
						(mid 362.782953 -288.415972)
						(end 362.787946 -288.402268)
					)
					(xy 362.787946 -288.38144) (xy 362.787946 -288.380932)
					(arc
						(start 362.787946 -288.379916)
						(mid 362.802948 -288.307318)
						(end 362.844334 -288.245804)
					)
					(arc
						(start 362.844334 -288.245804)
						(mid 362.979716 -288.189727)
						(end 363.115098 -288.245804)
					)
					(arc
						(start 363.115098 -288.245804)
						(mid 363.156698 -288.308152)
						(end 363.171232 -288.381694)
					)
					(xy 363.170978 -288.382456)
					(arc
						(start 363.170978 -288.40303)
						(mid 363.176068 -288.416892)
						(end 363.184948 -288.428684)
					)
				)
			)
		)
		(zone
			(layer "F.Cu")
			(hatch none 0.5)
			(connect_pads
				(clearance 0)
			)
			(min_thickness 0.25)
			(keepout
				(tracks not_allowed)
				(vias allowed)
				(pads allowed)
				(copperpour not_allowed)
				(footprints allowed)
			)
			(placement
				(enabled no)
				(sheetname "")
			)
			(fill
				(thermal_gap 0.5)
				(thermal_bridge_width 0.5)
				(island_removal_mode 0)
			)
			(polygon
				(pts
					(arc
						(start 363.604302 -214.297006)
						(mid 363.568398 -214.282246)
						(end 363.53242 -214.297006)
					)
					(arc
						(start 363.53242 -214.297006)
						(mid 363.521021 -214.314246)
						(end 363.517434 -214.334598)
					)
					(arc
						(start 363.517434 -214.334598)
						(mid 363.537703 -214.451827)
						(end 363.603032 -214.55126)
					)
					(arc
						(start 363.603032 -214.55126)
						(mid 363.809534 -214.636796)
						(end 364.016036 -214.55126)
					)
					(arc
						(start 364.016036 -214.55126)
						(mid 364.080825 -214.452867)
						(end 364.10138 -214.336884)
					)
					(arc
						(start 364.10138 -214.336884)
						(mid 364.09818 -214.315875)
						(end 364.086648 -214.298022)
					)
					(arc
						(start 364.086648 -214.298022)
						(mid 364.050744 -214.283262)
						(end 364.014766 -214.298022)
					)
					(arc
						(start 364.014766 -214.298022)
						(mid 364.006024 -214.309843)
						(end 364.00105 -214.323676)
					)
					(xy 364.00105 -214.344504) (xy 364.00105 -214.344758)
					(arc
						(start 364.00105 -214.345774)
						(mid 363.986212 -214.418479)
						(end 363.944916 -214.48014)
					)
					(arc
						(start 363.944916 -214.48014)
						(mid 363.809534 -214.536217)
						(end 363.674152 -214.48014)
					)
					(arc
						(start 363.674152 -214.48014)
						(mid 363.632503 -214.417674)
						(end 363.618018 -214.343996)
					)
					(xy 363.618272 -214.343488)
					(arc
						(start 363.618272 -214.322914)
						(mid 363.613216 -214.308916)
						(end 363.604302 -214.297006)
					)
				)
			)
		)
		(zone
			(layer "F.Cu")
			(hatch none 0.5)
			(connect_pads
				(clearance 0)
			)
			(min_thickness 0.25)
			(keepout
				(tracks not_allowed)
				(vias allowed)
				(pads allowed)
				(copperpour not_allowed)
				(footprints allowed)
			)
			(placement
				(enabled no)
				(sheetname "")
			)
			(fill
				(thermal_gap 0.5)
				(thermal_bridge_width 0.5)
				(island_removal_mode 0)
			)
			(polygon
				(pts
					(arc
						(start 363.654594 -289.242754)
						(mid 363.690572 -289.257694)
						(end 363.726476 -289.242754)
					)
					(arc
						(start 363.726476 -289.242754)
						(mid 363.737875 -289.225514)
						(end 363.741462 -289.205162)
					)
					(arc
						(start 363.741462 -289.205162)
						(mid 363.721193 -289.087933)
						(end 363.655864 -288.9885)
					)
					(arc
						(start 363.655864 -288.9885)
						(mid 363.449362 -288.902964)
						(end 363.24286 -288.9885)
					)
					(arc
						(start 363.24286 -288.9885)
						(mid 363.178071 -289.086893)
						(end 363.157516 -289.202876)
					)
					(arc
						(start 363.157516 -289.202876)
						(mid 363.160716 -289.223885)
						(end 363.172248 -289.241738)
					)
					(arc
						(start 363.172248 -289.241738)
						(mid 363.208226 -289.256678)
						(end 363.24413 -289.241738)
					)
					(arc
						(start 363.24413 -289.241738)
						(mid 363.252872 -289.229917)
						(end 363.257846 -289.216084)
					)
					(xy 363.257846 -289.195256) (xy 363.257846 -289.195002)
					(arc
						(start 363.257846 -289.193986)
						(mid 363.272684 -289.121281)
						(end 363.31398 -289.05962)
					)
					(arc
						(start 363.31398 -289.05962)
						(mid 363.449362 -289.003543)
						(end 363.584744 -289.05962)
					)
					(arc
						(start 363.584744 -289.05962)
						(mid 363.626393 -289.122086)
						(end 363.640878 -289.195764)
					)
					(xy 363.640624 -289.196272)
					(arc
						(start 363.640624 -289.216846)
						(mid 363.64568 -289.230844)
						(end 363.654594 -289.242754)
					)
				)
			)
		)
		(zone
			(layer "F.Cu")
			(hatch none 0.5)
			(connect_pads
				(clearance 0)
			)
			(min_thickness 0.25)
			(keepout
				(tracks not_allowed)
				(vias allowed)
				(pads allowed)
				(copperpour not_allowed)
				(footprints allowed)
			)
			(placement
				(enabled no)
				(sheetname "")
			)
			(fill
				(thermal_gap 0.5)
				(thermal_bridge_width 0.5)
				(island_removal_mode 0)
			)
			(polygon
				(pts
					(arc
						(start 364.544102 -214.297006)
						(mid 364.508198 -214.282246)
						(end 364.47222 -214.297006)
					)
					(arc
						(start 364.47222 -214.297006)
						(mid 364.460821 -214.314246)
						(end 364.457234 -214.334598)
					)
					(arc
						(start 364.457234 -214.334598)
						(mid 364.477503 -214.451827)
						(end 364.542832 -214.55126)
					)
					(arc
						(start 364.542832 -214.55126)
						(mid 364.749334 -214.636796)
						(end 364.955836 -214.55126)
					)
					(arc
						(start 364.955836 -214.55126)
						(mid 365.020625 -214.452867)
						(end 365.04118 -214.336884)
					)
					(arc
						(start 365.04118 -214.336884)
						(mid 365.03798 -214.315875)
						(end 365.026448 -214.298022)
					)
					(arc
						(start 365.026448 -214.298022)
						(mid 364.990544 -214.283262)
						(end 364.954566 -214.298022)
					)
					(arc
						(start 364.954566 -214.298022)
						(mid 364.945824 -214.309843)
						(end 364.94085 -214.323676)
					)
					(xy 364.94085 -214.344504) (xy 364.94085 -214.344758)
					(arc
						(start 364.94085 -214.345774)
						(mid 364.926012 -214.418479)
						(end 364.884716 -214.48014)
					)
					(arc
						(start 364.884716 -214.48014)
						(mid 364.749334 -214.536217)
						(end 364.613952 -214.48014)
					)
					(arc
						(start 364.613952 -214.48014)
						(mid 364.572303 -214.417674)
						(end 364.557818 -214.343996)
					)
					(xy 364.558072 -214.343488)
					(arc
						(start 364.558072 -214.322914)
						(mid 364.553016 -214.308916)
						(end 364.544102 -214.297006)
					)
				)
			)
		)
		(zone
			(layer "F.Cu")
			(hatch none 0.5)
			(connect_pads
				(clearance 0)
			)
			(min_thickness 0.25)
			(keepout
				(tracks not_allowed)
				(vias allowed)
				(pads allowed)
				(copperpour not_allowed)
				(footprints allowed)
			)
			(placement
				(enabled no)
				(sheetname "")
			)
			(fill
				(thermal_gap 0.5)
				(thermal_bridge_width 0.5)
				(island_removal_mode 0)
			)
			(polygon
				(pts
					(arc
						(start 364.594394 -289.242754)
						(mid 364.630372 -289.257694)
						(end 364.666276 -289.242754)
					)
					(arc
						(start 364.666276 -289.242754)
						(mid 364.677675 -289.225514)
						(end 364.681262 -289.205162)
					)
					(arc
						(start 364.681262 -289.205162)
						(mid 364.660993 -289.087933)
						(end 364.595664 -288.9885)
					)
					(arc
						(start 364.595664 -288.9885)
						(mid 364.389162 -288.902964)
						(end 364.18266 -288.9885)
					)
					(arc
						(start 364.18266 -288.9885)
						(mid 364.117871 -289.086893)
						(end 364.097316 -289.202876)
					)
					(arc
						(start 364.097316 -289.202876)
						(mid 364.100516 -289.223885)
						(end 364.112048 -289.241738)
					)
					(arc
						(start 364.112048 -289.241738)
						(mid 364.148026 -289.256678)
						(end 364.18393 -289.241738)
					)
					(arc
						(start 364.18393 -289.241738)
						(mid 364.192672 -289.229917)
						(end 364.197646 -289.216084)
					)
					(xy 364.197646 -289.195256) (xy 364.197646 -289.195002)
					(arc
						(start 364.197646 -289.193986)
						(mid 364.212484 -289.121281)
						(end 364.25378 -289.05962)
					)
					(arc
						(start 364.25378 -289.05962)
						(mid 364.389162 -289.003543)
						(end 364.524544 -289.05962)
					)
					(arc
						(start 364.524544 -289.05962)
						(mid 364.566193 -289.122086)
						(end 364.580678 -289.195764)
					)
					(xy 364.580424 -289.196272)
					(arc
						(start 364.580424 -289.216846)
						(mid 364.58548 -289.230844)
						(end 364.594394 -289.242754)
					)
				)
			)
		)
		(zone
			(layer "F.Cu")
			(hatch none 0.5)
			(connect_pads
				(clearance 0)
			)
			(min_thickness 0.25)
			(keepout
				(tracks not_allowed)
				(vias allowed)
				(pads allowed)
				(copperpour not_allowed)
				(footprints allowed)
			)
			(placement
				(enabled no)
				(sheetname "")
			)
			(fill
				(thermal_gap 0.5)
				(thermal_bridge_width 0.5)
				(island_removal_mode 0)
			)
			(polygon
				(pts
					(arc
						(start 365.483902 -214.297006)
						(mid 365.447998 -214.282246)
						(end 365.41202 -214.297006)
					)
					(arc
						(start 365.41202 -214.297006)
						(mid 365.400621 -214.314246)
						(end 365.397034 -214.334598)
					)
					(arc
						(start 365.397034 -214.334598)
						(mid 365.417303 -214.451827)
						(end 365.482632 -214.55126)
					)
					(arc
						(start 365.482632 -214.55126)
						(mid 365.689134 -214.636796)
						(end 365.895636 -214.55126)
					)
					(arc
						(start 365.895636 -214.55126)
						(mid 365.960425 -214.452867)
						(end 365.98098 -214.336884)
					)
					(arc
						(start 365.98098 -214.336884)
						(mid 365.97778 -214.315875)
						(end 365.966248 -214.298022)
					)
					(arc
						(start 365.966248 -214.298022)
						(mid 365.930344 -214.283262)
						(end 365.894366 -214.298022)
					)
					(arc
						(start 365.894366 -214.298022)
						(mid 365.885624 -214.309843)
						(end 365.88065 -214.323676)
					)
					(xy 365.88065 -214.344504) (xy 365.88065 -214.344758)
					(arc
						(start 365.88065 -214.345774)
						(mid 365.865812 -214.418479)
						(end 365.824516 -214.48014)
					)
					(arc
						(start 365.824516 -214.48014)
						(mid 365.689134 -214.536217)
						(end 365.553752 -214.48014)
					)
					(arc
						(start 365.553752 -214.48014)
						(mid 365.512103 -214.417674)
						(end 365.497618 -214.343996)
					)
					(xy 365.497872 -214.343488)
					(arc
						(start 365.497872 -214.322914)
						(mid 365.492816 -214.308916)
						(end 365.483902 -214.297006)
					)
				)
			)
		)
		(zone
			(layer "F.Cu")
			(hatch none 0.5)
			(connect_pads
				(clearance 0)
			)
			(min_thickness 0.25)
			(keepout
				(tracks not_allowed)
				(vias allowed)
				(pads allowed)
				(copperpour not_allowed)
				(footprints allowed)
			)
			(placement
				(enabled no)
				(sheetname "")
			)
			(fill
				(thermal_gap 0.5)
				(thermal_bridge_width 0.5)
				(island_removal_mode 0)
			)
			(polygon
				(pts
					(arc
						(start 365.534194 -289.242754)
						(mid 365.570172 -289.257694)
						(end 365.606076 -289.242754)
					)
					(arc
						(start 365.606076 -289.242754)
						(mid 365.617475 -289.225514)
						(end 365.621062 -289.205162)
					)
					(arc
						(start 365.621062 -289.205162)
						(mid 365.600793 -289.087933)
						(end 365.535464 -288.9885)
					)
					(arc
						(start 365.535464 -288.9885)
						(mid 365.328962 -288.902964)
						(end 365.12246 -288.9885)
					)
					(arc
						(start 365.12246 -288.9885)
						(mid 365.057671 -289.086893)
						(end 365.037116 -289.202876)
					)
					(arc
						(start 365.037116 -289.202876)
						(mid 365.040316 -289.223885)
						(end 365.051848 -289.241738)
					)
					(arc
						(start 365.051848 -289.241738)
						(mid 365.087826 -289.256678)
						(end 365.12373 -289.241738)
					)
					(arc
						(start 365.12373 -289.241738)
						(mid 365.132472 -289.229917)
						(end 365.137446 -289.216084)
					)
					(xy 365.137446 -289.195256) (xy 365.137446 -289.195002)
					(arc
						(start 365.137446 -289.193986)
						(mid 365.152284 -289.121281)
						(end 365.19358 -289.05962)
					)
					(arc
						(start 365.19358 -289.05962)
						(mid 365.328962 -289.003543)
						(end 365.464344 -289.05962)
					)
					(arc
						(start 365.464344 -289.05962)
						(mid 365.505993 -289.122086)
						(end 365.520478 -289.195764)
					)
					(xy 365.520224 -289.196272)
					(arc
						(start 365.520224 -289.216846)
						(mid 365.52528 -289.230844)
						(end 365.534194 -289.242754)
					)
				)
			)
		)
		(zone
			(layer "F.Cu")
			(hatch none 0.5)
			(connect_pads
				(clearance 0)
			)
			(min_thickness 0.25)
			(keepout
				(tracks not_allowed)
				(vias allowed)
				(pads allowed)
				(copperpour not_allowed)
				(footprints allowed)
			)
			(placement
				(enabled no)
				(sheetname "")
			)
			(fill
				(thermal_gap 0.5)
				(thermal_bridge_width 0.5)
				(island_removal_mode 0)
			)
			(polygon
				(pts
					(arc
						(start 366.423702 -214.297006)
						(mid 366.387798 -214.282246)
						(end 366.35182 -214.297006)
					)
					(arc
						(start 366.35182 -214.297006)
						(mid 366.340421 -214.314246)
						(end 366.336834 -214.334598)
					)
					(arc
						(start 366.336834 -214.334598)
						(mid 366.357103 -214.451827)
						(end 366.422432 -214.55126)
					)
					(arc
						(start 366.422432 -214.55126)
						(mid 366.628934 -214.636796)
						(end 366.835436 -214.55126)
					)
					(arc
						(start 366.835436 -214.55126)
						(mid 366.900225 -214.452867)
						(end 366.92078 -214.336884)
					)
					(arc
						(start 366.92078 -214.336884)
						(mid 366.91758 -214.315875)
						(end 366.906048 -214.298022)
					)
					(arc
						(start 366.906048 -214.298022)
						(mid 366.870144 -214.283262)
						(end 366.834166 -214.298022)
					)
					(arc
						(start 366.834166 -214.298022)
						(mid 366.825424 -214.309843)
						(end 366.82045 -214.323676)
					)
					(xy 366.82045 -214.344504) (xy 366.82045 -214.344758)
					(arc
						(start 366.82045 -214.345774)
						(mid 366.805612 -214.418479)
						(end 366.764316 -214.48014)
					)
					(arc
						(start 366.764316 -214.48014)
						(mid 366.628934 -214.536217)
						(end 366.493552 -214.48014)
					)
					(arc
						(start 366.493552 -214.48014)
						(mid 366.451903 -214.417674)
						(end 366.437418 -214.343996)
					)
					(xy 366.437672 -214.343488)
					(arc
						(start 366.437672 -214.322914)
						(mid 366.432616 -214.308916)
						(end 366.423702 -214.297006)
					)
				)
			)
		)
		(zone
			(layer "F.Cu")
			(hatch none 0.5)
			(connect_pads
				(clearance 0)
			)
			(min_thickness 0.25)
			(keepout
				(tracks not_allowed)
				(vias allowed)
				(pads allowed)
				(copperpour not_allowed)
				(footprints allowed)
			)
			(placement
				(enabled no)
				(sheetname "")
			)
			(fill
				(thermal_gap 0.5)
				(thermal_bridge_width 0.5)
				(island_removal_mode 0)
			)
			(polygon
				(pts
					(arc
						(start 366.473994 -289.242754)
						(mid 366.509972 -289.257694)
						(end 366.545876 -289.242754)
					)
					(arc
						(start 366.545876 -289.242754)
						(mid 366.557275 -289.225514)
						(end 366.560862 -289.205162)
					)
					(arc
						(start 366.560862 -289.205162)
						(mid 366.540593 -289.087933)
						(end 366.475264 -288.9885)
					)
					(arc
						(start 366.475264 -288.9885)
						(mid 366.268762 -288.902964)
						(end 366.06226 -288.9885)
					)
					(arc
						(start 366.06226 -288.9885)
						(mid 365.997471 -289.086893)
						(end 365.976916 -289.202876)
					)
					(arc
						(start 365.976916 -289.202876)
						(mid 365.980116 -289.223885)
						(end 365.991648 -289.241738)
					)
					(arc
						(start 365.991648 -289.241738)
						(mid 366.027626 -289.256678)
						(end 366.06353 -289.241738)
					)
					(arc
						(start 366.06353 -289.241738)
						(mid 366.072272 -289.229917)
						(end 366.077246 -289.216084)
					)
					(xy 366.077246 -289.195256) (xy 366.077246 -289.195002)
					(arc
						(start 366.077246 -289.193986)
						(mid 366.092084 -289.121281)
						(end 366.13338 -289.05962)
					)
					(arc
						(start 366.13338 -289.05962)
						(mid 366.268762 -289.003543)
						(end 366.404144 -289.05962)
					)
					(arc
						(start 366.404144 -289.05962)
						(mid 366.445793 -289.122086)
						(end 366.460278 -289.195764)
					)
					(xy 366.460024 -289.196272)
					(arc
						(start 366.460024 -289.216846)
						(mid 366.46508 -289.230844)
						(end 366.473994 -289.242754)
					)
				)
			)
		)
		(zone
			(layer "F.Cu")
			(hatch none 0.5)
			(connect_pads
				(clearance 0)
			)
			(min_thickness 0.25)
			(keepout
				(tracks not_allowed)
				(vias allowed)
				(pads allowed)
				(copperpour not_allowed)
				(footprints allowed)
			)
			(placement
				(enabled no)
				(sheetname "")
			)
			(fill
				(thermal_gap 0.5)
				(thermal_bridge_width 0.5)
				(island_removal_mode 0)
			)
			(polygon
				(pts
					(arc
						(start 367.363502 -214.297006)
						(mid 367.327598 -214.282246)
						(end 367.29162 -214.297006)
					)
					(arc
						(start 367.29162 -214.297006)
						(mid 367.280221 -214.314246)
						(end 367.276634 -214.334598)
					)
					(arc
						(start 367.276634 -214.334598)
						(mid 367.296903 -214.451827)
						(end 367.362232 -214.55126)
					)
					(arc
						(start 367.362232 -214.55126)
						(mid 367.568734 -214.636796)
						(end 367.775236 -214.55126)
					)
					(arc
						(start 367.775236 -214.55126)
						(mid 367.840025 -214.452867)
						(end 367.86058 -214.336884)
					)
					(arc
						(start 367.86058 -214.336884)
						(mid 367.85738 -214.315875)
						(end 367.845848 -214.298022)
					)
					(arc
						(start 367.845848 -214.298022)
						(mid 367.809944 -214.283262)
						(end 367.773966 -214.298022)
					)
					(arc
						(start 367.773966 -214.298022)
						(mid 367.765224 -214.309843)
						(end 367.76025 -214.323676)
					)
					(xy 367.76025 -214.344504) (xy 367.76025 -214.344758)
					(arc
						(start 367.76025 -214.345774)
						(mid 367.745412 -214.418479)
						(end 367.704116 -214.48014)
					)
					(arc
						(start 367.704116 -214.48014)
						(mid 367.568734 -214.536217)
						(end 367.433352 -214.48014)
					)
					(arc
						(start 367.433352 -214.48014)
						(mid 367.391703 -214.417674)
						(end 367.377218 -214.343996)
					)
					(xy 367.377472 -214.343488)
					(arc
						(start 367.377472 -214.322914)
						(mid 367.372416 -214.308916)
						(end 367.363502 -214.297006)
					)
				)
			)
		)
		(zone
			(layer "F.Cu")
			(hatch none 0.5)
			(connect_pads
				(clearance 0)
			)
			(min_thickness 0.25)
			(keepout
				(tracks not_allowed)
				(vias allowed)
				(pads allowed)
				(copperpour not_allowed)
				(footprints allowed)
			)
			(placement
				(enabled no)
				(sheetname "")
			)
			(fill
				(thermal_gap 0.5)
				(thermal_bridge_width 0.5)
				(island_removal_mode 0)
			)
			(polygon
				(pts
					(arc
						(start 367.413794 -289.242754)
						(mid 367.449772 -289.257694)
						(end 367.485676 -289.242754)
					)
					(arc
						(start 367.485676 -289.242754)
						(mid 367.497075 -289.225514)
						(end 367.500662 -289.205162)
					)
					(arc
						(start 367.500662 -289.205162)
						(mid 367.480393 -289.087933)
						(end 367.415064 -288.9885)
					)
					(arc
						(start 367.415064 -288.9885)
						(mid 367.208562 -288.902964)
						(end 367.00206 -288.9885)
					)
					(arc
						(start 367.00206 -288.9885)
						(mid 366.937271 -289.086893)
						(end 366.916716 -289.202876)
					)
					(arc
						(start 366.916716 -289.202876)
						(mid 366.919916 -289.223885)
						(end 366.931448 -289.241738)
					)
					(arc
						(start 366.931448 -289.241738)
						(mid 366.967426 -289.256678)
						(end 367.00333 -289.241738)
					)
					(arc
						(start 367.00333 -289.241738)
						(mid 367.012072 -289.229917)
						(end 367.017046 -289.216084)
					)
					(xy 367.017046 -289.195256) (xy 367.017046 -289.195002)
					(arc
						(start 367.017046 -289.193986)
						(mid 367.031884 -289.121281)
						(end 367.07318 -289.05962)
					)
					(arc
						(start 367.07318 -289.05962)
						(mid 367.208562 -289.003543)
						(end 367.343944 -289.05962)
					)
					(arc
						(start 367.343944 -289.05962)
						(mid 367.385593 -289.122086)
						(end 367.400078 -289.195764)
					)
					(xy 367.399824 -289.196272)
					(arc
						(start 367.399824 -289.216846)
						(mid 367.40488 -289.230844)
						(end 367.413794 -289.242754)
					)
				)
			)
		)
		(zone
			(layer "F.Cu")
			(hatch none 0.5)
			(connect_pads
				(clearance 0)
			)
			(min_thickness 0.25)
			(keepout
				(tracks not_allowed)
				(vias allowed)
				(pads allowed)
				(copperpour not_allowed)
				(footprints allowed)
			)
			(placement
				(enabled no)
				(sheetname "")
			)
			(fill
				(thermal_gap 0.5)
				(thermal_bridge_width 0.5)
				(island_removal_mode 0)
			)
			(polygon
				(pts
					(arc
						(start 368.303302 -214.297006)
						(mid 368.267398 -214.282246)
						(end 368.23142 -214.297006)
					)
					(arc
						(start 368.23142 -214.297006)
						(mid 368.220021 -214.314246)
						(end 368.216434 -214.334598)
					)
					(arc
						(start 368.216434 -214.334598)
						(mid 368.236703 -214.451827)
						(end 368.302032 -214.55126)
					)
					(arc
						(start 368.302032 -214.55126)
						(mid 368.508534 -214.636796)
						(end 368.715036 -214.55126)
					)
					(arc
						(start 368.715036 -214.55126)
						(mid 368.779825 -214.452867)
						(end 368.80038 -214.336884)
					)
					(arc
						(start 368.80038 -214.336884)
						(mid 368.79718 -214.315875)
						(end 368.785648 -214.298022)
					)
					(arc
						(start 368.785648 -214.298022)
						(mid 368.749744 -214.283262)
						(end 368.713766 -214.298022)
					)
					(arc
						(start 368.713766 -214.298022)
						(mid 368.705024 -214.309843)
						(end 368.70005 -214.323676)
					)
					(xy 368.70005 -214.344504) (xy 368.70005 -214.344758)
					(arc
						(start 368.70005 -214.345774)
						(mid 368.685212 -214.418479)
						(end 368.643916 -214.48014)
					)
					(arc
						(start 368.643916 -214.48014)
						(mid 368.508534 -214.536217)
						(end 368.373152 -214.48014)
					)
					(arc
						(start 368.373152 -214.48014)
						(mid 368.331503 -214.417674)
						(end 368.317018 -214.343996)
					)
					(xy 368.317272 -214.343488)
					(arc
						(start 368.317272 -214.322914)
						(mid 368.312216 -214.308916)
						(end 368.303302 -214.297006)
					)
				)
			)
		)
		(zone
			(layer "F.Cu")
			(hatch none 0.5)
			(connect_pads
				(clearance 0)
			)
			(min_thickness 0.25)
			(keepout
				(tracks not_allowed)
				(vias allowed)
				(pads allowed)
				(copperpour not_allowed)
				(footprints allowed)
			)
			(placement
				(enabled no)
				(sheetname "")
			)
			(fill
				(thermal_gap 0.5)
				(thermal_bridge_width 0.5)
				(island_removal_mode 0)
			)
			(polygon
				(pts
					(arc
						(start 368.353594 -289.242754)
						(mid 368.389572 -289.257694)
						(end 368.425476 -289.242754)
					)
					(arc
						(start 368.425476 -289.242754)
						(mid 368.436875 -289.225514)
						(end 368.440462 -289.205162)
					)
					(arc
						(start 368.440462 -289.205162)
						(mid 368.420193 -289.087933)
						(end 368.354864 -288.9885)
					)
					(arc
						(start 368.354864 -288.9885)
						(mid 368.148362 -288.902964)
						(end 367.94186 -288.9885)
					)
					(arc
						(start 367.94186 -288.9885)
						(mid 367.877071 -289.086893)
						(end 367.856516 -289.202876)
					)
					(arc
						(start 367.856516 -289.202876)
						(mid 367.859716 -289.223885)
						(end 367.871248 -289.241738)
					)
					(arc
						(start 367.871248 -289.241738)
						(mid 367.907226 -289.256678)
						(end 367.94313 -289.241738)
					)
					(arc
						(start 367.94313 -289.241738)
						(mid 367.951872 -289.229917)
						(end 367.956846 -289.216084)
					)
					(xy 367.956846 -289.195256) (xy 367.956846 -289.195002)
					(arc
						(start 367.956846 -289.193986)
						(mid 367.971684 -289.121281)
						(end 368.01298 -289.05962)
					)
					(arc
						(start 368.01298 -289.05962)
						(mid 368.148362 -289.003543)
						(end 368.283744 -289.05962)
					)
					(arc
						(start 368.283744 -289.05962)
						(mid 368.325393 -289.122086)
						(end 368.339878 -289.195764)
					)
					(xy 368.339624 -289.196272)
					(arc
						(start 368.339624 -289.216846)
						(mid 368.34468 -289.230844)
						(end 368.353594 -289.242754)
					)
				)
			)
		)
		(zone
			(layer "F.Cu")
			(hatch none 0.5)
			(connect_pads
				(clearance 0)
			)
			(min_thickness 0.25)
			(keepout
				(tracks not_allowed)
				(vias allowed)
				(pads allowed)
				(copperpour not_allowed)
				(footprints allowed)
			)
			(placement
				(enabled no)
				(sheetname "")
			)
			(fill
				(thermal_gap 0.5)
				(thermal_bridge_width 0.5)
				(island_removal_mode 0)
			)
			(polygon
				(pts
					(arc
						(start 369.243102 -214.297006)
						(mid 369.207198 -214.282246)
						(end 369.17122 -214.297006)
					)
					(arc
						(start 369.17122 -214.297006)
						(mid 369.159821 -214.314246)
						(end 369.156234 -214.334598)
					)
					(arc
						(start 369.156234 -214.334598)
						(mid 369.176503 -214.451827)
						(end 369.241832 -214.55126)
					)
					(arc
						(start 369.241832 -214.55126)
						(mid 369.448334 -214.636796)
						(end 369.654836 -214.55126)
					)
					(arc
						(start 369.654836 -214.55126)
						(mid 369.719625 -214.452867)
						(end 369.74018 -214.336884)
					)
					(arc
						(start 369.74018 -214.336884)
						(mid 369.73698 -214.315875)
						(end 369.725448 -214.298022)
					)
					(arc
						(start 369.725448 -214.298022)
						(mid 369.689544 -214.283262)
						(end 369.653566 -214.298022)
					)
					(arc
						(start 369.653566 -214.298022)
						(mid 369.644824 -214.309843)
						(end 369.63985 -214.323676)
					)
					(xy 369.63985 -214.344504) (xy 369.63985 -214.344758)
					(arc
						(start 369.63985 -214.345774)
						(mid 369.625012 -214.418479)
						(end 369.583716 -214.48014)
					)
					(arc
						(start 369.583716 -214.48014)
						(mid 369.448334 -214.536217)
						(end 369.312952 -214.48014)
					)
					(arc
						(start 369.312952 -214.48014)
						(mid 369.271303 -214.417674)
						(end 369.256818 -214.343996)
					)
					(xy 369.257072 -214.343488)
					(arc
						(start 369.257072 -214.322914)
						(mid 369.252016 -214.308916)
						(end 369.243102 -214.297006)
					)
				)
			)
		)
		(zone
			(layer "F.Cu")
			(hatch none 0.5)
			(connect_pads
				(clearance 0)
			)
			(min_thickness 0.25)
			(keepout
				(tracks not_allowed)
				(vias allowed)
				(pads allowed)
				(copperpour not_allowed)
				(footprints allowed)
			)
			(placement
				(enabled no)
				(sheetname "")
			)
			(fill
				(thermal_gap 0.5)
				(thermal_bridge_width 0.5)
				(island_removal_mode 0)
			)
			(polygon
				(pts
					(arc
						(start 369.293394 -289.242754)
						(mid 369.329372 -289.257694)
						(end 369.365276 -289.242754)
					)
					(arc
						(start 369.365276 -289.242754)
						(mid 369.376675 -289.225514)
						(end 369.380262 -289.205162)
					)
					(arc
						(start 369.380262 -289.205162)
						(mid 369.359993 -289.087933)
						(end 369.294664 -288.9885)
					)
					(arc
						(start 369.294664 -288.9885)
						(mid 369.088162 -288.902964)
						(end 368.88166 -288.9885)
					)
					(arc
						(start 368.88166 -288.9885)
						(mid 368.816871 -289.086893)
						(end 368.796316 -289.202876)
					)
					(arc
						(start 368.796316 -289.202876)
						(mid 368.799516 -289.223885)
						(end 368.811048 -289.241738)
					)
					(arc
						(start 368.811048 -289.241738)
						(mid 368.847026 -289.256678)
						(end 368.88293 -289.241738)
					)
					(arc
						(start 368.88293 -289.241738)
						(mid 368.891672 -289.229917)
						(end 368.896646 -289.216084)
					)
					(xy 368.896646 -289.195256) (xy 368.896646 -289.195002)
					(arc
						(start 368.896646 -289.193986)
						(mid 368.911484 -289.121281)
						(end 368.95278 -289.05962)
					)
					(arc
						(start 368.95278 -289.05962)
						(mid 369.088162 -289.003543)
						(end 369.223544 -289.05962)
					)
					(arc
						(start 369.223544 -289.05962)
						(mid 369.265193 -289.122086)
						(end 369.279678 -289.195764)
					)
					(xy 369.279424 -289.196272)
					(arc
						(start 369.279424 -289.216846)
						(mid 369.28448 -289.230844)
						(end 369.293394 -289.242754)
					)
				)
			)
		)
		(zone
			(layer "F.Cu")
			(hatch none 0.5)
			(connect_pads
				(clearance 0)
			)
			(min_thickness 0.25)
			(keepout
				(tracks not_allowed)
				(vias allowed)
				(pads allowed)
				(copperpour not_allowed)
				(footprints allowed)
			)
			(placement
				(enabled no)
				(sheetname "")
			)
			(fill
				(thermal_gap 0.5)
				(thermal_bridge_width 0.5)
				(island_removal_mode 0)
			)
			(polygon
				(pts
					(arc
						(start 370.182902 -214.297006)
						(mid 370.146998 -214.282246)
						(end 370.11102 -214.297006)
					)
					(arc
						(start 370.11102 -214.297006)
						(mid 370.099621 -214.314246)
						(end 370.096034 -214.334598)
					)
					(arc
						(start 370.096034 -214.334598)
						(mid 370.116303 -214.451827)
						(end 370.181632 -214.55126)
					)
					(arc
						(start 370.181632 -214.55126)
						(mid 370.388134 -214.636796)
						(end 370.594636 -214.55126)
					)
					(arc
						(start 370.594636 -214.55126)
						(mid 370.659425 -214.452867)
						(end 370.67998 -214.336884)
					)
					(arc
						(start 370.67998 -214.336884)
						(mid 370.67678 -214.315875)
						(end 370.665248 -214.298022)
					)
					(arc
						(start 370.665248 -214.298022)
						(mid 370.629344 -214.283262)
						(end 370.593366 -214.298022)
					)
					(arc
						(start 370.593366 -214.298022)
						(mid 370.584624 -214.309843)
						(end 370.57965 -214.323676)
					)
					(xy 370.57965 -214.344504) (xy 370.57965 -214.344758)
					(arc
						(start 370.57965 -214.345774)
						(mid 370.564812 -214.418479)
						(end 370.523516 -214.48014)
					)
					(arc
						(start 370.523516 -214.48014)
						(mid 370.388134 -214.536217)
						(end 370.252752 -214.48014)
					)
					(arc
						(start 370.252752 -214.48014)
						(mid 370.211103 -214.417674)
						(end 370.196618 -214.343996)
					)
					(xy 370.196872 -214.343488)
					(arc
						(start 370.196872 -214.322914)
						(mid 370.191816 -214.308916)
						(end 370.182902 -214.297006)
					)
				)
			)
		)
		(zone
			(layer "F.Cu")
			(hatch none 0.5)
			(connect_pads
				(clearance 0)
			)
			(min_thickness 0.25)
			(keepout
				(tracks not_allowed)
				(vias allowed)
				(pads allowed)
				(copperpour not_allowed)
				(footprints allowed)
			)
			(placement
				(enabled no)
				(sheetname "")
			)
			(fill
				(thermal_gap 0.5)
				(thermal_bridge_width 0.5)
				(island_removal_mode 0)
			)
			(polygon
				(pts
					(arc
						(start 370.233194 -289.242754)
						(mid 370.269172 -289.257694)
						(end 370.305076 -289.242754)
					)
					(arc
						(start 370.305076 -289.242754)
						(mid 370.316475 -289.225514)
						(end 370.320062 -289.205162)
					)
					(arc
						(start 370.320062 -289.205162)
						(mid 370.299793 -289.087933)
						(end 370.234464 -288.9885)
					)
					(arc
						(start 370.234464 -288.9885)
						(mid 370.027962 -288.902964)
						(end 369.82146 -288.9885)
					)
					(arc
						(start 369.82146 -288.9885)
						(mid 369.756671 -289.086893)
						(end 369.736116 -289.202876)
					)
					(arc
						(start 369.736116 -289.202876)
						(mid 369.739316 -289.223885)
						(end 369.750848 -289.241738)
					)
					(arc
						(start 369.750848 -289.241738)
						(mid 369.786826 -289.256678)
						(end 369.82273 -289.241738)
					)
					(arc
						(start 369.82273 -289.241738)
						(mid 369.831472 -289.229917)
						(end 369.836446 -289.216084)
					)
					(xy 369.836446 -289.195256) (xy 369.836446 -289.195002)
					(arc
						(start 369.836446 -289.193986)
						(mid 369.851284 -289.121281)
						(end 369.89258 -289.05962)
					)
					(arc
						(start 369.89258 -289.05962)
						(mid 370.027962 -289.003543)
						(end 370.163344 -289.05962)
					)
					(arc
						(start 370.163344 -289.05962)
						(mid 370.204993 -289.122086)
						(end 370.219478 -289.195764)
					)
					(xy 370.219224 -289.196272)
					(arc
						(start 370.219224 -289.216846)
						(mid 370.22428 -289.230844)
						(end 370.233194 -289.242754)
					)
				)
			)
		)
		(zone
			(layer "F.Cu")
			(hatch none 0.5)
			(connect_pads
				(clearance 0)
			)
			(min_thickness 0.25)
			(keepout
				(tracks not_allowed)
				(vias allowed)
				(pads allowed)
				(copperpour not_allowed)
				(footprints allowed)
			)
			(placement
				(enabled no)
				(sheetname "")
			)
			(fill
				(thermal_gap 0.5)
				(thermal_bridge_width 0.5)
				(island_removal_mode 0)
			)
			(polygon
				(pts
					(arc
						(start 371.122702 -214.297006)
						(mid 371.086798 -214.282246)
						(end 371.05082 -214.297006)
					)
					(arc
						(start 371.05082 -214.297006)
						(mid 371.039421 -214.314246)
						(end 371.035834 -214.334598)
					)
					(arc
						(start 371.035834 -214.334598)
						(mid 371.056103 -214.451827)
						(end 371.121432 -214.55126)
					)
					(arc
						(start 371.121432 -214.55126)
						(mid 371.327934 -214.636796)
						(end 371.534436 -214.55126)
					)
					(arc
						(start 371.534436 -214.55126)
						(mid 371.599225 -214.452867)
						(end 371.61978 -214.336884)
					)
					(arc
						(start 371.61978 -214.336884)
						(mid 371.61658 -214.315875)
						(end 371.605048 -214.298022)
					)
					(arc
						(start 371.605048 -214.298022)
						(mid 371.569144 -214.283262)
						(end 371.533166 -214.298022)
					)
					(arc
						(start 371.533166 -214.298022)
						(mid 371.524424 -214.309843)
						(end 371.51945 -214.323676)
					)
					(xy 371.51945 -214.344504) (xy 371.51945 -214.344758)
					(arc
						(start 371.51945 -214.345774)
						(mid 371.504612 -214.418479)
						(end 371.463316 -214.48014)
					)
					(arc
						(start 371.463316 -214.48014)
						(mid 371.327934 -214.536217)
						(end 371.192552 -214.48014)
					)
					(arc
						(start 371.192552 -214.48014)
						(mid 371.150903 -214.417674)
						(end 371.136418 -214.343996)
					)
					(xy 371.136672 -214.343488)
					(arc
						(start 371.136672 -214.322914)
						(mid 371.131616 -214.308916)
						(end 371.122702 -214.297006)
					)
				)
			)
		)
		(zone
			(layer "F.Cu")
			(hatch none 0.5)
			(connect_pads
				(clearance 0)
			)
			(min_thickness 0.25)
			(keepout
				(tracks not_allowed)
				(vias allowed)
				(pads allowed)
				(copperpour not_allowed)
				(footprints allowed)
			)
			(placement
				(enabled no)
				(sheetname "")
			)
			(fill
				(thermal_gap 0.5)
				(thermal_bridge_width 0.5)
				(island_removal_mode 0)
			)
			(polygon
				(pts
					(arc
						(start 371.172994 -289.242754)
						(mid 371.208972 -289.257694)
						(end 371.244876 -289.242754)
					)
					(arc
						(start 371.244876 -289.242754)
						(mid 371.256275 -289.225514)
						(end 371.259862 -289.205162)
					)
					(arc
						(start 371.259862 -289.205162)
						(mid 371.239593 -289.087933)
						(end 371.174264 -288.9885)
					)
					(arc
						(start 371.174264 -288.9885)
						(mid 370.967762 -288.902964)
						(end 370.76126 -288.9885)
					)
					(arc
						(start 370.76126 -288.9885)
						(mid 370.696471 -289.086893)
						(end 370.675916 -289.202876)
					)
					(arc
						(start 370.675916 -289.202876)
						(mid 370.679116 -289.223885)
						(end 370.690648 -289.241738)
					)
					(arc
						(start 370.690648 -289.241738)
						(mid 370.726626 -289.256678)
						(end 370.76253 -289.241738)
					)
					(arc
						(start 370.76253 -289.241738)
						(mid 370.771272 -289.229917)
						(end 370.776246 -289.216084)
					)
					(xy 370.776246 -289.195256) (xy 370.776246 -289.195002)
					(arc
						(start 370.776246 -289.193986)
						(mid 370.791084 -289.121281)
						(end 370.83238 -289.05962)
					)
					(arc
						(start 370.83238 -289.05962)
						(mid 370.967762 -289.003543)
						(end 371.103144 -289.05962)
					)
					(arc
						(start 371.103144 -289.05962)
						(mid 371.144793 -289.122086)
						(end 371.159278 -289.195764)
					)
					(xy 371.159024 -289.196272)
					(arc
						(start 371.159024 -289.216846)
						(mid 371.16408 -289.230844)
						(end 371.172994 -289.242754)
					)
				)
			)
		)
		(zone
			(layer "F.Cu")
			(hatch none 0.5)
			(connect_pads
				(clearance 0)
			)
			(min_thickness 0.25)
			(keepout
				(tracks not_allowed)
				(vias allowed)
				(pads allowed)
				(copperpour not_allowed)
				(footprints allowed)
			)
			(placement
				(enabled no)
				(sheetname "")
			)
			(fill
				(thermal_gap 0.5)
				(thermal_bridge_width 0.5)
				(island_removal_mode 0)
			)
			(polygon
				(pts
					(arc
						(start 372.062502 -214.297006)
						(mid 372.026598 -214.282246)
						(end 371.99062 -214.297006)
					)
					(arc
						(start 371.99062 -214.297006)
						(mid 371.979221 -214.314246)
						(end 371.975634 -214.334598)
					)
					(arc
						(start 371.975634 -214.334598)
						(mid 371.995903 -214.451827)
						(end 372.061232 -214.55126)
					)
					(arc
						(start 372.061232 -214.55126)
						(mid 372.267734 -214.636796)
						(end 372.474236 -214.55126)
					)
					(arc
						(start 372.474236 -214.55126)
						(mid 372.539025 -214.452867)
						(end 372.55958 -214.336884)
					)
					(arc
						(start 372.55958 -214.336884)
						(mid 372.55638 -214.315875)
						(end 372.544848 -214.298022)
					)
					(arc
						(start 372.544848 -214.298022)
						(mid 372.508944 -214.283262)
						(end 372.472966 -214.298022)
					)
					(arc
						(start 372.472966 -214.298022)
						(mid 372.464224 -214.309843)
						(end 372.45925 -214.323676)
					)
					(xy 372.45925 -214.344504) (xy 372.45925 -214.344758)
					(arc
						(start 372.45925 -214.345774)
						(mid 372.444412 -214.418479)
						(end 372.403116 -214.48014)
					)
					(arc
						(start 372.403116 -214.48014)
						(mid 372.267734 -214.536217)
						(end 372.132352 -214.48014)
					)
					(arc
						(start 372.132352 -214.48014)
						(mid 372.090703 -214.417674)
						(end 372.076218 -214.343996)
					)
					(xy 372.076472 -214.343488)
					(arc
						(start 372.076472 -214.322914)
						(mid 372.071416 -214.308916)
						(end 372.062502 -214.297006)
					)
				)
			)
		)
		(zone
			(layer "F.Cu")
			(hatch none 0.5)
			(connect_pads
				(clearance 0)
			)
			(min_thickness 0.25)
			(keepout
				(tracks not_allowed)
				(vias allowed)
				(pads allowed)
				(copperpour not_allowed)
				(footprints allowed)
			)
			(placement
				(enabled no)
				(sheetname "")
			)
			(fill
				(thermal_gap 0.5)
				(thermal_bridge_width 0.5)
				(island_removal_mode 0)
			)
			(polygon
				(pts
					(arc
						(start 372.112794 -289.242754)
						(mid 372.148772 -289.257694)
						(end 372.184676 -289.242754)
					)
					(arc
						(start 372.184676 -289.242754)
						(mid 372.196075 -289.225514)
						(end 372.199662 -289.205162)
					)
					(arc
						(start 372.199662 -289.205162)
						(mid 372.179393 -289.087933)
						(end 372.114064 -288.9885)
					)
					(arc
						(start 372.114064 -288.9885)
						(mid 371.907562 -288.902964)
						(end 371.70106 -288.9885)
					)
					(arc
						(start 371.70106 -288.9885)
						(mid 371.636271 -289.086893)
						(end 371.615716 -289.202876)
					)
					(arc
						(start 371.615716 -289.202876)
						(mid 371.618916 -289.223885)
						(end 371.630448 -289.241738)
					)
					(arc
						(start 371.630448 -289.241738)
						(mid 371.666426 -289.256678)
						(end 371.70233 -289.241738)
					)
					(arc
						(start 371.70233 -289.241738)
						(mid 371.711072 -289.229917)
						(end 371.716046 -289.216084)
					)
					(xy 371.716046 -289.195256) (xy 371.716046 -289.195002)
					(arc
						(start 371.716046 -289.193986)
						(mid 371.730884 -289.121281)
						(end 371.77218 -289.05962)
					)
					(arc
						(start 371.77218 -289.05962)
						(mid 371.907562 -289.003543)
						(end 372.042944 -289.05962)
					)
					(arc
						(start 372.042944 -289.05962)
						(mid 372.084593 -289.122086)
						(end 372.099078 -289.195764)
					)
					(xy 372.098824 -289.196272)
					(arc
						(start 372.098824 -289.216846)
						(mid 372.10388 -289.230844)
						(end 372.112794 -289.242754)
					)
				)
			)
		)
		(zone
			(layer "F.Cu")
			(hatch none 0.5)
			(connect_pads
				(clearance 0)
			)
			(min_thickness 0.25)
			(keepout
				(tracks not_allowed)
				(vias allowed)
				(pads allowed)
				(copperpour not_allowed)
				(footprints allowed)
			)
			(placement
				(enabled no)
				(sheetname "")
			)
			(fill
				(thermal_gap 0.5)
				(thermal_bridge_width 0.5)
				(island_removal_mode 0)
			)
			(polygon
				(pts
					(arc
						(start 373.002302 -214.297006)
						(mid 372.966398 -214.282246)
						(end 372.93042 -214.297006)
					)
					(arc
						(start 372.93042 -214.297006)
						(mid 372.919021 -214.314246)
						(end 372.915434 -214.334598)
					)
					(arc
						(start 372.915434 -214.334598)
						(mid 372.935703 -214.451827)
						(end 373.001032 -214.55126)
					)
					(arc
						(start 373.001032 -214.55126)
						(mid 373.207534 -214.636796)
						(end 373.414036 -214.55126)
					)
					(arc
						(start 373.414036 -214.55126)
						(mid 373.478825 -214.452867)
						(end 373.49938 -214.336884)
					)
					(arc
						(start 373.49938 -214.336884)
						(mid 373.49618 -214.315875)
						(end 373.484648 -214.298022)
					)
					(arc
						(start 373.484648 -214.298022)
						(mid 373.448744 -214.283262)
						(end 373.412766 -214.298022)
					)
					(arc
						(start 373.412766 -214.298022)
						(mid 373.404024 -214.309843)
						(end 373.39905 -214.323676)
					)
					(xy 373.39905 -214.344504) (xy 373.39905 -214.344758)
					(arc
						(start 373.39905 -214.345774)
						(mid 373.384212 -214.418479)
						(end 373.342916 -214.48014)
					)
					(arc
						(start 373.342916 -214.48014)
						(mid 373.207534 -214.536217)
						(end 373.072152 -214.48014)
					)
					(arc
						(start 373.072152 -214.48014)
						(mid 373.030503 -214.417674)
						(end 373.016018 -214.343996)
					)
					(xy 373.016272 -214.343488)
					(arc
						(start 373.016272 -214.322914)
						(mid 373.011216 -214.308916)
						(end 373.002302 -214.297006)
					)
				)
			)
		)
		(zone
			(layer "F.Cu")
			(hatch none 0.5)
			(connect_pads
				(clearance 0)
			)
			(min_thickness 0.25)
			(keepout
				(tracks not_allowed)
				(vias allowed)
				(pads allowed)
				(copperpour not_allowed)
				(footprints allowed)
			)
			(placement
				(enabled no)
				(sheetname "")
			)
			(fill
				(thermal_gap 0.5)
				(thermal_bridge_width 0.5)
				(island_removal_mode 0)
			)
			(polygon
				(pts
					(arc
						(start 373.052594 -289.242754)
						(mid 373.088572 -289.257694)
						(end 373.124476 -289.242754)
					)
					(arc
						(start 373.124476 -289.242754)
						(mid 373.135875 -289.225514)
						(end 373.139462 -289.205162)
					)
					(arc
						(start 373.139462 -289.205162)
						(mid 373.119193 -289.087933)
						(end 373.053864 -288.9885)
					)
					(arc
						(start 373.053864 -288.9885)
						(mid 372.847362 -288.902964)
						(end 372.64086 -288.9885)
					)
					(arc
						(start 372.64086 -288.9885)
						(mid 372.576071 -289.086893)
						(end 372.555516 -289.202876)
					)
					(arc
						(start 372.555516 -289.202876)
						(mid 372.558716 -289.223885)
						(end 372.570248 -289.241738)
					)
					(arc
						(start 372.570248 -289.241738)
						(mid 372.606226 -289.256678)
						(end 372.64213 -289.241738)
					)
					(arc
						(start 372.64213 -289.241738)
						(mid 372.650872 -289.229917)
						(end 372.655846 -289.216084)
					)
					(xy 372.655846 -289.195256) (xy 372.655846 -289.195002)
					(arc
						(start 372.655846 -289.193986)
						(mid 372.670684 -289.121281)
						(end 372.71198 -289.05962)
					)
					(arc
						(start 372.71198 -289.05962)
						(mid 372.847362 -289.003543)
						(end 372.982744 -289.05962)
					)
					(arc
						(start 372.982744 -289.05962)
						(mid 373.024393 -289.122086)
						(end 373.038878 -289.195764)
					)
					(xy 373.038624 -289.196272)
					(arc
						(start 373.038624 -289.216846)
						(mid 373.04368 -289.230844)
						(end 373.052594 -289.242754)
					)
				)
			)
		)
		(zone
			(layer "F.Cu")
			(hatch none 0.5)
			(connect_pads
				(clearance 0)
			)
			(min_thickness 0.25)
			(keepout
				(tracks not_allowed)
				(vias allowed)
				(pads allowed)
				(copperpour not_allowed)
				(footprints allowed)
			)
			(placement
				(enabled no)
				(sheetname "")
			)
			(fill
				(thermal_gap 0.5)
				(thermal_bridge_width 0.5)
				(island_removal_mode 0)
			)
			(polygon
				(pts
					(arc
						(start 373.942102 -214.297006)
						(mid 373.906198 -214.282246)
						(end 373.87022 -214.297006)
					)
					(arc
						(start 373.87022 -214.297006)
						(mid 373.858821 -214.314246)
						(end 373.855234 -214.334598)
					)
					(arc
						(start 373.855234 -214.334598)
						(mid 373.875503 -214.451827)
						(end 373.940832 -214.55126)
					)
					(arc
						(start 373.940832 -214.55126)
						(mid 374.147334 -214.636796)
						(end 374.353836 -214.55126)
					)
					(arc
						(start 374.353836 -214.55126)
						(mid 374.418625 -214.452867)
						(end 374.43918 -214.336884)
					)
					(arc
						(start 374.43918 -214.336884)
						(mid 374.43598 -214.315875)
						(end 374.424448 -214.298022)
					)
					(arc
						(start 374.424448 -214.298022)
						(mid 374.388544 -214.283262)
						(end 374.352566 -214.298022)
					)
					(arc
						(start 374.352566 -214.298022)
						(mid 374.343824 -214.309843)
						(end 374.33885 -214.323676)
					)
					(xy 374.33885 -214.344504) (xy 374.33885 -214.344758)
					(arc
						(start 374.33885 -214.345774)
						(mid 374.324012 -214.418479)
						(end 374.282716 -214.48014)
					)
					(arc
						(start 374.282716 -214.48014)
						(mid 374.147334 -214.536217)
						(end 374.011952 -214.48014)
					)
					(arc
						(start 374.011952 -214.48014)
						(mid 373.970303 -214.417674)
						(end 373.955818 -214.343996)
					)
					(xy 373.956072 -214.343488)
					(arc
						(start 373.956072 -214.322914)
						(mid 373.951016 -214.308916)
						(end 373.942102 -214.297006)
					)
				)
			)
		)
		(zone
			(layer "F.Cu")
			(hatch none 0.5)
			(connect_pads
				(clearance 0)
			)
			(min_thickness 0.25)
			(keepout
				(tracks not_allowed)
				(vias allowed)
				(pads allowed)
				(copperpour not_allowed)
				(footprints allowed)
			)
			(placement
				(enabled no)
				(sheetname "")
			)
			(fill
				(thermal_gap 0.5)
				(thermal_bridge_width 0.5)
				(island_removal_mode 0)
			)
			(polygon
				(pts
					(arc
						(start 373.992394 -289.242754)
						(mid 374.028372 -289.257694)
						(end 374.064276 -289.242754)
					)
					(arc
						(start 374.064276 -289.242754)
						(mid 374.075675 -289.225514)
						(end 374.079262 -289.205162)
					)
					(arc
						(start 374.079262 -289.205162)
						(mid 374.058993 -289.087933)
						(end 373.993664 -288.9885)
					)
					(arc
						(start 373.993664 -288.9885)
						(mid 373.787162 -288.902964)
						(end 373.58066 -288.9885)
					)
					(arc
						(start 373.58066 -288.9885)
						(mid 373.515871 -289.086893)
						(end 373.495316 -289.202876)
					)
					(arc
						(start 373.495316 -289.202876)
						(mid 373.498516 -289.223885)
						(end 373.510048 -289.241738)
					)
					(arc
						(start 373.510048 -289.241738)
						(mid 373.546026 -289.256678)
						(end 373.58193 -289.241738)
					)
					(arc
						(start 373.58193 -289.241738)
						(mid 373.590672 -289.229917)
						(end 373.595646 -289.216084)
					)
					(xy 373.595646 -289.195256) (xy 373.595646 -289.195002)
					(arc
						(start 373.595646 -289.193986)
						(mid 373.610484 -289.121281)
						(end 373.65178 -289.05962)
					)
					(arc
						(start 373.65178 -289.05962)
						(mid 373.787162 -289.003543)
						(end 373.922544 -289.05962)
					)
					(arc
						(start 373.922544 -289.05962)
						(mid 373.964193 -289.122086)
						(end 373.978678 -289.195764)
					)
					(xy 373.978424 -289.196272)
					(arc
						(start 373.978424 -289.216846)
						(mid 373.98348 -289.230844)
						(end 373.992394 -289.242754)
					)
				)
			)
		)
		(zone
			(layer "F.Cu")
			(hatch none 0.5)
			(connect_pads
				(clearance 0)
			)
			(min_thickness 0.25)
			(keepout
				(tracks not_allowed)
				(vias allowed)
				(pads allowed)
				(copperpour not_allowed)
				(footprints allowed)
			)
			(placement
				(enabled no)
				(sheetname "")
			)
			(fill
				(thermal_gap 0.5)
				(thermal_bridge_width 0.5)
				(island_removal_mode 0)
			)
			(polygon
				(pts
					(arc
						(start 374.881902 -214.297006)
						(mid 374.845998 -214.282246)
						(end 374.81002 -214.297006)
					)
					(arc
						(start 374.81002 -214.297006)
						(mid 374.798621 -214.314246)
						(end 374.795034 -214.334598)
					)
					(arc
						(start 374.795034 -214.334598)
						(mid 374.815303 -214.451827)
						(end 374.880632 -214.55126)
					)
					(arc
						(start 374.880632 -214.55126)
						(mid 375.087134 -214.636796)
						(end 375.293636 -214.55126)
					)
					(arc
						(start 375.293636 -214.55126)
						(mid 375.358425 -214.452867)
						(end 375.37898 -214.336884)
					)
					(arc
						(start 375.37898 -214.336884)
						(mid 375.37578 -214.315875)
						(end 375.364248 -214.298022)
					)
					(arc
						(start 375.364248 -214.298022)
						(mid 375.328344 -214.283262)
						(end 375.292366 -214.298022)
					)
					(arc
						(start 375.292366 -214.298022)
						(mid 375.283624 -214.309843)
						(end 375.27865 -214.323676)
					)
					(xy 375.27865 -214.344504) (xy 375.27865 -214.344758)
					(arc
						(start 375.27865 -214.345774)
						(mid 375.263812 -214.418479)
						(end 375.222516 -214.48014)
					)
					(arc
						(start 375.222516 -214.48014)
						(mid 375.087134 -214.536217)
						(end 374.951752 -214.48014)
					)
					(arc
						(start 374.951752 -214.48014)
						(mid 374.910103 -214.417674)
						(end 374.895618 -214.343996)
					)
					(xy 374.895872 -214.343488)
					(arc
						(start 374.895872 -214.322914)
						(mid 374.890816 -214.308916)
						(end 374.881902 -214.297006)
					)
				)
			)
		)
		(zone
			(layer "F.Cu")
			(hatch none 0.5)
			(connect_pads
				(clearance 0)
			)
			(min_thickness 0.25)
			(keepout
				(tracks not_allowed)
				(vias allowed)
				(pads allowed)
				(copperpour not_allowed)
				(footprints allowed)
			)
			(placement
				(enabled no)
				(sheetname "")
			)
			(fill
				(thermal_gap 0.5)
				(thermal_bridge_width 0.5)
				(island_removal_mode 0)
			)
			(polygon
				(pts
					(arc
						(start 374.932194 -289.242754)
						(mid 374.968172 -289.257694)
						(end 375.004076 -289.242754)
					)
					(arc
						(start 375.004076 -289.242754)
						(mid 375.015475 -289.225514)
						(end 375.019062 -289.205162)
					)
					(arc
						(start 375.019062 -289.205162)
						(mid 374.998793 -289.087933)
						(end 374.933464 -288.9885)
					)
					(arc
						(start 374.933464 -288.9885)
						(mid 374.726962 -288.902964)
						(end 374.52046 -288.9885)
					)
					(arc
						(start 374.52046 -288.9885)
						(mid 374.455671 -289.086893)
						(end 374.435116 -289.202876)
					)
					(arc
						(start 374.435116 -289.202876)
						(mid 374.438316 -289.223885)
						(end 374.449848 -289.241738)
					)
					(arc
						(start 374.449848 -289.241738)
						(mid 374.485826 -289.256678)
						(end 374.52173 -289.241738)
					)
					(arc
						(start 374.52173 -289.241738)
						(mid 374.530472 -289.229917)
						(end 374.535446 -289.216084)
					)
					(xy 374.535446 -289.195256) (xy 374.535446 -289.195002)
					(arc
						(start 374.535446 -289.193986)
						(mid 374.550284 -289.121281)
						(end 374.59158 -289.05962)
					)
					(arc
						(start 374.59158 -289.05962)
						(mid 374.726962 -289.003543)
						(end 374.862344 -289.05962)
					)
					(arc
						(start 374.862344 -289.05962)
						(mid 374.903993 -289.122086)
						(end 374.918478 -289.195764)
					)
					(xy 374.918224 -289.196272)
					(arc
						(start 374.918224 -289.216846)
						(mid 374.92328 -289.230844)
						(end 374.932194 -289.242754)
					)
				)
			)
		)
		(zone
			(layer "F.Cu")
			(hatch none 0.5)
			(connect_pads
				(clearance 0)
			)
			(min_thickness 0.25)
			(keepout
				(tracks not_allowed)
				(vias allowed)
				(pads allowed)
				(copperpour not_allowed)
				(footprints allowed)
			)
			(placement
				(enabled no)
				(sheetname "")
			)
			(fill
				(thermal_gap 0.5)
				(thermal_bridge_width 0.5)
				(island_removal_mode 0)
			)
			(polygon
				(pts
					(arc
						(start 375.821702 -214.297006)
						(mid 375.785798 -214.282246)
						(end 375.74982 -214.297006)
					)
					(arc
						(start 375.74982 -214.297006)
						(mid 375.738421 -214.314246)
						(end 375.734834 -214.334598)
					)
					(arc
						(start 375.734834 -214.334598)
						(mid 375.755103 -214.451827)
						(end 375.820432 -214.55126)
					)
					(arc
						(start 375.820432 -214.55126)
						(mid 376.026934 -214.636796)
						(end 376.233436 -214.55126)
					)
					(arc
						(start 376.233436 -214.55126)
						(mid 376.298225 -214.452867)
						(end 376.31878 -214.336884)
					)
					(arc
						(start 376.31878 -214.336884)
						(mid 376.31558 -214.315875)
						(end 376.304048 -214.298022)
					)
					(arc
						(start 376.304048 -214.298022)
						(mid 376.268144 -214.283262)
						(end 376.232166 -214.298022)
					)
					(arc
						(start 376.232166 -214.298022)
						(mid 376.223424 -214.309843)
						(end 376.21845 -214.323676)
					)
					(xy 376.21845 -214.344504) (xy 376.21845 -214.344758)
					(arc
						(start 376.21845 -214.345774)
						(mid 376.203612 -214.418479)
						(end 376.162316 -214.48014)
					)
					(arc
						(start 376.162316 -214.48014)
						(mid 376.026934 -214.536217)
						(end 375.891552 -214.48014)
					)
					(arc
						(start 375.891552 -214.48014)
						(mid 375.849903 -214.417674)
						(end 375.835418 -214.343996)
					)
					(xy 375.835672 -214.343488)
					(arc
						(start 375.835672 -214.322914)
						(mid 375.830616 -214.308916)
						(end 375.821702 -214.297006)
					)
				)
			)
		)
		(zone
			(layer "F.Cu")
			(hatch none 0.5)
			(connect_pads
				(clearance 0)
			)
			(min_thickness 0.25)
			(keepout
				(tracks not_allowed)
				(vias allowed)
				(pads allowed)
				(copperpour not_allowed)
				(footprints allowed)
			)
			(placement
				(enabled no)
				(sheetname "")
			)
			(fill
				(thermal_gap 0.5)
				(thermal_bridge_width 0.5)
				(island_removal_mode 0)
			)
			(polygon
				(pts
					(arc
						(start 375.871994 -289.242754)
						(mid 375.907972 -289.257694)
						(end 375.943876 -289.242754)
					)
					(arc
						(start 375.943876 -289.242754)
						(mid 375.955275 -289.225514)
						(end 375.958862 -289.205162)
					)
					(arc
						(start 375.958862 -289.205162)
						(mid 375.938593 -289.087933)
						(end 375.873264 -288.9885)
					)
					(arc
						(start 375.873264 -288.9885)
						(mid 375.666762 -288.902964)
						(end 375.46026 -288.9885)
					)
					(arc
						(start 375.46026 -288.9885)
						(mid 375.395471 -289.086893)
						(end 375.374916 -289.202876)
					)
					(arc
						(start 375.374916 -289.202876)
						(mid 375.378116 -289.223885)
						(end 375.389648 -289.241738)
					)
					(arc
						(start 375.389648 -289.241738)
						(mid 375.425626 -289.256678)
						(end 375.46153 -289.241738)
					)
					(arc
						(start 375.46153 -289.241738)
						(mid 375.470272 -289.229917)
						(end 375.475246 -289.216084)
					)
					(xy 375.475246 -289.195256) (xy 375.475246 -289.195002)
					(arc
						(start 375.475246 -289.193986)
						(mid 375.490084 -289.121281)
						(end 375.53138 -289.05962)
					)
					(arc
						(start 375.53138 -289.05962)
						(mid 375.666762 -289.003543)
						(end 375.802144 -289.05962)
					)
					(arc
						(start 375.802144 -289.05962)
						(mid 375.843793 -289.122086)
						(end 375.858278 -289.195764)
					)
					(xy 375.858024 -289.196272)
					(arc
						(start 375.858024 -289.216846)
						(mid 375.86308 -289.230844)
						(end 375.871994 -289.242754)
					)
				)
			)
		)
		(zone
			(layer "F.Cu")
			(hatch none 0.5)
			(connect_pads
				(clearance 0)
			)
			(min_thickness 0.25)
			(keepout
				(tracks not_allowed)
				(vias allowed)
				(pads allowed)
				(copperpour not_allowed)
				(footprints allowed)
			)
			(placement
				(enabled no)
				(sheetname "")
			)
			(fill
				(thermal_gap 0.5)
				(thermal_bridge_width 0.5)
				(island_removal_mode 0)
			)
			(polygon
				(pts
					(arc
						(start 376.761502 -214.297006)
						(mid 376.725598 -214.282246)
						(end 376.68962 -214.297006)
					)
					(arc
						(start 376.68962 -214.297006)
						(mid 376.678221 -214.314246)
						(end 376.674634 -214.334598)
					)
					(arc
						(start 376.674634 -214.334598)
						(mid 376.694903 -214.451827)
						(end 376.760232 -214.55126)
					)
					(arc
						(start 376.760232 -214.55126)
						(mid 376.966734 -214.636796)
						(end 377.173236 -214.55126)
					)
					(arc
						(start 377.173236 -214.55126)
						(mid 377.238025 -214.452867)
						(end 377.25858 -214.336884)
					)
					(arc
						(start 377.25858 -214.336884)
						(mid 377.25538 -214.315875)
						(end 377.243848 -214.298022)
					)
					(arc
						(start 377.243848 -214.298022)
						(mid 377.207944 -214.283262)
						(end 377.171966 -214.298022)
					)
					(arc
						(start 377.171966 -214.298022)
						(mid 377.163224 -214.309843)
						(end 377.15825 -214.323676)
					)
					(xy 377.15825 -214.344504) (xy 377.15825 -214.344758)
					(arc
						(start 377.15825 -214.345774)
						(mid 377.143412 -214.418479)
						(end 377.102116 -214.48014)
					)
					(arc
						(start 377.102116 -214.48014)
						(mid 376.966734 -214.536217)
						(end 376.831352 -214.48014)
					)
					(arc
						(start 376.831352 -214.48014)
						(mid 376.789703 -214.417674)
						(end 376.775218 -214.343996)
					)
					(xy 376.775472 -214.343488)
					(arc
						(start 376.775472 -214.322914)
						(mid 376.770416 -214.308916)
						(end 376.761502 -214.297006)
					)
				)
			)
		)
		(zone
			(layer "F.Cu")
			(hatch none 0.5)
			(connect_pads
				(clearance 0)
			)
			(min_thickness 0.25)
			(keepout
				(tracks not_allowed)
				(vias allowed)
				(pads allowed)
				(copperpour not_allowed)
				(footprints allowed)
			)
			(placement
				(enabled no)
				(sheetname "")
			)
			(fill
				(thermal_gap 0.5)
				(thermal_bridge_width 0.5)
				(island_removal_mode 0)
			)
			(polygon
				(pts
					(arc
						(start 376.811794 -289.242754)
						(mid 376.847772 -289.257694)
						(end 376.883676 -289.242754)
					)
					(arc
						(start 376.883676 -289.242754)
						(mid 376.895075 -289.225514)
						(end 376.898662 -289.205162)
					)
					(arc
						(start 376.898662 -289.205162)
						(mid 376.878393 -289.087933)
						(end 376.813064 -288.9885)
					)
					(arc
						(start 376.813064 -288.9885)
						(mid 376.606562 -288.902964)
						(end 376.40006 -288.9885)
					)
					(arc
						(start 376.40006 -288.9885)
						(mid 376.335271 -289.086893)
						(end 376.314716 -289.202876)
					)
					(arc
						(start 376.314716 -289.202876)
						(mid 376.317916 -289.223885)
						(end 376.329448 -289.241738)
					)
					(arc
						(start 376.329448 -289.241738)
						(mid 376.365426 -289.256678)
						(end 376.40133 -289.241738)
					)
					(arc
						(start 376.40133 -289.241738)
						(mid 376.410072 -289.229917)
						(end 376.415046 -289.216084)
					)
					(xy 376.415046 -289.195256) (xy 376.415046 -289.195002)
					(arc
						(start 376.415046 -289.193986)
						(mid 376.429884 -289.121281)
						(end 376.47118 -289.05962)
					)
					(arc
						(start 376.47118 -289.05962)
						(mid 376.606562 -289.003543)
						(end 376.741944 -289.05962)
					)
					(arc
						(start 376.741944 -289.05962)
						(mid 376.783593 -289.122086)
						(end 376.798078 -289.195764)
					)
					(xy 376.797824 -289.196272)
					(arc
						(start 376.797824 -289.216846)
						(mid 376.80288 -289.230844)
						(end 376.811794 -289.242754)
					)
				)
			)
		)
		(zone
			(layer "F.Cu")
			(hatch none 0.5)
			(connect_pads
				(clearance 0)
			)
			(min_thickness 0.25)
			(keepout
				(tracks not_allowed)
				(vias allowed)
				(pads allowed)
				(copperpour not_allowed)
				(footprints allowed)
			)
			(placement
				(enabled no)
				(sheetname "")
			)
			(fill
				(thermal_gap 0.5)
				(thermal_bridge_width 0.5)
				(island_removal_mode 0)
			)
			(polygon
				(pts
					(arc
						(start 377.701302 -214.297006)
						(mid 377.665398 -214.282246)
						(end 377.62942 -214.297006)
					)
					(arc
						(start 377.62942 -214.297006)
						(mid 377.618021 -214.314246)
						(end 377.614434 -214.334598)
					)
					(arc
						(start 377.614434 -214.334598)
						(mid 377.634703 -214.451827)
						(end 377.700032 -214.55126)
					)
					(arc
						(start 377.700032 -214.55126)
						(mid 377.906534 -214.636796)
						(end 378.113036 -214.55126)
					)
					(arc
						(start 378.113036 -214.55126)
						(mid 378.177825 -214.452867)
						(end 378.19838 -214.336884)
					)
					(arc
						(start 378.19838 -214.336884)
						(mid 378.19518 -214.315875)
						(end 378.183648 -214.298022)
					)
					(arc
						(start 378.183648 -214.298022)
						(mid 378.147744 -214.283262)
						(end 378.111766 -214.298022)
					)
					(arc
						(start 378.111766 -214.298022)
						(mid 378.103024 -214.309843)
						(end 378.09805 -214.323676)
					)
					(xy 378.09805 -214.344504) (xy 378.09805 -214.344758)
					(arc
						(start 378.09805 -214.345774)
						(mid 378.083212 -214.418479)
						(end 378.041916 -214.48014)
					)
					(arc
						(start 378.041916 -214.48014)
						(mid 377.906534 -214.536217)
						(end 377.771152 -214.48014)
					)
					(arc
						(start 377.771152 -214.48014)
						(mid 377.729503 -214.417674)
						(end 377.715018 -214.343996)
					)
					(xy 377.715272 -214.343488)
					(arc
						(start 377.715272 -214.322914)
						(mid 377.710216 -214.308916)
						(end 377.701302 -214.297006)
					)
				)
			)
		)
		(zone
			(layer "F.Cu")
			(hatch none 0.5)
			(connect_pads
				(clearance 0)
			)
			(min_thickness 0.25)
			(keepout
				(tracks not_allowed)
				(vias allowed)
				(pads allowed)
				(copperpour not_allowed)
				(footprints allowed)
			)
			(placement
				(enabled no)
				(sheetname "")
			)
			(fill
				(thermal_gap 0.5)
				(thermal_bridge_width 0.5)
				(island_removal_mode 0)
			)
			(polygon
				(pts
					(arc
						(start 377.751594 -289.242754)
						(mid 377.787572 -289.257694)
						(end 377.823476 -289.242754)
					)
					(arc
						(start 377.823476 -289.242754)
						(mid 377.834875 -289.225514)
						(end 377.838462 -289.205162)
					)
					(arc
						(start 377.838462 -289.205162)
						(mid 377.818193 -289.087933)
						(end 377.752864 -288.9885)
					)
					(arc
						(start 377.752864 -288.9885)
						(mid 377.546362 -288.902964)
						(end 377.33986 -288.9885)
					)
					(arc
						(start 377.33986 -288.9885)
						(mid 377.275071 -289.086893)
						(end 377.254516 -289.202876)
					)
					(arc
						(start 377.254516 -289.202876)
						(mid 377.257716 -289.223885)
						(end 377.269248 -289.241738)
					)
					(arc
						(start 377.269248 -289.241738)
						(mid 377.305226 -289.256678)
						(end 377.34113 -289.241738)
					)
					(arc
						(start 377.34113 -289.241738)
						(mid 377.349872 -289.229917)
						(end 377.354846 -289.216084)
					)
					(xy 377.354846 -289.195256) (xy 377.354846 -289.195002)
					(arc
						(start 377.354846 -289.193986)
						(mid 377.369684 -289.121281)
						(end 377.41098 -289.05962)
					)
					(arc
						(start 377.41098 -289.05962)
						(mid 377.546362 -289.003543)
						(end 377.681744 -289.05962)
					)
					(arc
						(start 377.681744 -289.05962)
						(mid 377.723393 -289.122086)
						(end 377.737878 -289.195764)
					)
					(xy 377.737624 -289.196272)
					(arc
						(start 377.737624 -289.216846)
						(mid 377.74268 -289.230844)
						(end 377.751594 -289.242754)
					)
				)
			)
		)
		(zone
			(layer "F.Cu")
			(hatch none 0.5)
			(connect_pads
				(clearance 0)
			)
			(min_thickness 0.25)
			(keepout
				(tracks not_allowed)
				(vias allowed)
				(pads allowed)
				(copperpour not_allowed)
				(footprints allowed)
			)
			(placement
				(enabled no)
				(sheetname "")
			)
			(fill
				(thermal_gap 0.5)
				(thermal_bridge_width 0.5)
				(island_removal_mode 0)
			)
			(polygon
				(pts
					(arc
						(start 378.641102 -214.297006)
						(mid 378.605198 -214.282246)
						(end 378.56922 -214.297006)
					)
					(arc
						(start 378.56922 -214.297006)
						(mid 378.557821 -214.314246)
						(end 378.554234 -214.334598)
					)
					(arc
						(start 378.554234 -214.334598)
						(mid 378.574503 -214.451827)
						(end 378.639832 -214.55126)
					)
					(arc
						(start 378.639832 -214.55126)
						(mid 378.846334 -214.636796)
						(end 379.052836 -214.55126)
					)
					(arc
						(start 379.052836 -214.55126)
						(mid 379.117625 -214.452867)
						(end 379.13818 -214.336884)
					)
					(arc
						(start 379.13818 -214.336884)
						(mid 379.13498 -214.315875)
						(end 379.123448 -214.298022)
					)
					(arc
						(start 379.123448 -214.298022)
						(mid 379.087544 -214.283262)
						(end 379.051566 -214.298022)
					)
					(arc
						(start 379.051566 -214.298022)
						(mid 379.042824 -214.309843)
						(end 379.03785 -214.323676)
					)
					(xy 379.03785 -214.344504) (xy 379.03785 -214.344758)
					(arc
						(start 379.03785 -214.345774)
						(mid 379.023012 -214.418479)
						(end 378.981716 -214.48014)
					)
					(arc
						(start 378.981716 -214.48014)
						(mid 378.846334 -214.536217)
						(end 378.710952 -214.48014)
					)
					(arc
						(start 378.710952 -214.48014)
						(mid 378.669303 -214.417674)
						(end 378.654818 -214.343996)
					)
					(xy 378.655072 -214.343488)
					(arc
						(start 378.655072 -214.322914)
						(mid 378.650016 -214.308916)
						(end 378.641102 -214.297006)
					)
				)
			)
		)
		(zone
			(layer "F.Cu")
			(hatch none 0.5)
			(connect_pads
				(clearance 0)
			)
			(min_thickness 0.25)
			(keepout
				(tracks not_allowed)
				(vias allowed)
				(pads allowed)
				(copperpour not_allowed)
				(footprints allowed)
			)
			(placement
				(enabled no)
				(sheetname "")
			)
			(fill
				(thermal_gap 0.5)
				(thermal_bridge_width 0.5)
				(island_removal_mode 0)
			)
			(polygon
				(pts
					(arc
						(start 378.691394 -289.242754)
						(mid 378.727372 -289.257694)
						(end 378.763276 -289.242754)
					)
					(arc
						(start 378.763276 -289.242754)
						(mid 378.774675 -289.225514)
						(end 378.778262 -289.205162)
					)
					(arc
						(start 378.778262 -289.205162)
						(mid 378.757993 -289.087933)
						(end 378.692664 -288.9885)
					)
					(arc
						(start 378.692664 -288.9885)
						(mid 378.486162 -288.902964)
						(end 378.27966 -288.9885)
					)
					(arc
						(start 378.27966 -288.9885)
						(mid 378.214871 -289.086893)
						(end 378.194316 -289.202876)
					)
					(arc
						(start 378.194316 -289.202876)
						(mid 378.197516 -289.223885)
						(end 378.209048 -289.241738)
					)
					(arc
						(start 378.209048 -289.241738)
						(mid 378.245026 -289.256678)
						(end 378.28093 -289.241738)
					)
					(arc
						(start 378.28093 -289.241738)
						(mid 378.289672 -289.229917)
						(end 378.294646 -289.216084)
					)
					(xy 378.294646 -289.195256) (xy 378.294646 -289.195002)
					(arc
						(start 378.294646 -289.193986)
						(mid 378.309484 -289.121281)
						(end 378.35078 -289.05962)
					)
					(arc
						(start 378.35078 -289.05962)
						(mid 378.486162 -289.003543)
						(end 378.621544 -289.05962)
					)
					(arc
						(start 378.621544 -289.05962)
						(mid 378.663193 -289.122086)
						(end 378.677678 -289.195764)
					)
					(xy 378.677424 -289.196272)
					(arc
						(start 378.677424 -289.216846)
						(mid 378.68248 -289.230844)
						(end 378.691394 -289.242754)
					)
				)
			)
		)
		(zone
			(layer "F.Cu")
			(hatch none 0.5)
			(connect_pads
				(clearance 0)
			)
			(min_thickness 0.25)
			(keepout
				(tracks not_allowed)
				(vias allowed)
				(pads allowed)
				(copperpour not_allowed)
				(footprints allowed)
			)
			(placement
				(enabled no)
				(sheetname "")
			)
			(fill
				(thermal_gap 0.5)
				(thermal_bridge_width 0.5)
				(island_removal_mode 0)
			)
			(polygon
				(pts
					(arc
						(start 379.580902 -214.297006)
						(mid 379.544998 -214.282246)
						(end 379.50902 -214.297006)
					)
					(arc
						(start 379.50902 -214.297006)
						(mid 379.497621 -214.314246)
						(end 379.494034 -214.334598)
					)
					(arc
						(start 379.494034 -214.334598)
						(mid 379.514303 -214.451827)
						(end 379.579632 -214.55126)
					)
					(arc
						(start 379.579632 -214.55126)
						(mid 379.786134 -214.636796)
						(end 379.992636 -214.55126)
					)
					(arc
						(start 379.992636 -214.55126)
						(mid 380.057425 -214.452867)
						(end 380.07798 -214.336884)
					)
					(arc
						(start 380.07798 -214.336884)
						(mid 380.07478 -214.315875)
						(end 380.063248 -214.298022)
					)
					(arc
						(start 380.063248 -214.298022)
						(mid 380.027344 -214.283262)
						(end 379.991366 -214.298022)
					)
					(arc
						(start 379.991366 -214.298022)
						(mid 379.982624 -214.309843)
						(end 379.97765 -214.323676)
					)
					(xy 379.97765 -214.344504) (xy 379.97765 -214.344758)
					(arc
						(start 379.97765 -214.345774)
						(mid 379.962812 -214.418479)
						(end 379.921516 -214.48014)
					)
					(arc
						(start 379.921516 -214.48014)
						(mid 379.786134 -214.536217)
						(end 379.650752 -214.48014)
					)
					(arc
						(start 379.650752 -214.48014)
						(mid 379.609103 -214.417674)
						(end 379.594618 -214.343996)
					)
					(xy 379.594872 -214.343488)
					(arc
						(start 379.594872 -214.322914)
						(mid 379.589816 -214.308916)
						(end 379.580902 -214.297006)
					)
				)
			)
		)
		(zone
			(layer "F.Cu")
			(hatch none 0.5)
			(connect_pads
				(clearance 0)
			)
			(min_thickness 0.25)
			(keepout
				(tracks not_allowed)
				(vias allowed)
				(pads allowed)
				(copperpour not_allowed)
				(footprints allowed)
			)
			(placement
				(enabled no)
				(sheetname "")
			)
			(fill
				(thermal_gap 0.5)
				(thermal_bridge_width 0.5)
				(island_removal_mode 0)
			)
			(polygon
				(pts
					(arc
						(start 379.631194 -289.242754)
						(mid 379.667172 -289.257694)
						(end 379.703076 -289.242754)
					)
					(arc
						(start 379.703076 -289.242754)
						(mid 379.714475 -289.225514)
						(end 379.718062 -289.205162)
					)
					(arc
						(start 379.718062 -289.205162)
						(mid 379.697793 -289.087933)
						(end 379.632464 -288.9885)
					)
					(arc
						(start 379.632464 -288.9885)
						(mid 379.425962 -288.902964)
						(end 379.21946 -288.9885)
					)
					(arc
						(start 379.21946 -288.9885)
						(mid 379.154671 -289.086893)
						(end 379.134116 -289.202876)
					)
					(arc
						(start 379.134116 -289.202876)
						(mid 379.137316 -289.223885)
						(end 379.148848 -289.241738)
					)
					(arc
						(start 379.148848 -289.241738)
						(mid 379.184826 -289.256678)
						(end 379.22073 -289.241738)
					)
					(arc
						(start 379.22073 -289.241738)
						(mid 379.229472 -289.229917)
						(end 379.234446 -289.216084)
					)
					(xy 379.234446 -289.195256) (xy 379.234446 -289.195002)
					(arc
						(start 379.234446 -289.193986)
						(mid 379.249284 -289.121281)
						(end 379.29058 -289.05962)
					)
					(arc
						(start 379.29058 -289.05962)
						(mid 379.425962 -289.003543)
						(end 379.561344 -289.05962)
					)
					(arc
						(start 379.561344 -289.05962)
						(mid 379.602993 -289.122086)
						(end 379.617478 -289.195764)
					)
					(xy 379.617224 -289.196272)
					(arc
						(start 379.617224 -289.216846)
						(mid 379.62228 -289.230844)
						(end 379.631194 -289.242754)
					)
				)
			)
		)
		(zone
			(layer "F.Cu")
			(hatch none 0.5)
			(connect_pads
				(clearance 0)
			)
			(min_thickness 0.25)
			(keepout
				(tracks not_allowed)
				(vias allowed)
				(pads allowed)
				(copperpour not_allowed)
				(footprints allowed)
			)
			(placement
				(enabled no)
				(sheetname "")
			)
			(fill
				(thermal_gap 0.5)
				(thermal_bridge_width 0.5)
				(island_removal_mode 0)
			)
			(polygon
				(pts
					(arc
						(start 380.520702 -214.297006)
						(mid 380.484798 -214.282246)
						(end 380.44882 -214.297006)
					)
					(arc
						(start 380.44882 -214.297006)
						(mid 380.437421 -214.314246)
						(end 380.433834 -214.334598)
					)
					(arc
						(start 380.433834 -214.334598)
						(mid 380.454103 -214.451827)
						(end 380.519432 -214.55126)
					)
					(arc
						(start 380.519432 -214.55126)
						(mid 380.725934 -214.636796)
						(end 380.932436 -214.55126)
					)
					(arc
						(start 380.932436 -214.55126)
						(mid 380.997225 -214.452867)
						(end 381.01778 -214.336884)
					)
					(arc
						(start 381.01778 -214.336884)
						(mid 381.01458 -214.315875)
						(end 381.003048 -214.298022)
					)
					(arc
						(start 381.003048 -214.298022)
						(mid 380.967144 -214.283262)
						(end 380.931166 -214.298022)
					)
					(arc
						(start 380.931166 -214.298022)
						(mid 380.922424 -214.309843)
						(end 380.91745 -214.323676)
					)
					(xy 380.91745 -214.344504) (xy 380.91745 -214.344758)
					(arc
						(start 380.91745 -214.345774)
						(mid 380.902612 -214.418479)
						(end 380.861316 -214.48014)
					)
					(arc
						(start 380.861316 -214.48014)
						(mid 380.725934 -214.536217)
						(end 380.590552 -214.48014)
					)
					(arc
						(start 380.590552 -214.48014)
						(mid 380.548903 -214.417674)
						(end 380.534418 -214.343996)
					)
					(xy 380.534672 -214.343488)
					(arc
						(start 380.534672 -214.322914)
						(mid 380.529616 -214.308916)
						(end 380.520702 -214.297006)
					)
				)
			)
		)
		(zone
			(layer "F.Cu")
			(hatch none 0.5)
			(connect_pads
				(clearance 0)
			)
			(min_thickness 0.25)
			(keepout
				(tracks not_allowed)
				(vias allowed)
				(pads allowed)
				(copperpour not_allowed)
				(footprints allowed)
			)
			(placement
				(enabled no)
				(sheetname "")
			)
			(fill
				(thermal_gap 0.5)
				(thermal_bridge_width 0.5)
				(island_removal_mode 0)
			)
			(polygon
				(pts
					(arc
						(start 380.570994 -289.242754)
						(mid 380.606972 -289.257694)
						(end 380.642876 -289.242754)
					)
					(arc
						(start 380.642876 -289.242754)
						(mid 380.654275 -289.225514)
						(end 380.657862 -289.205162)
					)
					(arc
						(start 380.657862 -289.205162)
						(mid 380.637593 -289.087933)
						(end 380.572264 -288.9885)
					)
					(arc
						(start 380.572264 -288.9885)
						(mid 380.365762 -288.902964)
						(end 380.15926 -288.9885)
					)
					(arc
						(start 380.15926 -288.9885)
						(mid 380.094471 -289.086893)
						(end 380.073916 -289.202876)
					)
					(arc
						(start 380.073916 -289.202876)
						(mid 380.077116 -289.223885)
						(end 380.088648 -289.241738)
					)
					(arc
						(start 380.088648 -289.241738)
						(mid 380.124626 -289.256678)
						(end 380.16053 -289.241738)
					)
					(arc
						(start 380.16053 -289.241738)
						(mid 380.169272 -289.229917)
						(end 380.174246 -289.216084)
					)
					(xy 380.174246 -289.195256) (xy 380.174246 -289.195002)
					(arc
						(start 380.174246 -289.193986)
						(mid 380.189084 -289.121281)
						(end 380.23038 -289.05962)
					)
					(arc
						(start 380.23038 -289.05962)
						(mid 380.365762 -289.003543)
						(end 380.501144 -289.05962)
					)
					(arc
						(start 380.501144 -289.05962)
						(mid 380.542793 -289.122086)
						(end 380.557278 -289.195764)
					)
					(xy 380.557024 -289.196272)
					(arc
						(start 380.557024 -289.216846)
						(mid 380.56208 -289.230844)
						(end 380.570994 -289.242754)
					)
				)
			)
		)
		(zone
			(layer "F.Cu")
			(hatch none 0.5)
			(connect_pads
				(clearance 0)
			)
			(min_thickness 0.25)
			(keepout
				(tracks not_allowed)
				(vias allowed)
				(pads allowed)
				(copperpour not_allowed)
				(footprints allowed)
			)
			(placement
				(enabled no)
				(sheetname "")
			)
			(fill
				(thermal_gap 0.5)
				(thermal_bridge_width 0.5)
				(island_removal_mode 0)
			)
			(polygon
				(pts
					(arc
						(start 380.990348 -215.111076)
						(mid 380.954534 -215.096241)
						(end 380.91872 -215.111076)
					)
					(arc
						(start 380.91872 -215.111076)
						(mid 380.907369 -215.128198)
						(end 380.903734 -215.148414)
					)
					(arc
						(start 380.903734 -215.148414)
						(mid 380.923883 -215.265615)
						(end 380.989078 -215.365076)
					)
					(arc
						(start 380.989078 -215.365076)
						(mid 381.19558 -215.450612)
						(end 381.402082 -215.365076)
					)
					(arc
						(start 381.402082 -215.365076)
						(mid 381.466964 -215.266832)
						(end 381.48768 -215.150954)
					)
					(arc
						(start 381.48768 -215.150954)
						(mid 381.484492 -215.129932)
						(end 381.472948 -215.112092)
					)
					(arc
						(start 381.472948 -215.112092)
						(mid 381.437045 -215.097257)
						(end 381.401066 -215.112092)
					)
					(arc
						(start 381.401066 -215.112092)
						(mid 381.392343 -215.123788)
						(end 381.38735 -215.137492)
					)
					(xy 381.38735 -215.15832) (xy 381.38735 -215.158828)
					(arc
						(start 381.38735 -215.159844)
						(mid 381.372348 -215.232442)
						(end 381.330962 -215.293956)
					)
					(arc
						(start 381.330962 -215.293956)
						(mid 381.19558 -215.350033)
						(end 381.060198 -215.293956)
					)
					(arc
						(start 381.060198 -215.293956)
						(mid 381.018598 -215.231608)
						(end 381.004064 -215.158066)
					)
					(xy 381.004318 -215.157304)
					(arc
						(start 381.004318 -215.13673)
						(mid 380.999228 -215.122868)
						(end 380.990348 -215.111076)
					)
				)
			)
		)
		(zone
			(layer "F.Cu")
			(hatch none 0.5)
			(connect_pads
				(clearance 0)
			)
			(min_thickness 0.25)
			(keepout
				(tracks not_allowed)
				(vias allowed)
				(pads allowed)
				(copperpour not_allowed)
				(footprints allowed)
			)
			(placement
				(enabled no)
				(sheetname "")
			)
			(fill
				(thermal_gap 0.5)
				(thermal_bridge_width 0.5)
				(island_removal_mode 0)
			)
			(polygon
				(pts
					(arc
						(start 381.510794 -289.242754)
						(mid 381.546772 -289.257694)
						(end 381.582676 -289.242754)
					)
					(arc
						(start 381.582676 -289.242754)
						(mid 381.594075 -289.225514)
						(end 381.597662 -289.205162)
					)
					(arc
						(start 381.597662 -289.205162)
						(mid 381.577393 -289.087933)
						(end 381.512064 -288.9885)
					)
					(arc
						(start 381.512064 -288.9885)
						(mid 381.305562 -288.902964)
						(end 381.09906 -288.9885)
					)
					(arc
						(start 381.09906 -288.9885)
						(mid 381.034271 -289.086893)
						(end 381.013716 -289.202876)
					)
					(arc
						(start 381.013716 -289.202876)
						(mid 381.016916 -289.223885)
						(end 381.028448 -289.241738)
					)
					(arc
						(start 381.028448 -289.241738)
						(mid 381.064426 -289.256678)
						(end 381.10033 -289.241738)
					)
					(arc
						(start 381.10033 -289.241738)
						(mid 381.109072 -289.229917)
						(end 381.114046 -289.216084)
					)
					(xy 381.114046 -289.195256) (xy 381.114046 -289.195002)
					(arc
						(start 381.114046 -289.193986)
						(mid 381.128884 -289.121281)
						(end 381.17018 -289.05962)
					)
					(arc
						(start 381.17018 -289.05962)
						(mid 381.305562 -289.003543)
						(end 381.440944 -289.05962)
					)
					(arc
						(start 381.440944 -289.05962)
						(mid 381.482593 -289.122086)
						(end 381.497078 -289.195764)
					)
					(xy 381.496824 -289.196272)
					(arc
						(start 381.496824 -289.216846)
						(mid 381.50188 -289.230844)
						(end 381.510794 -289.242754)
					)
				)
			)
		)
		(zone
			(layer "F.Cu")
			(hatch none 0.5)
			(connect_pads
				(clearance 0)
			)
			(min_thickness 0.25)
			(keepout
				(tracks not_allowed)
				(vias allowed)
				(pads allowed)
				(copperpour not_allowed)
				(footprints allowed)
			)
			(placement
				(enabled no)
				(sheetname "")
			)
			(fill
				(thermal_gap 0.5)
				(thermal_bridge_width 0.5)
				(island_removal_mode 0)
			)
			(polygon
				(pts
					(arc
						(start 381.930402 -215.111076)
						(mid 381.894499 -215.096241)
						(end 381.85852 -215.111076)
					)
					(arc
						(start 381.85852 -215.111076)
						(mid 381.847169 -215.128198)
						(end 381.843534 -215.148414)
					)
					(arc
						(start 381.843534 -215.148414)
						(mid 381.863803 -215.265643)
						(end 381.929132 -215.365076)
					)
					(arc
						(start 381.929132 -215.365076)
						(mid 382.135634 -215.450612)
						(end 382.342136 -215.365076)
					)
					(arc
						(start 382.342136 -215.365076)
						(mid 382.406877 -215.266801)
						(end 382.42748 -215.150954)
					)
					(arc
						(start 382.42748 -215.150954)
						(mid 382.42428 -215.129945)
						(end 382.412748 -215.112092)
					)
					(arc
						(start 382.412748 -215.112092)
						(mid 382.376845 -215.097257)
						(end 382.340866 -215.112092)
					)
					(arc
						(start 382.340866 -215.112092)
						(mid 382.332143 -215.123788)
						(end 382.32715 -215.137492)
					)
					(xy 382.32715 -215.15832) (xy 382.32715 -215.158828)
					(arc
						(start 382.32715 -215.159844)
						(mid 382.312265 -215.232413)
						(end 382.271016 -215.293956)
					)
					(arc
						(start 382.271016 -215.293956)
						(mid 382.135634 -215.350033)
						(end 382.000252 -215.293956)
					)
					(arc
						(start 382.000252 -215.293956)
						(mid 381.958652 -215.231608)
						(end 381.944118 -215.158066)
					)
					(xy 381.944372 -215.157304)
					(arc
						(start 381.944372 -215.13673)
						(mid 381.939282 -215.122868)
						(end 381.930402 -215.111076)
					)
				)
			)
		)
		(zone
			(layer "F.Cu")
			(hatch none 0.5)
			(connect_pads
				(clearance 0)
			)
			(min_thickness 0.25)
			(keepout
				(tracks not_allowed)
				(vias allowed)
				(pads allowed)
				(copperpour not_allowed)
				(footprints allowed)
			)
			(placement
				(enabled no)
				(sheetname "")
			)
			(fill
				(thermal_gap 0.5)
				(thermal_bridge_width 0.5)
				(island_removal_mode 0)
			)
			(polygon
				(pts
					(arc
						(start 381.980948 -288.428684)
						(mid 382.016762 -288.443519)
						(end 382.052576 -288.428684)
					)
					(arc
						(start 382.052576 -288.428684)
						(mid 382.063927 -288.411562)
						(end 382.067562 -288.391346)
					)
					(arc
						(start 382.067562 -288.391346)
						(mid 382.047413 -288.274145)
						(end 381.982218 -288.174684)
					)
					(arc
						(start 381.982218 -288.174684)
						(mid 381.775716 -288.089148)
						(end 381.569214 -288.174684)
					)
					(arc
						(start 381.569214 -288.174684)
						(mid 381.504332 -288.272928)
						(end 381.483616 -288.388806)
					)
					(arc
						(start 381.483616 -288.388806)
						(mid 381.486804 -288.409828)
						(end 381.498348 -288.427668)
					)
					(arc
						(start 381.498348 -288.427668)
						(mid 381.534326 -288.442682)
						(end 381.57023 -288.427668)
					)
					(arc
						(start 381.57023 -288.427668)
						(mid 381.578953 -288.415972)
						(end 381.583946 -288.402268)
					)
					(xy 381.583946 -288.38144) (xy 381.583946 -288.380932)
					(arc
						(start 381.583946 -288.379916)
						(mid 381.598948 -288.307318)
						(end 381.640334 -288.245804)
					)
					(arc
						(start 381.640334 -288.245804)
						(mid 381.775716 -288.189727)
						(end 381.911098 -288.245804)
					)
					(arc
						(start 381.911098 -288.245804)
						(mid 381.952698 -288.308152)
						(end 381.967232 -288.381694)
					)
					(xy 381.966978 -288.382456)
					(arc
						(start 381.966978 -288.40303)
						(mid 381.972068 -288.416892)
						(end 381.980948 -288.428684)
					)
				)
			)
		)
		(zone
			(layer "F.Cu")
			(hatch none 0.5)
			(connect_pads
				(clearance 0)
			)
			(min_thickness 0.25)
			(keepout
				(tracks not_allowed)
				(vias allowed)
				(pads allowed)
				(copperpour not_allowed)
				(footprints allowed)
			)
			(placement
				(enabled no)
				(sheetname "")
			)
			(fill
				(thermal_gap 0.5)
				(thermal_bridge_width 0.5)
				(island_removal_mode 0)
			)
			(polygon
				(pts
					(arc
						(start 382.894332 -288.26968)
						(mid 382.930253 -288.254801)
						(end 382.945132 -288.21888)
					)
					(arc
						(start 382.945132 -288.21888)
						(mid 382.9409 -288.198833)
						(end 382.92913 -288.18205)
					)
					(arc
						(start 382.92913 -288.18205)
						(mid 382.832003 -288.113321)
						(end 382.715516 -288.089086)
					)
					(arc
						(start 382.715516 -288.089086)
						(mid 382.50897 -288.17464)
						(end 382.423416 -288.381186)
					)
					(arc
						(start 382.423416 -288.381186)
						(mid 382.447117 -288.496443)
						(end 382.514348 -288.593022)
					)
					(arc
						(start 382.514348 -288.593022)
						(mid 382.531576 -288.605591)
						(end 382.552448 -288.61004)
					)
					(arc
						(start 382.552448 -288.61004)
						(mid 382.588369 -288.595161)
						(end 382.603248 -288.55924)
					)
					(arc
						(start 382.603248 -288.55924)
						(mid 382.601063 -288.544792)
						(end 382.594866 -288.531554)
					)
					(xy 382.580134 -288.516822) (xy 382.57988 -288.516568)
					(arc
						(start 382.579118 -288.515806)
						(mid 382.538274 -288.453929)
						(end 382.524 -288.381186)
					)
					(arc
						(start 382.524 -288.381186)
						(mid 382.580094 -288.245764)
						(end 382.715516 -288.18967)
					)
					(arc
						(start 382.715516 -288.18967)
						(mid 382.789109 -288.204268)
						(end 382.851406 -288.246058)
					)
					(xy 382.85166 -288.24682)
					(arc
						(start 382.866138 -288.261298)
						(mid 382.879616 -288.267571)
						(end 382.894332 -288.26968)
					)
				)
			)
		)
		(zone
			(layer "F.Cu")
			(hatch none 0.5)
			(connect_pads
				(clearance 0)
			)
			(min_thickness 0.25)
			(keepout
				(tracks not_allowed)
				(vias allowed)
				(pads allowed)
				(copperpour not_allowed)
				(footprints allowed)
			)
			(placement
				(enabled no)
				(sheetname "")
			)
			(fill
				(thermal_gap 0.5)
				(thermal_bridge_width 0.5)
				(island_removal_mode 0)
			)
			(polygon
				(pts
					(arc
						(start 382.963928 -214.979758)
						(mid 382.949049 -214.943837)
						(end 382.913128 -214.928958)
					)
					(arc
						(start 382.913128 -214.928958)
						(mid 382.892944 -214.93314)
						(end 382.876044 -214.94496)
					)
					(arc
						(start 382.876044 -214.94496)
						(mid 382.807373 -215.042103)
						(end 382.78308 -215.158574)
					)
					(arc
						(start 382.78308 -215.158574)
						(mid 382.868634 -215.36512)
						(end 383.07518 -215.450674)
					)
					(arc
						(start 383.07518 -215.450674)
						(mid 383.190586 -215.426887)
						(end 383.28727 -215.359488)
					)
					(arc
						(start 383.28727 -215.359488)
						(mid 383.299788 -215.342376)
						(end 383.304288 -215.321642)
					)
					(arc
						(start 383.304288 -215.321642)
						(mid 383.289409 -215.285721)
						(end 383.253488 -215.270842)
					)
					(arc
						(start 383.253488 -215.270842)
						(mid 383.238902 -215.272981)
						(end 383.225548 -215.279224)
					)
					(xy 383.21107 -215.293956) (xy 383.210562 -215.29421)
					(arc
						(start 383.210054 -215.294972)
						(mid 383.14806 -215.335864)
						(end 383.07518 -215.35009)
					)
					(arc
						(start 383.07518 -215.35009)
						(mid 382.939758 -215.293996)
						(end 382.883664 -215.158574)
					)
					(arc
						(start 382.883664 -215.158574)
						(mid 382.898448 -215.084992)
						(end 382.940306 -215.022684)
					)
					(xy 382.941068 -215.02243)
					(arc
						(start 382.955546 -215.007952)
						(mid 382.961788 -214.994469)
						(end 382.963928 -214.979758)
					)
				)
			)
		)
		(zone
			(layer "F.Cu")
			(hatch none 0.5)
			(connect_pads
				(clearance 0)
			)
			(min_thickness 0.25)
			(keepout
				(tracks not_allowed)
				(vias allowed)
				(pads allowed)
				(copperpour not_allowed)
				(footprints allowed)
			)
			(placement
				(enabled no)
				(sheetname "")
			)
			(fill
				(thermal_gap 0.5)
				(thermal_bridge_width 0.5)
				(island_removal_mode 0)
			)
			(polygon
				(pts
					(arc
						(start 383.363978 -287.455864)
						(mid 383.399899 -287.440985)
						(end 383.414778 -287.405064)
					)
					(arc
						(start 383.414778 -287.405064)
						(mid 383.410718 -287.384907)
						(end 383.39903 -287.36798)
					)
					(arc
						(start 383.39903 -287.36798)
						(mid 383.301738 -287.299402)
						(end 383.185162 -287.27527)
					)
					(arc
						(start 383.185162 -287.27527)
						(mid 382.978796 -287.36075)
						(end 382.893316 -287.567116)
					)
					(arc
						(start 382.893316 -287.567116)
						(mid 382.916966 -287.68251)
						(end 382.984248 -287.779206)
					)
					(arc
						(start 382.984248 -287.779206)
						(mid 383.001476 -287.791775)
						(end 383.022348 -287.796224)
					)
					(arc
						(start 383.022348 -287.796224)
						(mid 383.058269 -287.781345)
						(end 383.073148 -287.745424)
					)
					(arc
						(start 383.073148 -287.745424)
						(mid 383.071009 -287.730838)
						(end 383.064766 -287.717484)
					)
					(xy 383.050034 -287.703006) (xy 383.049526 -287.702498)
					(arc
						(start 383.049018 -287.70199)
						(mid 383.007991 -287.640025)
						(end 382.993646 -287.567116)
					)
					(arc
						(start 382.993646 -287.567116)
						(mid 383.04974 -287.431694)
						(end 383.185162 -287.3756)
					)
					(arc
						(start 383.185162 -287.3756)
						(mid 383.258784 -287.390316)
						(end 383.321052 -287.432242)
					)
					(xy 383.32156 -287.433004)
					(arc
						(start 383.336038 -287.447482)
						(mid 383.349394 -287.453718)
						(end 383.363978 -287.455864)
					)
				)
			)
		)
		(zone
			(layer "F.Cu")
			(hatch none 0.5)
			(connect_pads
				(clearance 0)
			)
			(min_thickness 0.25)
			(keepout
				(tracks not_allowed)
				(vias allowed)
				(pads allowed)
				(copperpour not_allowed)
				(footprints allowed)
			)
			(placement
				(enabled no)
				(sheetname "")
			)
			(fill
				(thermal_gap 0.5)
				(thermal_bridge_width 0.5)
				(island_removal_mode 0)
			)
			(polygon
				(pts
					(arc
						(start 383.433828 -215.793828)
						(mid 383.418949 -215.757907)
						(end 383.383028 -215.743028)
					)
					(arc
						(start 383.383028 -215.743028)
						(mid 383.363009 -215.747139)
						(end 383.346198 -215.758776)
					)
					(arc
						(start 383.346198 -215.758776)
						(mid 383.277476 -215.856036)
						(end 383.253234 -215.972644)
					)
					(arc
						(start 383.253234 -215.972644)
						(mid 383.338788 -216.17919)
						(end 383.545334 -216.264744)
					)
					(arc
						(start 383.545334 -216.264744)
						(mid 383.660619 -216.240922)
						(end 383.75717 -216.173558)
					)
					(arc
						(start 383.75717 -216.173558)
						(mid 383.769739 -216.15633)
						(end 383.774188 -216.135458)
					)
					(arc
						(start 383.774188 -216.135458)
						(mid 383.759309 -216.099537)
						(end 383.723388 -216.084658)
					)
					(arc
						(start 383.723388 -216.084658)
						(mid 383.708934 -216.086833)
						(end 383.695702 -216.09304)
					)
					(xy 383.68097 -216.107772) (xy 383.680716 -216.108026)
					(arc
						(start 383.679954 -216.108788)
						(mid 383.618106 -216.149767)
						(end 383.545334 -216.16416)
					)
					(arc
						(start 383.545334 -216.16416)
						(mid 383.409912 -216.108066)
						(end 383.353818 -215.972644)
					)
					(arc
						(start 383.353818 -215.972644)
						(mid 383.368534 -215.899022)
						(end 383.41046 -215.836754)
					)
					(xy 383.410968 -215.836246)
					(arc
						(start 383.425446 -215.821768)
						(mid 383.431682 -215.808412)
						(end 383.433828 -215.793828)
					)
				)
			)
		)
		(zone
			(layer "F.Cu")
			(hatch none 0.5)
			(connect_pads
				(clearance 0)
			)
			(min_thickness 0.25)
			(keepout
				(tracks not_allowed)
				(vias allowed)
				(pads allowed)
				(copperpour not_allowed)
				(footprints allowed)
			)
			(placement
				(enabled no)
				(sheetname "")
			)
			(fill
				(thermal_gap 0.5)
				(thermal_bridge_width 0.5)
				(island_removal_mode 0)
			)
			(polygon
				(pts
					(arc
						(start 383.833878 -288.26968)
						(mid 383.869799 -288.254801)
						(end 383.884678 -288.21888)
					)
					(arc
						(start 383.884678 -288.21888)
						(mid 383.880567 -288.198861)
						(end 383.86893 -288.18205)
					)
					(arc
						(start 383.86893 -288.18205)
						(mid 383.77167 -288.113328)
						(end 383.655062 -288.089086)
					)
					(arc
						(start 383.655062 -288.089086)
						(mid 383.44868 -288.17473)
						(end 383.363216 -288.381186)
					)
					(arc
						(start 383.363216 -288.381186)
						(mid 383.386932 -288.496427)
						(end 383.454148 -288.593022)
					)
					(arc
						(start 383.454148 -288.593022)
						(mid 383.471376 -288.605591)
						(end 383.492248 -288.61004)
					)
					(arc
						(start 383.492248 -288.61004)
						(mid 383.528169 -288.595161)
						(end 383.543048 -288.55924)
					)
					(arc
						(start 383.543048 -288.55924)
						(mid 383.540873 -288.544786)
						(end 383.534666 -288.531554)
					)
					(xy 383.519934 -288.516822) (xy 383.519426 -288.516568)
					(arc
						(start 383.518918 -288.515806)
						(mid 383.477939 -288.453958)
						(end 383.463546 -288.381186)
					)
					(arc
						(start 383.463546 -288.381186)
						(mid 383.51964 -288.245764)
						(end 383.655062 -288.18967)
					)
					(arc
						(start 383.655062 -288.18967)
						(mid 383.728655 -288.204268)
						(end 383.790952 -288.246058)
					)
					(xy 383.79146 -288.24682)
					(arc
						(start 383.805938 -288.261298)
						(mid 383.819294 -288.267534)
						(end 383.833878 -288.26968)
					)
				)
			)
		)
		(zone
			(layer "F.Cu")
			(hatch none 0.5)
			(connect_pads
				(clearance 0)
			)
			(min_thickness 0.25)
			(keepout
				(tracks not_allowed)
				(vias allowed)
				(pads allowed)
				(copperpour not_allowed)
				(footprints allowed)
			)
			(placement
				(enabled no)
				(sheetname "")
			)
			(fill
				(thermal_gap 0.5)
				(thermal_bridge_width 0.5)
				(island_removal_mode 0)
			)
			(polygon
				(pts
					(arc
						(start 383.833878 -286.641794)
						(mid 383.869709 -286.627005)
						(end 383.884678 -286.591248)
					)
					(arc
						(start 383.884678 -286.591248)
						(mid 383.880618 -286.571091)
						(end 383.86893 -286.554164)
					)
					(arc
						(start 383.86893 -286.554164)
						(mid 383.77167 -286.485442)
						(end 383.655062 -286.4612)
					)
					(arc
						(start 383.655062 -286.4612)
						(mid 383.44868 -286.546844)
						(end 383.363216 -286.7533)
					)
					(arc
						(start 383.363216 -286.7533)
						(mid 383.386866 -286.868694)
						(end 383.454148 -286.96539)
					)
					(arc
						(start 383.454148 -286.96539)
						(mid 383.47141 -286.977811)
						(end 383.492248 -286.982154)
					)
					(arc
						(start 383.492248 -286.982154)
						(mid 383.528169 -286.967275)
						(end 383.543048 -286.931354)
					)
					(arc
						(start 383.543048 -286.931354)
						(mid 383.540873 -286.9169)
						(end 383.534666 -286.903668)
					)
					(xy 383.519934 -286.88919) (xy 383.519426 -286.888682)
					(arc
						(start 383.518918 -286.88792)
						(mid 383.477939 -286.826072)
						(end 383.463546 -286.7533)
					)
					(arc
						(start 383.463546 -286.7533)
						(mid 383.51964 -286.617878)
						(end 383.655062 -286.561784)
					)
					(arc
						(start 383.655062 -286.561784)
						(mid 383.728684 -286.5765)
						(end 383.790952 -286.618426)
					)
					(xy 383.79146 -286.618934)
					(arc
						(start 383.805938 -286.633412)
						(mid 383.819294 -286.639648)
						(end 383.833878 -286.641794)
					)
				)
			)
		)
		(zone
			(layer "F.Cu")
			(hatch none 0.5)
			(connect_pads
				(clearance 0)
			)
			(min_thickness 0.25)
			(keepout
				(tracks not_allowed)
				(vias allowed)
				(pads allowed)
				(copperpour not_allowed)
				(footprints allowed)
			)
			(placement
				(enabled no)
				(sheetname "")
			)
			(fill
				(thermal_gap 0.5)
				(thermal_bridge_width 0.5)
				(island_removal_mode 0)
			)
			(polygon
				(pts
					(arc
						(start 383.903728 -216.607644)
						(mid 383.888849 -216.571723)
						(end 383.852928 -216.556844)
					)
					(arc
						(start 383.852928 -216.556844)
						(mid 383.832881 -216.561076)
						(end 383.816098 -216.572846)
					)
					(arc
						(start 383.816098 -216.572846)
						(mid 383.747369 -216.669973)
						(end 383.723134 -216.78646)
					)
					(arc
						(start 383.723134 -216.78646)
						(mid 383.808688 -216.993006)
						(end 384.015234 -217.07856)
					)
					(arc
						(start 384.015234 -217.07856)
						(mid 384.130519 -217.054738)
						(end 384.22707 -216.987374)
					)
					(arc
						(start 384.22707 -216.987374)
						(mid 384.239588 -216.970262)
						(end 384.244088 -216.949528)
					)
					(arc
						(start 384.244088 -216.949528)
						(mid 384.229209 -216.913607)
						(end 384.193288 -216.898728)
					)
					(arc
						(start 384.193288 -216.898728)
						(mid 384.17884 -216.900751)
						(end 384.165602 -216.906856)
					)
					(xy 384.15087 -216.921588) (xy 384.150616 -216.922096)
					(arc
						(start 384.149854 -216.922604)
						(mid 384.088006 -216.963583)
						(end 384.015234 -216.977976)
					)
					(arc
						(start 384.015234 -216.977976)
						(mid 383.879812 -216.921882)
						(end 383.823718 -216.78646)
					)
					(arc
						(start 383.823718 -216.78646)
						(mid 383.838434 -216.712838)
						(end 383.88036 -216.65057)
					)
					(xy 383.880868 -216.650062)
					(arc
						(start 383.895346 -216.635584)
						(mid 383.901582 -216.622228)
						(end 383.903728 -216.607644)
					)
				)
			)
		)
		(zone
			(layer "F.Cu")
			(hatch none 0.5)
			(connect_pads
				(clearance 0)
			)
			(min_thickness 0.25)
			(keepout
				(tracks not_allowed)
				(vias allowed)
				(pads allowed)
				(copperpour not_allowed)
				(footprints allowed)
			)
			(placement
				(enabled no)
				(sheetname "")
			)
			(fill
				(thermal_gap 0.5)
				(thermal_bridge_width 0.5)
				(island_removal_mode 0)
			)
			(polygon
				(pts
					(arc
						(start 383.903728 -214.979758)
						(mid 383.888849 -214.943837)
						(end 383.852928 -214.928958)
					)
					(arc
						(start 383.852928 -214.928958)
						(mid 383.832881 -214.93319)
						(end 383.816098 -214.94496)
					)
					(arc
						(start 383.816098 -214.94496)
						(mid 383.747427 -215.042103)
						(end 383.723134 -215.158574)
					)
					(arc
						(start 383.723134 -215.158574)
						(mid 383.808688 -215.36512)
						(end 384.015234 -215.450674)
					)
					(arc
						(start 384.015234 -215.450674)
						(mid 384.13056 -215.426921)
						(end 384.22707 -215.359488)
					)
					(arc
						(start 384.22707 -215.359488)
						(mid 384.239588 -215.342376)
						(end 384.244088 -215.321642)
					)
					(arc
						(start 384.244088 -215.321642)
						(mid 384.229209 -215.285721)
						(end 384.193288 -215.270842)
					)
					(arc
						(start 384.193288 -215.270842)
						(mid 384.178834 -215.273017)
						(end 384.165602 -215.279224)
					)
					(xy 384.15087 -215.293956) (xy 384.150616 -215.29421)
					(arc
						(start 384.149854 -215.294972)
						(mid 384.087977 -215.335816)
						(end 384.015234 -215.35009)
					)
					(arc
						(start 384.015234 -215.35009)
						(mid 383.879812 -215.293996)
						(end 383.823718 -215.158574)
					)
					(arc
						(start 383.823718 -215.158574)
						(mid 383.838434 -215.084952)
						(end 383.88036 -215.022684)
					)
					(xy 383.880868 -215.02243)
					(arc
						(start 383.895346 -215.007952)
						(mid 383.901619 -214.994474)
						(end 383.903728 -214.979758)
					)
				)
			)
		)
		(zone
			(layer "F.Cu")
			(hatch none 0.5)
			(connect_pads
				(clearance 0)
			)
			(min_thickness 0.25)
			(keepout
				(tracks not_allowed)
				(vias allowed)
				(pads allowed)
				(copperpour not_allowed)
				(footprints allowed)
			)
			(placement
				(enabled no)
				(sheetname "")
			)
			(fill
				(thermal_gap 0.5)
				(thermal_bridge_width 0.5)
				(island_removal_mode 0)
			)
			(polygon
				(pts
					(arc
						(start 384.303778 -287.455864)
						(mid 384.339699 -287.440985)
						(end 384.354578 -287.405064)
					)
					(arc
						(start 384.354578 -287.405064)
						(mid 384.350518 -287.384907)
						(end 384.33883 -287.36798)
					)
					(arc
						(start 384.33883 -287.36798)
						(mid 384.241538 -287.299402)
						(end 384.124962 -287.27527)
					)
					(arc
						(start 384.124962 -287.27527)
						(mid 383.918596 -287.36075)
						(end 383.833116 -287.567116)
					)
					(arc
						(start 383.833116 -287.567116)
						(mid 383.856766 -287.68251)
						(end 383.924048 -287.779206)
					)
					(arc
						(start 383.924048 -287.779206)
						(mid 383.941276 -287.791775)
						(end 383.962148 -287.796224)
					)
					(arc
						(start 383.962148 -287.796224)
						(mid 383.998069 -287.781345)
						(end 384.012948 -287.745424)
					)
					(arc
						(start 384.012948 -287.745424)
						(mid 384.010809 -287.730838)
						(end 384.004566 -287.717484)
					)
					(xy 383.989834 -287.703006) (xy 383.989326 -287.702498)
					(arc
						(start 383.988818 -287.70199)
						(mid 383.947791 -287.640025)
						(end 383.933446 -287.567116)
					)
					(arc
						(start 383.933446 -287.567116)
						(mid 383.98954 -287.431694)
						(end 384.124962 -287.3756)
					)
					(arc
						(start 384.124962 -287.3756)
						(mid 384.198584 -287.390316)
						(end 384.260852 -287.432242)
					)
					(xy 384.26136 -287.433004)
					(arc
						(start 384.275838 -287.447482)
						(mid 384.289194 -287.453718)
						(end 384.303778 -287.455864)
					)
				)
			)
		)
		(zone
			(layer "F.Cu")
			(hatch none 0.5)
			(connect_pads
				(clearance 0)
			)
			(min_thickness 0.25)
			(keepout
				(tracks not_allowed)
				(vias allowed)
				(pads allowed)
				(copperpour not_allowed)
				(footprints allowed)
			)
			(placement
				(enabled no)
				(sheetname "")
			)
			(fill
				(thermal_gap 0.5)
				(thermal_bridge_width 0.5)
				(island_removal_mode 0)
			)
			(polygon
				(pts
					(arc
						(start 384.303778 -285.827978)
						(mid 384.339699 -285.813099)
						(end 384.354578 -285.777178)
					)
					(arc
						(start 384.354578 -285.777178)
						(mid 384.350467 -285.757159)
						(end 384.33883 -285.740348)
					)
					(arc
						(start 384.33883 -285.740348)
						(mid 384.24157 -285.671626)
						(end 384.124962 -285.647384)
					)
					(arc
						(start 384.124962 -285.647384)
						(mid 383.91858 -285.733028)
						(end 383.833116 -285.939484)
					)
					(arc
						(start 383.833116 -285.939484)
						(mid 383.856832 -286.054725)
						(end 383.924048 -286.15132)
					)
					(arc
						(start 383.924048 -286.15132)
						(mid 383.941276 -286.163889)
						(end 383.962148 -286.168338)
					)
					(arc
						(start 383.962148 -286.168338)
						(mid 383.998069 -286.153459)
						(end 384.012948 -286.117538)
					)
					(arc
						(start 384.012948 -286.117538)
						(mid 384.010773 -286.103084)
						(end 384.004566 -286.089852)
					)
					(xy 383.989834 -286.07512) (xy 383.989326 -286.074866)
					(arc
						(start 383.988818 -286.074104)
						(mid 383.947839 -286.012256)
						(end 383.933446 -285.939484)
					)
					(arc
						(start 383.933446 -285.939484)
						(mid 383.98954 -285.804062)
						(end 384.124962 -285.747968)
					)
					(arc
						(start 384.124962 -285.747968)
						(mid 384.198555 -285.762566)
						(end 384.260852 -285.804356)
					)
					(xy 384.26136 -285.805118)
					(arc
						(start 384.275838 -285.819596)
						(mid 384.289194 -285.825832)
						(end 384.303778 -285.827978)
					)
				)
			)
		)
		(zone
			(layer "F.Cu")
			(hatch none 0.5)
			(connect_pads
				(clearance 0)
			)
			(min_thickness 0.25)
			(keepout
				(tracks not_allowed)
				(vias allowed)
				(pads allowed)
				(copperpour not_allowed)
				(footprints allowed)
			)
			(placement
				(enabled no)
				(sheetname "")
			)
			(fill
				(thermal_gap 0.5)
				(thermal_bridge_width 0.5)
				(island_removal_mode 0)
			)
			(polygon
				(pts
					(arc
						(start 384.373628 -217.42146)
						(mid 384.358749 -217.385539)
						(end 384.322828 -217.37066)
					)
					(arc
						(start 384.322828 -217.37066)
						(mid 384.302781 -217.374892)
						(end 384.285998 -217.386662)
					)
					(arc
						(start 384.285998 -217.386662)
						(mid 384.217327 -217.483805)
						(end 384.193034 -217.600276)
					)
					(arc
						(start 384.193034 -217.600276)
						(mid 384.278588 -217.806822)
						(end 384.485134 -217.892376)
					)
					(arc
						(start 384.485134 -217.892376)
						(mid 384.60046 -217.868623)
						(end 384.69697 -217.80119)
					)
					(arc
						(start 384.69697 -217.80119)
						(mid 384.709488 -217.784078)
						(end 384.713988 -217.763344)
					)
					(arc
						(start 384.713988 -217.763344)
						(mid 384.699109 -217.727423)
						(end 384.663188 -217.712544)
					)
					(arc
						(start 384.663188 -217.712544)
						(mid 384.648734 -217.714719)
						(end 384.635502 -217.720926)
					)
					(xy 384.62077 -217.735658) (xy 384.620516 -217.735912)
					(arc
						(start 384.619754 -217.736674)
						(mid 384.557877 -217.777518)
						(end 384.485134 -217.791792)
					)
					(arc
						(start 384.485134 -217.791792)
						(mid 384.349712 -217.735698)
						(end 384.293618 -217.600276)
					)
					(arc
						(start 384.293618 -217.600276)
						(mid 384.308334 -217.526654)
						(end 384.35026 -217.464386)
					)
					(xy 384.350768 -217.464132)
					(arc
						(start 384.365246 -217.449654)
						(mid 384.371519 -217.436176)
						(end 384.373628 -217.42146)
					)
				)
			)
		)
		(zone
			(layer "F.Cu")
			(hatch none 0.5)
			(connect_pads
				(clearance 0)
			)
			(min_thickness 0.25)
			(keepout
				(tracks not_allowed)
				(vias allowed)
				(pads allowed)
				(copperpour not_allowed)
				(footprints allowed)
			)
			(placement
				(enabled no)
				(sheetname "")
			)
			(fill
				(thermal_gap 0.5)
				(thermal_bridge_width 0.5)
				(island_removal_mode 0)
			)
			(polygon
				(pts
					(arc
						(start 384.373628 -215.793828)
						(mid 384.358749 -215.757907)
						(end 384.322828 -215.743028)
					)
					(arc
						(start 384.322828 -215.743028)
						(mid 384.302809 -215.747139)
						(end 384.285998 -215.758776)
					)
					(arc
						(start 384.285998 -215.758776)
						(mid 384.217276 -215.856036)
						(end 384.193034 -215.972644)
					)
					(arc
						(start 384.193034 -215.972644)
						(mid 384.278588 -216.17919)
						(end 384.485134 -216.264744)
					)
					(arc
						(start 384.485134 -216.264744)
						(mid 384.600419 -216.240922)
						(end 384.69697 -216.173558)
					)
					(arc
						(start 384.69697 -216.173558)
						(mid 384.709539 -216.15633)
						(end 384.713988 -216.135458)
					)
					(arc
						(start 384.713988 -216.135458)
						(mid 384.699109 -216.099537)
						(end 384.663188 -216.084658)
					)
					(arc
						(start 384.663188 -216.084658)
						(mid 384.648734 -216.086833)
						(end 384.635502 -216.09304)
					)
					(xy 384.62077 -216.107772) (xy 384.620516 -216.108026)
					(arc
						(start 384.619754 -216.108788)
						(mid 384.557906 -216.149767)
						(end 384.485134 -216.16416)
					)
					(arc
						(start 384.485134 -216.16416)
						(mid 384.349712 -216.108066)
						(end 384.293618 -215.972644)
					)
					(arc
						(start 384.293618 -215.972644)
						(mid 384.308334 -215.899022)
						(end 384.35026 -215.836754)
					)
					(xy 384.350768 -215.836246)
					(arc
						(start 384.365246 -215.821768)
						(mid 384.371482 -215.808412)
						(end 384.373628 -215.793828)
					)
				)
			)
		)
		(zone
			(layer "F.Cu")
			(hatch none 0.5)
			(connect_pads
				(clearance 0)
			)
			(min_thickness 0.25)
			(keepout
				(tracks not_allowed)
				(vias allowed)
				(pads allowed)
				(copperpour not_allowed)
				(footprints allowed)
			)
			(placement
				(enabled no)
				(sheetname "")
			)
			(fill
				(thermal_gap 0.5)
				(thermal_bridge_width 0.5)
				(island_removal_mode 0)
			)
			(polygon
				(pts
					(arc
						(start 384.773932 -286.641794)
						(mid 384.809763 -286.627005)
						(end 384.824732 -286.591248)
					)
					(arc
						(start 384.824732 -286.591248)
						(mid 384.82055 -286.571064)
						(end 384.80873 -286.554164)
					)
					(arc
						(start 384.80873 -286.554164)
						(mid 384.711587 -286.485493)
						(end 384.595116 -286.4612)
					)
					(arc
						(start 384.595116 -286.4612)
						(mid 384.38857 -286.546754)
						(end 384.303016 -286.7533)
					)
					(arc
						(start 384.303016 -286.7533)
						(mid 384.326666 -286.868694)
						(end 384.393948 -286.96539)
					)
					(arc
						(start 384.393948 -286.96539)
						(mid 384.41121 -286.977811)
						(end 384.432048 -286.982154)
					)
					(arc
						(start 384.432048 -286.982154)
						(mid 384.467969 -286.967275)
						(end 384.482848 -286.931354)
					)
					(arc
						(start 384.482848 -286.931354)
						(mid 384.480673 -286.9169)
						(end 384.474466 -286.903668)
					)
					(xy 384.459734 -286.88919) (xy 384.45948 -286.888682)
					(arc
						(start 384.458718 -286.88792)
						(mid 384.417874 -286.826043)
						(end 384.4036 -286.7533)
					)
					(arc
						(start 384.4036 -286.7533)
						(mid 384.459694 -286.617878)
						(end 384.595116 -286.561784)
					)
					(arc
						(start 384.595116 -286.561784)
						(mid 384.668738 -286.5765)
						(end 384.731006 -286.618426)
					)
					(xy 384.73126 -286.618934)
					(arc
						(start 384.745738 -286.633412)
						(mid 384.759216 -286.639685)
						(end 384.773932 -286.641794)
					)
				)
			)
		)
		(zone
			(layer "F.Cu")
			(hatch none 0.5)
			(connect_pads
				(clearance 0)
			)
			(min_thickness 0.25)
			(keepout
				(tracks not_allowed)
				(vias allowed)
				(pads allowed)
				(copperpour not_allowed)
				(footprints allowed)
			)
			(placement
				(enabled no)
				(sheetname "")
			)
			(fill
				(thermal_gap 0.5)
				(thermal_bridge_width 0.5)
				(island_removal_mode 0)
			)
			(polygon
				(pts
					(arc
						(start 384.773932 -285.014162)
						(mid 384.809853 -284.999283)
						(end 384.824732 -284.963362)
					)
					(arc
						(start 384.824732 -284.963362)
						(mid 384.82055 -284.943178)
						(end 384.80873 -284.926278)
					)
					(arc
						(start 384.80873 -284.926278)
						(mid 384.711555 -284.85775)
						(end 384.595116 -284.833568)
					)
					(arc
						(start 384.595116 -284.833568)
						(mid 384.38866 -284.919032)
						(end 384.303016 -285.125414)
					)
					(arc
						(start 384.303016 -285.125414)
						(mid 384.326666 -285.240808)
						(end 384.393948 -285.337504)
					)
					(arc
						(start 384.393948 -285.337504)
						(mid 384.411176 -285.350073)
						(end 384.432048 -285.354522)
					)
					(arc
						(start 384.432048 -285.354522)
						(mid 384.467969 -285.339643)
						(end 384.482848 -285.303722)
					)
					(arc
						(start 384.482848 -285.303722)
						(mid 384.480709 -285.289136)
						(end 384.474466 -285.275782)
					)
					(xy 384.459734 -285.261304) (xy 384.45948 -285.260796)
					(arc
						(start 384.458718 -285.260288)
						(mid 384.417826 -285.198294)
						(end 384.4036 -285.125414)
					)
					(arc
						(start 384.4036 -285.125414)
						(mid 384.459694 -284.989992)
						(end 384.595116 -284.933898)
					)
					(arc
						(start 384.595116 -284.933898)
						(mid 384.668698 -284.948682)
						(end 384.731006 -284.99054)
					)
					(xy 384.73126 -284.991302)
					(arc
						(start 384.745738 -285.00578)
						(mid 384.759221 -285.012022)
						(end 384.773932 -285.014162)
					)
				)
			)
		)
		(zone
			(layer "F.Cu")
			(hatch none 0.5)
			(connect_pads
				(clearance 0)
			)
			(min_thickness 0.25)
			(keepout
				(tracks not_allowed)
				(vias allowed)
				(pads allowed)
				(copperpour not_allowed)
				(footprints allowed)
			)
			(placement
				(enabled no)
				(sheetname "")
			)
			(fill
				(thermal_gap 0.5)
				(thermal_bridge_width 0.5)
				(island_removal_mode 0)
			)
			(polygon
				(pts
					(arc
						(start 384.843528 -218.23553)
						(mid 384.828649 -218.199609)
						(end 384.792728 -218.18473)
					)
					(arc
						(start 384.792728 -218.18473)
						(mid 384.772571 -218.18879)
						(end 384.755644 -218.200478)
					)
					(arc
						(start 384.755644 -218.200478)
						(mid 384.686922 -218.297738)
						(end 384.66268 -218.414346)
					)
					(arc
						(start 384.66268 -218.414346)
						(mid 384.748234 -218.620892)
						(end 384.95478 -218.706446)
					)
					(arc
						(start 384.95478 -218.706446)
						(mid 385.070202 -218.682675)
						(end 385.16687 -218.61526)
					)
					(arc
						(start 385.16687 -218.61526)
						(mid 385.179439 -218.598032)
						(end 385.183888 -218.57716)
					)
					(arc
						(start 385.183888 -218.57716)
						(mid 385.169009 -218.541239)
						(end 385.133088 -218.52636)
					)
					(arc
						(start 385.133088 -218.52636)
						(mid 385.118502 -218.528499)
						(end 385.105148 -218.534742)
					)
					(xy 385.09067 -218.549474) (xy 385.090162 -218.549728)
					(arc
						(start 385.089654 -218.55049)
						(mid 385.027689 -218.591517)
						(end 384.95478 -218.605862)
					)
					(arc
						(start 384.95478 -218.605862)
						(mid 384.819358 -218.549768)
						(end 384.763264 -218.414346)
					)
					(arc
						(start 384.763264 -218.414346)
						(mid 384.77798 -218.340724)
						(end 384.819906 -218.278456)
					)
					(xy 384.820668 -218.277948)
					(arc
						(start 384.835146 -218.26347)
						(mid 384.841382 -218.250114)
						(end 384.843528 -218.23553)
					)
				)
			)
		)
		(zone
			(layer "F.Cu")
			(hatch none 0.5)
			(connect_pads
				(clearance 0)
			)
			(min_thickness 0.25)
			(keepout
				(tracks not_allowed)
				(vias allowed)
				(pads allowed)
				(copperpour not_allowed)
				(footprints allowed)
			)
			(placement
				(enabled no)
				(sheetname "")
			)
			(fill
				(thermal_gap 0.5)
				(thermal_bridge_width 0.5)
				(island_removal_mode 0)
			)
			(polygon
				(pts
					(arc
						(start 384.843528 -216.607644)
						(mid 384.828649 -216.571723)
						(end 384.792728 -216.556844)
					)
					(arc
						(start 384.792728 -216.556844)
						(mid 384.772544 -216.561026)
						(end 384.755644 -216.572846)
					)
					(arc
						(start 384.755644 -216.572846)
						(mid 384.686973 -216.669989)
						(end 384.66268 -216.78646)
					)
					(arc
						(start 384.66268 -216.78646)
						(mid 384.748234 -216.993006)
						(end 384.95478 -217.07856)
					)
					(arc
						(start 384.95478 -217.07856)
						(mid 385.070202 -217.054789)
						(end 385.16687 -216.987374)
					)
					(arc
						(start 385.16687 -216.987374)
						(mid 385.179388 -216.970262)
						(end 385.183888 -216.949528)
					)
					(arc
						(start 385.183888 -216.949528)
						(mid 385.169009 -216.913607)
						(end 385.133088 -216.898728)
					)
					(arc
						(start 385.133088 -216.898728)
						(mid 385.118508 -216.900713)
						(end 385.105148 -216.906856)
					)
					(xy 385.09067 -216.921588) (xy 385.090162 -216.922096)
					(arc
						(start 385.089654 -216.922604)
						(mid 385.027689 -216.963631)
						(end 384.95478 -216.977976)
					)
					(arc
						(start 384.95478 -216.977976)
						(mid 384.819358 -216.921882)
						(end 384.763264 -216.78646)
					)
					(arc
						(start 384.763264 -216.78646)
						(mid 384.778063 -216.712892)
						(end 384.819906 -216.65057)
					)
					(xy 384.820668 -216.650062)
					(arc
						(start 384.835146 -216.635584)
						(mid 384.841382 -216.622228)
						(end 384.843528 -216.607644)
					)
				)
			)
		)
		(zone
			(layer "F.Cu")
			(hatch none 0.5)
			(connect_pads
				(clearance 0)
			)
			(min_thickness 0.25)
			(keepout
				(tracks not_allowed)
				(vias allowed)
				(pads allowed)
				(copperpour not_allowed)
				(footprints allowed)
			)
			(placement
				(enabled no)
				(sheetname "")
			)
			(fill
				(thermal_gap 0.5)
				(thermal_bridge_width 0.5)
				(island_removal_mode 0)
			)
			(polygon
				(pts
					(arc
						(start 385.243578 -285.827978)
						(mid 385.279499 -285.813099)
						(end 385.294378 -285.777178)
					)
					(arc
						(start 385.294378 -285.777178)
						(mid 385.290267 -285.757159)
						(end 385.27863 -285.740348)
					)
					(arc
						(start 385.27863 -285.740348)
						(mid 385.18137 -285.671626)
						(end 385.064762 -285.647384)
					)
					(arc
						(start 385.064762 -285.647384)
						(mid 384.85838 -285.733028)
						(end 384.772916 -285.939484)
					)
					(arc
						(start 384.772916 -285.939484)
						(mid 384.796632 -286.054725)
						(end 384.863848 -286.15132)
					)
					(arc
						(start 384.863848 -286.15132)
						(mid 384.881076 -286.163889)
						(end 384.901948 -286.168338)
					)
					(arc
						(start 384.901948 -286.168338)
						(mid 384.937869 -286.153459)
						(end 384.952748 -286.117538)
					)
					(arc
						(start 384.952748 -286.117538)
						(mid 384.950573 -286.103084)
						(end 384.944366 -286.089852)
					)
					(xy 384.929634 -286.07512) (xy 384.929126 -286.074866)
					(arc
						(start 384.928618 -286.074104)
						(mid 384.887639 -286.012256)
						(end 384.873246 -285.939484)
					)
					(arc
						(start 384.873246 -285.939484)
						(mid 384.92934 -285.804062)
						(end 385.064762 -285.747968)
					)
					(arc
						(start 385.064762 -285.747968)
						(mid 385.138355 -285.762566)
						(end 385.200652 -285.804356)
					)
					(xy 385.20116 -285.805118)
					(arc
						(start 385.215638 -285.819596)
						(mid 385.228994 -285.825832)
						(end 385.243578 -285.827978)
					)
				)
			)
		)
		(zone
			(layer "F.Cu")
			(hatch none 0.5)
			(connect_pads
				(clearance 0)
			)
			(min_thickness 0.25)
			(keepout
				(tracks not_allowed)
				(vias allowed)
				(pads allowed)
				(copperpour not_allowed)
				(footprints allowed)
			)
			(placement
				(enabled no)
				(sheetname "")
			)
			(fill
				(thermal_gap 0.5)
				(thermal_bridge_width 0.5)
				(island_removal_mode 0)
			)
			(polygon
				(pts
					(arc
						(start 385.243578 -284.200092)
						(mid 385.279409 -284.185303)
						(end 385.294378 -284.149546)
					)
					(arc
						(start 385.294378 -284.149546)
						(mid 385.290318 -284.129389)
						(end 385.27863 -284.112462)
					)
					(arc
						(start 385.27863 -284.112462)
						(mid 385.18137 -284.04374)
						(end 385.064762 -284.019498)
					)
					(arc
						(start 385.064762 -284.019498)
						(mid 384.85838 -284.105142)
						(end 384.772916 -284.311598)
					)
					(arc
						(start 384.772916 -284.311598)
						(mid 384.796566 -284.426992)
						(end 384.863848 -284.523688)
					)
					(arc
						(start 384.863848 -284.523688)
						(mid 384.881076 -284.536257)
						(end 384.901948 -284.540706)
					)
					(arc
						(start 384.901948 -284.540706)
						(mid 384.937869 -284.525827)
						(end 384.952748 -284.489906)
					)
					(arc
						(start 384.952748 -284.489906)
						(mid 384.950609 -284.47532)
						(end 384.944366 -284.461966)
					)
					(xy 384.929634 -284.447488) (xy 384.929126 -284.44698)
					(arc
						(start 384.928618 -284.446218)
						(mid 384.887639 -284.38437)
						(end 384.873246 -284.311598)
					)
					(arc
						(start 384.873246 -284.311598)
						(mid 384.92934 -284.176176)
						(end 385.064762 -284.120082)
					)
					(arc
						(start 385.064762 -284.120082)
						(mid 385.138384 -284.134798)
						(end 385.200652 -284.176724)
					)
					(xy 385.20116 -284.177232)
					(arc
						(start 385.215638 -284.19171)
						(mid 385.228994 -284.197946)
						(end 385.243578 -284.200092)
					)
				)
			)
		)
		(zone
			(layer "F.Cu")
			(hatch none 0.5)
			(connect_pads
				(clearance 0)
			)
			(min_thickness 0.25)
			(keepout
				(tracks not_allowed)
				(vias allowed)
				(pads allowed)
				(copperpour not_allowed)
				(footprints allowed)
			)
			(placement
				(enabled no)
				(sheetname "")
			)
			(fill
				(thermal_gap 0.5)
				(thermal_bridge_width 0.5)
				(island_removal_mode 0)
			)
			(polygon
				(pts
					(arc
						(start 385.313428 -219.049346)
						(mid 385.298549 -219.013425)
						(end 385.262628 -218.998546)
					)
					(arc
						(start 385.262628 -218.998546)
						(mid 385.242581 -219.002778)
						(end 385.225798 -219.014548)
					)
					(arc
						(start 385.225798 -219.014548)
						(mid 385.157069 -219.111675)
						(end 385.132834 -219.228162)
					)
					(arc
						(start 385.132834 -219.228162)
						(mid 385.218388 -219.434708)
						(end 385.424934 -219.520262)
					)
					(arc
						(start 385.424934 -219.520262)
						(mid 385.540219 -219.49644)
						(end 385.63677 -219.429076)
					)
					(arc
						(start 385.63677 -219.429076)
						(mid 385.649288 -219.411964)
						(end 385.653788 -219.39123)
					)
					(arc
						(start 385.653788 -219.39123)
						(mid 385.638909 -219.355309)
						(end 385.602988 -219.34043)
					)
					(arc
						(start 385.602988 -219.34043)
						(mid 385.58854 -219.342453)
						(end 385.575302 -219.348558)
					)
					(xy 385.56057 -219.36329) (xy 385.560316 -219.363798)
					(arc
						(start 385.559554 -219.364306)
						(mid 385.497706 -219.405285)
						(end 385.424934 -219.419678)
					)
					(arc
						(start 385.424934 -219.419678)
						(mid 385.289512 -219.363584)
						(end 385.233418 -219.228162)
					)
					(arc
						(start 385.233418 -219.228162)
						(mid 385.248134 -219.15454)
						(end 385.29006 -219.092272)
					)
					(xy 385.290568 -219.091764)
					(arc
						(start 385.305046 -219.077286)
						(mid 385.311282 -219.06393)
						(end 385.313428 -219.049346)
					)
				)
			)
		)
		(zone
			(layer "F.Cu")
			(hatch none 0.5)
			(connect_pads
				(clearance 0)
			)
			(min_thickness 0.25)
			(keepout
				(tracks not_allowed)
				(vias allowed)
				(pads allowed)
				(copperpour not_allowed)
				(footprints allowed)
			)
			(placement
				(enabled no)
				(sheetname "")
			)
			(fill
				(thermal_gap 0.5)
				(thermal_bridge_width 0.5)
				(island_removal_mode 0)
			)
			(polygon
				(pts
					(arc
						(start 385.313428 -217.42146)
						(mid 385.298549 -217.385539)
						(end 385.262628 -217.37066)
					)
					(arc
						(start 385.262628 -217.37066)
						(mid 385.242581 -217.374892)
						(end 385.225798 -217.386662)
					)
					(arc
						(start 385.225798 -217.386662)
						(mid 385.157127 -217.483805)
						(end 385.132834 -217.600276)
					)
					(arc
						(start 385.132834 -217.600276)
						(mid 385.218388 -217.806822)
						(end 385.424934 -217.892376)
					)
					(arc
						(start 385.424934 -217.892376)
						(mid 385.54026 -217.868623)
						(end 385.63677 -217.80119)
					)
					(arc
						(start 385.63677 -217.80119)
						(mid 385.649288 -217.784078)
						(end 385.653788 -217.763344)
					)
					(arc
						(start 385.653788 -217.763344)
						(mid 385.638909 -217.727423)
						(end 385.602988 -217.712544)
					)
					(arc
						(start 385.602988 -217.712544)
						(mid 385.588534 -217.714719)
						(end 385.575302 -217.720926)
					)
					(xy 385.56057 -217.735658) (xy 385.560316 -217.735912)
					(arc
						(start 385.559554 -217.736674)
						(mid 385.497677 -217.777518)
						(end 385.424934 -217.791792)
					)
					(arc
						(start 385.424934 -217.791792)
						(mid 385.289512 -217.735698)
						(end 385.233418 -217.600276)
					)
					(arc
						(start 385.233418 -217.600276)
						(mid 385.248134 -217.526654)
						(end 385.29006 -217.464386)
					)
					(xy 385.290568 -217.464132)
					(arc
						(start 385.305046 -217.449654)
						(mid 385.311319 -217.436176)
						(end 385.313428 -217.42146)
					)
				)
			)
		)
		(zone
			(layer "F.Cu")
			(hatch none 0.5)
			(connect_pads
				(clearance 0)
			)
			(min_thickness 0.25)
			(keepout
				(tracks not_allowed)
				(vias allowed)
				(pads allowed)
				(copperpour not_allowed)
				(footprints allowed)
			)
			(placement
				(enabled no)
				(sheetname "")
			)
			(fill
				(thermal_gap 0.5)
				(thermal_bridge_width 0.5)
				(island_removal_mode 0)
			)
			(polygon
				(pts
					(arc
						(start 385.472432 -249.950732)
						(mid 385.487267 -249.914918)
						(end 385.472432 -249.879104)
					)
					(arc
						(start 385.472432 -249.879104)
						(mid 385.45531 -249.867753)
						(end 385.435094 -249.864118)
					)
					(arc
						(start 385.435094 -249.864118)
						(mid 385.317893 -249.884267)
						(end 385.218432 -249.949462)
					)
					(arc
						(start 385.218432 -249.949462)
						(mid 385.132896 -250.155964)
						(end 385.218432 -250.362466)
					)
					(arc
						(start 385.218432 -250.362466)
						(mid 385.316676 -250.427348)
						(end 385.432554 -250.448064)
					)
					(arc
						(start 385.432554 -250.448064)
						(mid 385.453744 -250.444812)
						(end 385.47167 -250.433078)
					)
					(arc
						(start 385.47167 -250.433078)
						(mid 385.48643 -250.397174)
						(end 385.47167 -250.361196)
					)
					(arc
						(start 385.47167 -250.361196)
						(mid 385.459849 -250.352454)
						(end 385.446016 -250.34748)
					)
					(xy 385.425188 -250.34748) (xy 385.42468 -250.34748)
					(arc
						(start 385.423664 -250.34748)
						(mid 385.351109 -250.33258)
						(end 385.289552 -250.291346)
					)
					(arc
						(start 385.289552 -250.291346)
						(mid 385.233475 -250.155964)
						(end 385.289552 -250.020582)
					)
					(arc
						(start 385.289552 -250.020582)
						(mid 385.3519 -249.978982)
						(end 385.425442 -249.964448)
					)
					(xy 385.426204 -249.964702)
					(arc
						(start 385.446778 -249.964702)
						(mid 385.46064 -249.959612)
						(end 385.472432 -249.950732)
					)
				)
			)
		)
		(zone
			(layer "F.Cu")
			(hatch none 0.5)
			(connect_pads
				(clearance 0)
			)
			(min_thickness 0.25)
			(keepout
				(tracks not_allowed)
				(vias allowed)
				(pads allowed)
				(copperpour not_allowed)
				(footprints allowed)
			)
			(placement
				(enabled no)
				(sheetname "")
			)
			(fill
				(thermal_gap 0.5)
				(thermal_bridge_width 0.5)
				(island_removal_mode 0)
			)
			(polygon
				(pts
					(arc
						(start 385.713478 -286.641794)
						(mid 385.749309 -286.627005)
						(end 385.764278 -286.591248)
					)
					(arc
						(start 385.764278 -286.591248)
						(mid 385.760218 -286.571091)
						(end 385.74853 -286.554164)
					)
					(arc
						(start 385.74853 -286.554164)
						(mid 385.65127 -286.485442)
						(end 385.534662 -286.4612)
					)
					(arc
						(start 385.534662 -286.4612)
						(mid 385.32828 -286.546844)
						(end 385.242816 -286.7533)
					)
					(arc
						(start 385.242816 -286.7533)
						(mid 385.266466 -286.868694)
						(end 385.333748 -286.96539)
					)
					(arc
						(start 385.333748 -286.96539)
						(mid 385.35101 -286.977811)
						(end 385.371848 -286.982154)
					)
					(arc
						(start 385.371848 -286.982154)
						(mid 385.407769 -286.967275)
						(end 385.422648 -286.931354)
					)
					(arc
						(start 385.422648 -286.931354)
						(mid 385.420473 -286.9169)
						(end 385.414266 -286.903668)
					)
					(xy 385.399534 -286.88919) (xy 385.399026 -286.888682)
					(arc
						(start 385.398518 -286.88792)
						(mid 385.357539 -286.826072)
						(end 385.343146 -286.7533)
					)
					(arc
						(start 385.343146 -286.7533)
						(mid 385.39924 -286.617878)
						(end 385.534662 -286.561784)
					)
					(arc
						(start 385.534662 -286.561784)
						(mid 385.608284 -286.5765)
						(end 385.670552 -286.618426)
					)
					(xy 385.67106 -286.618934)
					(arc
						(start 385.685538 -286.633412)
						(mid 385.698894 -286.639648)
						(end 385.713478 -286.641794)
					)
				)
			)
		)
		(zone
			(layer "F.Cu")
			(hatch none 0.5)
			(connect_pads
				(clearance 0)
			)
			(min_thickness 0.25)
			(keepout
				(tracks not_allowed)
				(vias allowed)
				(pads allowed)
				(copperpour not_allowed)
				(footprints allowed)
			)
			(placement
				(enabled no)
				(sheetname "")
			)
			(fill
				(thermal_gap 0.5)
				(thermal_bridge_width 0.5)
				(island_removal_mode 0)
			)
			(polygon
				(pts
					(arc
						(start 385.713478 -285.014162)
						(mid 385.749399 -284.999283)
						(end 385.764278 -284.963362)
					)
					(arc
						(start 385.764278 -284.963362)
						(mid 385.760218 -284.943205)
						(end 385.74853 -284.926278)
					)
					(arc
						(start 385.74853 -284.926278)
						(mid 385.651238 -284.8577)
						(end 385.534662 -284.833568)
					)
					(arc
						(start 385.534662 -284.833568)
						(mid 385.328296 -284.919048)
						(end 385.242816 -285.125414)
					)
					(arc
						(start 385.242816 -285.125414)
						(mid 385.266466 -285.240808)
						(end 385.333748 -285.337504)
					)
					(arc
						(start 385.333748 -285.337504)
						(mid 385.350976 -285.350073)
						(end 385.371848 -285.354522)
					)
					(arc
						(start 385.371848 -285.354522)
						(mid 385.407769 -285.339643)
						(end 385.422648 -285.303722)
					)
					(arc
						(start 385.422648 -285.303722)
						(mid 385.420509 -285.289136)
						(end 385.414266 -285.275782)
					)
					(xy 385.399534 -285.261304) (xy 385.399026 -285.260796)
					(arc
						(start 385.398518 -285.260288)
						(mid 385.357491 -285.198323)
						(end 385.343146 -285.125414)
					)
					(arc
						(start 385.343146 -285.125414)
						(mid 385.39924 -284.989992)
						(end 385.534662 -284.933898)
					)
					(arc
						(start 385.534662 -284.933898)
						(mid 385.608284 -284.948614)
						(end 385.670552 -284.99054)
					)
					(xy 385.67106 -284.991302)
					(arc
						(start 385.685538 -285.00578)
						(mid 385.698894 -285.012016)
						(end 385.713478 -285.014162)
					)
				)
			)
		)
		(zone
			(layer "F.Cu")
			(hatch none 0.5)
			(connect_pads
				(clearance 0)
			)
			(min_thickness 0.25)
			(keepout
				(tracks not_allowed)
				(vias allowed)
				(pads allowed)
				(copperpour not_allowed)
				(footprints allowed)
			)
			(placement
				(enabled no)
				(sheetname "")
			)
			(fill
				(thermal_gap 0.5)
				(thermal_bridge_width 0.5)
				(island_removal_mode 0)
			)
			(polygon
				(pts
					(arc
						(start 385.713478 -283.386276)
						(mid 385.749399 -283.371397)
						(end 385.764278 -283.335476)
					)
					(arc
						(start 385.764278 -283.335476)
						(mid 385.760167 -283.315457)
						(end 385.74853 -283.298646)
					)
					(arc
						(start 385.74853 -283.298646)
						(mid 385.65127 -283.229924)
						(end 385.534662 -283.205682)
					)
					(arc
						(start 385.534662 -283.205682)
						(mid 385.32828 -283.291326)
						(end 385.242816 -283.497782)
					)
					(arc
						(start 385.242816 -283.497782)
						(mid 385.266532 -283.613023)
						(end 385.333748 -283.709618)
					)
					(arc
						(start 385.333748 -283.709618)
						(mid 385.350976 -283.722187)
						(end 385.371848 -283.726636)
					)
					(arc
						(start 385.371848 -283.726636)
						(mid 385.407769 -283.711757)
						(end 385.422648 -283.675836)
					)
					(arc
						(start 385.422648 -283.675836)
						(mid 385.420473 -283.661382)
						(end 385.414266 -283.64815)
					)
					(xy 385.399534 -283.633418) (xy 385.399026 -283.633164)
					(arc
						(start 385.398518 -283.632402)
						(mid 385.357539 -283.570554)
						(end 385.343146 -283.497782)
					)
					(arc
						(start 385.343146 -283.497782)
						(mid 385.39924 -283.36236)
						(end 385.534662 -283.306266)
					)
					(arc
						(start 385.534662 -283.306266)
						(mid 385.608255 -283.320864)
						(end 385.670552 -283.362654)
					)
					(xy 385.67106 -283.363416)
					(arc
						(start 385.685538 -283.377894)
						(mid 385.698894 -283.38413)
						(end 385.713478 -283.386276)
					)
				)
			)
		)
		(zone
			(layer "F.Cu")
			(hatch none 0.5)
			(connect_pads
				(clearance 0)
			)
			(min_thickness 0.25)
			(keepout
				(tracks not_allowed)
				(vias allowed)
				(pads allowed)
				(copperpour not_allowed)
				(footprints allowed)
			)
			(placement
				(enabled no)
				(sheetname "")
			)
			(fill
				(thermal_gap 0.5)
				(thermal_bridge_width 0.5)
				(island_removal_mode 0)
			)
			(polygon
				(pts
					(arc
						(start 385.783328 -219.863162)
						(mid 385.768449 -219.827241)
						(end 385.732528 -219.812362)
					)
					(arc
						(start 385.732528 -219.812362)
						(mid 385.712481 -219.816594)
						(end 385.695698 -219.828364)
					)
					(arc
						(start 385.695698 -219.828364)
						(mid 385.627027 -219.925507)
						(end 385.602734 -220.041978)
					)
					(arc
						(start 385.602734 -220.041978)
						(mid 385.688288 -220.248524)
						(end 385.894834 -220.334078)
					)
					(arc
						(start 385.894834 -220.334078)
						(mid 386.01016 -220.310325)
						(end 386.10667 -220.242892)
					)
					(arc
						(start 386.10667 -220.242892)
						(mid 386.119188 -220.22578)
						(end 386.123688 -220.205046)
					)
					(arc
						(start 386.123688 -220.205046)
						(mid 386.108809 -220.169125)
						(end 386.072888 -220.154246)
					)
					(arc
						(start 386.072888 -220.154246)
						(mid 386.058434 -220.156421)
						(end 386.045202 -220.162628)
					)
					(xy 386.03047 -220.17736) (xy 386.030216 -220.177614)
					(arc
						(start 386.029454 -220.178376)
						(mid 385.967577 -220.21922)
						(end 385.894834 -220.233494)
					)
					(arc
						(start 385.894834 -220.233494)
						(mid 385.759412 -220.1774)
						(end 385.703318 -220.041978)
					)
					(arc
						(start 385.703318 -220.041978)
						(mid 385.718034 -219.968356)
						(end 385.75996 -219.906088)
					)
					(xy 385.760468 -219.905834)
					(arc
						(start 385.774946 -219.891356)
						(mid 385.781219 -219.877878)
						(end 385.783328 -219.863162)
					)
				)
			)
		)
		(zone
			(layer "F.Cu")
			(hatch none 0.5)
			(connect_pads
				(clearance 0)
			)
			(min_thickness 0.25)
			(keepout
				(tracks not_allowed)
				(vias allowed)
				(pads allowed)
				(copperpour not_allowed)
				(footprints allowed)
			)
			(placement
				(enabled no)
				(sheetname "")
			)
			(fill
				(thermal_gap 0.5)
				(thermal_bridge_width 0.5)
				(island_removal_mode 0)
			)
			(polygon
				(pts
					(arc
						(start 385.783328 -218.23553)
						(mid 385.768449 -218.199609)
						(end 385.732528 -218.18473)
					)
					(arc
						(start 385.732528 -218.18473)
						(mid 385.712509 -218.188841)
						(end 385.695698 -218.200478)
					)
					(arc
						(start 385.695698 -218.200478)
						(mid 385.626976 -218.297738)
						(end 385.602734 -218.414346)
					)
					(arc
						(start 385.602734 -218.414346)
						(mid 385.688288 -218.620892)
						(end 385.894834 -218.706446)
					)
					(arc
						(start 385.894834 -218.706446)
						(mid 386.010119 -218.682624)
						(end 386.10667 -218.61526)
					)
					(arc
						(start 386.10667 -218.61526)
						(mid 386.119239 -218.598032)
						(end 386.123688 -218.57716)
					)
					(arc
						(start 386.123688 -218.57716)
						(mid 386.108809 -218.541239)
						(end 386.072888 -218.52636)
					)
					(arc
						(start 386.072888 -218.52636)
						(mid 386.058434 -218.528535)
						(end 386.045202 -218.534742)
					)
					(xy 386.03047 -218.549474) (xy 386.030216 -218.549728)
					(arc
						(start 386.029454 -218.55049)
						(mid 385.967606 -218.591469)
						(end 385.894834 -218.605862)
					)
					(arc
						(start 385.894834 -218.605862)
						(mid 385.759412 -218.549768)
						(end 385.703318 -218.414346)
					)
					(arc
						(start 385.703318 -218.414346)
						(mid 385.718034 -218.340724)
						(end 385.75996 -218.278456)
					)
					(xy 385.760468 -218.277948)
					(arc
						(start 385.774946 -218.26347)
						(mid 385.781182 -218.250114)
						(end 385.783328 -218.23553)
					)
				)
			)
		)
		(zone
			(layer "F.Cu")
			(hatch none 0.5)
			(connect_pads
				(clearance 0)
			)
			(min_thickness 0.25)
			(keepout
				(tracks not_allowed)
				(vias allowed)
				(pads allowed)
				(copperpour not_allowed)
				(footprints allowed)
			)
			(placement
				(enabled no)
				(sheetname "")
			)
			(fill
				(thermal_gap 0.5)
				(thermal_bridge_width 0.5)
				(island_removal_mode 0)
			)
			(polygon
				(pts
					(arc
						(start 385.783328 -216.607644)
						(mid 385.768449 -216.571723)
						(end 385.732528 -216.556844)
					)
					(arc
						(start 385.732528 -216.556844)
						(mid 385.712481 -216.561076)
						(end 385.695698 -216.572846)
					)
					(arc
						(start 385.695698 -216.572846)
						(mid 385.626969 -216.669973)
						(end 385.602734 -216.78646)
					)
					(arc
						(start 385.602734 -216.78646)
						(mid 385.688288 -216.993006)
						(end 385.894834 -217.07856)
					)
					(arc
						(start 385.894834 -217.07856)
						(mid 386.010119 -217.054738)
						(end 386.10667 -216.987374)
					)
					(arc
						(start 386.10667 -216.987374)
						(mid 386.119188 -216.970262)
						(end 386.123688 -216.949528)
					)
					(arc
						(start 386.123688 -216.949528)
						(mid 386.108809 -216.913607)
						(end 386.072888 -216.898728)
					)
					(arc
						(start 386.072888 -216.898728)
						(mid 386.05844 -216.900751)
						(end 386.045202 -216.906856)
					)
					(xy 386.03047 -216.921588) (xy 386.030216 -216.922096)
					(arc
						(start 386.029454 -216.922604)
						(mid 385.967606 -216.963583)
						(end 385.894834 -216.977976)
					)
					(arc
						(start 385.894834 -216.977976)
						(mid 385.759412 -216.921882)
						(end 385.703318 -216.78646)
					)
					(arc
						(start 385.703318 -216.78646)
						(mid 385.718034 -216.712838)
						(end 385.75996 -216.65057)
					)
					(xy 385.760468 -216.650062)
					(arc
						(start 385.774946 -216.635584)
						(mid 385.781182 -216.622228)
						(end 385.783328 -216.607644)
					)
				)
			)
		)
		(zone
			(layer "F.Cu")
			(hatch none 0.5)
			(connect_pads
				(clearance 0)
			)
			(min_thickness 0.25)
			(keepout
				(tracks not_allowed)
				(vias allowed)
				(pads allowed)
				(copperpour not_allowed)
				(footprints allowed)
			)
			(placement
				(enabled no)
				(sheetname "")
			)
			(fill
				(thermal_gap 0.5)
				(thermal_bridge_width 0.5)
				(island_removal_mode 0)
			)
			(polygon
				(pts
					(arc
						(start 385.942332 -249.136916)
						(mid 385.957167 -249.101013)
						(end 385.942332 -249.065034)
					)
					(arc
						(start 385.942332 -249.065034)
						(mid 385.925179 -249.053823)
						(end 385.904994 -249.050302)
					)
					(arc
						(start 385.904994 -249.050302)
						(mid 385.787793 -249.070451)
						(end 385.688332 -249.135646)
					)
					(arc
						(start 385.688332 -249.135646)
						(mid 385.602796 -249.342148)
						(end 385.688332 -249.54865)
					)
					(arc
						(start 385.688332 -249.54865)
						(mid 385.786607 -249.613391)
						(end 385.902454 -249.633994)
					)
					(arc
						(start 385.902454 -249.633994)
						(mid 385.923604 -249.630853)
						(end 385.94157 -249.619262)
					)
					(arc
						(start 385.94157 -249.619262)
						(mid 385.95633 -249.583358)
						(end 385.94157 -249.54738)
					)
					(arc
						(start 385.94157 -249.54738)
						(mid 385.929749 -249.538638)
						(end 385.915916 -249.533664)
					)
					(xy 385.895088 -249.533664) (xy 385.89458 -249.533664)
					(arc
						(start 385.893564 -249.533664)
						(mid 385.820995 -249.518779)
						(end 385.759452 -249.47753)
					)
					(arc
						(start 385.759452 -249.47753)
						(mid 385.703375 -249.342148)
						(end 385.759452 -249.206766)
					)
					(arc
						(start 385.759452 -249.206766)
						(mid 385.8218 -249.165166)
						(end 385.895342 -249.150632)
					)
					(xy 385.896104 -249.150886)
					(arc
						(start 385.916678 -249.150886)
						(mid 385.93054 -249.145796)
						(end 385.942332 -249.136916)
					)
				)
			)
		)
		(zone
			(layer "F.Cu")
			(hatch none 0.5)
			(connect_pads
				(clearance 0)
			)
			(min_thickness 0.25)
			(keepout
				(tracks not_allowed)
				(vias allowed)
				(pads allowed)
				(copperpour not_allowed)
				(footprints allowed)
			)
			(placement
				(enabled no)
				(sheetname "")
			)
			(fill
				(thermal_gap 0.5)
				(thermal_bridge_width 0.5)
				(island_removal_mode 0)
			)
			(polygon
				(pts
					(arc
						(start 386.052314 -253.178564)
						(mid 386.067149 -253.142661)
						(end 386.052314 -253.106682)
					)
					(arc
						(start 386.052314 -253.106682)
						(mid 386.035161 -253.095471)
						(end 386.014976 -253.09195)
					)
					(arc
						(start 386.014976 -253.09195)
						(mid 385.897635 -253.112044)
						(end 385.79806 -253.177294)
					)
					(arc
						(start 385.79806 -253.177294)
						(mid 385.712524 -253.383796)
						(end 385.79806 -253.590298)
					)
					(arc
						(start 385.79806 -253.590298)
						(mid 385.896422 -253.655227)
						(end 386.012436 -253.675896)
					)
					(arc
						(start 386.012436 -253.675896)
						(mid 386.033485 -253.672585)
						(end 386.051298 -253.66091)
					)
					(arc
						(start 386.051298 -253.66091)
						(mid 386.066133 -253.625007)
						(end 386.051298 -253.589028)
					)
					(arc
						(start 386.051298 -253.589028)
						(mid 386.039477 -253.580286)
						(end 386.025644 -253.575312)
					)
					(xy 386.00507 -253.575312) (xy 386.004562 -253.575312)
					(arc
						(start 386.003546 -253.575312)
						(mid 385.930841 -253.560474)
						(end 385.86918 -253.519178)
					)
					(arc
						(start 385.86918 -253.519178)
						(mid 385.813103 -253.383796)
						(end 385.86918 -253.248414)
					)
					(arc
						(start 385.86918 -253.248414)
						(mid 385.931646 -253.206765)
						(end 386.005324 -253.19228)
					)
					(xy 386.006086 -253.192534)
					(arc
						(start 386.02666 -253.192534)
						(mid 386.040522 -253.187444)
						(end 386.052314 -253.178564)
					)
				)
			)
		)
		(zone
			(layer "F.Cu")
			(hatch none 0.5)
			(connect_pads
				(clearance 0)
			)
			(min_thickness 0.25)
			(keepout
				(tracks not_allowed)
				(vias allowed)
				(pads allowed)
				(copperpour not_allowed)
				(footprints allowed)
			)
			(placement
				(enabled no)
				(sheetname "")
			)
			(fill
				(thermal_gap 0.5)
				(thermal_bridge_width 0.5)
				(island_removal_mode 0)
			)
			(polygon
				(pts
					(arc
						(start 386.183378 -285.827978)
						(mid 386.219299 -285.813099)
						(end 386.234178 -285.777178)
					)
					(arc
						(start 386.234178 -285.777178)
						(mid 386.230067 -285.757159)
						(end 386.21843 -285.740348)
					)
					(arc
						(start 386.21843 -285.740348)
						(mid 386.12117 -285.671626)
						(end 386.004562 -285.647384)
					)
					(arc
						(start 386.004562 -285.647384)
						(mid 385.79818 -285.733028)
						(end 385.712716 -285.939484)
					)
					(arc
						(start 385.712716 -285.939484)
						(mid 385.736432 -286.054725)
						(end 385.803648 -286.15132)
					)
					(arc
						(start 385.803648 -286.15132)
						(mid 385.820876 -286.163889)
						(end 385.841748 -286.168338)
					)
					(arc
						(start 385.841748 -286.168338)
						(mid 385.877669 -286.153459)
						(end 385.892548 -286.117538)
					)
					(arc
						(start 385.892548 -286.117538)
						(mid 385.890373 -286.103084)
						(end 385.884166 -286.089852)
					)
					(xy 385.869434 -286.07512) (xy 385.868926 -286.074866)
					(arc
						(start 385.868418 -286.074104)
						(mid 385.827439 -286.012256)
						(end 385.813046 -285.939484)
					)
					(arc
						(start 385.813046 -285.939484)
						(mid 385.86914 -285.804062)
						(end 386.004562 -285.747968)
					)
					(arc
						(start 386.004562 -285.747968)
						(mid 386.078155 -285.762566)
						(end 386.140452 -285.804356)
					)
					(xy 386.14096 -285.805118)
					(arc
						(start 386.155438 -285.819596)
						(mid 386.168794 -285.825832)
						(end 386.183378 -285.827978)
					)
				)
			)
		)
		(zone
			(layer "F.Cu")
			(hatch none 0.5)
			(connect_pads
				(clearance 0)
			)
			(min_thickness 0.25)
			(keepout
				(tracks not_allowed)
				(vias allowed)
				(pads allowed)
				(copperpour not_allowed)
				(footprints allowed)
			)
			(placement
				(enabled no)
				(sheetname "")
			)
			(fill
				(thermal_gap 0.5)
				(thermal_bridge_width 0.5)
				(island_removal_mode 0)
			)
			(polygon
				(pts
					(arc
						(start 386.183378 -284.200092)
						(mid 386.219209 -284.185303)
						(end 386.234178 -284.149546)
					)
					(arc
						(start 386.234178 -284.149546)
						(mid 386.230118 -284.129389)
						(end 386.21843 -284.112462)
					)
					(arc
						(start 386.21843 -284.112462)
						(mid 386.12117 -284.04374)
						(end 386.004562 -284.019498)
					)
					(arc
						(start 386.004562 -284.019498)
						(mid 385.79818 -284.105142)
						(end 385.712716 -284.311598)
					)
					(arc
						(start 385.712716 -284.311598)
						(mid 385.736366 -284.426992)
						(end 385.803648 -284.523688)
					)
					(arc
						(start 385.803648 -284.523688)
						(mid 385.820876 -284.536257)
						(end 385.841748 -284.540706)
					)
					(arc
						(start 385.841748 -284.540706)
						(mid 385.877669 -284.525827)
						(end 385.892548 -284.489906)
					)
					(arc
						(start 385.892548 -284.489906)
						(mid 385.890409 -284.47532)
						(end 385.884166 -284.461966)
					)
					(xy 385.869434 -284.447488) (xy 385.868926 -284.44698)
					(arc
						(start 385.868418 -284.446218)
						(mid 385.827439 -284.38437)
						(end 385.813046 -284.311598)
					)
					(arc
						(start 385.813046 -284.311598)
						(mid 385.86914 -284.176176)
						(end 386.004562 -284.120082)
					)
					(arc
						(start 386.004562 -284.120082)
						(mid 386.078184 -284.134798)
						(end 386.140452 -284.176724)
					)
					(xy 386.14096 -284.177232)
					(arc
						(start 386.155438 -284.19171)
						(mid 386.168794 -284.197946)
						(end 386.183378 -284.200092)
					)
				)
			)
		)
		(zone
			(layer "F.Cu")
			(hatch none 0.5)
			(connect_pads
				(clearance 0)
			)
			(min_thickness 0.25)
			(keepout
				(tracks not_allowed)
				(vias allowed)
				(pads allowed)
				(copperpour not_allowed)
				(footprints allowed)
			)
			(placement
				(enabled no)
				(sheetname "")
			)
			(fill
				(thermal_gap 0.5)
				(thermal_bridge_width 0.5)
				(island_removal_mode 0)
			)
			(polygon
				(pts
					(arc
						(start 386.183378 -282.57246)
						(mid 386.219299 -282.557581)
						(end 386.234178 -282.52166)
					)
					(arc
						(start 386.234178 -282.52166)
						(mid 386.230067 -282.501641)
						(end 386.21843 -282.48483)
					)
					(arc
						(start 386.21843 -282.48483)
						(mid 386.12117 -282.416108)
						(end 386.004562 -282.391866)
					)
					(arc
						(start 386.004562 -282.391866)
						(mid 385.79818 -282.47751)
						(end 385.712716 -282.683966)
					)
					(arc
						(start 385.712716 -282.683966)
						(mid 385.736432 -282.799207)
						(end 385.803648 -282.895802)
					)
					(arc
						(start 385.803648 -282.895802)
						(mid 385.820876 -282.908371)
						(end 385.841748 -282.91282)
					)
					(arc
						(start 385.841748 -282.91282)
						(mid 385.877669 -282.897941)
						(end 385.892548 -282.86202)
					)
					(arc
						(start 385.892548 -282.86202)
						(mid 385.890373 -282.847566)
						(end 385.884166 -282.834334)
					)
					(xy 385.869434 -282.819602) (xy 385.868926 -282.819348)
					(arc
						(start 385.868418 -282.818586)
						(mid 385.827439 -282.756738)
						(end 385.813046 -282.683966)
					)
					(arc
						(start 385.813046 -282.683966)
						(mid 385.86914 -282.548544)
						(end 386.004562 -282.49245)
					)
					(arc
						(start 386.004562 -282.49245)
						(mid 386.078184 -282.507166)
						(end 386.140452 -282.549092)
					)
					(xy 386.14096 -282.5496)
					(arc
						(start 386.155438 -282.564078)
						(mid 386.168794 -282.570314)
						(end 386.183378 -282.57246)
					)
				)
			)
		)
		(zone
			(layer "F.Cu")
			(hatch none 0.5)
			(connect_pads
				(clearance 0)
			)
			(min_thickness 0.25)
			(keepout
				(tracks not_allowed)
				(vias allowed)
				(pads allowed)
				(copperpour not_allowed)
				(footprints allowed)
			)
			(placement
				(enabled no)
				(sheetname "")
			)
			(fill
				(thermal_gap 0.5)
				(thermal_bridge_width 0.5)
				(island_removal_mode 0)
			)
			(polygon
				(pts
					(arc
						(start 386.253228 -220.676978)
						(mid 386.238349 -220.641057)
						(end 386.202428 -220.626178)
					)
					(arc
						(start 386.202428 -220.626178)
						(mid 386.182381 -220.63041)
						(end 386.165598 -220.64218)
					)
					(arc
						(start 386.165598 -220.64218)
						(mid 386.096927 -220.739323)
						(end 386.072634 -220.855794)
					)
					(arc
						(start 386.072634 -220.855794)
						(mid 386.158188 -221.06234)
						(end 386.364734 -221.147894)
					)
					(arc
						(start 386.364734 -221.147894)
						(mid 386.48006 -221.124141)
						(end 386.57657 -221.056708)
					)
					(arc
						(start 386.57657 -221.056708)
						(mid 386.589088 -221.039596)
						(end 386.593588 -221.018862)
					)
					(arc
						(start 386.593588 -221.018862)
						(mid 386.578709 -220.982941)
						(end 386.542788 -220.968062)
					)
					(arc
						(start 386.542788 -220.968062)
						(mid 386.528334 -220.970237)
						(end 386.515102 -220.976444)
					)
					(xy 386.50037 -220.991176) (xy 386.500116 -220.99143)
					(arc
						(start 386.499354 -220.992192)
						(mid 386.437477 -221.033036)
						(end 386.364734 -221.04731)
					)
					(arc
						(start 386.364734 -221.04731)
						(mid 386.229312 -220.991216)
						(end 386.173218 -220.855794)
					)
					(arc
						(start 386.173218 -220.855794)
						(mid 386.187934 -220.782172)
						(end 386.22986 -220.719904)
					)
					(xy 386.230368 -220.71965)
					(arc
						(start 386.244846 -220.705172)
						(mid 386.251119 -220.691694)
						(end 386.253228 -220.676978)
					)
				)
			)
		)
		(zone
			(layer "F.Cu")
			(hatch none 0.5)
			(connect_pads
				(clearance 0)
			)
			(min_thickness 0.25)
			(keepout
				(tracks not_allowed)
				(vias allowed)
				(pads allowed)
				(copperpour not_allowed)
				(footprints allowed)
			)
			(placement
				(enabled no)
				(sheetname "")
			)
			(fill
				(thermal_gap 0.5)
				(thermal_bridge_width 0.5)
				(island_removal_mode 0)
			)
			(polygon
				(pts
					(arc
						(start 386.253228 -219.049346)
						(mid 386.238349 -219.013425)
						(end 386.202428 -218.998546)
					)
					(arc
						(start 386.202428 -218.998546)
						(mid 386.182381 -219.002778)
						(end 386.165598 -219.014548)
					)
					(arc
						(start 386.165598 -219.014548)
						(mid 386.096869 -219.111675)
						(end 386.072634 -219.228162)
					)
					(arc
						(start 386.072634 -219.228162)
						(mid 386.158188 -219.434708)
						(end 386.364734 -219.520262)
					)
					(arc
						(start 386.364734 -219.520262)
						(mid 386.480019 -219.49644)
						(end 386.57657 -219.429076)
					)
					(arc
						(start 386.57657 -219.429076)
						(mid 386.589088 -219.411964)
						(end 386.593588 -219.39123)
					)
					(arc
						(start 386.593588 -219.39123)
						(mid 386.578709 -219.355309)
						(end 386.542788 -219.34043)
					)
					(arc
						(start 386.542788 -219.34043)
						(mid 386.52834 -219.342453)
						(end 386.515102 -219.348558)
					)
					(xy 386.50037 -219.36329) (xy 386.500116 -219.363798)
					(arc
						(start 386.499354 -219.364306)
						(mid 386.437506 -219.405285)
						(end 386.364734 -219.419678)
					)
					(arc
						(start 386.364734 -219.419678)
						(mid 386.229312 -219.363584)
						(end 386.173218 -219.228162)
					)
					(arc
						(start 386.173218 -219.228162)
						(mid 386.187934 -219.15454)
						(end 386.22986 -219.092272)
					)
					(xy 386.230368 -219.091764)
					(arc
						(start 386.244846 -219.077286)
						(mid 386.251082 -219.06393)
						(end 386.253228 -219.049346)
					)
				)
			)
		)
		(zone
			(layer "F.Cu")
			(hatch none 0.5)
			(connect_pads
				(clearance 0)
			)
			(min_thickness 0.25)
			(keepout
				(tracks not_allowed)
				(vias allowed)
				(pads allowed)
				(copperpour not_allowed)
				(footprints allowed)
			)
			(placement
				(enabled no)
				(sheetname "")
			)
			(fill
				(thermal_gap 0.5)
				(thermal_bridge_width 0.5)
				(island_removal_mode 0)
			)
			(polygon
				(pts
					(arc
						(start 386.253228 -217.42146)
						(mid 386.238349 -217.385539)
						(end 386.202428 -217.37066)
					)
					(arc
						(start 386.202428 -217.37066)
						(mid 386.182381 -217.374892)
						(end 386.165598 -217.386662)
					)
					(arc
						(start 386.165598 -217.386662)
						(mid 386.096927 -217.483805)
						(end 386.072634 -217.600276)
					)
					(arc
						(start 386.072634 -217.600276)
						(mid 386.158188 -217.806822)
						(end 386.364734 -217.892376)
					)
					(arc
						(start 386.364734 -217.892376)
						(mid 386.48006 -217.868623)
						(end 386.57657 -217.80119)
					)
					(arc
						(start 386.57657 -217.80119)
						(mid 386.589088 -217.784078)
						(end 386.593588 -217.763344)
					)
					(arc
						(start 386.593588 -217.763344)
						(mid 386.578709 -217.727423)
						(end 386.542788 -217.712544)
					)
					(arc
						(start 386.542788 -217.712544)
						(mid 386.528334 -217.714719)
						(end 386.515102 -217.720926)
					)
					(xy 386.50037 -217.735658) (xy 386.500116 -217.735912)
					(arc
						(start 386.499354 -217.736674)
						(mid 386.437477 -217.777518)
						(end 386.364734 -217.791792)
					)
					(arc
						(start 386.364734 -217.791792)
						(mid 386.229312 -217.735698)
						(end 386.173218 -217.600276)
					)
					(arc
						(start 386.173218 -217.600276)
						(mid 386.187934 -217.526654)
						(end 386.22986 -217.464386)
					)
					(xy 386.230368 -217.464132)
					(arc
						(start 386.244846 -217.449654)
						(mid 386.251119 -217.436176)
						(end 386.253228 -217.42146)
					)
				)
			)
		)
		(zone
			(layer "F.Cu")
			(hatch none 0.5)
			(connect_pads
				(clearance 0)
			)
			(min_thickness 0.25)
			(keepout
				(tracks not_allowed)
				(vias allowed)
				(pads allowed)
				(copperpour not_allowed)
				(footprints allowed)
			)
			(placement
				(enabled no)
				(sheetname "")
			)
			(fill
				(thermal_gap 0.5)
				(thermal_bridge_width 0.5)
				(island_removal_mode 0)
			)
			(polygon
				(pts
					(arc
						(start 386.412232 -248.3231)
						(mid 386.427067 -248.287197)
						(end 386.412232 -248.251218)
					)
					(arc
						(start 386.412232 -248.251218)
						(mid 386.39511 -248.239867)
						(end 386.374894 -248.236232)
					)
					(arc
						(start 386.374894 -248.236232)
						(mid 386.257693 -248.256381)
						(end 386.158232 -248.321576)
					)
					(arc
						(start 386.158232 -248.321576)
						(mid 386.072696 -248.528078)
						(end 386.158232 -248.73458)
					)
					(arc
						(start 386.158232 -248.73458)
						(mid 386.25649 -248.799375)
						(end 386.372354 -248.820178)
					)
					(arc
						(start 386.372354 -248.820178)
						(mid 386.393517 -248.817049)
						(end 386.41147 -248.805446)
					)
					(arc
						(start 386.41147 -248.805446)
						(mid 386.42623 -248.769542)
						(end 386.41147 -248.733564)
					)
					(arc
						(start 386.41147 -248.733564)
						(mid 386.399649 -248.724822)
						(end 386.385816 -248.719848)
					)
					(xy 386.364988 -248.719848) (xy 386.36448 -248.719848)
					(arc
						(start 386.363464 -248.719848)
						(mid 386.290866 -248.704846)
						(end 386.229352 -248.66346)
					)
					(arc
						(start 386.229352 -248.66346)
						(mid 386.173275 -248.528078)
						(end 386.229352 -248.392696)
					)
					(arc
						(start 386.229352 -248.392696)
						(mid 386.291685 -248.351013)
						(end 386.365242 -248.336562)
					)
					(xy 386.366004 -248.336816)
					(arc
						(start 386.386578 -248.336816)
						(mid 386.400402 -248.331825)
						(end 386.412232 -248.3231)
					)
				)
			)
		)
		(zone
			(layer "F.Cu")
			(hatch none 0.5)
			(connect_pads
				(clearance 0)
			)
			(min_thickness 0.25)
			(keepout
				(tracks not_allowed)
				(vias allowed)
				(pads allowed)
				(copperpour not_allowed)
				(footprints allowed)
			)
			(placement
				(enabled no)
				(sheetname "")
			)
			(fill
				(thermal_gap 0.5)
				(thermal_bridge_width 0.5)
				(island_removal_mode 0)
			)
			(polygon
				(pts
					(arc
						(start 386.522468 -280.037032)
						(mid 386.537229 -280.001218)
						(end 386.522468 -279.965404)
					)
					(arc
						(start 386.522468 -279.965404)
						(mid 386.505228 -279.954005)
						(end 386.484876 -279.950418)
					)
					(arc
						(start 386.484876 -279.950418)
						(mid 386.367675 -279.970567)
						(end 386.268214 -280.035762)
					)
					(arc
						(start 386.268214 -280.035762)
						(mid 386.182678 -280.242264)
						(end 386.268214 -280.448766)
					)
					(arc
						(start 386.268214 -280.448766)
						(mid 386.366458 -280.513648)
						(end 386.482336 -280.534364)
					)
					(arc
						(start 386.482336 -280.534364)
						(mid 386.503526 -280.531112)
						(end 386.521452 -280.519378)
					)
					(arc
						(start 386.521452 -280.519378)
						(mid 386.536212 -280.483474)
						(end 386.521452 -280.447496)
					)
					(arc
						(start 386.521452 -280.447496)
						(mid 386.509631 -280.438754)
						(end 386.495798 -280.43378)
					)
					(xy 386.47497 -280.43378) (xy 386.474462 -280.43378)
					(arc
						(start 386.473446 -280.43378)
						(mid 386.400877 -280.418895)
						(end 386.339334 -280.377646)
					)
					(arc
						(start 386.339334 -280.377646)
						(mid 386.283257 -280.242264)
						(end 386.339334 -280.106882)
					)
					(arc
						(start 386.339334 -280.106882)
						(mid 386.401682 -280.065282)
						(end 386.475224 -280.050748)
					)
					(xy 386.475986 -280.051002)
					(arc
						(start 386.49656 -280.051002)
						(mid 386.510542 -280.045926)
						(end 386.522468 -280.037032)
					)
				)
			)
		)
		(zone
			(layer "F.Cu")
			(hatch none 0.5)
			(connect_pads
				(clearance 0)
			)
			(min_thickness 0.25)
			(keepout
				(tracks not_allowed)
				(vias allowed)
				(pads allowed)
				(copperpour not_allowed)
				(footprints allowed)
			)
			(placement
				(enabled no)
				(sheetname "")
			)
			(fill
				(thermal_gap 0.5)
				(thermal_bridge_width 0.5)
				(island_removal_mode 0)
			)
			(polygon
				(pts
					(arc
						(start 386.522468 -278.4094)
						(mid 386.537228 -278.373496)
						(end 386.522468 -278.337518)
					)
					(arc
						(start 386.522468 -278.337518)
						(mid 386.505228 -278.326119)
						(end 386.484876 -278.322532)
					)
					(arc
						(start 386.484876 -278.322532)
						(mid 386.367675 -278.342681)
						(end 386.268214 -278.407876)
					)
					(arc
						(start 386.268214 -278.407876)
						(mid 386.182678 -278.614378)
						(end 386.268214 -278.82088)
					)
					(arc
						(start 386.268214 -278.82088)
						(mid 386.366472 -278.885675)
						(end 386.482336 -278.906478)
					)
					(arc
						(start 386.482336 -278.906478)
						(mid 386.503499 -278.903349)
						(end 386.521452 -278.891746)
					)
					(arc
						(start 386.521452 -278.891746)
						(mid 386.536212 -278.855842)
						(end 386.521452 -278.819864)
					)
					(arc
						(start 386.521452 -278.819864)
						(mid 386.509631 -278.811122)
						(end 386.495798 -278.806148)
					)
					(xy 386.47497 -278.806148) (xy 386.474462 -278.806148)
					(arc
						(start 386.473446 -278.806148)
						(mid 386.400848 -278.791146)
						(end 386.339334 -278.74976)
					)
					(arc
						(start 386.339334 -278.74976)
						(mid 386.283257 -278.614378)
						(end 386.339334 -278.478996)
					)
					(arc
						(start 386.339334 -278.478996)
						(mid 386.401667 -278.437313)
						(end 386.475224 -278.422862)
					)
					(xy 386.475986 -278.423116)
					(arc
						(start 386.49656 -278.423116)
						(mid 386.510521 -278.418159)
						(end 386.522468 -278.4094)
					)
				)
			)
		)
		(zone
			(layer "F.Cu")
			(hatch none 0.5)
			(connect_pads
				(clearance 0)
			)
			(min_thickness 0.25)
			(keepout
				(tracks not_allowed)
				(vias allowed)
				(pads allowed)
				(copperpour not_allowed)
				(footprints allowed)
			)
			(placement
				(enabled no)
				(sheetname "")
			)
			(fill
				(thermal_gap 0.5)
				(thermal_bridge_width 0.5)
				(island_removal_mode 0)
			)
			(polygon
				(pts
					(arc
						(start 386.522468 -276.781514)
						(mid 386.537228 -276.74561)
						(end 386.522468 -276.709632)
					)
					(arc
						(start 386.522468 -276.709632)
						(mid 386.505197 -276.698375)
						(end 386.484876 -276.6949)
					)
					(arc
						(start 386.484876 -276.6949)
						(mid 386.367675 -276.715049)
						(end 386.268214 -276.780244)
					)
					(arc
						(start 386.268214 -276.780244)
						(mid 386.182678 -276.986746)
						(end 386.268214 -277.193248)
					)
					(arc
						(start 386.268214 -277.193248)
						(mid 386.366489 -277.257989)
						(end 386.482336 -277.278592)
					)
					(arc
						(start 386.482336 -277.278592)
						(mid 386.503486 -277.275451)
						(end 386.521452 -277.26386)
					)
					(arc
						(start 386.521452 -277.26386)
						(mid 386.536212 -277.227956)
						(end 386.521452 -277.191978)
					)
					(arc
						(start 386.521452 -277.191978)
						(mid 386.509631 -277.183236)
						(end 386.495798 -277.178262)
					)
					(xy 386.47497 -277.178262) (xy 386.474462 -277.178262)
					(arc
						(start 386.473446 -277.178262)
						(mid 386.400877 -277.163377)
						(end 386.339334 -277.122128)
					)
					(arc
						(start 386.339334 -277.122128)
						(mid 386.283257 -276.986746)
						(end 386.339334 -276.851364)
					)
					(arc
						(start 386.339334 -276.851364)
						(mid 386.401682 -276.809764)
						(end 386.475224 -276.79523)
					)
					(xy 386.475986 -276.795484)
					(arc
						(start 386.49656 -276.795484)
						(mid 386.510558 -276.790428)
						(end 386.522468 -276.781514)
					)
				)
			)
		)
		(zone
			(layer "F.Cu")
			(hatch none 0.5)
			(connect_pads
				(clearance 0)
			)
			(min_thickness 0.25)
			(keepout
				(tracks not_allowed)
				(vias allowed)
				(pads allowed)
				(copperpour not_allowed)
				(footprints allowed)
			)
			(placement
				(enabled no)
				(sheetname "")
			)
			(fill
				(thermal_gap 0.5)
				(thermal_bridge_width 0.5)
				(island_removal_mode 0)
			)
			(polygon
				(pts
					(arc
						(start 386.522468 -275.153628)
						(mid 386.537229 -275.117814)
						(end 386.522468 -275.082)
					)
					(arc
						(start 386.522468 -275.082)
						(mid 386.505228 -275.070601)
						(end 386.484876 -275.067014)
					)
					(arc
						(start 386.484876 -275.067014)
						(mid 386.367675 -275.087163)
						(end 386.268214 -275.152358)
					)
					(arc
						(start 386.268214 -275.152358)
						(mid 386.182678 -275.35886)
						(end 386.268214 -275.565362)
					)
					(arc
						(start 386.268214 -275.565362)
						(mid 386.366458 -275.630244)
						(end 386.482336 -275.65096)
					)
					(arc
						(start 386.482336 -275.65096)
						(mid 386.503526 -275.647708)
						(end 386.521452 -275.635974)
					)
					(arc
						(start 386.521452 -275.635974)
						(mid 386.536212 -275.60007)
						(end 386.521452 -275.564092)
					)
					(arc
						(start 386.521452 -275.564092)
						(mid 386.509631 -275.55535)
						(end 386.495798 -275.550376)
					)
					(xy 386.47497 -275.550376) (xy 386.474462 -275.550376)
					(arc
						(start 386.473446 -275.550376)
						(mid 386.400891 -275.535476)
						(end 386.339334 -275.494242)
					)
					(arc
						(start 386.339334 -275.494242)
						(mid 386.283257 -275.35886)
						(end 386.339334 -275.223478)
					)
					(arc
						(start 386.339334 -275.223478)
						(mid 386.401682 -275.181878)
						(end 386.475224 -275.167344)
					)
					(xy 386.475986 -275.167598)
					(arc
						(start 386.49656 -275.167598)
						(mid 386.510542 -275.162522)
						(end 386.522468 -275.153628)
					)
				)
			)
		)
		(zone
			(layer "F.Cu")
			(hatch none 0.5)
			(connect_pads
				(clearance 0)
			)
			(min_thickness 0.25)
			(keepout
				(tracks not_allowed)
				(vias allowed)
				(pads allowed)
				(copperpour not_allowed)
				(footprints allowed)
			)
			(placement
				(enabled no)
				(sheetname "")
			)
			(fill
				(thermal_gap 0.5)
				(thermal_bridge_width 0.5)
				(island_removal_mode 0)
			)
			(polygon
				(pts
					(arc
						(start 386.522468 -273.525996)
						(mid 386.537228 -273.490092)
						(end 386.522468 -273.454114)
					)
					(arc
						(start 386.522468 -273.454114)
						(mid 386.505197 -273.442857)
						(end 386.484876 -273.439382)
					)
					(arc
						(start 386.484876 -273.439382)
						(mid 386.367675 -273.459531)
						(end 386.268214 -273.524726)
					)
					(arc
						(start 386.268214 -273.524726)
						(mid 386.182678 -273.731228)
						(end 386.268214 -273.93773)
					)
					(arc
						(start 386.268214 -273.93773)
						(mid 386.366489 -274.002471)
						(end 386.482336 -274.023074)
					)
					(arc
						(start 386.482336 -274.023074)
						(mid 386.503486 -274.019933)
						(end 386.521452 -274.008342)
					)
					(arc
						(start 386.521452 -274.008342)
						(mid 386.536212 -273.972438)
						(end 386.521452 -273.93646)
					)
					(arc
						(start 386.521452 -273.93646)
						(mid 386.509631 -273.927718)
						(end 386.495798 -273.922744)
					)
					(xy 386.47497 -273.922744) (xy 386.474462 -273.922744)
					(arc
						(start 386.473446 -273.922744)
						(mid 386.400877 -273.907859)
						(end 386.339334 -273.86661)
					)
					(arc
						(start 386.339334 -273.86661)
						(mid 386.283257 -273.731228)
						(end 386.339334 -273.595846)
					)
					(arc
						(start 386.339334 -273.595846)
						(mid 386.401682 -273.554246)
						(end 386.475224 -273.539712)
					)
					(xy 386.475986 -273.539966)
					(arc
						(start 386.49656 -273.539966)
						(mid 386.510558 -273.53491)
						(end 386.522468 -273.525996)
					)
				)
			)
		)
		(zone
			(layer "F.Cu")
			(hatch none 0.5)
			(connect_pads
				(clearance 0)
			)
			(min_thickness 0.25)
			(keepout
				(tracks not_allowed)
				(vias allowed)
				(pads allowed)
				(copperpour not_allowed)
				(footprints allowed)
			)
			(placement
				(enabled no)
				(sheetname "")
			)
			(fill
				(thermal_gap 0.5)
				(thermal_bridge_width 0.5)
				(island_removal_mode 0)
			)
			(polygon
				(pts
					(arc
						(start 386.522468 -271.89811)
						(mid 386.537229 -271.862296)
						(end 386.522468 -271.826482)
					)
					(arc
						(start 386.522468 -271.826482)
						(mid 386.505228 -271.815083)
						(end 386.484876 -271.811496)
					)
					(arc
						(start 386.484876 -271.811496)
						(mid 386.367675 -271.831645)
						(end 386.268214 -271.89684)
					)
					(arc
						(start 386.268214 -271.89684)
						(mid 386.182678 -272.103342)
						(end 386.268214 -272.309844)
					)
					(arc
						(start 386.268214 -272.309844)
						(mid 386.366458 -272.374726)
						(end 386.482336 -272.395442)
					)
					(arc
						(start 386.482336 -272.395442)
						(mid 386.503526 -272.39219)
						(end 386.521452 -272.380456)
					)
					(arc
						(start 386.521452 -272.380456)
						(mid 386.536212 -272.344552)
						(end 386.521452 -272.308574)
					)
					(arc
						(start 386.521452 -272.308574)
						(mid 386.509631 -272.299832)
						(end 386.495798 -272.294858)
					)
					(xy 386.47497 -272.294858) (xy 386.474462 -272.294858)
					(arc
						(start 386.473446 -272.294858)
						(mid 386.400891 -272.279958)
						(end 386.339334 -272.238724)
					)
					(arc
						(start 386.339334 -272.238724)
						(mid 386.283257 -272.103342)
						(end 386.339334 -271.96796)
					)
					(arc
						(start 386.339334 -271.96796)
						(mid 386.401682 -271.92636)
						(end 386.475224 -271.911826)
					)
					(xy 386.475986 -271.91208)
					(arc
						(start 386.49656 -271.91208)
						(mid 386.510542 -271.907004)
						(end 386.522468 -271.89811)
					)
				)
			)
		)
		(zone
			(layer "F.Cu")
			(hatch none 0.5)
			(connect_pads
				(clearance 0)
			)
			(min_thickness 0.25)
			(keepout
				(tracks not_allowed)
				(vias allowed)
				(pads allowed)
				(copperpour not_allowed)
				(footprints allowed)
			)
			(placement
				(enabled no)
				(sheetname "")
			)
			(fill
				(thermal_gap 0.5)
				(thermal_bridge_width 0.5)
				(island_removal_mode 0)
			)
			(polygon
				(pts
					(arc
						(start 386.522468 -270.270478)
						(mid 386.537228 -270.234574)
						(end 386.522468 -270.198596)
					)
					(arc
						(start 386.522468 -270.198596)
						(mid 386.505228 -270.187197)
						(end 386.484876 -270.18361)
					)
					(arc
						(start 386.484876 -270.18361)
						(mid 386.367675 -270.203759)
						(end 386.268214 -270.268954)
					)
					(arc
						(start 386.268214 -270.268954)
						(mid 386.182678 -270.475456)
						(end 386.268214 -270.681958)
					)
					(arc
						(start 386.268214 -270.681958)
						(mid 386.366472 -270.746753)
						(end 386.482336 -270.767556)
					)
					(arc
						(start 386.482336 -270.767556)
						(mid 386.503499 -270.764427)
						(end 386.521452 -270.752824)
					)
					(arc
						(start 386.521452 -270.752824)
						(mid 386.536212 -270.71692)
						(end 386.521452 -270.680942)
					)
					(arc
						(start 386.521452 -270.680942)
						(mid 386.509631 -270.6722)
						(end 386.495798 -270.667226)
					)
					(xy 386.47497 -270.667226) (xy 386.474462 -270.667226)
					(arc
						(start 386.473446 -270.667226)
						(mid 386.400877 -270.652341)
						(end 386.339334 -270.611092)
					)
					(arc
						(start 386.339334 -270.611092)
						(mid 386.283257 -270.47562)
						(end 386.339334 -270.340074)
					)
					(arc
						(start 386.339334 -270.340074)
						(mid 386.401712 -270.298611)
						(end 386.475224 -270.284194)
					)
					(xy 386.475986 -270.284194)
					(arc
						(start 386.49656 -270.284194)
						(mid 386.510521 -270.279237)
						(end 386.522468 -270.270478)
					)
				)
			)
		)
		(zone
			(layer "F.Cu")
			(hatch none 0.5)
			(connect_pads
				(clearance 0)
			)
			(min_thickness 0.25)
			(keepout
				(tracks not_allowed)
				(vias allowed)
				(pads allowed)
				(copperpour not_allowed)
				(footprints allowed)
			)
			(placement
				(enabled no)
				(sheetname "")
			)
			(fill
				(thermal_gap 0.5)
				(thermal_bridge_width 0.5)
				(island_removal_mode 0)
			)
			(polygon
				(pts
					(arc
						(start 386.522468 -268.642592)
						(mid 386.537228 -268.606688)
						(end 386.522468 -268.57071)
					)
					(arc
						(start 386.522468 -268.57071)
						(mid 386.505197 -268.559453)
						(end 386.484876 -268.555978)
					)
					(arc
						(start 386.484876 -268.555978)
						(mid 386.367675 -268.576127)
						(end 386.268214 -268.641322)
					)
					(arc
						(start 386.268214 -268.641322)
						(mid 386.182678 -268.847824)
						(end 386.268214 -269.054326)
					)
					(arc
						(start 386.268214 -269.054326)
						(mid 386.366489 -269.119067)
						(end 386.482336 -269.13967)
					)
					(arc
						(start 386.482336 -269.13967)
						(mid 386.503486 -269.136529)
						(end 386.521452 -269.124938)
					)
					(arc
						(start 386.521452 -269.124938)
						(mid 386.536212 -269.089034)
						(end 386.521452 -269.053056)
					)
					(arc
						(start 386.521452 -269.053056)
						(mid 386.509631 -269.044314)
						(end 386.495798 -269.03934)
					)
					(xy 386.47497 -269.03934) (xy 386.474462 -269.03934)
					(arc
						(start 386.473446 -269.03934)
						(mid 386.400877 -269.024455)
						(end 386.339334 -268.983206)
					)
					(arc
						(start 386.339334 -268.983206)
						(mid 386.283257 -268.847824)
						(end 386.339334 -268.712442)
					)
					(arc
						(start 386.339334 -268.712442)
						(mid 386.401682 -268.670842)
						(end 386.475224 -268.656308)
					)
					(xy 386.475986 -268.656562)
					(arc
						(start 386.49656 -268.656562)
						(mid 386.510558 -268.651506)
						(end 386.522468 -268.642592)
					)
				)
			)
		)
		(zone
			(layer "F.Cu")
			(hatch none 0.5)
			(connect_pads
				(clearance 0)
			)
			(min_thickness 0.25)
			(keepout
				(tracks not_allowed)
				(vias allowed)
				(pads allowed)
				(copperpour not_allowed)
				(footprints allowed)
			)
			(placement
				(enabled no)
				(sheetname "")
			)
			(fill
				(thermal_gap 0.5)
				(thermal_bridge_width 0.5)
				(island_removal_mode 0)
			)
			(polygon
				(pts
					(arc
						(start 386.522468 -267.014706)
						(mid 386.537229 -266.978892)
						(end 386.522468 -266.943078)
					)
					(arc
						(start 386.522468 -266.943078)
						(mid 386.505228 -266.931679)
						(end 386.484876 -266.928092)
					)
					(arc
						(start 386.484876 -266.928092)
						(mid 386.367675 -266.948241)
						(end 386.268214 -267.013436)
					)
					(arc
						(start 386.268214 -267.013436)
						(mid 386.182678 -267.219938)
						(end 386.268214 -267.42644)
					)
					(arc
						(start 386.268214 -267.42644)
						(mid 386.366458 -267.491322)
						(end 386.482336 -267.512038)
					)
					(arc
						(start 386.482336 -267.512038)
						(mid 386.503499 -267.508909)
						(end 386.521452 -267.497306)
					)
					(arc
						(start 386.521452 -267.497306)
						(mid 386.536392 -267.461238)
						(end 386.521452 -267.42517)
					)
					(arc
						(start 386.521452 -267.42517)
						(mid 386.509631 -267.416428)
						(end 386.495798 -267.411454)
					)
					(xy 386.47497 -267.411454) (xy 386.474462 -267.411454)
					(arc
						(start 386.473446 -267.411454)
						(mid 386.400891 -267.396554)
						(end 386.339334 -267.35532)
					)
					(arc
						(start 386.339334 -267.35532)
						(mid 386.283257 -267.219938)
						(end 386.339334 -267.084556)
					)
					(arc
						(start 386.339334 -267.084556)
						(mid 386.401682 -267.042956)
						(end 386.475224 -267.028422)
					)
					(xy 386.475986 -267.028676)
					(arc
						(start 386.49656 -267.028676)
						(mid 386.510542 -267.0236)
						(end 386.522468 -267.014706)
					)
				)
			)
		)
		(zone
			(layer "F.Cu")
			(hatch none 0.5)
			(connect_pads
				(clearance 0)
			)
			(min_thickness 0.25)
			(keepout
				(tracks not_allowed)
				(vias allowed)
				(pads allowed)
				(copperpour not_allowed)
				(footprints allowed)
			)
			(placement
				(enabled no)
				(sheetname "")
			)
			(fill
				(thermal_gap 0.5)
				(thermal_bridge_width 0.5)
				(island_removal_mode 0)
			)
			(polygon
				(pts
					(arc
						(start 386.522468 -265.387074)
						(mid 386.537228 -265.35117)
						(end 386.522468 -265.315192)
					)
					(arc
						(start 386.522468 -265.315192)
						(mid 386.505228 -265.303793)
						(end 386.484876 -265.300206)
					)
					(arc
						(start 386.484876 -265.300206)
						(mid 386.367647 -265.320475)
						(end 386.268214 -265.385804)
					)
					(arc
						(start 386.268214 -265.385804)
						(mid 386.182678 -265.592216)
						(end 386.268214 -265.798554)
					)
					(arc
						(start 386.268214 -265.798554)
						(mid 386.366472 -265.863349)
						(end 386.482336 -265.884152)
					)
					(arc
						(start 386.482336 -265.884152)
						(mid 386.503499 -265.881023)
						(end 386.521452 -265.86942)
					)
					(arc
						(start 386.521452 -265.86942)
						(mid 386.536212 -265.833516)
						(end 386.521452 -265.797538)
					)
					(arc
						(start 386.521452 -265.797538)
						(mid 386.509631 -265.788796)
						(end 386.495798 -265.783822)
					)
					(xy 386.47497 -265.783822) (xy 386.474462 -265.783822)
					(arc
						(start 386.473446 -265.783822)
						(mid 386.400877 -265.768937)
						(end 386.339334 -265.727688)
					)
					(arc
						(start 386.339334 -265.727688)
						(mid 386.283257 -265.592216)
						(end 386.339334 -265.45667)
					)
					(arc
						(start 386.339334 -265.45667)
						(mid 386.401712 -265.415207)
						(end 386.475224 -265.40079)
					)
					(xy 386.475986 -265.40079)
					(arc
						(start 386.49656 -265.40079)
						(mid 386.510521 -265.395833)
						(end 386.522468 -265.387074)
					)
				)
			)
		)
		(zone
			(layer "F.Cu")
			(hatch none 0.5)
			(connect_pads
				(clearance 0)
			)
			(min_thickness 0.25)
			(keepout
				(tracks not_allowed)
				(vias allowed)
				(pads allowed)
				(copperpour not_allowed)
				(footprints allowed)
			)
			(placement
				(enabled no)
				(sheetname "")
			)
			(fill
				(thermal_gap 0.5)
				(thermal_bridge_width 0.5)
				(island_removal_mode 0)
			)
			(polygon
				(pts
					(arc
						(start 386.522468 -253.99238)
						(mid 386.537229 -253.956566)
						(end 386.522468 -253.920752)
					)
					(arc
						(start 386.522468 -253.920752)
						(mid 386.505228 -253.909353)
						(end 386.484876 -253.905766)
					)
					(arc
						(start 386.484876 -253.905766)
						(mid 386.367675 -253.925915)
						(end 386.268214 -253.99111)
					)
					(arc
						(start 386.268214 -253.99111)
						(mid 386.182678 -254.197612)
						(end 386.268214 -254.404114)
					)
					(arc
						(start 386.268214 -254.404114)
						(mid 386.366458 -254.468996)
						(end 386.482336 -254.489712)
					)
					(arc
						(start 386.482336 -254.489712)
						(mid 386.503499 -254.486583)
						(end 386.521452 -254.47498)
					)
					(arc
						(start 386.521452 -254.47498)
						(mid 386.536212 -254.439076)
						(end 386.521452 -254.403098)
					)
					(arc
						(start 386.521452 -254.403098)
						(mid 386.509631 -254.394356)
						(end 386.495798 -254.389382)
					)
					(xy 386.47497 -254.389382) (xy 386.474462 -254.389382)
					(arc
						(start 386.473446 -254.389382)
						(mid 386.400848 -254.37438)
						(end 386.339334 -254.332994)
					)
					(arc
						(start 386.339334 -254.332994)
						(mid 386.283257 -254.197612)
						(end 386.339334 -254.06223)
					)
					(arc
						(start 386.339334 -254.06223)
						(mid 386.401682 -254.02063)
						(end 386.475224 -254.006096)
					)
					(xy 386.475986 -254.00635)
					(arc
						(start 386.49656 -254.00635)
						(mid 386.510542 -254.001274)
						(end 386.522468 -253.99238)
					)
				)
			)
		)
		(zone
			(layer "F.Cu")
			(hatch none 0.5)
			(connect_pads
				(clearance 0)
			)
			(min_thickness 0.25)
			(keepout
				(tracks not_allowed)
				(vias allowed)
				(pads allowed)
				(copperpour not_allowed)
				(footprints allowed)
			)
			(placement
				(enabled no)
				(sheetname "")
			)
			(fill
				(thermal_gap 0.5)
				(thermal_bridge_width 0.5)
				(island_removal_mode 0)
			)
			(polygon
				(pts
					(arc
						(start 386.653532 -285.014162)
						(mid 386.689453 -284.999283)
						(end 386.704332 -284.963362)
					)
					(arc
						(start 386.704332 -284.963362)
						(mid 386.70015 -284.943178)
						(end 386.68833 -284.926278)
					)
					(arc
						(start 386.68833 -284.926278)
						(mid 386.591155 -284.85775)
						(end 386.474716 -284.833568)
					)
					(arc
						(start 386.474716 -284.833568)
						(mid 386.26826 -284.919032)
						(end 386.182616 -285.125414)
					)
					(arc
						(start 386.182616 -285.125414)
						(mid 386.206266 -285.240808)
						(end 386.273548 -285.337504)
					)
					(arc
						(start 386.273548 -285.337504)
						(mid 386.290776 -285.350073)
						(end 386.311648 -285.354522)
					)
					(arc
						(start 386.311648 -285.354522)
						(mid 386.347569 -285.339643)
						(end 386.362448 -285.303722)
					)
					(arc
						(start 386.362448 -285.303722)
						(mid 386.360309 -285.289136)
						(end 386.354066 -285.275782)
					)
					(xy 386.339334 -285.261304) (xy 386.33908 -285.260796)
					(arc
						(start 386.338318 -285.260288)
						(mid 386.297426 -285.198294)
						(end 386.2832 -285.125414)
					)
					(arc
						(start 386.2832 -285.125414)
						(mid 386.339294 -284.989992)
						(end 386.474716 -284.933898)
					)
					(arc
						(start 386.474716 -284.933898)
						(mid 386.548298 -284.948682)
						(end 386.610606 -284.99054)
					)
					(xy 386.61086 -284.991302)
					(arc
						(start 386.625338 -285.00578)
						(mid 386.638821 -285.012022)
						(end 386.653532 -285.014162)
					)
				)
			)
		)
		(zone
			(layer "F.Cu")
			(hatch none 0.5)
			(connect_pads
				(clearance 0)
			)
			(min_thickness 0.25)
			(keepout
				(tracks not_allowed)
				(vias allowed)
				(pads allowed)
				(copperpour not_allowed)
				(footprints allowed)
			)
			(placement
				(enabled no)
				(sheetname "")
			)
			(fill
				(thermal_gap 0.5)
				(thermal_bridge_width 0.5)
				(island_removal_mode 0)
			)
			(polygon
				(pts
					(arc
						(start 386.653532 -283.386276)
						(mid 386.689453 -283.371397)
						(end 386.704332 -283.335476)
					)
					(arc
						(start 386.704332 -283.335476)
						(mid 386.7001 -283.315429)
						(end 386.68833 -283.298646)
					)
					(arc
						(start 386.68833 -283.298646)
						(mid 386.591203 -283.229917)
						(end 386.474716 -283.205682)
					)
					(arc
						(start 386.474716 -283.205682)
						(mid 386.26817 -283.291236)
						(end 386.182616 -283.497782)
					)
					(arc
						(start 386.182616 -283.497782)
						(mid 386.206317 -283.613039)
						(end 386.273548 -283.709618)
					)
					(arc
						(start 386.273548 -283.709618)
						(mid 386.290776 -283.722187)
						(end 386.311648 -283.726636)
					)
					(arc
						(start 386.311648 -283.726636)
						(mid 386.347569 -283.711757)
						(end 386.362448 -283.675836)
					)
					(arc
						(start 386.362448 -283.675836)
						(mid 386.360263 -283.661388)
						(end 386.354066 -283.64815)
					)
					(xy 386.339334 -283.633418) (xy 386.33908 -283.633164)
					(arc
						(start 386.338318 -283.632402)
						(mid 386.297474 -283.570525)
						(end 386.2832 -283.497782)
					)
					(arc
						(start 386.2832 -283.497782)
						(mid 386.339294 -283.36236)
						(end 386.474716 -283.306266)
					)
					(arc
						(start 386.474716 -283.306266)
						(mid 386.548309 -283.320864)
						(end 386.610606 -283.362654)
					)
					(xy 386.61086 -283.363416)
					(arc
						(start 386.625338 -283.377894)
						(mid 386.638816 -283.384167)
						(end 386.653532 -283.386276)
					)
				)
			)
		)
		(zone
			(layer "F.Cu")
			(hatch none 0.5)
			(connect_pads
				(clearance 0)
			)
			(min_thickness 0.25)
			(keepout
				(tracks not_allowed)
				(vias allowed)
				(pads allowed)
				(copperpour not_allowed)
				(footprints allowed)
			)
			(placement
				(enabled no)
				(sheetname "")
			)
			(fill
				(thermal_gap 0.5)
				(thermal_bridge_width 0.5)
				(island_removal_mode 0)
			)
			(polygon
				(pts
					(arc
						(start 386.653532 -281.758644)
						(mid 386.689453 -281.743765)
						(end 386.704332 -281.707844)
					)
					(arc
						(start 386.704332 -281.707844)
						(mid 386.70015 -281.68766)
						(end 386.68833 -281.67076)
					)
					(arc
						(start 386.68833 -281.67076)
						(mid 386.591155 -281.602232)
						(end 386.474716 -281.57805)
					)
					(arc
						(start 386.474716 -281.57805)
						(mid 386.26826 -281.663514)
						(end 386.182616 -281.869896)
					)
					(arc
						(start 386.182616 -281.869896)
						(mid 386.206266 -281.98529)
						(end 386.273548 -282.081986)
					)
					(arc
						(start 386.273548 -282.081986)
						(mid 386.290776 -282.094555)
						(end 386.311648 -282.099004)
					)
					(arc
						(start 386.311648 -282.099004)
						(mid 386.347569 -282.084125)
						(end 386.362448 -282.048204)
					)
					(arc
						(start 386.362448 -282.048204)
						(mid 386.360309 -282.033618)
						(end 386.354066 -282.020264)
					)
					(xy 386.339334 -282.005786) (xy 386.33908 -282.005278)
					(arc
						(start 386.338318 -282.00477)
						(mid 386.297426 -281.942776)
						(end 386.2832 -281.869896)
					)
					(arc
						(start 386.2832 -281.869896)
						(mid 386.339294 -281.734474)
						(end 386.474716 -281.67838)
					)
					(arc
						(start 386.474716 -281.67838)
						(mid 386.548298 -281.693164)
						(end 386.610606 -281.735022)
					)
					(xy 386.61086 -281.735784)
					(arc
						(start 386.625338 -281.750262)
						(mid 386.638821 -281.756504)
						(end 386.653532 -281.758644)
					)
				)
			)
		)
		(zone
			(layer "F.Cu")
			(hatch none 0.5)
			(connect_pads
				(clearance 0)
			)
			(min_thickness 0.25)
			(keepout
				(tracks not_allowed)
				(vias allowed)
				(pads allowed)
				(copperpour not_allowed)
				(footprints allowed)
			)
			(placement
				(enabled no)
				(sheetname "")
			)
			(fill
				(thermal_gap 0.5)
				(thermal_bridge_width 0.5)
				(island_removal_mode 0)
			)
			(polygon
				(pts
					(arc
						(start 386.723128 -221.491048)
						(mid 386.708249 -221.455127)
						(end 386.672328 -221.440248)
					)
					(arc
						(start 386.672328 -221.440248)
						(mid 386.652171 -221.444308)
						(end 386.635244 -221.455996)
					)
					(arc
						(start 386.635244 -221.455996)
						(mid 386.566522 -221.553256)
						(end 386.54228 -221.669864)
					)
					(arc
						(start 386.54228 -221.669864)
						(mid 386.627834 -221.87641)
						(end 386.83438 -221.961964)
					)
					(arc
						(start 386.83438 -221.961964)
						(mid 386.949802 -221.938193)
						(end 387.04647 -221.870778)
					)
					(arc
						(start 387.04647 -221.870778)
						(mid 387.059039 -221.85355)
						(end 387.063488 -221.832678)
					)
					(arc
						(start 387.063488 -221.832678)
						(mid 387.048609 -221.796757)
						(end 387.012688 -221.781878)
					)
					(arc
						(start 387.012688 -221.781878)
						(mid 386.998102 -221.784017)
						(end 386.984748 -221.79026)
					)
					(xy 386.97027 -221.804992) (xy 386.969762 -221.805246)
					(arc
						(start 386.969254 -221.806008)
						(mid 386.907289 -221.847035)
						(end 386.83438 -221.86138)
					)
					(arc
						(start 386.83438 -221.86138)
						(mid 386.698958 -221.805286)
						(end 386.642864 -221.669864)
					)
					(arc
						(start 386.642864 -221.669864)
						(mid 386.65758 -221.596242)
						(end 386.699506 -221.533974)
					)
					(xy 386.700268 -221.533466)
					(arc
						(start 386.714746 -221.518988)
						(mid 386.720982 -221.505632)
						(end 386.723128 -221.491048)
					)
				)
			)
		)
		(zone
			(layer "F.Cu")
			(hatch none 0.5)
			(connect_pads
				(clearance 0)
			)
			(min_thickness 0.25)
			(keepout
				(tracks not_allowed)
				(vias allowed)
				(pads allowed)
				(copperpour not_allowed)
				(footprints allowed)
			)
			(placement
				(enabled no)
				(sheetname "")
			)
			(fill
				(thermal_gap 0.5)
				(thermal_bridge_width 0.5)
				(island_removal_mode 0)
			)
			(polygon
				(pts
					(arc
						(start 386.723128 -219.863162)
						(mid 386.708249 -219.827241)
						(end 386.672328 -219.812362)
					)
					(arc
						(start 386.672328 -219.812362)
						(mid 386.652144 -219.816544)
						(end 386.635244 -219.828364)
					)
					(arc
						(start 386.635244 -219.828364)
						(mid 386.566573 -219.925507)
						(end 386.54228 -220.041978)
					)
					(arc
						(start 386.54228 -220.041978)
						(mid 386.627834 -220.248524)
						(end 386.83438 -220.334078)
					)
					(arc
						(start 386.83438 -220.334078)
						(mid 386.949786 -220.310291)
						(end 387.04647 -220.242892)
					)
					(arc
						(start 387.04647 -220.242892)
						(mid 387.058988 -220.22578)
						(end 387.063488 -220.205046)
					)
					(arc
						(start 387.063488 -220.205046)
						(mid 387.048609 -220.169125)
						(end 387.012688 -220.154246)
					)
					(arc
						(start 387.012688 -220.154246)
						(mid 386.998102 -220.156385)
						(end 386.984748 -220.162628)
					)
					(xy 386.97027 -220.17736) (xy 386.969762 -220.177614)
					(arc
						(start 386.969254 -220.178376)
						(mid 386.90726 -220.219268)
						(end 386.83438 -220.233494)
					)
					(arc
						(start 386.83438 -220.233494)
						(mid 386.698958 -220.1774)
						(end 386.642864 -220.041978)
					)
					(arc
						(start 386.642864 -220.041978)
						(mid 386.657648 -219.968396)
						(end 386.699506 -219.906088)
					)
					(xy 386.700268 -219.905834)
					(arc
						(start 386.714746 -219.891356)
						(mid 386.720988 -219.877873)
						(end 386.723128 -219.863162)
					)
				)
			)
		)
		(zone
			(layer "F.Cu")
			(hatch none 0.5)
			(connect_pads
				(clearance 0)
			)
			(min_thickness 0.25)
			(keepout
				(tracks not_allowed)
				(vias allowed)
				(pads allowed)
				(copperpour not_allowed)
				(footprints allowed)
			)
			(placement
				(enabled no)
				(sheetname "")
			)
			(fill
				(thermal_gap 0.5)
				(thermal_bridge_width 0.5)
				(island_removal_mode 0)
			)
			(polygon
				(pts
					(arc
						(start 386.882132 -247.50903)
						(mid 386.896893 -247.473216)
						(end 386.882132 -247.437402)
					)
					(arc
						(start 386.882132 -247.437402)
						(mid 386.86501 -247.426051)
						(end 386.844794 -247.422416)
					)
					(arc
						(start 386.844794 -247.422416)
						(mid 386.727453 -247.44251)
						(end 386.627878 -247.50776)
					)
					(arc
						(start 386.627878 -247.50776)
						(mid 386.542342 -247.714262)
						(end 386.627878 -247.920764)
					)
					(arc
						(start 386.627878 -247.920764)
						(mid 386.72624 -247.985693)
						(end 386.842254 -248.006362)
					)
					(arc
						(start 386.842254 -248.006362)
						(mid 386.863303 -248.003051)
						(end 386.881116 -247.991376)
					)
					(arc
						(start 386.881116 -247.991376)
						(mid 386.895951 -247.955473)
						(end 386.881116 -247.919494)
					)
					(arc
						(start 386.881116 -247.919494)
						(mid 386.869295 -247.910752)
						(end 386.855462 -247.905778)
					)
					(xy 386.834888 -247.905778) (xy 386.83438 -247.905778)
					(arc
						(start 386.833364 -247.905778)
						(mid 386.760659 -247.89094)
						(end 386.698998 -247.849644)
					)
					(arc
						(start 386.698998 -247.849644)
						(mid 386.642921 -247.714262)
						(end 386.698998 -247.57888)
					)
					(arc
						(start 386.698998 -247.57888)
						(mid 386.761464 -247.537231)
						(end 386.835142 -247.522746)
					)
					(xy 386.835904 -247.523)
					(arc
						(start 386.856224 -247.523)
						(mid 386.870206 -247.517924)
						(end 386.882132 -247.50903)
					)
				)
			)
		)
		(zone
			(layer "F.Cu")
			(hatch none 0.5)
			(connect_pads
				(clearance 0)
			)
			(min_thickness 0.25)
			(keepout
				(tracks not_allowed)
				(vias allowed)
				(pads allowed)
				(copperpour not_allowed)
				(footprints allowed)
			)
			(placement
				(enabled no)
				(sheetname "")
			)
			(fill
				(thermal_gap 0.5)
				(thermal_bridge_width 0.5)
				(island_removal_mode 0)
			)
			(polygon
				(pts
					(arc
						(start 386.882132 -245.881398)
						(mid 386.896967 -245.845495)
						(end 386.882132 -245.809516)
					)
					(arc
						(start 386.882132 -245.809516)
						(mid 386.864979 -245.798305)
						(end 386.844794 -245.794784)
					)
					(arc
						(start 386.844794 -245.794784)
						(mid 386.727453 -245.814878)
						(end 386.627878 -245.880128)
					)
					(arc
						(start 386.627878 -245.880128)
						(mid 386.542342 -246.08663)
						(end 386.627878 -246.293132)
					)
					(arc
						(start 386.627878 -246.293132)
						(mid 386.726271 -246.357921)
						(end 386.842254 -246.378476)
					)
					(arc
						(start 386.842254 -246.378476)
						(mid 386.863263 -246.375276)
						(end 386.881116 -246.363744)
					)
					(arc
						(start 386.881116 -246.363744)
						(mid 386.895951 -246.327841)
						(end 386.881116 -246.291862)
					)
					(arc
						(start 386.881116 -246.291862)
						(mid 386.869295 -246.28312)
						(end 386.855462 -246.278146)
					)
					(xy 386.834888 -246.278146) (xy 386.83438 -246.278146)
					(arc
						(start 386.833364 -246.278146)
						(mid 386.760659 -246.263308)
						(end 386.698998 -246.222012)
					)
					(arc
						(start 386.698998 -246.222012)
						(mid 386.642921 -246.08663)
						(end 386.698998 -245.951248)
					)
					(arc
						(start 386.698998 -245.951248)
						(mid 386.761464 -245.909599)
						(end 386.835142 -245.895114)
					)
					(xy 386.835904 -245.895368)
					(arc
						(start 386.856224 -245.895368)
						(mid 386.870206 -245.890292)
						(end 386.882132 -245.881398)
					)
				)
			)
		)
		(zone
			(layer "F.Cu")
			(hatch none 0.5)
			(connect_pads
				(clearance 0)
			)
			(min_thickness 0.25)
			(keepout
				(tracks not_allowed)
				(vias allowed)
				(pads allowed)
				(copperpour not_allowed)
				(footprints allowed)
			)
			(placement
				(enabled no)
				(sheetname "")
			)
			(fill
				(thermal_gap 0.5)
				(thermal_bridge_width 0.5)
				(island_removal_mode 0)
			)
			(polygon
				(pts
					(arc
						(start 386.882132 -244.253512)
						(mid 386.896893 -244.217698)
						(end 386.882132 -244.181884)
					)
					(arc
						(start 386.882132 -244.181884)
						(mid 386.86501 -244.170533)
						(end 386.844794 -244.166898)
					)
					(arc
						(start 386.844794 -244.166898)
						(mid 386.727453 -244.186992)
						(end 386.627878 -244.252242)
					)
					(arc
						(start 386.627878 -244.252242)
						(mid 386.542342 -244.458744)
						(end 386.627878 -244.665246)
					)
					(arc
						(start 386.627878 -244.665246)
						(mid 386.72624 -244.730175)
						(end 386.842254 -244.750844)
					)
					(arc
						(start 386.842254 -244.750844)
						(mid 386.863303 -244.747533)
						(end 386.881116 -244.735858)
					)
					(arc
						(start 386.881116 -244.735858)
						(mid 386.895951 -244.699955)
						(end 386.881116 -244.663976)
					)
					(arc
						(start 386.881116 -244.663976)
						(mid 386.869295 -244.655234)
						(end 386.855462 -244.65026)
					)
					(xy 386.834888 -244.65026) (xy 386.83438 -244.65026)
					(arc
						(start 386.833364 -244.65026)
						(mid 386.760659 -244.635422)
						(end 386.698998 -244.594126)
					)
					(arc
						(start 386.698998 -244.594126)
						(mid 386.642921 -244.458744)
						(end 386.698998 -244.323362)
					)
					(arc
						(start 386.698998 -244.323362)
						(mid 386.761449 -244.28163)
						(end 386.835142 -244.267228)
					)
					(xy 386.835904 -244.267482)
					(arc
						(start 386.856224 -244.267482)
						(mid 386.870206 -244.262406)
						(end 386.882132 -244.253512)
					)
				)
			)
		)
		(zone
			(layer "F.Cu")
			(hatch none 0.5)
			(connect_pads
				(clearance 0)
			)
			(min_thickness 0.25)
			(keepout
				(tracks not_allowed)
				(vias allowed)
				(pads allowed)
				(copperpour not_allowed)
				(footprints allowed)
			)
			(placement
				(enabled no)
				(sheetname "")
			)
			(fill
				(thermal_gap 0.5)
				(thermal_bridge_width 0.5)
				(island_removal_mode 0)
			)
			(polygon
				(pts
					(arc
						(start 386.882132 -242.62588)
						(mid 386.896967 -242.589977)
						(end 386.882132 -242.553998)
					)
					(arc
						(start 386.882132 -242.553998)
						(mid 386.86501 -242.542647)
						(end 386.844794 -242.539012)
					)
					(arc
						(start 386.844794 -242.539012)
						(mid 386.727453 -242.559106)
						(end 386.627878 -242.624356)
					)
					(arc
						(start 386.627878 -242.624356)
						(mid 386.542342 -242.830858)
						(end 386.627878 -243.03736)
					)
					(arc
						(start 386.627878 -243.03736)
						(mid 386.72624 -243.102289)
						(end 386.842254 -243.122958)
					)
					(arc
						(start 386.842254 -243.122958)
						(mid 386.863276 -243.11977)
						(end 386.881116 -243.108226)
					)
					(arc
						(start 386.881116 -243.108226)
						(mid 386.895951 -243.072323)
						(end 386.881116 -243.036344)
					)
					(arc
						(start 386.881116 -243.036344)
						(mid 386.869311 -243.027561)
						(end 386.855462 -243.022628)
					)
					(xy 386.834888 -243.022628) (xy 386.83438 -243.022628)
					(arc
						(start 386.833364 -243.022628)
						(mid 386.760659 -243.00779)
						(end 386.698998 -242.966494)
					)
					(arc
						(start 386.698998 -242.966494)
						(mid 386.642921 -242.831022)
						(end 386.698998 -242.695476)
					)
					(arc
						(start 386.698998 -242.695476)
						(mid 386.761493 -242.653965)
						(end 386.835142 -242.639596)
					)
					(xy 386.835904 -242.639596)
					(arc
						(start 386.856224 -242.639596)
						(mid 386.870185 -242.634639)
						(end 386.882132 -242.62588)
					)
				)
			)
		)
		(zone
			(layer "F.Cu")
			(hatch none 0.5)
			(connect_pads
				(clearance 0)
			)
			(min_thickness 0.25)
			(keepout
				(tracks not_allowed)
				(vias allowed)
				(pads allowed)
				(copperpour not_allowed)
				(footprints allowed)
			)
			(placement
				(enabled no)
				(sheetname "")
			)
			(fill
				(thermal_gap 0.5)
				(thermal_bridge_width 0.5)
				(island_removal_mode 0)
			)
			(polygon
				(pts
					(arc
						(start 386.882132 -240.997994)
						(mid 386.896967 -240.962091)
						(end 386.882132 -240.926112)
					)
					(arc
						(start 386.882132 -240.926112)
						(mid 386.864979 -240.914901)
						(end 386.844794 -240.91138)
					)
					(arc
						(start 386.844794 -240.91138)
						(mid 386.727453 -240.931474)
						(end 386.627878 -240.996724)
					)
					(arc
						(start 386.627878 -240.996724)
						(mid 386.542342 -241.203226)
						(end 386.627878 -241.409728)
					)
					(arc
						(start 386.627878 -241.409728)
						(mid 386.726271 -241.474517)
						(end 386.842254 -241.495072)
					)
					(arc
						(start 386.842254 -241.495072)
						(mid 386.863263 -241.491872)
						(end 386.881116 -241.48034)
					)
					(arc
						(start 386.881116 -241.48034)
						(mid 386.895951 -241.444437)
						(end 386.881116 -241.408458)
					)
					(arc
						(start 386.881116 -241.408458)
						(mid 386.869295 -241.399716)
						(end 386.855462 -241.394742)
					)
					(xy 386.834888 -241.394742) (xy 386.83438 -241.394742)
					(arc
						(start 386.833364 -241.394742)
						(mid 386.760659 -241.379904)
						(end 386.698998 -241.338608)
					)
					(arc
						(start 386.698998 -241.338608)
						(mid 386.642921 -241.203226)
						(end 386.698998 -241.067844)
					)
					(arc
						(start 386.698998 -241.067844)
						(mid 386.761464 -241.026195)
						(end 386.835142 -241.01171)
					)
					(xy 386.835904 -241.011964)
					(arc
						(start 386.856224 -241.011964)
						(mid 386.870206 -241.006888)
						(end 386.882132 -240.997994)
					)
				)
			)
		)
		(zone
			(layer "F.Cu")
			(hatch none 0.5)
			(connect_pads
				(clearance 0)
			)
			(min_thickness 0.25)
			(keepout
				(tracks not_allowed)
				(vias allowed)
				(pads allowed)
				(copperpour not_allowed)
				(footprints allowed)
			)
			(placement
				(enabled no)
				(sheetname "")
			)
			(fill
				(thermal_gap 0.5)
				(thermal_bridge_width 0.5)
				(island_removal_mode 0)
			)
			(polygon
				(pts
					(arc
						(start 386.882132 -239.370108)
						(mid 386.896893 -239.334294)
						(end 386.882132 -239.29848)
					)
					(arc
						(start 386.882132 -239.29848)
						(mid 386.86501 -239.287129)
						(end 386.844794 -239.283494)
					)
					(arc
						(start 386.844794 -239.283494)
						(mid 386.727453 -239.303588)
						(end 386.627878 -239.368838)
					)
					(arc
						(start 386.627878 -239.368838)
						(mid 386.542342 -239.57534)
						(end 386.627878 -239.781842)
					)
					(arc
						(start 386.627878 -239.781842)
						(mid 386.72624 -239.846771)
						(end 386.842254 -239.86744)
					)
					(arc
						(start 386.842254 -239.86744)
						(mid 386.863303 -239.864129)
						(end 386.881116 -239.852454)
					)
					(arc
						(start 386.881116 -239.852454)
						(mid 386.895951 -239.816551)
						(end 386.881116 -239.780572)
					)
					(arc
						(start 386.881116 -239.780572)
						(mid 386.869295 -239.77183)
						(end 386.855462 -239.766856)
					)
					(xy 386.834888 -239.766856) (xy 386.83438 -239.766856)
					(arc
						(start 386.833364 -239.766856)
						(mid 386.760659 -239.752018)
						(end 386.698998 -239.710722)
					)
					(arc
						(start 386.698998 -239.710722)
						(mid 386.642921 -239.57534)
						(end 386.698998 -239.439958)
					)
					(arc
						(start 386.698998 -239.439958)
						(mid 386.761449 -239.398226)
						(end 386.835142 -239.383824)
					)
					(xy 386.835904 -239.384078)
					(arc
						(start 386.856224 -239.384078)
						(mid 386.870206 -239.379002)
						(end 386.882132 -239.370108)
					)
				)
			)
		)
		(zone
			(layer "F.Cu")
			(hatch none 0.5)
			(connect_pads
				(clearance 0)
			)
			(min_thickness 0.25)
			(keepout
				(tracks not_allowed)
				(vias allowed)
				(pads allowed)
				(copperpour not_allowed)
				(footprints allowed)
			)
			(placement
				(enabled no)
				(sheetname "")
			)
			(fill
				(thermal_gap 0.5)
				(thermal_bridge_width 0.5)
				(island_removal_mode 0)
			)
			(polygon
				(pts
					(arc
						(start 386.882132 -237.742476)
						(mid 386.896967 -237.706573)
						(end 386.882132 -237.670594)
					)
					(arc
						(start 386.882132 -237.670594)
						(mid 386.86501 -237.659243)
						(end 386.844794 -237.655608)
					)
					(arc
						(start 386.844794 -237.655608)
						(mid 386.727426 -237.675823)
						(end 386.627878 -237.741206)
					)
					(arc
						(start 386.627878 -237.741206)
						(mid 386.542342 -237.947618)
						(end 386.627878 -238.153956)
					)
					(arc
						(start 386.627878 -238.153956)
						(mid 386.72624 -238.218885)
						(end 386.842254 -238.239554)
					)
					(arc
						(start 386.842254 -238.239554)
						(mid 386.863276 -238.236366)
						(end 386.881116 -238.224822)
					)
					(arc
						(start 386.881116 -238.224822)
						(mid 386.895951 -238.188919)
						(end 386.881116 -238.15294)
					)
					(arc
						(start 386.881116 -238.15294)
						(mid 386.869311 -238.144157)
						(end 386.855462 -238.139224)
					)
					(xy 386.834888 -238.139224) (xy 386.83438 -238.139224)
					(arc
						(start 386.833364 -238.139224)
						(mid 386.760659 -238.124386)
						(end 386.698998 -238.08309)
					)
					(arc
						(start 386.698998 -238.08309)
						(mid 386.642921 -237.947618)
						(end 386.698998 -237.812072)
					)
					(arc
						(start 386.698998 -237.812072)
						(mid 386.761493 -237.770561)
						(end 386.835142 -237.756192)
					)
					(xy 386.835904 -237.756192)
					(arc
						(start 386.856224 -237.756192)
						(mid 386.870168 -237.751216)
						(end 386.882132 -237.742476)
					)
				)
			)
		)
		(zone
			(layer "F.Cu")
			(hatch none 0.5)
			(connect_pads
				(clearance 0)
			)
			(min_thickness 0.25)
			(keepout
				(tracks not_allowed)
				(vias allowed)
				(pads allowed)
				(copperpour not_allowed)
				(footprints allowed)
			)
			(placement
				(enabled no)
				(sheetname "")
			)
			(fill
				(thermal_gap 0.5)
				(thermal_bridge_width 0.5)
				(island_removal_mode 0)
			)
			(polygon
				(pts
					(arc
						(start 386.882132 -236.11459)
						(mid 386.896893 -236.078776)
						(end 386.882132 -236.042962)
					)
					(arc
						(start 386.882132 -236.042962)
						(mid 386.86501 -236.031611)
						(end 386.844794 -236.027976)
					)
					(arc
						(start 386.844794 -236.027976)
						(mid 386.727453 -236.04807)
						(end 386.627878 -236.11332)
					)
					(arc
						(start 386.627878 -236.11332)
						(mid 386.542342 -236.319822)
						(end 386.627878 -236.526324)
					)
					(arc
						(start 386.627878 -236.526324)
						(mid 386.72624 -236.591253)
						(end 386.842254 -236.611922)
					)
					(arc
						(start 386.842254 -236.611922)
						(mid 386.863276 -236.608734)
						(end 386.881116 -236.59719)
					)
					(arc
						(start 386.881116 -236.59719)
						(mid 386.896131 -236.561122)
						(end 386.881116 -236.525054)
					)
					(arc
						(start 386.881116 -236.525054)
						(mid 386.869262 -236.516478)
						(end 386.855462 -236.511592)
					)
					(xy 386.834888 -236.511592) (xy 386.83438 -236.511592)
					(arc
						(start 386.833364 -236.511592)
						(mid 386.760629 -236.496638)
						(end 386.698998 -236.455204)
					)
					(arc
						(start 386.698998 -236.455204)
						(mid 386.642921 -236.319822)
						(end 386.698998 -236.18444)
					)
					(arc
						(start 386.698998 -236.18444)
						(mid 386.761449 -236.142708)
						(end 386.835142 -236.128306)
					)
					(xy 386.835904 -236.12856)
					(arc
						(start 386.856224 -236.12856)
						(mid 386.870206 -236.123484)
						(end 386.882132 -236.11459)
					)
				)
			)
		)
		(zone
			(layer "F.Cu")
			(hatch none 0.5)
			(connect_pads
				(clearance 0)
			)
			(min_thickness 0.25)
			(keepout
				(tracks not_allowed)
				(vias allowed)
				(pads allowed)
				(copperpour not_allowed)
				(footprints allowed)
			)
			(placement
				(enabled no)
				(sheetname "")
			)
			(fill
				(thermal_gap 0.5)
				(thermal_bridge_width 0.5)
				(island_removal_mode 0)
			)
			(polygon
				(pts
					(arc
						(start 386.882132 -234.486958)
						(mid 386.896967 -234.451055)
						(end 386.882132 -234.415076)
					)
					(arc
						(start 386.882132 -234.415076)
						(mid 386.86501 -234.403725)
						(end 386.844794 -234.40009)
					)
					(arc
						(start 386.844794 -234.40009)
						(mid 386.727426 -234.420305)
						(end 386.627878 -234.485688)
					)
					(arc
						(start 386.627878 -234.485688)
						(mid 386.542342 -234.69219)
						(end 386.627878 -234.898692)
					)
					(arc
						(start 386.627878 -234.898692)
						(mid 386.726271 -234.963481)
						(end 386.842254 -234.984036)
					)
					(arc
						(start 386.842254 -234.984036)
						(mid 386.863263 -234.980836)
						(end 386.881116 -234.969304)
					)
					(arc
						(start 386.881116 -234.969304)
						(mid 386.895951 -234.933401)
						(end 386.881116 -234.897422)
					)
					(arc
						(start 386.881116 -234.897422)
						(mid 386.869295 -234.88868)
						(end 386.855462 -234.883706)
					)
					(xy 386.834888 -234.883706) (xy 386.83438 -234.883706)
					(arc
						(start 386.833364 -234.883706)
						(mid 386.760659 -234.868868)
						(end 386.698998 -234.827572)
					)
					(arc
						(start 386.698998 -234.827572)
						(mid 386.642921 -234.6921)
						(end 386.698998 -234.556554)
					)
					(arc
						(start 386.698998 -234.556554)
						(mid 386.761493 -234.515043)
						(end 386.835142 -234.500674)
					)
					(xy 386.835904 -234.500674)
					(arc
						(start 386.856224 -234.500674)
						(mid 386.870168 -234.495698)
						(end 386.882132 -234.486958)
					)
				)
			)
		)
		(zone
			(layer "F.Cu")
			(hatch none 0.5)
			(connect_pads
				(clearance 0)
			)
			(min_thickness 0.25)
			(keepout
				(tracks not_allowed)
				(vias allowed)
				(pads allowed)
				(copperpour not_allowed)
				(footprints allowed)
			)
			(placement
				(enabled no)
				(sheetname "")
			)
			(fill
				(thermal_gap 0.5)
				(thermal_bridge_width 0.5)
				(island_removal_mode 0)
			)
			(polygon
				(pts
					(arc
						(start 386.882132 -232.859072)
						(mid 386.896967 -232.823169)
						(end 386.882132 -232.78719)
					)
					(arc
						(start 386.882132 -232.78719)
						(mid 386.864979 -232.775979)
						(end 386.844794 -232.772458)
					)
					(arc
						(start 386.844794 -232.772458)
						(mid 386.727453 -232.792552)
						(end 386.627878 -232.857802)
					)
					(arc
						(start 386.627878 -232.857802)
						(mid 386.542342 -233.064304)
						(end 386.627878 -233.270806)
					)
					(arc
						(start 386.627878 -233.270806)
						(mid 386.72624 -233.335735)
						(end 386.842254 -233.356404)
					)
					(arc
						(start 386.842254 -233.356404)
						(mid 386.863303 -233.353093)
						(end 386.881116 -233.341418)
					)
					(arc
						(start 386.881116 -233.341418)
						(mid 386.895951 -233.305515)
						(end 386.881116 -233.269536)
					)
					(arc
						(start 386.881116 -233.269536)
						(mid 386.869295 -233.260794)
						(end 386.855462 -233.25582)
					)
					(xy 386.834888 -233.25582) (xy 386.83438 -233.25582)
					(arc
						(start 386.833364 -233.25582)
						(mid 386.760659 -233.240982)
						(end 386.698998 -233.199686)
					)
					(arc
						(start 386.698998 -233.199686)
						(mid 386.642921 -233.064304)
						(end 386.698998 -232.928922)
					)
					(arc
						(start 386.698998 -232.928922)
						(mid 386.761464 -232.887273)
						(end 386.835142 -232.872788)
					)
					(xy 386.835904 -232.873042)
					(arc
						(start 386.856224 -232.873042)
						(mid 386.870206 -232.867966)
						(end 386.882132 -232.859072)
					)
				)
			)
		)
		(zone
			(layer "F.Cu")
			(hatch none 0.5)
			(connect_pads
				(clearance 0)
			)
			(min_thickness 0.25)
			(keepout
				(tracks not_allowed)
				(vias allowed)
				(pads allowed)
				(copperpour not_allowed)
				(footprints allowed)
			)
			(placement
				(enabled no)
				(sheetname "")
			)
			(fill
				(thermal_gap 0.5)
				(thermal_bridge_width 0.5)
				(island_removal_mode 0)
			)
			(polygon
				(pts
					(arc
						(start 386.882132 -231.231186)
						(mid 386.896893 -231.195372)
						(end 386.882132 -231.159558)
					)
					(arc
						(start 386.882132 -231.159558)
						(mid 386.86501 -231.148207)
						(end 386.844794 -231.144572)
					)
					(arc
						(start 386.844794 -231.144572)
						(mid 386.727453 -231.164666)
						(end 386.627878 -231.229916)
					)
					(arc
						(start 386.627878 -231.229916)
						(mid 386.542342 -231.436418)
						(end 386.627878 -231.64292)
					)
					(arc
						(start 386.627878 -231.64292)
						(mid 386.72624 -231.707849)
						(end 386.842254 -231.728518)
					)
					(arc
						(start 386.842254 -231.728518)
						(mid 386.863276 -231.72533)
						(end 386.881116 -231.713786)
					)
					(arc
						(start 386.881116 -231.713786)
						(mid 386.895951 -231.677883)
						(end 386.881116 -231.641904)
					)
					(arc
						(start 386.881116 -231.641904)
						(mid 386.869311 -231.633121)
						(end 386.855462 -231.628188)
					)
					(xy 386.834888 -231.628188) (xy 386.83438 -231.628188)
					(arc
						(start 386.833364 -231.628188)
						(mid 386.760629 -231.613234)
						(end 386.698998 -231.5718)
					)
					(arc
						(start 386.698998 -231.5718)
						(mid 386.642921 -231.436418)
						(end 386.698998 -231.301036)
					)
					(arc
						(start 386.698998 -231.301036)
						(mid 386.761463 -231.259358)
						(end 386.835142 -231.244902)
					)
					(xy 386.835904 -231.245156)
					(arc
						(start 386.856224 -231.245156)
						(mid 386.870206 -231.24008)
						(end 386.882132 -231.231186)
					)
				)
			)
		)
		(zone
			(layer "F.Cu")
			(hatch none 0.5)
			(connect_pads
				(clearance 0)
			)
			(min_thickness 0.25)
			(keepout
				(tracks not_allowed)
				(vias allowed)
				(pads allowed)
				(copperpour not_allowed)
				(footprints allowed)
			)
			(placement
				(enabled no)
				(sheetname "")
			)
			(fill
				(thermal_gap 0.5)
				(thermal_bridge_width 0.5)
				(island_removal_mode 0)
			)
			(polygon
				(pts
					(arc
						(start 386.882132 -229.603554)
						(mid 386.896967 -229.567651)
						(end 386.882132 -229.531672)
					)
					(arc
						(start 386.882132 -229.531672)
						(mid 386.86501 -229.520321)
						(end 386.844794 -229.516686)
					)
					(arc
						(start 386.844794 -229.516686)
						(mid 386.727426 -229.536901)
						(end 386.627878 -229.602284)
					)
					(arc
						(start 386.627878 -229.602284)
						(mid 386.542342 -229.808786)
						(end 386.627878 -230.015288)
					)
					(arc
						(start 386.627878 -230.015288)
						(mid 386.726271 -230.080077)
						(end 386.842254 -230.100632)
					)
					(arc
						(start 386.842254 -230.100632)
						(mid 386.863263 -230.097432)
						(end 386.881116 -230.0859)
					)
					(arc
						(start 386.881116 -230.0859)
						(mid 386.895951 -230.049997)
						(end 386.881116 -230.014018)
					)
					(arc
						(start 386.881116 -230.014018)
						(mid 386.869295 -230.005276)
						(end 386.855462 -230.000302)
					)
					(xy 386.834888 -230.000302) (xy 386.83438 -230.000302)
					(arc
						(start 386.833364 -230.000302)
						(mid 386.760659 -229.985464)
						(end 386.698998 -229.944168)
					)
					(arc
						(start 386.698998 -229.944168)
						(mid 386.642921 -229.808786)
						(end 386.698998 -229.673404)
					)
					(arc
						(start 386.698998 -229.673404)
						(mid 386.761464 -229.631755)
						(end 386.835142 -229.61727)
					)
					(xy 386.835904 -229.61727)
					(arc
						(start 386.856224 -229.61727)
						(mid 386.870168 -229.612294)
						(end 386.882132 -229.603554)
					)
				)
			)
		)
		(zone
			(layer "F.Cu")
			(hatch none 0.5)
			(connect_pads
				(clearance 0)
			)
			(min_thickness 0.25)
			(keepout
				(tracks not_allowed)
				(vias allowed)
				(pads allowed)
				(copperpour not_allowed)
				(footprints allowed)
			)
			(placement
				(enabled no)
				(sheetname "")
			)
			(fill
				(thermal_gap 0.5)
				(thermal_bridge_width 0.5)
				(island_removal_mode 0)
			)
			(polygon
				(pts
					(arc
						(start 386.882132 -227.975668)
						(mid 386.896893 -227.939854)
						(end 386.882132 -227.90404)
					)
					(arc
						(start 386.882132 -227.90404)
						(mid 386.86501 -227.892689)
						(end 386.844794 -227.889054)
					)
					(arc
						(start 386.844794 -227.889054)
						(mid 386.727453 -227.909148)
						(end 386.627878 -227.974398)
					)
					(arc
						(start 386.627878 -227.974398)
						(mid 386.542342 -228.1809)
						(end 386.627878 -228.387402)
					)
					(arc
						(start 386.627878 -228.387402)
						(mid 386.72624 -228.452331)
						(end 386.842254 -228.473)
					)
					(arc
						(start 386.842254 -228.473)
						(mid 386.863276 -228.469812)
						(end 386.881116 -228.458268)
					)
					(arc
						(start 386.881116 -228.458268)
						(mid 386.895951 -228.422365)
						(end 386.881116 -228.386386)
					)
					(arc
						(start 386.881116 -228.386386)
						(mid 386.869311 -228.377603)
						(end 386.855462 -228.37267)
					)
					(xy 386.834888 -228.37267) (xy 386.83438 -228.37267)
					(arc
						(start 386.833364 -228.37267)
						(mid 386.760629 -228.357716)
						(end 386.698998 -228.316282)
					)
					(arc
						(start 386.698998 -228.316282)
						(mid 386.642921 -228.1809)
						(end 386.698998 -228.045518)
					)
					(arc
						(start 386.698998 -228.045518)
						(mid 386.761463 -228.00384)
						(end 386.835142 -227.989384)
					)
					(xy 386.835904 -227.989638)
					(arc
						(start 386.856224 -227.989638)
						(mid 386.870206 -227.984562)
						(end 386.882132 -227.975668)
					)
				)
			)
		)
		(zone
			(layer "F.Cu")
			(hatch none 0.5)
			(connect_pads
				(clearance 0)
			)
			(min_thickness 0.25)
			(keepout
				(tracks not_allowed)
				(vias allowed)
				(pads allowed)
				(copperpour not_allowed)
				(footprints allowed)
			)
			(placement
				(enabled no)
				(sheetname "")
			)
			(fill
				(thermal_gap 0.5)
				(thermal_bridge_width 0.5)
				(island_removal_mode 0)
			)
			(polygon
				(pts
					(arc
						(start 386.882132 -226.348036)
						(mid 386.896967 -226.312133)
						(end 386.882132 -226.276154)
					)
					(arc
						(start 386.882132 -226.276154)
						(mid 386.86501 -226.264803)
						(end 386.844794 -226.261168)
					)
					(arc
						(start 386.844794 -226.261168)
						(mid 386.727426 -226.281383)
						(end 386.627878 -226.346766)
					)
					(arc
						(start 386.627878 -226.346766)
						(mid 386.542342 -226.553268)
						(end 386.627878 -226.75977)
					)
					(arc
						(start 386.627878 -226.75977)
						(mid 386.726271 -226.824559)
						(end 386.842254 -226.845114)
					)
					(arc
						(start 386.842254 -226.845114)
						(mid 386.863263 -226.841914)
						(end 386.881116 -226.830382)
					)
					(arc
						(start 386.881116 -226.830382)
						(mid 386.895951 -226.794479)
						(end 386.881116 -226.7585)
					)
					(arc
						(start 386.881116 -226.7585)
						(mid 386.869295 -226.749758)
						(end 386.855462 -226.744784)
					)
					(xy 386.834888 -226.744784) (xy 386.83438 -226.744784)
					(arc
						(start 386.833364 -226.744784)
						(mid 386.760659 -226.729946)
						(end 386.698998 -226.68865)
					)
					(arc
						(start 386.698998 -226.68865)
						(mid 386.642921 -226.553268)
						(end 386.698998 -226.417886)
					)
					(arc
						(start 386.698998 -226.417886)
						(mid 386.761464 -226.376237)
						(end 386.835142 -226.361752)
					)
					(xy 386.835904 -226.362006)
					(arc
						(start 386.856224 -226.362006)
						(mid 386.870206 -226.35693)
						(end 386.882132 -226.348036)
					)
				)
			)
		)
		(zone
			(layer "F.Cu")
			(hatch none 0.5)
			(connect_pads
				(clearance 0)
			)
			(min_thickness 0.25)
			(keepout
				(tracks not_allowed)
				(vias allowed)
				(pads allowed)
				(copperpour not_allowed)
				(footprints allowed)
			)
			(placement
				(enabled no)
				(sheetname "")
			)
			(fill
				(thermal_gap 0.5)
				(thermal_bridge_width 0.5)
				(island_removal_mode 0)
			)
			(polygon
				(pts
					(arc
						(start 386.882132 -224.72015)
						(mid 386.896967 -224.684247)
						(end 386.882132 -224.648268)
					)
					(arc
						(start 386.882132 -224.648268)
						(mid 386.864979 -224.637057)
						(end 386.844794 -224.633536)
					)
					(arc
						(start 386.844794 -224.633536)
						(mid 386.727453 -224.65363)
						(end 386.627878 -224.71888)
					)
					(arc
						(start 386.627878 -224.71888)
						(mid 386.542342 -224.925382)
						(end 386.627878 -225.131884)
					)
					(arc
						(start 386.627878 -225.131884)
						(mid 386.72624 -225.196813)
						(end 386.842254 -225.217482)
					)
					(arc
						(start 386.842254 -225.217482)
						(mid 386.863303 -225.214171)
						(end 386.881116 -225.202496)
					)
					(arc
						(start 386.881116 -225.202496)
						(mid 386.895951 -225.166593)
						(end 386.881116 -225.130614)
					)
					(arc
						(start 386.881116 -225.130614)
						(mid 386.869295 -225.121872)
						(end 386.855462 -225.116898)
					)
					(xy 386.834888 -225.116898) (xy 386.83438 -225.116898)
					(arc
						(start 386.833364 -225.116898)
						(mid 386.760659 -225.10206)
						(end 386.698998 -225.060764)
					)
					(arc
						(start 386.698998 -225.060764)
						(mid 386.642921 -224.925382)
						(end 386.698998 -224.79)
					)
					(arc
						(start 386.698998 -224.79)
						(mid 386.761464 -224.748351)
						(end 386.835142 -224.733866)
					)
					(xy 386.835904 -224.73412)
					(arc
						(start 386.856224 -224.73412)
						(mid 386.870206 -224.729044)
						(end 386.882132 -224.72015)
					)
				)
			)
		)
		(zone
			(layer "F.Cu")
			(hatch none 0.5)
			(connect_pads
				(clearance 0)
			)
			(min_thickness 0.25)
			(keepout
				(tracks not_allowed)
				(vias allowed)
				(pads allowed)
				(copperpour not_allowed)
				(footprints allowed)
			)
			(placement
				(enabled no)
				(sheetname "")
			)
			(fill
				(thermal_gap 0.5)
				(thermal_bridge_width 0.5)
				(island_removal_mode 0)
			)
			(polygon
				(pts
					(arc
						(start 386.882132 -223.092264)
						(mid 386.896893 -223.05645)
						(end 386.882132 -223.020636)
					)
					(arc
						(start 386.882132 -223.020636)
						(mid 386.86501 -223.009285)
						(end 386.844794 -223.00565)
					)
					(arc
						(start 386.844794 -223.00565)
						(mid 386.727453 -223.025744)
						(end 386.627878 -223.090994)
					)
					(arc
						(start 386.627878 -223.090994)
						(mid 386.542342 -223.297496)
						(end 386.627878 -223.503998)
					)
					(arc
						(start 386.627878 -223.503998)
						(mid 386.72624 -223.568927)
						(end 386.842254 -223.589596)
					)
					(arc
						(start 386.842254 -223.589596)
						(mid 386.863276 -223.586408)
						(end 386.881116 -223.574864)
					)
					(arc
						(start 386.881116 -223.574864)
						(mid 386.895951 -223.538961)
						(end 386.881116 -223.502982)
					)
					(arc
						(start 386.881116 -223.502982)
						(mid 386.869311 -223.494199)
						(end 386.855462 -223.489266)
					)
					(xy 386.834888 -223.489266) (xy 386.83438 -223.489266)
					(arc
						(start 386.833364 -223.489266)
						(mid 386.760629 -223.474312)
						(end 386.698998 -223.432878)
					)
					(arc
						(start 386.698998 -223.432878)
						(mid 386.642921 -223.297496)
						(end 386.698998 -223.162114)
					)
					(arc
						(start 386.698998 -223.162114)
						(mid 386.761463 -223.120436)
						(end 386.835142 -223.10598)
					)
					(xy 386.835904 -223.106234)
					(arc
						(start 386.856224 -223.106234)
						(mid 386.870206 -223.101158)
						(end 386.882132 -223.092264)
					)
				)
			)
		)
		(zone
			(layer "F.Cu")
			(hatch none 0.5)
			(connect_pads
				(clearance 0)
			)
			(min_thickness 0.25)
			(keepout
				(tracks not_allowed)
				(vias allowed)
				(pads allowed)
				(copperpour not_allowed)
				(footprints allowed)
			)
			(placement
				(enabled no)
				(sheetname "")
			)
			(fill
				(thermal_gap 0.5)
				(thermal_bridge_width 0.5)
				(island_removal_mode 0)
			)
			(polygon
				(pts
					(arc
						(start 386.992114 -264.573258)
						(mid 387.006949 -264.537355)
						(end 386.992114 -264.501376)
					)
					(arc
						(start 386.992114 -264.501376)
						(mid 386.974992 -264.490025)
						(end 386.954776 -264.48639)
					)
					(arc
						(start 386.954776 -264.48639)
						(mid 386.837408 -264.506605)
						(end 386.73786 -264.571988)
					)
					(arc
						(start 386.73786 -264.571988)
						(mid 386.652324 -264.77849)
						(end 386.73786 -264.984992)
					)
					(arc
						(start 386.73786 -264.984992)
						(mid 386.836253 -265.049781)
						(end 386.952236 -265.070336)
					)
					(arc
						(start 386.952236 -265.070336)
						(mid 386.973245 -265.067136)
						(end 386.991098 -265.055604)
					)
					(arc
						(start 386.991098 -265.055604)
						(mid 387.005933 -265.019701)
						(end 386.991098 -264.983722)
					)
					(arc
						(start 386.991098 -264.983722)
						(mid 386.979277 -264.97498)
						(end 386.965444 -264.970006)
					)
					(xy 386.94487 -264.970006) (xy 386.944362 -264.970006)
					(arc
						(start 386.943346 -264.970006)
						(mid 386.870641 -264.955168)
						(end 386.80898 -264.913872)
					)
					(arc
						(start 386.80898 -264.913872)
						(mid 386.752903 -264.7784)
						(end 386.80898 -264.642854)
					)
					(arc
						(start 386.80898 -264.642854)
						(mid 386.871475 -264.601343)
						(end 386.945124 -264.586974)
					)
					(xy 386.945886 -264.586974)
					(arc
						(start 386.96646 -264.586974)
						(mid 386.980284 -264.581983)
						(end 386.992114 -264.573258)
					)
				)
			)
		)
		(zone
			(layer "F.Cu")
			(hatch none 0.5)
			(connect_pads
				(clearance 0)
			)
			(min_thickness 0.25)
			(keepout
				(tracks not_allowed)
				(vias allowed)
				(pads allowed)
				(copperpour not_allowed)
				(footprints allowed)
			)
			(placement
				(enabled no)
				(sheetname "")
			)
			(fill
				(thermal_gap 0.5)
				(thermal_bridge_width 0.5)
				(island_removal_mode 0)
			)
			(polygon
				(pts
					(arc
						(start 386.992114 -262.945372)
						(mid 387.006949 -262.909469)
						(end 386.992114 -262.87349)
					)
					(arc
						(start 386.992114 -262.87349)
						(mid 386.974961 -262.862279)
						(end 386.954776 -262.858758)
					)
					(arc
						(start 386.954776 -262.858758)
						(mid 386.837435 -262.878852)
						(end 386.73786 -262.944102)
					)
					(arc
						(start 386.73786 -262.944102)
						(mid 386.652324 -263.150604)
						(end 386.73786 -263.357106)
					)
					(arc
						(start 386.73786 -263.357106)
						(mid 386.836222 -263.422035)
						(end 386.952236 -263.442704)
					)
					(arc
						(start 386.952236 -263.442704)
						(mid 386.973285 -263.439393)
						(end 386.991098 -263.427718)
					)
					(arc
						(start 386.991098 -263.427718)
						(mid 387.005933 -263.391815)
						(end 386.991098 -263.355836)
					)
					(arc
						(start 386.991098 -263.355836)
						(mid 386.979277 -263.347094)
						(end 386.965444 -263.34212)
					)
					(xy 386.94487 -263.34212) (xy 386.944362 -263.34212)
					(arc
						(start 386.943346 -263.34212)
						(mid 386.870641 -263.327282)
						(end 386.80898 -263.285986)
					)
					(arc
						(start 386.80898 -263.285986)
						(mid 386.752903 -263.150604)
						(end 386.80898 -263.015222)
					)
					(arc
						(start 386.80898 -263.015222)
						(mid 386.871446 -262.973573)
						(end 386.945124 -262.959088)
					)
					(xy 386.945886 -262.959342)
					(arc
						(start 386.96646 -262.959342)
						(mid 386.980322 -262.954252)
						(end 386.992114 -262.945372)
					)
				)
			)
		)
		(zone
			(layer "F.Cu")
			(hatch none 0.5)
			(connect_pads
				(clearance 0)
			)
			(min_thickness 0.25)
			(keepout
				(tracks not_allowed)
				(vias allowed)
				(pads allowed)
				(copperpour not_allowed)
				(footprints allowed)
			)
			(placement
				(enabled no)
				(sheetname "")
			)
			(fill
				(thermal_gap 0.5)
				(thermal_bridge_width 0.5)
				(island_removal_mode 0)
			)
			(polygon
				(pts
					(arc
						(start 386.992114 -261.317486)
						(mid 387.006875 -261.281672)
						(end 386.992114 -261.245858)
					)
					(arc
						(start 386.992114 -261.245858)
						(mid 386.974992 -261.234507)
						(end 386.954776 -261.230872)
					)
					(arc
						(start 386.954776 -261.230872)
						(mid 386.837435 -261.250966)
						(end 386.73786 -261.316216)
					)
					(arc
						(start 386.73786 -261.316216)
						(mid 386.652324 -261.522718)
						(end 386.73786 -261.72922)
					)
					(arc
						(start 386.73786 -261.72922)
						(mid 386.836222 -261.794149)
						(end 386.952236 -261.814818)
					)
					(arc
						(start 386.952236 -261.814818)
						(mid 386.973258 -261.81163)
						(end 386.991098 -261.800086)
					)
					(arc
						(start 386.991098 -261.800086)
						(mid 387.005933 -261.764183)
						(end 386.991098 -261.728204)
					)
					(arc
						(start 386.991098 -261.728204)
						(mid 386.979293 -261.719421)
						(end 386.965444 -261.714488)
					)
					(xy 386.94487 -261.714488) (xy 386.944362 -261.714488)
					(arc
						(start 386.943346 -261.714488)
						(mid 386.870611 -261.699534)
						(end 386.80898 -261.6581)
					)
					(arc
						(start 386.80898 -261.6581)
						(mid 386.752903 -261.522718)
						(end 386.80898 -261.387336)
					)
					(arc
						(start 386.80898 -261.387336)
						(mid 386.871445 -261.345658)
						(end 386.945124 -261.331202)
					)
					(xy 386.945886 -261.331456)
					(arc
						(start 386.96646 -261.331456)
						(mid 386.980322 -261.326366)
						(end 386.992114 -261.317486)
					)
				)
			)
		)
		(zone
			(layer "F.Cu")
			(hatch none 0.5)
			(connect_pads
				(clearance 0)
			)
			(min_thickness 0.25)
			(keepout
				(tracks not_allowed)
				(vias allowed)
				(pads allowed)
				(copperpour not_allowed)
				(footprints allowed)
			)
			(placement
				(enabled no)
				(sheetname "")
			)
			(fill
				(thermal_gap 0.5)
				(thermal_bridge_width 0.5)
				(island_removal_mode 0)
			)
			(polygon
				(pts
					(arc
						(start 386.992114 -259.689854)
						(mid 387.006949 -259.653951)
						(end 386.992114 -259.617972)
					)
					(arc
						(start 386.992114 -259.617972)
						(mid 386.974992 -259.606621)
						(end 386.954776 -259.602986)
					)
					(arc
						(start 386.954776 -259.602986)
						(mid 386.837408 -259.623201)
						(end 386.73786 -259.688584)
					)
					(arc
						(start 386.73786 -259.688584)
						(mid 386.652324 -259.895086)
						(end 386.73786 -260.101588)
					)
					(arc
						(start 386.73786 -260.101588)
						(mid 386.836253 -260.166377)
						(end 386.952236 -260.186932)
					)
					(arc
						(start 386.952236 -260.186932)
						(mid 386.973245 -260.183732)
						(end 386.991098 -260.1722)
					)
					(arc
						(start 386.991098 -260.1722)
						(mid 387.005933 -260.136297)
						(end 386.991098 -260.100318)
					)
					(arc
						(start 386.991098 -260.100318)
						(mid 386.979277 -260.091576)
						(end 386.965444 -260.086602)
					)
					(xy 386.94487 -260.086602) (xy 386.944362 -260.086602)
					(arc
						(start 386.943346 -260.086602)
						(mid 386.870641 -260.071764)
						(end 386.80898 -260.030468)
					)
					(arc
						(start 386.80898 -260.030468)
						(mid 386.752903 -259.895086)
						(end 386.80898 -259.759704)
					)
					(arc
						(start 386.80898 -259.759704)
						(mid 386.871446 -259.718055)
						(end 386.945124 -259.70357)
					)
					(xy 386.945886 -259.70357)
					(arc
						(start 386.96646 -259.70357)
						(mid 386.980284 -259.698579)
						(end 386.992114 -259.689854)
					)
				)
			)
		)
		(zone
			(layer "F.Cu")
			(hatch none 0.5)
			(connect_pads
				(clearance 0)
			)
			(min_thickness 0.25)
			(keepout
				(tracks not_allowed)
				(vias allowed)
				(pads allowed)
				(copperpour not_allowed)
				(footprints allowed)
			)
			(placement
				(enabled no)
				(sheetname "")
			)
			(fill
				(thermal_gap 0.5)
				(thermal_bridge_width 0.5)
				(island_removal_mode 0)
			)
			(polygon
				(pts
					(arc
						(start 386.992114 -258.061968)
						(mid 387.006949 -258.026065)
						(end 386.992114 -257.990086)
					)
					(arc
						(start 386.992114 -257.990086)
						(mid 386.974961 -257.978875)
						(end 386.954776 -257.975354)
					)
					(arc
						(start 386.954776 -257.975354)
						(mid 386.837435 -257.995448)
						(end 386.73786 -258.060698)
					)
					(arc
						(start 386.73786 -258.060698)
						(mid 386.652324 -258.2672)
						(end 386.73786 -258.473702)
					)
					(arc
						(start 386.73786 -258.473702)
						(mid 386.836222 -258.538631)
						(end 386.952236 -258.5593)
					)
					(arc
						(start 386.952236 -258.5593)
						(mid 386.973285 -258.555989)
						(end 386.991098 -258.544314)
					)
					(arc
						(start 386.991098 -258.544314)
						(mid 387.005933 -258.508411)
						(end 386.991098 -258.472432)
					)
					(arc
						(start 386.991098 -258.472432)
						(mid 386.979277 -258.46369)
						(end 386.965444 -258.458716)
					)
					(xy 386.94487 -258.458716) (xy 386.944362 -258.458716)
					(arc
						(start 386.943346 -258.458716)
						(mid 386.870641 -258.443878)
						(end 386.80898 -258.402582)
					)
					(arc
						(start 386.80898 -258.402582)
						(mid 386.752903 -258.2672)
						(end 386.80898 -258.131818)
					)
					(arc
						(start 386.80898 -258.131818)
						(mid 386.871446 -258.090169)
						(end 386.945124 -258.075684)
					)
					(xy 386.945886 -258.075938)
					(arc
						(start 386.96646 -258.075938)
						(mid 386.980322 -258.070848)
						(end 386.992114 -258.061968)
					)
				)
			)
		)
		(zone
			(layer "F.Cu")
			(hatch none 0.5)
			(connect_pads
				(clearance 0)
			)
			(min_thickness 0.25)
			(keepout
				(tracks not_allowed)
				(vias allowed)
				(pads allowed)
				(copperpour not_allowed)
				(footprints allowed)
			)
			(placement
				(enabled no)
				(sheetname "")
			)
			(fill
				(thermal_gap 0.5)
				(thermal_bridge_width 0.5)
				(island_removal_mode 0)
			)
			(polygon
				(pts
					(arc
						(start 386.992114 -256.434082)
						(mid 387.006875 -256.398268)
						(end 386.992114 -256.362454)
					)
					(arc
						(start 386.992114 -256.362454)
						(mid 386.974992 -256.351103)
						(end 386.954776 -256.347468)
					)
					(arc
						(start 386.954776 -256.347468)
						(mid 386.837435 -256.367562)
						(end 386.73786 -256.432812)
					)
					(arc
						(start 386.73786 -256.432812)
						(mid 386.652324 -256.639314)
						(end 386.73786 -256.845816)
					)
					(arc
						(start 386.73786 -256.845816)
						(mid 386.836222 -256.910745)
						(end 386.952236 -256.931414)
					)
					(arc
						(start 386.952236 -256.931414)
						(mid 386.973258 -256.928226)
						(end 386.991098 -256.916682)
					)
					(arc
						(start 386.991098 -256.916682)
						(mid 387.005933 -256.880779)
						(end 386.991098 -256.8448)
					)
					(arc
						(start 386.991098 -256.8448)
						(mid 386.979293 -256.836017)
						(end 386.965444 -256.831084)
					)
					(xy 386.94487 -256.831084) (xy 386.944362 -256.831084)
					(arc
						(start 386.943346 -256.831084)
						(mid 386.870611 -256.81613)
						(end 386.80898 -256.774696)
					)
					(arc
						(start 386.80898 -256.774696)
						(mid 386.752903 -256.639314)
						(end 386.80898 -256.503932)
					)
					(arc
						(start 386.80898 -256.503932)
						(mid 386.871445 -256.462254)
						(end 386.945124 -256.447798)
					)
					(xy 386.945886 -256.448052)
					(arc
						(start 386.96646 -256.448052)
						(mid 386.980322 -256.442962)
						(end 386.992114 -256.434082)
					)
				)
			)
		)
		(zone
			(layer "F.Cu")
			(hatch none 0.5)
			(connect_pads
				(clearance 0)
			)
			(min_thickness 0.25)
			(keepout
				(tracks not_allowed)
				(vias allowed)
				(pads allowed)
				(copperpour not_allowed)
				(footprints allowed)
			)
			(placement
				(enabled no)
				(sheetname "")
			)
			(fill
				(thermal_gap 0.5)
				(thermal_bridge_width 0.5)
				(island_removal_mode 0)
			)
			(polygon
				(pts
					(arc
						(start 386.992114 -254.80645)
						(mid 387.006949 -254.770547)
						(end 386.992114 -254.734568)
					)
					(arc
						(start 386.992114 -254.734568)
						(mid 386.974992 -254.723217)
						(end 386.954776 -254.719582)
					)
					(arc
						(start 386.954776 -254.719582)
						(mid 386.837408 -254.739797)
						(end 386.73786 -254.80518)
					)
					(arc
						(start 386.73786 -254.80518)
						(mid 386.652324 -255.011682)
						(end 386.73786 -255.218184)
					)
					(arc
						(start 386.73786 -255.218184)
						(mid 386.836253 -255.282973)
						(end 386.952236 -255.303528)
					)
					(arc
						(start 386.952236 -255.303528)
						(mid 386.973245 -255.300328)
						(end 386.991098 -255.288796)
					)
					(arc
						(start 386.991098 -255.288796)
						(mid 387.005933 -255.252893)
						(end 386.991098 -255.216914)
					)
					(arc
						(start 386.991098 -255.216914)
						(mid 386.979277 -255.208172)
						(end 386.965444 -255.203198)
					)
					(xy 386.94487 -255.203198) (xy 386.944362 -255.203198)
					(arc
						(start 386.943346 -255.203198)
						(mid 386.870641 -255.18836)
						(end 386.80898 -255.147064)
					)
					(arc
						(start 386.80898 -255.147064)
						(mid 386.752903 -255.011682)
						(end 386.80898 -254.8763)
					)
					(arc
						(start 386.80898 -254.8763)
						(mid 386.871446 -254.834651)
						(end 386.945124 -254.820166)
					)
					(xy 386.945886 -254.820166)
					(arc
						(start 386.96646 -254.820166)
						(mid 386.980284 -254.815175)
						(end 386.992114 -254.80645)
					)
				)
			)
		)
	)
	(footprint ""
		(layer "F.Cu")
		(at 32.761428 -99.586034 180)
		(property "Reference" "C2176"
			(at 0 0 180)
			(layer "F.SilkS")
			(hide yes)
			(effects
				(font
					(size 1.27 1.27)
				)
			)
		)
		(property "Value" ""
			(at 0 0 180)
			(layer "F.Fab")
			(effects
				(font
					(size 1.27 1.27)
				)
			)
		)
		(duplicate_pad_numbers_are_jumpers no)
		(fp_line
			(start 0.7874 0.4064)
			(end -0.7874 0.4064)
			(stroke
				(width 0.1524)
				(type default)
			)
			(layer "F.SilkS")
		)
		(fp_line
			(start 0.7874 -0.4064)
			(end 0.7874 0.4064)
			(stroke
				(width 0.1524)
				(type default)
			)
			(layer "F.SilkS")
		)
		(fp_line
			(start -0.7874 0.4064)
			(end -0.7874 -0.4064)
			(stroke
				(width 0.1524)
				(type default)
			)
			(layer "F.SilkS")
		)
		(fp_line
			(start -0.7874 -0.4064)
			(end 0.7874 -0.4064)
			(stroke
				(width 0.1524)
				(type default)
			)
			(layer "F.SilkS")
		)
		(fp_line
			(start 0.67945 0.3048)
			(end 0.120396 0.3048)
			(stroke
				(width 0.1)
				(type default)
			)
			(layer "F.Fab")
		)
		(fp_line
			(start 0.67945 -0.3048)
			(end 0.67945 0.3048)
			(stroke
				(width 0.1)
				(type default)
			)
			(layer "F.Fab")
		)
		(fp_line
			(start 0.12065 -0.2794)
			(end 0.12065 -0.3048)
			(stroke
				(width 0.1)
				(type default)
			)
			(layer "F.Fab")
		)
		(fp_line
			(start 0.12065 -0.3048)
			(end 0.67945 -0.3048)
			(stroke
				(width 0.1)
				(type default)
			)
			(layer "F.Fab")
		)
		(fp_line
			(start 0.120396 0.3048)
			(end 0.120396 0.2794)
			(stroke
				(width 0.1)
				(type default)
			)
			(layer "F.Fab")
		)
		(fp_line
			(start 0.120396 0.2794)
			(end -0.12065 0.2794)
			(stroke
				(width 0.1)
				(type default)
			)
			(layer "F.Fab")
		)
		(fp_line
			(start -0.12065 0.3048)
			(end -0.67945 0.3048)
			(stroke
				(width 0.1)
				(type default)
			)
			(layer "F.Fab")
		)
		(fp_line
			(start -0.12065 0.2794)
			(end -0.12065 0.3048)
			(stroke
				(width 0.1)
				(type default)
			)
			(layer "F.Fab")
		)
		(fp_line
			(start -0.12065 -0.2794)
			(end 0.12065 -0.2794)
			(stroke
				(width 0.1)
				(type default)
			)
			(layer "F.Fab")
		)
		(fp_line
			(start -0.12065 -0.305054)
			(end -0.12065 -0.2794)
			(stroke
				(width 0.1)
				(type default)
			)
			(layer "F.Fab")
		)
		(fp_line
			(start -0.67945 0.3048)
			(end -0.67945 -0.305054)
			(stroke
				(width 0.1)
				(type default)
			)
			(layer "F.Fab")
		)
		(fp_line
			(start -0.67945 -0.305054)
			(end -0.12065 -0.305054)
			(stroke
				(width 0.1)
				(type default)
			)
			(layer "F.Fab")
		)
		(pad "1" smd circle
			(at -0.40005 0 180)
			(size 0 0)
			(layers "F.Cu" "F.Mask" "F.Paste")
			(net "P12V_OCP_SFF_ISENSE_MAM")
		)
		(pad "2" smd circle
			(at 0.40005 0 180)
			(size 0 0)
			(layers "F.Cu" "F.Mask" "F.Paste")
			(net "GND")
		)
	)
	(footprint ""
		(layer "F.Cu")
		(at 425.71416 -143.675608 90)
		(property "Reference" "PR4222"
			(at 0 0 90)
			(layer "F.SilkS")
			(hide yes)
			(effects
				(font
					(size 1.27 1.27)
				)
			)
		)
		(property "Value" ""
			(at 0 0 90)
			(layer "F.Fab")
			(effects
				(font
					(size 1.27 1.27)
				)
			)
		)
		(duplicate_pad_numbers_are_jumpers no)
		(fp_line
			(start 0.7874 -0.4064)
			(end 0.7874 0.4064)
			(stroke
				(width 0.1524)
				(type default)
			)
			(layer "F.SilkS")
		)
		(fp_line
			(start -0.7874 -0.4064)
			(end 0.7874 -0.4064)
			(stroke
				(width 0.1524)
				(type default)
			)
			(layer "F.SilkS")
		)
		(fp_line
			(start 0.7874 0.4064)
			(end -0.7874 0.4064)
			(stroke
				(width 0.1524)
				(type default)
			)
			(layer "F.SilkS")
		)
		(fp_line
			(start -0.7874 0.4064)
			(end -0.7874 -0.4064)
			(stroke
				(width 0.1524)
				(type default)
			)
			(layer "F.SilkS")
		)
		(fp_line
			(start -0.12065 -0.305054)
			(end -0.12065 -0.2794)
			(stroke
				(width 0.1)
				(type default)
			)
			(layer "F.Fab")
		)
		(fp_line
			(start -0.67945 -0.305054)
			(end -0.12065 -0.305054)
			(stroke
				(width 0.1)
				(type default)
			)
			(layer "F.Fab")
		)
		(fp_line
			(start 0.67945 -0.3048)
			(end 0.67945 0.3048)
			(stroke
				(width 0.1)
				(type default)
			)
			(layer "F.Fab")
		)
		(fp_line
			(start 0.12065 -0.3048)
			(end 0.67945 -0.3048)
			(stroke
				(width 0.1)
				(type default)
			)
			(layer "F.Fab")
		)
		(fp_line
			(start 0.12065 -0.2794)
			(end 0.12065 -0.3048)
			(stroke
				(width 0.1)
				(type default)
			)
			(layer "F.Fab")
		)
		(fp_line
			(start -0.12065 -0.2794)
			(end 0.12065 -0.2794)
			(stroke
				(width 0.1)
				(type default)
			)
			(layer "F.Fab")
		)
		(fp_line
			(start 0.120396 0.2794)
			(end -0.12065 0.2794)
			(stroke
				(width 0.1)
				(type default)
			)
			(layer "F.Fab")
		)
		(fp_line
			(start -0.12065 0.2794)
			(end -0.12065 0.3048)
			(stroke
				(width 0.1)
				(type default)
			)
			(layer "F.Fab")
		)
		(fp_line
			(start 0.67945 0.3048)
			(end 0.120396 0.3048)
			(stroke
				(width 0.1)
				(type default)
			)
			(layer "F.Fab")
		)
		(fp_line
			(start 0.120396 0.3048)
			(end 0.120396 0.2794)
			(stroke
				(width 0.1)
				(type default)
			)
			(layer "F.Fab")
		)
		(fp_line
			(start -0.12065 0.3048)
			(end -0.67945 0.3048)
			(stroke
				(width 0.1)
				(type default)
			)
			(layer "F.Fab")
		)
		(fp_line
			(start -0.67945 0.3048)
			(end -0.67945 -0.305054)
			(stroke
				(width 0.1)
				(type default)
			)
			(layer "F.Fab")
		)
		(pad "1" smd circle
			(at -0.40005 0 90)
			(size 0 0)
			(layers "F.Cu" "F.Mask" "F.Paste")
			(net "NC_PVCCINFAON_CPU0_ACSP4")
		)
		(pad "2" smd circle
			(at 0.40005 0 90)
			(size 0 0)
			(layers "F.Cu" "F.Mask" "F.Paste")
			(net "GND")
		)
	)
	(footprint ""
		(layer "F.Cu")
		(at 4.699 -50.891948 180)
		(property "Reference" "R579"
			(at 0 0 180)
			(layer "F.SilkS")
			(hide yes)
			(effects
				(font
					(size 1.27 1.27)
				)
			)
		)
		(property "Value" ""
			(at 0 0 180)
			(layer "F.Fab")
			(effects
				(font
					(size 1.27 1.27)
				)
			)
		)
		(duplicate_pad_numbers_are_jumpers no)
		(fp_line
			(start 0.7874 0.4064)
			(end -0.7874 0.4064)
			(stroke
				(width 0.1524)
				(type default)
			)
			(layer "F.SilkS")
		)
		(fp_line
			(start 0.7874 -0.4064)
			(end 0.7874 0.4064)
			(stroke
				(width 0.1524)
				(type default)
			)
			(layer "F.SilkS")
		)
		(fp_line
			(start -0.7874 0.4064)
			(end -0.7874 -0.4064)
			(stroke
				(width 0.1524)
				(type default)
			)
			(layer "F.SilkS")
		)
		(fp_line
			(start -0.7874 -0.4064)
			(end 0.7874 -0.4064)
			(stroke
				(width 0.1524)
				(type default)
			)
			(layer "F.SilkS")
		)
		(fp_line
			(start 0.67945 0.3048)
			(end 0.120396 0.3048)
			(stroke
				(width 0.1)
				(type default)
			)
			(layer "F.Fab")
		)
		(fp_line
			(start 0.67945 -0.3048)
			(end 0.67945 0.3048)
			(stroke
				(width 0.1)
				(type default)
			)
			(layer "F.Fab")
		)
		(fp_line
			(start 0.12065 -0.2794)
			(end 0.12065 -0.3048)
			(stroke
				(width 0.1)
				(type default)
			)
			(layer "F.Fab")
		)
		(fp_line
			(start 0.12065 -0.3048)
			(end 0.67945 -0.3048)
			(stroke
				(width 0.1)
				(type default)
			)
			(layer "F.Fab")
		)
		(fp_line
			(start 0.120396 0.3048)
			(end 0.120396 0.2794)
			(stroke
				(width 0.1)
				(type default)
			)
			(layer "F.Fab")
		)
		(fp_line
			(start 0.120396 0.2794)
			(end -0.12065 0.2794)
			(stroke
				(width 0.1)
				(type default)
			)
			(layer "F.Fab")
		)
		(fp_line
			(start -0.12065 0.3048)
			(end -0.67945 0.3048)
			(stroke
				(width 0.1)
				(type default)
			)
			(layer "F.Fab")
		)
		(fp_line
			(start -0.12065 0.2794)
			(end -0.12065 0.3048)
			(stroke
				(width 0.1)
				(type default)
			)
			(layer "F.Fab")
		)
		(fp_line
			(start -0.12065 -0.2794)
			(end 0.12065 -0.2794)
			(stroke
				(width 0.1)
				(type default)
			)
			(layer "F.Fab")
		)
		(fp_line
			(start -0.12065 -0.305054)
			(end -0.12065 -0.2794)
			(stroke
				(width 0.1)
				(type default)
			)
			(layer "F.Fab")
		)
		(fp_line
			(start -0.67945 0.3048)
			(end -0.67945 -0.305054)
			(stroke
				(width 0.1)
				(type default)
			)
			(layer "F.Fab")
		)
		(fp_line
			(start -0.67945 -0.305054)
			(end -0.12065 -0.305054)
			(stroke
				(width 0.1)
				(type default)
			)
			(layer "F.Fab")
		)
		(pad "1" smd circle
			(at -0.40005 0 180)
			(size 0 0)
			(layers "F.Cu" "F.Mask" "F.Paste")
			(net "SMB_HOST_3V3AUX_SCL_R5")
		)
		(pad "2" smd circle
			(at 0.40005 0 180)
			(size 0 0)
			(layers "F.Cu" "F.Mask" "F.Paste")
			(net "SMB_HOST_BMC_3V3AUX_SCL")
		)
	)
	(footprint ""
		(layer "F.Cu")
		(at 158.234634 -408.517344 -90)
		(property "Reference" "C1540"
			(at 0 0 270)
			(layer "F.SilkS")
			(hide yes)
			(effects
				(font
					(size 1.27 1.27)
				)
			)
		)
		(property "Value" ""
			(at 0 0 270)
			(layer "F.Fab")
			(effects
				(font
					(size 1.27 1.27)
				)
			)
		)
		(duplicate_pad_numbers_are_jumpers no)
		(fp_line
			(start -0.299974 0.150114)
			(end -0.299974 -0.150114)
			(stroke
				(width 0.1)
				(type default)
			)
			(layer "F.Fab")
		)
		(fp_line
			(start 0.299974 0.150114)
			(end -0.299974 0.150114)
			(stroke
				(width 0.1)
				(type default)
			)
			(layer "F.Fab")
		)
		(fp_line
			(start -0.299974 -0.150114)
			(end 0.299974 -0.150114)
			(stroke
				(width 0.1)
				(type default)
			)
			(layer "F.Fab")
		)
		(fp_line
			(start 0.299974 -0.150114)
			(end 0.299974 0.150114)
			(stroke
				(width 0.1)
				(type default)
			)
			(layer "F.Fab")
		)
		(pad "1" smd rect
			(at -0.2667 0 270)
			(size 0.3048 0.381)
			(layers "F.Cu" "F.Mask" "F.Paste")
			(net "P5E_CPU1_PE3_TX_C_DN<3>")
		)
		(pad "2" smd rect
			(at 0.2667 0 270)
			(size 0.3048 0.381)
			(layers "F.Cu" "F.Mask" "F.Paste")
			(net "P5E_CPU1_PE3_TX_DN<3>")
		)
	)
	(footprint ""
		(layer "F.Cu")
		(at 83.730592 -65.068958 -90)
		(property "Reference" "R3070"
			(at 0 0 270)
			(layer "F.SilkS")
			(hide yes)
			(effects
				(font
					(size 1.27 1.27)
				)
			)
		)
		(property "Value" ""
			(at 0 0 270)
			(layer "F.Fab")
			(effects
				(font
					(size 1.27 1.27)
				)
			)
		)
		(duplicate_pad_numbers_are_jumpers no)
		(fp_line
			(start -0.7874 0.4064)
			(end -0.7874 -0.4064)
			(stroke
				(width 0.1524)
				(type default)
			)
			(layer "F.SilkS")
		)
		(fp_line
			(start 0.7874 0.4064)
			(end -0.7874 0.4064)
			(stroke
				(width 0.1524)
				(type default)
			)
			(layer "F.SilkS")
		)
		(fp_line
			(start -0.7874 -0.4064)
			(end 0.7874 -0.4064)
			(stroke
				(width 0.1524)
				(type default)
			)
			(layer "F.SilkS")
		)
		(fp_line
			(start 0.7874 -0.4064)
			(end 0.7874 0.4064)
			(stroke
				(width 0.1524)
				(type default)
			)
			(layer "F.SilkS")
		)
		(fp_line
			(start -0.67945 0.3048)
			(end -0.67945 -0.305054)
			(stroke
				(width 0.1)
				(type default)
			)
			(layer "F.Fab")
		)
		(fp_line
			(start -0.12065 0.3048)
			(end -0.67945 0.3048)
			(stroke
				(width 0.1)
				(type default)
			)
			(layer "F.Fab")
		)
		(fp_line
			(start 0.120396 0.3048)
			(end 0.120396 0.2794)
			(stroke
				(width 0.1)
				(type default)
			)
			(layer "F.Fab")
		)
		(fp_line
			(start 0.67945 0.3048)
			(end 0.120396 0.3048)
			(stroke
				(width 0.1)
				(type default)
			)
			(layer "F.Fab")
		)
		(fp_line
			(start -0.12065 0.2794)
			(end -0.12065 0.3048)
			(stroke
				(width 0.1)
				(type default)
			)
			(layer "F.Fab")
		)
		(fp_line
			(start 0.120396 0.2794)
			(end -0.12065 0.2794)
			(stroke
				(width 0.1)
				(type default)
			)
			(layer "F.Fab")
		)
		(fp_line
			(start -0.12065 -0.2794)
			(end 0.12065 -0.2794)
			(stroke
				(width 0.1)
				(type default)
			)
			(layer "F.Fab")
		)
		(fp_line
			(start 0.12065 -0.2794)
			(end 0.12065 -0.3048)
			(stroke
				(width 0.1)
				(type default)
			)
			(layer "F.Fab")
		)
		(fp_line
			(start 0.12065 -0.3048)
			(end 0.67945 -0.3048)
			(stroke
				(width 0.1)
				(type default)
			)
			(layer "F.Fab")
		)
		(fp_line
			(start 0.67945 -0.3048)
			(end 0.67945 0.3048)
			(stroke
				(width 0.1)
				(type default)
			)
			(layer "F.Fab")
		)
		(fp_line
			(start -0.67945 -0.305054)
			(end -0.12065 -0.305054)
			(stroke
				(width 0.1)
				(type default)
			)
			(layer "F.Fab")
		)
		(fp_line
			(start -0.12065 -0.305054)
			(end -0.12065 -0.2794)
			(stroke
				(width 0.1)
				(type default)
			)
			(layer "F.Fab")
		)
		(pad "1" smd circle
			(at -0.40005 0 270)
			(size 0 0)
			(layers "F.Cu" "F.Mask" "F.Paste")
			(net "LED_RST_PLTRST_N")
		)
		(pad "2" smd circle
			(at 0.40005 0 270)
			(size 0 0)
			(layers "F.Cu" "F.Mask" "F.Paste")
			(net "P3V3_AUX")
		)
	)
	(footprint ""
		(layer "F.Cu")
		(at 364.50143 -260.364986 -90)
		(property "Reference" "C407"
			(at 0 0 270)
			(layer "F.SilkS")
			(hide yes)
			(effects
				(font
					(size 1.27 1.27)
				)
			)
		)
		(property "Value" ""
			(at 0 0 270)
			(layer "F.Fab")
			(effects
				(font
					(size 1.27 1.27)
				)
			)
		)
		(duplicate_pad_numbers_are_jumpers no)
		(fp_line
			(start -0.7874 0.4064)
			(end -0.7874 -0.4064)
			(stroke
				(width 0.1524)
				(type default)
			)
			(layer "F.SilkS")
		)
		(fp_line
			(start 0.7874 0.4064)
			(end -0.7874 0.4064)
			(stroke
				(width 0.1524)
				(type default)
			)
			(layer "F.SilkS")
		)
		(fp_line
			(start -0.7874 -0.4064)
			(end 0.7874 -0.4064)
			(stroke
				(width 0.1524)
				(type default)
			)
			(layer "F.SilkS")
		)
		(fp_line
			(start 0.7874 -0.4064)
			(end 0.7874 0.4064)
			(stroke
				(width 0.1524)
				(type default)
			)
			(layer "F.SilkS")
		)
		(fp_line
			(start -0.67945 0.3048)
			(end -0.67945 -0.305054)
			(stroke
				(width 0.1)
				(type default)
			)
			(layer "F.Fab")
		)
		(fp_line
			(start -0.12065 0.3048)
			(end -0.67945 0.3048)
			(stroke
				(width 0.1)
				(type default)
			)
			(layer "F.Fab")
		)
		(fp_line
			(start 0.120396 0.3048)
			(end 0.120396 0.2794)
			(stroke
				(width 0.1)
				(type default)
			)
			(layer "F.Fab")
		)
		(fp_line
			(start 0.67945 0.3048)
			(end 0.120396 0.3048)
			(stroke
				(width 0.1)
				(type default)
			)
			(layer "F.Fab")
		)
		(fp_line
			(start -0.12065 0.2794)
			(end -0.12065 0.3048)
			(stroke
				(width 0.1)
				(type default)
			)
			(layer "F.Fab")
		)
		(fp_line
			(start 0.120396 0.2794)
			(end -0.12065 0.2794)
			(stroke
				(width 0.1)
				(type default)
			)
			(layer "F.Fab")
		)
		(fp_line
			(start -0.12065 -0.2794)
			(end 0.12065 -0.2794)
			(stroke
				(width 0.1)
				(type default)
			)
			(layer "F.Fab")
		)
		(fp_line
			(start 0.12065 -0.2794)
			(end 0.12065 -0.3048)
			(stroke
				(width 0.1)
				(type default)
			)
			(layer "F.Fab")
		)
		(fp_line
			(start 0.12065 -0.3048)
			(end 0.67945 -0.3048)
			(stroke
				(width 0.1)
				(type default)
			)
			(layer "F.Fab")
		)
		(fp_line
			(start 0.67945 -0.3048)
			(end 0.67945 0.3048)
			(stroke
				(width 0.1)
				(type default)
			)
			(layer "F.Fab")
		)
		(fp_line
			(start -0.67945 -0.305054)
			(end -0.12065 -0.305054)
			(stroke
				(width 0.1)
				(type default)
			)
			(layer "F.Fab")
		)
		(fp_line
			(start -0.12065 -0.305054)
			(end -0.12065 -0.2794)
			(stroke
				(width 0.1)
				(type default)
			)
			(layer "F.Fab")
		)
		(pad "1" smd circle
			(at -0.40005 0 270)
			(size 0 0)
			(layers "F.Cu" "F.Mask" "F.Paste")
			(net "PVCCFA_EHV_FIVRA_CPU0")
		)
		(pad "2" smd circle
			(at 0.40005 0 270)
			(size 0 0)
			(layers "F.Cu" "F.Mask" "F.Paste")
			(net "GND")
		)
	)
	(footprint ""
		(layer "F.Cu")
		(at 206.45374 -131.669028 90)
		(property "Reference" "R2530"
			(at 0 0 90)
			(layer "F.SilkS")
			(hide yes)
			(effects
				(font
					(size 1.27 1.27)
				)
			)
		)
		(property "Value" ""
			(at 0 0 90)
			(layer "F.Fab")
			(effects
				(font
					(size 1.27 1.27)
				)
			)
		)
		(duplicate_pad_numbers_are_jumpers no)
		(fp_line
			(start 0.7874 -0.4064)
			(end 0.7874 0.4064)
			(stroke
				(width 0.1524)
				(type default)
			)
			(layer "F.SilkS")
		)
		(fp_line
			(start -0.7874 -0.4064)
			(end 0.7874 -0.4064)
			(stroke
				(width 0.1524)
				(type default)
			)
			(layer "F.SilkS")
		)
		(fp_line
			(start 0.7874 0.4064)
			(end -0.7874 0.4064)
			(stroke
				(width 0.1524)
				(type default)
			)
			(layer "F.SilkS")
		)
		(fp_line
			(start -0.7874 0.4064)
			(end -0.7874 -0.4064)
			(stroke
				(width 0.1524)
				(type default)
			)
			(layer "F.SilkS")
		)
		(fp_line
			(start -0.12065 -0.305054)
			(end -0.12065 -0.2794)
			(stroke
				(width 0.1)
				(type default)
			)
			(layer "F.Fab")
		)
		(fp_line
			(start -0.67945 -0.305054)
			(end -0.12065 -0.305054)
			(stroke
				(width 0.1)
				(type default)
			)
			(layer "F.Fab")
		)
		(fp_line
			(start 0.67945 -0.3048)
			(end 0.67945 0.3048)
			(stroke
				(width 0.1)
				(type default)
			)
			(layer "F.Fab")
		)
		(fp_line
			(start 0.12065 -0.3048)
			(end 0.67945 -0.3048)
			(stroke
				(width 0.1)
				(type default)
			)
			(layer "F.Fab")
		)
		(fp_line
			(start 0.12065 -0.2794)
			(end 0.12065 -0.3048)
			(stroke
				(width 0.1)
				(type default)
			)
			(layer "F.Fab")
		)
		(fp_line
			(start -0.12065 -0.2794)
			(end 0.12065 -0.2794)
			(stroke
				(width 0.1)
				(type default)
			)
			(layer "F.Fab")
		)
		(fp_line
			(start 0.120396 0.2794)
			(end -0.12065 0.2794)
			(stroke
				(width 0.1)
				(type default)
			)
			(layer "F.Fab")
		)
		(fp_line
			(start -0.12065 0.2794)
			(end -0.12065 0.3048)
			(stroke
				(width 0.1)
				(type default)
			)
			(layer "F.Fab")
		)
		(fp_line
			(start 0.67945 0.3048)
			(end 0.120396 0.3048)
			(stroke
				(width 0.1)
				(type default)
			)
			(layer "F.Fab")
		)
		(fp_line
			(start 0.120396 0.3048)
			(end 0.120396 0.2794)
			(stroke
				(width 0.1)
				(type default)
			)
			(layer "F.Fab")
		)
		(fp_line
			(start -0.12065 0.3048)
			(end -0.67945 0.3048)
			(stroke
				(width 0.1)
				(type default)
			)
			(layer "F.Fab")
		)
		(fp_line
			(start -0.67945 0.3048)
			(end -0.67945 -0.305054)
			(stroke
				(width 0.1)
				(type default)
			)
			(layer "F.Fab")
		)
		(pad "1" smd circle
			(at -0.40005 0 90)
			(size 0 0)
			(layers "F.Cu" "F.Mask" "F.Paste")
			(net "P12V_AUX")
		)
		(pad "2" smd circle
			(at 0.40005 0 90)
			(size 0 0)
			(layers "F.Cu" "F.Mask" "F.Paste")
			(net "P12V_AUX_BLEEDING")
		)
	)
	(footprint ""
		(layer "F.Cu")
		(at 362.991908 -338.17814 -90)
		(property "Reference" "PC279"
			(at 0 0 270)
			(layer "F.SilkS")
			(hide yes)
			(effects
				(font
					(size 1.27 1.27)
				)
			)
		)
		(property "Value" ""
			(at 0 0 270)
			(layer "F.Fab")
			(effects
				(font
					(size 1.27 1.27)
				)
			)
		)
		(duplicate_pad_numbers_are_jumpers no)
		(fp_line
			(start -0.7874 0.4064)
			(end -0.7874 -0.4064)
			(stroke
				(width 0.1524)
				(type default)
			)
			(layer "F.SilkS")
		)
		(fp_line
			(start 0.7874 0.4064)
			(end -0.7874 0.4064)
			(stroke
				(width 0.1524)
				(type default)
			)
			(layer "F.SilkS")
		)
		(fp_line
			(start -0.7874 -0.4064)
			(end 0.7874 -0.4064)
			(stroke
				(width 0.1524)
				(type default)
			)
			(layer "F.SilkS")
		)
		(fp_line
			(start 0.7874 -0.4064)
			(end 0.7874 0.4064)
			(stroke
				(width 0.1524)
				(type default)
			)
			(layer "F.SilkS")
		)
		(fp_line
			(start -0.67945 0.3048)
			(end -0.67945 -0.305054)
			(stroke
				(width 0.1)
				(type default)
			)
			(layer "F.Fab")
		)
		(fp_line
			(start -0.12065 0.3048)
			(end -0.67945 0.3048)
			(stroke
				(width 0.1)
				(type default)
			)
			(layer "F.Fab")
		)
		(fp_line
			(start 0.120396 0.3048)
			(end 0.120396 0.2794)
			(stroke
				(width 0.1)
				(type default)
			)
			(layer "F.Fab")
		)
		(fp_line
			(start 0.67945 0.3048)
			(end 0.120396 0.3048)
			(stroke
				(width 0.1)
				(type default)
			)
			(layer "F.Fab")
		)
		(fp_line
			(start -0.12065 0.2794)
			(end -0.12065 0.3048)
			(stroke
				(width 0.1)
				(type default)
			)
			(layer "F.Fab")
		)
		(fp_line
			(start 0.120396 0.2794)
			(end -0.12065 0.2794)
			(stroke
				(width 0.1)
				(type default)
			)
			(layer "F.Fab")
		)
		(fp_line
			(start -0.12065 -0.2794)
			(end 0.12065 -0.2794)
			(stroke
				(width 0.1)
				(type default)
			)
			(layer "F.Fab")
		)
		(fp_line
			(start 0.12065 -0.2794)
			(end 0.12065 -0.3048)
			(stroke
				(width 0.1)
				(type default)
			)
			(layer "F.Fab")
		)
		(fp_line
			(start 0.12065 -0.3048)
			(end 0.67945 -0.3048)
			(stroke
				(width 0.1)
				(type default)
			)
			(layer "F.Fab")
		)
		(fp_line
			(start 0.67945 -0.3048)
			(end 0.67945 0.3048)
			(stroke
				(width 0.1)
				(type default)
			)
			(layer "F.Fab")
		)
		(fp_line
			(start -0.67945 -0.305054)
			(end -0.12065 -0.305054)
			(stroke
				(width 0.1)
				(type default)
			)
			(layer "F.Fab")
		)
		(fp_line
			(start -0.12065 -0.305054)
			(end -0.12065 -0.2794)
			(stroke
				(width 0.1)
				(type default)
			)
			(layer "F.Fab")
		)
		(pad "1" smd circle
			(at -0.40005 0 270)
			(size 0 0)
			(layers "F.Cu" "F.Mask" "F.Paste")
			(net "SW_PVCCIN_CPU0_BOOT3_R")
		)
		(pad "2" smd circle
			(at 0.40005 0 270)
			(size 0 0)
			(layers "F.Cu" "F.Mask" "F.Paste")
			(net "SW_PVCCIN_CPU0_BOOTR3")
		)
	)
	(footprint ""
		(layer "F.Cu")
		(at 179.2224 -93.538548 90)
		(property "Reference" "R4591"
			(at 0 0 90)
			(layer "F.SilkS")
			(hide yes)
			(effects
				(font
					(size 1.27 1.27)
				)
			)
		)
		(property "Value" ""
			(at 0 0 90)
			(layer "F.Fab")
			(effects
				(font
					(size 1.27 1.27)
				)
			)
		)
		(duplicate_pad_numbers_are_jumpers no)
		(fp_line
			(start 0.7874 -0.4064)
			(end 0.7874 0.4064)
			(stroke
				(width 0.1524)
				(type default)
			)
			(layer "F.SilkS")
		)
		(fp_line
			(start -0.7874 -0.4064)
			(end 0.7874 -0.4064)
			(stroke
				(width 0.1524)
				(type default)
			)
			(layer "F.SilkS")
		)
		(fp_line
			(start 0.7874 0.4064)
			(end -0.7874 0.4064)
			(stroke
				(width 0.1524)
				(type default)
			)
			(layer "F.SilkS")
		)
		(fp_line
			(start -0.7874 0.4064)
			(end -0.7874 -0.4064)
			(stroke
				(width 0.1524)
				(type default)
			)
			(layer "F.SilkS")
		)
		(fp_line
			(start -0.12065 -0.305054)
			(end -0.12065 -0.2794)
			(stroke
				(width 0.1)
				(type default)
			)
			(layer "F.Fab")
		)
		(fp_line
			(start -0.67945 -0.305054)
			(end -0.12065 -0.305054)
			(stroke
				(width 0.1)
				(type default)
			)
			(layer "F.Fab")
		)
		(fp_line
			(start 0.67945 -0.3048)
			(end 0.67945 0.3048)
			(stroke
				(width 0.1)
				(type default)
			)
			(layer "F.Fab")
		)
		(fp_line
			(start 0.12065 -0.3048)
			(end 0.67945 -0.3048)
			(stroke
				(width 0.1)
				(type default)
			)
			(layer "F.Fab")
		)
		(fp_line
			(start 0.12065 -0.2794)
			(end 0.12065 -0.3048)
			(stroke
				(width 0.1)
				(type default)
			)
			(layer "F.Fab")
		)
		(fp_line
			(start -0.12065 -0.2794)
			(end 0.12065 -0.2794)
			(stroke
				(width 0.1)
				(type default)
			)
			(layer "F.Fab")
		)
		(fp_line
			(start 0.120396 0.2794)
			(end -0.12065 0.2794)
			(stroke
				(width 0.1)
				(type default)
			)
			(layer "F.Fab")
		)
		(fp_line
			(start -0.12065 0.2794)
			(end -0.12065 0.3048)
			(stroke
				(width 0.1)
				(type default)
			)
			(layer "F.Fab")
		)
		(fp_line
			(start 0.67945 0.3048)
			(end 0.120396 0.3048)
			(stroke
				(width 0.1)
				(type default)
			)
			(layer "F.Fab")
		)
		(fp_line
			(start 0.120396 0.3048)
			(end 0.120396 0.2794)
			(stroke
				(width 0.1)
				(type default)
			)
			(layer "F.Fab")
		)
		(fp_line
			(start -0.12065 0.3048)
			(end -0.67945 0.3048)
			(stroke
				(width 0.1)
				(type default)
			)
			(layer "F.Fab")
		)
		(fp_line
			(start -0.67945 0.3048)
			(end -0.67945 -0.305054)
			(stroke
				(width 0.1)
				(type default)
			)
			(layer "F.Fab")
		)
		(pad "1" smd rect
			(at -0.40005 0 270)
			(size 0.4572 0.508)
			(layers "F.Cu" "F.Mask" "F.Paste")
			(net "P3V3_AUX")
		)
		(pad "2" smd rect
			(at 0.40005 0 270)
			(size 0.4572 0.508)
			(layers "F.Cu" "F.Mask" "F.Paste")
			(net "FM_BOARD_BMC_SKU_ID3")
		)
	)
	(footprint ""
		(layer "F.Cu")
		(at 100.382832 -47.049944)
		(property "Reference" "H32"
			(at -1.7272 -4.511548 0)
			(unlocked yes)
			(layer "B.SilkS")
			(effects
				(font
					(size 0.7874 0.5842)
					(thickness 0.1524)
				)
				(justify left mirror)
			)
		)
		(property "Value" ""
			(at 0 0 0)
			(layer "F.Fab")
			(effects
				(font
					(size 1.27 1.27)
				)
			)
		)
		(duplicate_pad_numbers_are_jumpers no)
		(pad "1" thru_hole circle
			(at 0 0)
			(size 4.5212 4.5212)
			(drill 3.81)
			(layers "*.Cu" "*.Mask")
			(remove_unused_layers no)
			(net "GND")
			(clearance -0.1016)
			(padstack
				(mode front_inner_back)
				(layer "Inner"
					(shape circle)
					(size 5.6134 5.6134)
					(clearance -0.6477)
				)
				(layer "B.Cu"
					(shape circle)
					(size 8.001 8.001)
					(clearance -1.8415)
				)
			)
		)
	)
	(footprint ""
		(layer "F.Cu")
		(at 335.002124 -25.954482 -90)
		(property "Reference" "R1870"
			(at 0 0 270)
			(layer "F.SilkS")
			(hide yes)
			(effects
				(font
					(size 1.27 1.27)
				)
			)
		)
		(property "Value" ""
			(at 0 0 270)
			(layer "F.Fab")
			(effects
				(font
					(size 1.27 1.27)
				)
			)
		)
		(duplicate_pad_numbers_are_jumpers no)
		(fp_line
			(start -0.7874 0.4064)
			(end -0.7874 -0.4064)
			(stroke
				(width 0.1524)
				(type default)
			)
			(layer "F.SilkS")
		)
		(fp_line
			(start 0.7874 0.4064)
			(end -0.7874 0.4064)
			(stroke
				(width 0.1524)
				(type default)
			)
			(layer "F.SilkS")
		)
		(fp_line
			(start -0.7874 -0.4064)
			(end 0.7874 -0.4064)
			(stroke
				(width 0.1524)
				(type default)
			)
			(layer "F.SilkS")
		)
		(fp_line
			(start 0.7874 -0.4064)
			(end 0.7874 0.4064)
			(stroke
				(width 0.1524)
				(type default)
			)
			(layer "F.SilkS")
		)
		(fp_line
			(start -0.67945 0.3048)
			(end -0.67945 -0.305054)
			(stroke
				(width 0.1)
				(type default)
			)
			(layer "F.Fab")
		)
		(fp_line
			(start -0.12065 0.3048)
			(end -0.67945 0.3048)
			(stroke
				(width 0.1)
				(type default)
			)
			(layer "F.Fab")
		)
		(fp_line
			(start 0.120396 0.3048)
			(end 0.120396 0.2794)
			(stroke
				(width 0.1)
				(type default)
			)
			(layer "F.Fab")
		)
		(fp_line
			(start 0.67945 0.3048)
			(end 0.120396 0.3048)
			(stroke
				(width 0.1)
				(type default)
			)
			(layer "F.Fab")
		)
		(fp_line
			(start -0.12065 0.2794)
			(end -0.12065 0.3048)
			(stroke
				(width 0.1)
				(type default)
			)
			(layer "F.Fab")
		)
		(fp_line
			(start 0.120396 0.2794)
			(end -0.12065 0.2794)
			(stroke
				(width 0.1)
				(type default)
			)
			(layer "F.Fab")
		)
		(fp_line
			(start -0.12065 -0.2794)
			(end 0.12065 -0.2794)
			(stroke
				(width 0.1)
				(type default)
			)
			(layer "F.Fab")
		)
		(fp_line
			(start 0.12065 -0.2794)
			(end 0.12065 -0.3048)
			(stroke
				(width 0.1)
				(type default)
			)
			(layer "F.Fab")
		)
		(fp_line
			(start 0.12065 -0.3048)
			(end 0.67945 -0.3048)
			(stroke
				(width 0.1)
				(type default)
			)
			(layer "F.Fab")
		)
		(fp_line
			(start 0.67945 -0.3048)
			(end 0.67945 0.3048)
			(stroke
				(width 0.1)
				(type default)
			)
			(layer "F.Fab")
		)
		(fp_line
			(start -0.67945 -0.305054)
			(end -0.12065 -0.305054)
			(stroke
				(width 0.1)
				(type default)
			)
			(layer "F.Fab")
		)
		(fp_line
			(start -0.12065 -0.305054)
			(end -0.12065 -0.2794)
			(stroke
				(width 0.1)
				(type default)
			)
			(layer "F.Fab")
		)
		(pad "1" smd circle
			(at -0.40005 0 270)
			(size 0 0)
			(layers "F.Cu" "F.Mask" "F.Paste")
			(net "ESPI_LAD0_DATA_IO1")
		)
		(pad "2" smd circle
			(at 0.40005 0 270)
			(size 0 0)
			(layers "F.Cu" "F.Mask" "F.Paste")
			(net "ESPI_LPC_LAD0_IO1")
		)
	)
	(footprint ""
		(layer "F.Cu")
		(at 356.54488 -296.05478)
		(property "Reference" "C216"
			(at 0 0 0)
			(layer "F.SilkS")
			(hide yes)
			(effects
				(font
					(size 1.27 1.27)
				)
			)
		)
		(property "Value" ""
			(at 0 0 0)
			(layer "F.Fab")
			(effects
				(font
					(size 1.27 1.27)
				)
			)
		)
		(duplicate_pad_numbers_are_jumpers no)
		(fp_line
			(start -1.524 -0.762)
			(end 1.524 -0.762)
			(stroke
				(width 0.1524)
				(type default)
			)
			(layer "F.SilkS")
		)
		(fp_line
			(start -1.524 0.762)
			(end -1.524 -0.762)
			(stroke
				(width 0.1524)
				(type default)
			)
			(layer "F.SilkS")
		)
		(fp_line
			(start 1.524 -0.762)
			(end 1.524 0.762)
			(stroke
				(width 0.1524)
				(type default)
			)
			(layer "F.SilkS")
		)
		(fp_line
			(start 1.524 0.762)
			(end -1.524 0.762)
			(stroke
				(width 0.1524)
				(type default)
			)
			(layer "F.SilkS")
		)
		(fp_line
			(start -1.1049 -0.724916)
			(end -1.1049 0.724916)
			(stroke
				(width 0.1)
				(type default)
			)
			(layer "F.Fab")
		)
		(fp_line
			(start -1.1049 0.724916)
			(end 1.1049 0.724916)
			(stroke
				(width 0.1)
				(type default)
			)
			(layer "F.Fab")
		)
		(fp_line
			(start 1.1049 -0.724916)
			(end -1.1049 -0.724916)
			(stroke
				(width 0.1)
				(type default)
			)
			(layer "F.Fab")
		)
		(fp_line
			(start 1.1049 0.724916)
			(end 1.1049 -0.724916)
			(stroke
				(width 0.1)
				(type default)
			)
			(layer "F.Fab")
		)
		(pad "1" smd rect
			(at -0.889 0 180)
			(size 1.016 1.27)
			(layers "F.Cu" "F.Mask" "F.Paste")
			(net "PVCCIN_CPU0")
		)
		(pad "2" smd rect
			(at 0.889 0 180)
			(size 1.016 1.27)
			(layers "F.Cu" "F.Mask" "F.Paste")
			(net "GND")
		)
	)
	(footprint ""
		(layer "F.Cu")
		(at 24.892 -420.5732 180)
		(property "Reference" "R4741"
			(at 0 0 180)
			(layer "F.SilkS")
			(hide yes)
			(effects
				(font
					(size 1.27 1.27)
				)
			)
		)
		(property "Value" ""
			(at 0 0 180)
			(layer "F.Fab")
			(effects
				(font
					(size 1.27 1.27)
				)
			)
		)
		(duplicate_pad_numbers_are_jumpers no)
		(fp_line
			(start 0.7874 0.4064)
			(end -0.7874 0.4064)
			(stroke
				(width 0.1524)
				(type default)
			)
			(layer "F.SilkS")
		)
		(fp_line
			(start 0.7874 -0.4064)
			(end 0.7874 0.4064)
			(stroke
				(width 0.1524)
				(type default)
			)
			(layer "F.SilkS")
		)
		(fp_line
			(start -0.7874 0.4064)
			(end -0.7874 -0.4064)
			(stroke
				(width 0.1524)
				(type default)
			)
			(layer "F.SilkS")
		)
		(fp_line
			(start -0.7874 -0.4064)
			(end 0.7874 -0.4064)
			(stroke
				(width 0.1524)
				(type default)
			)
			(layer "F.SilkS")
		)
		(fp_line
			(start 0.67945 0.3048)
			(end 0.120396 0.3048)
			(stroke
				(width 0.1)
				(type default)
			)
			(layer "F.Fab")
		)
		(fp_line
			(start 0.67945 -0.3048)
			(end 0.67945 0.3048)
			(stroke
				(width 0.1)
				(type default)
			)
			(layer "F.Fab")
		)
		(fp_line
			(start 0.12065 -0.2794)
			(end 0.12065 -0.3048)
			(stroke
				(width 0.1)
				(type default)
			)
			(layer "F.Fab")
		)
		(fp_line
			(start 0.12065 -0.3048)
			(end 0.67945 -0.3048)
			(stroke
				(width 0.1)
				(type default)
			)
			(layer "F.Fab")
		)
		(fp_line
			(start 0.120396 0.3048)
			(end 0.120396 0.2794)
			(stroke
				(width 0.1)
				(type default)
			)
			(layer "F.Fab")
		)
		(fp_line
			(start 0.120396 0.2794)
			(end -0.12065 0.2794)
			(stroke
				(width 0.1)
				(type default)
			)
			(layer "F.Fab")
		)
		(fp_line
			(start -0.12065 0.3048)
			(end -0.67945 0.3048)
			(stroke
				(width 0.1)
				(type default)
			)
			(layer "F.Fab")
		)
		(fp_line
			(start -0.12065 0.2794)
			(end -0.12065 0.3048)
			(stroke
				(width 0.1)
				(type default)
			)
			(layer "F.Fab")
		)
		(fp_line
			(start -0.12065 -0.2794)
			(end 0.12065 -0.2794)
			(stroke
				(width 0.1)
				(type default)
			)
			(layer "F.Fab")
		)
		(fp_line
			(start -0.12065 -0.305054)
			(end -0.12065 -0.2794)
			(stroke
				(width 0.1)
				(type default)
			)
			(layer "F.Fab")
		)
		(fp_line
			(start -0.67945 0.3048)
			(end -0.67945 -0.305054)
			(stroke
				(width 0.1)
				(type default)
			)
			(layer "F.Fab")
		)
		(fp_line
			(start -0.67945 -0.305054)
			(end -0.12065 -0.305054)
			(stroke
				(width 0.1)
				(type default)
			)
			(layer "F.Fab")
		)
		(pad "1" smd circle
			(at -0.40005 0 180)
			(size 0 0)
			(layers "F.Cu" "F.Mask" "F.Paste")
			(net "PRSNT_CABLE_SWB_B1_ISO_N")
		)
		(pad "2" smd circle
			(at 0.40005 0 180)
			(size 0 0)
			(layers "F.Cu" "F.Mask" "F.Paste")
			(net "PRSNT_CABLE_SWB_B1_ISO_R_N")
		)
	)
	(footprint ""
		(layer "F.Cu")
		(at 328.913998 -190.74511 -90)
		(property "Reference" "R4263"
			(at 0 0 270)
			(layer "F.SilkS")
			(hide yes)
			(effects
				(font
					(size 1.27 1.27)
				)
			)
		)
		(property "Value" ""
			(at 0 0 270)
			(layer "F.Fab")
			(effects
				(font
					(size 1.27 1.27)
				)
			)
		)
		(duplicate_pad_numbers_are_jumpers no)
		(fp_line
			(start -0.7874 0.4064)
			(end -0.7874 -0.4064)
			(stroke
				(width 0.1524)
				(type default)
			)
			(layer "F.SilkS")
		)
		(fp_line
			(start 0.7874 0.4064)
			(end -0.7874 0.4064)
			(stroke
				(width 0.1524)
				(type default)
			)
			(layer "F.SilkS")
		)
		(fp_line
			(start -0.7874 -0.4064)
			(end 0.7874 -0.4064)
			(stroke
				(width 0.1524)
				(type default)
			)
			(layer "F.SilkS")
		)
		(fp_line
			(start 0.7874 -0.4064)
			(end 0.7874 0.4064)
			(stroke
				(width 0.1524)
				(type default)
			)
			(layer "F.SilkS")
		)
		(fp_line
			(start -0.67945 0.3048)
			(end -0.67945 -0.305054)
			(stroke
				(width 0.1)
				(type default)
			)
			(layer "F.Fab")
		)
		(fp_line
			(start -0.12065 0.3048)
			(end -0.67945 0.3048)
			(stroke
				(width 0.1)
				(type default)
			)
			(layer "F.Fab")
		)
		(fp_line
			(start 0.120396 0.3048)
			(end 0.120396 0.2794)
			(stroke
				(width 0.1)
				(type default)
			)
			(layer "F.Fab")
		)
		(fp_line
			(start 0.67945 0.3048)
			(end 0.120396 0.3048)
			(stroke
				(width 0.1)
				(type default)
			)
			(layer "F.Fab")
		)
		(fp_line
			(start -0.12065 0.2794)
			(end -0.12065 0.3048)
			(stroke
				(width 0.1)
				(type default)
			)
			(layer "F.Fab")
		)
		(fp_line
			(start 0.120396 0.2794)
			(end -0.12065 0.2794)
			(stroke
				(width 0.1)
				(type default)
			)
			(layer "F.Fab")
		)
		(fp_line
			(start -0.12065 -0.2794)
			(end 0.12065 -0.2794)
			(stroke
				(width 0.1)
				(type default)
			)
			(layer "F.Fab")
		)
		(fp_line
			(start 0.12065 -0.2794)
			(end 0.12065 -0.3048)
			(stroke
				(width 0.1)
				(type default)
			)
			(layer "F.Fab")
		)
		(fp_line
			(start 0.12065 -0.3048)
			(end 0.67945 -0.3048)
			(stroke
				(width 0.1)
				(type default)
			)
			(layer "F.Fab")
		)
		(fp_line
			(start 0.67945 -0.3048)
			(end 0.67945 0.3048)
			(stroke
				(width 0.1)
				(type default)
			)
			(layer "F.Fab")
		)
		(fp_line
			(start -0.67945 -0.305054)
			(end -0.12065 -0.305054)
			(stroke
				(width 0.1)
				(type default)
			)
			(layer "F.Fab")
		)
		(fp_line
			(start -0.12065 -0.305054)
			(end -0.12065 -0.2794)
			(stroke
				(width 0.1)
				(type default)
			)
			(layer "F.Fab")
		)
		(pad "1" smd circle
			(at -0.40005 0 270)
			(size 0 0)
			(layers "F.Cu" "F.Mask" "F.Paste")
			(net "PD_CPU0_BIST_ENABLE")
		)
		(pad "2" smd circle
			(at 0.40005 0 270)
			(size 0 0)
			(layers "F.Cu" "F.Mask" "F.Paste")
			(net "GND")
		)
	)
	(footprint ""
		(layer "F.Cu")
		(at 357.587042 -393.28725 180)
		(property "Reference" "R4161"
			(at 0 0 180)
			(layer "F.SilkS")
			(hide yes)
			(effects
				(font
					(size 1.27 1.27)
				)
			)
		)
		(property "Value" ""
			(at 0 0 180)
			(layer "F.Fab")
			(effects
				(font
					(size 1.27 1.27)
				)
			)
		)
		(duplicate_pad_numbers_are_jumpers no)
		(fp_line
			(start 0.7874 0.4064)
			(end -0.7874 0.4064)
			(stroke
				(width 0.1524)
				(type default)
			)
			(layer "F.SilkS")
		)
		(fp_line
			(start 0.7874 -0.4064)
			(end 0.7874 0.4064)
			(stroke
				(width 0.1524)
				(type default)
			)
			(layer "F.SilkS")
		)
		(fp_line
			(start -0.7874 0.4064)
			(end -0.7874 -0.4064)
			(stroke
				(width 0.1524)
				(type default)
			)
			(layer "F.SilkS")
		)
		(fp_line
			(start -0.7874 -0.4064)
			(end 0.7874 -0.4064)
			(stroke
				(width 0.1524)
				(type default)
			)
			(layer "F.SilkS")
		)
		(fp_line
			(start 0.67945 0.3048)
			(end 0.120396 0.3048)
			(stroke
				(width 0.1)
				(type default)
			)
			(layer "F.Fab")
		)
		(fp_line
			(start 0.67945 -0.3048)
			(end 0.67945 0.3048)
			(stroke
				(width 0.1)
				(type default)
			)
			(layer "F.Fab")
		)
		(fp_line
			(start 0.12065 -0.2794)
			(end 0.12065 -0.3048)
			(stroke
				(width 0.1)
				(type default)
			)
			(layer "F.Fab")
		)
		(fp_line
			(start 0.12065 -0.3048)
			(end 0.67945 -0.3048)
			(stroke
				(width 0.1)
				(type default)
			)
			(layer "F.Fab")
		)
		(fp_line
			(start 0.120396 0.3048)
			(end 0.120396 0.2794)
			(stroke
				(width 0.1)
				(type default)
			)
			(layer "F.Fab")
		)
		(fp_line
			(start 0.120396 0.2794)
			(end -0.12065 0.2794)
			(stroke
				(width 0.1)
				(type default)
			)
			(layer "F.Fab")
		)
		(fp_line
			(start -0.12065 0.3048)
			(end -0.67945 0.3048)
			(stroke
				(width 0.1)
				(type default)
			)
			(layer "F.Fab")
		)
		(fp_line
			(start -0.12065 0.2794)
			(end -0.12065 0.3048)
			(stroke
				(width 0.1)
				(type default)
			)
			(layer "F.Fab")
		)
		(fp_line
			(start -0.12065 -0.2794)
			(end 0.12065 -0.2794)
			(stroke
				(width 0.1)
				(type default)
			)
			(layer "F.Fab")
		)
		(fp_line
			(start -0.12065 -0.305054)
			(end -0.12065 -0.2794)
			(stroke
				(width 0.1)
				(type default)
			)
			(layer "F.Fab")
		)
		(fp_line
			(start -0.67945 0.3048)
			(end -0.67945 -0.305054)
			(stroke
				(width 0.1)
				(type default)
			)
			(layer "F.Fab")
		)
		(fp_line
			(start -0.67945 -0.305054)
			(end -0.12065 -0.305054)
			(stroke
				(width 0.1)
				(type default)
			)
			(layer "F.Fab")
		)
		(pad "1" smd circle
			(at -0.40005 0 180)
			(size 0 0)
			(layers "F.Cu" "F.Mask" "F.Paste")
			(net "GPU_3V3IO_RSVD4")
		)
		(pad "2" smd circle
			(at 0.40005 0 180)
			(size 0 0)
			(layers "F.Cu" "F.Mask" "F.Paste")
			(net "GND")
		)
	)
	(footprint ""
		(layer "F.Cu")
		(at 337.845908 -16.219678 -90)
		(property "Reference" "C605"
			(at 0 0 270)
			(layer "F.SilkS")
			(hide yes)
			(effects
				(font
					(size 1.27 1.27)
				)
			)
		)
		(property "Value" ""
			(at 0 0 270)
			(layer "F.Fab")
			(effects
				(font
					(size 1.27 1.27)
				)
			)
		)
		(duplicate_pad_numbers_are_jumpers no)
		(fp_line
			(start -0.7874 0.4064)
			(end -0.7874 -0.4064)
			(stroke
				(width 0.1524)
				(type default)
			)
			(layer "F.SilkS")
		)
		(fp_line
			(start 0.7874 0.4064)
			(end -0.7874 0.4064)
			(stroke
				(width 0.1524)
				(type default)
			)
			(layer "F.SilkS")
		)
		(fp_line
			(start -0.7874 -0.4064)
			(end 0.7874 -0.4064)
			(stroke
				(width 0.1524)
				(type default)
			)
			(layer "F.SilkS")
		)
		(fp_line
			(start 0.7874 -0.4064)
			(end 0.7874 0.4064)
			(stroke
				(width 0.1524)
				(type default)
			)
			(layer "F.SilkS")
		)
		(fp_line
			(start -0.67945 0.3048)
			(end -0.67945 -0.305054)
			(stroke
				(width 0.1)
				(type default)
			)
			(layer "F.Fab")
		)
		(fp_line
			(start -0.12065 0.3048)
			(end -0.67945 0.3048)
			(stroke
				(width 0.1)
				(type default)
			)
			(layer "F.Fab")
		)
		(fp_line
			(start 0.120396 0.3048)
			(end 0.120396 0.2794)
			(stroke
				(width 0.1)
				(type default)
			)
			(layer "F.Fab")
		)
		(fp_line
			(start 0.67945 0.3048)
			(end 0.120396 0.3048)
			(stroke
				(width 0.1)
				(type default)
			)
			(layer "F.Fab")
		)
		(fp_line
			(start -0.12065 0.2794)
			(end -0.12065 0.3048)
			(stroke
				(width 0.1)
				(type default)
			)
			(layer "F.Fab")
		)
		(fp_line
			(start 0.120396 0.2794)
			(end -0.12065 0.2794)
			(stroke
				(width 0.1)
				(type default)
			)
			(layer "F.Fab")
		)
		(fp_line
			(start -0.12065 -0.2794)
			(end 0.12065 -0.2794)
			(stroke
				(width 0.1)
				(type default)
			)
			(layer "F.Fab")
		)
		(fp_line
			(start 0.12065 -0.2794)
			(end 0.12065 -0.3048)
			(stroke
				(width 0.1)
				(type default)
			)
			(layer "F.Fab")
		)
		(fp_line
			(start 0.12065 -0.3048)
			(end 0.67945 -0.3048)
			(stroke
				(width 0.1)
				(type default)
			)
			(layer "F.Fab")
		)
		(fp_line
			(start 0.67945 -0.3048)
			(end 0.67945 0.3048)
			(stroke
				(width 0.1)
				(type default)
			)
			(layer "F.Fab")
		)
		(fp_line
			(start -0.67945 -0.305054)
			(end -0.12065 -0.305054)
			(stroke
				(width 0.1)
				(type default)
			)
			(layer "F.Fab")
		)
		(fp_line
			(start -0.12065 -0.305054)
			(end -0.12065 -0.2794)
			(stroke
				(width 0.1)
				(type default)
			)
			(layer "F.Fab")
		)
		(pad "1" smd circle
			(at -0.40005 0 270)
			(size 0 0)
			(layers "F.Cu" "F.Mask" "F.Paste")
			(net "PGPPA_AUX")
		)
		(pad "2" smd circle
			(at 0.40005 0 270)
			(size 0 0)
			(layers "F.Cu" "F.Mask" "F.Paste")
			(net "GND")
		)
	)
	(footprint ""
		(layer "F.Cu")
		(at 355.229414 -251.375418 90)
		(property "Reference" "C1026"
			(at 0 0 90)
			(layer "F.SilkS")
			(hide yes)
			(effects
				(font
					(size 1.27 1.27)
				)
			)
		)
		(property "Value" ""
			(at 0 0 90)
			(layer "F.Fab")
			(effects
				(font
					(size 1.27 1.27)
				)
			)
		)
		(duplicate_pad_numbers_are_jumpers no)
		(fp_line
			(start 0.7874 -0.4064)
			(end 0.7874 0.4064)
			(stroke
				(width 0.1524)
				(type default)
			)
			(layer "F.SilkS")
		)
		(fp_line
			(start -0.7874 -0.4064)
			(end 0.7874 -0.4064)
			(stroke
				(width 0.1524)
				(type default)
			)
			(layer "F.SilkS")
		)
		(fp_line
			(start 0.7874 0.4064)
			(end -0.7874 0.4064)
			(stroke
				(width 0.1524)
				(type default)
			)
			(layer "F.SilkS")
		)
		(fp_line
			(start -0.7874 0.4064)
			(end -0.7874 -0.4064)
			(stroke
				(width 0.1524)
				(type default)
			)
			(layer "F.SilkS")
		)
		(fp_line
			(start -0.12065 -0.305054)
			(end -0.12065 -0.2794)
			(stroke
				(width 0.1)
				(type default)
			)
			(layer "F.Fab")
		)
		(fp_line
			(start -0.67945 -0.305054)
			(end -0.12065 -0.305054)
			(stroke
				(width 0.1)
				(type default)
			)
			(layer "F.Fab")
		)
		(fp_line
			(start 0.67945 -0.3048)
			(end 0.67945 0.3048)
			(stroke
				(width 0.1)
				(type default)
			)
			(layer "F.Fab")
		)
		(fp_line
			(start 0.12065 -0.3048)
			(end 0.67945 -0.3048)
			(stroke
				(width 0.1)
				(type default)
			)
			(layer "F.Fab")
		)
		(fp_line
			(start 0.12065 -0.2794)
			(end 0.12065 -0.3048)
			(stroke
				(width 0.1)
				(type default)
			)
			(layer "F.Fab")
		)
		(fp_line
			(start -0.12065 -0.2794)
			(end 0.12065 -0.2794)
			(stroke
				(width 0.1)
				(type default)
			)
			(layer "F.Fab")
		)
		(fp_line
			(start 0.120396 0.2794)
			(end -0.12065 0.2794)
			(stroke
				(width 0.1)
				(type default)
			)
			(layer "F.Fab")
		)
		(fp_line
			(start -0.12065 0.2794)
			(end -0.12065 0.3048)
			(stroke
				(width 0.1)
				(type default)
			)
			(layer "F.Fab")
		)
		(fp_line
			(start 0.67945 0.3048)
			(end 0.120396 0.3048)
			(stroke
				(width 0.1)
				(type default)
			)
			(layer "F.Fab")
		)
		(fp_line
			(start 0.120396 0.3048)
			(end 0.120396 0.2794)
			(stroke
				(width 0.1)
				(type default)
			)
			(layer "F.Fab")
		)
		(fp_line
			(start -0.12065 0.3048)
			(end -0.67945 0.3048)
			(stroke
				(width 0.1)
				(type default)
			)
			(layer "F.Fab")
		)
		(fp_line
			(start -0.67945 0.3048)
			(end -0.67945 -0.305054)
			(stroke
				(width 0.1)
				(type default)
			)
			(layer "F.Fab")
		)
		(pad "1" smd circle
			(at -0.40005 0 90)
			(size 0 0)
			(layers "F.Cu" "F.Mask" "F.Paste")
			(net "PVCCIN_CPU0")
		)
		(pad "2" smd circle
			(at 0.40005 0 90)
			(size 0 0)
			(layers "F.Cu" "F.Mask" "F.Paste")
			(net "GND")
		)
	)
	(footprint ""
		(layer "F.Cu")
		(at 126.89078 -108.295948 -90)
		(property "Reference" "C2247"
			(at 0 0 270)
			(layer "F.SilkS")
			(hide yes)
			(effects
				(font
					(size 1.27 1.27)
				)
			)
		)
		(property "Value" ""
			(at 0 0 270)
			(layer "F.Fab")
			(effects
				(font
					(size 1.27 1.27)
				)
			)
		)
		(duplicate_pad_numbers_are_jumpers no)
		(fp_line
			(start -0.7874 0.4064)
			(end -0.7874 -0.4064)
			(stroke
				(width 0.1524)
				(type default)
			)
			(layer "F.SilkS")
		)
		(fp_line
			(start 0.7874 0.4064)
			(end -0.7874 0.4064)
			(stroke
				(width 0.1524)
				(type default)
			)
			(layer "F.SilkS")
		)
		(fp_line
			(start -0.7874 -0.4064)
			(end 0.7874 -0.4064)
			(stroke
				(width 0.1524)
				(type default)
			)
			(layer "F.SilkS")
		)
		(fp_line
			(start 0.7874 -0.4064)
			(end 0.7874 0.4064)
			(stroke
				(width 0.1524)
				(type default)
			)
			(layer "F.SilkS")
		)
		(fp_line
			(start -0.67945 0.3048)
			(end -0.67945 -0.305054)
			(stroke
				(width 0.1)
				(type default)
			)
			(layer "F.Fab")
		)
		(fp_line
			(start -0.12065 0.3048)
			(end -0.67945 0.3048)
			(stroke
				(width 0.1)
				(type default)
			)
			(layer "F.Fab")
		)
		(fp_line
			(start 0.120396 0.3048)
			(end 0.120396 0.2794)
			(stroke
				(width 0.1)
				(type default)
			)
			(layer "F.Fab")
		)
		(fp_line
			(start 0.67945 0.3048)
			(end 0.120396 0.3048)
			(stroke
				(width 0.1)
				(type default)
			)
			(layer "F.Fab")
		)
		(fp_line
			(start -0.12065 0.2794)
			(end -0.12065 0.3048)
			(stroke
				(width 0.1)
				(type default)
			)
			(layer "F.Fab")
		)
		(fp_line
			(start 0.120396 0.2794)
			(end -0.12065 0.2794)
			(stroke
				(width 0.1)
				(type default)
			)
			(layer "F.Fab")
		)
		(fp_line
			(start -0.12065 -0.2794)
			(end 0.12065 -0.2794)
			(stroke
				(width 0.1)
				(type default)
			)
			(layer "F.Fab")
		)
		(fp_line
			(start 0.12065 -0.2794)
			(end 0.12065 -0.3048)
			(stroke
				(width 0.1)
				(type default)
			)
			(layer "F.Fab")
		)
		(fp_line
			(start 0.12065 -0.3048)
			(end 0.67945 -0.3048)
			(stroke
				(width 0.1)
				(type default)
			)
			(layer "F.Fab")
		)
		(fp_line
			(start 0.67945 -0.3048)
			(end 0.67945 0.3048)
			(stroke
				(width 0.1)
				(type default)
			)
			(layer "F.Fab")
		)
		(fp_line
			(start -0.67945 -0.305054)
			(end -0.12065 -0.305054)
			(stroke
				(width 0.1)
				(type default)
			)
			(layer "F.Fab")
		)
		(fp_line
			(start -0.12065 -0.305054)
			(end -0.12065 -0.2794)
			(stroke
				(width 0.1)
				(type default)
			)
			(layer "F.Fab")
		)
		(pad "1" smd circle
			(at -0.40005 0 270)
			(size 0 0)
			(layers "F.Cu" "F.Mask" "F.Paste")
			(net "P3V3_AUX")
		)
		(pad "2" smd circle
			(at 0.40005 0 270)
			(size 0 0)
			(layers "F.Cu" "F.Mask" "F.Paste")
			(net "GND")
		)
	)
	(footprint ""
		(layer "F.Cu")
		(at 18.753582 -428.049436 90)
		(property "Reference" "R3442"
			(at 0 0 90)
			(layer "F.SilkS")
			(hide yes)
			(effects
				(font
					(size 1.27 1.27)
				)
			)
		)
		(property "Value" ""
			(at 0 0 90)
			(layer "F.Fab")
			(effects
				(font
					(size 1.27 1.27)
				)
			)
		)
		(duplicate_pad_numbers_are_jumpers no)
		(fp_line
			(start 0.7874 -0.4064)
			(end 0.7874 0.4064)
			(stroke
				(width 0.1524)
				(type default)
			)
			(layer "F.SilkS")
		)
		(fp_line
			(start -0.7874 -0.4064)
			(end 0.7874 -0.4064)
			(stroke
				(width 0.1524)
				(type default)
			)
			(layer "F.SilkS")
		)
		(fp_line
			(start 0.7874 0.4064)
			(end -0.7874 0.4064)
			(stroke
				(width 0.1524)
				(type default)
			)
			(layer "F.SilkS")
		)
		(fp_line
			(start -0.7874 0.4064)
			(end -0.7874 -0.4064)
			(stroke
				(width 0.1524)
				(type default)
			)
			(layer "F.SilkS")
		)
		(fp_line
			(start -0.12065 -0.305054)
			(end -0.12065 -0.2794)
			(stroke
				(width 0.1)
				(type default)
			)
			(layer "F.Fab")
		)
		(fp_line
			(start -0.67945 -0.305054)
			(end -0.12065 -0.305054)
			(stroke
				(width 0.1)
				(type default)
			)
			(layer "F.Fab")
		)
		(fp_line
			(start 0.67945 -0.3048)
			(end 0.67945 0.3048)
			(stroke
				(width 0.1)
				(type default)
			)
			(layer "F.Fab")
		)
		(fp_line
			(start 0.12065 -0.3048)
			(end 0.67945 -0.3048)
			(stroke
				(width 0.1)
				(type default)
			)
			(layer "F.Fab")
		)
		(fp_line
			(start 0.12065 -0.2794)
			(end 0.12065 -0.3048)
			(stroke
				(width 0.1)
				(type default)
			)
			(layer "F.Fab")
		)
		(fp_line
			(start -0.12065 -0.2794)
			(end 0.12065 -0.2794)
			(stroke
				(width 0.1)
				(type default)
			)
			(layer "F.Fab")
		)
		(fp_line
			(start 0.120396 0.2794)
			(end -0.12065 0.2794)
			(stroke
				(width 0.1)
				(type default)
			)
			(layer "F.Fab")
		)
		(fp_line
			(start -0.12065 0.2794)
			(end -0.12065 0.3048)
			(stroke
				(width 0.1)
				(type default)
			)
			(layer "F.Fab")
		)
		(fp_line
			(start 0.67945 0.3048)
			(end 0.120396 0.3048)
			(stroke
				(width 0.1)
				(type default)
			)
			(layer "F.Fab")
		)
		(fp_line
			(start 0.120396 0.3048)
			(end 0.120396 0.2794)
			(stroke
				(width 0.1)
				(type default)
			)
			(layer "F.Fab")
		)
		(fp_line
			(start -0.12065 0.3048)
			(end -0.67945 0.3048)
			(stroke
				(width 0.1)
				(type default)
			)
			(layer "F.Fab")
		)
		(fp_line
			(start -0.67945 0.3048)
			(end -0.67945 -0.305054)
			(stroke
				(width 0.1)
				(type default)
			)
			(layer "F.Fab")
		)
		(pad "1" smd circle
			(at -0.40005 0 90)
			(size 0 0)
			(layers "F.Cu" "F.Mask" "F.Paste")
			(net "GPU_PEX_STRAP0")
		)
		(pad "2" smd circle
			(at 0.40005 0 90)
			(size 0 0)
			(layers "F.Cu" "F.Mask" "F.Paste")
			(net "GND")
		)
	)
	(footprint ""
		(layer "F.Cu")
		(at 183.66486 -422.58742 90)
		(property "Reference" "U343"
			(at -2.11074 2.34569 90)
			(unlocked yes)
			(layer "F.SilkS")
			(effects
				(font
					(size 0.7874 0.5842)
					(thickness 0.1524)
				)
				(justify left)
			)
		)
		(property "Value" ""
			(at 0 0 90)
			(layer "F.Fab")
			(effects
				(font
					(size 1.27 1.27)
				)
			)
		)
		(duplicate_pad_numbers_are_jumpers no)
		(fp_line
			(start 1.868424 -1.519936)
			(end -1.868424 -1.519936)
			(stroke
				(width 0.1524)
				(type default)
			)
			(layer "F.SilkS")
		)
		(fp_line
			(start -1.868424 -1.519936)
			(end -1.868424 1.519936)
			(stroke
				(width 0.1524)
				(type default)
			)
			(layer "F.SilkS")
		)
		(fp_line
			(start 1.868424 1.519936)
			(end 1.868424 -1.519936)
			(stroke
				(width 0.1524)
				(type default)
			)
			(layer "F.SilkS")
		)
		(fp_line
			(start -1.868424 1.519936)
			(end 1.868424 1.519936)
			(stroke
				(width 0.1524)
				(type default)
			)
			(layer "F.SilkS")
		)
		(fp_line
			(start 0.700024 -1.519936)
			(end -0.700024 -1.519936)
			(stroke
				(width 0.1)
				(type default)
			)
			(layer "F.Fab")
		)
		(fp_line
			(start -0.700024 -1.519936)
			(end -0.700024 1.519936)
			(stroke
				(width 0.1)
				(type default)
			)
			(layer "F.Fab")
		)
		(fp_line
			(start 0.700024 1.519936)
			(end 0.700024 -1.519936)
			(stroke
				(width 0.1)
				(type default)
			)
			(layer "F.Fab")
		)
		(fp_line
			(start -0.700024 1.519936)
			(end 0.700024 1.519936)
			(stroke
				(width 0.1)
				(type default)
			)
			(layer "F.Fab")
		)
		(pad "1" smd rect
			(at -1.18491 -0.94996)
			(size 0.6096 1.0668)
			(layers "F.Cu" "F.Mask" "F.Paste")
			(net "OC_P2V5_COMP")
		)
		(pad "2" smd rect
			(at -1.18491 0.94996)
			(size 0.6096 1.0668)
			(layers "F.Cu" "F.Mask" "F.Paste")
			(net "GND")
		)
		(pad "3" smd rect
			(at 1.18491 0)
			(size 0.6096 1.0668)
			(layers "F.Cu" "F.Mask" "F.Paste")
			(net "Net_8629")
		)
	)
	(footprint ""
		(layer "F.Cu")
		(at 74.395076 -79.078836)
		(property "Reference" "D81"
			(at -38.71341 34.331402 90)
			(unlocked yes)
			(layer "F.SilkS")
			(effects
				(font
					(size 0.635 0.4064)
					(thickness 0.1524)
				)
				(justify left)
			)
		)
		(property "Value" ""
			(at 0 0 0)
			(layer "F.Fab")
			(effects
				(font
					(size 1.27 1.27)
				)
			)
		)
		(duplicate_pad_numbers_are_jumpers no)
		(fp_line
			(start -0.90678 0.4826)
			(end -0.90678 -0.4699)
			(stroke
				(width 0.1524)
				(type default)
			)
			(layer "F.SilkS")
		)
		(fp_line
			(start -0.89408 -0.4826)
			(end 0.90678 -0.4826)
			(stroke
				(width 0.1524)
				(type default)
			)
			(layer "F.SilkS")
		)
		(fp_line
			(start -0.79248 -0.4826)
			(end 1.03378 -0.4826)
			(stroke
				(width 0.1524)
				(type default)
			)
			(layer "F.SilkS")
		)
		(fp_line
			(start -0.64008 -0.4826)
			(end 1.16078 -0.4826)
			(stroke
				(width 0.1524)
				(type default)
			)
			(layer "F.SilkS")
		)
		(fp_line
			(start 0.90678 -0.4826)
			(end 0.90678 0.4826)
			(stroke
				(width 0.1524)
				(type default)
			)
			(layer "F.SilkS")
		)
		(fp_line
			(start 0.90678 0.4826)
			(end -0.90678 0.4826)
			(stroke
				(width 0.1524)
				(type default)
			)
			(layer "F.SilkS")
		)
		(fp_line
			(start 1.03378 -0.4826)
			(end 1.03378 0.4826)
			(stroke
				(width 0.1524)
				(type default)
			)
			(layer "F.SilkS")
		)
		(fp_line
			(start 1.03378 0.4826)
			(end -0.79248 0.4826)
			(stroke
				(width 0.1524)
				(type default)
			)
			(layer "F.SilkS")
		)
		(fp_line
			(start 1.16078 -0.4826)
			(end 1.16078 0.4826)
			(stroke
				(width 0.1524)
				(type default)
			)
			(layer "F.SilkS")
		)
		(fp_line
			(start 1.16078 0.4826)
			(end -0.64008 0.4826)
			(stroke
				(width 0.1524)
				(type default)
			)
			(layer "F.SilkS")
		)
		(fp_line
			(start -0.499872 -0.249936)
			(end 0.499872 -0.249936)
			(stroke
				(width 0.1)
				(type default)
			)
			(layer "F.Fab")
		)
		(fp_line
			(start -0.499872 0.249936)
			(end -0.499872 -0.249936)
			(stroke
				(width 0.1)
				(type default)
			)
			(layer "F.Fab")
		)
		(fp_line
			(start 0.499872 -0.249936)
			(end 0.499872 0.249936)
			(stroke
				(width 0.1)
				(type default)
			)
			(layer "F.Fab")
		)
		(fp_line
			(start 0.499872 0.249936)
			(end -0.499872 0.249936)
			(stroke
				(width 0.1)
				(type default)
			)
			(layer "F.Fab")
		)
		(pad "A" smd rect
			(at -0.47498 0)
			(size 0.6096 0.7112)
			(layers "F.Cu" "F.Mask" "F.Paste")
			(net "LED_PWRGD_PVPP_HBM_CPU1")
		)
		(pad "C" smd rect
			(at 0.47498 0)
			(size 0.6096 0.7112)
			(layers "F.Cu" "F.Mask" "F.Paste")
			(net "LED_PWRGD_PVPP_HBM_CPU1_D")
		)
	)
	(footprint ""
		(layer "F.Cu")
		(at 27.0383 -130.396996 180)
		(property "Reference" "PC475"
			(at 0 0 180)
			(layer "F.SilkS")
			(hide yes)
			(effects
				(font
					(size 1.27 1.27)
				)
			)
		)
		(property "Value" ""
			(at 0 0 180)
			(layer "F.Fab")
			(effects
				(font
					(size 1.27 1.27)
				)
			)
		)
		(duplicate_pad_numbers_are_jumpers no)
		(fp_line
			(start 0.7874 0.4064)
			(end -0.7874 0.4064)
			(stroke
				(width 0.1524)
				(type default)
			)
			(layer "F.SilkS")
		)
		(fp_line
			(start 0.7874 -0.4064)
			(end 0.7874 0.4064)
			(stroke
				(width 0.1524)
				(type default)
			)
			(layer "F.SilkS")
		)
		(fp_line
			(start -0.7874 0.4064)
			(end -0.7874 -0.4064)
			(stroke
				(width 0.1524)
				(type default)
			)
			(layer "F.SilkS")
		)
		(fp_line
			(start -0.7874 -0.4064)
			(end 0.7874 -0.4064)
			(stroke
				(width 0.1524)
				(type default)
			)
			(layer "F.SilkS")
		)
		(fp_line
			(start 0.67945 0.3048)
			(end 0.120396 0.3048)
			(stroke
				(width 0.1)
				(type default)
			)
			(layer "F.Fab")
		)
		(fp_line
			(start 0.67945 -0.3048)
			(end 0.67945 0.3048)
			(stroke
				(width 0.1)
				(type default)
			)
			(layer "F.Fab")
		)
		(fp_line
			(start 0.12065 -0.2794)
			(end 0.12065 -0.3048)
			(stroke
				(width 0.1)
				(type default)
			)
			(layer "F.Fab")
		)
		(fp_line
			(start 0.12065 -0.3048)
			(end 0.67945 -0.3048)
			(stroke
				(width 0.1)
				(type default)
			)
			(layer "F.Fab")
		)
		(fp_line
			(start 0.120396 0.3048)
			(end 0.120396 0.2794)
			(stroke
				(width 0.1)
				(type default)
			)
			(layer "F.Fab")
		)
		(fp_line
			(start 0.120396 0.2794)
			(end -0.12065 0.2794)
			(stroke
				(width 0.1)
				(type default)
			)
			(layer "F.Fab")
		)
		(fp_line
			(start -0.12065 0.3048)
			(end -0.67945 0.3048)
			(stroke
				(width 0.1)
				(type default)
			)
			(layer "F.Fab")
		)
		(fp_line
			(start -0.12065 0.2794)
			(end -0.12065 0.3048)
			(stroke
				(width 0.1)
				(type default)
			)
			(layer "F.Fab")
		)
		(fp_line
			(start -0.12065 -0.2794)
			(end 0.12065 -0.2794)
			(stroke
				(width 0.1)
				(type default)
			)
			(layer "F.Fab")
		)
		(fp_line
			(start -0.12065 -0.305054)
			(end -0.12065 -0.2794)
			(stroke
				(width 0.1)
				(type default)
			)
			(layer "F.Fab")
		)
		(fp_line
			(start -0.67945 0.3048)
			(end -0.67945 -0.305054)
			(stroke
				(width 0.1)
				(type default)
			)
			(layer "F.Fab")
		)
		(fp_line
			(start -0.67945 -0.305054)
			(end -0.12065 -0.305054)
			(stroke
				(width 0.1)
				(type default)
			)
			(layer "F.Fab")
		)
		(pad "1" smd circle
			(at -0.40005 0 180)
			(size 0 0)
			(layers "F.Cu" "F.Mask" "F.Paste")
			(net "PVCCINFAON_CPU1_ATSEN")
		)
		(pad "2" smd circle
			(at 0.40005 0 180)
			(size 0 0)
			(layers "F.Cu" "F.Mask" "F.Paste")
			(net "GND")
		)
	)
	(footprint ""
		(layer "F.Cu")
		(at 140.39088 -42.255948 90)
		(property "Reference" "C2007"
			(at 0 0 90)
			(layer "F.SilkS")
			(hide yes)
			(effects
				(font
					(size 1.27 1.27)
				)
			)
		)
		(property "Value" ""
			(at 0 0 90)
			(layer "F.Fab")
			(effects
				(font
					(size 1.27 1.27)
				)
			)
		)
		(duplicate_pad_numbers_are_jumpers no)
		(fp_line
			(start 0.7874 -0.4064)
			(end 0.7874 0.4064)
			(stroke
				(width 0.1524)
				(type default)
			)
			(layer "F.SilkS")
		)
		(fp_line
			(start -0.7874 -0.4064)
			(end 0.7874 -0.4064)
			(stroke
				(width 0.1524)
				(type default)
			)
			(layer "F.SilkS")
		)
		(fp_line
			(start 0.7874 0.4064)
			(end -0.7874 0.4064)
			(stroke
				(width 0.1524)
				(type default)
			)
			(layer "F.SilkS")
		)
		(fp_line
			(start -0.7874 0.4064)
			(end -0.7874 -0.4064)
			(stroke
				(width 0.1524)
				(type default)
			)
			(layer "F.SilkS")
		)
		(fp_line
			(start -0.12065 -0.305054)
			(end -0.12065 -0.2794)
			(stroke
				(width 0.1)
				(type default)
			)
			(layer "F.Fab")
		)
		(fp_line
			(start -0.67945 -0.305054)
			(end -0.12065 -0.305054)
			(stroke
				(width 0.1)
				(type default)
			)
			(layer "F.Fab")
		)
		(fp_line
			(start 0.67945 -0.3048)
			(end 0.67945 0.3048)
			(stroke
				(width 0.1)
				(type default)
			)
			(layer "F.Fab")
		)
		(fp_line
			(start 0.12065 -0.3048)
			(end 0.67945 -0.3048)
			(stroke
				(width 0.1)
				(type default)
			)
			(layer "F.Fab")
		)
		(fp_line
			(start 0.12065 -0.2794)
			(end 0.12065 -0.3048)
			(stroke
				(width 0.1)
				(type default)
			)
			(layer "F.Fab")
		)
		(fp_line
			(start -0.12065 -0.2794)
			(end 0.12065 -0.2794)
			(stroke
				(width 0.1)
				(type default)
			)
			(layer "F.Fab")
		)
		(fp_line
			(start 0.120396 0.2794)
			(end -0.12065 0.2794)
			(stroke
				(width 0.1)
				(type default)
			)
			(layer "F.Fab")
		)
		(fp_line
			(start -0.12065 0.2794)
			(end -0.12065 0.3048)
			(stroke
				(width 0.1)
				(type default)
			)
			(layer "F.Fab")
		)
		(fp_line
			(start 0.67945 0.3048)
			(end 0.120396 0.3048)
			(stroke
				(width 0.1)
				(type default)
			)
			(layer "F.Fab")
		)
		(fp_line
			(start 0.120396 0.3048)
			(end 0.120396 0.2794)
			(stroke
				(width 0.1)
				(type default)
			)
			(layer "F.Fab")
		)
		(fp_line
			(start -0.12065 0.3048)
			(end -0.67945 0.3048)
			(stroke
				(width 0.1)
				(type default)
			)
			(layer "F.Fab")
		)
		(fp_line
			(start -0.67945 0.3048)
			(end -0.67945 -0.305054)
			(stroke
				(width 0.1)
				(type default)
			)
			(layer "F.Fab")
		)
		(pad "1" smd circle
			(at -0.40005 0 90)
			(size 0 0)
			(layers "F.Cu" "F.Mask" "F.Paste")
			(net "P3V3_AUX")
		)
		(pad "2" smd circle
			(at 0.40005 0 90)
			(size 0 0)
			(layers "F.Cu" "F.Mask" "F.Paste")
			(net "GND")
		)
	)
	(footprint ""
		(layer "F.Cu")
		(at 525.408906 -303.624488 90)
		(property "Reference" "X1"
			(at -2.594864 3.123184 90)
			(unlocked yes)
			(layer "F.SilkS")
			(effects
				(font
					(size 0.7874 0.5842)
					(thickness 0.1524)
				)
				(justify left)
			)
		)
		(property "Value" ""
			(at 0 0 90)
			(layer "F.Fab")
			(effects
				(font
					(size 1.27 1.27)
				)
			)
		)
		(property "Device Type" "TP_TDR_4P_FTS_TH-TP_TDR_4P_DIPA"
			(at 1.30175 1.27 180)
			(unlocked yes)
			(layer "F.Fab")
			(hide yes)
			(effects
				(font
					(size 0.635 0.4064)
					(thickness 0.1524)
				)
			)
		)
		(property "User Part Number" "N_A"
			(at 1.30175 1.27 180)
			(unlocked yes)
			(layer "Cmts.User")
			(hide yes)
			(effects
				(font
					(size 0.635 0.4064)
					(thickness 0.1524)
				)
			)
		)
		(duplicate_pad_numbers_are_jumpers no)
		(fp_line
			(start 2.54 -1.27)
			(end 0 -1.27)
			(stroke
				(width 0.1524)
				(type default)
			)
			(layer "F.SilkS")
		)
		(fp_line
			(start 0 -1.27)
			(end 0 -0.635)
			(stroke
				(width 0.1524)
				(type default)
			)
			(layer "F.SilkS")
		)
		(fp_line
			(start 2.54 -1.1303)
			(end 2.54 -1.27)
			(stroke
				(width 0.1524)
				(type default)
			)
			(layer "F.SilkS")
		)
		(fp_line
			(start 0 0.635)
			(end 0 1.905)
			(stroke
				(width 0.1524)
				(type default)
			)
			(layer "F.SilkS")
		)
		(fp_line
			(start 2.54 1.4097)
			(end 2.54 1.1303)
			(stroke
				(width 0.1524)
				(type default)
			)
			(layer "F.SilkS")
		)
		(fp_line
			(start 0 3.175)
			(end 0 3.81)
			(stroke
				(width 0.1524)
				(type default)
			)
			(layer "F.SilkS")
		)
		(fp_line
			(start 2.54 3.81)
			(end 2.54 3.6703)
			(stroke
				(width 0.1524)
				(type default)
			)
			(layer "F.SilkS")
		)
		(fp_line
			(start 0 3.81)
			(end 2.54 3.81)
			(stroke
				(width 0.1524)
				(type default)
			)
			(layer "F.SilkS")
		)
		(fp_poly
			(pts
				(xy -0.761746 0) (xy -2.285746 0.762) (xy -2.285746 -0.762)
			)
			(stroke
				(width 0)
				(type default)
			)
			(fill yes)
			(layer "F.SilkS")
		)
		(fp_line
			(start 2.54 -1.27)
			(end 0 -1.27)
			(stroke
				(width 0.1)
				(type default)
			)
			(layer "F.Fab")
		)
		(fp_line
			(start 0 -1.27)
			(end 0 3.81)
			(stroke
				(width 0.1)
				(type default)
			)
			(layer "F.Fab")
		)
		(fp_line
			(start 2.54 3.81)
			(end 2.54 -1.27)
			(stroke
				(width 0.1)
				(type default)
			)
			(layer "F.Fab")
		)
		(fp_line
			(start 0 3.81)
			(end 2.54 3.81)
			(stroke
				(width 0.1)
				(type default)
			)
			(layer "F.Fab")
		)
		(fp_poly
			(pts
				(xy -0.761746 0) (xy -2.285746 -0.762) (xy -2.285746 0.762)
			)
			(stroke
				(width 0)
				(type default)
			)
			(fill yes)
			(layer "F.Fab")
		)
		(pad "1" thru_hole circle
			(at 0 0 90)
			(size 1.0033 1.0033)
			(drill 0.249936)
			(layers "*.Cu" "*.Mask")
			(remove_unused_layers no)
			(net "TDR_DIFF_85_TOP_DP")
			(clearance 0.10795)
			(thermal_gap 0.10795)
			(padstack
				(mode front_inner_back)
				(layer "Inner"
					(shape circle)
					(size 0.8001 0.8001)
					(clearance 0.1524)
				)
				(layer "B.Cu"
					(shape circle)
					(size 1.0033 1.0033)
					(clearance 0.10795)
				)
			)
		)
		(pad "2" thru_hole circle
			(at 2.54 0 90)
			(size 1.9939 1.9939)
			(drill 0.249936)
			(layers "*.Cu" "*.Mask")
			(remove_unused_layers no)
			(net "T1_GND")
			(clearance 0.10795)
			(thermal_gap 0.10795)
			(padstack
				(mode front_inner_back)
				(layer "Inner"
					(shape circle)
					(size 0.8001 0.8001)
					(clearance 0.1524)
				)
				(layer "B.Cu"
					(shape circle)
					(size 1.9939 1.9939)
					(clearance 0.10795)
				)
			)
		)
		(pad "3" thru_hole circle
			(at 2.54 2.54 90)
			(size 1.9939 1.9939)
			(drill 0.249936)
			(layers "*.Cu" "*.Mask")
			(remove_unused_layers no)
			(net "T1_GND")
			(clearance 0.10795)
			(thermal_gap 0.10795)
			(padstack
				(mode front_inner_back)
				(layer "Inner"
					(shape circle)
					(size 0.8001 0.8001)
					(clearance 0.1524)
				)
				(layer "B.Cu"
					(shape circle)
					(size 1.9939 1.9939)
					(clearance 0.10795)
				)
			)
		)
		(pad "4" thru_hole circle
			(at 0 2.54 90)
			(size 1.0033 1.0033)
			(drill 0.249936)
			(layers "*.Cu" "*.Mask")
			(remove_unused_layers no)
			(net "TDR_DIFF_85_TOP_DN")
			(clearance 0.10795)
			(thermal_gap 0.10795)
			(padstack
				(mode front_inner_back)
				(layer "Inner"
					(shape circle)
					(size 0.8001 0.8001)
					(clearance 0.1524)
				)
				(layer "B.Cu"
					(shape circle)
					(size 1.0033 1.0033)
					(clearance 0.10795)
				)
			)
		)
	)
	(footprint ""
		(layer "F.Cu")
		(at 193.38036 -122.900948)
		(property "Reference" "R2792"
			(at 0 0 0)
			(layer "F.SilkS")
			(hide yes)
			(effects
				(font
					(size 1.27 1.27)
				)
			)
		)
		(property "Value" ""
			(at 0 0 0)
			(layer "F.Fab")
			(effects
				(font
					(size 1.27 1.27)
				)
			)
		)
		(duplicate_pad_numbers_are_jumpers no)
		(fp_line
			(start -0.7874 -0.4064)
			(end 0.7874 -0.4064)
			(stroke
				(width 0.1524)
				(type default)
			)
			(layer "F.SilkS")
		)
		(fp_line
			(start -0.7874 0.4064)
			(end -0.7874 -0.4064)
			(stroke
				(width 0.1524)
				(type default)
			)
			(layer "F.SilkS")
		)
		(fp_line
			(start 0.7874 -0.4064)
			(end 0.7874 0.4064)
			(stroke
				(width 0.1524)
				(type default)
			)
			(layer "F.SilkS")
		)
		(fp_line
			(start 0.7874 0.4064)
			(end -0.7874 0.4064)
			(stroke
				(width 0.1524)
				(type default)
			)
			(layer "F.SilkS")
		)
		(fp_line
			(start -0.67945 -0.305054)
			(end -0.12065 -0.305054)
			(stroke
				(width 0.1)
				(type default)
			)
			(layer "F.Fab")
		)
		(fp_line
			(start -0.67945 0.3048)
			(end -0.67945 -0.305054)
			(stroke
				(width 0.1)
				(type default)
			)
			(layer "F.Fab")
		)
		(fp_line
			(start -0.12065 -0.305054)
			(end -0.12065 -0.2794)
			(stroke
				(width 0.1)
				(type default)
			)
			(layer "F.Fab")
		)
		(fp_line
			(start -0.12065 -0.2794)
			(end 0.12065 -0.2794)
			(stroke
				(width 0.1)
				(type default)
			)
			(layer "F.Fab")
		)
		(fp_line
			(start -0.12065 0.2794)
			(end -0.12065 0.3048)
			(stroke
				(width 0.1)
				(type default)
			)
			(layer "F.Fab")
		)
		(fp_line
			(start -0.12065 0.3048)
			(end -0.67945 0.3048)
			(stroke
				(width 0.1)
				(type default)
			)
			(layer "F.Fab")
		)
		(fp_line
			(start 0.120396 0.2794)
			(end -0.12065 0.2794)
			(stroke
				(width 0.1)
				(type default)
			)
			(layer "F.Fab")
		)
		(fp_line
			(start 0.120396 0.3048)
			(end 0.120396 0.2794)
			(stroke
				(width 0.1)
				(type default)
			)
			(layer "F.Fab")
		)
		(fp_line
			(start 0.12065 -0.3048)
			(end 0.67945 -0.3048)
			(stroke
				(width 0.1)
				(type default)
			)
			(layer "F.Fab")
		)
		(fp_line
			(start 0.12065 -0.2794)
			(end 0.12065 -0.3048)
			(stroke
				(width 0.1)
				(type default)
			)
			(layer "F.Fab")
		)
		(fp_line
			(start 0.67945 -0.3048)
			(end 0.67945 0.3048)
			(stroke
				(width 0.1)
				(type default)
			)
			(layer "F.Fab")
		)
		(fp_line
			(start 0.67945 0.3048)
			(end 0.120396 0.3048)
			(stroke
				(width 0.1)
				(type default)
			)
			(layer "F.Fab")
		)
		(pad "1" smd circle
			(at -0.40005 0)
			(size 0 0)
			(layers "F.Cu" "F.Mask" "F.Paste")
			(net "FM_PDB_BUF_EN")
		)
		(pad "2" smd circle
			(at 0.40005 0)
			(size 0 0)
			(layers "F.Cu" "F.Mask" "F.Paste")
			(net "FM_PDB_BUF_EN_R")
		)
	)
	(footprint ""
		(layer "F.Cu")
		(at 133.296914 -402.371052 -90)
		(property "Reference" "C750"
			(at 0 0 270)
			(layer "F.SilkS")
			(hide yes)
			(effects
				(font
					(size 1.27 1.27)
				)
			)
		)
		(property "Value" ""
			(at 0 0 270)
			(layer "F.Fab")
			(effects
				(font
					(size 1.27 1.27)
				)
			)
		)
		(duplicate_pad_numbers_are_jumpers no)
		(fp_line
			(start -0.299974 0.150114)
			(end -0.299974 -0.150114)
			(stroke
				(width 0.1)
				(type default)
			)
			(layer "F.Fab")
		)
		(fp_line
			(start 0.299974 0.150114)
			(end -0.299974 0.150114)
			(stroke
				(width 0.1)
				(type default)
			)
			(layer "F.Fab")
		)
		(fp_line
			(start -0.299974 -0.150114)
			(end 0.299974 -0.150114)
			(stroke
				(width 0.1)
				(type default)
			)
			(layer "F.Fab")
		)
		(fp_line
			(start 0.299974 -0.150114)
			(end 0.299974 0.150114)
			(stroke
				(width 0.1)
				(type default)
			)
			(layer "F.Fab")
		)
		(pad "1" smd rect
			(at -0.2667 0 270)
			(size 0.3048 0.381)
			(layers "F.Cu" "F.Mask" "F.Paste")
			(net "P5E_CPU1_PE2_TX_C_DN<11>")
		)
		(pad "2" smd rect
			(at 0.2667 0 270)
			(size 0.3048 0.381)
			(layers "F.Cu" "F.Mask" "F.Paste")
			(net "P5E_CPU1_PE2_TX_DN<11>")
		)
	)
	(footprint ""
		(layer "F.Cu")
		(at 219.276676 -67.954144 -90)
		(property "Reference" "PR3964"
			(at 0 0 270)
			(layer "F.SilkS")
			(hide yes)
			(effects
				(font
					(size 1.27 1.27)
				)
			)
		)
		(property "Value" ""
			(at 0 0 270)
			(layer "F.Fab")
			(effects
				(font
					(size 1.27 1.27)
				)
			)
		)
		(duplicate_pad_numbers_are_jumpers no)
		(fp_line
			(start -0.7874 0.4064)
			(end -0.7874 -0.4064)
			(stroke
				(width 0.1524)
				(type default)
			)
			(layer "F.SilkS")
		)
		(fp_line
			(start 0.7874 0.4064)
			(end -0.7874 0.4064)
			(stroke
				(width 0.1524)
				(type default)
			)
			(layer "F.SilkS")
		)
		(fp_line
			(start -0.7874 -0.4064)
			(end 0.7874 -0.4064)
			(stroke
				(width 0.1524)
				(type default)
			)
			(layer "F.SilkS")
		)
		(fp_line
			(start 0.7874 -0.4064)
			(end 0.7874 0.4064)
			(stroke
				(width 0.1524)
				(type default)
			)
			(layer "F.SilkS")
		)
		(fp_line
			(start -0.67945 0.3048)
			(end -0.67945 -0.305054)
			(stroke
				(width 0.1)
				(type default)
			)
			(layer "F.Fab")
		)
		(fp_line
			(start -0.12065 0.3048)
			(end -0.67945 0.3048)
			(stroke
				(width 0.1)
				(type default)
			)
			(layer "F.Fab")
		)
		(fp_line
			(start 0.120396 0.3048)
			(end 0.120396 0.2794)
			(stroke
				(width 0.1)
				(type default)
			)
			(layer "F.Fab")
		)
		(fp_line
			(start 0.67945 0.3048)
			(end 0.120396 0.3048)
			(stroke
				(width 0.1)
				(type default)
			)
			(layer "F.Fab")
		)
		(fp_line
			(start -0.12065 0.2794)
			(end -0.12065 0.3048)
			(stroke
				(width 0.1)
				(type default)
			)
			(layer "F.Fab")
		)
		(fp_line
			(start 0.120396 0.2794)
			(end -0.12065 0.2794)
			(stroke
				(width 0.1)
				(type default)
			)
			(layer "F.Fab")
		)
		(fp_line
			(start -0.12065 -0.2794)
			(end 0.12065 -0.2794)
			(stroke
				(width 0.1)
				(type default)
			)
			(layer "F.Fab")
		)
		(fp_line
			(start 0.12065 -0.2794)
			(end 0.12065 -0.3048)
			(stroke
				(width 0.1)
				(type default)
			)
			(layer "F.Fab")
		)
		(fp_line
			(start 0.12065 -0.3048)
			(end 0.67945 -0.3048)
			(stroke
				(width 0.1)
				(type default)
			)
			(layer "F.Fab")
		)
		(fp_line
			(start 0.67945 -0.3048)
			(end 0.67945 0.3048)
			(stroke
				(width 0.1)
				(type default)
			)
			(layer "F.Fab")
		)
		(fp_line
			(start -0.67945 -0.305054)
			(end -0.12065 -0.305054)
			(stroke
				(width 0.1)
				(type default)
			)
			(layer "F.Fab")
		)
		(fp_line
			(start -0.12065 -0.305054)
			(end -0.12065 -0.2794)
			(stroke
				(width 0.1)
				(type default)
			)
			(layer "F.Fab")
		)
		(pad "1" smd circle
			(at -0.40005 0 270)
			(size 0 0)
			(layers "F.Cu" "F.Mask" "F.Paste")
			(net "P3V3_E1S_UV_0")
		)
		(pad "2" smd circle
			(at 0.40005 0 270)
			(size 0 0)
			(layers "F.Cu" "F.Mask" "F.Paste")
			(net "P3V3_E1S_OV_0")
		)
	)
	(footprint ""
		(layer "F.Cu")
		(at 67.672458 -27.889962 -90)
		(property "Reference" "PU206"
			(at -0.065532 -4.389628 0)
			(unlocked yes)
			(layer "F.SilkS")
			(effects
				(font
					(size 0.7874 0.5842)
					(thickness 0.1524)
				)
				(justify left)
			)
		)
		(property "Value" ""
			(at 0 0 270)
			(layer "F.Fab")
			(effects
				(font
					(size 1.27 1.27)
				)
			)
		)
		(duplicate_pad_numbers_are_jumpers no)
		(fp_line
			(start -1.549908 2.549906)
			(end -0.753872 2.549906)
			(stroke
				(width 0.1524)
				(type default)
			)
			(layer "F.SilkS")
		)
		(fp_line
			(start -0.245872 2.549906)
			(end 0.245872 2.549906)
			(stroke
				(width 0.1524)
				(type default)
			)
			(layer "F.SilkS")
		)
		(fp_line
			(start 0.753872 2.549906)
			(end 1.549908 2.549906)
			(stroke
				(width 0.1524)
				(type default)
			)
			(layer "F.SilkS")
		)
		(fp_line
			(start 1.549908 2.549906)
			(end 1.549908 2.253996)
			(stroke
				(width 0.1524)
				(type default)
			)
			(layer "F.SilkS")
		)
		(fp_line
			(start -1.549908 2.253996)
			(end -1.549908 2.549906)
			(stroke
				(width 0.1524)
				(type default)
			)
			(layer "F.SilkS")
		)
		(fp_line
			(start 1.549908 -2.253996)
			(end 1.549908 -2.549906)
			(stroke
				(width 0.1524)
				(type default)
			)
			(layer "F.SilkS")
		)
		(fp_line
			(start -1.549908 -2.549906)
			(end -1.549908 -2.251964)
			(stroke
				(width 0.1524)
				(type default)
			)
			(layer "F.SilkS")
		)
		(fp_line
			(start -0.752094 -2.549906)
			(end -1.549908 -2.549906)
			(stroke
				(width 0.1524)
				(type default)
			)
			(layer "F.SilkS")
		)
		(fp_line
			(start 0.2413 -2.549906)
			(end -0.2413 -2.549906)
			(stroke
				(width 0.1524)
				(type default)
			)
			(layer "F.SilkS")
		)
		(fp_line
			(start 1.549908 -2.549906)
			(end 0.752094 -2.549906)
			(stroke
				(width 0.1524)
				(type default)
			)
			(layer "F.SilkS")
		)
		(fp_poly
			(pts
				(xy -2.83845 -2.769616) (xy -2.23647 -3.37185) (xy -1.935226 -2.468626)
			)
			(stroke
				(width 0)
				(type default)
			)
			(fill yes)
			(layer "F.SilkS")
		)
		(fp_line
			(start -1.549908 2.549906)
			(end 1.549908 2.549906)
			(stroke
				(width 0.1)
				(type default)
			)
			(layer "F.Fab")
		)
		(fp_line
			(start 1.549908 2.549906)
			(end 1.549908 -2.549906)
			(stroke
				(width 0.1)
				(type default)
			)
			(layer "F.Fab")
		)
		(fp_line
			(start -1.549908 -2.549906)
			(end -1.549908 2.549906)
			(stroke
				(width 0.1)
				(type default)
			)
			(layer "F.Fab")
		)
		(fp_line
			(start 1.549908 -2.549906)
			(end -1.549908 -2.549906)
			(stroke
				(width 0.1)
				(type default)
			)
			(layer "F.Fab")
		)
		(fp_poly
			(pts
				(xy -1.891538 -1.999996) (xy -2.7432 -1.574292) (xy -2.7432 -2.4257)
			)
			(stroke
				(width 0)
				(type default)
			)
			(fill yes)
			(layer "F.Fab")
		)
		(fp_text user "12"
			(at 4.230624 5.597398 0)
			(unlocked yes)
			(layer "F.SilkS")
			(effects
				(font
					(size 0.635 0.4064)
					(thickness 0.1524)
				)
			)
		)
		(fp_text user "11"
			(at 2.996184 5.389118 0)
			(unlocked yes)
			(layer "F.SilkS")
			(effects
				(font
					(size 0.635 0.4064)
					(thickness 0.1524)
				)
			)
		)
		(fp_text user "10"
			(at -2.393696 3.639058 0)
			(unlocked yes)
			(layer "F.SilkS")
			(effects
				(font
					(size 0.635 0.4064)
					(thickness 0.1524)
				)
			)
		)
		(fp_text user "9"
			(at -2.338832 2.5908 180)
			(unlocked yes)
			(layer "F.SilkS")
			(effects
				(font
					(size 0.635 0.4064)
					(thickness 0.1524)
				)
			)
		)
		(fp_text user "20"
			(at 1.510284 -3.318002 0)
			(unlocked yes)
			(layer "F.SilkS")
			(effects
				(font
					(size 0.635 0.4064)
					(thickness 0.1524)
				)
			)
		)
		(fp_text user "21_22"
			(at -3.696716 -4.349242 0)
			(unlocked yes)
			(layer "F.SilkS")
			(effects
				(font
					(size 0.635 0.4064)
					(thickness 0.1524)
				)
			)
		)
		(fp_text user "11"
			(at 1.1938 3.329432 270)
			(unlocked yes)
			(layer "F.Fab")
			(effects
				(font
					(size 0.635 0.4064)
					(thickness 0.1524)
				)
			)
		)
		(fp_text user "10"
			(at -1.4224 3.253232 270)
			(unlocked yes)
			(layer "F.Fab")
			(effects
				(font
					(size 0.635 0.4064)
					(thickness 0.1524)
				)
			)
		)
		(fp_text user "12"
			(at 2.207768 2.7178 180)
			(unlocked yes)
			(layer "F.Fab")
			(effects
				(font
					(size 0.635 0.4064)
					(thickness 0.1524)
				)
			)
		)
		(fp_text user "9"
			(at -2.338832 2.5908 180)
			(unlocked yes)
			(layer "F.Fab")
			(effects
				(font
					(size 0.635 0.4064)
					(thickness 0.1524)
				)
			)
		)
		(fp_text user "20"
			(at 2.055368 -2.7686 180)
			(unlocked yes)
			(layer "F.Fab")
			(effects
				(font
					(size 0.635 0.4064)
					(thickness 0.1524)
				)
			)
		)
		(fp_text user "21_22"
			(at -0.0762 -3.401568 270)
			(unlocked yes)
			(layer "F.Fab")
			(effects
				(font
					(size 0.635 0.4064)
					(thickness 0.1524)
				)
			)
		)
		(pad "1" smd circle
			(at -1.374902 -1.999996 180)
			(size 0 0)
			(layers "F.Cu" "F.Mask" "F.Paste")
			(net "P12V_OCP_V3_2_EN_2_R3")
		)
		(pad "2" smd rect
			(at -1.400048 -1.500124 180)
			(size 0.254 0.8128)
			(layers "F.Cu" "F.Mask" "F.Paste")
			(net "GND")
		)
		(pad "3" smd rect
			(at -1.400048 -0.999998 180)
			(size 0.254 0.8128)
			(layers "F.Cu" "F.Mask" "F.Paste")
			(net "GND")
		)
		(pad "4" smd rect
			(at -1.400048 -0.499872 180)
			(size 0.254 0.8128)
			(layers "F.Cu" "F.Mask" "F.Paste")
			(net "P12V_OCP_TIMER_2")
		)
		(pad "5" smd rect
			(at -1.400048 0 180)
			(size 0.254 0.8128)
			(layers "F.Cu" "F.Mask" "F.Paste")
			(net "P12V_OCP_ISET_2")
		)
		(pad "6" smd rect
			(at -1.400048 0.499872 180)
			(size 0.254 0.8128)
			(layers "F.Cu" "F.Mask" "F.Paste")
			(net "P12V_OCP_SS_2")
		)
		(pad "7" smd rect
			(at -1.400048 0.999998 180)
			(size 0.254 0.8128)
			(layers "F.Cu" "F.Mask" "F.Paste")
			(net "GND")
		)
		(pad "8" smd rect
			(at -1.400048 1.500124 180)
			(size 0.254 0.8128)
			(layers "F.Cu" "F.Mask" "F.Paste")
			(net "P12V_OCP_IMON_2")
		)
		(pad "9" smd rect
			(at -1.400048 1.999996 180)
			(size 0.254 0.8128)
			(layers "F.Cu" "F.Mask" "F.Paste")
			(net "P12V_OCP_FLTB_2")
		)
		(pad "10" smd rect
			(at -0.499872 2.400046 270)
			(size 0.254 0.8128)
			(layers "F.Cu" "F.Mask" "F.Paste")
			(net "HP_LVC3_OCP_V3_2_P12V_PWRGD")
		)
		(pad "11" smd rect
			(at 0.499872 2.400046 270)
			(size 0.254 0.8128)
			(layers "F.Cu" "F.Mask" "F.Paste")
			(net "P12V_OCP_OV_FB_2")
		)
		(pad "12" smd rect
			(at 1.400048 1.999996 180)
			(size 0.254 0.8128)
			(layers "F.Cu" "F.Mask" "F.Paste")
			(net "P12V_OCP_AVIN_PD_2")
		)
		(pad "13" smd rect
			(at 1.400048 1.500124 180)
			(size 0.254 0.8128)
			(layers "F.Cu" "F.Mask" "F.Paste")
			(net "P12V_OCP_V3_2")
		)
		(pad "14" smd rect
			(at 1.400048 0.999998 180)
			(size 0.254 0.8128)
			(layers "F.Cu" "F.Mask" "F.Paste")
			(net "P12V_OCP_V3_2")
		)
		(pad "15" smd rect
			(at 1.400048 0.499872 180)
			(size 0.254 0.8128)
			(layers "F.Cu" "F.Mask" "F.Paste")
			(net "P12V_OCP_V3_2")
		)
		(pad "16" smd rect
			(at 1.400048 0 180)
			(size 0.254 0.8128)
			(layers "F.Cu" "F.Mask" "F.Paste")
			(net "P12V_OCP_V3_2")
		)
		(pad "17" smd rect
			(at 1.400048 -0.499872 180)
			(size 0.254 0.8128)
			(layers "F.Cu" "F.Mask" "F.Paste")
			(net "P12V_OCP_V3_2")
		)
		(pad "18" smd rect
			(at 1.400048 -0.999998 180)
			(size 0.254 0.8128)
			(layers "F.Cu" "F.Mask" "F.Paste")
			(net "P12V_OCP_V3_2")
		)
		(pad "19" smd rect
			(at 1.400048 -1.500124 180)
			(size 0.254 0.8128)
			(layers "F.Cu" "F.Mask" "F.Paste")
			(net "P12V_OCP_V3_2")
		)
		(pad "20" smd rect
			(at 1.400048 -1.999996 180)
			(size 0.254 0.8128)
			(layers "F.Cu" "F.Mask" "F.Paste")
			(net "P12V_OCP_V3_2")
		)
		(pad "21_22" smd circle
			(at 0.499872 -2.337562 180)
			(size 0 0)
			(layers "F.Cu" "F.Mask" "F.Paste")
			(net "P12V_AUX")
		)
		(pad "23" smd rect
			(at 0 -1.100074 180)
			(size 0.254 1.27)
			(layers "F.Cu" "F.Mask" "F.Paste")
			(net "P12V_AUX")
		)
		(pad "24" smd rect
			(at 0 -0.199898 180)
			(size 0.254 1.27)
			(layers "F.Cu" "F.Mask" "F.Paste")
			(net "P12V_AUX")
		)
		(pad "25" smd rect
			(at 0 0.700024 180)
			(size 0.254 1.27)
			(layers "F.Cu" "F.Mask" "F.Paste")
			(net "P12V_AUX")
		)
		(pad "26" smd rect
			(at 0 1.599946 180)
			(size 0.254 1.27)
			(layers "F.Cu" "F.Mask" "F.Paste")
			(net "P12V_AUX")
		)
	)
	(footprint ""
		(layer "F.Cu")
		(at 353.246944 -240.276888 90)
		(property "Reference" "C1027"
			(at 0 0 90)
			(layer "F.SilkS")
			(hide yes)
			(effects
				(font
					(size 1.27 1.27)
				)
			)
		)
		(property "Value" ""
			(at 0 0 90)
			(layer "F.Fab")
			(effects
				(font
					(size 1.27 1.27)
				)
			)
		)
		(duplicate_pad_numbers_are_jumpers no)
		(fp_line
			(start 0.7874 -0.4064)
			(end 0.7874 0.4064)
			(stroke
				(width 0.1524)
				(type default)
			)
			(layer "F.SilkS")
		)
		(fp_line
			(start -0.7874 -0.4064)
			(end 0.7874 -0.4064)
			(stroke
				(width 0.1524)
				(type default)
			)
			(layer "F.SilkS")
		)
		(fp_line
			(start 0.7874 0.4064)
			(end -0.7874 0.4064)
			(stroke
				(width 0.1524)
				(type default)
			)
			(layer "F.SilkS")
		)
		(fp_line
			(start -0.7874 0.4064)
			(end -0.7874 -0.4064)
			(stroke
				(width 0.1524)
				(type default)
			)
			(layer "F.SilkS")
		)
		(fp_line
			(start -0.12065 -0.305054)
			(end -0.12065 -0.2794)
			(stroke
				(width 0.1)
				(type default)
			)
			(layer "F.Fab")
		)
		(fp_line
			(start -0.67945 -0.305054)
			(end -0.12065 -0.305054)
			(stroke
				(width 0.1)
				(type default)
			)
			(layer "F.Fab")
		)
		(fp_line
			(start 0.67945 -0.3048)
			(end 0.67945 0.3048)
			(stroke
				(width 0.1)
				(type default)
			)
			(layer "F.Fab")
		)
		(fp_line
			(start 0.12065 -0.3048)
			(end 0.67945 -0.3048)
			(stroke
				(width 0.1)
				(type default)
			)
			(layer "F.Fab")
		)
		(fp_line
			(start 0.12065 -0.2794)
			(end 0.12065 -0.3048)
			(stroke
				(width 0.1)
				(type default)
			)
			(layer "F.Fab")
		)
		(fp_line
			(start -0.12065 -0.2794)
			(end 0.12065 -0.2794)
			(stroke
				(width 0.1)
				(type default)
			)
			(layer "F.Fab")
		)
		(fp_line
			(start 0.120396 0.2794)
			(end -0.12065 0.2794)
			(stroke
				(width 0.1)
				(type default)
			)
			(layer "F.Fab")
		)
		(fp_line
			(start -0.12065 0.2794)
			(end -0.12065 0.3048)
			(stroke
				(width 0.1)
				(type default)
			)
			(layer "F.Fab")
		)
		(fp_line
			(start 0.67945 0.3048)
			(end 0.120396 0.3048)
			(stroke
				(width 0.1)
				(type default)
			)
			(layer "F.Fab")
		)
		(fp_line
			(start 0.120396 0.3048)
			(end 0.120396 0.2794)
			(stroke
				(width 0.1)
				(type default)
			)
			(layer "F.Fab")
		)
		(fp_line
			(start -0.12065 0.3048)
			(end -0.67945 0.3048)
			(stroke
				(width 0.1)
				(type default)
			)
			(layer "F.Fab")
		)
		(fp_line
			(start -0.67945 0.3048)
			(end -0.67945 -0.305054)
			(stroke
				(width 0.1)
				(type default)
			)
			(layer "F.Fab")
		)
		(pad "1" smd circle
			(at -0.40005 0 90)
			(size 0 0)
			(layers "F.Cu" "F.Mask" "F.Paste")
			(net "PVCCIN_CPU0")
		)
		(pad "2" smd circle
			(at 0.40005 0 90)
			(size 0 0)
			(layers "F.Cu" "F.Mask" "F.Paste")
			(net "GND")
		)
	)
	(footprint ""
		(layer "F.Cu")
		(at 140.70838 -39.085012 180)
		(property "Reference" "R3308"
			(at 0 0 180)
			(layer "F.SilkS")
			(hide yes)
			(effects
				(font
					(size 1.27 1.27)
				)
			)
		)
		(property "Value" ""
			(at 0 0 180)
			(layer "F.Fab")
			(effects
				(font
					(size 1.27 1.27)
				)
			)
		)
		(duplicate_pad_numbers_are_jumpers no)
		(fp_line
			(start 0.7874 0.4064)
			(end -0.7874 0.4064)
			(stroke
				(width 0.1524)
				(type default)
			)
			(layer "F.SilkS")
		)
		(fp_line
			(start 0.7874 -0.4064)
			(end 0.7874 0.4064)
			(stroke
				(width 0.1524)
				(type default)
			)
			(layer "F.SilkS")
		)
		(fp_line
			(start -0.7874 0.4064)
			(end -0.7874 -0.4064)
			(stroke
				(width 0.1524)
				(type default)
			)
			(layer "F.SilkS")
		)
		(fp_line
			(start -0.7874 -0.4064)
			(end 0.7874 -0.4064)
			(stroke
				(width 0.1524)
				(type default)
			)
			(layer "F.SilkS")
		)
		(fp_line
			(start 0.67945 0.3048)
			(end 0.120396 0.3048)
			(stroke
				(width 0.1)
				(type default)
			)
			(layer "F.Fab")
		)
		(fp_line
			(start 0.67945 -0.3048)
			(end 0.67945 0.3048)
			(stroke
				(width 0.1)
				(type default)
			)
			(layer "F.Fab")
		)
		(fp_line
			(start 0.12065 -0.2794)
			(end 0.12065 -0.3048)
			(stroke
				(width 0.1)
				(type default)
			)
			(layer "F.Fab")
		)
		(fp_line
			(start 0.12065 -0.3048)
			(end 0.67945 -0.3048)
			(stroke
				(width 0.1)
				(type default)
			)
			(layer "F.Fab")
		)
		(fp_line
			(start 0.120396 0.3048)
			(end 0.120396 0.2794)
			(stroke
				(width 0.1)
				(type default)
			)
			(layer "F.Fab")
		)
		(fp_line
			(start 0.120396 0.2794)
			(end -0.12065 0.2794)
			(stroke
				(width 0.1)
				(type default)
			)
			(layer "F.Fab")
		)
		(fp_line
			(start -0.12065 0.3048)
			(end -0.67945 0.3048)
			(stroke
				(width 0.1)
				(type default)
			)
			(layer "F.Fab")
		)
		(fp_line
			(start -0.12065 0.2794)
			(end -0.12065 0.3048)
			(stroke
				(width 0.1)
				(type default)
			)
			(layer "F.Fab")
		)
		(fp_line
			(start -0.12065 -0.2794)
			(end 0.12065 -0.2794)
			(stroke
				(width 0.1)
				(type default)
			)
			(layer "F.Fab")
		)
		(fp_line
			(start -0.12065 -0.305054)
			(end -0.12065 -0.2794)
			(stroke
				(width 0.1)
				(type default)
			)
			(layer "F.Fab")
		)
		(fp_line
			(start -0.67945 0.3048)
			(end -0.67945 -0.305054)
			(stroke
				(width 0.1)
				(type default)
			)
			(layer "F.Fab")
		)
		(fp_line
			(start -0.67945 -0.305054)
			(end -0.12065 -0.305054)
			(stroke
				(width 0.1)
				(type default)
			)
			(layer "F.Fab")
		)
		(pad "1" smd circle
			(at -0.40005 0 180)
			(size 0 0)
			(layers "F.Cu" "F.Mask" "F.Paste")
			(net "OCP_V3_2_PRSNT_ALL_R_N")
		)
		(pad "2" smd circle
			(at 0.40005 0 180)
			(size 0 0)
			(layers "F.Cu" "F.Mask" "F.Paste")
			(net "OCP_V3_2_PRSNT_ALL_R1_N")
		)
	)
	(footprint ""
		(layer "F.Cu")
		(at 342.974168 -408.517344 -90)
		(property "Reference" "C927"
			(at 0 0 270)
			(layer "F.SilkS")
			(hide yes)
			(effects
				(font
					(size 1.27 1.27)
				)
			)
		)
		(property "Value" ""
			(at 0 0 270)
			(layer "F.Fab")
			(effects
				(font
					(size 1.27 1.27)
				)
			)
		)
		(duplicate_pad_numbers_are_jumpers no)
		(fp_line
			(start -0.299974 0.150114)
			(end -0.299974 -0.150114)
			(stroke
				(width 0.1)
				(type default)
			)
			(layer "F.Fab")
		)
		(fp_line
			(start 0.299974 0.150114)
			(end -0.299974 0.150114)
			(stroke
				(width 0.1)
				(type default)
			)
			(layer "F.Fab")
		)
		(fp_line
			(start -0.299974 -0.150114)
			(end 0.299974 -0.150114)
			(stroke
				(width 0.1)
				(type default)
			)
			(layer "F.Fab")
		)
		(fp_line
			(start 0.299974 -0.150114)
			(end 0.299974 0.150114)
			(stroke
				(width 0.1)
				(type default)
			)
			(layer "F.Fab")
		)
		(pad "1" smd rect
			(at -0.2667 0 270)
			(size 0.3048 0.381)
			(layers "F.Cu" "F.Mask" "F.Paste")
			(net "P5E_CPU0_PE0_TX_C_DP<3>")
		)
		(pad "2" smd rect
			(at 0.2667 0 270)
			(size 0.3048 0.381)
			(layers "F.Cu" "F.Mask" "F.Paste")
			(net "P5E_CPU0_PE0_TX_DP<3>")
		)
	)
	(footprint ""
		(layer "F.Cu")
		(at 117.904514 -333.525368 -90)
		(property "Reference" "PC525_P1_4"
			(at 0 0 270)
			(layer "F.SilkS")
			(hide yes)
			(effects
				(font
					(size 1.27 1.27)
				)
			)
		)
		(property "Value" ""
			(at 0 0 270)
			(layer "F.Fab")
			(effects
				(font
					(size 1.27 1.27)
				)
			)
		)
		(duplicate_pad_numbers_are_jumpers no)
		(fp_line
			(start -0.7874 0.4064)
			(end -0.7874 -0.4064)
			(stroke
				(width 0.1524)
				(type default)
			)
			(layer "F.SilkS")
		)
		(fp_line
			(start 0.7874 0.4064)
			(end -0.7874 0.4064)
			(stroke
				(width 0.1524)
				(type default)
			)
			(layer "F.SilkS")
		)
		(fp_line
			(start -0.7874 -0.4064)
			(end 0.7874 -0.4064)
			(stroke
				(width 0.1524)
				(type default)
			)
			(layer "F.SilkS")
		)
		(fp_line
			(start 0.7874 -0.4064)
			(end 0.7874 0.4064)
			(stroke
				(width 0.1524)
				(type default)
			)
			(layer "F.SilkS")
		)
		(fp_line
			(start -0.67945 0.3048)
			(end -0.67945 -0.305054)
			(stroke
				(width 0.1)
				(type default)
			)
			(layer "F.Fab")
		)
		(fp_line
			(start -0.12065 0.3048)
			(end -0.67945 0.3048)
			(stroke
				(width 0.1)
				(type default)
			)
			(layer "F.Fab")
		)
		(fp_line
			(start 0.120396 0.3048)
			(end 0.120396 0.2794)
			(stroke
				(width 0.1)
				(type default)
			)
			(layer "F.Fab")
		)
		(fp_line
			(start 0.67945 0.3048)
			(end 0.120396 0.3048)
			(stroke
				(width 0.1)
				(type default)
			)
			(layer "F.Fab")
		)
		(fp_line
			(start -0.12065 0.2794)
			(end -0.12065 0.3048)
			(stroke
				(width 0.1)
				(type default)
			)
			(layer "F.Fab")
		)
		(fp_line
			(start 0.120396 0.2794)
			(end -0.12065 0.2794)
			(stroke
				(width 0.1)
				(type default)
			)
			(layer "F.Fab")
		)
		(fp_line
			(start -0.12065 -0.2794)
			(end 0.12065 -0.2794)
			(stroke
				(width 0.1)
				(type default)
			)
			(layer "F.Fab")
		)
		(fp_line
			(start 0.12065 -0.2794)
			(end 0.12065 -0.3048)
			(stroke
				(width 0.1)
				(type default)
			)
			(layer "F.Fab")
		)
		(fp_line
			(start 0.12065 -0.3048)
			(end 0.67945 -0.3048)
			(stroke
				(width 0.1)
				(type default)
			)
			(layer "F.Fab")
		)
		(fp_line
			(start 0.67945 -0.3048)
			(end 0.67945 0.3048)
			(stroke
				(width 0.1)
				(type default)
			)
			(layer "F.Fab")
		)
		(fp_line
			(start -0.67945 -0.305054)
			(end -0.12065 -0.305054)
			(stroke
				(width 0.1)
				(type default)
			)
			(layer "F.Fab")
		)
		(fp_line
			(start -0.12065 -0.305054)
			(end -0.12065 -0.2794)
			(stroke
				(width 0.1)
				(type default)
			)
			(layer "F.Fab")
		)
		(pad "1" smd circle
			(at -0.40005 0 270)
			(size 0 0)
			(layers "F.Cu" "F.Mask" "F.Paste")
			(net "PVCCIN_CPU1_PVCC")
		)
		(pad "2" smd circle
			(at 0.40005 0 270)
			(size 0 0)
			(layers "F.Cu" "F.Mask" "F.Paste")
			(net "GND")
		)
	)
	(footprint ""
		(layer "F.Cu")
		(at 94.086426 -99.577398)
		(property "Reference" "Q84"
			(at -4.72948 -0.638048 0)
			(unlocked yes)
			(layer "F.SilkS")
			(effects
				(font
					(size 0.7874 0.5842)
					(thickness 0.1524)
				)
				(justify left)
			)
		)
		(property "Value" ""
			(at 0 0 0)
			(layer "F.Fab")
			(effects
				(font
					(size 1.27 1.27)
				)
			)
		)
		(duplicate_pad_numbers_are_jumpers no)
		(fp_line
			(start -1.332738 -1.100074)
			(end -0.4826 -1.100074)
			(stroke
				(width 0.1524)
				(type default)
			)
			(layer "F.SilkS")
		)
		(fp_line
			(start -1.332738 1.100074)
			(end -1.332738 -1.100074)
			(stroke
				(width 0.1524)
				(type default)
			)
			(layer "F.SilkS")
		)
		(fp_line
			(start -0.4826 -1.100074)
			(end 0 -0.541274)
			(stroke
				(width 0.1524)
				(type default)
			)
			(layer "F.SilkS")
		)
		(fp_line
			(start 0 -0.541274)
			(end 0.4826 -1.100074)
			(stroke
				(width 0.1524)
				(type default)
			)
			(layer "F.SilkS")
		)
		(fp_line
			(start 0.4826 -1.100074)
			(end 1.332738 -1.100074)
			(stroke
				(width 0.1524)
				(type default)
			)
			(layer "F.SilkS")
		)
		(fp_line
			(start 1.332738 -1.100074)
			(end 1.332738 1.100074)
			(stroke
				(width 0.1524)
				(type default)
			)
			(layer "F.SilkS")
		)
		(fp_line
			(start 1.332738 1.100074)
			(end -1.332738 1.100074)
			(stroke
				(width 0.1524)
				(type default)
			)
			(layer "F.SilkS")
		)
		(fp_poly
			(pts
				(xy -2.32918 -1.036574) (xy -1.627124 -0.685546) (xy -2.32918 -0.334518)
			)
			(stroke
				(width 0)
				(type default)
			)
			(fill yes)
			(layer "F.SilkS")
		)
		(fp_line
			(start -0.674878 -1.100074)
			(end 0.674878 -1.100074)
			(stroke
				(width 0.1)
				(type default)
			)
			(layer "F.Fab")
		)
		(fp_line
			(start -0.674878 1.100074)
			(end -0.674878 -1.100074)
			(stroke
				(width 0.1)
				(type default)
			)
			(layer "F.Fab")
		)
		(fp_line
			(start 0.674878 -1.100074)
			(end 0.674878 1.100074)
			(stroke
				(width 0.1)
				(type default)
			)
			(layer "F.Fab")
		)
		(fp_line
			(start 0.674878 1.100074)
			(end -0.674878 1.100074)
			(stroke
				(width 0.1)
				(type default)
			)
			(layer "F.Fab")
		)
		(fp_poly
			(pts
				(xy -2.2352 -0.298958) (xy -2.2352 -1.001014) (xy -1.533144 -0.649986)
			)
			(stroke
				(width 0)
				(type default)
			)
			(fill yes)
			(layer "F.Fab")
		)
		(pad "1" smd rect
			(at -0.94996 -0.649986 90)
			(size 0.4318 0.508)
			(layers "F.Cu" "F.Mask" "F.Paste")
			(net "GND")
		)
		(pad "2" smd rect
			(at -0.94996 0 90)
			(size 0.4318 0.508)
			(layers "F.Cu" "F.Mask" "F.Paste")
			(net "PWRGD_PVCCD_HV_CPU1")
		)
		(pad "3" smd rect
			(at -0.94996 0.649986 90)
			(size 0.4318 0.508)
			(layers "F.Cu" "F.Mask" "F.Paste")
			(net "LED_PWRGD_PVPP_HBM_CPU1_D")
		)
		(pad "4" smd rect
			(at 0.94996 0.649986 90)
			(size 0.4318 0.508)
			(layers "F.Cu" "F.Mask" "F.Paste")
			(net "GND")
		)
		(pad "5" smd rect
			(at 0.94996 0 90)
			(size 0.4318 0.508)
			(layers "F.Cu" "F.Mask" "F.Paste")
			(net "PWRGD_PVPP_HBM_CPU1")
		)
		(pad "6" smd rect
			(at 0.94996 -0.649986 90)
			(size 0.4318 0.508)
			(layers "F.Cu" "F.Mask" "F.Paste")
			(net "LED_PWRGD_PVCCD_HV_CPU1_D")
		)
	)
	(footprint ""
		(layer "F.Cu")
		(at 19.927824 -396.812008 -90)
		(property "Reference" "C2352"
			(at 0 0 270)
			(layer "F.SilkS")
			(hide yes)
			(effects
				(font
					(size 1.27 1.27)
				)
			)
		)
		(property "Value" ""
			(at 0 0 270)
			(layer "F.Fab")
			(effects
				(font
					(size 1.27 1.27)
				)
			)
		)
		(duplicate_pad_numbers_are_jumpers no)
		(fp_line
			(start 0.020828 0.4064)
			(end -0.7874 0.4064)
			(stroke
				(width 0.1524)
				(type default)
			)
			(layer "F.SilkS")
		)
		(fp_line
			(start -0.7874 -0.4064)
			(end 0.7874 -0.4064)
			(stroke
				(width 0.1524)
				(type default)
			)
			(layer "F.SilkS")
		)
		(fp_line
			(start 0.7874 -0.4064)
			(end 0.7874 0.4064)
			(stroke
				(width 0.1524)
				(type default)
			)
			(layer "F.SilkS")
		)
		(fp_line
			(start -0.6858 0.3048)
			(end -0.6858 -0.3048)
			(stroke
				(width 0.1)
				(type default)
			)
			(layer "F.Fab")
		)
		(fp_line
			(start -0.1016 0.3048)
			(end -0.6858 0.3048)
			(stroke
				(width 0.1)
				(type default)
			)
			(layer "F.Fab")
		)
		(fp_line
			(start 0.1016 0.3048)
			(end 0.1016 0.2794)
			(stroke
				(width 0.1)
				(type default)
			)
			(layer "F.Fab")
		)
		(fp_line
			(start 0.6858 0.3048)
			(end 0.1016 0.3048)
			(stroke
				(width 0.1)
				(type default)
			)
			(layer "F.Fab")
		)
		(fp_line
			(start -0.1016 0.2794)
			(end -0.1016 0.3048)
			(stroke
				(width 0.1)
				(type default)
			)
			(layer "F.Fab")
		)
		(fp_line
			(start 0.1016 0.2794)
			(end -0.1016 0.2794)
			(stroke
				(width 0.1)
				(type default)
			)
			(layer "F.Fab")
		)
		(fp_line
			(start -0.1016 -0.2794)
			(end 0.1016 -0.2794)
			(stroke
				(width 0.1)
				(type default)
			)
			(layer "F.Fab")
		)
		(fp_line
			(start 0.1016 -0.2794)
			(end 0.1016 -0.3048)
			(stroke
				(width 0.1)
				(type default)
			)
			(layer "F.Fab")
		)
		(fp_line
			(start -0.6858 -0.3048)
			(end -0.1016 -0.3048)
			(stroke
				(width 0.1)
				(type default)
			)
			(layer "F.Fab")
		)
		(fp_line
			(start -0.1016 -0.3048)
			(end -0.1016 -0.2794)
			(stroke
				(width 0.1)
				(type default)
			)
			(layer "F.Fab")
		)
		(fp_line
			(start 0.1016 -0.3048)
			(end 0.6858 -0.3048)
			(stroke
				(width 0.1)
				(type default)
			)
			(layer "F.Fab")
		)
		(fp_line
			(start 0.6858 -0.3048)
			(end 0.6858 0.3048)
			(stroke
				(width 0.1)
				(type default)
			)
			(layer "F.Fab")
		)
		(pad "1" smd rect
			(at -0.40005 0 90)
			(size 0.4572 0.508)
			(layers "F.Cu" "F.Mask" "F.Paste")
			(net "P2E_MB_BMC_TX_BUF2_DN<0>")
		)
		(pad "2" smd rect
			(at 0.40005 0 90)
			(size 0.4572 0.508)
			(layers "F.Cu" "F.Mask" "F.Paste")
			(net "P2E_MB_BMC_TX_BUF_C_DN<0>")
		)
	)
	(footprint ""
		(layer "F.Cu")
		(at 111.332772 -132.266182)
		(property "Reference" "R3582"
			(at 0 0 0)
			(layer "F.SilkS")
			(hide yes)
			(effects
				(font
					(size 1.27 1.27)
				)
			)
		)
		(property "Value" ""
			(at 0 0 0)
			(layer "F.Fab")
			(effects
				(font
					(size 1.27 1.27)
				)
			)
		)
		(duplicate_pad_numbers_are_jumpers no)
		(fp_line
			(start -0.7874 -0.4064)
			(end 0.7874 -0.4064)
			(stroke
				(width 0.1524)
				(type default)
			)
			(layer "F.SilkS")
		)
		(fp_line
			(start -0.7874 0.4064)
			(end -0.7874 -0.4064)
			(stroke
				(width 0.1524)
				(type default)
			)
			(layer "F.SilkS")
		)
		(fp_line
			(start 0.7874 -0.4064)
			(end 0.7874 0.4064)
			(stroke
				(width 0.1524)
				(type default)
			)
			(layer "F.SilkS")
		)
		(fp_line
			(start 0.7874 0.4064)
			(end -0.7874 0.4064)
			(stroke
				(width 0.1524)
				(type default)
			)
			(layer "F.SilkS")
		)
		(fp_line
			(start -0.67945 -0.305054)
			(end -0.12065 -0.305054)
			(stroke
				(width 0.1)
				(type default)
			)
			(layer "F.Fab")
		)
		(fp_line
			(start -0.67945 0.3048)
			(end -0.67945 -0.305054)
			(stroke
				(width 0.1)
				(type default)
			)
			(layer "F.Fab")
		)
		(fp_line
			(start -0.12065 -0.305054)
			(end -0.12065 -0.2794)
			(stroke
				(width 0.1)
				(type default)
			)
			(layer "F.Fab")
		)
		(fp_line
			(start -0.12065 -0.2794)
			(end 0.12065 -0.2794)
			(stroke
				(width 0.1)
				(type default)
			)
			(layer "F.Fab")
		)
		(fp_line
			(start -0.12065 0.2794)
			(end -0.12065 0.3048)
			(stroke
				(width 0.1)
				(type default)
			)
			(layer "F.Fab")
		)
		(fp_line
			(start -0.12065 0.3048)
			(end -0.67945 0.3048)
			(stroke
				(width 0.1)
				(type default)
			)
			(layer "F.Fab")
		)
		(fp_line
			(start 0.120396 0.2794)
			(end -0.12065 0.2794)
			(stroke
				(width 0.1)
				(type default)
			)
			(layer "F.Fab")
		)
		(fp_line
			(start 0.120396 0.3048)
			(end 0.120396 0.2794)
			(stroke
				(width 0.1)
				(type default)
			)
			(layer "F.Fab")
		)
		(fp_line
			(start 0.12065 -0.3048)
			(end 0.67945 -0.3048)
			(stroke
				(width 0.1)
				(type default)
			)
			(layer "F.Fab")
		)
		(fp_line
			(start 0.12065 -0.2794)
			(end 0.12065 -0.3048)
			(stroke
				(width 0.1)
				(type default)
			)
			(layer "F.Fab")
		)
		(fp_line
			(start 0.67945 -0.3048)
			(end 0.67945 0.3048)
			(stroke
				(width 0.1)
				(type default)
			)
			(layer "F.Fab")
		)
		(fp_line
			(start 0.67945 0.3048)
			(end 0.120396 0.3048)
			(stroke
				(width 0.1)
				(type default)
			)
			(layer "F.Fab")
		)
		(pad "1" smd circle
			(at -0.40005 0)
			(size 0 0)
			(layers "F.Cu" "F.Mask" "F.Paste")
			(net "P3V3_AUX")
		)
		(pad "2" smd circle
			(at 0.40005 0)
			(size 0 0)
			(layers "F.Cu" "F.Mask" "F.Paste")
			(net "SMB_IOEXP_3V3AUX_SCL")
		)
	)
	(footprint ""
		(layer "F.Cu")
		(at 40.389556 -400.153886 -90)
		(property "Reference" "R4648"
			(at 0 0 270)
			(layer "F.SilkS")
			(hide yes)
			(effects
				(font
					(size 1.27 1.27)
				)
			)
		)
		(property "Value" ""
			(at 0 0 270)
			(layer "F.Fab")
			(effects
				(font
					(size 1.27 1.27)
				)
			)
		)
		(duplicate_pad_numbers_are_jumpers no)
		(fp_line
			(start -0.7874 0.4064)
			(end -0.7874 -0.4064)
			(stroke
				(width 0.1524)
				(type default)
			)
			(layer "F.SilkS")
		)
		(fp_line
			(start 0.7874 0.4064)
			(end -0.7874 0.4064)
			(stroke
				(width 0.1524)
				(type default)
			)
			(layer "F.SilkS")
		)
		(fp_line
			(start -0.7874 -0.4064)
			(end 0.7874 -0.4064)
			(stroke
				(width 0.1524)
				(type default)
			)
			(layer "F.SilkS")
		)
		(fp_line
			(start 0.7874 -0.4064)
			(end 0.7874 0.4064)
			(stroke
				(width 0.1524)
				(type default)
			)
			(layer "F.SilkS")
		)
		(fp_line
			(start -0.67945 0.3048)
			(end -0.67945 -0.305054)
			(stroke
				(width 0.1)
				(type default)
			)
			(layer "F.Fab")
		)
		(fp_line
			(start -0.12065 0.3048)
			(end -0.67945 0.3048)
			(stroke
				(width 0.1)
				(type default)
			)
			(layer "F.Fab")
		)
		(fp_line
			(start 0.120396 0.3048)
			(end 0.120396 0.2794)
			(stroke
				(width 0.1)
				(type default)
			)
			(layer "F.Fab")
		)
		(fp_line
			(start 0.67945 0.3048)
			(end 0.120396 0.3048)
			(stroke
				(width 0.1)
				(type default)
			)
			(layer "F.Fab")
		)
		(fp_line
			(start -0.12065 0.2794)
			(end -0.12065 0.3048)
			(stroke
				(width 0.1)
				(type default)
			)
			(layer "F.Fab")
		)
		(fp_line
			(start 0.120396 0.2794)
			(end -0.12065 0.2794)
			(stroke
				(width 0.1)
				(type default)
			)
			(layer "F.Fab")
		)
		(fp_line
			(start -0.12065 -0.2794)
			(end 0.12065 -0.2794)
			(stroke
				(width 0.1)
				(type default)
			)
			(layer "F.Fab")
		)
		(fp_line
			(start 0.12065 -0.2794)
			(end 0.12065 -0.3048)
			(stroke
				(width 0.1)
				(type default)
			)
			(layer "F.Fab")
		)
		(fp_line
			(start 0.12065 -0.3048)
			(end 0.67945 -0.3048)
			(stroke
				(width 0.1)
				(type default)
			)
			(layer "F.Fab")
		)
		(fp_line
			(start 0.67945 -0.3048)
			(end 0.67945 0.3048)
			(stroke
				(width 0.1)
				(type default)
			)
			(layer "F.Fab")
		)
		(fp_line
			(start -0.67945 -0.305054)
			(end -0.12065 -0.305054)
			(stroke
				(width 0.1)
				(type default)
			)
			(layer "F.Fab")
		)
		(fp_line
			(start -0.12065 -0.305054)
			(end -0.12065 -0.2794)
			(stroke
				(width 0.1)
				(type default)
			)
			(layer "F.Fab")
		)
		(pad "1" smd circle
			(at -0.40005 0 270)
			(size 0 0)
			(layers "F.Cu" "F.Mask" "F.Paste")
			(net "P3V3_AUX")
		)
		(pad "2" smd circle
			(at 0.40005 0 270)
			(size 0 0)
			(layers "F.Cu" "F.Mask" "F.Paste")
			(net "FM_P2E_BUF2_EQA1")
		)
	)
	(footprint ""
		(layer "F.Cu")
		(at 194.856608 -405.102822)
		(property "Reference" "PR3916"
			(at 0 0 0)
			(layer "F.SilkS")
			(hide yes)
			(effects
				(font
					(size 1.27 1.27)
				)
			)
		)
		(property "Value" ""
			(at 0 0 0)
			(layer "F.Fab")
			(effects
				(font
					(size 1.27 1.27)
				)
			)
		)
		(duplicate_pad_numbers_are_jumpers no)
		(fp_line
			(start -0.7874 -0.4064)
			(end 0.7874 -0.4064)
			(stroke
				(width 0.1524)
				(type default)
			)
			(layer "F.SilkS")
		)
		(fp_line
			(start -0.7874 0.4064)
			(end -0.7874 -0.4064)
			(stroke
				(width 0.1524)
				(type default)
			)
			(layer "F.SilkS")
		)
		(fp_line
			(start 0.7874 -0.4064)
			(end 0.7874 0.4064)
			(stroke
				(width 0.1524)
				(type default)
			)
			(layer "F.SilkS")
		)
		(fp_line
			(start 0.7874 0.4064)
			(end -0.7874 0.4064)
			(stroke
				(width 0.1524)
				(type default)
			)
			(layer "F.SilkS")
		)
		(fp_line
			(start -0.67945 -0.305054)
			(end -0.12065 -0.305054)
			(stroke
				(width 0.1)
				(type default)
			)
			(layer "F.Fab")
		)
		(fp_line
			(start -0.67945 0.3048)
			(end -0.67945 -0.305054)
			(stroke
				(width 0.1)
				(type default)
			)
			(layer "F.Fab")
		)
		(fp_line
			(start -0.12065 -0.305054)
			(end -0.12065 -0.2794)
			(stroke
				(width 0.1)
				(type default)
			)
			(layer "F.Fab")
		)
		(fp_line
			(start -0.12065 -0.2794)
			(end 0.12065 -0.2794)
			(stroke
				(width 0.1)
				(type default)
			)
			(layer "F.Fab")
		)
		(fp_line
			(start -0.12065 0.2794)
			(end -0.12065 0.3048)
			(stroke
				(width 0.1)
				(type default)
			)
			(layer "F.Fab")
		)
		(fp_line
			(start -0.12065 0.3048)
			(end -0.67945 0.3048)
			(stroke
				(width 0.1)
				(type default)
			)
			(layer "F.Fab")
		)
		(fp_line
			(start 0.120396 0.2794)
			(end -0.12065 0.2794)
			(stroke
				(width 0.1)
				(type default)
			)
			(layer "F.Fab")
		)
		(fp_line
			(start 0.120396 0.3048)
			(end 0.120396 0.2794)
			(stroke
				(width 0.1)
				(type default)
			)
			(layer "F.Fab")
		)
		(fp_line
			(start 0.12065 -0.3048)
			(end 0.67945 -0.3048)
			(stroke
				(width 0.1)
				(type default)
			)
			(layer "F.Fab")
		)
		(fp_line
			(start 0.12065 -0.2794)
			(end 0.12065 -0.3048)
			(stroke
				(width 0.1)
				(type default)
			)
			(layer "F.Fab")
		)
		(fp_line
			(start 0.67945 -0.3048)
			(end 0.67945 0.3048)
			(stroke
				(width 0.1)
				(type default)
			)
			(layer "F.Fab")
		)
		(fp_line
			(start 0.67945 0.3048)
			(end 0.120396 0.3048)
			(stroke
				(width 0.1)
				(type default)
			)
			(layer "F.Fab")
		)
		(pad "1" smd circle
			(at -0.40005 0)
			(size 0 0)
			(layers "F.Cu" "F.Mask" "F.Paste")
			(net "HSC_SCREF")
		)
		(pad "2" smd circle
			(at 0.40005 0)
			(size 0 0)
			(layers "F.Cu" "F.Mask" "F.Paste")
			(net "HSC_SCREF_1")
		)
	)
	(footprint ""
		(layer "F.Cu")
		(at 160.402016 -10.850118 -90)
		(property "Reference" "J41"
			(at -12.075414 24.511762 0)
			(unlocked yes)
			(layer "F.SilkS")
			(effects
				(font
					(size 0.7874 0.5842)
					(thickness 0.1524)
				)
				(justify left)
			)
		)
		(property "Value" ""
			(at 0 0 270)
			(layer "F.Fab")
			(effects
				(font
					(size 1.27 1.27)
				)
			)
		)
		(duplicate_pad_numbers_are_jumpers no)
		(fp_line
			(start -7.420102 34.360104)
			(end 6.210046 34.360104)
			(stroke
				(width 0.1524)
				(type default)
			)
			(layer "F.SilkS")
		)
		(fp_line
			(start 6.210046 34.360104)
			(end 6.210046 -34.360104)
			(stroke
				(width 0.1524)
				(type default)
			)
			(layer "F.SilkS")
		)
		(fp_line
			(start -5.5499 33.8201)
			(end 5.5499 33.8201)
			(stroke
				(width 0.1524)
				(type default)
			)
			(layer "F.SilkS")
		)
		(fp_line
			(start 5.5499 33.8201)
			(end 5.5499 -33.8201)
			(stroke
				(width 0.1524)
				(type default)
			)
			(layer "F.SilkS")
		)
		(fp_line
			(start -5.5499 30.97784)
			(end -5.5499 33.8201)
			(stroke
				(width 0.1524)
				(type default)
			)
			(layer "F.SilkS")
		)
		(fp_line
			(start -7.420102 28.672536)
			(end -7.420102 34.360104)
			(stroke
				(width 0.1524)
				(type default)
			)
			(layer "F.SilkS")
		)
		(fp_line
			(start -7.420102 24.928576)
			(end -7.420102 27.306016)
			(stroke
				(width 0.1524)
				(type default)
			)
			(layer "F.SilkS")
		)
		(fp_line
			(start -7.420102 23.475696)
			(end -7.420102 24.031956)
			(stroke
				(width 0.1524)
				(type default)
			)
			(layer "F.SilkS")
		)
		(fp_line
			(start -7.420102 21.270976)
			(end -7.420102 21.644356)
			(stroke
				(width 0.1524)
				(type default)
			)
			(layer "F.SilkS")
		)
		(fp_line
			(start -7.420102 19.719036)
			(end -7.420102 20.392136)
			(stroke
				(width 0.1524)
				(type default)
			)
			(layer "F.SilkS")
		)
		(fp_line
			(start -5.5499 9.8806)
			(end -5.5499 14.13256)
			(stroke
				(width 0.1524)
				(type default)
			)
			(layer "F.SilkS")
		)
		(fp_line
			(start -5.5499 -1.9304)
			(end -5.5499 1.4224)
			(stroke
				(width 0.1524)
				(type default)
			)
			(layer "F.SilkS")
		)
		(fp_line
			(start -5.5499 -22.5425)
			(end -5.5499 -18.7833)
			(stroke
				(width 0.1524)
				(type default)
			)
			(layer "F.SilkS")
		)
		(fp_line
			(start -7.420102 -25.297384)
			(end -7.420102 18.210276)
			(stroke
				(width 0.1524)
				(type default)
			)
			(layer "F.SilkS")
		)
		(fp_line
			(start -5.5499 -33.8201)
			(end -5.5499 -30.988)
			(stroke
				(width 0.1524)
				(type default)
			)
			(layer "F.SilkS")
		)
		(fp_line
			(start 5.5499 -33.8201)
			(end -5.5499 -33.8201)
			(stroke
				(width 0.1524)
				(type default)
			)
			(layer "F.SilkS")
		)
		(fp_line
			(start -7.420102 -34.360104)
			(end -7.420102 -27.072844)
			(stroke
				(width 0.1524)
				(type default)
			)
			(layer "F.SilkS")
		)
		(fp_line
			(start 6.210046 -34.360104)
			(end -7.420102 -34.360104)
			(stroke
				(width 0.1524)
				(type default)
			)
			(layer "F.SilkS")
		)
		(fp_poly
			(pts
				(xy 5.36448 -17.832578) (xy 5.36448 -18.848578) (xy 4.34848 -18.340578)
			)
			(stroke
				(width 0)
				(type default)
			)
			(fill yes)
			(layer "F.SilkS")
		)
		(fp_line
			(start -5.5499 33.8201)
			(end 5.5499 33.8201)
			(stroke
				(width 0.1)
				(type default)
			)
			(layer "F.Fab")
		)
		(fp_line
			(start 5.5499 33.8201)
			(end 5.5499 -33.8201)
			(stroke
				(width 0.1)
				(type default)
			)
			(layer "F.Fab")
		)
		(fp_line
			(start -5.5499 -33.8201)
			(end -5.5499 33.8201)
			(stroke
				(width 0.1)
				(type default)
			)
			(layer "F.Fab")
		)
		(fp_line
			(start 5.5499 -33.8201)
			(end -5.5499 -33.8201)
			(stroke
				(width 0.1)
				(type default)
			)
			(layer "F.Fab")
		)
		(fp_poly
			(pts
				(xy 7.4168 -17.957038) (xy 7.4168 -18.973038) (xy 6.4008 -18.465038)
			)
			(stroke
				(width 0)
				(type default)
			)
			(fill yes)
			(layer "F.Fab")
		)
		(pad "" np_thru_hole circle
			(at -0.599948 -32.079946 180)
			(size 1.1176 1.1176)
			(drill 1.1176)
			(layers "*.Cu" "*.Mask")
			(clearance 0.381)
			(thermal_gap 0.381)
		)
		(pad "" np_thru_hole circle
			(at 0.40005 32.085026 180)
			(size 1.1176 1.1176)
			(drill 1.1176)
			(layers "*.Cu" "*.Mask")
			(clearance 0.381)
			(thermal_gap 0.381)
		)
		(pad "A1" smd rect
			(at -2.750058 -18.465038 180)
			(size 0.381 1.4478)
			(layers "F.Cu" "F.Mask" "F.Paste")
			(net "SMB_OCP_SFF_3V3AUX_SCL_R0")
		)
		(pad "A2" smd rect
			(at -2.750058 -17.86509 180)
			(size 0.381 1.4478)
			(layers "F.Cu" "F.Mask" "F.Paste")
			(net "SMB_OCP_SFF_3V3AUX_SDA_R0")
		)
		(pad "A3" smd rect
			(at -2.750058 -17.264888 180)
			(size 0.381 1.4478)
			(layers "F.Cu" "F.Mask" "F.Paste")
			(net "SMB_HOST_3V3AUX_SCL_R0")
		)
		(pad "A4" smd rect
			(at -2.750058 -16.66494 180)
			(size 0.381 1.4478)
			(layers "F.Cu" "F.Mask" "F.Paste")
			(net "SMB_HOST_3V3AUX_SDA_R0")
		)
		(pad "A5" smd rect
			(at -2.750058 -16.064992 180)
			(size 0.381 1.4478)
			(layers "F.Cu" "F.Mask" "F.Paste")
			(net "SMB_VR_3V3AUX_SCL_R0")
		)
		(pad "A6" smd rect
			(at -2.750058 -15.465044 180)
			(size 0.381 1.4478)
			(layers "F.Cu" "F.Mask" "F.Paste")
			(net "SMB_VR_3V3AUX_SDA_R0")
		)
		(pad "A7" smd rect
			(at -2.750058 -14.865096 180)
			(size 0.381 1.4478)
			(layers "F.Cu" "F.Mask" "F.Paste")
			(net "SMB_SML1_PMBUS_3V3AUX_PCH_SCL_R")
		)
		(pad "A8" smd rect
			(at -2.750058 -14.264894 180)
			(size 0.381 1.4478)
			(layers "F.Cu" "F.Mask" "F.Paste")
			(net "SMB_SML1_PMBUS_3V3AUX_PCH_SDA_R")
		)
		(pad "A9" smd rect
			(at -2.750058 -13.664946 180)
			(size 0.381 1.4478)
			(layers "F.Cu" "F.Mask" "F.Paste")
			(net "I3C_BMC_SWB_SCL")
		)
		(pad "A10" smd rect
			(at -2.750058 -13.064998 180)
			(size 0.381 1.4478)
			(layers "F.Cu" "F.Mask" "F.Paste")
			(net "I3C_BMC_SWB_SDA")
		)
		(pad "A11" smd rect
			(at -2.750058 -12.46505 180)
			(size 0.381 1.4478)
			(layers "F.Cu" "F.Mask" "F.Paste")
			(net "SMB_OCP_V3_2_3V3AUX_SCL_R0")
		)
		(pad "A12" smd rect
			(at -2.750058 -11.865102 180)
			(size 0.381 1.4478)
			(layers "F.Cu" "F.Mask" "F.Paste")
			(net "SMB_OCP_V3_2_3V3AUX_SDA_R0")
		)
		(pad "A13" smd rect
			(at -2.750058 -11.2649 180)
			(size 0.381 1.4478)
			(layers "F.Cu" "F.Mask" "F.Paste")
			(net "GND")
		)
		(pad "A14" smd rect
			(at -2.750058 -10.664952 180)
			(size 0.381 1.4478)
			(layers "F.Cu" "F.Mask" "F.Paste")
			(net "CLK_100M_BMC_P3E_DP_R")
		)
		(pad "A15" smd rect
			(at -2.750058 -10.065004 180)
			(size 0.381 1.4478)
			(layers "F.Cu" "F.Mask" "F.Paste")
			(net "CLK_100M_BMC_P3E_DN_R")
		)
		(pad "A16" smd rect
			(at -2.750058 -9.465056 180)
			(size 0.381 1.4478)
			(layers "F.Cu" "F.Mask" "F.Paste")
			(net "GND")
		)
		(pad "A17" smd rect
			(at -2.750058 -8.865108 180)
			(size 0.381 1.4478)
			(layers "F.Cu" "F.Mask" "F.Paste")
			(net "P3E_PCH_BMC_TX_C_DP")
		)
		(pad "A18" smd rect
			(at -2.750058 -8.264906 180)
			(size 0.381 1.4478)
			(layers "F.Cu" "F.Mask" "F.Paste")
			(net "P3E_PCH_BMC_TX_C_DN")
		)
		(pad "A19" smd rect
			(at -2.750058 -7.664958 180)
			(size 0.381 1.4478)
			(layers "F.Cu" "F.Mask" "F.Paste")
			(net "GND")
		)
		(pad "A20" smd rect
			(at -2.750058 -7.06501 180)
			(size 0.381 1.4478)
			(layers "F.Cu" "F.Mask" "F.Paste")
			(net "P3E_PCH_BMC_RX_DP")
		)
		(pad "A21" smd rect
			(at -2.750058 -6.465062 180)
			(size 0.381 1.4478)
			(layers "F.Cu" "F.Mask" "F.Paste")
			(net "P3E_PCH_BMC_RX_DN")
		)
		(pad "A22" smd rect
			(at -2.750058 -5.865114 180)
			(size 0.381 1.4478)
			(layers "F.Cu" "F.Mask" "F.Paste")
			(net "GND")
		)
		(pad "A23" smd rect
			(at -2.750058 -5.264912 180)
			(size 0.381 1.4478)
			(layers "F.Cu" "F.Mask" "F.Paste")
			(net "SMB_PCIE0_3V3AUX_SCL")
		)
		(pad "A24" smd rect
			(at -2.750058 -4.664964 180)
			(size 0.381 1.4478)
			(layers "F.Cu" "F.Mask" "F.Paste")
			(net "SMB_PCIE0_3V3AUX_SDA")
		)
		(pad "A25" smd rect
			(at -2.750058 -4.065016 180)
			(size 0.381 1.4478)
			(layers "F.Cu" "F.Mask" "F.Paste")
			(net "SMB_SML0_3V3AUX_SCL_R1")
		)
		(pad "A26" smd rect
			(at -2.750058 -3.465068 180)
			(size 0.381 1.4478)
			(layers "F.Cu" "F.Mask" "F.Paste")
			(net "SMB_SML0_3V3AUX_SDA_R1")
		)
		(pad "A27" smd rect
			(at -2.750058 -2.86512 180)
			(size 0.381 1.4478)
			(layers "F.Cu" "F.Mask" "F.Paste")
			(net "SMB_1_PLD_3V3AUX_SCL_R3")
		)
		(pad "A28" smd rect
			(at -2.750058 -2.264918 180)
			(size 0.381 1.4478)
			(layers "F.Cu" "F.Mask" "F.Paste")
			(net "SMB_1_PLD_3V3AUX_SDA_R3")
		)
		(pad "A29" smd rect
			(at -2.750058 1.74498 180)
			(size 0.381 1.4478)
			(layers "F.Cu" "F.Mask" "F.Paste")
			(net "SMB_FAN_3V3AUX_SCL")
		)
		(pad "A30" smd rect
			(at -2.750058 2.344928 180)
			(size 0.381 1.4478)
			(layers "F.Cu" "F.Mask" "F.Paste")
			(net "SMB_FAN_3V3AUX_SDA")
		)
		(pad "A31" smd rect
			(at -2.750058 2.944876 180)
			(size 0.381 1.4478)
			(layers "F.Cu" "F.Mask" "F.Paste")
			(net "SMB_PCIE2_3V3AUX_SCL_R0")
		)
		(pad "A32" smd rect
			(at -2.750058 3.545078 180)
			(size 0.381 1.4478)
			(layers "F.Cu" "F.Mask" "F.Paste")
			(net "SMB_PCIE2_3V3AUX_SDA_R0")
		)
		(pad "A33" smd rect
			(at -2.750058 4.145026 180)
			(size 0.381 1.4478)
			(layers "F.Cu" "F.Mask" "F.Paste")
			(net "GND")
		)
		(pad "A34" smd rect
			(at -2.750058 4.744974 180)
			(size 0.381 1.4478)
			(layers "F.Cu" "F.Mask" "F.Paste")
			(net "JTAG_BMC_TCK")
		)
		(pad "A35" smd rect
			(at -2.750058 5.344922 180)
			(size 0.381 1.4478)
			(layers "F.Cu" "F.Mask" "F.Paste")
			(net "JTAG_BMC_TMS")
		)
		(pad "A36" smd rect
			(at -2.750058 5.945124 180)
			(size 0.381 1.4478)
			(layers "F.Cu" "F.Mask" "F.Paste")
			(net "JTAG_BMC_TDI")
		)
		(pad "A37" smd rect
			(at -2.750058 6.545072 180)
			(size 0.381 1.4478)
			(layers "F.Cu" "F.Mask" "F.Paste")
			(net "JTAG_BMC_TDO")
		)
		(pad "A38" smd rect
			(at -2.750058 7.14502 180)
			(size 0.381 1.4478)
			(layers "F.Cu" "F.Mask" "F.Paste")
			(net "SMB_PCIE3_3V3AUX_SCL_R")
		)
		(pad "A39" smd rect
			(at -2.750058 7.744968 180)
			(size 0.381 1.4478)
			(layers "F.Cu" "F.Mask" "F.Paste")
			(net "SMB_PCIE3_3V3AUX_SDA_R")
		)
		(pad "A40" smd rect
			(at -2.750058 8.344916 180)
			(size 0.381 1.4478)
			(layers "F.Cu" "F.Mask" "F.Paste")
			(net "SMB_S3M_CPU_3V3AUX_SCL_R0")
		)
		(pad "A41" smd rect
			(at -2.750058 8.945118 180)
			(size 0.381 1.4478)
			(layers "F.Cu" "F.Mask" "F.Paste")
			(net "SMB_S3M_CPU_3V3AUX_SDA_R0")
		)
		(pad "A42" smd rect
			(at -2.750058 9.545066 180)
			(size 0.381 1.4478)
			(layers "F.Cu" "F.Mask" "F.Paste")
			(net "GND")
		)
		(pad "A43" smd rect
			(at -2.750058 14.454886 180)
			(size 0.381 1.4478)
			(layers "F.Cu" "F.Mask" "F.Paste")
			(net "FM_JTAG_BMC_MUX_SEL_FROM_BMC_R2")
		)
		(pad "A44" smd rect
			(at -2.750058 15.055088 180)
			(size 0.381 1.4478)
			(layers "F.Cu" "F.Mask" "F.Paste")
			(net "PWRGD_PS_PWROK_R")
		)
		(pad "A45" smd rect
			(at -2.750058 15.655036 180)
			(size 0.381 1.4478)
			(layers "F.Cu" "F.Mask" "F.Paste")
			(net "TP_HPM_STBY_EN")
		)
		(pad "A46" smd rect
			(at -2.750058 16.254984 180)
			(size 0.381 1.4478)
			(layers "F.Cu" "F.Mask" "F.Paste")
			(net "RST_MB_STBY_N")
		)
		(pad "A47" smd rect
			(at -2.750058 16.854932 180)
			(size 0.381 1.4478)
			(layers "F.Cu" "F.Mask" "F.Paste")
			(net "FM_BMC_PWRBTN_OUT_R_N")
		)
		(pad "A48" smd rect
			(at -2.750058 17.45488 180)
			(size 0.381 1.4478)
			(layers "F.Cu" "F.Mask" "F.Paste")
			(net "PWRGD_SYS_PWROK")
		)
		(pad "A49" smd rect
			(at -2.750058 18.055082 180)
			(size 0.381 1.4478)
			(layers "F.Cu" "F.Mask" "F.Paste")
			(net "JTAG_BMC_DBP_PREQ_N")
		)
		(pad "A50" smd rect
			(at -2.750058 18.65503 180)
			(size 0.381 1.4478)
			(layers "F.Cu" "F.Mask" "F.Paste")
			(net "JTAG_DBP_BMC_PRDY_N")
		)
		(pad "A51" smd rect
			(at -2.750058 19.254978 180)
			(size 0.381 1.4478)
			(layers "F.Cu" "F.Mask" "F.Paste")
			(net "RST_PLTRST_B_N")
		)
		(pad "A52" smd rect
			(at -2.750058 19.854926 180)
			(size 0.381 1.4478)
			(layers "F.Cu" "F.Mask" "F.Paste")
			(net "FM_UARTSW_MSB_R")
		)
		(pad "A53" smd rect
			(at -2.750058 20.455128 180)
			(size 0.381 1.4478)
			(layers "F.Cu" "F.Mask" "F.Paste")
			(net "ROT_P1_RST_IND_N")
		)
		(pad "A54" smd rect
			(at -2.750058 21.055076 180)
			(size 0.381 1.4478)
			(layers "F.Cu" "F.Mask" "F.Paste")
			(net "FM_BMC_INTRUDER_N")
		)
		(pad "A55" smd rect
			(at -2.750058 21.655024 180)
			(size 0.381 1.4478)
			(layers "F.Cu" "F.Mask" "F.Paste")
			(net "FM_UARTSW_LSB_R")
		)
		(pad "A56" smd rect
			(at -2.750058 22.254972 180)
			(size 0.381 1.4478)
			(layers "F.Cu" "F.Mask" "F.Paste")
			(net "IRQ0_A57")
		)
		(pad "A57" smd rect
			(at -2.750058 22.85492 180)
			(size 0.381 1.4478)
			(layers "F.Cu" "F.Mask" "F.Paste")
			(net "FM_SCM_PRSNT1_N")
		)
		(pad "A58" smd rect
			(at -2.750058 23.455122 180)
			(size 0.381 1.4478)
			(layers "F.Cu" "F.Mask" "F.Paste")
			(net "GND")
		)
		(pad "A59" smd rect
			(at -2.750058 24.05507 180)
			(size 0.381 1.4478)
			(layers "F.Cu" "F.Mask" "F.Paste")
			(net "USB3_PCH_RX_DP<4>")
		)
		(pad "A60" smd rect
			(at -2.750058 24.655018 180)
			(size 0.381 1.4478)
			(layers "F.Cu" "F.Mask" "F.Paste")
			(net "USB3_PCH_RX_DN<4>")
		)
		(pad "A61" smd rect
			(at -2.750058 25.254966 180)
			(size 0.381 1.4478)
			(layers "F.Cu" "F.Mask" "F.Paste")
			(net "GND")
		)
		(pad "A62" smd rect
			(at -2.750058 25.854914 180)
			(size 0.381 1.4478)
			(layers "F.Cu" "F.Mask" "F.Paste")
			(net "TP_PCIE_HPM_RXP<1>")
		)
		(pad "A63" smd rect
			(at -2.750058 26.455116 180)
			(size 0.381 1.4478)
			(layers "F.Cu" "F.Mask" "F.Paste")
			(net "TP_PCIE_HPM_RXN<1>")
		)
		(pad "A64" smd rect
			(at -2.750058 27.055064 180)
			(size 0.381 1.4478)
			(layers "F.Cu" "F.Mask" "F.Paste")
			(net "GND")
		)
		(pad "A65" smd rect
			(at -2.750058 27.655012 180)
			(size 0.381 1.4478)
			(layers "F.Cu" "F.Mask" "F.Paste")
			(net "P2E_MB_BMC_RX_BUF_DP<0>")
		)
		(pad "A66" smd rect
			(at -2.750058 28.25496 180)
			(size 0.381 1.4478)
			(layers "F.Cu" "F.Mask" "F.Paste")
			(net "P2E_MB_BMC_RX_BUF_DN<0>")
		)
		(pad "A67" smd rect
			(at -2.750058 28.854908 180)
			(size 0.381 1.4478)
			(layers "F.Cu" "F.Mask" "F.Paste")
			(net "GND")
		)
		(pad "A68" smd rect
			(at -2.750058 29.45511 180)
			(size 0.381 1.4478)
			(layers "F.Cu" "F.Mask" "F.Paste")
			(net "CLK_100M_BMC_RC_DP")
		)
		(pad "A69" smd rect
			(at -2.750058 30.055058 180)
			(size 0.381 1.4478)
			(layers "F.Cu" "F.Mask" "F.Paste")
			(net "CLK_100M_BMC_RC_DN")
		)
		(pad "A70" smd rect
			(at -2.750058 30.655006 180)
			(size 0.381 1.4478)
			(layers "F.Cu" "F.Mask" "F.Paste")
			(net "GND")
		)
		(pad "B1" smd rect
			(at -5.700014 -18.465038 180)
			(size 0.381 1.4478)
			(layers "F.Cu" "F.Mask" "F.Paste")
			(net "ESPI_HOST_LPC_BMC_CLK")
		)
		(pad "B2" smd rect
			(at -5.700014 -17.86509 180)
			(size 0.381 1.4478)
			(layers "F.Cu" "F.Mask" "F.Paste")
			(net "ESPI_HOST_LPC_BMC_LFRAME_N")
		)
		(pad "B3" smd rect
			(at -5.700014 -17.264888 180)
			(size 0.381 1.4478)
			(layers "F.Cu" "F.Mask" "F.Paste")
			(net "IRQ_ESPI_LPC_SERIRQ_ALERT_R_N")
		)
		(pad "B4" smd rect
			(at -5.700014 -16.66494 180)
			(size 0.381 1.4478)
			(layers "F.Cu" "F.Mask" "F.Paste")
			(net "ESPI_BMC_LPC_RST_N")
		)
		(pad "B5" smd rect
			(at -5.700014 -16.064992 180)
			(size 0.381 1.4478)
			(layers "F.Cu" "F.Mask" "F.Paste")
			(net "ESPI_LPC_LAD0_IO0")
		)
		(pad "B6" smd rect
			(at -5.700014 -15.465044 180)
			(size 0.381 1.4478)
			(layers "F.Cu" "F.Mask" "F.Paste")
			(net "ESPI_LPC_LAD0_IO1")
		)
		(pad "B7" smd rect
			(at -5.700014 -14.865096 180)
			(size 0.381 1.4478)
			(layers "F.Cu" "F.Mask" "F.Paste")
			(net "ESPI_LPC_LAD0_IO2")
		)
		(pad "B8" smd rect
			(at -5.700014 -14.264894 180)
			(size 0.381 1.4478)
			(layers "F.Cu" "F.Mask" "F.Paste")
			(net "ESPI_LPC_LAD0_IO3")
		)
		(pad "B9" smd rect
			(at -5.700014 -13.664946 180)
			(size 0.381 1.4478)
			(layers "F.Cu" "F.Mask" "F.Paste")
			(net "FM_LPC_ESPI_SEL")
		)
		(pad "B10" smd rect
			(at -5.700014 -13.064998 180)
			(size 0.381 1.4478)
			(layers "F.Cu" "F.Mask" "F.Paste")
			(net "GND")
		)
		(pad "B11" smd rect
			(at -5.700014 -12.46505 180)
			(size 0.381 1.4478)
			(layers "F.Cu" "F.Mask" "F.Paste")
			(net "SPI_SYS_CLK")
		)
		(pad "B12" smd rect
			(at -5.700014 -11.865102 180)
			(size 0.381 1.4478)
			(layers "F.Cu" "F.Mask" "F.Paste")
			(net "SPI_SYS_CS0_N")
		)
		(pad "B13" smd rect
			(at -5.700014 -11.2649 180)
			(size 0.381 1.4478)
			(layers "F.Cu" "F.Mask" "F.Paste")
			(net "SPI_SYS_MOSI")
		)
		(pad "B14" smd rect
			(at -5.700014 -10.664952 180)
			(size 0.381 1.4478)
			(layers "F.Cu" "F.Mask" "F.Paste")
			(net "SPI_SYS_MISO")
		)
		(pad "B15" smd rect
			(at -5.700014 -10.065004 180)
			(size 0.381 1.4478)
			(layers "F.Cu" "F.Mask" "F.Paste")
			(net "SPI_SYS_WP_IO2")
		)
		(pad "B16" smd rect
			(at -5.700014 -9.465056 180)
			(size 0.381 1.4478)
			(layers "F.Cu" "F.Mask" "F.Paste")
			(net "SPI_SYS_HOLD_IO3")
		)
		(pad "B17" smd rect
			(at -5.700014 -8.865108 180)
			(size 0.381 1.4478)
			(layers "F.Cu" "F.Mask" "F.Paste")
			(net "GND")
		)
		(pad "B18" smd rect
			(at -5.700014 -8.264906 180)
			(size 0.381 1.4478)
			(layers "F.Cu" "F.Mask" "F.Paste")
			(net "CLK_50M_RMII_BMC_OCP")
		)
		(pad "B19" smd rect
			(at -5.700014 -7.664958 180)
			(size 0.381 1.4478)
			(layers "F.Cu" "F.Mask" "F.Paste")
			(net "RMII_OCP_BMC_CRSDV")
		)
		(pad "B20" smd rect
			(at -5.700014 -7.06501 180)
			(size 0.381 1.4478)
			(layers "F.Cu" "F.Mask" "F.Paste")
			(net "RMII_BMC_OCP_TX_EN")
		)
		(pad "B21" smd rect
			(at -5.700014 -6.465062 180)
			(size 0.381 1.4478)
			(layers "F.Cu" "F.Mask" "F.Paste")
			(net "RMII_BMC_OCP_TXD_0")
		)
		(pad "B22" smd rect
			(at -5.700014 -5.865114 180)
			(size 0.381 1.4478)
			(layers "F.Cu" "F.Mask" "F.Paste")
			(net "RMII_BMC_OCP_TXD_1")
		)
		(pad "B23" smd rect
			(at -5.700014 -5.264912 180)
			(size 0.381 1.4478)
			(layers "F.Cu" "F.Mask" "F.Paste")
			(net "RMII_BMC_OCP_RX_ER")
		)
		(pad "B24" smd rect
			(at -5.700014 -4.664964 180)
			(size 0.381 1.4478)
			(layers "F.Cu" "F.Mask" "F.Paste")
			(net "RMII_OCP_BMC_RXD_0")
		)
		(pad "B25" smd rect
			(at -5.700014 -4.065016 180)
			(size 0.381 1.4478)
			(layers "F.Cu" "F.Mask" "F.Paste")
			(net "RMII_OCP_BMC_RXD_1")
		)
		(pad "B26" smd rect
			(at -5.700014 -3.465068 180)
			(size 0.381 1.4478)
			(layers "F.Cu" "F.Mask" "F.Paste")
			(net "GND")
		)
		(pad "B27" smd rect
			(at -5.700014 -2.86512 180)
			(size 0.381 1.4478)
			(layers "F.Cu" "F.Mask" "F.Paste")
			(net "PECI_BMC")
		)
		(pad "B28" smd rect
			(at -5.700014 -2.264918 180)
			(size 0.381 1.4478)
			(layers "F.Cu" "F.Mask" "F.Paste")
			(net "PVCCIO_PECI_BMC")
		)
		(pad "B29" smd rect
			(at -5.700014 1.74498 180)
			(size 0.381 1.4478)
			(layers "F.Cu" "F.Mask" "F.Paste")
			(net "SGPIO_DO_0")
		)
		(pad "B30" smd rect
			(at -5.700014 2.344928 180)
			(size 0.381 1.4478)
			(layers "F.Cu" "F.Mask" "F.Paste")
			(net "SGPIO_CLK_0")
		)
		(pad "B31" smd rect
			(at -5.700014 2.944876 180)
			(size 0.381 1.4478)
			(layers "F.Cu" "F.Mask" "F.Paste")
			(net "SGPIO_DI_0")
		)
		(pad "B32" smd rect
			(at -5.700014 3.545078 180)
			(size 0.381 1.4478)
			(layers "F.Cu" "F.Mask" "F.Paste")
			(net "SGPIO_LD_0")
		)
		(pad "B33" smd rect
			(at -5.700014 4.145026 180)
			(size 0.381 1.4478)
			(layers "F.Cu" "F.Mask" "F.Paste")
			(net "GND")
		)
		(pad "B34" smd rect
			(at -5.700014 4.744974 180)
			(size 0.381 1.4478)
			(layers "F.Cu" "F.Mask" "F.Paste")
			(net "SGPIO_DO_1")
		)
		(pad "B35" smd rect
			(at -5.700014 5.344922 180)
			(size 0.381 1.4478)
			(layers "F.Cu" "F.Mask" "F.Paste")
			(net "SGPIO_CLK_1")
		)
		(pad "B36" smd rect
			(at -5.700014 5.945124 180)
			(size 0.381 1.4478)
			(layers "F.Cu" "F.Mask" "F.Paste")
			(net "SGPIO_DI_1")
		)
		(pad "B37" smd rect
			(at -5.700014 6.545072 180)
			(size 0.381 1.4478)
			(layers "F.Cu" "F.Mask" "F.Paste")
			(net "SGPIO_LD_1")
		)
		(pad "B38" smd rect
			(at -5.700014 7.14502 180)
			(size 0.381 1.4478)
			(layers "F.Cu" "F.Mask" "F.Paste")
			(net "GND")
		)
		(pad "B39" smd rect
			(at -5.700014 7.744968 180)
			(size 0.381 1.4478)
			(layers "F.Cu" "F.Mask" "F.Paste")
			(net "RST_SGPIO_RESET_N")
		)
		(pad "B40" smd rect
			(at -5.700014 8.344916 180)
			(size 0.381 1.4478)
			(layers "F.Cu" "F.Mask" "F.Paste")
			(net "IRQ_SGPIO_INTR_N")
		)
		(pad "B41" smd rect
			(at -5.700014 8.945118 180)
			(size 0.381 1.4478)
			(layers "F.Cu" "F.Mask" "F.Paste")
			(net "P3V_BAT_R1")
		)
		(pad "B42" smd rect
			(at -5.700014 9.545066 180)
			(size 0.381 1.4478)
			(layers "F.Cu" "F.Mask" "F.Paste")
			(net "FM_AC_PWR_BTN_N")
		)
		(pad "B43" smd rect
			(at -5.700014 14.454886 180)
			(size 0.381 1.4478)
			(layers "F.Cu" "F.Mask" "F.Paste")
			(net "TP_SPI_2_PLD_CLK")
		)
		(pad "B44" smd rect
			(at -5.700014 15.055088 180)
			(size 0.381 1.4478)
			(layers "F.Cu" "F.Mask" "F.Paste")
			(net "TP_SPI_2_PLD_CS_N")
		)
		(pad "B45" smd rect
			(at -5.700014 15.655036 180)
			(size 0.381 1.4478)
			(layers "F.Cu" "F.Mask" "F.Paste")
			(net "TP_SPI_2_PLD_IO0")
		)
		(pad "B46" smd rect
			(at -5.700014 16.254984 180)
			(size 0.381 1.4478)
			(layers "F.Cu" "F.Mask" "F.Paste")
			(net "TP_SPI_2_PLD_IO1")
		)
		(pad "B47" smd rect
			(at -5.700014 16.854932 180)
			(size 0.381 1.4478)
			(layers "F.Cu" "F.Mask" "F.Paste")
			(net "TP_SPI_2_PLD_IO2")
		)
		(pad "B48" smd rect
			(at -5.700014 17.45488 180)
			(size 0.381 1.4478)
			(layers "F.Cu" "F.Mask" "F.Paste")
			(net "TP_SPI_2_PLD_IO3")
		)
		(pad "B49" smd rect
			(at -5.700014 18.055082 180)
			(size 0.381 1.4478)
			(layers "F.Cu" "F.Mask" "F.Paste")
			(net "GND")
		)
		(pad "B50" smd rect
			(at -5.700014 18.65503 180)
			(size 0.381 1.4478)
			(layers "F.Cu" "F.Mask" "F.Paste")
			(net "USB2_HOST_BMC_B_DP")
		)
		(pad "B51" smd rect
			(at -5.700014 19.254978 180)
			(size 0.381 1.4478)
			(layers "F.Cu" "F.Mask" "F.Paste")
			(net "USB2_HOST_BMC_B_DN")
		)
		(pad "B52" smd rect
			(at -5.700014 19.854926 180)
			(size 0.381 1.4478)
			(layers "F.Cu" "F.Mask" "F.Paste")
			(net "GND")
		)
		(pad "B53" smd rect
			(at -5.700014 20.455128 180)
			(size 0.381 1.4478)
			(layers "F.Cu" "F.Mask" "F.Paste")
			(net "USB2_8_DP")
		)
		(pad "B54" smd rect
			(at -5.700014 21.055076 180)
			(size 0.381 1.4478)
			(layers "F.Cu" "F.Mask" "F.Paste")
			(net "USB2_8_DN")
		)
		(pad "B55" smd rect
			(at -5.700014 21.655024 180)
			(size 0.381 1.4478)
			(layers "F.Cu" "F.Mask" "F.Paste")
			(net "GND")
		)
		(pad "B56" smd rect
			(at -5.700014 22.254972 180)
			(size 0.381 1.4478)
			(layers "F.Cu" "F.Mask" "F.Paste")
			(net "USB2_HUB_2_BUF_EXT_DP")
		)
		(pad "B57" smd rect
			(at -5.700014 22.85492 180)
			(size 0.381 1.4478)
			(layers "F.Cu" "F.Mask" "F.Paste")
			(net "USB2_HUB_2_BUF_EXT_DN")
		)
		(pad "B58" smd rect
			(at -5.700014 23.455122 180)
			(size 0.381 1.4478)
			(layers "F.Cu" "F.Mask" "F.Paste")
			(net "GND")
		)
		(pad "B59" smd rect
			(at -5.700014 24.05507 180)
			(size 0.381 1.4478)
			(layers "F.Cu" "F.Mask" "F.Paste")
			(net "USB3_PCH_TX_BUF_C_DP<4>")
		)
		(pad "B60" smd rect
			(at -5.700014 24.655018 180)
			(size 0.381 1.4478)
			(layers "F.Cu" "F.Mask" "F.Paste")
			(net "USB3_PCH_TX_BUF_C_DN<4>")
		)
		(pad "B61" smd rect
			(at -5.700014 25.254966 180)
			(size 0.381 1.4478)
			(layers "F.Cu" "F.Mask" "F.Paste")
			(net "GND")
		)
		(pad "B62" smd rect
			(at -5.700014 25.854914 180)
			(size 0.381 1.4478)
			(layers "F.Cu" "F.Mask" "F.Paste")
			(net "TP_PCIE_HPM_TXP<1>")
		)
		(pad "B63" smd rect
			(at -5.700014 26.455116 180)
			(size 0.381 1.4478)
			(layers "F.Cu" "F.Mask" "F.Paste")
			(net "TP_PCIE_HPM_TXN<1>")
		)
		(pad "B64" smd rect
			(at -5.700014 27.055064 180)
			(size 0.381 1.4478)
			(layers "F.Cu" "F.Mask" "F.Paste")
			(net "GND")
		)
		(pad "B65" smd rect
			(at -5.700014 27.655012 180)
			(size 0.381 1.4478)
			(layers "F.Cu" "F.Mask" "F.Paste")
			(net "P2E_MB_BMC_TX_C_DP<0>")
		)
		(pad "B66" smd rect
			(at -5.700014 28.25496 180)
			(size 0.381 1.4478)
			(layers "F.Cu" "F.Mask" "F.Paste")
			(net "P2E_MB_BMC_TX_C_DN<0>")
		)
		(pad "B67" smd rect
			(at -5.700014 28.854908 180)
			(size 0.381 1.4478)
			(layers "F.Cu" "F.Mask" "F.Paste")
			(net "GND")
		)
		(pad "B68" smd rect
			(at -5.700014 29.45511 180)
			(size 0.381 1.4478)
			(layers "F.Cu" "F.Mask" "F.Paste")
			(net "TP_PCIE_HPM_TXP<3>")
		)
		(pad "B69" smd rect
			(at -5.700014 30.055058 180)
			(size 0.381 1.4478)
			(layers "F.Cu" "F.Mask" "F.Paste")
			(net "TP_PCIE_HPM_TXN<3>")
		)
		(pad "B70" smd rect
			(at -5.700014 30.655006 180)
			(size 0.381 1.4478)
			(layers "F.Cu" "F.Mask" "F.Paste")
			(net "GND")
		)
		(pad "G1" thru_hole circle
			(at 2.400046 -32.759904 180)
			(size 1.6256 1.6256)
			(drill 1.1176)
			(layers "*.Cu" "*.Mask")
			(remove_unused_layers no)
			(net "GND")
			(clearance 0)
		)
		(pad "G2" thru_hole circle
			(at 2.400046 -20.379944 180)
			(size 1.6256 1.6256)
			(drill 1.1176)
			(layers "*.Cu" "*.Mask")
			(remove_unused_layers no)
			(net "GND")
			(clearance 0)
		)
		(pad "G3" thru_hole circle
			(at 2.400046 0 180)
			(size 1.6256 1.6256)
			(drill 1.1176)
			(layers "*.Cu" "*.Mask")
			(remove_unused_layers no)
			(net "GND")
			(clearance 0)
		)
		(pad "G4" thru_hole circle
			(at 2.400046 12.5349 180)
			(size 1.6256 1.6256)
			(drill 1.1176)
			(layers "*.Cu" "*.Mask")
			(remove_unused_layers no)
			(net "GND")
			(clearance 0)
		)
		(pad "G5" thru_hole circle
			(at 2.400046 32.759904 180)
			(size 1.6256 1.6256)
			(drill 1.1176)
			(layers "*.Cu" "*.Mask")
			(remove_unused_layers no)
			(net "GND")
			(clearance 0)
		)
		(pad "OA1" smd rect
			(at -2.750058 -30.660086 180)
			(size 0.381 1.4478)
			(layers "F.Cu" "F.Mask" "F.Paste")
			(net "P12V_SCM")
		)
		(pad "OA2" smd rect
			(at -2.750058 -30.059884 180)
			(size 0.381 1.4478)
			(layers "F.Cu" "F.Mask" "F.Paste")
			(net "P12V_SCM")
		)
		(pad "OA3" smd rect
			(at -2.750058 -29.459936 180)
			(size 0.381 1.4478)
			(layers "F.Cu" "F.Mask" "F.Paste")
			(net "GND")
		)
		(pad "OA4" smd rect
			(at -2.750058 -28.859988 180)
			(size 0.381 1.4478)
			(layers "F.Cu" "F.Mask" "F.Paste")
			(net "GND")
		)
		(pad "OA5" smd rect
			(at -2.750058 -28.26004 180)
			(size 0.381 1.4478)
			(layers "F.Cu" "F.Mask" "F.Paste")
			(net "I3C_SPD_DDRABCD_CPU0_BMC_R_SCL")
		)
		(pad "OA6" smd rect
			(at -2.750058 -27.660092 180)
			(size 0.381 1.4478)
			(layers "F.Cu" "F.Mask" "F.Paste")
			(net "I3C_SPD_DDRABCD_CPU0_BMC_R_SDA")
		)
		(pad "OA7" smd rect
			(at -2.750058 -27.05989 180)
			(size 0.381 1.4478)
			(layers "F.Cu" "F.Mask" "F.Paste")
			(net "I3C_SPD_DDREFGH_CPU0_BMC_R_SCL")
		)
		(pad "OA8" smd rect
			(at -2.750058 -26.459942 180)
			(size 0.381 1.4478)
			(layers "F.Cu" "F.Mask" "F.Paste")
			(net "I3C_SPD_DDREFGH_CPU0_BMC_R_SDA")
		)
		(pad "OA9" smd rect
			(at -2.750058 -25.859994 180)
			(size 0.381 1.4478)
			(layers "F.Cu" "F.Mask" "F.Paste")
			(net "I3C_SPD_DDRABCD_CPU1_BMC_R_SCL")
		)
		(pad "OA10" smd rect
			(at -2.750058 -25.260046 180)
			(size 0.381 1.4478)
			(layers "F.Cu" "F.Mask" "F.Paste")
			(net "I3C_SPD_DDRABCD_CPU1_BMC_R_SDA")
		)
		(pad "OA11" smd rect
			(at -2.750058 -24.660098 180)
			(size 0.381 1.4478)
			(layers "F.Cu" "F.Mask" "F.Paste")
			(net "I3C_SPD_DDREFGH_CPU1_BMC_R_SCL")
		)
		(pad "OA12" smd rect
			(at -2.750058 -24.059896 180)
			(size 0.381 1.4478)
			(layers "F.Cu" "F.Mask" "F.Paste")
			(net "I3C_SPD_DDREFGH_CPU1_BMC_R_SDA")
		)
		(pad "OA13" smd rect
			(at -2.750058 -23.459948 180)
			(size 0.381 1.4478)
			(layers "F.Cu" "F.Mask" "F.Paste")
			(net "GND")
		)
		(pad "OA14" smd rect
			(at -2.750058 -22.86 180)
			(size 0.381 1.4478)
			(layers "F.Cu" "F.Mask" "F.Paste")
			(net "VIRTUAL_RESEAT")
		)
		(pad "OB1" smd rect
			(at -5.700014 -30.660086 180)
			(size 0.381 1.4478)
			(layers "F.Cu" "F.Mask" "F.Paste")
			(net "P12V_SCM")
		)
		(pad "OB2" smd rect
			(at -5.700014 -30.059884 180)
			(size 0.381 1.4478)
			(layers "F.Cu" "F.Mask" "F.Paste")
			(net "P12V_SCM")
		)
		(pad "OB3" smd rect
			(at -5.700014 -29.459936 180)
			(size 0.381 1.4478)
			(layers "F.Cu" "F.Mask" "F.Paste")
			(net "PRSNT0_N")
		)
		(pad "OB4" smd rect
			(at -5.700014 -28.859988 180)
			(size 0.381 1.4478)
			(layers "F.Cu" "F.Mask" "F.Paste")
			(net "GND")
		)
		(pad "OB5" smd rect
			(at -5.700014 -28.26004 180)
			(size 0.381 1.4478)
			(layers "F.Cu" "F.Mask" "F.Paste")
			(net "UART_BMC_BIC_TX")
		)
		(pad "OB6" smd rect
			(at -5.700014 -27.660092 180)
			(size 0.381 1.4478)
			(layers "F.Cu" "F.Mask" "F.Paste")
			(net "UART_BMC_BIC_BUF_RX")
		)
		(pad "OB7" smd rect
			(at -5.700014 -27.05989 180)
			(size 0.381 1.4478)
			(layers "F.Cu" "F.Mask" "F.Paste")
			(net "GND")
		)
		(pad "OB8" smd rect
			(at -5.700014 -26.459942 180)
			(size 0.381 1.4478)
			(layers "F.Cu" "F.Mask" "F.Paste")
			(net "USB2_7_R_DP")
		)
		(pad "OB9" smd rect
			(at -5.700014 -25.859994 180)
			(size 0.381 1.4478)
			(layers "F.Cu" "F.Mask" "F.Paste")
			(net "USB2_7_R_DN")
		)
		(pad "OB10" smd rect
			(at -5.700014 -25.260046 180)
			(size 0.381 1.4478)
			(layers "F.Cu" "F.Mask" "F.Paste")
			(net "GND")
		)
		(pad "OB11" smd rect
			(at -5.700014 -24.660098 180)
			(size 0.381 1.4478)
			(layers "F.Cu" "F.Mask" "F.Paste")
			(net "RST_SRST_PLD_BMC_N")
		)
		(pad "OB12" smd rect
			(at -5.700014 -24.059896 180)
			(size 0.381 1.4478)
			(layers "F.Cu" "F.Mask" "F.Paste")
			(net "SPI_TPM_CS_N")
		)
		(pad "OB13" smd rect
			(at -5.700014 -23.459948 180)
			(size 0.381 1.4478)
			(layers "F.Cu" "F.Mask" "F.Paste")
			(net "H_CPU_CATERR_LVC2_BMC_N")
		)
		(pad "OB14" smd rect
			(at -5.700014 -22.86 180)
			(size 0.381 1.4478)
			(layers "F.Cu" "F.Mask" "F.Paste")
			(net "FM_SOL_UART_CH_SEL_R")
		)
		(zone
			(layers "F.Cu" "B.Cu" "In1.Cu" "In2.Cu" "In3.Cu" "In4.Cu" "In5.Cu" "In6.Cu"
				"In7.Cu" "In8.Cu" "In9.Cu" "In10.Cu" "In11.Cu" "In12.Cu" "In13.Cu" "In14.Cu"
				"In15.Cu" "In16.Cu"
			)
			(hatch none 0.5)
			(connect_pads
				(clearance 0)
			)
			(min_thickness 0.25)
			(keepout
				(tracks not_allowed)
				(vias allowed)
				(pads allowed)
				(copperpour not_allowed)
				(footprints allowed)
			)
			(placement
				(enabled no)
				(sheetname "")
			)
			(fill
				(thermal_gap 0.5)
				(thermal_bridge_width 0.5)
				(island_removal_mode 0)
			)
			(polygon
				(pts
					(arc
						(start 129.28219 -10.450068)
						(mid 127.35179 -10.450068)
						(end 129.28219 -10.450068)
					)
				)
			)
		)
		(zone
			(layers "F.Cu" "B.Cu" "In1.Cu" "In2.Cu" "In3.Cu" "In4.Cu" "In5.Cu" "In6.Cu"
				"In7.Cu" "In8.Cu" "In9.Cu" "In10.Cu" "In11.Cu" "In12.Cu" "In13.Cu" "In14.Cu"
				"In15.Cu" "In16.Cu"
			)
			(hatch none 0.5)
			(connect_pads
				(clearance 0)
			)
			(min_thickness 0.25)
			(keepout
				(tracks not_allowed)
				(vias allowed)
				(pads allowed)
				(copperpour not_allowed)
				(footprints allowed)
			)
			(placement
				(enabled no)
				(sheetname "")
			)
			(fill
				(thermal_gap 0.5)
				(thermal_bridge_width 0.5)
				(island_removal_mode 0)
			)
			(polygon
				(pts
					(arc
						(start 193.447162 -11.450066)
						(mid 191.516762 -11.450066)
						(end 193.447162 -11.450066)
					)
				)
			)
		)
	)
	(footprint ""
		(layer "F.Cu")
		(at 447.557652 -18.449798)
		(property "Reference" "PR3786"
			(at 0 0 0)
			(layer "F.SilkS")
			(hide yes)
			(effects
				(font
					(size 1.27 1.27)
				)
			)
		)
		(property "Value" ""
			(at 0 0 0)
			(layer "F.Fab")
			(effects
				(font
					(size 1.27 1.27)
				)
			)
		)
		(duplicate_pad_numbers_are_jumpers no)
		(fp_line
			(start -0.7874 -0.4064)
			(end 0.7874 -0.4064)
			(stroke
				(width 0.1524)
				(type default)
			)
			(layer "F.SilkS")
		)
		(fp_line
			(start -0.7874 0.4064)
			(end -0.7874 -0.4064)
			(stroke
				(width 0.1524)
				(type default)
			)
			(layer "F.SilkS")
		)
		(fp_line
			(start 0.7874 -0.4064)
			(end 0.7874 0.4064)
			(stroke
				(width 0.1524)
				(type default)
			)
			(layer "F.SilkS")
		)
		(fp_line
			(start 0.7874 0.4064)
			(end -0.7874 0.4064)
			(stroke
				(width 0.1524)
				(type default)
			)
			(layer "F.SilkS")
		)
		(fp_line
			(start -0.67945 -0.305054)
			(end -0.12065 -0.305054)
			(stroke
				(width 0.1)
				(type default)
			)
			(layer "F.Fab")
		)
		(fp_line
			(start -0.67945 0.3048)
			(end -0.67945 -0.305054)
			(stroke
				(width 0.1)
				(type default)
			)
			(layer "F.Fab")
		)
		(fp_line
			(start -0.12065 -0.305054)
			(end -0.12065 -0.2794)
			(stroke
				(width 0.1)
				(type default)
			)
			(layer "F.Fab")
		)
		(fp_line
			(start -0.12065 -0.2794)
			(end 0.12065 -0.2794)
			(stroke
				(width 0.1)
				(type default)
			)
			(layer "F.Fab")
		)
		(fp_line
			(start -0.12065 0.2794)
			(end -0.12065 0.3048)
			(stroke
				(width 0.1)
				(type default)
			)
			(layer "F.Fab")
		)
		(fp_line
			(start -0.12065 0.3048)
			(end -0.67945 0.3048)
			(stroke
				(width 0.1)
				(type default)
			)
			(layer "F.Fab")
		)
		(fp_line
			(start 0.120396 0.2794)
			(end -0.12065 0.2794)
			(stroke
				(width 0.1)
				(type default)
			)
			(layer "F.Fab")
		)
		(fp_line
			(start 0.120396 0.3048)
			(end 0.120396 0.2794)
			(stroke
				(width 0.1)
				(type default)
			)
			(layer "F.Fab")
		)
		(fp_line
			(start 0.12065 -0.3048)
			(end 0.67945 -0.3048)
			(stroke
				(width 0.1)
				(type default)
			)
			(layer "F.Fab")
		)
		(fp_line
			(start 0.12065 -0.2794)
			(end 0.12065 -0.3048)
			(stroke
				(width 0.1)
				(type default)
			)
			(layer "F.Fab")
		)
		(fp_line
			(start 0.67945 -0.3048)
			(end 0.67945 0.3048)
			(stroke
				(width 0.1)
				(type default)
			)
			(layer "F.Fab")
		)
		(fp_line
			(start 0.67945 0.3048)
			(end 0.120396 0.3048)
			(stroke
				(width 0.1)
				(type default)
			)
			(layer "F.Fab")
		)
		(pad "1" smd circle
			(at -0.40005 0)
			(size 0 0)
			(layers "F.Cu" "F.Mask" "F.Paste")
			(net "P12V_AUX")
		)
		(pad "2" smd circle
			(at 0.40005 0)
			(size 0 0)
			(layers "F.Cu" "F.Mask" "F.Paste")
			(net "P12V_OCP_UV_1")
		)
	)
	(footprint ""
		(layer "F.Cu")
		(at 89.596468 -341.729822 90)
		(property "Reference" "PR1790"
			(at 0 0 90)
			(layer "F.SilkS")
			(hide yes)
			(effects
				(font
					(size 1.27 1.27)
				)
			)
		)
		(property "Value" ""
			(at 0 0 90)
			(layer "F.Fab")
			(effects
				(font
					(size 1.27 1.27)
				)
			)
		)
		(duplicate_pad_numbers_are_jumpers no)
		(fp_line
			(start 0.7874 -0.4064)
			(end 0.7874 0.4064)
			(stroke
				(width 0.1524)
				(type default)
			)
			(layer "F.SilkS")
		)
		(fp_line
			(start -0.7874 -0.4064)
			(end 0.7874 -0.4064)
			(stroke
				(width 0.1524)
				(type default)
			)
			(layer "F.SilkS")
		)
		(fp_line
			(start 0.7874 0.4064)
			(end -0.7874 0.4064)
			(stroke
				(width 0.1524)
				(type default)
			)
			(layer "F.SilkS")
		)
		(fp_line
			(start -0.7874 0.4064)
			(end -0.7874 -0.4064)
			(stroke
				(width 0.1524)
				(type default)
			)
			(layer "F.SilkS")
		)
		(fp_line
			(start -0.12065 -0.305054)
			(end -0.12065 -0.2794)
			(stroke
				(width 0.1)
				(type default)
			)
			(layer "F.Fab")
		)
		(fp_line
			(start -0.67945 -0.305054)
			(end -0.12065 -0.305054)
			(stroke
				(width 0.1)
				(type default)
			)
			(layer "F.Fab")
		)
		(fp_line
			(start 0.67945 -0.3048)
			(end 0.67945 0.3048)
			(stroke
				(width 0.1)
				(type default)
			)
			(layer "F.Fab")
		)
		(fp_line
			(start 0.12065 -0.3048)
			(end 0.67945 -0.3048)
			(stroke
				(width 0.1)
				(type default)
			)
			(layer "F.Fab")
		)
		(fp_line
			(start 0.12065 -0.2794)
			(end 0.12065 -0.3048)
			(stroke
				(width 0.1)
				(type default)
			)
			(layer "F.Fab")
		)
		(fp_line
			(start -0.12065 -0.2794)
			(end 0.12065 -0.2794)
			(stroke
				(width 0.1)
				(type default)
			)
			(layer "F.Fab")
		)
		(fp_line
			(start 0.120396 0.2794)
			(end -0.12065 0.2794)
			(stroke
				(width 0.1)
				(type default)
			)
			(layer "F.Fab")
		)
		(fp_line
			(start -0.12065 0.2794)
			(end -0.12065 0.3048)
			(stroke
				(width 0.1)
				(type default)
			)
			(layer "F.Fab")
		)
		(fp_line
			(start 0.67945 0.3048)
			(end 0.120396 0.3048)
			(stroke
				(width 0.1)
				(type default)
			)
			(layer "F.Fab")
		)
		(fp_line
			(start 0.120396 0.3048)
			(end 0.120396 0.2794)
			(stroke
				(width 0.1)
				(type default)
			)
			(layer "F.Fab")
		)
		(fp_line
			(start -0.12065 0.3048)
			(end -0.67945 0.3048)
			(stroke
				(width 0.1)
				(type default)
			)
			(layer "F.Fab")
		)
		(fp_line
			(start -0.67945 0.3048)
			(end -0.67945 -0.305054)
			(stroke
				(width 0.1)
				(type default)
			)
			(layer "F.Fab")
		)
		(pad "1" smd circle
			(at -0.40005 0 90)
			(size 0 0)
			(layers "F.Cu" "F.Mask" "F.Paste")
			(net "SW_PVCCIN_CPU1_BOOT6")
		)
		(pad "2" smd circle
			(at 0.40005 0 90)
			(size 0 0)
			(layers "F.Cu" "F.Mask" "F.Paste")
			(net "SW_PVCCIN_CPU1_BOOT6_R")
		)
	)
	(footprint ""
		(layer "F.Cu")
		(at 197.180962 -39.046912)
		(property "Reference" "R1857"
			(at 0 0 0)
			(layer "F.SilkS")
			(hide yes)
			(effects
				(font
					(size 1.27 1.27)
				)
			)
		)
		(property "Value" ""
			(at 0 0 0)
			(layer "F.Fab")
			(effects
				(font
					(size 1.27 1.27)
				)
			)
		)
		(duplicate_pad_numbers_are_jumpers no)
		(fp_line
			(start -0.7874 -0.4064)
			(end 0.7874 -0.4064)
			(stroke
				(width 0.1524)
				(type default)
			)
			(layer "F.SilkS")
		)
		(fp_line
			(start -0.7874 0.4064)
			(end -0.7874 -0.4064)
			(stroke
				(width 0.1524)
				(type default)
			)
			(layer "F.SilkS")
		)
		(fp_line
			(start 0.7874 -0.4064)
			(end 0.7874 0.4064)
			(stroke
				(width 0.1524)
				(type default)
			)
			(layer "F.SilkS")
		)
		(fp_line
			(start 0.7874 0.4064)
			(end -0.7874 0.4064)
			(stroke
				(width 0.1524)
				(type default)
			)
			(layer "F.SilkS")
		)
		(fp_line
			(start -0.67945 -0.305054)
			(end -0.12065 -0.305054)
			(stroke
				(width 0.1)
				(type default)
			)
			(layer "F.Fab")
		)
		(fp_line
			(start -0.67945 0.3048)
			(end -0.67945 -0.305054)
			(stroke
				(width 0.1)
				(type default)
			)
			(layer "F.Fab")
		)
		(fp_line
			(start -0.12065 -0.305054)
			(end -0.12065 -0.2794)
			(stroke
				(width 0.1)
				(type default)
			)
			(layer "F.Fab")
		)
		(fp_line
			(start -0.12065 -0.2794)
			(end 0.12065 -0.2794)
			(stroke
				(width 0.1)
				(type default)
			)
			(layer "F.Fab")
		)
		(fp_line
			(start -0.12065 0.2794)
			(end -0.12065 0.3048)
			(stroke
				(width 0.1)
				(type default)
			)
			(layer "F.Fab")
		)
		(fp_line
			(start -0.12065 0.3048)
			(end -0.67945 0.3048)
			(stroke
				(width 0.1)
				(type default)
			)
			(layer "F.Fab")
		)
		(fp_line
			(start 0.120396 0.2794)
			(end -0.12065 0.2794)
			(stroke
				(width 0.1)
				(type default)
			)
			(layer "F.Fab")
		)
		(fp_line
			(start 0.120396 0.3048)
			(end 0.120396 0.2794)
			(stroke
				(width 0.1)
				(type default)
			)
			(layer "F.Fab")
		)
		(fp_line
			(start 0.12065 -0.3048)
			(end 0.67945 -0.3048)
			(stroke
				(width 0.1)
				(type default)
			)
			(layer "F.Fab")
		)
		(fp_line
			(start 0.12065 -0.2794)
			(end 0.12065 -0.3048)
			(stroke
				(width 0.1)
				(type default)
			)
			(layer "F.Fab")
		)
		(fp_line
			(start 0.67945 -0.3048)
			(end 0.67945 0.3048)
			(stroke
				(width 0.1)
				(type default)
			)
			(layer "F.Fab")
		)
		(fp_line
			(start 0.67945 0.3048)
			(end 0.120396 0.3048)
			(stroke
				(width 0.1)
				(type default)
			)
			(layer "F.Fab")
		)
		(pad "1" smd circle
			(at -0.40005 0)
			(size 0 0)
			(layers "F.Cu" "F.Mask" "F.Paste")
			(net "P3V3_AUX")
		)
		(pad "2" smd circle
			(at 0.40005 0)
			(size 0 0)
			(layers "F.Cu" "F.Mask" "F.Paste")
			(net "P12V_SCM_EN")
		)
	)
	(footprint ""
		(layer "F.Cu")
		(at 21.176996 -100.54971 180)
		(property "Reference" "R3656"
			(at 0 0 180)
			(layer "F.SilkS")
			(hide yes)
			(effects
				(font
					(size 1.27 1.27)
				)
			)
		)
		(property "Value" ""
			(at 0 0 180)
			(layer "F.Fab")
			(effects
				(font
					(size 1.27 1.27)
				)
			)
		)
		(duplicate_pad_numbers_are_jumpers no)
		(fp_line
			(start 0.7874 0.4064)
			(end -0.7874 0.4064)
			(stroke
				(width 0.1524)
				(type default)
			)
			(layer "F.SilkS")
		)
		(fp_line
			(start 0.7874 -0.4064)
			(end 0.7874 0.4064)
			(stroke
				(width 0.1524)
				(type default)
			)
			(layer "F.SilkS")
		)
		(fp_line
			(start -0.7874 0.4064)
			(end -0.7874 -0.4064)
			(stroke
				(width 0.1524)
				(type default)
			)
			(layer "F.SilkS")
		)
		(fp_line
			(start -0.7874 -0.4064)
			(end 0.7874 -0.4064)
			(stroke
				(width 0.1524)
				(type default)
			)
			(layer "F.SilkS")
		)
		(fp_line
			(start 0.67945 0.3048)
			(end 0.120396 0.3048)
			(stroke
				(width 0.1)
				(type default)
			)
			(layer "F.Fab")
		)
		(fp_line
			(start 0.67945 -0.3048)
			(end 0.67945 0.3048)
			(stroke
				(width 0.1)
				(type default)
			)
			(layer "F.Fab")
		)
		(fp_line
			(start 0.12065 -0.2794)
			(end 0.12065 -0.3048)
			(stroke
				(width 0.1)
				(type default)
			)
			(layer "F.Fab")
		)
		(fp_line
			(start 0.12065 -0.3048)
			(end 0.67945 -0.3048)
			(stroke
				(width 0.1)
				(type default)
			)
			(layer "F.Fab")
		)
		(fp_line
			(start 0.120396 0.3048)
			(end 0.120396 0.2794)
			(stroke
				(width 0.1)
				(type default)
			)
			(layer "F.Fab")
		)
		(fp_line
			(start 0.120396 0.2794)
			(end -0.12065 0.2794)
			(stroke
				(width 0.1)
				(type default)
			)
			(layer "F.Fab")
		)
		(fp_line
			(start -0.12065 0.3048)
			(end -0.67945 0.3048)
			(stroke
				(width 0.1)
				(type default)
			)
			(layer "F.Fab")
		)
		(fp_line
			(start -0.12065 0.2794)
			(end -0.12065 0.3048)
			(stroke
				(width 0.1)
				(type default)
			)
			(layer "F.Fab")
		)
		(fp_line
			(start -0.12065 -0.2794)
			(end 0.12065 -0.2794)
			(stroke
				(width 0.1)
				(type default)
			)
			(layer "F.Fab")
		)
		(fp_line
			(start -0.12065 -0.305054)
			(end -0.12065 -0.2794)
			(stroke
				(width 0.1)
				(type default)
			)
			(layer "F.Fab")
		)
		(fp_line
			(start -0.67945 0.3048)
			(end -0.67945 -0.305054)
			(stroke
				(width 0.1)
				(type default)
			)
			(layer "F.Fab")
		)
		(fp_line
			(start -0.67945 -0.305054)
			(end -0.12065 -0.305054)
			(stroke
				(width 0.1)
				(type default)
			)
			(layer "F.Fab")
		)
		(pad "1" smd circle
			(at -0.40005 0 180)
			(size 0 0)
			(layers "F.Cu" "F.Mask" "F.Paste")
			(net "P3V3_AUX")
		)
		(pad "2" smd circle
			(at 0.40005 0 180)
			(size 0 0)
			(layers "F.Cu" "F.Mask" "F.Paste")
			(net "USB_HUB_OVCUR1")
		)
	)
	(footprint ""
		(layer "F.Cu")
		(at 173.216062 -30.370272 180)
		(property "Reference" "PR4007"
			(at 0 0 180)
			(layer "F.SilkS")
			(hide yes)
			(effects
				(font
					(size 1.27 1.27)
				)
			)
		)
		(property "Value" ""
			(at 0 0 180)
			(layer "F.Fab")
			(effects
				(font
					(size 1.27 1.27)
				)
			)
		)
		(duplicate_pad_numbers_are_jumpers no)
		(fp_line
			(start 0.7874 0.4064)
			(end -0.7874 0.4064)
			(stroke
				(width 0.1524)
				(type default)
			)
			(layer "F.SilkS")
		)
		(fp_line
			(start 0.7874 -0.4064)
			(end 0.7874 0.4064)
			(stroke
				(width 0.1524)
				(type default)
			)
			(layer "F.SilkS")
		)
		(fp_line
			(start -0.7874 0.4064)
			(end -0.7874 -0.4064)
			(stroke
				(width 0.1524)
				(type default)
			)
			(layer "F.SilkS")
		)
		(fp_line
			(start -0.7874 -0.4064)
			(end 0.7874 -0.4064)
			(stroke
				(width 0.1524)
				(type default)
			)
			(layer "F.SilkS")
		)
		(fp_line
			(start 0.67945 0.3048)
			(end 0.120396 0.3048)
			(stroke
				(width 0.1)
				(type default)
			)
			(layer "F.Fab")
		)
		(fp_line
			(start 0.67945 -0.3048)
			(end 0.67945 0.3048)
			(stroke
				(width 0.1)
				(type default)
			)
			(layer "F.Fab")
		)
		(fp_line
			(start 0.12065 -0.2794)
			(end 0.12065 -0.3048)
			(stroke
				(width 0.1)
				(type default)
			)
			(layer "F.Fab")
		)
		(fp_line
			(start 0.12065 -0.3048)
			(end 0.67945 -0.3048)
			(stroke
				(width 0.1)
				(type default)
			)
			(layer "F.Fab")
		)
		(fp_line
			(start 0.120396 0.3048)
			(end 0.120396 0.2794)
			(stroke
				(width 0.1)
				(type default)
			)
			(layer "F.Fab")
		)
		(fp_line
			(start 0.120396 0.2794)
			(end -0.12065 0.2794)
			(stroke
				(width 0.1)
				(type default)
			)
			(layer "F.Fab")
		)
		(fp_line
			(start -0.12065 0.3048)
			(end -0.67945 0.3048)
			(stroke
				(width 0.1)
				(type default)
			)
			(layer "F.Fab")
		)
		(fp_line
			(start -0.12065 0.2794)
			(end -0.12065 0.3048)
			(stroke
				(width 0.1)
				(type default)
			)
			(layer "F.Fab")
		)
		(fp_line
			(start -0.12065 -0.2794)
			(end 0.12065 -0.2794)
			(stroke
				(width 0.1)
				(type default)
			)
			(layer "F.Fab")
		)
		(fp_line
			(start -0.12065 -0.305054)
			(end -0.12065 -0.2794)
			(stroke
				(width 0.1)
				(type default)
			)
			(layer "F.Fab")
		)
		(fp_line
			(start -0.67945 0.3048)
			(end -0.67945 -0.305054)
			(stroke
				(width 0.1)
				(type default)
			)
			(layer "F.Fab")
		)
		(fp_line
			(start -0.67945 -0.305054)
			(end -0.12065 -0.305054)
			(stroke
				(width 0.1)
				(type default)
			)
			(layer "F.Fab")
		)
		(pad "1" smd circle
			(at -0.40005 0 180)
			(size 0 0)
			(layers "F.Cu" "F.Mask" "F.Paste")
			(net "P12V_SCM_FLTB_N")
		)
		(pad "2" smd circle
			(at 0.40005 0 180)
			(size 0 0)
			(layers "F.Cu" "F.Mask" "F.Paste")
			(net "P3V3_AUX")
		)
	)
	(footprint ""
		(layer "F.Cu")
		(at 420.4716 -169.088562 180)
		(property "Reference" "PC193"
			(at 0 0 180)
			(layer "F.SilkS")
			(hide yes)
			(effects
				(font
					(size 1.27 1.27)
				)
			)
		)
		(property "Value" ""
			(at 0 0 180)
			(layer "F.Fab")
			(effects
				(font
					(size 1.27 1.27)
				)
			)
		)
		(duplicate_pad_numbers_are_jumpers no)
		(fp_line
			(start 0.7874 0.4064)
			(end -0.7874 0.4064)
			(stroke
				(width 0.1524)
				(type default)
			)
			(layer "F.SilkS")
		)
		(fp_line
			(start 0.7874 -0.4064)
			(end 0.7874 0.4064)
			(stroke
				(width 0.1524)
				(type default)
			)
			(layer "F.SilkS")
		)
		(fp_line
			(start -0.7874 0.4064)
			(end -0.7874 -0.4064)
			(stroke
				(width 0.1524)
				(type default)
			)
			(layer "F.SilkS")
		)
		(fp_line
			(start -0.7874 -0.4064)
			(end 0.7874 -0.4064)
			(stroke
				(width 0.1524)
				(type default)
			)
			(layer "F.SilkS")
		)
		(fp_line
			(start 0.67945 0.3048)
			(end 0.120396 0.3048)
			(stroke
				(width 0.1)
				(type default)
			)
			(layer "F.Fab")
		)
		(fp_line
			(start 0.67945 -0.3048)
			(end 0.67945 0.3048)
			(stroke
				(width 0.1)
				(type default)
			)
			(layer "F.Fab")
		)
		(fp_line
			(start 0.12065 -0.2794)
			(end 0.12065 -0.3048)
			(stroke
				(width 0.1)
				(type default)
			)
			(layer "F.Fab")
		)
		(fp_line
			(start 0.12065 -0.3048)
			(end 0.67945 -0.3048)
			(stroke
				(width 0.1)
				(type default)
			)
			(layer "F.Fab")
		)
		(fp_line
			(start 0.120396 0.3048)
			(end 0.120396 0.2794)
			(stroke
				(width 0.1)
				(type default)
			)
			(layer "F.Fab")
		)
		(fp_line
			(start 0.120396 0.2794)
			(end -0.12065 0.2794)
			(stroke
				(width 0.1)
				(type default)
			)
			(layer "F.Fab")
		)
		(fp_line
			(start -0.12065 0.3048)
			(end -0.67945 0.3048)
			(stroke
				(width 0.1)
				(type default)
			)
			(layer "F.Fab")
		)
		(fp_line
			(start -0.12065 0.2794)
			(end -0.12065 0.3048)
			(stroke
				(width 0.1)
				(type default)
			)
			(layer "F.Fab")
		)
		(fp_line
			(start -0.12065 -0.2794)
			(end 0.12065 -0.2794)
			(stroke
				(width 0.1)
				(type default)
			)
			(layer "F.Fab")
		)
		(fp_line
			(start -0.12065 -0.305054)
			(end -0.12065 -0.2794)
			(stroke
				(width 0.1)
				(type default)
			)
			(layer "F.Fab")
		)
		(fp_line
			(start -0.67945 0.3048)
			(end -0.67945 -0.305054)
			(stroke
				(width 0.1)
				(type default)
			)
			(layer "F.Fab")
		)
		(fp_line
			(start -0.67945 -0.305054)
			(end -0.12065 -0.305054)
			(stroke
				(width 0.1)
				(type default)
			)
			(layer "F.Fab")
		)
		(pad "1" smd circle
			(at -0.40005 0 180)
			(size 0 0)
			(layers "F.Cu" "F.Mask" "F.Paste")
			(net "SW_PVCCINFAON_CPU0_BOOT1_R")
		)
		(pad "2" smd circle
			(at 0.40005 0 180)
			(size 0 0)
			(layers "F.Cu" "F.Mask" "F.Paste")
			(net "SW_PVCCINFAON_CPU0_BOOTR1")
		)
	)
	(footprint ""
		(layer "F.Cu")
		(at 365.46663 -244.03177 90)
		(property "Reference" "C1013"
			(at 0 0 90)
			(layer "F.SilkS")
			(hide yes)
			(effects
				(font
					(size 1.27 1.27)
				)
			)
		)
		(property "Value" ""
			(at 0 0 90)
			(layer "F.Fab")
			(effects
				(font
					(size 1.27 1.27)
				)
			)
		)
		(duplicate_pad_numbers_are_jumpers no)
		(fp_line
			(start 0.7874 -0.4064)
			(end 0.7874 0.4064)
			(stroke
				(width 0.1524)
				(type default)
			)
			(layer "F.SilkS")
		)
		(fp_line
			(start -0.7874 -0.4064)
			(end 0.7874 -0.4064)
			(stroke
				(width 0.1524)
				(type default)
			)
			(layer "F.SilkS")
		)
		(fp_line
			(start 0.7874 0.4064)
			(end -0.7874 0.4064)
			(stroke
				(width 0.1524)
				(type default)
			)
			(layer "F.SilkS")
		)
		(fp_line
			(start -0.7874 0.4064)
			(end -0.7874 -0.4064)
			(stroke
				(width 0.1524)
				(type default)
			)
			(layer "F.SilkS")
		)
		(fp_line
			(start -0.12065 -0.305054)
			(end -0.12065 -0.2794)
			(stroke
				(width 0.1)
				(type default)
			)
			(layer "F.Fab")
		)
		(fp_line
			(start -0.67945 -0.305054)
			(end -0.12065 -0.305054)
			(stroke
				(width 0.1)
				(type default)
			)
			(layer "F.Fab")
		)
		(fp_line
			(start 0.67945 -0.3048)
			(end 0.67945 0.3048)
			(stroke
				(width 0.1)
				(type default)
			)
			(layer "F.Fab")
		)
		(fp_line
			(start 0.12065 -0.3048)
			(end 0.67945 -0.3048)
			(stroke
				(width 0.1)
				(type default)
			)
			(layer "F.Fab")
		)
		(fp_line
			(start 0.12065 -0.2794)
			(end 0.12065 -0.3048)
			(stroke
				(width 0.1)
				(type default)
			)
			(layer "F.Fab")
		)
		(fp_line
			(start -0.12065 -0.2794)
			(end 0.12065 -0.2794)
			(stroke
				(width 0.1)
				(type default)
			)
			(layer "F.Fab")
		)
		(fp_line
			(start 0.120396 0.2794)
			(end -0.12065 0.2794)
			(stroke
				(width 0.1)
				(type default)
			)
			(layer "F.Fab")
		)
		(fp_line
			(start -0.12065 0.2794)
			(end -0.12065 0.3048)
			(stroke
				(width 0.1)
				(type default)
			)
			(layer "F.Fab")
		)
		(fp_line
			(start 0.67945 0.3048)
			(end 0.120396 0.3048)
			(stroke
				(width 0.1)
				(type default)
			)
			(layer "F.Fab")
		)
		(fp_line
			(start 0.120396 0.3048)
			(end 0.120396 0.2794)
			(stroke
				(width 0.1)
				(type default)
			)
			(layer "F.Fab")
		)
		(fp_line
			(start -0.12065 0.3048)
			(end -0.67945 0.3048)
			(stroke
				(width 0.1)
				(type default)
			)
			(layer "F.Fab")
		)
		(fp_line
			(start -0.67945 0.3048)
			(end -0.67945 -0.305054)
			(stroke
				(width 0.1)
				(type default)
			)
			(layer "F.Fab")
		)
		(pad "1" smd circle
			(at -0.40005 0 90)
			(size 0 0)
			(layers "F.Cu" "F.Mask" "F.Paste")
			(net "PVCCIN_CPU0")
		)
		(pad "2" smd circle
			(at 0.40005 0 90)
			(size 0 0)
			(layers "F.Cu" "F.Mask" "F.Paste")
			(net "GND")
		)
	)
	(footprint ""
		(layer "F.Cu")
		(at 167.395906 -131.976114 90)
		(property "Reference" "R1641"
			(at 0 0 90)
			(layer "F.SilkS")
			(hide yes)
			(effects
				(font
					(size 1.27 1.27)
				)
			)
		)
		(property "Value" ""
			(at 0 0 90)
			(layer "F.Fab")
			(effects
				(font
					(size 1.27 1.27)
				)
			)
		)
		(duplicate_pad_numbers_are_jumpers no)
		(fp_line
			(start 0.7874 -0.4064)
			(end 0.7874 0.4064)
			(stroke
				(width 0.1524)
				(type default)
			)
			(layer "F.SilkS")
		)
		(fp_line
			(start -0.7874 -0.4064)
			(end 0.7874 -0.4064)
			(stroke
				(width 0.1524)
				(type default)
			)
			(layer "F.SilkS")
		)
		(fp_line
			(start 0.7874 0.4064)
			(end -0.7874 0.4064)
			(stroke
				(width 0.1524)
				(type default)
			)
			(layer "F.SilkS")
		)
		(fp_line
			(start -0.7874 0.4064)
			(end -0.7874 -0.4064)
			(stroke
				(width 0.1524)
				(type default)
			)
			(layer "F.SilkS")
		)
		(fp_line
			(start -0.12065 -0.305054)
			(end -0.12065 -0.2794)
			(stroke
				(width 0.1)
				(type default)
			)
			(layer "F.Fab")
		)
		(fp_line
			(start -0.67945 -0.305054)
			(end -0.12065 -0.305054)
			(stroke
				(width 0.1)
				(type default)
			)
			(layer "F.Fab")
		)
		(fp_line
			(start 0.67945 -0.3048)
			(end 0.67945 0.3048)
			(stroke
				(width 0.1)
				(type default)
			)
			(layer "F.Fab")
		)
		(fp_line
			(start 0.12065 -0.3048)
			(end 0.67945 -0.3048)
			(stroke
				(width 0.1)
				(type default)
			)
			(layer "F.Fab")
		)
		(fp_line
			(start 0.12065 -0.2794)
			(end 0.12065 -0.3048)
			(stroke
				(width 0.1)
				(type default)
			)
			(layer "F.Fab")
		)
		(fp_line
			(start -0.12065 -0.2794)
			(end 0.12065 -0.2794)
			(stroke
				(width 0.1)
				(type default)
			)
			(layer "F.Fab")
		)
		(fp_line
			(start 0.120396 0.2794)
			(end -0.12065 0.2794)
			(stroke
				(width 0.1)
				(type default)
			)
			(layer "F.Fab")
		)
		(fp_line
			(start -0.12065 0.2794)
			(end -0.12065 0.3048)
			(stroke
				(width 0.1)
				(type default)
			)
			(layer "F.Fab")
		)
		(fp_line
			(start 0.67945 0.3048)
			(end 0.120396 0.3048)
			(stroke
				(width 0.1)
				(type default)
			)
			(layer "F.Fab")
		)
		(fp_line
			(start 0.120396 0.3048)
			(end 0.120396 0.2794)
			(stroke
				(width 0.1)
				(type default)
			)
			(layer "F.Fab")
		)
		(fp_line
			(start -0.12065 0.3048)
			(end -0.67945 0.3048)
			(stroke
				(width 0.1)
				(type default)
			)
			(layer "F.Fab")
		)
		(fp_line
			(start -0.67945 0.3048)
			(end -0.67945 -0.305054)
			(stroke
				(width 0.1)
				(type default)
			)
			(layer "F.Fab")
		)
		(pad "1" smd circle
			(at -0.40005 0 90)
			(size 0 0)
			(layers "F.Cu" "F.Mask" "F.Paste")
			(net "VR_P5V_EN")
		)
		(pad "2" smd circle
			(at 0.40005 0 90)
			(size 0 0)
			(layers "F.Cu" "F.Mask" "F.Paste")
			(net "GND")
		)
	)
	(footprint ""
		(layer "F.Cu")
		(at 430.186592 -118.815104 -90)
		(property "Reference" "PC630"
			(at 0 0 270)
			(layer "F.SilkS")
			(hide yes)
			(effects
				(font
					(size 1.27 1.27)
				)
			)
		)
		(property "Value" ""
			(at 0 0 270)
			(layer "F.Fab")
			(effects
				(font
					(size 1.27 1.27)
				)
			)
		)
		(duplicate_pad_numbers_are_jumpers no)
		(fp_line
			(start -0.7874 0.4064)
			(end -0.7874 -0.4064)
			(stroke
				(width 0.1524)
				(type default)
			)
			(layer "F.SilkS")
		)
		(fp_line
			(start 0.7874 0.4064)
			(end -0.7874 0.4064)
			(stroke
				(width 0.1524)
				(type default)
			)
			(layer "F.SilkS")
		)
		(fp_line
			(start -0.7874 -0.4064)
			(end 0.7874 -0.4064)
			(stroke
				(width 0.1524)
				(type default)
			)
			(layer "F.SilkS")
		)
		(fp_line
			(start 0.7874 -0.4064)
			(end 0.7874 0.4064)
			(stroke
				(width 0.1524)
				(type default)
			)
			(layer "F.SilkS")
		)
		(fp_line
			(start -0.67945 0.3048)
			(end -0.67945 -0.305054)
			(stroke
				(width 0.1)
				(type default)
			)
			(layer "F.Fab")
		)
		(fp_line
			(start -0.12065 0.3048)
			(end -0.67945 0.3048)
			(stroke
				(width 0.1)
				(type default)
			)
			(layer "F.Fab")
		)
		(fp_line
			(start 0.120396 0.3048)
			(end 0.120396 0.2794)
			(stroke
				(width 0.1)
				(type default)
			)
			(layer "F.Fab")
		)
		(fp_line
			(start 0.67945 0.3048)
			(end 0.120396 0.3048)
			(stroke
				(width 0.1)
				(type default)
			)
			(layer "F.Fab")
		)
		(fp_line
			(start -0.12065 0.2794)
			(end -0.12065 0.3048)
			(stroke
				(width 0.1)
				(type default)
			)
			(layer "F.Fab")
		)
		(fp_line
			(start 0.120396 0.2794)
			(end -0.12065 0.2794)
			(stroke
				(width 0.1)
				(type default)
			)
			(layer "F.Fab")
		)
		(fp_line
			(start -0.12065 -0.2794)
			(end 0.12065 -0.2794)
			(stroke
				(width 0.1)
				(type default)
			)
			(layer "F.Fab")
		)
		(fp_line
			(start 0.12065 -0.2794)
			(end 0.12065 -0.3048)
			(stroke
				(width 0.1)
				(type default)
			)
			(layer "F.Fab")
		)
		(fp_line
			(start 0.12065 -0.3048)
			(end 0.67945 -0.3048)
			(stroke
				(width 0.1)
				(type default)
			)
			(layer "F.Fab")
		)
		(fp_line
			(start 0.67945 -0.3048)
			(end 0.67945 0.3048)
			(stroke
				(width 0.1)
				(type default)
			)
			(layer "F.Fab")
		)
		(fp_line
			(start -0.67945 -0.305054)
			(end -0.12065 -0.305054)
			(stroke
				(width 0.1)
				(type default)
			)
			(layer "F.Fab")
		)
		(fp_line
			(start -0.12065 -0.305054)
			(end -0.12065 -0.2794)
			(stroke
				(width 0.1)
				(type default)
			)
			(layer "F.Fab")
		)
		(pad "1" smd circle
			(at -0.40005 0 270)
			(size 0 0)
			(layers "F.Cu" "F.Mask" "F.Paste")
			(net "PVCCD_HV_CPU0_VREF")
		)
		(pad "2" smd circle
			(at 0.40005 0 270)
			(size 0 0)
			(layers "F.Cu" "F.Mask" "F.Paste")
			(net "GND")
		)
	)
	(footprint ""
		(layer "F.Cu")
		(at 121.708926 -122.096784 90)
		(property "Reference" "R935"
			(at 0 0 90)
			(layer "F.SilkS")
			(hide yes)
			(effects
				(font
					(size 1.27 1.27)
				)
			)
		)
		(property "Value" ""
			(at 0 0 90)
			(layer "F.Fab")
			(effects
				(font
					(size 1.27 1.27)
				)
			)
		)
		(duplicate_pad_numbers_are_jumpers no)
		(fp_line
			(start 0.7874 -0.4064)
			(end 0.7874 0.4064)
			(stroke
				(width 0.1524)
				(type default)
			)
			(layer "F.SilkS")
		)
		(fp_line
			(start -0.7874 -0.4064)
			(end 0.7874 -0.4064)
			(stroke
				(width 0.1524)
				(type default)
			)
			(layer "F.SilkS")
		)
		(fp_line
			(start 0.7874 0.4064)
			(end -0.7874 0.4064)
			(stroke
				(width 0.1524)
				(type default)
			)
			(layer "F.SilkS")
		)
		(fp_line
			(start -0.7874 0.4064)
			(end -0.7874 -0.4064)
			(stroke
				(width 0.1524)
				(type default)
			)
			(layer "F.SilkS")
		)
		(fp_line
			(start -0.12065 -0.305054)
			(end -0.12065 -0.2794)
			(stroke
				(width 0.1)
				(type default)
			)
			(layer "F.Fab")
		)
		(fp_line
			(start -0.67945 -0.305054)
			(end -0.12065 -0.305054)
			(stroke
				(width 0.1)
				(type default)
			)
			(layer "F.Fab")
		)
		(fp_line
			(start 0.67945 -0.3048)
			(end 0.67945 0.3048)
			(stroke
				(width 0.1)
				(type default)
			)
			(layer "F.Fab")
		)
		(fp_line
			(start 0.12065 -0.3048)
			(end 0.67945 -0.3048)
			(stroke
				(width 0.1)
				(type default)
			)
			(layer "F.Fab")
		)
		(fp_line
			(start 0.12065 -0.2794)
			(end 0.12065 -0.3048)
			(stroke
				(width 0.1)
				(type default)
			)
			(layer "F.Fab")
		)
		(fp_line
			(start -0.12065 -0.2794)
			(end 0.12065 -0.2794)
			(stroke
				(width 0.1)
				(type default)
			)
			(layer "F.Fab")
		)
		(fp_line
			(start 0.120396 0.2794)
			(end -0.12065 0.2794)
			(stroke
				(width 0.1)
				(type default)
			)
			(layer "F.Fab")
		)
		(fp_line
			(start -0.12065 0.2794)
			(end -0.12065 0.3048)
			(stroke
				(width 0.1)
				(type default)
			)
			(layer "F.Fab")
		)
		(fp_line
			(start 0.67945 0.3048)
			(end 0.120396 0.3048)
			(stroke
				(width 0.1)
				(type default)
			)
			(layer "F.Fab")
		)
		(fp_line
			(start 0.120396 0.3048)
			(end 0.120396 0.2794)
			(stroke
				(width 0.1)
				(type default)
			)
			(layer "F.Fab")
		)
		(fp_line
			(start -0.12065 0.3048)
			(end -0.67945 0.3048)
			(stroke
				(width 0.1)
				(type default)
			)
			(layer "F.Fab")
		)
		(fp_line
			(start -0.67945 0.3048)
			(end -0.67945 -0.305054)
			(stroke
				(width 0.1)
				(type default)
			)
			(layer "F.Fab")
		)
		(pad "1" smd circle
			(at -0.40005 0 90)
			(size 0 0)
			(layers "F.Cu" "F.Mask" "F.Paste")
			(net "RST_CPU1_DRAM_CD_N")
		)
		(pad "2" smd circle
			(at 0.40005 0 90)
			(size 0 0)
			(layers "F.Cu" "F.Mask" "F.Paste")
			(net "GND")
		)
	)
	(footprint ""
		(layer "F.Cu")
		(at 176.17948 -421.350948)
		(property "Reference" "R2927"
			(at 0 0 0)
			(layer "F.SilkS")
			(hide yes)
			(effects
				(font
					(size 1.27 1.27)
				)
			)
		)
		(property "Value" ""
			(at 0 0 0)
			(layer "F.Fab")
			(effects
				(font
					(size 1.27 1.27)
				)
			)
		)
		(duplicate_pad_numbers_are_jumpers no)
		(fp_line
			(start -0.7874 -0.4064)
			(end 0.7874 -0.4064)
			(stroke
				(width 0.1524)
				(type default)
			)
			(layer "F.SilkS")
		)
		(fp_line
			(start -0.7874 0.4064)
			(end -0.7874 -0.4064)
			(stroke
				(width 0.1524)
				(type default)
			)
			(layer "F.SilkS")
		)
		(fp_line
			(start 0.7874 -0.4064)
			(end 0.7874 0.4064)
			(stroke
				(width 0.1524)
				(type default)
			)
			(layer "F.SilkS")
		)
		(fp_line
			(start 0.7874 0.4064)
			(end -0.7874 0.4064)
			(stroke
				(width 0.1524)
				(type default)
			)
			(layer "F.SilkS")
		)
		(fp_line
			(start -0.67945 -0.305054)
			(end -0.12065 -0.305054)
			(stroke
				(width 0.1)
				(type default)
			)
			(layer "F.Fab")
		)
		(fp_line
			(start -0.67945 0.3048)
			(end -0.67945 -0.305054)
			(stroke
				(width 0.1)
				(type default)
			)
			(layer "F.Fab")
		)
		(fp_line
			(start -0.12065 -0.305054)
			(end -0.12065 -0.2794)
			(stroke
				(width 0.1)
				(type default)
			)
			(layer "F.Fab")
		)
		(fp_line
			(start -0.12065 -0.2794)
			(end 0.12065 -0.2794)
			(stroke
				(width 0.1)
				(type default)
			)
			(layer "F.Fab")
		)
		(fp_line
			(start -0.12065 0.2794)
			(end -0.12065 0.3048)
			(stroke
				(width 0.1)
				(type default)
			)
			(layer "F.Fab")
		)
		(fp_line
			(start -0.12065 0.3048)
			(end -0.67945 0.3048)
			(stroke
				(width 0.1)
				(type default)
			)
			(layer "F.Fab")
		)
		(fp_line
			(start 0.120396 0.2794)
			(end -0.12065 0.2794)
			(stroke
				(width 0.1)
				(type default)
			)
			(layer "F.Fab")
		)
		(fp_line
			(start 0.120396 0.3048)
			(end 0.120396 0.2794)
			(stroke
				(width 0.1)
				(type default)
			)
			(layer "F.Fab")
		)
		(fp_line
			(start 0.12065 -0.3048)
			(end 0.67945 -0.3048)
			(stroke
				(width 0.1)
				(type default)
			)
			(layer "F.Fab")
		)
		(fp_line
			(start 0.12065 -0.2794)
			(end 0.12065 -0.3048)
			(stroke
				(width 0.1)
				(type default)
			)
			(layer "F.Fab")
		)
		(fp_line
			(start 0.67945 -0.3048)
			(end 0.67945 0.3048)
			(stroke
				(width 0.1)
				(type default)
			)
			(layer "F.Fab")
		)
		(fp_line
			(start 0.67945 0.3048)
			(end 0.120396 0.3048)
			(stroke
				(width 0.1)
				(type default)
			)
			(layer "F.Fab")
		)
		(pad "1" smd circle
			(at -0.40005 0)
			(size 0 0)
			(layers "F.Cu" "F.Mask" "F.Paste")
			(net "RST_SWB_BIC_BUF_R_N")
		)
		(pad "2" smd circle
			(at 0.40005 0)
			(size 0 0)
			(layers "F.Cu" "F.Mask" "F.Paste")
			(net "GND")
		)
	)
	(footprint ""
		(layer "F.Cu")
		(at 318.8081 -76.585064 -90)
		(property "Reference" "R2242"
			(at 0 0 270)
			(layer "F.SilkS")
			(hide yes)
			(effects
				(font
					(size 1.27 1.27)
				)
			)
		)
		(property "Value" ""
			(at 0 0 270)
			(layer "F.Fab")
			(effects
				(font
					(size 1.27 1.27)
				)
			)
		)
		(duplicate_pad_numbers_are_jumpers no)
		(fp_line
			(start -0.7874 0.4064)
			(end -0.7874 -0.4064)
			(stroke
				(width 0.1524)
				(type default)
			)
			(layer "F.SilkS")
		)
		(fp_line
			(start 0.7874 0.4064)
			(end -0.7874 0.4064)
			(stroke
				(width 0.1524)
				(type default)
			)
			(layer "F.SilkS")
		)
		(fp_line
			(start -0.7874 -0.4064)
			(end 0.7874 -0.4064)
			(stroke
				(width 0.1524)
				(type default)
			)
			(layer "F.SilkS")
		)
		(fp_line
			(start 0.7874 -0.4064)
			(end 0.7874 0.4064)
			(stroke
				(width 0.1524)
				(type default)
			)
			(layer "F.SilkS")
		)
		(fp_line
			(start -0.67945 0.3048)
			(end -0.67945 -0.305054)
			(stroke
				(width 0.1)
				(type default)
			)
			(layer "F.Fab")
		)
		(fp_line
			(start -0.12065 0.3048)
			(end -0.67945 0.3048)
			(stroke
				(width 0.1)
				(type default)
			)
			(layer "F.Fab")
		)
		(fp_line
			(start 0.120396 0.3048)
			(end 0.120396 0.2794)
			(stroke
				(width 0.1)
				(type default)
			)
			(layer "F.Fab")
		)
		(fp_line
			(start 0.67945 0.3048)
			(end 0.120396 0.3048)
			(stroke
				(width 0.1)
				(type default)
			)
			(layer "F.Fab")
		)
		(fp_line
			(start -0.12065 0.2794)
			(end -0.12065 0.3048)
			(stroke
				(width 0.1)
				(type default)
			)
			(layer "F.Fab")
		)
		(fp_line
			(start 0.120396 0.2794)
			(end -0.12065 0.2794)
			(stroke
				(width 0.1)
				(type default)
			)
			(layer "F.Fab")
		)
		(fp_line
			(start -0.12065 -0.2794)
			(end 0.12065 -0.2794)
			(stroke
				(width 0.1)
				(type default)
			)
			(layer "F.Fab")
		)
		(fp_line
			(start 0.12065 -0.2794)
			(end 0.12065 -0.3048)
			(stroke
				(width 0.1)
				(type default)
			)
			(layer "F.Fab")
		)
		(fp_line
			(start 0.12065 -0.3048)
			(end 0.67945 -0.3048)
			(stroke
				(width 0.1)
				(type default)
			)
			(layer "F.Fab")
		)
		(fp_line
			(start 0.67945 -0.3048)
			(end 0.67945 0.3048)
			(stroke
				(width 0.1)
				(type default)
			)
			(layer "F.Fab")
		)
		(fp_line
			(start -0.67945 -0.305054)
			(end -0.12065 -0.305054)
			(stroke
				(width 0.1)
				(type default)
			)
			(layer "F.Fab")
		)
		(fp_line
			(start -0.12065 -0.305054)
			(end -0.12065 -0.2794)
			(stroke
				(width 0.1)
				(type default)
			)
			(layer "F.Fab")
		)
		(pad "1" smd circle
			(at -0.40005 0 270)
			(size 0 0)
			(layers "F.Cu" "F.Mask" "F.Paste")
			(net "P1V05_PCH_AUX")
		)
		(pad "2" smd circle
			(at 0.40005 0 270)
			(size 0 0)
			(layers "F.Cu" "F.Mask" "F.Paste")
			(net "FM_BOARD_SKU_ID0")
		)
	)
	(footprint ""
		(layer "F.Cu")
		(at 385.637532 -72.378824)
		(property "Reference" "R2360"
			(at 0 0 0)
			(layer "F.SilkS")
			(hide yes)
			(effects
				(font
					(size 1.27 1.27)
				)
			)
		)
		(property "Value" ""
			(at 0 0 0)
			(layer "F.Fab")
			(effects
				(font
					(size 1.27 1.27)
				)
			)
		)
		(duplicate_pad_numbers_are_jumpers no)
		(fp_line
			(start -0.7874 -0.4064)
			(end 0.7874 -0.4064)
			(stroke
				(width 0.1524)
				(type default)
			)
			(layer "F.SilkS")
		)
		(fp_line
			(start -0.7874 0.4064)
			(end -0.7874 -0.4064)
			(stroke
				(width 0.1524)
				(type default)
			)
			(layer "F.SilkS")
		)
		(fp_line
			(start 0.7874 -0.4064)
			(end 0.7874 0.4064)
			(stroke
				(width 0.1524)
				(type default)
			)
			(layer "F.SilkS")
		)
		(fp_line
			(start 0.7874 0.4064)
			(end -0.7874 0.4064)
			(stroke
				(width 0.1524)
				(type default)
			)
			(layer "F.SilkS")
		)
		(fp_line
			(start -0.67945 -0.305054)
			(end -0.12065 -0.305054)
			(stroke
				(width 0.1)
				(type default)
			)
			(layer "F.Fab")
		)
		(fp_line
			(start -0.67945 0.3048)
			(end -0.67945 -0.305054)
			(stroke
				(width 0.1)
				(type default)
			)
			(layer "F.Fab")
		)
		(fp_line
			(start -0.12065 -0.305054)
			(end -0.12065 -0.2794)
			(stroke
				(width 0.1)
				(type default)
			)
			(layer "F.Fab")
		)
		(fp_line
			(start -0.12065 -0.2794)
			(end 0.12065 -0.2794)
			(stroke
				(width 0.1)
				(type default)
			)
			(layer "F.Fab")
		)
		(fp_line
			(start -0.12065 0.2794)
			(end -0.12065 0.3048)
			(stroke
				(width 0.1)
				(type default)
			)
			(layer "F.Fab")
		)
		(fp_line
			(start -0.12065 0.3048)
			(end -0.67945 0.3048)
			(stroke
				(width 0.1)
				(type default)
			)
			(layer "F.Fab")
		)
		(fp_line
			(start 0.120396 0.2794)
			(end -0.12065 0.2794)
			(stroke
				(width 0.1)
				(type default)
			)
			(layer "F.Fab")
		)
		(fp_line
			(start 0.120396 0.3048)
			(end 0.120396 0.2794)
			(stroke
				(width 0.1)
				(type default)
			)
			(layer "F.Fab")
		)
		(fp_line
			(start 0.12065 -0.3048)
			(end 0.67945 -0.3048)
			(stroke
				(width 0.1)
				(type default)
			)
			(layer "F.Fab")
		)
		(fp_line
			(start 0.12065 -0.2794)
			(end 0.12065 -0.3048)
			(stroke
				(width 0.1)
				(type default)
			)
			(layer "F.Fab")
		)
		(fp_line
			(start 0.67945 -0.3048)
			(end 0.67945 0.3048)
			(stroke
				(width 0.1)
				(type default)
			)
			(layer "F.Fab")
		)
		(fp_line
			(start 0.67945 0.3048)
			(end 0.120396 0.3048)
			(stroke
				(width 0.1)
				(type default)
			)
			(layer "F.Fab")
		)
		(pad "1" smd circle
			(at -0.40005 0)
			(size 0 0)
			(layers "F.Cu" "F.Mask" "F.Paste")
			(net "PWRGD_P1V8_PCH_AUX_R")
		)
		(pad "2" smd circle
			(at 0.40005 0)
			(size 0 0)
			(layers "F.Cu" "F.Mask" "F.Paste")
			(net "PWRGD_P1V8_PCH_AUX")
		)
	)
	(footprint ""
		(layer "F.Cu")
		(at 353.245928 -258.726686 90)
		(property "Reference" "C419"
			(at 0 0 90)
			(layer "F.SilkS")
			(hide yes)
			(effects
				(font
					(size 1.27 1.27)
				)
			)
		)
		(property "Value" ""
			(at 0 0 90)
			(layer "F.Fab")
			(effects
				(font
					(size 1.27 1.27)
				)
			)
		)
		(duplicate_pad_numbers_are_jumpers no)
		(fp_line
			(start 0.7874 -0.4064)
			(end 0.7874 0.4064)
			(stroke
				(width 0.1524)
				(type default)
			)
			(layer "F.SilkS")
		)
		(fp_line
			(start -0.7874 -0.4064)
			(end 0.7874 -0.4064)
			(stroke
				(width 0.1524)
				(type default)
			)
			(layer "F.SilkS")
		)
		(fp_line
			(start 0.7874 0.4064)
			(end -0.7874 0.4064)
			(stroke
				(width 0.1524)
				(type default)
			)
			(layer "F.SilkS")
		)
		(fp_line
			(start -0.7874 0.4064)
			(end -0.7874 -0.4064)
			(stroke
				(width 0.1524)
				(type default)
			)
			(layer "F.SilkS")
		)
		(fp_line
			(start -0.12065 -0.305054)
			(end -0.12065 -0.2794)
			(stroke
				(width 0.1)
				(type default)
			)
			(layer "F.Fab")
		)
		(fp_line
			(start -0.67945 -0.305054)
			(end -0.12065 -0.305054)
			(stroke
				(width 0.1)
				(type default)
			)
			(layer "F.Fab")
		)
		(fp_line
			(start 0.67945 -0.3048)
			(end 0.67945 0.3048)
			(stroke
				(width 0.1)
				(type default)
			)
			(layer "F.Fab")
		)
		(fp_line
			(start 0.12065 -0.3048)
			(end 0.67945 -0.3048)
			(stroke
				(width 0.1)
				(type default)
			)
			(layer "F.Fab")
		)
		(fp_line
			(start 0.12065 -0.2794)
			(end 0.12065 -0.3048)
			(stroke
				(width 0.1)
				(type default)
			)
			(layer "F.Fab")
		)
		(fp_line
			(start -0.12065 -0.2794)
			(end 0.12065 -0.2794)
			(stroke
				(width 0.1)
				(type default)
			)
			(layer "F.Fab")
		)
		(fp_line
			(start 0.120396 0.2794)
			(end -0.12065 0.2794)
			(stroke
				(width 0.1)
				(type default)
			)
			(layer "F.Fab")
		)
		(fp_line
			(start -0.12065 0.2794)
			(end -0.12065 0.3048)
			(stroke
				(width 0.1)
				(type default)
			)
			(layer "F.Fab")
		)
		(fp_line
			(start 0.67945 0.3048)
			(end 0.120396 0.3048)
			(stroke
				(width 0.1)
				(type default)
			)
			(layer "F.Fab")
		)
		(fp_line
			(start 0.120396 0.3048)
			(end 0.120396 0.2794)
			(stroke
				(width 0.1)
				(type default)
			)
			(layer "F.Fab")
		)
		(fp_line
			(start -0.12065 0.3048)
			(end -0.67945 0.3048)
			(stroke
				(width 0.1)
				(type default)
			)
			(layer "F.Fab")
		)
		(fp_line
			(start -0.67945 0.3048)
			(end -0.67945 -0.305054)
			(stroke
				(width 0.1)
				(type default)
			)
			(layer "F.Fab")
		)
		(pad "1" smd circle
			(at -0.40005 0 90)
			(size 0 0)
			(layers "F.Cu" "F.Mask" "F.Paste")
			(net "PVCCFA_EHV_CPU0")
		)
		(pad "2" smd circle
			(at 0.40005 0 90)
			(size 0 0)
			(layers "F.Cu" "F.Mask" "F.Paste")
			(net "GND")
		)
	)
	(footprint ""
		(layer "F.Cu")
		(at 321.899788 -26.711656 90)
		(property "Reference" "R1694"
			(at 0 0 90)
			(layer "F.SilkS")
			(hide yes)
			(effects
				(font
					(size 1.27 1.27)
				)
			)
		)
		(property "Value" ""
			(at 0 0 90)
			(layer "F.Fab")
			(effects
				(font
					(size 1.27 1.27)
				)
			)
		)
		(duplicate_pad_numbers_are_jumpers no)
		(fp_line
			(start 0.7874 -0.4064)
			(end 0.7874 0.4064)
			(stroke
				(width 0.1524)
				(type default)
			)
			(layer "F.SilkS")
		)
		(fp_line
			(start -0.7874 -0.4064)
			(end 0.7874 -0.4064)
			(stroke
				(width 0.1524)
				(type default)
			)
			(layer "F.SilkS")
		)
		(fp_line
			(start 0.7874 0.4064)
			(end -0.7874 0.4064)
			(stroke
				(width 0.1524)
				(type default)
			)
			(layer "F.SilkS")
		)
		(fp_line
			(start -0.7874 0.4064)
			(end -0.7874 -0.4064)
			(stroke
				(width 0.1524)
				(type default)
			)
			(layer "F.SilkS")
		)
		(fp_line
			(start -0.12065 -0.305054)
			(end -0.12065 -0.2794)
			(stroke
				(width 0.1)
				(type default)
			)
			(layer "F.Fab")
		)
		(fp_line
			(start -0.67945 -0.305054)
			(end -0.12065 -0.305054)
			(stroke
				(width 0.1)
				(type default)
			)
			(layer "F.Fab")
		)
		(fp_line
			(start 0.67945 -0.3048)
			(end 0.67945 0.3048)
			(stroke
				(width 0.1)
				(type default)
			)
			(layer "F.Fab")
		)
		(fp_line
			(start 0.12065 -0.3048)
			(end 0.67945 -0.3048)
			(stroke
				(width 0.1)
				(type default)
			)
			(layer "F.Fab")
		)
		(fp_line
			(start 0.12065 -0.2794)
			(end 0.12065 -0.3048)
			(stroke
				(width 0.1)
				(type default)
			)
			(layer "F.Fab")
		)
		(fp_line
			(start -0.12065 -0.2794)
			(end 0.12065 -0.2794)
			(stroke
				(width 0.1)
				(type default)
			)
			(layer "F.Fab")
		)
		(fp_line
			(start 0.120396 0.2794)
			(end -0.12065 0.2794)
			(stroke
				(width 0.1)
				(type default)
			)
			(layer "F.Fab")
		)
		(fp_line
			(start -0.12065 0.2794)
			(end -0.12065 0.3048)
			(stroke
				(width 0.1)
				(type default)
			)
			(layer "F.Fab")
		)
		(fp_line
			(start 0.67945 0.3048)
			(end 0.120396 0.3048)
			(stroke
				(width 0.1)
				(type default)
			)
			(layer "F.Fab")
		)
		(fp_line
			(start 0.120396 0.3048)
			(end 0.120396 0.2794)
			(stroke
				(width 0.1)
				(type default)
			)
			(layer "F.Fab")
		)
		(fp_line
			(start -0.12065 0.3048)
			(end -0.67945 0.3048)
			(stroke
				(width 0.1)
				(type default)
			)
			(layer "F.Fab")
		)
		(fp_line
			(start -0.67945 0.3048)
			(end -0.67945 -0.305054)
			(stroke
				(width 0.1)
				(type default)
			)
			(layer "F.Fab")
		)
		(pad "1" smd circle
			(at -0.40005 0 90)
			(size 0 0)
			(layers "F.Cu" "F.Mask" "F.Paste")
			(net "P3V3_AUX")
		)
		(pad "2" smd circle
			(at 0.40005 0 90)
			(size 0 0)
			(layers "F.Cu" "F.Mask" "F.Paste")
			(net "PWRGD_DSW_PWROK")
		)
	)
	(footprint ""
		(layer "F.Cu")
		(at 389.77697 -402.371052 -90)
		(property "Reference" "C947"
			(at 0 0 270)
			(layer "F.SilkS")
			(hide yes)
			(effects
				(font
					(size 1.27 1.27)
				)
			)
		)
		(property "Value" ""
			(at 0 0 270)
			(layer "F.Fab")
			(effects
				(font
					(size 1.27 1.27)
				)
			)
		)
		(duplicate_pad_numbers_are_jumpers no)
		(fp_line
			(start -0.299974 0.150114)
			(end -0.299974 -0.150114)
			(stroke
				(width 0.1)
				(type default)
			)
			(layer "F.Fab")
		)
		(fp_line
			(start 0.299974 0.150114)
			(end -0.299974 0.150114)
			(stroke
				(width 0.1)
				(type default)
			)
			(layer "F.Fab")
		)
		(fp_line
			(start -0.299974 -0.150114)
			(end 0.299974 -0.150114)
			(stroke
				(width 0.1)
				(type default)
			)
			(layer "F.Fab")
		)
		(fp_line
			(start 0.299974 -0.150114)
			(end 0.299974 0.150114)
			(stroke
				(width 0.1)
				(type default)
			)
			(layer "F.Fab")
		)
		(pad "1" smd rect
			(at -0.2667 0 270)
			(size 0.3048 0.381)
			(layers "F.Cu" "F.Mask" "F.Paste")
			(net "P5E_CPU0_PE2_TX_C_DP<9>")
		)
		(pad "2" smd rect
			(at 0.2667 0 270)
			(size 0.3048 0.381)
			(layers "F.Cu" "F.Mask" "F.Paste")
			(net "P5E_CPU0_PE2_TX_DP<9>")
		)
	)
	(footprint ""
		(layer "F.Cu")
		(at 479.84537 -184.606692 -90)
		(property "Reference" "X43"
			(at 2.361692 4.7117 90)
			(unlocked yes)
			(layer "F.SilkS")
			(effects
				(font
					(size 0.7874 0.5842)
					(thickness 0.1524)
				)
				(justify left)
			)
		)
		(property "Value" ""
			(at 0 0 270)
			(layer "F.Fab")
			(effects
				(font
					(size 1.27 1.27)
				)
			)
		)
		(property "Device Type" "TP_TDR_4P_FTS_TH-TP_TDR_4P_DIPA"
			(at 1.30175 1.27 0)
			(unlocked yes)
			(layer "F.Fab")
			(hide yes)
			(effects
				(font
					(size 0.635 0.4064)
					(thickness 0.1524)
				)
			)
		)
		(property "User Part Number" "N_A"
			(at 1.30175 1.27 0)
			(unlocked yes)
			(layer "Cmts.User")
			(hide yes)
			(effects
				(font
					(size 0.635 0.4064)
					(thickness 0.1524)
				)
			)
		)
		(duplicate_pad_numbers_are_jumpers no)
		(fp_line
			(start 0 3.81)
			(end 2.54 3.81)
			(stroke
				(width 0.1524)
				(type default)
			)
			(layer "F.SilkS")
		)
		(fp_line
			(start 2.54 3.81)
			(end 2.54 3.6703)
			(stroke
				(width 0.1524)
				(type default)
			)
			(layer "F.SilkS")
		)
		(fp_line
			(start 0 3.175)
			(end 0 3.81)
			(stroke
				(width 0.1524)
				(type default)
			)
			(layer "F.SilkS")
		)
		(fp_line
			(start 2.54 1.4097)
			(end 2.54 1.1303)
			(stroke
				(width 0.1524)
				(type default)
			)
			(layer "F.SilkS")
		)
		(fp_line
			(start 0 0.635)
			(end 0 1.905)
			(stroke
				(width 0.1524)
				(type default)
			)
			(layer "F.SilkS")
		)
		(fp_line
			(start 2.54 -1.1303)
			(end 2.54 -1.27)
			(stroke
				(width 0.1524)
				(type default)
			)
			(layer "F.SilkS")
		)
		(fp_line
			(start 0 -1.27)
			(end 0 -0.635)
			(stroke
				(width 0.1524)
				(type default)
			)
			(layer "F.SilkS")
		)
		(fp_line
			(start 2.54 -1.27)
			(end 0 -1.27)
			(stroke
				(width 0.1524)
				(type default)
			)
			(layer "F.SilkS")
		)
		(fp_poly
			(pts
				(xy -0.761746 0) (xy -2.285746 -0.762) (xy -2.285746 0.762)
			)
			(stroke
				(width 0)
				(type default)
			)
			(fill yes)
			(layer "F.SilkS")
		)
		(fp_line
			(start 0 3.81)
			(end 2.54 3.81)
			(stroke
				(width 0.1)
				(type default)
			)
			(layer "F.Fab")
		)
		(fp_line
			(start 2.54 3.81)
			(end 2.54 -1.27)
			(stroke
				(width 0.1)
				(type default)
			)
			(layer "F.Fab")
		)
		(fp_line
			(start 0 -1.27)
			(end 0 3.81)
			(stroke
				(width 0.1)
				(type default)
			)
			(layer "F.Fab")
		)
		(fp_line
			(start 2.54 -1.27)
			(end 0 -1.27)
			(stroke
				(width 0.1)
				(type default)
			)
			(layer "F.Fab")
		)
		(fp_poly
			(pts
				(xy -0.761746 0) (xy -2.285746 -0.762) (xy -2.285746 0.762)
			)
			(stroke
				(width 0)
				(type default)
			)
			(fill yes)
			(layer "F.Fab")
		)
		(pad "1" thru_hole circle
			(at 0 0 270)
			(size 1.0033 1.0033)
			(drill 0.249936)
			(layers "*.Cu" "*.Mask")
			(remove_unused_layers no)
			(net "TDR_DIFF_85_NECK_IN2_DN")
			(clearance 0.10795)
			(thermal_gap 0.10795)
			(padstack
				(mode front_inner_back)
				(layer "Inner"
					(shape circle)
					(size 0.8001 0.8001)
					(clearance 0.1524)
				)
				(layer "B.Cu"
					(shape circle)
					(size 1.0033 1.0033)
					(clearance 0.10795)
				)
			)
		)
		(pad "2" thru_hole circle
			(at 2.54 0 270)
			(size 1.9939 1.9939)
			(drill 0.249936)
			(layers "*.Cu" "*.Mask")
			(remove_unused_layers no)
			(net "T1_GND")
			(clearance 0.10795)
			(thermal_gap 0.10795)
			(padstack
				(mode front_inner_back)
				(layer "Inner"
					(shape circle)
					(size 0.8001 0.8001)
					(clearance 0.1524)
				)
				(layer "B.Cu"
					(shape circle)
					(size 1.9939 1.9939)
					(clearance 0.10795)
				)
			)
		)
		(pad "3" thru_hole circle
			(at 2.54 2.54 270)
			(size 1.9939 1.9939)
			(drill 0.249936)
			(layers "*.Cu" "*.Mask")
			(remove_unused_layers no)
			(net "T1_GND")
			(clearance 0.10795)
			(thermal_gap 0.10795)
			(padstack
				(mode front_inner_back)
				(layer "Inner"
					(shape circle)
					(size 0.8001 0.8001)
					(clearance 0.1524)
				)
				(layer "B.Cu"
					(shape circle)
					(size 1.9939 1.9939)
					(clearance 0.10795)
				)
			)
		)
		(pad "4" thru_hole circle
			(at 0 2.54 270)
			(size 1.0033 1.0033)
			(drill 0.249936)
			(layers "*.Cu" "*.Mask")
			(remove_unused_layers no)
			(net "TDR_DIFF_85_NECK_IN2_DP")
			(clearance 0.10795)
			(thermal_gap 0.10795)
			(padstack
				(mode front_inner_back)
				(layer "Inner"
					(shape circle)
					(size 0.8001 0.8001)
					(clearance 0.1524)
				)
				(layer "B.Cu"
					(shape circle)
					(size 1.0033 1.0033)
					(clearance 0.10795)
				)
			)
		)
	)
	(footprint ""
		(layer "F.Cu")
		(at 183.353964 -337.483958)
		(property "Reference" "PC1201"
			(at 0 0 0)
			(layer "F.SilkS")
			(hide yes)
			(effects
				(font
					(size 1.27 1.27)
				)
			)
		)
		(property "Value" ""
			(at 0 0 0)
			(layer "F.Fab")
			(effects
				(font
					(size 1.27 1.27)
				)
			)
		)
		(duplicate_pad_numbers_are_jumpers no)
		(fp_line
			(start 2.750058 0.999998)
			(end -2.750058 0.999998)
			(stroke
				(width 0.1524)
				(type default)
			)
			(layer "F.SilkS")
		)
		(fp_circle
			(center 0 0.999998)
			(end 2.750058 0.999998)
			(stroke
				(width 0.1524)
				(type default)
			)
			(fill no)
			(layer "F.SilkS")
		)
		(fp_poly
			(pts
				(arc
					(start 2.750058 0.999998)
					(mid 0 3.750056)
					(end -2.750058 0.999998)
				)
			)
			(stroke
				(width 0)
				(type default)
			)
			(fill yes)
			(layer "F.SilkS")
		)
		(fp_circle
			(center 0 0.999998)
			(end 2.750058 0.999998)
			(stroke
				(width 0.1)
				(type default)
			)
			(fill no)
			(layer "F.Fab")
		)
		(pad "1" thru_hole rect
			(at 0 0)
			(size 1.5748 1.5748)
			(drill 1.0668)
			(layers "*.Cu" "*.Mask")
			(remove_unused_layers no)
			(net "PVCCFA_EHV_FIVRA_CPU1")
			(clearance 0)
			(padstack
				(mode front_inner_back)
				(layer "Inner"
					(shape circle)
					(size 1.5748 1.5748)
					(clearance 0)
				)
				(layer "B.Cu"
					(shape rect)
					(size 1.5748 1.5748)
					(clearance 0)
				)
			)
		)
		(pad "2" thru_hole circle
			(at 0 1.999996)
			(size 1.5748 1.5748)
			(drill 1.0668)
			(layers "*.Cu" "*.Mask")
			(remove_unused_layers no)
			(net "GND")
			(clearance 0)
		)
	)
	(footprint ""
		(layer "F.Cu")
		(at 36.605718 -353.75723)
		(property "Reference" "PR704"
			(at 0 0 0)
			(layer "F.SilkS")
			(hide yes)
			(effects
				(font
					(size 1.27 1.27)
				)
			)
		)
		(property "Value" ""
			(at 0 0 0)
			(layer "F.Fab")
			(effects
				(font
					(size 1.27 1.27)
				)
			)
		)
		(duplicate_pad_numbers_are_jumpers no)
		(fp_line
			(start -0.7874 -0.4064)
			(end 0.7874 -0.4064)
			(stroke
				(width 0.1524)
				(type default)
			)
			(layer "F.SilkS")
		)
		(fp_line
			(start -0.7874 0.4064)
			(end -0.7874 -0.4064)
			(stroke
				(width 0.1524)
				(type default)
			)
			(layer "F.SilkS")
		)
		(fp_line
			(start 0.7874 -0.4064)
			(end 0.7874 0.4064)
			(stroke
				(width 0.1524)
				(type default)
			)
			(layer "F.SilkS")
		)
		(fp_line
			(start 0.7874 0.4064)
			(end -0.7874 0.4064)
			(stroke
				(width 0.1524)
				(type default)
			)
			(layer "F.SilkS")
		)
		(fp_line
			(start -0.67945 -0.305054)
			(end -0.12065 -0.305054)
			(stroke
				(width 0.1)
				(type default)
			)
			(layer "F.Fab")
		)
		(fp_line
			(start -0.67945 0.3048)
			(end -0.67945 -0.305054)
			(stroke
				(width 0.1)
				(type default)
			)
			(layer "F.Fab")
		)
		(fp_line
			(start -0.12065 -0.305054)
			(end -0.12065 -0.2794)
			(stroke
				(width 0.1)
				(type default)
			)
			(layer "F.Fab")
		)
		(fp_line
			(start -0.12065 -0.2794)
			(end 0.12065 -0.2794)
			(stroke
				(width 0.1)
				(type default)
			)
			(layer "F.Fab")
		)
		(fp_line
			(start -0.12065 0.2794)
			(end -0.12065 0.3048)
			(stroke
				(width 0.1)
				(type default)
			)
			(layer "F.Fab")
		)
		(fp_line
			(start -0.12065 0.3048)
			(end -0.67945 0.3048)
			(stroke
				(width 0.1)
				(type default)
			)
			(layer "F.Fab")
		)
		(fp_line
			(start 0.120396 0.2794)
			(end -0.12065 0.2794)
			(stroke
				(width 0.1)
				(type default)
			)
			(layer "F.Fab")
		)
		(fp_line
			(start 0.120396 0.3048)
			(end 0.120396 0.2794)
			(stroke
				(width 0.1)
				(type default)
			)
			(layer "F.Fab")
		)
		(fp_line
			(start 0.12065 -0.3048)
			(end 0.67945 -0.3048)
			(stroke
				(width 0.1)
				(type default)
			)
			(layer "F.Fab")
		)
		(fp_line
			(start 0.12065 -0.2794)
			(end 0.12065 -0.3048)
			(stroke
				(width 0.1)
				(type default)
			)
			(layer "F.Fab")
		)
		(fp_line
			(start 0.67945 -0.3048)
			(end 0.67945 0.3048)
			(stroke
				(width 0.1)
				(type default)
			)
			(layer "F.Fab")
		)
		(fp_line
			(start 0.67945 0.3048)
			(end 0.120396 0.3048)
			(stroke
				(width 0.1)
				(type default)
			)
			(layer "F.Fab")
		)
		(pad "1" smd circle
			(at -0.40005 0)
			(size 0 0)
			(layers "F.Cu" "F.Mask" "F.Paste")
			(net "P3V3")
		)
		(pad "2" smd circle
			(at 0.40005 0)
			(size 0 0)
			(layers "F.Cu" "F.Mask" "F.Paste")
			(net "PVCCFA_EHV_FIVRA_CPU1_PVCC2")
		)
	)
	(footprint ""
		(layer "F.Cu")
		(at 46.350428 -102.888034)
		(property "Reference" "C1757"
			(at 0 0 0)
			(layer "F.SilkS")
			(hide yes)
			(effects
				(font
					(size 1.27 1.27)
				)
			)
		)
		(property "Value" ""
			(at 0 0 0)
			(layer "F.Fab")
			(effects
				(font
					(size 1.27 1.27)
				)
			)
		)
		(duplicate_pad_numbers_are_jumpers no)
		(fp_line
			(start -0.7874 -0.4064)
			(end 0.7874 -0.4064)
			(stroke
				(width 0.1524)
				(type default)
			)
			(layer "F.SilkS")
		)
		(fp_line
			(start -0.7874 0.4064)
			(end -0.7874 -0.4064)
			(stroke
				(width 0.1524)
				(type default)
			)
			(layer "F.SilkS")
		)
		(fp_line
			(start 0.7874 -0.4064)
			(end 0.7874 0.4064)
			(stroke
				(width 0.1524)
				(type default)
			)
			(layer "F.SilkS")
		)
		(fp_line
			(start 0.7874 0.4064)
			(end -0.7874 0.4064)
			(stroke
				(width 0.1524)
				(type default)
			)
			(layer "F.SilkS")
		)
		(fp_line
			(start -0.67945 -0.305054)
			(end -0.12065 -0.305054)
			(stroke
				(width 0.1)
				(type default)
			)
			(layer "F.Fab")
		)
		(fp_line
			(start -0.67945 0.3048)
			(end -0.67945 -0.305054)
			(stroke
				(width 0.1)
				(type default)
			)
			(layer "F.Fab")
		)
		(fp_line
			(start -0.12065 -0.305054)
			(end -0.12065 -0.2794)
			(stroke
				(width 0.1)
				(type default)
			)
			(layer "F.Fab")
		)
		(fp_line
			(start -0.12065 -0.2794)
			(end 0.12065 -0.2794)
			(stroke
				(width 0.1)
				(type default)
			)
			(layer "F.Fab")
		)
		(fp_line
			(start -0.12065 0.2794)
			(end -0.12065 0.3048)
			(stroke
				(width 0.1)
				(type default)
			)
			(layer "F.Fab")
		)
		(fp_line
			(start -0.12065 0.3048)
			(end -0.67945 0.3048)
			(stroke
				(width 0.1)
				(type default)
			)
			(layer "F.Fab")
		)
		(fp_line
			(start 0.120396 0.2794)
			(end -0.12065 0.2794)
			(stroke
				(width 0.1)
				(type default)
			)
			(layer "F.Fab")
		)
		(fp_line
			(start 0.120396 0.3048)
			(end 0.120396 0.2794)
			(stroke
				(width 0.1)
				(type default)
			)
			(layer "F.Fab")
		)
		(fp_line
			(start 0.12065 -0.3048)
			(end 0.67945 -0.3048)
			(stroke
				(width 0.1)
				(type default)
			)
			(layer "F.Fab")
		)
		(fp_line
			(start 0.12065 -0.2794)
			(end 0.12065 -0.3048)
			(stroke
				(width 0.1)
				(type default)
			)
			(layer "F.Fab")
		)
		(fp_line
			(start 0.67945 -0.3048)
			(end 0.67945 0.3048)
			(stroke
				(width 0.1)
				(type default)
			)
			(layer "F.Fab")
		)
		(fp_line
			(start 0.67945 0.3048)
			(end 0.120396 0.3048)
			(stroke
				(width 0.1)
				(type default)
			)
			(layer "F.Fab")
		)
		(pad "1" smd circle
			(at -0.40005 0)
			(size 0 0)
			(layers "F.Cu" "F.Mask" "F.Paste")
			(net "P3V3_MAX11617_VDD")
		)
		(pad "2" smd circle
			(at 0.40005 0)
			(size 0 0)
			(layers "F.Cu" "F.Mask" "F.Paste")
			(net "GND")
		)
	)
	(footprint ""
		(layer "F.Cu")
		(at 278.439626 -16.576548)
		(property "Reference" "C1824"
			(at 0 0 0)
			(layer "F.SilkS")
			(hide yes)
			(effects
				(font
					(size 1.27 1.27)
				)
			)
		)
		(property "Value" ""
			(at 0 0 0)
			(layer "F.Fab")
			(effects
				(font
					(size 1.27 1.27)
				)
			)
		)
		(duplicate_pad_numbers_are_jumpers no)
		(fp_line
			(start -0.7874 -0.4064)
			(end 0.7874 -0.4064)
			(stroke
				(width 0.1524)
				(type default)
			)
			(layer "F.SilkS")
		)
		(fp_line
			(start -0.7874 0.4064)
			(end -0.7874 -0.4064)
			(stroke
				(width 0.1524)
				(type default)
			)
			(layer "F.SilkS")
		)
		(fp_line
			(start 0.7874 -0.4064)
			(end 0.7874 0.4064)
			(stroke
				(width 0.1524)
				(type default)
			)
			(layer "F.SilkS")
		)
		(fp_line
			(start 0.7874 0.4064)
			(end -0.7874 0.4064)
			(stroke
				(width 0.1524)
				(type default)
			)
			(layer "F.SilkS")
		)
		(fp_line
			(start -0.67945 -0.305054)
			(end -0.12065 -0.305054)
			(stroke
				(width 0.1)
				(type default)
			)
			(layer "F.Fab")
		)
		(fp_line
			(start -0.67945 0.3048)
			(end -0.67945 -0.305054)
			(stroke
				(width 0.1)
				(type default)
			)
			(layer "F.Fab")
		)
		(fp_line
			(start -0.12065 -0.305054)
			(end -0.12065 -0.2794)
			(stroke
				(width 0.1)
				(type default)
			)
			(layer "F.Fab")
		)
		(fp_line
			(start -0.12065 -0.2794)
			(end 0.12065 -0.2794)
			(stroke
				(width 0.1)
				(type default)
			)
			(layer "F.Fab")
		)
		(fp_line
			(start -0.12065 0.2794)
			(end -0.12065 0.3048)
			(stroke
				(width 0.1)
				(type default)
			)
			(layer "F.Fab")
		)
		(fp_line
			(start -0.12065 0.3048)
			(end -0.67945 0.3048)
			(stroke
				(width 0.1)
				(type default)
			)
			(layer "F.Fab")
		)
		(fp_line
			(start 0.120396 0.2794)
			(end -0.12065 0.2794)
			(stroke
				(width 0.1)
				(type default)
			)
			(layer "F.Fab")
		)
		(fp_line
			(start 0.120396 0.3048)
			(end 0.120396 0.2794)
			(stroke
				(width 0.1)
				(type default)
			)
			(layer "F.Fab")
		)
		(fp_line
			(start 0.12065 -0.3048)
			(end 0.67945 -0.3048)
			(stroke
				(width 0.1)
				(type default)
			)
			(layer "F.Fab")
		)
		(fp_line
			(start 0.12065 -0.2794)
			(end 0.12065 -0.3048)
			(stroke
				(width 0.1)
				(type default)
			)
			(layer "F.Fab")
		)
		(fp_line
			(start 0.67945 -0.3048)
			(end 0.67945 0.3048)
			(stroke
				(width 0.1)
				(type default)
			)
			(layer "F.Fab")
		)
		(fp_line
			(start 0.67945 0.3048)
			(end 0.120396 0.3048)
			(stroke
				(width 0.1)
				(type default)
			)
			(layer "F.Fab")
		)
		(pad "1" smd circle
			(at -0.40005 0)
			(size 0 0)
			(layers "F.Cu" "F.Mask" "F.Paste")
			(net "P3V3_AUX")
		)
		(pad "2" smd circle
			(at 0.40005 0)
			(size 0 0)
			(layers "F.Cu" "F.Mask" "F.Paste")
			(net "GND")
		)
	)
	(footprint ""
		(layer "F.Cu")
		(at 413.520382 -30.893258)
		(property "Reference" "R3039"
			(at 0 0 0)
			(layer "F.SilkS")
			(hide yes)
			(effects
				(font
					(size 1.27 1.27)
				)
			)
		)
		(property "Value" ""
			(at 0 0 0)
			(layer "F.Fab")
			(effects
				(font
					(size 1.27 1.27)
				)
			)
		)
		(duplicate_pad_numbers_are_jumpers no)
		(fp_line
			(start -0.7874 -0.4064)
			(end 0.7874 -0.4064)
			(stroke
				(width 0.1524)
				(type default)
			)
			(layer "F.SilkS")
		)
		(fp_line
			(start -0.7874 0.4064)
			(end -0.7874 -0.4064)
			(stroke
				(width 0.1524)
				(type default)
			)
			(layer "F.SilkS")
		)
		(fp_line
			(start 0.7874 -0.4064)
			(end 0.7874 0.4064)
			(stroke
				(width 0.1524)
				(type default)
			)
			(layer "F.SilkS")
		)
		(fp_line
			(start 0.7874 0.4064)
			(end -0.7874 0.4064)
			(stroke
				(width 0.1524)
				(type default)
			)
			(layer "F.SilkS")
		)
		(fp_line
			(start -0.67945 -0.305054)
			(end -0.12065 -0.305054)
			(stroke
				(width 0.1)
				(type default)
			)
			(layer "F.Fab")
		)
		(fp_line
			(start -0.67945 0.3048)
			(end -0.67945 -0.305054)
			(stroke
				(width 0.1)
				(type default)
			)
			(layer "F.Fab")
		)
		(fp_line
			(start -0.12065 -0.305054)
			(end -0.12065 -0.2794)
			(stroke
				(width 0.1)
				(type default)
			)
			(layer "F.Fab")
		)
		(fp_line
			(start -0.12065 -0.2794)
			(end 0.12065 -0.2794)
			(stroke
				(width 0.1)
				(type default)
			)
			(layer "F.Fab")
		)
		(fp_line
			(start -0.12065 0.2794)
			(end -0.12065 0.3048)
			(stroke
				(width 0.1)
				(type default)
			)
			(layer "F.Fab")
		)
		(fp_line
			(start -0.12065 0.3048)
			(end -0.67945 0.3048)
			(stroke
				(width 0.1)
				(type default)
			)
			(layer "F.Fab")
		)
		(fp_line
			(start 0.120396 0.2794)
			(end -0.12065 0.2794)
			(stroke
				(width 0.1)
				(type default)
			)
			(layer "F.Fab")
		)
		(fp_line
			(start 0.120396 0.3048)
			(end 0.120396 0.2794)
			(stroke
				(width 0.1)
				(type default)
			)
			(layer "F.Fab")
		)
		(fp_line
			(start 0.12065 -0.3048)
			(end 0.67945 -0.3048)
			(stroke
				(width 0.1)
				(type default)
			)
			(layer "F.Fab")
		)
		(fp_line
			(start 0.12065 -0.2794)
			(end 0.12065 -0.3048)
			(stroke
				(width 0.1)
				(type default)
			)
			(layer "F.Fab")
		)
		(fp_line
			(start 0.67945 -0.3048)
			(end 0.67945 0.3048)
			(stroke
				(width 0.1)
				(type default)
			)
			(layer "F.Fab")
		)
		(fp_line
			(start 0.67945 0.3048)
			(end 0.120396 0.3048)
			(stroke
				(width 0.1)
				(type default)
			)
			(layer "F.Fab")
		)
		(pad "1" smd circle
			(at -0.40005 0)
			(size 0 0)
			(layers "F.Cu" "F.Mask" "F.Paste")
			(net "GND")
		)
		(pad "2" smd circle
			(at 0.40005 0)
			(size 0 0)
			(layers "F.Cu" "F.Mask" "F.Paste")
			(net "PD_ME_RCVR_N")
		)
	)
	(footprint ""
		(layer "F.Cu")
		(at 12.999974 -435.600094)
		(property "Reference" "H96"
			(at -5.463794 -5.055616 0)
			(unlocked yes)
			(layer "F.SilkS")
			(effects
				(font
					(size 0.7874 0.5842)
					(thickness 0.1524)
				)
				(justify left)
			)
		)
		(property "Value" ""
			(at 0 0 0)
			(layer "F.Fab")
			(effects
				(font
					(size 1.27 1.27)
				)
			)
		)
		(duplicate_pad_numbers_are_jumpers no)
		(pad "1" thru_hole circle
			(at 0 0)
			(size 10.0076 10.0076)
			(drill 5.6134)
			(layers "*.Cu" "*.Mask")
			(remove_unused_layers no)
			(net "GND")
			(clearance -1.9431)
		)
	)
	(footprint ""
		(layer "F.Cu")
		(at 117.53088 -101.793548 90)
		(property "Reference" "R4029"
			(at 0 0 90)
			(layer "F.SilkS")
			(hide yes)
			(effects
				(font
					(size 1.27 1.27)
				)
			)
		)
		(property "Value" ""
			(at 0 0 90)
			(layer "F.Fab")
			(effects
				(font
					(size 1.27 1.27)
				)
			)
		)
		(duplicate_pad_numbers_are_jumpers no)
		(fp_line
			(start 0.7874 -0.4064)
			(end 0.7874 0.4064)
			(stroke
				(width 0.1524)
				(type default)
			)
			(layer "F.SilkS")
		)
		(fp_line
			(start -0.7874 -0.4064)
			(end 0.7874 -0.4064)
			(stroke
				(width 0.1524)
				(type default)
			)
			(layer "F.SilkS")
		)
		(fp_line
			(start 0.7874 0.4064)
			(end -0.7874 0.4064)
			(stroke
				(width 0.1524)
				(type default)
			)
			(layer "F.SilkS")
		)
		(fp_line
			(start -0.7874 0.4064)
			(end -0.7874 -0.4064)
			(stroke
				(width 0.1524)
				(type default)
			)
			(layer "F.SilkS")
		)
		(fp_line
			(start -0.12065 -0.305054)
			(end -0.12065 -0.2794)
			(stroke
				(width 0.1)
				(type default)
			)
			(layer "F.Fab")
		)
		(fp_line
			(start -0.67945 -0.305054)
			(end -0.12065 -0.305054)
			(stroke
				(width 0.1)
				(type default)
			)
			(layer "F.Fab")
		)
		(fp_line
			(start 0.67945 -0.3048)
			(end 0.67945 0.3048)
			(stroke
				(width 0.1)
				(type default)
			)
			(layer "F.Fab")
		)
		(fp_line
			(start 0.12065 -0.3048)
			(end 0.67945 -0.3048)
			(stroke
				(width 0.1)
				(type default)
			)
			(layer "F.Fab")
		)
		(fp_line
			(start 0.12065 -0.2794)
			(end 0.12065 -0.3048)
			(stroke
				(width 0.1)
				(type default)
			)
			(layer "F.Fab")
		)
		(fp_line
			(start -0.12065 -0.2794)
			(end 0.12065 -0.2794)
			(stroke
				(width 0.1)
				(type default)
			)
			(layer "F.Fab")
		)
		(fp_line
			(start 0.120396 0.2794)
			(end -0.12065 0.2794)
			(stroke
				(width 0.1)
				(type default)
			)
			(layer "F.Fab")
		)
		(fp_line
			(start -0.12065 0.2794)
			(end -0.12065 0.3048)
			(stroke
				(width 0.1)
				(type default)
			)
			(layer "F.Fab")
		)
		(fp_line
			(start 0.67945 0.3048)
			(end 0.120396 0.3048)
			(stroke
				(width 0.1)
				(type default)
			)
			(layer "F.Fab")
		)
		(fp_line
			(start 0.120396 0.3048)
			(end 0.120396 0.2794)
			(stroke
				(width 0.1)
				(type default)
			)
			(layer "F.Fab")
		)
		(fp_line
			(start -0.12065 0.3048)
			(end -0.67945 0.3048)
			(stroke
				(width 0.1)
				(type default)
			)
			(layer "F.Fab")
		)
		(fp_line
			(start -0.67945 0.3048)
			(end -0.67945 -0.305054)
			(stroke
				(width 0.1)
				(type default)
			)
			(layer "F.Fab")
		)
		(pad "1" smd circle
			(at -0.40005 0 90)
			(size 0 0)
			(layers "F.Cu" "F.Mask" "F.Paste")
			(net "PD_CPU0_ERRS_DIR")
		)
		(pad "2" smd circle
			(at 0.40005 0 90)
			(size 0 0)
			(layers "F.Cu" "F.Mask" "F.Paste")
			(net "GND")
		)
	)
	(footprint ""
		(layer "F.Cu")
		(at 309.522622 -47.107348)
		(property "Reference" "R1456"
			(at 0 0 0)
			(layer "F.SilkS")
			(hide yes)
			(effects
				(font
					(size 1.27 1.27)
				)
			)
		)
		(property "Value" ""
			(at 0 0 0)
			(layer "F.Fab")
			(effects
				(font
					(size 1.27 1.27)
				)
			)
		)
		(duplicate_pad_numbers_are_jumpers no)
		(fp_line
			(start -0.7874 -0.4064)
			(end 0.7874 -0.4064)
			(stroke
				(width 0.1524)
				(type default)
			)
			(layer "F.SilkS")
		)
		(fp_line
			(start -0.7874 0.4064)
			(end -0.7874 -0.4064)
			(stroke
				(width 0.1524)
				(type default)
			)
			(layer "F.SilkS")
		)
		(fp_line
			(start 0.7874 -0.4064)
			(end 0.7874 0.4064)
			(stroke
				(width 0.1524)
				(type default)
			)
			(layer "F.SilkS")
		)
		(fp_line
			(start 0.7874 0.4064)
			(end -0.7874 0.4064)
			(stroke
				(width 0.1524)
				(type default)
			)
			(layer "F.SilkS")
		)
		(fp_line
			(start -0.67945 -0.305054)
			(end -0.12065 -0.305054)
			(stroke
				(width 0.1)
				(type default)
			)
			(layer "F.Fab")
		)
		(fp_line
			(start -0.67945 0.3048)
			(end -0.67945 -0.305054)
			(stroke
				(width 0.1)
				(type default)
			)
			(layer "F.Fab")
		)
		(fp_line
			(start -0.12065 -0.305054)
			(end -0.12065 -0.2794)
			(stroke
				(width 0.1)
				(type default)
			)
			(layer "F.Fab")
		)
		(fp_line
			(start -0.12065 -0.2794)
			(end 0.12065 -0.2794)
			(stroke
				(width 0.1)
				(type default)
			)
			(layer "F.Fab")
		)
		(fp_line
			(start -0.12065 0.2794)
			(end -0.12065 0.3048)
			(stroke
				(width 0.1)
				(type default)
			)
			(layer "F.Fab")
		)
		(fp_line
			(start -0.12065 0.3048)
			(end -0.67945 0.3048)
			(stroke
				(width 0.1)
				(type default)
			)
			(layer "F.Fab")
		)
		(fp_line
			(start 0.120396 0.2794)
			(end -0.12065 0.2794)
			(stroke
				(width 0.1)
				(type default)
			)
			(layer "F.Fab")
		)
		(fp_line
			(start 0.120396 0.3048)
			(end 0.120396 0.2794)
			(stroke
				(width 0.1)
				(type default)
			)
			(layer "F.Fab")
		)
		(fp_line
			(start 0.12065 -0.3048)
			(end 0.67945 -0.3048)
			(stroke
				(width 0.1)
				(type default)
			)
			(layer "F.Fab")
		)
		(fp_line
			(start 0.12065 -0.2794)
			(end 0.12065 -0.3048)
			(stroke
				(width 0.1)
				(type default)
			)
			(layer "F.Fab")
		)
		(fp_line
			(start 0.67945 -0.3048)
			(end 0.67945 0.3048)
			(stroke
				(width 0.1)
				(type default)
			)
			(layer "F.Fab")
		)
		(fp_line
			(start 0.67945 0.3048)
			(end 0.120396 0.3048)
			(stroke
				(width 0.1)
				(type default)
			)
			(layer "F.Fab")
		)
		(pad "1" smd circle
			(at -0.40005 0)
			(size 0 0)
			(layers "F.Cu" "F.Mask" "F.Paste")
			(net "FM_CPU_RMCA_CATERR_DLY_LVT3_R_N")
		)
		(pad "2" smd circle
			(at 0.40005 0)
			(size 0 0)
			(layers "F.Cu" "F.Mask" "F.Paste")
			(net "FM_CPU_RMCA_CATERR_DLY_N")
		)
	)
	(footprint ""
		(layer "F.Cu")
		(at 438.920636 -46.033436 180)
		(property "Reference" "C1860"
			(at 0 0 180)
			(layer "F.SilkS")
			(hide yes)
			(effects
				(font
					(size 1.27 1.27)
				)
			)
		)
		(property "Value" ""
			(at 0 0 180)
			(layer "F.Fab")
			(effects
				(font
					(size 1.27 1.27)
				)
			)
		)
		(duplicate_pad_numbers_are_jumpers no)
		(fp_line
			(start 0.7874 0.4064)
			(end -0.7874 0.4064)
			(stroke
				(width 0.1524)
				(type default)
			)
			(layer "F.SilkS")
		)
		(fp_line
			(start 0.7874 -0.4064)
			(end 0.7874 0.4064)
			(stroke
				(width 0.1524)
				(type default)
			)
			(layer "F.SilkS")
		)
		(fp_line
			(start -0.7874 0.4064)
			(end -0.7874 -0.4064)
			(stroke
				(width 0.1524)
				(type default)
			)
			(layer "F.SilkS")
		)
		(fp_line
			(start -0.7874 -0.4064)
			(end 0.7874 -0.4064)
			(stroke
				(width 0.1524)
				(type default)
			)
			(layer "F.SilkS")
		)
		(fp_line
			(start 0.67945 0.3048)
			(end 0.120396 0.3048)
			(stroke
				(width 0.1)
				(type default)
			)
			(layer "F.Fab")
		)
		(fp_line
			(start 0.67945 -0.3048)
			(end 0.67945 0.3048)
			(stroke
				(width 0.1)
				(type default)
			)
			(layer "F.Fab")
		)
		(fp_line
			(start 0.12065 -0.2794)
			(end 0.12065 -0.3048)
			(stroke
				(width 0.1)
				(type default)
			)
			(layer "F.Fab")
		)
		(fp_line
			(start 0.12065 -0.3048)
			(end 0.67945 -0.3048)
			(stroke
				(width 0.1)
				(type default)
			)
			(layer "F.Fab")
		)
		(fp_line
			(start 0.120396 0.3048)
			(end 0.120396 0.2794)
			(stroke
				(width 0.1)
				(type default)
			)
			(layer "F.Fab")
		)
		(fp_line
			(start 0.120396 0.2794)
			(end -0.12065 0.2794)
			(stroke
				(width 0.1)
				(type default)
			)
			(layer "F.Fab")
		)
		(fp_line
			(start -0.12065 0.3048)
			(end -0.67945 0.3048)
			(stroke
				(width 0.1)
				(type default)
			)
			(layer "F.Fab")
		)
		(fp_line
			(start -0.12065 0.2794)
			(end -0.12065 0.3048)
			(stroke
				(width 0.1)
				(type default)
			)
			(layer "F.Fab")
		)
		(fp_line
			(start -0.12065 -0.2794)
			(end 0.12065 -0.2794)
			(stroke
				(width 0.1)
				(type default)
			)
			(layer "F.Fab")
		)
		(fp_line
			(start -0.12065 -0.305054)
			(end -0.12065 -0.2794)
			(stroke
				(width 0.1)
				(type default)
			)
			(layer "F.Fab")
		)
		(fp_line
			(start -0.67945 0.3048)
			(end -0.67945 -0.305054)
			(stroke
				(width 0.1)
				(type default)
			)
			(layer "F.Fab")
		)
		(fp_line
			(start -0.67945 -0.305054)
			(end -0.12065 -0.305054)
			(stroke
				(width 0.1)
				(type default)
			)
			(layer "F.Fab")
		)
		(pad "1" smd circle
			(at -0.40005 0 180)
			(size 0 0)
			(layers "F.Cu" "F.Mask" "F.Paste")
			(net "P3V3_AUX")
		)
		(pad "2" smd circle
			(at 0.40005 0 180)
			(size 0 0)
			(layers "F.Cu" "F.Mask" "F.Paste")
			(net "GND")
		)
	)
	(footprint ""
		(layer "F.Cu")
		(at 168.96588 -436.971948)
		(property "Reference" "C1958"
			(at 0 0 0)
			(layer "F.SilkS")
			(hide yes)
			(effects
				(font
					(size 1.27 1.27)
				)
			)
		)
		(property "Value" ""
			(at 0 0 0)
			(layer "F.Fab")
			(effects
				(font
					(size 1.27 1.27)
				)
			)
		)
		(duplicate_pad_numbers_are_jumpers no)
		(fp_line
			(start -0.7874 -0.4064)
			(end 0.7874 -0.4064)
			(stroke
				(width 0.1524)
				(type default)
			)
			(layer "F.SilkS")
		)
		(fp_line
			(start -0.7874 0.4064)
			(end -0.7874 -0.4064)
			(stroke
				(width 0.1524)
				(type default)
			)
			(layer "F.SilkS")
		)
		(fp_line
			(start 0.7874 -0.4064)
			(end 0.7874 0.4064)
			(stroke
				(width 0.1524)
				(type default)
			)
			(layer "F.SilkS")
		)
		(fp_line
			(start 0.7874 0.4064)
			(end -0.7874 0.4064)
			(stroke
				(width 0.1524)
				(type default)
			)
			(layer "F.SilkS")
		)
		(fp_line
			(start -0.67945 -0.305054)
			(end -0.12065 -0.305054)
			(stroke
				(width 0.1)
				(type default)
			)
			(layer "F.Fab")
		)
		(fp_line
			(start -0.67945 0.3048)
			(end -0.67945 -0.305054)
			(stroke
				(width 0.1)
				(type default)
			)
			(layer "F.Fab")
		)
		(fp_line
			(start -0.12065 -0.305054)
			(end -0.12065 -0.2794)
			(stroke
				(width 0.1)
				(type default)
			)
			(layer "F.Fab")
		)
		(fp_line
			(start -0.12065 -0.2794)
			(end 0.12065 -0.2794)
			(stroke
				(width 0.1)
				(type default)
			)
			(layer "F.Fab")
		)
		(fp_line
			(start -0.12065 0.2794)
			(end -0.12065 0.3048)
			(stroke
				(width 0.1)
				(type default)
			)
			(layer "F.Fab")
		)
		(fp_line
			(start -0.12065 0.3048)
			(end -0.67945 0.3048)
			(stroke
				(width 0.1)
				(type default)
			)
			(layer "F.Fab")
		)
		(fp_line
			(start 0.120396 0.2794)
			(end -0.12065 0.2794)
			(stroke
				(width 0.1)
				(type default)
			)
			(layer "F.Fab")
		)
		(fp_line
			(start 0.120396 0.3048)
			(end 0.120396 0.2794)
			(stroke
				(width 0.1)
				(type default)
			)
			(layer "F.Fab")
		)
		(fp_line
			(start 0.12065 -0.3048)
			(end 0.67945 -0.3048)
			(stroke
				(width 0.1)
				(type default)
			)
			(layer "F.Fab")
		)
		(fp_line
			(start 0.12065 -0.2794)
			(end 0.12065 -0.3048)
			(stroke
				(width 0.1)
				(type default)
			)
			(layer "F.Fab")
		)
		(fp_line
			(start 0.67945 -0.3048)
			(end 0.67945 0.3048)
			(stroke
				(width 0.1)
				(type default)
			)
			(layer "F.Fab")
		)
		(fp_line
			(start 0.67945 0.3048)
			(end 0.120396 0.3048)
			(stroke
				(width 0.1)
				(type default)
			)
			(layer "F.Fab")
		)
		(pad "1" smd circle
			(at -0.40005 0)
			(size 0 0)
			(layers "F.Cu" "F.Mask" "F.Paste")
			(net "P3V3_AUX")
		)
		(pad "2" smd circle
			(at 0.40005 0)
			(size 0 0)
			(layers "F.Cu" "F.Mask" "F.Paste")
			(net "GND")
		)
	)
	(footprint ""
		(layer "F.Cu")
		(at 434.113178 -183.84139 90)
		(property "Reference" "PR1301"
			(at 0 0 90)
			(layer "F.SilkS")
			(hide yes)
			(effects
				(font
					(size 1.27 1.27)
				)
			)
		)
		(property "Value" ""
			(at 0 0 90)
			(layer "F.Fab")
			(effects
				(font
					(size 1.27 1.27)
				)
			)
		)
		(duplicate_pad_numbers_are_jumpers no)
		(fp_line
			(start 0.7874 -0.4064)
			(end 0.7874 0.4064)
			(stroke
				(width 0.1524)
				(type default)
			)
			(layer "F.SilkS")
		)
		(fp_line
			(start -0.7874 -0.4064)
			(end 0.7874 -0.4064)
			(stroke
				(width 0.1524)
				(type default)
			)
			(layer "F.SilkS")
		)
		(fp_line
			(start 0.7874 0.4064)
			(end -0.7874 0.4064)
			(stroke
				(width 0.1524)
				(type default)
			)
			(layer "F.SilkS")
		)
		(fp_line
			(start -0.7874 0.4064)
			(end -0.7874 -0.4064)
			(stroke
				(width 0.1524)
				(type default)
			)
			(layer "F.SilkS")
		)
		(fp_line
			(start -0.12065 -0.305054)
			(end -0.12065 -0.2794)
			(stroke
				(width 0.1)
				(type default)
			)
			(layer "F.Fab")
		)
		(fp_line
			(start -0.67945 -0.305054)
			(end -0.12065 -0.305054)
			(stroke
				(width 0.1)
				(type default)
			)
			(layer "F.Fab")
		)
		(fp_line
			(start 0.67945 -0.3048)
			(end 0.67945 0.3048)
			(stroke
				(width 0.1)
				(type default)
			)
			(layer "F.Fab")
		)
		(fp_line
			(start 0.12065 -0.3048)
			(end 0.67945 -0.3048)
			(stroke
				(width 0.1)
				(type default)
			)
			(layer "F.Fab")
		)
		(fp_line
			(start 0.12065 -0.2794)
			(end 0.12065 -0.3048)
			(stroke
				(width 0.1)
				(type default)
			)
			(layer "F.Fab")
		)
		(fp_line
			(start -0.12065 -0.2794)
			(end 0.12065 -0.2794)
			(stroke
				(width 0.1)
				(type default)
			)
			(layer "F.Fab")
		)
		(fp_line
			(start 0.120396 0.2794)
			(end -0.12065 0.2794)
			(stroke
				(width 0.1)
				(type default)
			)
			(layer "F.Fab")
		)
		(fp_line
			(start -0.12065 0.2794)
			(end -0.12065 0.3048)
			(stroke
				(width 0.1)
				(type default)
			)
			(layer "F.Fab")
		)
		(fp_line
			(start 0.67945 0.3048)
			(end 0.120396 0.3048)
			(stroke
				(width 0.1)
				(type default)
			)
			(layer "F.Fab")
		)
		(fp_line
			(start 0.120396 0.3048)
			(end 0.120396 0.2794)
			(stroke
				(width 0.1)
				(type default)
			)
			(layer "F.Fab")
		)
		(fp_line
			(start -0.12065 0.3048)
			(end -0.67945 0.3048)
			(stroke
				(width 0.1)
				(type default)
			)
			(layer "F.Fab")
		)
		(fp_line
			(start -0.67945 0.3048)
			(end -0.67945 -0.305054)
			(stroke
				(width 0.1)
				(type default)
			)
			(layer "F.Fab")
		)
		(pad "1" smd circle
			(at -0.40005 0 90)
			(size 0 0)
			(layers "F.Cu" "F.Mask" "F.Paste")
			(net "PVNN_MAIN_CPU0_MODE")
		)
		(pad "2" smd circle
			(at 0.40005 0 90)
			(size 0 0)
			(layers "F.Cu" "F.Mask" "F.Paste")
			(net "GND")
		)
	)
	(footprint ""
		(layer "F.Cu")
		(at 457.52131 -42.05351)
		(property "Reference" "R5487"
			(at 0 0 0)
			(layer "F.SilkS")
			(hide yes)
			(effects
				(font
					(size 1.27 1.27)
				)
			)
		)
		(property "Value" ""
			(at 0 0 0)
			(layer "F.Fab")
			(effects
				(font
					(size 1.27 1.27)
				)
			)
		)
		(duplicate_pad_numbers_are_jumpers no)
		(fp_line
			(start -0.7874 -0.4064)
			(end 0.7874 -0.4064)
			(stroke
				(width 0.1524)
				(type default)
			)
			(layer "F.SilkS")
		)
		(fp_line
			(start -0.7874 0.4064)
			(end -0.7874 -0.4064)
			(stroke
				(width 0.1524)
				(type default)
			)
			(layer "F.SilkS")
		)
		(fp_line
			(start 0.7874 -0.4064)
			(end 0.7874 0.4064)
			(stroke
				(width 0.1524)
				(type default)
			)
			(layer "F.SilkS")
		)
		(fp_line
			(start 0.7874 0.4064)
			(end -0.7874 0.4064)
			(stroke
				(width 0.1524)
				(type default)
			)
			(layer "F.SilkS")
		)
		(fp_line
			(start -0.67945 -0.305054)
			(end -0.12065 -0.305054)
			(stroke
				(width 0.1)
				(type default)
			)
			(layer "F.Fab")
		)
		(fp_line
			(start -0.67945 0.3048)
			(end -0.67945 -0.305054)
			(stroke
				(width 0.1)
				(type default)
			)
			(layer "F.Fab")
		)
		(fp_line
			(start -0.12065 -0.305054)
			(end -0.12065 -0.2794)
			(stroke
				(width 0.1)
				(type default)
			)
			(layer "F.Fab")
		)
		(fp_line
			(start -0.12065 -0.2794)
			(end 0.12065 -0.2794)
			(stroke
				(width 0.1)
				(type default)
			)
			(layer "F.Fab")
		)
		(fp_line
			(start -0.12065 0.2794)
			(end -0.12065 0.3048)
			(stroke
				(width 0.1)
				(type default)
			)
			(layer "F.Fab")
		)
		(fp_line
			(start -0.12065 0.3048)
			(end -0.67945 0.3048)
			(stroke
				(width 0.1)
				(type default)
			)
			(layer "F.Fab")
		)
		(fp_line
			(start 0.120396 0.2794)
			(end -0.12065 0.2794)
			(stroke
				(width 0.1)
				(type default)
			)
			(layer "F.Fab")
		)
		(fp_line
			(start 0.120396 0.3048)
			(end 0.120396 0.2794)
			(stroke
				(width 0.1)
				(type default)
			)
			(layer "F.Fab")
		)
		(fp_line
			(start 0.12065 -0.3048)
			(end 0.67945 -0.3048)
			(stroke
				(width 0.1)
				(type default)
			)
			(layer "F.Fab")
		)
		(fp_line
			(start 0.12065 -0.2794)
			(end 0.12065 -0.3048)
			(stroke
				(width 0.1)
				(type default)
			)
			(layer "F.Fab")
		)
		(fp_line
			(start 0.67945 -0.3048)
			(end 0.67945 0.3048)
			(stroke
				(width 0.1)
				(type default)
			)
			(layer "F.Fab")
		)
		(fp_line
			(start 0.67945 0.3048)
			(end 0.120396 0.3048)
			(stroke
				(width 0.1)
				(type default)
			)
			(layer "F.Fab")
		)
		(pad "1" smd circle
			(at -0.40005 0)
			(size 0 0)
			(layers "F.Cu" "F.Mask" "F.Paste")
			(net "HP_LVC3_OCP_V3_1_EN")
		)
		(pad "2" smd circle
			(at 0.40005 0)
			(size 0 0)
			(layers "F.Cu" "F.Mask" "F.Paste")
			(net "P3V3_OCP_EN_1_R")
		)
	)
	(footprint ""
		(layer "F.Cu")
		(at 463.465926 -96.406208)
		(property "Reference" "R2474"
			(at 0 0 0)
			(layer "F.SilkS")
			(hide yes)
			(effects
				(font
					(size 1.27 1.27)
				)
			)
		)
		(property "Value" ""
			(at 0 0 0)
			(layer "F.Fab")
			(effects
				(font
					(size 1.27 1.27)
				)
			)
		)
		(duplicate_pad_numbers_are_jumpers no)
		(fp_line
			(start -0.7874 -0.4064)
			(end 0.7874 -0.4064)
			(stroke
				(width 0.1524)
				(type default)
			)
			(layer "F.SilkS")
		)
		(fp_line
			(start -0.7874 0.4064)
			(end -0.7874 -0.4064)
			(stroke
				(width 0.1524)
				(type default)
			)
			(layer "F.SilkS")
		)
		(fp_line
			(start 0.7874 -0.4064)
			(end 0.7874 0.4064)
			(stroke
				(width 0.1524)
				(type default)
			)
			(layer "F.SilkS")
		)
		(fp_line
			(start 0.7874 0.4064)
			(end -0.7874 0.4064)
			(stroke
				(width 0.1524)
				(type default)
			)
			(layer "F.SilkS")
		)
		(fp_line
			(start -0.67945 -0.305054)
			(end -0.12065 -0.305054)
			(stroke
				(width 0.1)
				(type default)
			)
			(layer "F.Fab")
		)
		(fp_line
			(start -0.67945 0.3048)
			(end -0.67945 -0.305054)
			(stroke
				(width 0.1)
				(type default)
			)
			(layer "F.Fab")
		)
		(fp_line
			(start -0.12065 -0.305054)
			(end -0.12065 -0.2794)
			(stroke
				(width 0.1)
				(type default)
			)
			(layer "F.Fab")
		)
		(fp_line
			(start -0.12065 -0.2794)
			(end 0.12065 -0.2794)
			(stroke
				(width 0.1)
				(type default)
			)
			(layer "F.Fab")
		)
		(fp_line
			(start -0.12065 0.2794)
			(end -0.12065 0.3048)
			(stroke
				(width 0.1)
				(type default)
			)
			(layer "F.Fab")
		)
		(fp_line
			(start -0.12065 0.3048)
			(end -0.67945 0.3048)
			(stroke
				(width 0.1)
				(type default)
			)
			(layer "F.Fab")
		)
		(fp_line
			(start 0.120396 0.2794)
			(end -0.12065 0.2794)
			(stroke
				(width 0.1)
				(type default)
			)
			(layer "F.Fab")
		)
		(fp_line
			(start 0.120396 0.3048)
			(end 0.120396 0.2794)
			(stroke
				(width 0.1)
				(type default)
			)
			(layer "F.Fab")
		)
		(fp_line
			(start 0.12065 -0.3048)
			(end 0.67945 -0.3048)
			(stroke
				(width 0.1)
				(type default)
			)
			(layer "F.Fab")
		)
		(fp_line
			(start 0.12065 -0.2794)
			(end 0.12065 -0.3048)
			(stroke
				(width 0.1)
				(type default)
			)
			(layer "F.Fab")
		)
		(fp_line
			(start 0.67945 -0.3048)
			(end 0.67945 0.3048)
			(stroke
				(width 0.1)
				(type default)
			)
			(layer "F.Fab")
		)
		(fp_line
			(start 0.67945 0.3048)
			(end 0.120396 0.3048)
			(stroke
				(width 0.1)
				(type default)
			)
			(layer "F.Fab")
		)
		(pad "1" smd circle
			(at -0.40005 0)
			(size 0 0)
			(layers "F.Cu" "F.Mask" "F.Paste")
			(net "FM_NCSI_OCP_V3_1_R_OE")
		)
		(pad "2" smd circle
			(at 0.40005 0)
			(size 0 0)
			(layers "F.Cu" "F.Mask" "F.Paste")
			(net "FB_BMC_ISOLATE")
		)
	)
	(footprint ""
		(layer "F.Cu")
		(at 212.598 -113.4872)
		(property "Reference" "C2384"
			(at 0 0 0)
			(layer "F.SilkS")
			(hide yes)
			(effects
				(font
					(size 1.27 1.27)
				)
			)
		)
		(property "Value" ""
			(at 0 0 0)
			(layer "F.Fab")
			(effects
				(font
					(size 1.27 1.27)
				)
			)
		)
		(duplicate_pad_numbers_are_jumpers no)
		(fp_line
			(start -0.7874 -0.4064)
			(end 0.7874 -0.4064)
			(stroke
				(width 0.1524)
				(type default)
			)
			(layer "F.SilkS")
		)
		(fp_line
			(start -0.7874 0.4064)
			(end -0.7874 -0.4064)
			(stroke
				(width 0.1524)
				(type default)
			)
			(layer "F.SilkS")
		)
		(fp_line
			(start 0.7874 -0.4064)
			(end 0.7874 0.4064)
			(stroke
				(width 0.1524)
				(type default)
			)
			(layer "F.SilkS")
		)
		(fp_line
			(start 0.7874 0.4064)
			(end -0.7874 0.4064)
			(stroke
				(width 0.1524)
				(type default)
			)
			(layer "F.SilkS")
		)
		(fp_line
			(start -0.67945 -0.305054)
			(end -0.12065 -0.305054)
			(stroke
				(width 0.1)
				(type default)
			)
			(layer "F.Fab")
		)
		(fp_line
			(start -0.67945 0.3048)
			(end -0.67945 -0.305054)
			(stroke
				(width 0.1)
				(type default)
			)
			(layer "F.Fab")
		)
		(fp_line
			(start -0.12065 -0.305054)
			(end -0.12065 -0.2794)
			(stroke
				(width 0.1)
				(type default)
			)
			(layer "F.Fab")
		)
		(fp_line
			(start -0.12065 -0.2794)
			(end 0.12065 -0.2794)
			(stroke
				(width 0.1)
				(type default)
			)
			(layer "F.Fab")
		)
		(fp_line
			(start -0.12065 0.2794)
			(end -0.12065 0.3048)
			(stroke
				(width 0.1)
				(type default)
			)
			(layer "F.Fab")
		)
		(fp_line
			(start -0.12065 0.3048)
			(end -0.67945 0.3048)
			(stroke
				(width 0.1)
				(type default)
			)
			(layer "F.Fab")
		)
		(fp_line
			(start 0.120396 0.2794)
			(end -0.12065 0.2794)
			(stroke
				(width 0.1)
				(type default)
			)
			(layer "F.Fab")
		)
		(fp_line
			(start 0.120396 0.3048)
			(end 0.120396 0.2794)
			(stroke
				(width 0.1)
				(type default)
			)
			(layer "F.Fab")
		)
		(fp_line
			(start 0.12065 -0.3048)
			(end 0.67945 -0.3048)
			(stroke
				(width 0.1)
				(type default)
			)
			(layer "F.Fab")
		)
		(fp_line
			(start 0.12065 -0.2794)
			(end 0.12065 -0.3048)
			(stroke
				(width 0.1)
				(type default)
			)
			(layer "F.Fab")
		)
		(fp_line
			(start 0.67945 -0.3048)
			(end 0.67945 0.3048)
			(stroke
				(width 0.1)
				(type default)
			)
			(layer "F.Fab")
		)
		(fp_line
			(start 0.67945 0.3048)
			(end 0.120396 0.3048)
			(stroke
				(width 0.1)
				(type default)
			)
			(layer "F.Fab")
		)
		(pad "1" smd circle
			(at -0.40005 0)
			(size 0 0)
			(layers "F.Cu" "F.Mask" "F.Paste")
			(net "P12V_AUX")
		)
		(pad "2" smd circle
			(at 0.40005 0)
			(size 0 0)
			(layers "F.Cu" "F.Mask" "F.Paste")
			(net "GND")
		)
	)
	(footprint ""
		(layer "F.Cu")
		(at 93.903038 -402.371052 -90)
		(property "Reference" "C740"
			(at 0 0 270)
			(layer "F.SilkS")
			(hide yes)
			(effects
				(font
					(size 1.27 1.27)
				)
			)
		)
		(property "Value" ""
			(at 0 0 270)
			(layer "F.Fab")
			(effects
				(font
					(size 1.27 1.27)
				)
			)
		)
		(duplicate_pad_numbers_are_jumpers no)
		(fp_line
			(start -0.299974 0.150114)
			(end -0.299974 -0.150114)
			(stroke
				(width 0.1)
				(type default)
			)
			(layer "F.Fab")
		)
		(fp_line
			(start 0.299974 0.150114)
			(end -0.299974 0.150114)
			(stroke
				(width 0.1)
				(type default)
			)
			(layer "F.Fab")
		)
		(fp_line
			(start -0.299974 -0.150114)
			(end 0.299974 -0.150114)
			(stroke
				(width 0.1)
				(type default)
			)
			(layer "F.Fab")
		)
		(fp_line
			(start 0.299974 -0.150114)
			(end 0.299974 0.150114)
			(stroke
				(width 0.1)
				(type default)
			)
			(layer "F.Fab")
		)
		(pad "1" smd rect
			(at -0.2667 0 270)
			(size 0.3048 0.381)
			(layers "F.Cu" "F.Mask" "F.Paste")
			(net "P5E_CPU1_PE0_TX_C_DN<0>")
		)
		(pad "2" smd rect
			(at 0.2667 0 270)
			(size 0.3048 0.381)
			(layers "F.Cu" "F.Mask" "F.Paste")
			(net "P5E_CPU1_PE0_TX_DN<0>")
		)
	)
	(footprint ""
		(layer "F.Cu")
		(at 216.065608 -405.839422 180)
		(property "Reference" "PC2226"
			(at 0 0 180)
			(layer "F.SilkS")
			(hide yes)
			(effects
				(font
					(size 1.27 1.27)
				)
			)
		)
		(property "Value" ""
			(at 0 0 180)
			(layer "F.Fab")
			(effects
				(font
					(size 1.27 1.27)
				)
			)
		)
		(duplicate_pad_numbers_are_jumpers no)
		(fp_line
			(start 0.7874 0.4064)
			(end -0.7874 0.4064)
			(stroke
				(width 0.1524)
				(type default)
			)
			(layer "F.SilkS")
		)
		(fp_line
			(start 0.7874 -0.4064)
			(end 0.7874 0.4064)
			(stroke
				(width 0.1524)
				(type default)
			)
			(layer "F.SilkS")
		)
		(fp_line
			(start -0.7874 0.4064)
			(end -0.7874 -0.4064)
			(stroke
				(width 0.1524)
				(type default)
			)
			(layer "F.SilkS")
		)
		(fp_line
			(start -0.7874 -0.4064)
			(end 0.7874 -0.4064)
			(stroke
				(width 0.1524)
				(type default)
			)
			(layer "F.SilkS")
		)
		(fp_line
			(start 0.67945 0.3048)
			(end 0.120396 0.3048)
			(stroke
				(width 0.1)
				(type default)
			)
			(layer "F.Fab")
		)
		(fp_line
			(start 0.67945 -0.3048)
			(end 0.67945 0.3048)
			(stroke
				(width 0.1)
				(type default)
			)
			(layer "F.Fab")
		)
		(fp_line
			(start 0.12065 -0.2794)
			(end 0.12065 -0.3048)
			(stroke
				(width 0.1)
				(type default)
			)
			(layer "F.Fab")
		)
		(fp_line
			(start 0.12065 -0.3048)
			(end 0.67945 -0.3048)
			(stroke
				(width 0.1)
				(type default)
			)
			(layer "F.Fab")
		)
		(fp_line
			(start 0.120396 0.3048)
			(end 0.120396 0.2794)
			(stroke
				(width 0.1)
				(type default)
			)
			(layer "F.Fab")
		)
		(fp_line
			(start 0.120396 0.2794)
			(end -0.12065 0.2794)
			(stroke
				(width 0.1)
				(type default)
			)
			(layer "F.Fab")
		)
		(fp_line
			(start -0.12065 0.3048)
			(end -0.67945 0.3048)
			(stroke
				(width 0.1)
				(type default)
			)
			(layer "F.Fab")
		)
		(fp_line
			(start -0.12065 0.2794)
			(end -0.12065 0.3048)
			(stroke
				(width 0.1)
				(type default)
			)
			(layer "F.Fab")
		)
		(fp_line
			(start -0.12065 -0.2794)
			(end 0.12065 -0.2794)
			(stroke
				(width 0.1)
				(type default)
			)
			(layer "F.Fab")
		)
		(fp_line
			(start -0.12065 -0.305054)
			(end -0.12065 -0.2794)
			(stroke
				(width 0.1)
				(type default)
			)
			(layer "F.Fab")
		)
		(fp_line
			(start -0.67945 0.3048)
			(end -0.67945 -0.305054)
			(stroke
				(width 0.1)
				(type default)
			)
			(layer "F.Fab")
		)
		(fp_line
			(start -0.67945 -0.305054)
			(end -0.12065 -0.305054)
			(stroke
				(width 0.1)
				(type default)
			)
			(layer "F.Fab")
		)
		(pad "1" smd circle
			(at -0.40005 0 180)
			(size 0 0)
			(layers "F.Cu" "F.Mask" "F.Paste")
			(net "HSC_SS")
		)
		(pad "2" smd circle
			(at 0.40005 0 180)
			(size 0 0)
			(layers "F.Cu" "F.Mask" "F.Paste")
			(net "AGND_HSC")
		)
	)
	(footprint ""
		(layer "F.Cu")
		(at 374.325642 -350.780858)
		(property "Reference" "PC1248"
			(at 0 0 0)
			(layer "F.SilkS")
			(hide yes)
			(effects
				(font
					(size 1.27 1.27)
				)
			)
		)
		(property "Value" ""
			(at 0 0 0)
			(layer "F.Fab")
			(effects
				(font
					(size 1.27 1.27)
				)
			)
		)
		(duplicate_pad_numbers_are_jumpers no)
		(fp_line
			(start -1.524 -0.762)
			(end 1.524 -0.762)
			(stroke
				(width 0.1524)
				(type default)
			)
			(layer "F.SilkS")
		)
		(fp_line
			(start -1.524 0.762)
			(end -1.524 -0.762)
			(stroke
				(width 0.1524)
				(type default)
			)
			(layer "F.SilkS")
		)
		(fp_line
			(start 1.524 -0.762)
			(end 1.524 0.762)
			(stroke
				(width 0.1524)
				(type default)
			)
			(layer "F.SilkS")
		)
		(fp_line
			(start 1.524 0.762)
			(end -1.524 0.762)
			(stroke
				(width 0.1524)
				(type default)
			)
			(layer "F.SilkS")
		)
		(fp_line
			(start -1.1049 -0.724916)
			(end -1.1049 0.724916)
			(stroke
				(width 0.1)
				(type default)
			)
			(layer "F.Fab")
		)
		(fp_line
			(start -1.1049 0.724916)
			(end 1.1049 0.724916)
			(stroke
				(width 0.1)
				(type default)
			)
			(layer "F.Fab")
		)
		(fp_line
			(start 1.1049 -0.724916)
			(end -1.1049 -0.724916)
			(stroke
				(width 0.1)
				(type default)
			)
			(layer "F.Fab")
		)
		(fp_line
			(start 1.1049 0.724916)
			(end 1.1049 -0.724916)
			(stroke
				(width 0.1)
				(type default)
			)
			(layer "F.Fab")
		)
		(pad "1" smd rect
			(at -0.889 0 180)
			(size 1.016 1.27)
			(layers "F.Cu" "F.Mask" "F.Paste")
			(net "SW_P12V_PVCCIN_CPU0_FLT")
		)
		(pad "2" smd rect
			(at 0.889 0 180)
			(size 1.016 1.27)
			(layers "F.Cu" "F.Mask" "F.Paste")
			(net "GND")
		)
	)
	(footprint ""
		(layer "F.Cu")
		(at 163.88715 -419.911276)
		(property "Reference" "R2724"
			(at 0 0 0)
			(layer "F.SilkS")
			(hide yes)
			(effects
				(font
					(size 1.27 1.27)
				)
			)
		)
		(property "Value" ""
			(at 0 0 0)
			(layer "F.Fab")
			(effects
				(font
					(size 1.27 1.27)
				)
			)
		)
		(duplicate_pad_numbers_are_jumpers no)
		(fp_line
			(start -0.7874 -0.4064)
			(end 0.7874 -0.4064)
			(stroke
				(width 0.1524)
				(type default)
			)
			(layer "F.SilkS")
		)
		(fp_line
			(start -0.7874 0.4064)
			(end -0.7874 -0.4064)
			(stroke
				(width 0.1524)
				(type default)
			)
			(layer "F.SilkS")
		)
		(fp_line
			(start 0.7874 -0.4064)
			(end 0.7874 0.4064)
			(stroke
				(width 0.1524)
				(type default)
			)
			(layer "F.SilkS")
		)
		(fp_line
			(start 0.7874 0.4064)
			(end -0.7874 0.4064)
			(stroke
				(width 0.1524)
				(type default)
			)
			(layer "F.SilkS")
		)
		(fp_line
			(start -0.67945 -0.305054)
			(end -0.12065 -0.305054)
			(stroke
				(width 0.1)
				(type default)
			)
			(layer "F.Fab")
		)
		(fp_line
			(start -0.67945 0.3048)
			(end -0.67945 -0.305054)
			(stroke
				(width 0.1)
				(type default)
			)
			(layer "F.Fab")
		)
		(fp_line
			(start -0.12065 -0.305054)
			(end -0.12065 -0.2794)
			(stroke
				(width 0.1)
				(type default)
			)
			(layer "F.Fab")
		)
		(fp_line
			(start -0.12065 -0.2794)
			(end 0.12065 -0.2794)
			(stroke
				(width 0.1)
				(type default)
			)
			(layer "F.Fab")
		)
		(fp_line
			(start -0.12065 0.2794)
			(end -0.12065 0.3048)
			(stroke
				(width 0.1)
				(type default)
			)
			(layer "F.Fab")
		)
		(fp_line
			(start -0.12065 0.3048)
			(end -0.67945 0.3048)
			(stroke
				(width 0.1)
				(type default)
			)
			(layer "F.Fab")
		)
		(fp_line
			(start 0.120396 0.2794)
			(end -0.12065 0.2794)
			(stroke
				(width 0.1)
				(type default)
			)
			(layer "F.Fab")
		)
		(fp_line
			(start 0.120396 0.3048)
			(end 0.120396 0.2794)
			(stroke
				(width 0.1)
				(type default)
			)
			(layer "F.Fab")
		)
		(fp_line
			(start 0.12065 -0.3048)
			(end 0.67945 -0.3048)
			(stroke
				(width 0.1)
				(type default)
			)
			(layer "F.Fab")
		)
		(fp_line
			(start 0.12065 -0.2794)
			(end 0.12065 -0.3048)
			(stroke
				(width 0.1)
				(type default)
			)
			(layer "F.Fab")
		)
		(fp_line
			(start 0.67945 -0.3048)
			(end 0.67945 0.3048)
			(stroke
				(width 0.1)
				(type default)
			)
			(layer "F.Fab")
		)
		(fp_line
			(start 0.67945 0.3048)
			(end 0.120396 0.3048)
			(stroke
				(width 0.1)
				(type default)
			)
			(layer "F.Fab")
		)
		(pad "1" smd circle
			(at -0.40005 0)
			(size 0 0)
			(layers "F.Cu" "F.Mask" "F.Paste")
			(net "SMB_BMC_SWB_R_SDA")
		)
		(pad "2" smd circle
			(at 0.40005 0)
			(size 0 0)
			(layers "F.Cu" "F.Mask" "F.Paste")
			(net "SMB_BMC_SWB_BUF_R_SDA")
		)
	)
	(footprint ""
		(layer "F.Cu")
		(at 402.94433 -402.371052 -90)
		(property "Reference" "C954"
			(at 0 0 270)
			(layer "F.SilkS")
			(hide yes)
			(effects
				(font
					(size 1.27 1.27)
				)
			)
		)
		(property "Value" ""
			(at 0 0 270)
			(layer "F.Fab")
			(effects
				(font
					(size 1.27 1.27)
				)
			)
		)
		(duplicate_pad_numbers_are_jumpers no)
		(fp_line
			(start -0.299974 0.150114)
			(end -0.299974 -0.150114)
			(stroke
				(width 0.1)
				(type default)
			)
			(layer "F.Fab")
		)
		(fp_line
			(start 0.299974 0.150114)
			(end -0.299974 0.150114)
			(stroke
				(width 0.1)
				(type default)
			)
			(layer "F.Fab")
		)
		(fp_line
			(start -0.299974 -0.150114)
			(end 0.299974 -0.150114)
			(stroke
				(width 0.1)
				(type default)
			)
			(layer "F.Fab")
		)
		(fp_line
			(start 0.299974 -0.150114)
			(end 0.299974 0.150114)
			(stroke
				(width 0.1)
				(type default)
			)
			(layer "F.Fab")
		)
		(pad "1" smd rect
			(at -0.2667 0 270)
			(size 0.3048 0.381)
			(layers "F.Cu" "F.Mask" "F.Paste")
			(net "P5E_CPU0_PE2_TX_C_DN<5>")
		)
		(pad "2" smd rect
			(at 0.2667 0 270)
			(size 0.3048 0.381)
			(layers "F.Cu" "F.Mask" "F.Paste")
			(net "P5E_CPU0_PE2_TX_DN<5>")
		)
	)
	(footprint ""
		(layer "F.Cu")
		(at 152.108154 -408.517344 -90)
		(property "Reference" "C1536"
			(at 0 0 270)
			(layer "F.SilkS")
			(hide yes)
			(effects
				(font
					(size 1.27 1.27)
				)
			)
		)
		(property "Value" ""
			(at 0 0 270)
			(layer "F.Fab")
			(effects
				(font
					(size 1.27 1.27)
				)
			)
		)
		(duplicate_pad_numbers_are_jumpers no)
		(fp_line
			(start -0.299974 0.150114)
			(end -0.299974 -0.150114)
			(stroke
				(width 0.1)
				(type default)
			)
			(layer "F.Fab")
		)
		(fp_line
			(start 0.299974 0.150114)
			(end -0.299974 0.150114)
			(stroke
				(width 0.1)
				(type default)
			)
			(layer "F.Fab")
		)
		(fp_line
			(start -0.299974 -0.150114)
			(end 0.299974 -0.150114)
			(stroke
				(width 0.1)
				(type default)
			)
			(layer "F.Fab")
		)
		(fp_line
			(start 0.299974 -0.150114)
			(end 0.299974 0.150114)
			(stroke
				(width 0.1)
				(type default)
			)
			(layer "F.Fab")
		)
		(pad "1" smd rect
			(at -0.2667 0 270)
			(size 0.3048 0.381)
			(layers "F.Cu" "F.Mask" "F.Paste")
			(net "P5E_CPU1_PE3_TX_C_DN<5>")
		)
		(pad "2" smd rect
			(at 0.2667 0 270)
			(size 0.3048 0.381)
			(layers "F.Cu" "F.Mask" "F.Paste")
			(net "P5E_CPU1_PE3_TX_DN<5>")
		)
	)
	(footprint ""
		(layer "F.Cu")
		(at 162.848036 -63.297308 180)
		(property "Reference" "R2125"
			(at 0 0 180)
			(layer "F.SilkS")
			(hide yes)
			(effects
				(font
					(size 1.27 1.27)
				)
			)
		)
		(property "Value" ""
			(at 0 0 180)
			(layer "F.Fab")
			(effects
				(font
					(size 1.27 1.27)
				)
			)
		)
		(duplicate_pad_numbers_are_jumpers no)
		(fp_line
			(start 0.7874 0.4064)
			(end -0.7874 0.4064)
			(stroke
				(width 0.1524)
				(type default)
			)
			(layer "F.SilkS")
		)
		(fp_line
			(start 0.7874 -0.4064)
			(end 0.7874 0.4064)
			(stroke
				(width 0.1524)
				(type default)
			)
			(layer "F.SilkS")
		)
		(fp_line
			(start -0.7874 0.4064)
			(end -0.7874 -0.4064)
			(stroke
				(width 0.1524)
				(type default)
			)
			(layer "F.SilkS")
		)
		(fp_line
			(start -0.7874 -0.4064)
			(end 0.7874 -0.4064)
			(stroke
				(width 0.1524)
				(type default)
			)
			(layer "F.SilkS")
		)
		(fp_line
			(start 0.67945 0.3048)
			(end 0.120396 0.3048)
			(stroke
				(width 0.1)
				(type default)
			)
			(layer "F.Fab")
		)
		(fp_line
			(start 0.67945 -0.3048)
			(end 0.67945 0.3048)
			(stroke
				(width 0.1)
				(type default)
			)
			(layer "F.Fab")
		)
		(fp_line
			(start 0.12065 -0.2794)
			(end 0.12065 -0.3048)
			(stroke
				(width 0.1)
				(type default)
			)
			(layer "F.Fab")
		)
		(fp_line
			(start 0.12065 -0.3048)
			(end 0.67945 -0.3048)
			(stroke
				(width 0.1)
				(type default)
			)
			(layer "F.Fab")
		)
		(fp_line
			(start 0.120396 0.3048)
			(end 0.120396 0.2794)
			(stroke
				(width 0.1)
				(type default)
			)
			(layer "F.Fab")
		)
		(fp_line
			(start 0.120396 0.2794)
			(end -0.12065 0.2794)
			(stroke
				(width 0.1)
				(type default)
			)
			(layer "F.Fab")
		)
		(fp_line
			(start -0.12065 0.3048)
			(end -0.67945 0.3048)
			(stroke
				(width 0.1)
				(type default)
			)
			(layer "F.Fab")
		)
		(fp_line
			(start -0.12065 0.2794)
			(end -0.12065 0.3048)
			(stroke
				(width 0.1)
				(type default)
			)
			(layer "F.Fab")
		)
		(fp_line
			(start -0.12065 -0.2794)
			(end 0.12065 -0.2794)
			(stroke
				(width 0.1)
				(type default)
			)
			(layer "F.Fab")
		)
		(fp_line
			(start -0.12065 -0.305054)
			(end -0.12065 -0.2794)
			(stroke
				(width 0.1)
				(type default)
			)
			(layer "F.Fab")
		)
		(fp_line
			(start -0.67945 0.3048)
			(end -0.67945 -0.305054)
			(stroke
				(width 0.1)
				(type default)
			)
			(layer "F.Fab")
		)
		(fp_line
			(start -0.67945 -0.305054)
			(end -0.12065 -0.305054)
			(stroke
				(width 0.1)
				(type default)
			)
			(layer "F.Fab")
		)
		(pad "1" smd circle
			(at -0.40005 0 180)
			(size 0 0)
			(layers "F.Cu" "F.Mask" "F.Paste")
			(net "P3V3_AUX")
		)
		(pad "2" smd circle
			(at 0.40005 0 180)
			(size 0 0)
			(layers "F.Cu" "F.Mask" "F.Paste")
			(net "SMB_PCIE_E1S_ISO_EN")
		)
	)
	(footprint ""
		(layer "F.Cu")
		(at 410.094176 -153.069036 180)
		(property "Reference" "PL3"
			(at -1.462786 -4.512564 0)
			(unlocked yes)
			(layer "F.SilkS")
			(effects
				(font
					(size 0.7874 0.5842)
					(thickness 0.1524)
				)
				(justify left)
			)
		)
		(property "Value" ""
			(at 0 0 180)
			(layer "F.Fab")
			(effects
				(font
					(size 1.27 1.27)
				)
			)
		)
		(duplicate_pad_numbers_are_jumpers no)
		(fp_line
			(start 4.800092 3.199892)
			(end -4.800092 3.199892)
			(stroke
				(width 0.1524)
				(type default)
			)
			(layer "F.SilkS")
		)
		(fp_line
			(start 4.800092 1.6891)
			(end 4.800092 3.199892)
			(stroke
				(width 0.1524)
				(type default)
			)
			(layer "F.SilkS")
		)
		(fp_line
			(start 4.800092 -3.199892)
			(end 4.800092 -1.6891)
			(stroke
				(width 0.1524)
				(type default)
			)
			(layer "F.SilkS")
		)
		(fp_line
			(start -4.800092 3.199892)
			(end -4.800092 1.6891)
			(stroke
				(width 0.1524)
				(type default)
			)
			(layer "F.SilkS")
		)
		(fp_line
			(start -4.800092 -1.6891)
			(end -4.800092 -3.199892)
			(stroke
				(width 0.1524)
				(type default)
			)
			(layer "F.SilkS")
		)
		(fp_line
			(start -4.800092 -3.199892)
			(end 4.800092 -3.199892)
			(stroke
				(width 0.1524)
				(type default)
			)
			(layer "F.SilkS")
		)
		(fp_line
			(start 4.800092 3.199892)
			(end -4.800092 3.199892)
			(stroke
				(width 0.1)
				(type default)
			)
			(layer "F.Fab")
		)
		(fp_line
			(start 4.800092 -3.199892)
			(end 4.800092 3.199892)
			(stroke
				(width 0.1)
				(type default)
			)
			(layer "F.Fab")
		)
		(fp_line
			(start -4.800092 3.199892)
			(end -4.800092 -3.199892)
			(stroke
				(width 0.1)
				(type default)
			)
			(layer "F.Fab")
		)
		(fp_line
			(start -4.800092 -3.199892)
			(end 4.800092 -3.199892)
			(stroke
				(width 0.1)
				(type default)
			)
			(layer "F.Fab")
		)
		(pad "1" smd rect
			(at -3.350006 0 270)
			(size 3.0988 3.2004)
			(layers "F.Cu" "F.Mask" "F.Paste")
			(net "SW_PVCCFA_EHV_CPU0_SW1")
		)
		(pad "2" smd rect
			(at 3.350006 0 270)
			(size 3.0988 3.2004)
			(layers "F.Cu" "F.Mask" "F.Paste")
			(net "PVCCFA_EHV_CPU0")
		)
	)
	(footprint ""
		(layer "F.Cu")
		(at 392.10488 -148.808948 90)
		(property "Reference" "R979"
			(at 0 0 90)
			(layer "F.SilkS")
			(hide yes)
			(effects
				(font
					(size 1.27 1.27)
				)
			)
		)
		(property "Value" ""
			(at 0 0 90)
			(layer "F.Fab")
			(effects
				(font
					(size 1.27 1.27)
				)
			)
		)
		(duplicate_pad_numbers_are_jumpers no)
		(fp_line
			(start 0.7874 -0.4064)
			(end 0.7874 0.4064)
			(stroke
				(width 0.1524)
				(type default)
			)
			(layer "F.SilkS")
		)
		(fp_line
			(start -0.7874 -0.4064)
			(end 0.7874 -0.4064)
			(stroke
				(width 0.1524)
				(type default)
			)
			(layer "F.SilkS")
		)
		(fp_line
			(start 0.7874 0.4064)
			(end -0.7874 0.4064)
			(stroke
				(width 0.1524)
				(type default)
			)
			(layer "F.SilkS")
		)
		(fp_line
			(start -0.7874 0.4064)
			(end -0.7874 -0.4064)
			(stroke
				(width 0.1524)
				(type default)
			)
			(layer "F.SilkS")
		)
		(fp_line
			(start -0.12065 -0.305054)
			(end -0.12065 -0.2794)
			(stroke
				(width 0.1)
				(type default)
			)
			(layer "F.Fab")
		)
		(fp_line
			(start -0.67945 -0.305054)
			(end -0.12065 -0.305054)
			(stroke
				(width 0.1)
				(type default)
			)
			(layer "F.Fab")
		)
		(fp_line
			(start 0.67945 -0.3048)
			(end 0.67945 0.3048)
			(stroke
				(width 0.1)
				(type default)
			)
			(layer "F.Fab")
		)
		(fp_line
			(start 0.12065 -0.3048)
			(end 0.67945 -0.3048)
			(stroke
				(width 0.1)
				(type default)
			)
			(layer "F.Fab")
		)
		(fp_line
			(start 0.12065 -0.2794)
			(end 0.12065 -0.3048)
			(stroke
				(width 0.1)
				(type default)
			)
			(layer "F.Fab")
		)
		(fp_line
			(start -0.12065 -0.2794)
			(end 0.12065 -0.2794)
			(stroke
				(width 0.1)
				(type default)
			)
			(layer "F.Fab")
		)
		(fp_line
			(start 0.120396 0.2794)
			(end -0.12065 0.2794)
			(stroke
				(width 0.1)
				(type default)
			)
			(layer "F.Fab")
		)
		(fp_line
			(start -0.12065 0.2794)
			(end -0.12065 0.3048)
			(stroke
				(width 0.1)
				(type default)
			)
			(layer "F.Fab")
		)
		(fp_line
			(start 0.67945 0.3048)
			(end 0.120396 0.3048)
			(stroke
				(width 0.1)
				(type default)
			)
			(layer "F.Fab")
		)
		(fp_line
			(start 0.120396 0.3048)
			(end 0.120396 0.2794)
			(stroke
				(width 0.1)
				(type default)
			)
			(layer "F.Fab")
		)
		(fp_line
			(start -0.12065 0.3048)
			(end -0.67945 0.3048)
			(stroke
				(width 0.1)
				(type default)
			)
			(layer "F.Fab")
		)
		(fp_line
			(start -0.67945 0.3048)
			(end -0.67945 -0.305054)
			(stroke
				(width 0.1)
				(type default)
			)
			(layer "F.Fab")
		)
		(pad "1" smd circle
			(at -0.40005 0 90)
			(size 0 0)
			(layers "F.Cu" "F.Mask" "F.Paste")
			(net "P3V3_AUX")
		)
		(pad "2" smd circle
			(at 0.40005 0 90)
			(size 0 0)
			(layers "F.Cu" "F.Mask" "F.Paste")
			(net "SMB_S3M_CPU0_3V3AUX_SDA")
		)
	)
	(footprint ""
		(layer "F.Cu")
		(at 385.716272 -63.423292 180)
		(property "Reference" "R1026"
			(at 0 0 180)
			(layer "F.SilkS")
			(hide yes)
			(effects
				(font
					(size 1.27 1.27)
				)
			)
		)
		(property "Value" ""
			(at 0 0 180)
			(layer "F.Fab")
			(effects
				(font
					(size 1.27 1.27)
				)
			)
		)
		(duplicate_pad_numbers_are_jumpers no)
		(fp_line
			(start 0.7874 0.4064)
			(end -0.7874 0.4064)
			(stroke
				(width 0.1524)
				(type default)
			)
			(layer "F.SilkS")
		)
		(fp_line
			(start 0.7874 -0.4064)
			(end 0.7874 0.4064)
			(stroke
				(width 0.1524)
				(type default)
			)
			(layer "F.SilkS")
		)
		(fp_line
			(start -0.7874 0.4064)
			(end -0.7874 -0.4064)
			(stroke
				(width 0.1524)
				(type default)
			)
			(layer "F.SilkS")
		)
		(fp_line
			(start -0.7874 -0.4064)
			(end 0.7874 -0.4064)
			(stroke
				(width 0.1524)
				(type default)
			)
			(layer "F.SilkS")
		)
		(fp_line
			(start 0.67945 0.3048)
			(end 0.120396 0.3048)
			(stroke
				(width 0.1)
				(type default)
			)
			(layer "F.Fab")
		)
		(fp_line
			(start 0.67945 -0.3048)
			(end 0.67945 0.3048)
			(stroke
				(width 0.1)
				(type default)
			)
			(layer "F.Fab")
		)
		(fp_line
			(start 0.12065 -0.2794)
			(end 0.12065 -0.3048)
			(stroke
				(width 0.1)
				(type default)
			)
			(layer "F.Fab")
		)
		(fp_line
			(start 0.12065 -0.3048)
			(end 0.67945 -0.3048)
			(stroke
				(width 0.1)
				(type default)
			)
			(layer "F.Fab")
		)
		(fp_line
			(start 0.120396 0.3048)
			(end 0.120396 0.2794)
			(stroke
				(width 0.1)
				(type default)
			)
			(layer "F.Fab")
		)
		(fp_line
			(start 0.120396 0.2794)
			(end -0.12065 0.2794)
			(stroke
				(width 0.1)
				(type default)
			)
			(layer "F.Fab")
		)
		(fp_line
			(start -0.12065 0.3048)
			(end -0.67945 0.3048)
			(stroke
				(width 0.1)
				(type default)
			)
			(layer "F.Fab")
		)
		(fp_line
			(start -0.12065 0.2794)
			(end -0.12065 0.3048)
			(stroke
				(width 0.1)
				(type default)
			)
			(layer "F.Fab")
		)
		(fp_line
			(start -0.12065 -0.2794)
			(end 0.12065 -0.2794)
			(stroke
				(width 0.1)
				(type default)
			)
			(layer "F.Fab")
		)
		(fp_line
			(start -0.12065 -0.305054)
			(end -0.12065 -0.2794)
			(stroke
				(width 0.1)
				(type default)
			)
			(layer "F.Fab")
		)
		(fp_line
			(start -0.67945 0.3048)
			(end -0.67945 -0.305054)
			(stroke
				(width 0.1)
				(type default)
			)
			(layer "F.Fab")
		)
		(fp_line
			(start -0.67945 -0.305054)
			(end -0.12065 -0.305054)
			(stroke
				(width 0.1)
				(type default)
			)
			(layer "F.Fab")
		)
		(pad "1" smd circle
			(at -0.40005 0 180)
			(size 0 0)
			(layers "F.Cu" "F.Mask" "F.Paste")
			(net "JTAG_DBP_PMODE")
		)
		(pad "2" smd circle
			(at 0.40005 0 180)
			(size 0 0)
			(layers "F.Cu" "F.Mask" "F.Paste")
			(net "P1V05_PCH_AUX")
		)
	)
	(footprint ""
		(layer "F.Cu")
		(at 440.38012 -100.27158 90)
		(property "Reference" "R4745"
			(at 0 0 90)
			(layer "F.SilkS")
			(hide yes)
			(effects
				(font
					(size 1.27 1.27)
				)
			)
		)
		(property "Value" ""
			(at 0 0 90)
			(layer "F.Fab")
			(effects
				(font
					(size 1.27 1.27)
				)
			)
		)
		(duplicate_pad_numbers_are_jumpers no)
		(fp_line
			(start 0.7874 -0.4064)
			(end 0.7874 0.4064)
			(stroke
				(width 0.1524)
				(type default)
			)
			(layer "F.SilkS")
		)
		(fp_line
			(start -0.7874 -0.4064)
			(end 0.7874 -0.4064)
			(stroke
				(width 0.1524)
				(type default)
			)
			(layer "F.SilkS")
		)
		(fp_line
			(start 0.7874 0.4064)
			(end -0.7874 0.4064)
			(stroke
				(width 0.1524)
				(type default)
			)
			(layer "F.SilkS")
		)
		(fp_line
			(start -0.7874 0.4064)
			(end -0.7874 -0.4064)
			(stroke
				(width 0.1524)
				(type default)
			)
			(layer "F.SilkS")
		)
		(fp_line
			(start -0.12065 -0.305054)
			(end -0.12065 -0.2794)
			(stroke
				(width 0.1)
				(type default)
			)
			(layer "F.Fab")
		)
		(fp_line
			(start -0.67945 -0.305054)
			(end -0.12065 -0.305054)
			(stroke
				(width 0.1)
				(type default)
			)
			(layer "F.Fab")
		)
		(fp_line
			(start 0.67945 -0.3048)
			(end 0.67945 0.3048)
			(stroke
				(width 0.1)
				(type default)
			)
			(layer "F.Fab")
		)
		(fp_line
			(start 0.12065 -0.3048)
			(end 0.67945 -0.3048)
			(stroke
				(width 0.1)
				(type default)
			)
			(layer "F.Fab")
		)
		(fp_line
			(start 0.12065 -0.2794)
			(end 0.12065 -0.3048)
			(stroke
				(width 0.1)
				(type default)
			)
			(layer "F.Fab")
		)
		(fp_line
			(start -0.12065 -0.2794)
			(end 0.12065 -0.2794)
			(stroke
				(width 0.1)
				(type default)
			)
			(layer "F.Fab")
		)
		(fp_line
			(start 0.120396 0.2794)
			(end -0.12065 0.2794)
			(stroke
				(width 0.1)
				(type default)
			)
			(layer "F.Fab")
		)
		(fp_line
			(start -0.12065 0.2794)
			(end -0.12065 0.3048)
			(stroke
				(width 0.1)
				(type default)
			)
			(layer "F.Fab")
		)
		(fp_line
			(start 0.67945 0.3048)
			(end 0.120396 0.3048)
			(stroke
				(width 0.1)
				(type default)
			)
			(layer "F.Fab")
		)
		(fp_line
			(start 0.120396 0.3048)
			(end 0.120396 0.2794)
			(stroke
				(width 0.1)
				(type default)
			)
			(layer "F.Fab")
		)
		(fp_line
			(start -0.12065 0.3048)
			(end -0.67945 0.3048)
			(stroke
				(width 0.1)
				(type default)
			)
			(layer "F.Fab")
		)
		(fp_line
			(start -0.67945 0.3048)
			(end -0.67945 -0.305054)
			(stroke
				(width 0.1)
				(type default)
			)
			(layer "F.Fab")
		)
		(pad "1" smd circle
			(at -0.40005 0 90)
			(size 0 0)
			(layers "F.Cu" "F.Mask" "F.Paste")
			(net "P3V3_AUX")
		)
		(pad "2" smd circle
			(at 0.40005 0 90)
			(size 0 0)
			(layers "F.Cu" "F.Mask" "F.Paste")
			(net "OCP_SFF_AUX_PWR_PLD_EN_R")
		)
	)
	(footprint ""
		(layer "F.Cu")
		(at 69.042534 -65.082674 -90)
		(property "Reference" "R3083"
			(at 0 0 270)
			(layer "F.SilkS")
			(hide yes)
			(effects
				(font
					(size 1.27 1.27)
				)
			)
		)
		(property "Value" ""
			(at 0 0 270)
			(layer "F.Fab")
			(effects
				(font
					(size 1.27 1.27)
				)
			)
		)
		(duplicate_pad_numbers_are_jumpers no)
		(fp_line
			(start -0.7874 0.4064)
			(end -0.7874 -0.4064)
			(stroke
				(width 0.1524)
				(type default)
			)
			(layer "F.SilkS")
		)
		(fp_line
			(start 0.7874 0.4064)
			(end -0.7874 0.4064)
			(stroke
				(width 0.1524)
				(type default)
			)
			(layer "F.SilkS")
		)
		(fp_line
			(start -0.7874 -0.4064)
			(end 0.7874 -0.4064)
			(stroke
				(width 0.1524)
				(type default)
			)
			(layer "F.SilkS")
		)
		(fp_line
			(start 0.7874 -0.4064)
			(end 0.7874 0.4064)
			(stroke
				(width 0.1524)
				(type default)
			)
			(layer "F.SilkS")
		)
		(fp_line
			(start -0.67945 0.3048)
			(end -0.67945 -0.305054)
			(stroke
				(width 0.1)
				(type default)
			)
			(layer "F.Fab")
		)
		(fp_line
			(start -0.12065 0.3048)
			(end -0.67945 0.3048)
			(stroke
				(width 0.1)
				(type default)
			)
			(layer "F.Fab")
		)
		(fp_line
			(start 0.120396 0.3048)
			(end 0.120396 0.2794)
			(stroke
				(width 0.1)
				(type default)
			)
			(layer "F.Fab")
		)
		(fp_line
			(start 0.67945 0.3048)
			(end 0.120396 0.3048)
			(stroke
				(width 0.1)
				(type default)
			)
			(layer "F.Fab")
		)
		(fp_line
			(start -0.12065 0.2794)
			(end -0.12065 0.3048)
			(stroke
				(width 0.1)
				(type default)
			)
			(layer "F.Fab")
		)
		(fp_line
			(start 0.120396 0.2794)
			(end -0.12065 0.2794)
			(stroke
				(width 0.1)
				(type default)
			)
			(layer "F.Fab")
		)
		(fp_line
			(start -0.12065 -0.2794)
			(end 0.12065 -0.2794)
			(stroke
				(width 0.1)
				(type default)
			)
			(layer "F.Fab")
		)
		(fp_line
			(start 0.12065 -0.2794)
			(end 0.12065 -0.3048)
			(stroke
				(width 0.1)
				(type default)
			)
			(layer "F.Fab")
		)
		(fp_line
			(start 0.12065 -0.3048)
			(end 0.67945 -0.3048)
			(stroke
				(width 0.1)
				(type default)
			)
			(layer "F.Fab")
		)
		(fp_line
			(start 0.67945 -0.3048)
			(end 0.67945 0.3048)
			(stroke
				(width 0.1)
				(type default)
			)
			(layer "F.Fab")
		)
		(fp_line
			(start -0.67945 -0.305054)
			(end -0.12065 -0.305054)
			(stroke
				(width 0.1)
				(type default)
			)
			(layer "F.Fab")
		)
		(fp_line
			(start -0.12065 -0.305054)
			(end -0.12065 -0.2794)
			(stroke
				(width 0.1)
				(type default)
			)
			(layer "F.Fab")
		)
		(pad "1" smd circle
			(at -0.40005 0 270)
			(size 0 0)
			(layers "F.Cu" "F.Mask" "F.Paste")
			(net "LED_RST_PLD_CPU1_DRAM_EF_N")
		)
		(pad "2" smd circle
			(at 0.40005 0 270)
			(size 0 0)
			(layers "F.Cu" "F.Mask" "F.Paste")
			(net "P3V3_AUX")
		)
	)
	(footprint ""
		(layer "F.Cu")
		(at 160.83788 -118.836948 180)
		(property "Reference" "R1409"
			(at 0 0 180)
			(layer "F.SilkS")
			(hide yes)
			(effects
				(font
					(size 1.27 1.27)
				)
			)
		)
		(property "Value" ""
			(at 0 0 180)
			(layer "F.Fab")
			(effects
				(font
					(size 1.27 1.27)
				)
			)
		)
		(duplicate_pad_numbers_are_jumpers no)
		(fp_line
			(start 0.7874 0.4064)
			(end -0.7874 0.4064)
			(stroke
				(width 0.1524)
				(type default)
			)
			(layer "F.SilkS")
		)
		(fp_line
			(start 0.7874 -0.4064)
			(end 0.7874 0.4064)
			(stroke
				(width 0.1524)
				(type default)
			)
			(layer "F.SilkS")
		)
		(fp_line
			(start -0.7874 0.4064)
			(end -0.7874 -0.4064)
			(stroke
				(width 0.1524)
				(type default)
			)
			(layer "F.SilkS")
		)
		(fp_line
			(start -0.7874 -0.4064)
			(end 0.7874 -0.4064)
			(stroke
				(width 0.1524)
				(type default)
			)
			(layer "F.SilkS")
		)
		(fp_line
			(start 0.67945 0.3048)
			(end 0.120396 0.3048)
			(stroke
				(width 0.1)
				(type default)
			)
			(layer "F.Fab")
		)
		(fp_line
			(start 0.67945 -0.3048)
			(end 0.67945 0.3048)
			(stroke
				(width 0.1)
				(type default)
			)
			(layer "F.Fab")
		)
		(fp_line
			(start 0.12065 -0.2794)
			(end 0.12065 -0.3048)
			(stroke
				(width 0.1)
				(type default)
			)
			(layer "F.Fab")
		)
		(fp_line
			(start 0.12065 -0.3048)
			(end 0.67945 -0.3048)
			(stroke
				(width 0.1)
				(type default)
			)
			(layer "F.Fab")
		)
		(fp_line
			(start 0.120396 0.3048)
			(end 0.120396 0.2794)
			(stroke
				(width 0.1)
				(type default)
			)
			(layer "F.Fab")
		)
		(fp_line
			(start 0.120396 0.2794)
			(end -0.12065 0.2794)
			(stroke
				(width 0.1)
				(type default)
			)
			(layer "F.Fab")
		)
		(fp_line
			(start -0.12065 0.3048)
			(end -0.67945 0.3048)
			(stroke
				(width 0.1)
				(type default)
			)
			(layer "F.Fab")
		)
		(fp_line
			(start -0.12065 0.2794)
			(end -0.12065 0.3048)
			(stroke
				(width 0.1)
				(type default)
			)
			(layer "F.Fab")
		)
		(fp_line
			(start -0.12065 -0.2794)
			(end 0.12065 -0.2794)
			(stroke
				(width 0.1)
				(type default)
			)
			(layer "F.Fab")
		)
		(fp_line
			(start -0.12065 -0.305054)
			(end -0.12065 -0.2794)
			(stroke
				(width 0.1)
				(type default)
			)
			(layer "F.Fab")
		)
		(fp_line
			(start -0.67945 0.3048)
			(end -0.67945 -0.305054)
			(stroke
				(width 0.1)
				(type default)
			)
			(layer "F.Fab")
		)
		(fp_line
			(start -0.67945 -0.305054)
			(end -0.12065 -0.305054)
			(stroke
				(width 0.1)
				(type default)
			)
			(layer "F.Fab")
		)
		(pad "1" smd circle
			(at -0.40005 0 180)
			(size 0 0)
			(layers "F.Cu" "F.Mask" "F.Paste")
			(net "FM_PVCCFA_EHV_CPU0_R_EN")
		)
		(pad "2" smd circle
			(at 0.40005 0 180)
			(size 0 0)
			(layers "F.Cu" "F.Mask" "F.Paste")
			(net "GND")
		)
	)
	(footprint ""
		(layer "F.Cu")
		(at 226.733608 -402.791422 180)
		(property "Reference" "PR3991"
			(at 0 0 180)
			(layer "F.SilkS")
			(hide yes)
			(effects
				(font
					(size 1.27 1.27)
				)
			)
		)
		(property "Value" ""
			(at 0 0 180)
			(layer "F.Fab")
			(effects
				(font
					(size 1.27 1.27)
				)
			)
		)
		(duplicate_pad_numbers_are_jumpers no)
		(fp_line
			(start 0.7874 0.4064)
			(end -0.7874 0.4064)
			(stroke
				(width 0.1524)
				(type default)
			)
			(layer "F.SilkS")
		)
		(fp_line
			(start 0.7874 -0.4064)
			(end 0.7874 0.4064)
			(stroke
				(width 0.1524)
				(type default)
			)
			(layer "F.SilkS")
		)
		(fp_line
			(start -0.7874 0.4064)
			(end -0.7874 -0.4064)
			(stroke
				(width 0.1524)
				(type default)
			)
			(layer "F.SilkS")
		)
		(fp_line
			(start -0.7874 -0.4064)
			(end 0.7874 -0.4064)
			(stroke
				(width 0.1524)
				(type default)
			)
			(layer "F.SilkS")
		)
		(fp_line
			(start 0.67945 0.3048)
			(end 0.120396 0.3048)
			(stroke
				(width 0.1)
				(type default)
			)
			(layer "F.Fab")
		)
		(fp_line
			(start 0.67945 -0.3048)
			(end 0.67945 0.3048)
			(stroke
				(width 0.1)
				(type default)
			)
			(layer "F.Fab")
		)
		(fp_line
			(start 0.12065 -0.2794)
			(end 0.12065 -0.3048)
			(stroke
				(width 0.1)
				(type default)
			)
			(layer "F.Fab")
		)
		(fp_line
			(start 0.12065 -0.3048)
			(end 0.67945 -0.3048)
			(stroke
				(width 0.1)
				(type default)
			)
			(layer "F.Fab")
		)
		(fp_line
			(start 0.120396 0.3048)
			(end 0.120396 0.2794)
			(stroke
				(width 0.1)
				(type default)
			)
			(layer "F.Fab")
		)
		(fp_line
			(start 0.120396 0.2794)
			(end -0.12065 0.2794)
			(stroke
				(width 0.1)
				(type default)
			)
			(layer "F.Fab")
		)
		(fp_line
			(start -0.12065 0.3048)
			(end -0.67945 0.3048)
			(stroke
				(width 0.1)
				(type default)
			)
			(layer "F.Fab")
		)
		(fp_line
			(start -0.12065 0.2794)
			(end -0.12065 0.3048)
			(stroke
				(width 0.1)
				(type default)
			)
			(layer "F.Fab")
		)
		(fp_line
			(start -0.12065 -0.2794)
			(end 0.12065 -0.2794)
			(stroke
				(width 0.1)
				(type default)
			)
			(layer "F.Fab")
		)
		(fp_line
			(start -0.12065 -0.305054)
			(end -0.12065 -0.2794)
			(stroke
				(width 0.1)
				(type default)
			)
			(layer "F.Fab")
		)
		(fp_line
			(start -0.67945 0.3048)
			(end -0.67945 -0.305054)
			(stroke
				(width 0.1)
				(type default)
			)
			(layer "F.Fab")
		)
		(fp_line
			(start -0.67945 -0.305054)
			(end -0.12065 -0.305054)
			(stroke
				(width 0.1)
				(type default)
			)
			(layer "F.Fab")
		)
		(pad "1" smd circle
			(at -0.40005 0 180)
			(size 0 0)
			(layers "F.Cu" "F.Mask" "F.Paste")
			(net "HSC_IMON")
		)
		(pad "2" smd circle
			(at 0.40005 0 180)
			(size 0 0)
			(layers "F.Cu" "F.Mask" "F.Paste")
			(net "AGND_HSC")
		)
	)
	(footprint ""
		(layer "F.Cu")
		(at 355.236018 -245.634002 -90)
		(property "Reference" "C991"
			(at 0 0 270)
			(layer "F.SilkS")
			(hide yes)
			(effects
				(font
					(size 1.27 1.27)
				)
			)
		)
		(property "Value" ""
			(at 0 0 270)
			(layer "F.Fab")
			(effects
				(font
					(size 1.27 1.27)
				)
			)
		)
		(duplicate_pad_numbers_are_jumpers no)
		(fp_line
			(start -0.7874 0.4064)
			(end -0.7874 -0.4064)
			(stroke
				(width 0.1524)
				(type default)
			)
			(layer "F.SilkS")
		)
		(fp_line
			(start 0.7874 0.4064)
			(end -0.7874 0.4064)
			(stroke
				(width 0.1524)
				(type default)
			)
			(layer "F.SilkS")
		)
		(fp_line
			(start -0.7874 -0.4064)
			(end 0.7874 -0.4064)
			(stroke
				(width 0.1524)
				(type default)
			)
			(layer "F.SilkS")
		)
		(fp_line
			(start 0.7874 -0.4064)
			(end 0.7874 0.4064)
			(stroke
				(width 0.1524)
				(type default)
			)
			(layer "F.SilkS")
		)
		(fp_line
			(start -0.67945 0.3048)
			(end -0.67945 -0.305054)
			(stroke
				(width 0.1)
				(type default)
			)
			(layer "F.Fab")
		)
		(fp_line
			(start -0.12065 0.3048)
			(end -0.67945 0.3048)
			(stroke
				(width 0.1)
				(type default)
			)
			(layer "F.Fab")
		)
		(fp_line
			(start 0.120396 0.3048)
			(end 0.120396 0.2794)
			(stroke
				(width 0.1)
				(type default)
			)
			(layer "F.Fab")
		)
		(fp_line
			(start 0.67945 0.3048)
			(end 0.120396 0.3048)
			(stroke
				(width 0.1)
				(type default)
			)
			(layer "F.Fab")
		)
		(fp_line
			(start -0.12065 0.2794)
			(end -0.12065 0.3048)
			(stroke
				(width 0.1)
				(type default)
			)
			(layer "F.Fab")
		)
		(fp_line
			(start 0.120396 0.2794)
			(end -0.12065 0.2794)
			(stroke
				(width 0.1)
				(type default)
			)
			(layer "F.Fab")
		)
		(fp_line
			(start -0.12065 -0.2794)
			(end 0.12065 -0.2794)
			(stroke
				(width 0.1)
				(type default)
			)
			(layer "F.Fab")
		)
		(fp_line
			(start 0.12065 -0.2794)
			(end 0.12065 -0.3048)
			(stroke
				(width 0.1)
				(type default)
			)
			(layer "F.Fab")
		)
		(fp_line
			(start 0.12065 -0.3048)
			(end 0.67945 -0.3048)
			(stroke
				(width 0.1)
				(type default)
			)
			(layer "F.Fab")
		)
		(fp_line
			(start 0.67945 -0.3048)
			(end 0.67945 0.3048)
			(stroke
				(width 0.1)
				(type default)
			)
			(layer "F.Fab")
		)
		(fp_line
			(start -0.67945 -0.305054)
			(end -0.12065 -0.305054)
			(stroke
				(width 0.1)
				(type default)
			)
			(layer "F.Fab")
		)
		(fp_line
			(start -0.12065 -0.305054)
			(end -0.12065 -0.2794)
			(stroke
				(width 0.1)
				(type default)
			)
			(layer "F.Fab")
		)
		(pad "1" smd circle
			(at -0.40005 0 270)
			(size 0 0)
			(layers "F.Cu" "F.Mask" "F.Paste")
			(net "PVCCIN_CPU0")
		)
		(pad "2" smd circle
			(at 0.40005 0 270)
			(size 0 0)
			(layers "F.Cu" "F.Mask" "F.Paste")
			(net "GND")
		)
	)
	(footprint ""
		(layer "F.Cu")
		(at 15.436596 -393.215876 180)
		(property "Reference" "R3276"
			(at 0 0 180)
			(layer "F.SilkS")
			(hide yes)
			(effects
				(font
					(size 1.27 1.27)
				)
			)
		)
		(property "Value" ""
			(at 0 0 180)
			(layer "F.Fab")
			(effects
				(font
					(size 1.27 1.27)
				)
			)
		)
		(duplicate_pad_numbers_are_jumpers no)
		(fp_line
			(start 0.7874 0.4064)
			(end -0.7874 0.4064)
			(stroke
				(width 0.1524)
				(type default)
			)
			(layer "F.SilkS")
		)
		(fp_line
			(start 0.7874 -0.4064)
			(end 0.7874 0.4064)
			(stroke
				(width 0.1524)
				(type default)
			)
			(layer "F.SilkS")
		)
		(fp_line
			(start -0.7874 0.4064)
			(end -0.7874 -0.4064)
			(stroke
				(width 0.1524)
				(type default)
			)
			(layer "F.SilkS")
		)
		(fp_line
			(start -0.7874 -0.4064)
			(end 0.7874 -0.4064)
			(stroke
				(width 0.1524)
				(type default)
			)
			(layer "F.SilkS")
		)
		(fp_line
			(start 0.67945 0.3048)
			(end 0.120396 0.3048)
			(stroke
				(width 0.1)
				(type default)
			)
			(layer "F.Fab")
		)
		(fp_line
			(start 0.67945 -0.3048)
			(end 0.67945 0.3048)
			(stroke
				(width 0.1)
				(type default)
			)
			(layer "F.Fab")
		)
		(fp_line
			(start 0.12065 -0.2794)
			(end 0.12065 -0.3048)
			(stroke
				(width 0.1)
				(type default)
			)
			(layer "F.Fab")
		)
		(fp_line
			(start 0.12065 -0.3048)
			(end 0.67945 -0.3048)
			(stroke
				(width 0.1)
				(type default)
			)
			(layer "F.Fab")
		)
		(fp_line
			(start 0.120396 0.3048)
			(end 0.120396 0.2794)
			(stroke
				(width 0.1)
				(type default)
			)
			(layer "F.Fab")
		)
		(fp_line
			(start 0.120396 0.2794)
			(end -0.12065 0.2794)
			(stroke
				(width 0.1)
				(type default)
			)
			(layer "F.Fab")
		)
		(fp_line
			(start -0.12065 0.3048)
			(end -0.67945 0.3048)
			(stroke
				(width 0.1)
				(type default)
			)
			(layer "F.Fab")
		)
		(fp_line
			(start -0.12065 0.2794)
			(end -0.12065 0.3048)
			(stroke
				(width 0.1)
				(type default)
			)
			(layer "F.Fab")
		)
		(fp_line
			(start -0.12065 -0.2794)
			(end 0.12065 -0.2794)
			(stroke
				(width 0.1)
				(type default)
			)
			(layer "F.Fab")
		)
		(fp_line
			(start -0.12065 -0.305054)
			(end -0.12065 -0.2794)
			(stroke
				(width 0.1)
				(type default)
			)
			(layer "F.Fab")
		)
		(fp_line
			(start -0.67945 0.3048)
			(end -0.67945 -0.305054)
			(stroke
				(width 0.1)
				(type default)
			)
			(layer "F.Fab")
		)
		(fp_line
			(start -0.67945 -0.305054)
			(end -0.12065 -0.305054)
			(stroke
				(width 0.1)
				(type default)
			)
			(layer "F.Fab")
		)
		(pad "1" smd circle
			(at -0.40005 0 180)
			(size 0 0)
			(layers "F.Cu" "F.Mask" "F.Paste")
			(net "FM_P2E_FGA")
		)
		(pad "2" smd circle
			(at 0.40005 0 180)
			(size 0 0)
			(layers "F.Cu" "F.Mask" "F.Paste")
			(net "GND")
		)
	)
	(footprint ""
		(layer "F.Cu")
		(at 431.989992 -391.505948 180)
		(property "Reference" "R2836"
			(at 0 0 180)
			(layer "F.SilkS")
			(hide yes)
			(effects
				(font
					(size 1.27 1.27)
				)
			)
		)
		(property "Value" ""
			(at 0 0 180)
			(layer "F.Fab")
			(effects
				(font
					(size 1.27 1.27)
				)
			)
		)
		(duplicate_pad_numbers_are_jumpers no)
		(fp_line
			(start 0.7874 0.4064)
			(end -0.7874 0.4064)
			(stroke
				(width 0.1524)
				(type default)
			)
			(layer "F.SilkS")
		)
		(fp_line
			(start 0.7874 -0.4064)
			(end 0.7874 0.4064)
			(stroke
				(width 0.1524)
				(type default)
			)
			(layer "F.SilkS")
		)
		(fp_line
			(start -0.7874 0.4064)
			(end -0.7874 -0.4064)
			(stroke
				(width 0.1524)
				(type default)
			)
			(layer "F.SilkS")
		)
		(fp_line
			(start -0.7874 -0.4064)
			(end 0.7874 -0.4064)
			(stroke
				(width 0.1524)
				(type default)
			)
			(layer "F.SilkS")
		)
		(fp_line
			(start 0.67945 0.3048)
			(end 0.120396 0.3048)
			(stroke
				(width 0.1)
				(type default)
			)
			(layer "F.Fab")
		)
		(fp_line
			(start 0.67945 -0.3048)
			(end 0.67945 0.3048)
			(stroke
				(width 0.1)
				(type default)
			)
			(layer "F.Fab")
		)
		(fp_line
			(start 0.12065 -0.2794)
			(end 0.12065 -0.3048)
			(stroke
				(width 0.1)
				(type default)
			)
			(layer "F.Fab")
		)
		(fp_line
			(start 0.12065 -0.3048)
			(end 0.67945 -0.3048)
			(stroke
				(width 0.1)
				(type default)
			)
			(layer "F.Fab")
		)
		(fp_line
			(start 0.120396 0.3048)
			(end 0.120396 0.2794)
			(stroke
				(width 0.1)
				(type default)
			)
			(layer "F.Fab")
		)
		(fp_line
			(start 0.120396 0.2794)
			(end -0.12065 0.2794)
			(stroke
				(width 0.1)
				(type default)
			)
			(layer "F.Fab")
		)
		(fp_line
			(start -0.12065 0.3048)
			(end -0.67945 0.3048)
			(stroke
				(width 0.1)
				(type default)
			)
			(layer "F.Fab")
		)
		(fp_line
			(start -0.12065 0.2794)
			(end -0.12065 0.3048)
			(stroke
				(width 0.1)
				(type default)
			)
			(layer "F.Fab")
		)
		(fp_line
			(start -0.12065 -0.2794)
			(end 0.12065 -0.2794)
			(stroke
				(width 0.1)
				(type default)
			)
			(layer "F.Fab")
		)
		(fp_line
			(start -0.12065 -0.305054)
			(end -0.12065 -0.2794)
			(stroke
				(width 0.1)
				(type default)
			)
			(layer "F.Fab")
		)
		(fp_line
			(start -0.67945 0.3048)
			(end -0.67945 -0.305054)
			(stroke
				(width 0.1)
				(type default)
			)
			(layer "F.Fab")
		)
		(fp_line
			(start -0.67945 -0.305054)
			(end -0.12065 -0.305054)
			(stroke
				(width 0.1)
				(type default)
			)
			(layer "F.Fab")
		)
		(pad "1" smd circle
			(at -0.40005 0 180)
			(size 0 0)
			(layers "F.Cu" "F.Mask" "F.Paste")
			(net "P3V3_AUX")
		)
		(pad "2" smd circle
			(at 0.40005 0 180)
			(size 0 0)
			(layers "F.Cu" "F.Mask" "F.Paste")
			(net "FM_SWB_BIC_READY")
		)
	)
	(footprint ""
		(layer "F.Cu")
		(at 315.110622 -55.235348 180)
		(property "Reference" "R1497"
			(at 0 0 180)
			(layer "F.SilkS")
			(hide yes)
			(effects
				(font
					(size 1.27 1.27)
				)
			)
		)
		(property "Value" ""
			(at 0 0 180)
			(layer "F.Fab")
			(effects
				(font
					(size 1.27 1.27)
				)
			)
		)
		(duplicate_pad_numbers_are_jumpers no)
		(fp_line
			(start 0.7874 0.4064)
			(end -0.7874 0.4064)
			(stroke
				(width 0.1524)
				(type default)
			)
			(layer "F.SilkS")
		)
		(fp_line
			(start 0.7874 -0.4064)
			(end 0.7874 0.4064)
			(stroke
				(width 0.1524)
				(type default)
			)
			(layer "F.SilkS")
		)
		(fp_line
			(start -0.7874 0.4064)
			(end -0.7874 -0.4064)
			(stroke
				(width 0.1524)
				(type default)
			)
			(layer "F.SilkS")
		)
		(fp_line
			(start -0.7874 -0.4064)
			(end 0.7874 -0.4064)
			(stroke
				(width 0.1524)
				(type default)
			)
			(layer "F.SilkS")
		)
		(fp_line
			(start 0.67945 0.3048)
			(end 0.120396 0.3048)
			(stroke
				(width 0.1)
				(type default)
			)
			(layer "F.Fab")
		)
		(fp_line
			(start 0.67945 -0.3048)
			(end 0.67945 0.3048)
			(stroke
				(width 0.1)
				(type default)
			)
			(layer "F.Fab")
		)
		(fp_line
			(start 0.12065 -0.2794)
			(end 0.12065 -0.3048)
			(stroke
				(width 0.1)
				(type default)
			)
			(layer "F.Fab")
		)
		(fp_line
			(start 0.12065 -0.3048)
			(end 0.67945 -0.3048)
			(stroke
				(width 0.1)
				(type default)
			)
			(layer "F.Fab")
		)
		(fp_line
			(start 0.120396 0.3048)
			(end 0.120396 0.2794)
			(stroke
				(width 0.1)
				(type default)
			)
			(layer "F.Fab")
		)
		(fp_line
			(start 0.120396 0.2794)
			(end -0.12065 0.2794)
			(stroke
				(width 0.1)
				(type default)
			)
			(layer "F.Fab")
		)
		(fp_line
			(start -0.12065 0.3048)
			(end -0.67945 0.3048)
			(stroke
				(width 0.1)
				(type default)
			)
			(layer "F.Fab")
		)
		(fp_line
			(start -0.12065 0.2794)
			(end -0.12065 0.3048)
			(stroke
				(width 0.1)
				(type default)
			)
			(layer "F.Fab")
		)
		(fp_line
			(start -0.12065 -0.2794)
			(end 0.12065 -0.2794)
			(stroke
				(width 0.1)
				(type default)
			)
			(layer "F.Fab")
		)
		(fp_line
			(start -0.12065 -0.305054)
			(end -0.12065 -0.2794)
			(stroke
				(width 0.1)
				(type default)
			)
			(layer "F.Fab")
		)
		(fp_line
			(start -0.67945 0.3048)
			(end -0.67945 -0.305054)
			(stroke
				(width 0.1)
				(type default)
			)
			(layer "F.Fab")
		)
		(fp_line
			(start -0.67945 -0.305054)
			(end -0.12065 -0.305054)
			(stroke
				(width 0.1)
				(type default)
			)
			(layer "F.Fab")
		)
		(pad "1" smd circle
			(at -0.40005 0 180)
			(size 0 0)
			(layers "F.Cu" "F.Mask" "F.Paste")
			(net "FM_PCH_DFXTESTMODE")
		)
		(pad "2" smd circle
			(at 0.40005 0 180)
			(size 0 0)
			(layers "F.Cu" "F.Mask" "F.Paste")
			(net "GND")
		)
	)
	(footprint ""
		(layer "F.Cu")
		(at 463.82305 -382.610614 90)
		(property "Reference" "PC1648"
			(at 0 0 90)
			(layer "F.SilkS")
			(hide yes)
			(effects
				(font
					(size 1.27 1.27)
				)
			)
		)
		(property "Value" ""
			(at 0 0 90)
			(layer "F.Fab")
			(effects
				(font
					(size 1.27 1.27)
				)
			)
		)
		(duplicate_pad_numbers_are_jumpers no)
		(fp_line
			(start 0.7874 -0.4064)
			(end 0.7874 0.4064)
			(stroke
				(width 0.1524)
				(type default)
			)
			(layer "F.SilkS")
		)
		(fp_line
			(start -0.7874 -0.4064)
			(end 0.7874 -0.4064)
			(stroke
				(width 0.1524)
				(type default)
			)
			(layer "F.SilkS")
		)
		(fp_line
			(start 0.7874 0.4064)
			(end -0.7874 0.4064)
			(stroke
				(width 0.1524)
				(type default)
			)
			(layer "F.SilkS")
		)
		(fp_line
			(start -0.7874 0.4064)
			(end -0.7874 -0.4064)
			(stroke
				(width 0.1524)
				(type default)
			)
			(layer "F.SilkS")
		)
		(fp_line
			(start -0.12065 -0.305054)
			(end -0.12065 -0.2794)
			(stroke
				(width 0.1)
				(type default)
			)
			(layer "F.Fab")
		)
		(fp_line
			(start -0.67945 -0.305054)
			(end -0.12065 -0.305054)
			(stroke
				(width 0.1)
				(type default)
			)
			(layer "F.Fab")
		)
		(fp_line
			(start 0.67945 -0.3048)
			(end 0.67945 0.3048)
			(stroke
				(width 0.1)
				(type default)
			)
			(layer "F.Fab")
		)
		(fp_line
			(start 0.12065 -0.3048)
			(end 0.67945 -0.3048)
			(stroke
				(width 0.1)
				(type default)
			)
			(layer "F.Fab")
		)
		(fp_line
			(start 0.12065 -0.2794)
			(end 0.12065 -0.3048)
			(stroke
				(width 0.1)
				(type default)
			)
			(layer "F.Fab")
		)
		(fp_line
			(start -0.12065 -0.2794)
			(end 0.12065 -0.2794)
			(stroke
				(width 0.1)
				(type default)
			)
			(layer "F.Fab")
		)
		(fp_line
			(start 0.120396 0.2794)
			(end -0.12065 0.2794)
			(stroke
				(width 0.1)
				(type default)
			)
			(layer "F.Fab")
		)
		(fp_line
			(start -0.12065 0.2794)
			(end -0.12065 0.3048)
			(stroke
				(width 0.1)
				(type default)
			)
			(layer "F.Fab")
		)
		(fp_line
			(start 0.67945 0.3048)
			(end 0.120396 0.3048)
			(stroke
				(width 0.1)
				(type default)
			)
			(layer "F.Fab")
		)
		(fp_line
			(start 0.120396 0.3048)
			(end 0.120396 0.2794)
			(stroke
				(width 0.1)
				(type default)
			)
			(layer "F.Fab")
		)
		(fp_line
			(start -0.12065 0.3048)
			(end -0.67945 0.3048)
			(stroke
				(width 0.1)
				(type default)
			)
			(layer "F.Fab")
		)
		(fp_line
			(start -0.67945 0.3048)
			(end -0.67945 -0.305054)
			(stroke
				(width 0.1)
				(type default)
			)
			(layer "F.Fab")
		)
		(pad "1" smd circle
			(at -0.40005 0 90)
			(size 0 0)
			(layers "F.Cu" "F.Mask" "F.Paste")
			(net "P12V_AUX")
		)
		(pad "2" smd circle
			(at 0.40005 0 90)
			(size 0 0)
			(layers "F.Cu" "F.Mask" "F.Paste")
			(net "GND")
		)
	)
	(footprint ""
		(layer "F.Cu")
		(at 120.36044 -426.075348 180)
		(property "Reference" "R2936"
			(at 0 0 180)
			(layer "F.SilkS")
			(hide yes)
			(effects
				(font
					(size 1.27 1.27)
				)
			)
		)
		(property "Value" ""
			(at 0 0 180)
			(layer "F.Fab")
			(effects
				(font
					(size 1.27 1.27)
				)
			)
		)
		(duplicate_pad_numbers_are_jumpers no)
		(fp_line
			(start 0.7874 0.4064)
			(end -0.7874 0.4064)
			(stroke
				(width 0.1524)
				(type default)
			)
			(layer "F.SilkS")
		)
		(fp_line
			(start 0.7874 -0.4064)
			(end 0.7874 0.4064)
			(stroke
				(width 0.1524)
				(type default)
			)
			(layer "F.SilkS")
		)
		(fp_line
			(start -0.7874 0.4064)
			(end -0.7874 -0.4064)
			(stroke
				(width 0.1524)
				(type default)
			)
			(layer "F.SilkS")
		)
		(fp_line
			(start -0.7874 -0.4064)
			(end 0.7874 -0.4064)
			(stroke
				(width 0.1524)
				(type default)
			)
			(layer "F.SilkS")
		)
		(fp_line
			(start 0.67945 0.3048)
			(end 0.120396 0.3048)
			(stroke
				(width 0.1)
				(type default)
			)
			(layer "F.Fab")
		)
		(fp_line
			(start 0.67945 -0.3048)
			(end 0.67945 0.3048)
			(stroke
				(width 0.1)
				(type default)
			)
			(layer "F.Fab")
		)
		(fp_line
			(start 0.12065 -0.2794)
			(end 0.12065 -0.3048)
			(stroke
				(width 0.1)
				(type default)
			)
			(layer "F.Fab")
		)
		(fp_line
			(start 0.12065 -0.3048)
			(end 0.67945 -0.3048)
			(stroke
				(width 0.1)
				(type default)
			)
			(layer "F.Fab")
		)
		(fp_line
			(start 0.120396 0.3048)
			(end 0.120396 0.2794)
			(stroke
				(width 0.1)
				(type default)
			)
			(layer "F.Fab")
		)
		(fp_line
			(start 0.120396 0.2794)
			(end -0.12065 0.2794)
			(stroke
				(width 0.1)
				(type default)
			)
			(layer "F.Fab")
		)
		(fp_line
			(start -0.12065 0.3048)
			(end -0.67945 0.3048)
			(stroke
				(width 0.1)
				(type default)
			)
			(layer "F.Fab")
		)
		(fp_line
			(start -0.12065 0.2794)
			(end -0.12065 0.3048)
			(stroke
				(width 0.1)
				(type default)
			)
			(layer "F.Fab")
		)
		(fp_line
			(start -0.12065 -0.2794)
			(end 0.12065 -0.2794)
			(stroke
				(width 0.1)
				(type default)
			)
			(layer "F.Fab")
		)
		(fp_line
			(start -0.12065 -0.305054)
			(end -0.12065 -0.2794)
			(stroke
				(width 0.1)
				(type default)
			)
			(layer "F.Fab")
		)
		(fp_line
			(start -0.67945 0.3048)
			(end -0.67945 -0.305054)
			(stroke
				(width 0.1)
				(type default)
			)
			(layer "F.Fab")
		)
		(fp_line
			(start -0.67945 -0.305054)
			(end -0.12065 -0.305054)
			(stroke
				(width 0.1)
				(type default)
			)
			(layer "F.Fab")
		)
		(pad "1" smd circle
			(at -0.40005 0 180)
			(size 0 0)
			(layers "F.Cu" "F.Mask" "F.Paste")
			(net "P3V3_AUX")
		)
		(pad "2" smd circle
			(at 0.40005 0 180)
			(size 0 0)
			(layers "F.Cu" "F.Mask" "F.Paste")
			(net "FM_GPU_PWR_EN_R")
		)
	)
	(footprint ""
		(layer "F.Cu")
		(at 74.2188 -35.347148 180)
		(property "Reference" "R3590"
			(at 0 0 180)
			(layer "F.SilkS")
			(hide yes)
			(effects
				(font
					(size 1.27 1.27)
				)
			)
		)
		(property "Value" ""
			(at 0 0 180)
			(layer "F.Fab")
			(effects
				(font
					(size 1.27 1.27)
				)
			)
		)
		(duplicate_pad_numbers_are_jumpers no)
		(fp_line
			(start 0.7874 0.4064)
			(end -0.7874 0.4064)
			(stroke
				(width 0.1524)
				(type default)
			)
			(layer "F.SilkS")
		)
		(fp_line
			(start 0.7874 -0.4064)
			(end 0.7874 0.4064)
			(stroke
				(width 0.1524)
				(type default)
			)
			(layer "F.SilkS")
		)
		(fp_line
			(start -0.7874 0.4064)
			(end -0.7874 -0.4064)
			(stroke
				(width 0.1524)
				(type default)
			)
			(layer "F.SilkS")
		)
		(fp_line
			(start -0.7874 -0.4064)
			(end 0.7874 -0.4064)
			(stroke
				(width 0.1524)
				(type default)
			)
			(layer "F.SilkS")
		)
		(fp_line
			(start 0.67945 0.3048)
			(end 0.120396 0.3048)
			(stroke
				(width 0.1)
				(type default)
			)
			(layer "F.Fab")
		)
		(fp_line
			(start 0.67945 -0.3048)
			(end 0.67945 0.3048)
			(stroke
				(width 0.1)
				(type default)
			)
			(layer "F.Fab")
		)
		(fp_line
			(start 0.12065 -0.2794)
			(end 0.12065 -0.3048)
			(stroke
				(width 0.1)
				(type default)
			)
			(layer "F.Fab")
		)
		(fp_line
			(start 0.12065 -0.3048)
			(end 0.67945 -0.3048)
			(stroke
				(width 0.1)
				(type default)
			)
			(layer "F.Fab")
		)
		(fp_line
			(start 0.120396 0.3048)
			(end 0.120396 0.2794)
			(stroke
				(width 0.1)
				(type default)
			)
			(layer "F.Fab")
		)
		(fp_line
			(start 0.120396 0.2794)
			(end -0.12065 0.2794)
			(stroke
				(width 0.1)
				(type default)
			)
			(layer "F.Fab")
		)
		(fp_line
			(start -0.12065 0.3048)
			(end -0.67945 0.3048)
			(stroke
				(width 0.1)
				(type default)
			)
			(layer "F.Fab")
		)
		(fp_line
			(start -0.12065 0.2794)
			(end -0.12065 0.3048)
			(stroke
				(width 0.1)
				(type default)
			)
			(layer "F.Fab")
		)
		(fp_line
			(start -0.12065 -0.2794)
			(end 0.12065 -0.2794)
			(stroke
				(width 0.1)
				(type default)
			)
			(layer "F.Fab")
		)
		(fp_line
			(start -0.12065 -0.305054)
			(end -0.12065 -0.2794)
			(stroke
				(width 0.1)
				(type default)
			)
			(layer "F.Fab")
		)
		(fp_line
			(start -0.67945 0.3048)
			(end -0.67945 -0.305054)
			(stroke
				(width 0.1)
				(type default)
			)
			(layer "F.Fab")
		)
		(fp_line
			(start -0.67945 -0.305054)
			(end -0.12065 -0.305054)
			(stroke
				(width 0.1)
				(type default)
			)
			(layer "F.Fab")
		)
		(pad "1" smd circle
			(at -0.40005 0 180)
			(size 0 0)
			(layers "F.Cu" "F.Mask" "F.Paste")
			(net "SMB_INA230_3V3AUX_SCL")
		)
		(pad "2" smd circle
			(at 0.40005 0 180)
			(size 0 0)
			(layers "F.Cu" "F.Mask" "F.Paste")
			(net "SMB_INA230_3_3V3AUX_SCL_R")
		)
	)
	(footprint ""
		(layer "F.Cu")
		(at 429.48225 -362.18368 -90)
		(property "Reference" "PC1175_P0_3"
			(at 0 0 270)
			(layer "F.SilkS")
			(hide yes)
			(effects
				(font
					(size 1.27 1.27)
				)
			)
		)
		(property "Value" ""
			(at 0 0 270)
			(layer "F.Fab")
			(effects
				(font
					(size 1.27 1.27)
				)
			)
		)
		(duplicate_pad_numbers_are_jumpers no)
		(fp_line
			(start -0.7874 0.4064)
			(end -0.7874 -0.4064)
			(stroke
				(width 0.1524)
				(type default)
			)
			(layer "F.SilkS")
		)
		(fp_line
			(start 0.7874 0.4064)
			(end -0.7874 0.4064)
			(stroke
				(width 0.1524)
				(type default)
			)
			(layer "F.SilkS")
		)
		(fp_line
			(start -0.7874 -0.4064)
			(end 0.7874 -0.4064)
			(stroke
				(width 0.1524)
				(type default)
			)
			(layer "F.SilkS")
		)
		(fp_line
			(start 0.7874 -0.4064)
			(end 0.7874 0.4064)
			(stroke
				(width 0.1524)
				(type default)
			)
			(layer "F.SilkS")
		)
		(fp_line
			(start -0.67945 0.3048)
			(end -0.67945 -0.305054)
			(stroke
				(width 0.1)
				(type default)
			)
			(layer "F.Fab")
		)
		(fp_line
			(start -0.12065 0.3048)
			(end -0.67945 0.3048)
			(stroke
				(width 0.1)
				(type default)
			)
			(layer "F.Fab")
		)
		(fp_line
			(start 0.120396 0.3048)
			(end 0.120396 0.2794)
			(stroke
				(width 0.1)
				(type default)
			)
			(layer "F.Fab")
		)
		(fp_line
			(start 0.67945 0.3048)
			(end 0.120396 0.3048)
			(stroke
				(width 0.1)
				(type default)
			)
			(layer "F.Fab")
		)
		(fp_line
			(start -0.12065 0.2794)
			(end -0.12065 0.3048)
			(stroke
				(width 0.1)
				(type default)
			)
			(layer "F.Fab")
		)
		(fp_line
			(start 0.120396 0.2794)
			(end -0.12065 0.2794)
			(stroke
				(width 0.1)
				(type default)
			)
			(layer "F.Fab")
		)
		(fp_line
			(start -0.12065 -0.2794)
			(end 0.12065 -0.2794)
			(stroke
				(width 0.1)
				(type default)
			)
			(layer "F.Fab")
		)
		(fp_line
			(start 0.12065 -0.2794)
			(end 0.12065 -0.3048)
			(stroke
				(width 0.1)
				(type default)
			)
			(layer "F.Fab")
		)
		(fp_line
			(start 0.12065 -0.3048)
			(end 0.67945 -0.3048)
			(stroke
				(width 0.1)
				(type default)
			)
			(layer "F.Fab")
		)
		(fp_line
			(start 0.67945 -0.3048)
			(end 0.67945 0.3048)
			(stroke
				(width 0.1)
				(type default)
			)
			(layer "F.Fab")
		)
		(fp_line
			(start -0.67945 -0.305054)
			(end -0.12065 -0.305054)
			(stroke
				(width 0.1)
				(type default)
			)
			(layer "F.Fab")
		)
		(fp_line
			(start -0.12065 -0.305054)
			(end -0.12065 -0.2794)
			(stroke
				(width 0.1)
				(type default)
			)
			(layer "F.Fab")
		)
		(pad "1" smd circle
			(at -0.40005 0 270)
			(size 0 0)
			(layers "F.Cu" "F.Mask" "F.Paste")
			(net "SW_P12V_PVCCFA_EHV_FIVRA_CPU0_R")
		)
		(pad "2" smd circle
			(at 0.40005 0 270)
			(size 0 0)
			(layers "F.Cu" "F.Mask" "F.Paste")
			(net "GND")
		)
	)
	(footprint ""
		(layer "F.Cu")
		(at 295.72204 -367.357152 -90)
		(property "Reference" "PC1350"
			(at 0 0 270)
			(layer "F.SilkS")
			(hide yes)
			(effects
				(font
					(size 1.27 1.27)
				)
			)
		)
		(property "Value" ""
			(at 0 0 270)
			(layer "F.Fab")
			(effects
				(font
					(size 1.27 1.27)
				)
			)
		)
		(duplicate_pad_numbers_are_jumpers no)
		(fp_line
			(start -0.7874 0.4064)
			(end -0.7874 -0.4064)
			(stroke
				(width 0.1524)
				(type default)
			)
			(layer "F.SilkS")
		)
		(fp_line
			(start 0.7874 0.4064)
			(end -0.7874 0.4064)
			(stroke
				(width 0.1524)
				(type default)
			)
			(layer "F.SilkS")
		)
		(fp_line
			(start -0.7874 -0.4064)
			(end 0.7874 -0.4064)
			(stroke
				(width 0.1524)
				(type default)
			)
			(layer "F.SilkS")
		)
		(fp_line
			(start 0.7874 -0.4064)
			(end 0.7874 0.4064)
			(stroke
				(width 0.1524)
				(type default)
			)
			(layer "F.SilkS")
		)
		(fp_line
			(start -0.67945 0.3048)
			(end -0.67945 -0.305054)
			(stroke
				(width 0.1)
				(type default)
			)
			(layer "F.Fab")
		)
		(fp_line
			(start -0.12065 0.3048)
			(end -0.67945 0.3048)
			(stroke
				(width 0.1)
				(type default)
			)
			(layer "F.Fab")
		)
		(fp_line
			(start 0.120396 0.3048)
			(end 0.120396 0.2794)
			(stroke
				(width 0.1)
				(type default)
			)
			(layer "F.Fab")
		)
		(fp_line
			(start 0.67945 0.3048)
			(end 0.120396 0.3048)
			(stroke
				(width 0.1)
				(type default)
			)
			(layer "F.Fab")
		)
		(fp_line
			(start -0.12065 0.2794)
			(end -0.12065 0.3048)
			(stroke
				(width 0.1)
				(type default)
			)
			(layer "F.Fab")
		)
		(fp_line
			(start 0.120396 0.2794)
			(end -0.12065 0.2794)
			(stroke
				(width 0.1)
				(type default)
			)
			(layer "F.Fab")
		)
		(fp_line
			(start -0.12065 -0.2794)
			(end 0.12065 -0.2794)
			(stroke
				(width 0.1)
				(type default)
			)
			(layer "F.Fab")
		)
		(fp_line
			(start 0.12065 -0.2794)
			(end 0.12065 -0.3048)
			(stroke
				(width 0.1)
				(type default)
			)
			(layer "F.Fab")
		)
		(fp_line
			(start 0.12065 -0.3048)
			(end 0.67945 -0.3048)
			(stroke
				(width 0.1)
				(type default)
			)
			(layer "F.Fab")
		)
		(fp_line
			(start 0.67945 -0.3048)
			(end 0.67945 0.3048)
			(stroke
				(width 0.1)
				(type default)
			)
			(layer "F.Fab")
		)
		(fp_line
			(start -0.67945 -0.305054)
			(end -0.12065 -0.305054)
			(stroke
				(width 0.1)
				(type default)
			)
			(layer "F.Fab")
		)
		(fp_line
			(start -0.12065 -0.305054)
			(end -0.12065 -0.2794)
			(stroke
				(width 0.1)
				(type default)
			)
			(layer "F.Fab")
		)
		(pad "1" smd circle
			(at -0.40005 0 270)
			(size 0 0)
			(layers "F.Cu" "F.Mask" "F.Paste")
			(net "GND")
		)
		(pad "2" smd circle
			(at 0.40005 0 270)
			(size 0 0)
			(layers "F.Cu" "F.Mask" "F.Paste")
			(net "PVCCIN_CPU0_VREF")
		)
	)
	(footprint ""
		(layer "F.Cu")
		(at 46.548294 -17.623536 90)
		(property "Reference" "C828"
			(at 0 0 90)
			(layer "F.SilkS")
			(hide yes)
			(effects
				(font
					(size 1.27 1.27)
				)
			)
		)
		(property "Value" ""
			(at 0 0 90)
			(layer "F.Fab")
			(effects
				(font
					(size 1.27 1.27)
				)
			)
		)
		(duplicate_pad_numbers_are_jumpers no)
		(fp_line
			(start 0.299974 -0.150114)
			(end 0.299974 0.150114)
			(stroke
				(width 0.1)
				(type default)
			)
			(layer "F.Fab")
		)
		(fp_line
			(start -0.299974 -0.150114)
			(end 0.299974 -0.150114)
			(stroke
				(width 0.1)
				(type default)
			)
			(layer "F.Fab")
		)
		(fp_line
			(start 0.299974 0.150114)
			(end -0.299974 0.150114)
			(stroke
				(width 0.1)
				(type default)
			)
			(layer "F.Fab")
		)
		(fp_line
			(start -0.299974 0.150114)
			(end -0.299974 -0.150114)
			(stroke
				(width 0.1)
				(type default)
			)
			(layer "F.Fab")
		)
		(pad "1" smd rect
			(at -0.2667 0 90)
			(size 0.3048 0.381)
			(layers "F.Cu" "F.Mask" "F.Paste")
			(net "P5E_CPU1_PE1_TX_C_DN<4>")
		)
		(pad "2" smd rect
			(at 0.2667 0 90)
			(size 0.3048 0.381)
			(layers "F.Cu" "F.Mask" "F.Paste")
			(net "P5E_CPU1_PE1_TX_DN<4>")
		)
	)
	(footprint ""
		(layer "F.Cu")
		(at 206.12608 -258.091686)
		(property "Reference" "J32"
			(at 0.68834 -81.826608 0)
			(unlocked yes)
			(layer "F.SilkS")
			(effects
				(font
					(size 0.7874 0.5842)
					(thickness 0.1524)
				)
				(justify left)
			)
		)
		(property "Value" ""
			(at 0 0 0)
			(layer "F.Fab")
			(effects
				(font
					(size 1.27 1.27)
				)
			)
		)
		(duplicate_pad_numbers_are_jumpers no)
		(fp_line
			(start -3.24993 -81.000092)
			(end -3.24993 75.914758)
			(stroke
				(width 0.1524)
				(type default)
			)
			(layer "F.SilkS")
		)
		(fp_line
			(start -3.24993 77.471778)
			(end -3.24993 81.000092)
			(stroke
				(width 0.1524)
				(type default)
			)
			(layer "F.SilkS")
		)
		(fp_line
			(start -3.24993 81.000092)
			(end 3.24993 81.000092)
			(stroke
				(width 0.1524)
				(type default)
			)
			(layer "F.SilkS")
		)
		(fp_line
			(start 3.24993 -81.000092)
			(end -3.24993 -81.000092)
			(stroke
				(width 0.1524)
				(type default)
			)
			(layer "F.SilkS")
		)
		(fp_line
			(start 3.24993 -72.00011)
			(end -3.24993 -72.00011)
			(stroke
				(width 0.1524)
				(type default)
			)
			(layer "F.SilkS")
		)
		(fp_line
			(start 3.24993 72.00011)
			(end -3.24993 72.00011)
			(stroke
				(width 0.1524)
				(type default)
			)
			(layer "F.SilkS")
		)
		(fp_line
			(start 3.24993 73.062338)
			(end 3.24993 -81.000092)
			(stroke
				(width 0.1524)
				(type default)
			)
			(layer "F.SilkS")
		)
		(fp_line
			(start 3.24993 81.000092)
			(end 3.24993 74.715878)
			(stroke
				(width 0.1524)
				(type default)
			)
			(layer "F.SilkS")
		)
		(fp_poly
			(pts
				(xy -4.197858 -63.809118) (xy -3.325368 -63.372746) (xy -4.197858 -62.936374)
			)
			(stroke
				(width 0)
				(type default)
			)
			(fill yes)
			(layer "F.SilkS")
		)
		(fp_line
			(start -3.24993 -81.000092)
			(end -3.24993 81.000092)
			(stroke
				(width 0.1)
				(type default)
			)
			(layer "F.Fab")
		)
		(fp_line
			(start -3.24993 81.000092)
			(end 3.24993 81.000092)
			(stroke
				(width 0.1)
				(type default)
			)
			(layer "F.Fab")
		)
		(fp_line
			(start 3.24993 -81.000092)
			(end -3.24993 -81.000092)
			(stroke
				(width 0.1)
				(type default)
			)
			(layer "F.Fab")
		)
		(fp_line
			(start 3.24993 -72.00011)
			(end -3.24993 -72.00011)
			(stroke
				(width 0.1)
				(type default)
			)
			(layer "F.Fab")
		)
		(fp_line
			(start 3.24993 -71.000112)
			(end -3.24993 -71.000112)
			(stroke
				(width 0.1)
				(type default)
			)
			(layer "F.Fab")
		)
		(fp_line
			(start 3.24993 71.000112)
			(end -3.24993 71.000112)
			(stroke
				(width 0.1)
				(type default)
			)
			(layer "F.Fab")
		)
		(fp_line
			(start 3.24993 72.00011)
			(end -3.24993 72.00011)
			(stroke
				(width 0.1)
				(type default)
			)
			(layer "F.Fab")
		)
		(fp_line
			(start 3.24993 81.000092)
			(end 3.24993 -81.000092)
			(stroke
				(width 0.1)
				(type default)
			)
			(layer "F.Fab")
		)
		(fp_poly
			(pts
				(xy -4.445 -63.832994) (xy -4.445 -62.816994) (xy -3.429 -63.324994)
			)
			(stroke
				(width 0)
				(type default)
			)
			(fill yes)
			(layer "F.Fab")
		)
		(pad "1" smd rect
			(at -2.050034 -63.324994 270)
			(size 0.519938 1.4986)
			(layers "F.Cu" "F.Mask" "F.Paste")
			(net "P12V_S3_AUX_CPU1_NVDIMM")
		)
		(pad "2" smd rect
			(at -2.050034 -62.47511 270)
			(size 0.519938 1.4986)
			(layers "F.Cu" "F.Mask" "F.Paste")
			(net "TP_CHH_CPU1_DIMM2_FRU_0")
		)
		(pad "3" smd rect
			(at -2.050034 -61.624972 270)
			(size 0.519938 1.4986)
			(layers "F.Cu" "F.Mask" "F.Paste")
			(net "P3V3_AUX")
		)
		(pad "4" smd rect
			(at -2.050034 -60.775088 270)
			(size 0.519938 1.4986)
			(layers "F.Cu" "F.Mask" "F.Paste")
			(net "I3C_SPD_DDREFGH_CPU1_LVC1_SCL_7")
		)
		(pad "5" smd rect
			(at -2.050034 -59.92495 270)
			(size 0.519938 1.4986)
			(layers "F.Cu" "F.Mask" "F.Paste")
			(net "I3C_SPD_DDREFGH_CPU1_LVC1_SDA")
		)
		(pad "6" smd rect
			(at -2.050034 -59.075066 270)
			(size 0.519938 1.4986)
			(layers "F.Cu" "F.Mask" "F.Paste")
			(net "GND")
		)
		(pad "7" smd rect
			(at -2.050034 -58.224928 270)
			(size 0.519938 1.4986)
			(layers "F.Cu" "F.Mask" "F.Paste")
			(net "M_H_CPU1_SA_DQ<0>")
		)
		(pad "8" smd rect
			(at -2.050034 -57.375044 270)
			(size 0.519938 1.4986)
			(layers "F.Cu" "F.Mask" "F.Paste")
			(net "GND")
		)
		(pad "9" smd rect
			(at -2.050034 -56.524906 270)
			(size 0.519938 1.4986)
			(layers "F.Cu" "F.Mask" "F.Paste")
			(net "M_H_CPU1_SA_DQ<1>")
		)
		(pad "10" smd rect
			(at -2.050034 -55.675022 270)
			(size 0.519938 1.4986)
			(layers "F.Cu" "F.Mask" "F.Paste")
			(net "GND")
		)
		(pad "11" smd rect
			(at -2.050034 -54.824884 270)
			(size 0.519938 1.4986)
			(layers "F.Cu" "F.Mask" "F.Paste")
			(net "M_H_CPU1_SA_DQS_DP<0>")
		)
		(pad "12" smd rect
			(at -2.050034 -53.975 270)
			(size 0.519938 1.4986)
			(layers "F.Cu" "F.Mask" "F.Paste")
			(net "M_H_CPU1_SA_DQS_DN<0>")
		)
		(pad "13" smd rect
			(at -2.050034 -53.125116 270)
			(size 0.519938 1.4986)
			(layers "F.Cu" "F.Mask" "F.Paste")
			(net "GND")
		)
		(pad "14" smd rect
			(at -2.050034 -52.274978 270)
			(size 0.519938 1.4986)
			(layers "F.Cu" "F.Mask" "F.Paste")
			(net "M_H_CPU1_SA_DQ<4>")
		)
		(pad "15" smd rect
			(at -2.050034 -51.425094 270)
			(size 0.519938 1.4986)
			(layers "F.Cu" "F.Mask" "F.Paste")
			(net "GND")
		)
		(pad "16" smd rect
			(at -2.050034 -50.574956 270)
			(size 0.519938 1.4986)
			(layers "F.Cu" "F.Mask" "F.Paste")
			(net "M_H_CPU1_SA_DQ<5>")
		)
		(pad "17" smd rect
			(at -2.050034 -49.725072 270)
			(size 0.519938 1.4986)
			(layers "F.Cu" "F.Mask" "F.Paste")
			(net "GND")
		)
		(pad "18" smd rect
			(at -2.050034 -48.874934 270)
			(size 0.519938 1.4986)
			(layers "F.Cu" "F.Mask" "F.Paste")
			(net "M_H_CPU1_SA_DQ<8>")
		)
		(pad "19" smd rect
			(at -2.050034 -48.02505 270)
			(size 0.519938 1.4986)
			(layers "F.Cu" "F.Mask" "F.Paste")
			(net "GND")
		)
		(pad "20" smd rect
			(at -2.050034 -47.174912 270)
			(size 0.519938 1.4986)
			(layers "F.Cu" "F.Mask" "F.Paste")
			(net "M_H_CPU1_SA_DQ<9>")
		)
		(pad "21" smd rect
			(at -2.050034 -46.325028 270)
			(size 0.519938 1.4986)
			(layers "F.Cu" "F.Mask" "F.Paste")
			(net "GND")
		)
		(pad "22" smd rect
			(at -2.050034 -45.47489 270)
			(size 0.519938 1.4986)
			(layers "F.Cu" "F.Mask" "F.Paste")
			(net "M_H_CPU1_SA_DQS_DP<1>")
		)
		(pad "23" smd rect
			(at -2.050034 -44.625006 270)
			(size 0.519938 1.4986)
			(layers "F.Cu" "F.Mask" "F.Paste")
			(net "M_H_CPU1_SA_DQS_DN<1>")
		)
		(pad "24" smd rect
			(at -2.050034 -43.775122 270)
			(size 0.519938 1.4986)
			(layers "F.Cu" "F.Mask" "F.Paste")
			(net "GND")
		)
		(pad "25" smd rect
			(at -2.050034 -42.924984 270)
			(size 0.519938 1.4986)
			(layers "F.Cu" "F.Mask" "F.Paste")
			(net "M_H_CPU1_SA_DQ<12>")
		)
		(pad "26" smd rect
			(at -2.050034 -42.0751 270)
			(size 0.519938 1.4986)
			(layers "F.Cu" "F.Mask" "F.Paste")
			(net "GND")
		)
		(pad "27" smd rect
			(at -2.050034 -41.224962 270)
			(size 0.519938 1.4986)
			(layers "F.Cu" "F.Mask" "F.Paste")
			(net "M_H_CPU1_SA_DQ<13>")
		)
		(pad "28" smd rect
			(at -2.050034 -40.375078 270)
			(size 0.519938 1.4986)
			(layers "F.Cu" "F.Mask" "F.Paste")
			(net "GND")
		)
		(pad "29" smd rect
			(at -2.050034 -39.52494 270)
			(size 0.519938 1.4986)
			(layers "F.Cu" "F.Mask" "F.Paste")
			(net "M_H_CPU1_SA_DQ<16>")
		)
		(pad "30" smd rect
			(at -2.050034 -38.675056 270)
			(size 0.519938 1.4986)
			(layers "F.Cu" "F.Mask" "F.Paste")
			(net "GND")
		)
		(pad "31" smd rect
			(at -2.050034 -37.824918 270)
			(size 0.519938 1.4986)
			(layers "F.Cu" "F.Mask" "F.Paste")
			(net "M_H_CPU1_SA_DQ<17>")
		)
		(pad "32" smd rect
			(at -2.050034 -36.975034 270)
			(size 0.519938 1.4986)
			(layers "F.Cu" "F.Mask" "F.Paste")
			(net "GND")
		)
		(pad "33" smd rect
			(at -2.050034 -36.124896 270)
			(size 0.519938 1.4986)
			(layers "F.Cu" "F.Mask" "F.Paste")
			(net "M_H_CPU1_SA_DQS_DP<2>")
		)
		(pad "34" smd rect
			(at -2.050034 -35.275012 270)
			(size 0.519938 1.4986)
			(layers "F.Cu" "F.Mask" "F.Paste")
			(net "M_H_CPU1_SA_DQS_DN<2>")
		)
		(pad "35" smd rect
			(at -2.050034 -34.425128 270)
			(size 0.519938 1.4986)
			(layers "F.Cu" "F.Mask" "F.Paste")
			(net "GND")
		)
		(pad "36" smd rect
			(at -2.050034 -33.57499 270)
			(size 0.519938 1.4986)
			(layers "F.Cu" "F.Mask" "F.Paste")
			(net "M_H_CPU1_SA_DQ<20>")
		)
		(pad "37" smd rect
			(at -2.050034 -32.725106 270)
			(size 0.519938 1.4986)
			(layers "F.Cu" "F.Mask" "F.Paste")
			(net "GND")
		)
		(pad "38" smd rect
			(at -2.050034 -31.874968 270)
			(size 0.519938 1.4986)
			(layers "F.Cu" "F.Mask" "F.Paste")
			(net "M_H_CPU1_SA_DQ<21>")
		)
		(pad "39" smd rect
			(at -2.050034 -31.025084 270)
			(size 0.519938 1.4986)
			(layers "F.Cu" "F.Mask" "F.Paste")
			(net "GND")
		)
		(pad "40" smd rect
			(at -2.050034 -30.174946 270)
			(size 0.519938 1.4986)
			(layers "F.Cu" "F.Mask" "F.Paste")
			(net "M_H_CPU1_SA_DQ<24>")
		)
		(pad "41" smd rect
			(at -2.050034 -29.325062 270)
			(size 0.519938 1.4986)
			(layers "F.Cu" "F.Mask" "F.Paste")
			(net "GND")
		)
		(pad "42" smd rect
			(at -2.050034 -28.474924 270)
			(size 0.519938 1.4986)
			(layers "F.Cu" "F.Mask" "F.Paste")
			(net "M_H_CPU1_SA_DQ<25>")
		)
		(pad "43" smd rect
			(at -2.050034 -27.62504 270)
			(size 0.519938 1.4986)
			(layers "F.Cu" "F.Mask" "F.Paste")
			(net "GND")
		)
		(pad "44" smd rect
			(at -2.050034 -26.774902 270)
			(size 0.519938 1.4986)
			(layers "F.Cu" "F.Mask" "F.Paste")
			(net "M_H_CPU1_SA_DQS_DP<3>")
		)
		(pad "45" smd rect
			(at -2.050034 -25.925018 270)
			(size 0.519938 1.4986)
			(layers "F.Cu" "F.Mask" "F.Paste")
			(net "M_H_CPU1_SA_DQS_DN<3>")
		)
		(pad "46" smd rect
			(at -2.050034 -25.07488 270)
			(size 0.519938 1.4986)
			(layers "F.Cu" "F.Mask" "F.Paste")
			(net "GND")
		)
		(pad "47" smd rect
			(at -2.050034 -24.224996 270)
			(size 0.519938 1.4986)
			(layers "F.Cu" "F.Mask" "F.Paste")
			(net "M_H_CPU1_SA_DQ<28>")
		)
		(pad "48" smd rect
			(at -2.050034 -23.375112 270)
			(size 0.519938 1.4986)
			(layers "F.Cu" "F.Mask" "F.Paste")
			(net "GND")
		)
		(pad "49" smd rect
			(at -2.050034 -22.524974 270)
			(size 0.519938 1.4986)
			(layers "F.Cu" "F.Mask" "F.Paste")
			(net "M_H_CPU1_SA_DQ<29>")
		)
		(pad "50" smd rect
			(at -2.050034 -21.67509 270)
			(size 0.519938 1.4986)
			(layers "F.Cu" "F.Mask" "F.Paste")
			(net "GND")
		)
		(pad "51" smd rect
			(at -2.050034 -20.824952 270)
			(size 0.519938 1.4986)
			(layers "F.Cu" "F.Mask" "F.Paste")
			(net "M_H_CPU1_SA_CB<0>")
		)
		(pad "52" smd rect
			(at -2.050034 -19.975068 270)
			(size 0.519938 1.4986)
			(layers "F.Cu" "F.Mask" "F.Paste")
			(net "GND")
		)
		(pad "53" smd rect
			(at -2.050034 -19.12493 270)
			(size 0.519938 1.4986)
			(layers "F.Cu" "F.Mask" "F.Paste")
			(net "M_H_CPU1_SA_CB<1>")
		)
		(pad "54" smd rect
			(at -2.050034 -18.275046 270)
			(size 0.519938 1.4986)
			(layers "F.Cu" "F.Mask" "F.Paste")
			(net "GND")
		)
		(pad "55" smd rect
			(at -2.050034 -17.424908 270)
			(size 0.519938 1.4986)
			(layers "F.Cu" "F.Mask" "F.Paste")
			(net "M_H_CPU1_SA_DQS_DP<4>")
		)
		(pad "56" smd rect
			(at -2.050034 -16.575024 270)
			(size 0.519938 1.4986)
			(layers "F.Cu" "F.Mask" "F.Paste")
			(net "M_H_CPU1_SA_DQS_DN<4>")
		)
		(pad "57" smd rect
			(at -2.050034 -15.724886 270)
			(size 0.519938 1.4986)
			(layers "F.Cu" "F.Mask" "F.Paste")
			(net "GND")
		)
		(pad "58" smd rect
			(at -2.050034 -14.875002 270)
			(size 0.519938 1.4986)
			(layers "F.Cu" "F.Mask" "F.Paste")
			(net "M_H_CPU1_SA_CB<4>")
		)
		(pad "59" smd rect
			(at -2.050034 -14.025118 270)
			(size 0.519938 1.4986)
			(layers "F.Cu" "F.Mask" "F.Paste")
			(net "GND")
		)
		(pad "60" smd rect
			(at -2.050034 -13.17498 270)
			(size 0.519938 1.4986)
			(layers "F.Cu" "F.Mask" "F.Paste")
			(net "M_H_CPU1_SA_CB<5>")
		)
		(pad "61" smd rect
			(at -2.050034 -12.325096 270)
			(size 0.519938 1.4986)
			(layers "F.Cu" "F.Mask" "F.Paste")
			(net "GND")
		)
		(pad "62" smd rect
			(at -2.050034 -11.474958 270)
			(size 0.519938 1.4986)
			(layers "F.Cu" "F.Mask" "F.Paste")
			(net "M_H_CPU1_ALERT_N")
		)
		(pad "63" smd rect
			(at -2.050034 -10.625074 270)
			(size 0.519938 1.4986)
			(layers "F.Cu" "F.Mask" "F.Paste")
			(net "GND")
		)
		(pad "64" smd rect
			(at -2.050034 -9.774936 270)
			(size 0.519938 1.4986)
			(layers "F.Cu" "F.Mask" "F.Paste")
			(net "M_H_CPU1_SA_CS_N<2>")
		)
		(pad "65" smd rect
			(at -2.050034 -8.925052 270)
			(size 0.519938 1.4986)
			(layers "F.Cu" "F.Mask" "F.Paste")
			(net "GND")
		)
		(pad "66" smd rect
			(at -2.050034 -8.074914 270)
			(size 0.519938 1.4986)
			(layers "F.Cu" "F.Mask" "F.Paste")
			(net "M_H_CPU1_SA_CA<0>")
		)
		(pad "67" smd rect
			(at -2.050034 -7.22503 270)
			(size 0.519938 1.4986)
			(layers "F.Cu" "F.Mask" "F.Paste")
			(net "GND")
		)
		(pad "68" smd rect
			(at -2.050034 -6.374892 270)
			(size 0.519938 1.4986)
			(layers "F.Cu" "F.Mask" "F.Paste")
			(net "M_H_CPU1_SA_CA<2>")
		)
		(pad "69" smd rect
			(at -2.050034 -5.525008 270)
			(size 0.519938 1.4986)
			(layers "F.Cu" "F.Mask" "F.Paste")
			(net "GND")
		)
		(pad "70" smd rect
			(at -2.050034 -4.675124 270)
			(size 0.519938 1.4986)
			(layers "F.Cu" "F.Mask" "F.Paste")
			(net "M_H_CPU1_SA_CA<4>")
		)
		(pad "71" smd rect
			(at -2.050034 -3.824986 270)
			(size 0.519938 1.4986)
			(layers "F.Cu" "F.Mask" "F.Paste")
			(net "GND")
		)
		(pad "72" smd rect
			(at -2.050034 -2.975102 270)
			(size 0.519938 1.4986)
			(layers "F.Cu" "F.Mask" "F.Paste")
			(net "M_H_CPU1_SA_CA<6>")
		)
		(pad "73" smd rect
			(at -2.050034 -2.124964 270)
			(size 0.519938 1.4986)
			(layers "F.Cu" "F.Mask" "F.Paste")
			(net "GND")
		)
		(pad "74" smd rect
			(at -2.050034 -1.27508 270)
			(size 0.519938 1.4986)
			(layers "F.Cu" "F.Mask" "F.Paste")
			(net "M_H_CPU1_SA_PAR")
		)
		(pad "75" smd rect
			(at -2.050034 -0.424942 270)
			(size 0.519938 1.4986)
			(layers "F.Cu" "F.Mask" "F.Paste")
			(net "GND")
		)
		(pad "76" smd rect
			(at -2.050034 5.525008 270)
			(size 0.519938 1.4986)
			(layers "F.Cu" "F.Mask" "F.Paste")
			(net "M_H_CPU1_SB_CA<0>")
		)
		(pad "77" smd rect
			(at -2.050034 6.374892 270)
			(size 0.519938 1.4986)
			(layers "F.Cu" "F.Mask" "F.Paste")
			(net "GND")
		)
		(pad "78" smd rect
			(at -2.050034 7.22503 270)
			(size 0.519938 1.4986)
			(layers "F.Cu" "F.Mask" "F.Paste")
			(net "M_H_CPU1_SB_CA<2>")
		)
		(pad "79" smd rect
			(at -2.050034 8.074914 270)
			(size 0.519938 1.4986)
			(layers "F.Cu" "F.Mask" "F.Paste")
			(net "GND")
		)
		(pad "80" smd rect
			(at -2.050034 8.925052 270)
			(size 0.519938 1.4986)
			(layers "F.Cu" "F.Mask" "F.Paste")
			(net "M_H_CPU1_SB_CA<4>")
		)
		(pad "81" smd rect
			(at -2.050034 9.774936 270)
			(size 0.519938 1.4986)
			(layers "F.Cu" "F.Mask" "F.Paste")
			(net "GND")
		)
		(pad "82" smd rect
			(at -2.050034 10.625074 270)
			(size 0.519938 1.4986)
			(layers "F.Cu" "F.Mask" "F.Paste")
			(net "M_H_CPU1_SB_CA<6>")
		)
		(pad "83" smd rect
			(at -2.050034 11.474958 270)
			(size 0.519938 1.4986)
			(layers "F.Cu" "F.Mask" "F.Paste")
			(net "GND")
		)
		(pad "84" smd rect
			(at -2.050034 12.325096 270)
			(size 0.519938 1.4986)
			(layers "F.Cu" "F.Mask" "F.Paste")
			(net "M_H_CPU1_SB_CS_N<2>")
		)
		(pad "85" smd rect
			(at -2.050034 13.17498 270)
			(size 0.519938 1.4986)
			(layers "F.Cu" "F.Mask" "F.Paste")
			(net "GND")
		)
		(pad "86" smd rect
			(at -2.050034 14.025118 270)
			(size 0.519938 1.4986)
			(layers "F.Cu" "F.Mask" "F.Paste")
			(net "M_H_CPU1_SA_RSP<1>")
		)
		(pad "87" smd rect
			(at -2.050034 14.875002 270)
			(size 0.519938 1.4986)
			(layers "F.Cu" "F.Mask" "F.Paste")
			(net "M_H_CPU1_SB_RSP<1>")
		)
		(pad "88" smd rect
			(at -2.050034 15.724886 270)
			(size 0.519938 1.4986)
			(layers "F.Cu" "F.Mask" "F.Paste")
			(net "GND")
		)
		(pad "89" smd rect
			(at -2.050034 16.575024 270)
			(size 0.519938 1.4986)
			(layers "F.Cu" "F.Mask" "F.Paste")
			(net "M_H_CPU1_SB_CB<4>")
		)
		(pad "90" smd rect
			(at -2.050034 17.424908 270)
			(size 0.519938 1.4986)
			(layers "F.Cu" "F.Mask" "F.Paste")
			(net "GND")
		)
		(pad "91" smd rect
			(at -2.050034 18.275046 270)
			(size 0.519938 1.4986)
			(layers "F.Cu" "F.Mask" "F.Paste")
			(net "M_H_CPU1_SB_CB<5>")
		)
		(pad "92" smd rect
			(at -2.050034 19.12493 270)
			(size 0.519938 1.4986)
			(layers "F.Cu" "F.Mask" "F.Paste")
			(net "GND")
		)
		(pad "93" smd rect
			(at -2.050034 19.975068 270)
			(size 0.519938 1.4986)
			(layers "F.Cu" "F.Mask" "F.Paste")
			(net "M_H_CPU1_SB_DQS_DP<9>")
		)
		(pad "94" smd rect
			(at -2.050034 20.824952 270)
			(size 0.519938 1.4986)
			(layers "F.Cu" "F.Mask" "F.Paste")
			(net "M_H_CPU1_SB_DQS_DN<9>")
		)
		(pad "95" smd rect
			(at -2.050034 21.67509 270)
			(size 0.519938 1.4986)
			(layers "F.Cu" "F.Mask" "F.Paste")
			(net "GND")
		)
		(pad "96" smd rect
			(at -2.050034 22.524974 270)
			(size 0.519938 1.4986)
			(layers "F.Cu" "F.Mask" "F.Paste")
			(net "M_H_CPU1_SB_CB<0>")
		)
		(pad "97" smd rect
			(at -2.050034 23.375112 270)
			(size 0.519938 1.4986)
			(layers "F.Cu" "F.Mask" "F.Paste")
			(net "GND")
		)
		(pad "98" smd rect
			(at -2.050034 24.224996 270)
			(size 0.519938 1.4986)
			(layers "F.Cu" "F.Mask" "F.Paste")
			(net "M_H_CPU1_SB_CB<1>")
		)
		(pad "99" smd rect
			(at -2.050034 25.07488 270)
			(size 0.519938 1.4986)
			(layers "F.Cu" "F.Mask" "F.Paste")
			(net "GND")
		)
		(pad "100" smd rect
			(at -2.050034 25.925018 270)
			(size 0.519938 1.4986)
			(layers "F.Cu" "F.Mask" "F.Paste")
			(net "M_H_CPU1_SB_DQ<0>")
		)
		(pad "101" smd rect
			(at -2.050034 26.774902 270)
			(size 0.519938 1.4986)
			(layers "F.Cu" "F.Mask" "F.Paste")
			(net "GND")
		)
		(pad "102" smd rect
			(at -2.050034 27.62504 270)
			(size 0.519938 1.4986)
			(layers "F.Cu" "F.Mask" "F.Paste")
			(net "M_H_CPU1_SB_DQ<1>")
		)
		(pad "103" smd rect
			(at -2.050034 28.474924 270)
			(size 0.519938 1.4986)
			(layers "F.Cu" "F.Mask" "F.Paste")
			(net "GND")
		)
		(pad "104" smd rect
			(at -2.050034 29.325062 270)
			(size 0.519938 1.4986)
			(layers "F.Cu" "F.Mask" "F.Paste")
			(net "M_H_CPU1_SB_DQS_DP<0>")
		)
		(pad "105" smd rect
			(at -2.050034 30.174946 270)
			(size 0.519938 1.4986)
			(layers "F.Cu" "F.Mask" "F.Paste")
			(net "M_H_CPU1_SB_DQS_DN<0>")
		)
		(pad "106" smd rect
			(at -2.050034 31.025084 270)
			(size 0.519938 1.4986)
			(layers "F.Cu" "F.Mask" "F.Paste")
			(net "GND")
		)
		(pad "107" smd rect
			(at -2.050034 31.874968 270)
			(size 0.519938 1.4986)
			(layers "F.Cu" "F.Mask" "F.Paste")
			(net "M_H_CPU1_SB_DQ<4>")
		)
		(pad "108" smd rect
			(at -2.050034 32.725106 270)
			(size 0.519938 1.4986)
			(layers "F.Cu" "F.Mask" "F.Paste")
			(net "GND")
		)
		(pad "109" smd rect
			(at -2.050034 33.57499 270)
			(size 0.519938 1.4986)
			(layers "F.Cu" "F.Mask" "F.Paste")
			(net "M_H_CPU1_SB_DQ<5>")
		)
		(pad "110" smd rect
			(at -2.050034 34.425128 270)
			(size 0.519938 1.4986)
			(layers "F.Cu" "F.Mask" "F.Paste")
			(net "GND")
		)
		(pad "111" smd rect
			(at -2.050034 35.275012 270)
			(size 0.519938 1.4986)
			(layers "F.Cu" "F.Mask" "F.Paste")
			(net "M_H_CPU1_SB_DQ<8>")
		)
		(pad "112" smd rect
			(at -2.050034 36.124896 270)
			(size 0.519938 1.4986)
			(layers "F.Cu" "F.Mask" "F.Paste")
			(net "GND")
		)
		(pad "113" smd rect
			(at -2.050034 36.975034 270)
			(size 0.519938 1.4986)
			(layers "F.Cu" "F.Mask" "F.Paste")
			(net "M_H_CPU1_SB_DQ<9>")
		)
		(pad "114" smd rect
			(at -2.050034 37.824918 270)
			(size 0.519938 1.4986)
			(layers "F.Cu" "F.Mask" "F.Paste")
			(net "GND")
		)
		(pad "115" smd rect
			(at -2.050034 38.675056 270)
			(size 0.519938 1.4986)
			(layers "F.Cu" "F.Mask" "F.Paste")
			(net "M_H_CPU1_SB_DQS_DP<1>")
		)
		(pad "116" smd rect
			(at -2.050034 39.52494 270)
			(size 0.519938 1.4986)
			(layers "F.Cu" "F.Mask" "F.Paste")
			(net "M_H_CPU1_SB_DQS_DN<1>")
		)
		(pad "117" smd rect
			(at -2.050034 40.375078 270)
			(size 0.519938 1.4986)
			(layers "F.Cu" "F.Mask" "F.Paste")
			(net "GND")
		)
		(pad "118" smd rect
			(at -2.050034 41.224962 270)
			(size 0.519938 1.4986)
			(layers "F.Cu" "F.Mask" "F.Paste")
			(net "M_H_CPU1_SB_DQ<12>")
		)
		(pad "119" smd rect
			(at -2.050034 42.0751 270)
			(size 0.519938 1.4986)
			(layers "F.Cu" "F.Mask" "F.Paste")
			(net "GND")
		)
		(pad "120" smd rect
			(at -2.050034 42.924984 270)
			(size 0.519938 1.4986)
			(layers "F.Cu" "F.Mask" "F.Paste")
			(net "M_H_CPU1_SB_DQ<13>")
		)
		(pad "121" smd rect
			(at -2.050034 43.775122 270)
			(size 0.519938 1.4986)
			(layers "F.Cu" "F.Mask" "F.Paste")
			(net "GND")
		)
		(pad "122" smd rect
			(at -2.050034 44.625006 270)
			(size 0.519938 1.4986)
			(layers "F.Cu" "F.Mask" "F.Paste")
			(net "M_H_CPU1_SB_DQ<16>")
		)
		(pad "123" smd rect
			(at -2.050034 45.47489 270)
			(size 0.519938 1.4986)
			(layers "F.Cu" "F.Mask" "F.Paste")
			(net "GND")
		)
		(pad "124" smd rect
			(at -2.050034 46.325028 270)
			(size 0.519938 1.4986)
			(layers "F.Cu" "F.Mask" "F.Paste")
			(net "M_H_CPU1_SB_DQ<17>")
		)
		(pad "125" smd rect
			(at -2.050034 47.174912 270)
			(size 0.519938 1.4986)
			(layers "F.Cu" "F.Mask" "F.Paste")
			(net "GND")
		)
		(pad "126" smd rect
			(at -2.050034 48.02505 270)
			(size 0.519938 1.4986)
			(layers "F.Cu" "F.Mask" "F.Paste")
			(net "M_H_CPU1_SB_DQS_DP<2>")
		)
		(pad "127" smd rect
			(at -2.050034 48.874934 270)
			(size 0.519938 1.4986)
			(layers "F.Cu" "F.Mask" "F.Paste")
			(net "M_H_CPU1_SB_DQS_DN<2>")
		)
		(pad "128" smd rect
			(at -2.050034 49.725072 270)
			(size 0.519938 1.4986)
			(layers "F.Cu" "F.Mask" "F.Paste")
			(net "GND")
		)
		(pad "129" smd rect
			(at -2.050034 50.574956 270)
			(size 0.519938 1.4986)
			(layers "F.Cu" "F.Mask" "F.Paste")
			(net "M_H_CPU1_SB_DQ<20>")
		)
		(pad "130" smd rect
			(at -2.050034 51.425094 270)
			(size 0.519938 1.4986)
			(layers "F.Cu" "F.Mask" "F.Paste")
			(net "GND")
		)
		(pad "131" smd rect
			(at -2.050034 52.274978 270)
			(size 0.519938 1.4986)
			(layers "F.Cu" "F.Mask" "F.Paste")
			(net "M_H_CPU1_SB_DQ<21>")
		)
		(pad "132" smd rect
			(at -2.050034 53.125116 270)
			(size 0.519938 1.4986)
			(layers "F.Cu" "F.Mask" "F.Paste")
			(net "GND")
		)
		(pad "133" smd rect
			(at -2.050034 53.975 270)
			(size 0.519938 1.4986)
			(layers "F.Cu" "F.Mask" "F.Paste")
			(net "M_H_CPU1_SB_DQ<24>")
		)
		(pad "134" smd rect
			(at -2.050034 54.824884 270)
			(size 0.519938 1.4986)
			(layers "F.Cu" "F.Mask" "F.Paste")
			(net "GND")
		)
		(pad "135" smd rect
			(at -2.050034 55.675022 270)
			(size 0.519938 1.4986)
			(layers "F.Cu" "F.Mask" "F.Paste")
			(net "M_H_CPU1_SB_DQ<25>")
		)
		(pad "136" smd rect
			(at -2.050034 56.524906 270)
			(size 0.519938 1.4986)
			(layers "F.Cu" "F.Mask" "F.Paste")
			(net "GND")
		)
		(pad "137" smd rect
			(at -2.050034 57.375044 270)
			(size 0.519938 1.4986)
			(layers "F.Cu" "F.Mask" "F.Paste")
			(net "M_H_CPU1_SB_DQS_DP<3>")
		)
		(pad "138" smd rect
			(at -2.050034 58.224928 270)
			(size 0.519938 1.4986)
			(layers "F.Cu" "F.Mask" "F.Paste")
			(net "M_H_CPU1_SB_DQS_DN<3>")
		)
		(pad "139" smd rect
			(at -2.050034 59.075066 270)
			(size 0.519938 1.4986)
			(layers "F.Cu" "F.Mask" "F.Paste")
			(net "GND")
		)
		(pad "140" smd rect
			(at -2.050034 59.92495 270)
			(size 0.519938 1.4986)
			(layers "F.Cu" "F.Mask" "F.Paste")
			(net "M_H_CPU1_SB_DQ<28>")
		)
		(pad "141" smd rect
			(at -2.050034 60.775088 270)
			(size 0.519938 1.4986)
			(layers "F.Cu" "F.Mask" "F.Paste")
			(net "GND")
		)
		(pad "142" smd rect
			(at -2.050034 61.624972 270)
			(size 0.519938 1.4986)
			(layers "F.Cu" "F.Mask" "F.Paste")
			(net "M_H_CPU1_SB_DQ<29>")
		)
		(pad "143" smd rect
			(at -2.050034 62.47511 270)
			(size 0.519938 1.4986)
			(layers "F.Cu" "F.Mask" "F.Paste")
			(net "GND")
		)
		(pad "144" smd rect
			(at -2.050034 63.324994 270)
			(size 0.519938 1.4986)
			(layers "F.Cu" "F.Mask" "F.Paste")
			(net "TP_CHH_CPU1_DIMM2_FRU_1")
		)
		(pad "145" smd rect
			(at 2.050034 -63.324994 270)
			(size 0.519938 1.4986)
			(layers "F.Cu" "F.Mask" "F.Paste")
			(net "P12V_S3_AUX_CPU1_NVDIMM")
		)
		(pad "146" smd rect
			(at 2.050034 -62.47511 270)
			(size 0.519938 1.4986)
			(layers "F.Cu" "F.Mask" "F.Paste")
			(net "P12V_S3_AUX_CPU1_NVDIMM")
		)
		(pad "147" smd rect
			(at 2.050034 -61.624972 270)
			(size 0.519938 1.4986)
			(layers "F.Cu" "F.Mask" "F.Paste")
			(net "PWRGD_CHH_CPU1_DIMM2")
		)
		(pad "148" smd rect
			(at 2.050034 -60.775088 270)
			(size 0.519938 1.4986)
			(layers "F.Cu" "F.Mask" "F.Paste")
			(net "PD_CHH_CPU1_DIMM2_SAA")
		)
		(pad "149" smd rect
			(at 2.050034 -59.92495 270)
			(size 0.519938 1.4986)
			(layers "F.Cu" "F.Mask" "F.Paste")
			(net "TP_CHH_CPU1_DIMM2_FRU_2")
		)
		(pad "150" smd rect
			(at 2.050034 -59.075066 270)
			(size 0.519938 1.4986)
			(layers "F.Cu" "F.Mask" "F.Paste")
			(net "TP_CHH_CPU1_DIMM2_FRU_3")
		)
		(pad "151" smd rect
			(at 2.050034 -58.224928 270)
			(size 0.519938 1.4986)
			(layers "F.Cu" "F.Mask" "F.Paste")
			(net "GND")
		)
		(pad "152" smd rect
			(at 2.050034 -57.375044 270)
			(size 0.519938 1.4986)
			(layers "F.Cu" "F.Mask" "F.Paste")
			(net "M_H_CPU1_SA_DQ<2>")
		)
		(pad "153" smd rect
			(at 2.050034 -56.524906 270)
			(size 0.519938 1.4986)
			(layers "F.Cu" "F.Mask" "F.Paste")
			(net "GND")
		)
		(pad "154" smd rect
			(at 2.050034 -55.675022 270)
			(size 0.519938 1.4986)
			(layers "F.Cu" "F.Mask" "F.Paste")
			(net "M_H_CPU1_SA_DQ<3>")
		)
		(pad "155" smd rect
			(at 2.050034 -54.824884 270)
			(size 0.519938 1.4986)
			(layers "F.Cu" "F.Mask" "F.Paste")
			(net "GND")
		)
		(pad "156" smd rect
			(at 2.050034 -53.975 270)
			(size 0.519938 1.4986)
			(layers "F.Cu" "F.Mask" "F.Paste")
			(net "M_H_CPU1_SA_DQS_DN<5>")
		)
		(pad "157" smd rect
			(at 2.050034 -53.125116 270)
			(size 0.519938 1.4986)
			(layers "F.Cu" "F.Mask" "F.Paste")
			(net "M_H_CPU1_SA_DQS_DP<5>")
		)
		(pad "158" smd rect
			(at 2.050034 -52.274978 270)
			(size 0.519938 1.4986)
			(layers "F.Cu" "F.Mask" "F.Paste")
			(net "GND")
		)
		(pad "159" smd rect
			(at 2.050034 -51.425094 270)
			(size 0.519938 1.4986)
			(layers "F.Cu" "F.Mask" "F.Paste")
			(net "M_H_CPU1_SA_DQ<6>")
		)
		(pad "160" smd rect
			(at 2.050034 -50.574956 270)
			(size 0.519938 1.4986)
			(layers "F.Cu" "F.Mask" "F.Paste")
			(net "GND")
		)
		(pad "161" smd rect
			(at 2.050034 -49.725072 270)
			(size 0.519938 1.4986)
			(layers "F.Cu" "F.Mask" "F.Paste")
			(net "M_H_CPU1_SA_DQ<7>")
		)
		(pad "162" smd rect
			(at 2.050034 -48.874934 270)
			(size 0.519938 1.4986)
			(layers "F.Cu" "F.Mask" "F.Paste")
			(net "GND")
		)
		(pad "163" smd rect
			(at 2.050034 -48.02505 270)
			(size 0.519938 1.4986)
			(layers "F.Cu" "F.Mask" "F.Paste")
			(net "M_H_CPU1_SA_DQ<10>")
		)
		(pad "164" smd rect
			(at 2.050034 -47.174912 270)
			(size 0.519938 1.4986)
			(layers "F.Cu" "F.Mask" "F.Paste")
			(net "GND")
		)
		(pad "165" smd rect
			(at 2.050034 -46.325028 270)
			(size 0.519938 1.4986)
			(layers "F.Cu" "F.Mask" "F.Paste")
			(net "M_H_CPU1_SA_DQ<11>")
		)
		(pad "166" smd rect
			(at 2.050034 -45.47489 270)
			(size 0.519938 1.4986)
			(layers "F.Cu" "F.Mask" "F.Paste")
			(net "GND")
		)
		(pad "167" smd rect
			(at 2.050034 -44.625006 270)
			(size 0.519938 1.4986)
			(layers "F.Cu" "F.Mask" "F.Paste")
			(net "M_H_CPU1_SA_DQS_DN<6>")
		)
		(pad "168" smd rect
			(at 2.050034 -43.775122 270)
			(size 0.519938 1.4986)
			(layers "F.Cu" "F.Mask" "F.Paste")
			(net "M_H_CPU1_SA_DQS_DP<6>")
		)
		(pad "169" smd rect
			(at 2.050034 -42.924984 270)
			(size 0.519938 1.4986)
			(layers "F.Cu" "F.Mask" "F.Paste")
			(net "GND")
		)
		(pad "170" smd rect
			(at 2.050034 -42.0751 270)
			(size 0.519938 1.4986)
			(layers "F.Cu" "F.Mask" "F.Paste")
			(net "M_H_CPU1_SA_DQ<14>")
		)
		(pad "171" smd rect
			(at 2.050034 -41.224962 270)
			(size 0.519938 1.4986)
			(layers "F.Cu" "F.Mask" "F.Paste")
			(net "GND")
		)
		(pad "172" smd rect
			(at 2.050034 -40.375078 270)
			(size 0.519938 1.4986)
			(layers "F.Cu" "F.Mask" "F.Paste")
			(net "M_H_CPU1_SA_DQ<15>")
		)
		(pad "173" smd rect
			(at 2.050034 -39.52494 270)
			(size 0.519938 1.4986)
			(layers "F.Cu" "F.Mask" "F.Paste")
			(net "GND")
		)
		(pad "174" smd rect
			(at 2.050034 -38.675056 270)
			(size 0.519938 1.4986)
			(layers "F.Cu" "F.Mask" "F.Paste")
			(net "M_H_CPU1_SA_DQ<18>")
		)
		(pad "175" smd rect
			(at 2.050034 -37.824918 270)
			(size 0.519938 1.4986)
			(layers "F.Cu" "F.Mask" "F.Paste")
			(net "GND")
		)
		(pad "176" smd rect
			(at 2.050034 -36.975034 270)
			(size 0.519938 1.4986)
			(layers "F.Cu" "F.Mask" "F.Paste")
			(net "M_H_CPU1_SA_DQ<19>")
		)
		(pad "177" smd rect
			(at 2.050034 -36.124896 270)
			(size 0.519938 1.4986)
			(layers "F.Cu" "F.Mask" "F.Paste")
			(net "GND")
		)
		(pad "178" smd rect
			(at 2.050034 -35.275012 270)
			(size 0.519938 1.4986)
			(layers "F.Cu" "F.Mask" "F.Paste")
			(net "M_H_CPU1_SA_DQS_DN<7>")
		)
		(pad "179" smd rect
			(at 2.050034 -34.425128 270)
			(size 0.519938 1.4986)
			(layers "F.Cu" "F.Mask" "F.Paste")
			(net "M_H_CPU1_SA_DQS_DP<7>")
		)
		(pad "180" smd rect
			(at 2.050034 -33.57499 270)
			(size 0.519938 1.4986)
			(layers "F.Cu" "F.Mask" "F.Paste")
			(net "GND")
		)
		(pad "181" smd rect
			(at 2.050034 -32.725106 270)
			(size 0.519938 1.4986)
			(layers "F.Cu" "F.Mask" "F.Paste")
			(net "M_H_CPU1_SA_DQ<22>")
		)
		(pad "182" smd rect
			(at 2.050034 -31.874968 270)
			(size 0.519938 1.4986)
			(layers "F.Cu" "F.Mask" "F.Paste")
			(net "GND")
		)
		(pad "183" smd rect
			(at 2.050034 -31.025084 270)
			(size 0.519938 1.4986)
			(layers "F.Cu" "F.Mask" "F.Paste")
			(net "M_H_CPU1_SA_DQ<23>")
		)
		(pad "184" smd rect
			(at 2.050034 -30.174946 270)
			(size 0.519938 1.4986)
			(layers "F.Cu" "F.Mask" "F.Paste")
			(net "GND")
		)
		(pad "185" smd rect
			(at 2.050034 -29.325062 270)
			(size 0.519938 1.4986)
			(layers "F.Cu" "F.Mask" "F.Paste")
			(net "M_H_CPU1_SA_DQ<26>")
		)
		(pad "186" smd rect
			(at 2.050034 -28.474924 270)
			(size 0.519938 1.4986)
			(layers "F.Cu" "F.Mask" "F.Paste")
			(net "GND")
		)
		(pad "187" smd rect
			(at 2.050034 -27.62504 270)
			(size 0.519938 1.4986)
			(layers "F.Cu" "F.Mask" "F.Paste")
			(net "M_H_CPU1_SA_DQ<27>")
		)
		(pad "188" smd rect
			(at 2.050034 -26.774902 270)
			(size 0.519938 1.4986)
			(layers "F.Cu" "F.Mask" "F.Paste")
			(net "GND")
		)
		(pad "189" smd rect
			(at 2.050034 -25.925018 270)
			(size 0.519938 1.4986)
			(layers "F.Cu" "F.Mask" "F.Paste")
			(net "M_H_CPU1_SA_DQS_DN<8>")
		)
		(pad "190" smd rect
			(at 2.050034 -25.07488 270)
			(size 0.519938 1.4986)
			(layers "F.Cu" "F.Mask" "F.Paste")
			(net "M_H_CPU1_SA_DQS_DP<8>")
		)
		(pad "191" smd rect
			(at 2.050034 -24.224996 270)
			(size 0.519938 1.4986)
			(layers "F.Cu" "F.Mask" "F.Paste")
			(net "GND")
		)
		(pad "192" smd rect
			(at 2.050034 -23.375112 270)
			(size 0.519938 1.4986)
			(layers "F.Cu" "F.Mask" "F.Paste")
			(net "M_H_CPU1_SA_DQ<30>")
		)
		(pad "193" smd rect
			(at 2.050034 -22.524974 270)
			(size 0.519938 1.4986)
			(layers "F.Cu" "F.Mask" "F.Paste")
			(net "GND")
		)
		(pad "194" smd rect
			(at 2.050034 -21.67509 270)
			(size 0.519938 1.4986)
			(layers "F.Cu" "F.Mask" "F.Paste")
			(net "M_H_CPU1_SA_DQ<31>")
		)
		(pad "195" smd rect
			(at 2.050034 -20.824952 270)
			(size 0.519938 1.4986)
			(layers "F.Cu" "F.Mask" "F.Paste")
			(net "GND")
		)
		(pad "196" smd rect
			(at 2.050034 -19.975068 270)
			(size 0.519938 1.4986)
			(layers "F.Cu" "F.Mask" "F.Paste")
			(net "M_H_CPU1_SA_CB<2>")
		)
		(pad "197" smd rect
			(at 2.050034 -19.12493 270)
			(size 0.519938 1.4986)
			(layers "F.Cu" "F.Mask" "F.Paste")
			(net "GND")
		)
		(pad "198" smd rect
			(at 2.050034 -18.275046 270)
			(size 0.519938 1.4986)
			(layers "F.Cu" "F.Mask" "F.Paste")
			(net "M_H_CPU1_SA_CB<3>")
		)
		(pad "199" smd rect
			(at 2.050034 -17.424908 270)
			(size 0.519938 1.4986)
			(layers "F.Cu" "F.Mask" "F.Paste")
			(net "GND")
		)
		(pad "200" smd rect
			(at 2.050034 -16.575024 270)
			(size 0.519938 1.4986)
			(layers "F.Cu" "F.Mask" "F.Paste")
			(net "M_H_CPU1_SA_DQS_DN<9>")
		)
		(pad "201" smd rect
			(at 2.050034 -15.724886 270)
			(size 0.519938 1.4986)
			(layers "F.Cu" "F.Mask" "F.Paste")
			(net "M_H_CPU1_SA_DQS_DP<9>")
		)
		(pad "202" smd rect
			(at 2.050034 -14.875002 270)
			(size 0.519938 1.4986)
			(layers "F.Cu" "F.Mask" "F.Paste")
			(net "GND")
		)
		(pad "203" smd rect
			(at 2.050034 -14.025118 270)
			(size 0.519938 1.4986)
			(layers "F.Cu" "F.Mask" "F.Paste")
			(net "M_H_CPU1_SA_CB<6>")
		)
		(pad "204" smd rect
			(at 2.050034 -13.17498 270)
			(size 0.519938 1.4986)
			(layers "F.Cu" "F.Mask" "F.Paste")
			(net "GND")
		)
		(pad "205" smd rect
			(at 2.050034 -12.325096 270)
			(size 0.519938 1.4986)
			(layers "F.Cu" "F.Mask" "F.Paste")
			(net "M_H_CPU1_SA_CB<7>")
		)
		(pad "206" smd rect
			(at 2.050034 -11.474958 270)
			(size 0.519938 1.4986)
			(layers "F.Cu" "F.Mask" "F.Paste")
			(net "GND")
		)
		(pad "207" smd rect
			(at 2.050034 -10.625074 270)
			(size 0.519938 1.4986)
			(layers "F.Cu" "F.Mask" "F.Paste")
			(net "RST_M_GH_CPU1_FPGA_N")
		)
		(pad "208" smd rect
			(at 2.050034 -9.774936 270)
			(size 0.519938 1.4986)
			(layers "F.Cu" "F.Mask" "F.Paste")
			(net "GND")
		)
		(pad "209" smd rect
			(at 2.050034 -8.925052 270)
			(size 0.519938 1.4986)
			(layers "F.Cu" "F.Mask" "F.Paste")
			(net "M_H_CPU1_SA_CS_N<3>")
		)
		(pad "210" smd rect
			(at 2.050034 -8.074914 270)
			(size 0.519938 1.4986)
			(layers "F.Cu" "F.Mask" "F.Paste")
			(net "GND")
		)
		(pad "211" smd rect
			(at 2.050034 -7.22503 270)
			(size 0.519938 1.4986)
			(layers "F.Cu" "F.Mask" "F.Paste")
			(net "M_H_CPU1_SA_CA<1>")
		)
		(pad "212" smd rect
			(at 2.050034 -6.374892 270)
			(size 0.519938 1.4986)
			(layers "F.Cu" "F.Mask" "F.Paste")
			(net "GND")
		)
		(pad "213" smd rect
			(at 2.050034 -5.525008 270)
			(size 0.519938 1.4986)
			(layers "F.Cu" "F.Mask" "F.Paste")
			(net "M_H_CPU1_SA_CA<3>")
		)
		(pad "214" smd rect
			(at 2.050034 -4.675124 270)
			(size 0.519938 1.4986)
			(layers "F.Cu" "F.Mask" "F.Paste")
			(net "GND")
		)
		(pad "215" smd rect
			(at 2.050034 -3.824986 270)
			(size 0.519938 1.4986)
			(layers "F.Cu" "F.Mask" "F.Paste")
			(net "M_H_CPU1_SA_CA<5>")
		)
		(pad "216" smd rect
			(at 2.050034 -2.975102 270)
			(size 0.519938 1.4986)
			(layers "F.Cu" "F.Mask" "F.Paste")
			(net "GND")
		)
		(pad "217" smd rect
			(at 2.050034 -2.124964 270)
			(size 0.519938 1.4986)
			(layers "F.Cu" "F.Mask" "F.Paste")
			(net "M_H_CPU1_CLK_DP<1>")
		)
		(pad "218" smd rect
			(at 2.050034 -1.27508 270)
			(size 0.519938 1.4986)
			(layers "F.Cu" "F.Mask" "F.Paste")
			(net "M_H_CPU1_CLK_DN<1>")
		)
		(pad "219" smd rect
			(at 2.050034 -0.424942 270)
			(size 0.519938 1.4986)
			(layers "F.Cu" "F.Mask" "F.Paste")
			(net "GND")
		)
		(pad "220" smd rect
			(at 2.050034 5.525008 270)
			(size 0.519938 1.4986)
			(layers "F.Cu" "F.Mask" "F.Paste")
			(net "TP_CHH_CPU1_DIMM2_FRU_4")
		)
		(pad "221" smd rect
			(at 2.050034 6.374892 270)
			(size 0.519938 1.4986)
			(layers "F.Cu" "F.Mask" "F.Paste")
			(net "M_H_CPU1_SB_CA<1>")
		)
		(pad "222" smd rect
			(at 2.050034 7.22503 270)
			(size 0.519938 1.4986)
			(layers "F.Cu" "F.Mask" "F.Paste")
			(net "GND")
		)
		(pad "223" smd rect
			(at 2.050034 8.074914 270)
			(size 0.519938 1.4986)
			(layers "F.Cu" "F.Mask" "F.Paste")
			(net "M_H_CPU1_SB_CA<3>")
		)
		(pad "224" smd rect
			(at 2.050034 8.925052 270)
			(size 0.519938 1.4986)
			(layers "F.Cu" "F.Mask" "F.Paste")
			(net "GND")
		)
		(pad "225" smd rect
			(at 2.050034 9.774936 270)
			(size 0.519938 1.4986)
			(layers "F.Cu" "F.Mask" "F.Paste")
			(net "M_H_CPU1_SB_CA<5>")
		)
		(pad "226" smd rect
			(at 2.050034 10.625074 270)
			(size 0.519938 1.4986)
			(layers "F.Cu" "F.Mask" "F.Paste")
			(net "GND")
		)
		(pad "227" smd rect
			(at 2.050034 11.474958 270)
			(size 0.519938 1.4986)
			(layers "F.Cu" "F.Mask" "F.Paste")
			(net "M_H_CPU1_SB_PAR")
		)
		(pad "228" smd rect
			(at 2.050034 12.325096 270)
			(size 0.519938 1.4986)
			(layers "F.Cu" "F.Mask" "F.Paste")
			(net "GND")
		)
		(pad "229" smd rect
			(at 2.050034 13.17498 270)
			(size 0.519938 1.4986)
			(layers "F.Cu" "F.Mask" "F.Paste")
			(net "M_H_CPU1_SB_CS_N<3>")
		)
		(pad "230" smd rect
			(at 2.050034 14.025118 270)
			(size 0.519938 1.4986)
			(layers "F.Cu" "F.Mask" "F.Paste")
			(net "GND")
		)
		(pad "231" smd rect
			(at 2.050034 14.875002 270)
			(size 0.519938 1.4986)
			(layers "F.Cu" "F.Mask" "F.Paste")
			(net "TP_CHH_CPU1_DIMM2_FRU_5")
		)
		(pad "232" smd rect
			(at 2.050034 15.724886 270)
			(size 0.519938 1.4986)
			(layers "F.Cu" "F.Mask" "F.Paste")
			(net "TP_CHH_CPU1_DIMM2_FRU_6")
		)
		(pad "233" smd rect
			(at 2.050034 16.575024 270)
			(size 0.519938 1.4986)
			(layers "F.Cu" "F.Mask" "F.Paste")
			(net "GND")
		)
		(pad "234" smd rect
			(at 2.050034 17.424908 270)
			(size 0.519938 1.4986)
			(layers "F.Cu" "F.Mask" "F.Paste")
			(net "M_H_CPU1_SB_CB<6>")
		)
		(pad "235" smd rect
			(at 2.050034 18.275046 270)
			(size 0.519938 1.4986)
			(layers "F.Cu" "F.Mask" "F.Paste")
			(net "GND")
		)
		(pad "236" smd rect
			(at 2.050034 19.12493 270)
			(size 0.519938 1.4986)
			(layers "F.Cu" "F.Mask" "F.Paste")
			(net "M_H_CPU1_SB_CB<7>")
		)
		(pad "237" smd rect
			(at 2.050034 19.975068 270)
			(size 0.519938 1.4986)
			(layers "F.Cu" "F.Mask" "F.Paste")
			(net "GND")
		)
		(pad "238" smd rect
			(at 2.050034 20.824952 270)
			(size 0.519938 1.4986)
			(layers "F.Cu" "F.Mask" "F.Paste")
			(net "M_H_CPU1_SB_DQS_DN<4>")
		)
		(pad "239" smd rect
			(at 2.050034 21.67509 270)
			(size 0.519938 1.4986)
			(layers "F.Cu" "F.Mask" "F.Paste")
			(net "M_H_CPU1_SB_DQS_DP<4>")
		)
		(pad "240" smd rect
			(at 2.050034 22.524974 270)
			(size 0.519938 1.4986)
			(layers "F.Cu" "F.Mask" "F.Paste")
			(net "GND")
		)
		(pad "241" smd rect
			(at 2.050034 23.375112 270)
			(size 0.519938 1.4986)
			(layers "F.Cu" "F.Mask" "F.Paste")
			(net "M_H_CPU1_SB_CB<2>")
		)
		(pad "242" smd rect
			(at 2.050034 24.224996 270)
			(size 0.519938 1.4986)
			(layers "F.Cu" "F.Mask" "F.Paste")
			(net "GND")
		)
		(pad "243" smd rect
			(at 2.050034 25.07488 270)
			(size 0.519938 1.4986)
			(layers "F.Cu" "F.Mask" "F.Paste")
			(net "M_H_CPU1_SB_CB<3>")
		)
		(pad "244" smd rect
			(at 2.050034 25.925018 270)
			(size 0.519938 1.4986)
			(layers "F.Cu" "F.Mask" "F.Paste")
			(net "GND")
		)
		(pad "245" smd rect
			(at 2.050034 26.774902 270)
			(size 0.519938 1.4986)
			(layers "F.Cu" "F.Mask" "F.Paste")
			(net "M_H_CPU1_SB_DQ<2>")
		)
		(pad "246" smd rect
			(at 2.050034 27.62504 270)
			(size 0.519938 1.4986)
			(layers "F.Cu" "F.Mask" "F.Paste")
			(net "GND")
		)
		(pad "247" smd rect
			(at 2.050034 28.474924 270)
			(size 0.519938 1.4986)
			(layers "F.Cu" "F.Mask" "F.Paste")
			(net "M_H_CPU1_SB_DQ<3>")
		)
		(pad "248" smd rect
			(at 2.050034 29.325062 270)
			(size 0.519938 1.4986)
			(layers "F.Cu" "F.Mask" "F.Paste")
			(net "GND")
		)
		(pad "249" smd rect
			(at 2.050034 30.174946 270)
			(size 0.519938 1.4986)
			(layers "F.Cu" "F.Mask" "F.Paste")
			(net "M_H_CPU1_SB_DQS_DN<5>")
		)
		(pad "250" smd rect
			(at 2.050034 31.025084 270)
			(size 0.519938 1.4986)
			(layers "F.Cu" "F.Mask" "F.Paste")
			(net "M_H_CPU1_SB_DQS_DP<5>")
		)
		(pad "251" smd rect
			(at 2.050034 31.874968 270)
			(size 0.519938 1.4986)
			(layers "F.Cu" "F.Mask" "F.Paste")
			(net "GND")
		)
		(pad "252" smd rect
			(at 2.050034 32.725106 270)
			(size 0.519938 1.4986)
			(layers "F.Cu" "F.Mask" "F.Paste")
			(net "M_H_CPU1_SB_DQ<6>")
		)
		(pad "253" smd rect
			(at 2.050034 33.57499 270)
			(size 0.519938 1.4986)
			(layers "F.Cu" "F.Mask" "F.Paste")
			(net "GND")
		)
		(pad "254" smd rect
			(at 2.050034 34.425128 270)
			(size 0.519938 1.4986)
			(layers "F.Cu" "F.Mask" "F.Paste")
			(net "M_H_CPU1_SB_DQ<7>")
		)
		(pad "255" smd rect
			(at 2.050034 35.275012 270)
			(size 0.519938 1.4986)
			(layers "F.Cu" "F.Mask" "F.Paste")
			(net "GND")
		)
		(pad "256" smd rect
			(at 2.050034 36.124896 270)
			(size 0.519938 1.4986)
			(layers "F.Cu" "F.Mask" "F.Paste")
			(net "M_H_CPU1_SB_DQ<10>")
		)
		(pad "257" smd rect
			(at 2.050034 36.975034 270)
			(size 0.519938 1.4986)
			(layers "F.Cu" "F.Mask" "F.Paste")
			(net "GND")
		)
		(pad "258" smd rect
			(at 2.050034 37.824918 270)
			(size 0.519938 1.4986)
			(layers "F.Cu" "F.Mask" "F.Paste")
			(net "M_H_CPU1_SB_DQ<11>")
		)
		(pad "259" smd rect
			(at 2.050034 38.675056 270)
			(size 0.519938 1.4986)
			(layers "F.Cu" "F.Mask" "F.Paste")
			(net "GND")
		)
		(pad "260" smd rect
			(at 2.050034 39.52494 270)
			(size 0.519938 1.4986)
			(layers "F.Cu" "F.Mask" "F.Paste")
			(net "M_H_CPU1_SB_DQS_DN<6>")
		)
		(pad "261" smd rect
			(at 2.050034 40.375078 270)
			(size 0.519938 1.4986)
			(layers "F.Cu" "F.Mask" "F.Paste")
			(net "M_H_CPU1_SB_DQS_DP<6>")
		)
		(pad "262" smd rect
			(at 2.050034 41.224962 270)
			(size 0.519938 1.4986)
			(layers "F.Cu" "F.Mask" "F.Paste")
			(net "GND")
		)
		(pad "263" smd rect
			(at 2.050034 42.0751 270)
			(size 0.519938 1.4986)
			(layers "F.Cu" "F.Mask" "F.Paste")
			(net "M_H_CPU1_SB_DQ<14>")
		)
		(pad "264" smd rect
			(at 2.050034 42.924984 270)
			(size 0.519938 1.4986)
			(layers "F.Cu" "F.Mask" "F.Paste")
			(net "GND")
		)
		(pad "265" smd rect
			(at 2.050034 43.775122 270)
			(size 0.519938 1.4986)
			(layers "F.Cu" "F.Mask" "F.Paste")
			(net "M_H_CPU1_SB_DQ<15>")
		)
		(pad "266" smd rect
			(at 2.050034 44.625006 270)
			(size 0.519938 1.4986)
			(layers "F.Cu" "F.Mask" "F.Paste")
			(net "GND")
		)
		(pad "267" smd rect
			(at 2.050034 45.47489 270)
			(size 0.519938 1.4986)
			(layers "F.Cu" "F.Mask" "F.Paste")
			(net "M_H_CPU1_SB_DQ<18>")
		)
		(pad "268" smd rect
			(at 2.050034 46.325028 270)
			(size 0.519938 1.4986)
			(layers "F.Cu" "F.Mask" "F.Paste")
			(net "GND")
		)
		(pad "269" smd rect
			(at 2.050034 47.174912 270)
			(size 0.519938 1.4986)
			(layers "F.Cu" "F.Mask" "F.Paste")
			(net "M_H_CPU1_SB_DQ<19>")
		)
		(pad "270" smd rect
			(at 2.050034 48.02505 270)
			(size 0.519938 1.4986)
			(layers "F.Cu" "F.Mask" "F.Paste")
			(net "GND")
		)
		(pad "271" smd rect
			(at 2.050034 48.874934 270)
			(size 0.519938 1.4986)
			(layers "F.Cu" "F.Mask" "F.Paste")
			(net "M_H_CPU1_SB_DQS_DN<7>")
		)
		(pad "272" smd rect
			(at 2.050034 49.725072 270)
			(size 0.519938 1.4986)
			(layers "F.Cu" "F.Mask" "F.Paste")
			(net "M_H_CPU1_SB_DQS_DP<7>")
		)
		(pad "273" smd rect
			(at 2.050034 50.574956 270)
			(size 0.519938 1.4986)
			(layers "F.Cu" "F.Mask" "F.Paste")
			(net "GND")
		)
		(pad "274" smd rect
			(at 2.050034 51.425094 270)
			(size 0.519938 1.4986)
			(layers "F.Cu" "F.Mask" "F.Paste")
			(net "M_H_CPU1_SB_DQ<22>")
		)
		(pad "275" smd rect
			(at 2.050034 52.274978 270)
			(size 0.519938 1.4986)
			(layers "F.Cu" "F.Mask" "F.Paste")
			(net "GND")
		)
		(pad "276" smd rect
			(at 2.050034 53.125116 270)
			(size 0.519938 1.4986)
			(layers "F.Cu" "F.Mask" "F.Paste")
			(net "M_H_CPU1_SB_DQ<23>")
		)
		(pad "277" smd rect
			(at 2.050034 53.975 270)
			(size 0.519938 1.4986)
			(layers "F.Cu" "F.Mask" "F.Paste")
			(net "GND")
		)
		(pad "278" smd rect
			(at 2.050034 54.824884 270)
			(size 0.519938 1.4986)
			(layers "F.Cu" "F.Mask" "F.Paste")
			(net "M_H_CPU1_SB_DQ<26>")
		)
		(pad "279" smd rect
			(at 2.050034 55.675022 270)
			(size 0.519938 1.4986)
			(layers "F.Cu" "F.Mask" "F.Paste")
			(net "GND")
		)
		(pad "280" smd rect
			(at 2.050034 56.524906 270)
			(size 0.519938 1.4986)
			(layers "F.Cu" "F.Mask" "F.Paste")
			(net "M_H_CPU1_SB_DQ<27>")
		)
		(pad "281" smd rect
			(at 2.050034 57.375044 270)
			(size 0.519938 1.4986)
			(layers "F.Cu" "F.Mask" "F.Paste")
			(net "GND")
		)
		(pad "282" smd rect
			(at 2.050034 58.224928 270)
			(size 0.519938 1.4986)
			(layers "F.Cu" "F.Mask" "F.Paste")
			(net "M_H_CPU1_SB_DQS_DN<8>")
		)
		(pad "283" smd rect
			(at 2.050034 59.075066 270)
			(size 0.519938 1.4986)
			(layers "F.Cu" "F.Mask" "F.Paste")
			(net "M_H_CPU1_SB_DQS_DP<8>")
		)
		(pad "284" smd rect
			(at 2.050034 59.92495 270)
			(size 0.519938 1.4986)
			(layers "F.Cu" "F.Mask" "F.Paste")
			(net "GND")
		)
		(pad "285" smd rect
			(at 2.050034 60.775088 270)
			(size 0.519938 1.4986)
			(layers "F.Cu" "F.Mask" "F.Paste")
			(net "M_H_CPU1_SB_DQ<30>")
		)
		(pad "286" smd rect
			(at 2.050034 61.624972 270)
			(size 0.519938 1.4986)
			(layers "F.Cu" "F.Mask" "F.Paste")
			(net "GND")
		)
		(pad "287" smd rect
			(at 2.050034 62.47511 270)
			(size 0.519938 1.4986)
			(layers "F.Cu" "F.Mask" "F.Paste")
			(net "M_H_CPU1_SB_DQ<31>")
		)
		(pad "288" smd rect
			(at 2.050034 63.324994 270)
			(size 0.519938 1.4986)
			(layers "F.Cu" "F.Mask" "F.Paste")
			(net "GND")
		)
		(pad "G1" thru_hole oval
			(at 0 -68.97497)
			(size 2.8194 1.5748)
			(drill oval 2.4384 1.1938)
			(layers "*.Cu" "*.Mask")
			(remove_unused_layers no)
			(net "GND")
			(clearance 0.127)
			(thermal_gap 0.127)
		)
		(pad "G2" thru_hole oval
			(at 0 3.875024)
			(size 2.8194 1.5748)
			(drill oval 2.4384 1.1938)
			(layers "*.Cu" "*.Mask")
			(remove_unused_layers no)
			(net "GND")
			(clearance 0.127)
			(thermal_gap 0.127)
		)
		(pad "G3" thru_hole oval
			(at 0 68.97497)
			(size 2.8194 1.5748)
			(drill oval 2.4384 1.1938)
			(layers "*.Cu" "*.Mask")
			(remove_unused_layers no)
			(net "GND")
			(clearance 0.127)
			(thermal_gap 0.127)
		)
	)
	(footprint ""
		(layer "F.Cu")
		(at 406.124664 -368.826034)
		(property "Reference" "R334"
			(at 0 0 0)
			(layer "F.SilkS")
			(hide yes)
			(effects
				(font
					(size 1.27 1.27)
				)
			)
		)
		(property "Value" ""
			(at 0 0 0)
			(layer "F.Fab")
			(effects
				(font
					(size 1.27 1.27)
				)
			)
		)
		(duplicate_pad_numbers_are_jumpers no)
		(fp_line
			(start -0.7874 -0.4064)
			(end 0.7874 -0.4064)
			(stroke
				(width 0.1524)
				(type default)
			)
			(layer "F.SilkS")
		)
		(fp_line
			(start -0.7874 0.4064)
			(end -0.7874 -0.4064)
			(stroke
				(width 0.1524)
				(type default)
			)
			(layer "F.SilkS")
		)
		(fp_line
			(start 0.7874 -0.4064)
			(end 0.7874 0.4064)
			(stroke
				(width 0.1524)
				(type default)
			)
			(layer "F.SilkS")
		)
		(fp_line
			(start 0.7874 0.4064)
			(end -0.7874 0.4064)
			(stroke
				(width 0.1524)
				(type default)
			)
			(layer "F.SilkS")
		)
		(fp_line
			(start -0.67945 -0.305054)
			(end -0.12065 -0.305054)
			(stroke
				(width 0.1)
				(type default)
			)
			(layer "F.Fab")
		)
		(fp_line
			(start -0.67945 0.3048)
			(end -0.67945 -0.305054)
			(stroke
				(width 0.1)
				(type default)
			)
			(layer "F.Fab")
		)
		(fp_line
			(start -0.12065 -0.305054)
			(end -0.12065 -0.2794)
			(stroke
				(width 0.1)
				(type default)
			)
			(layer "F.Fab")
		)
		(fp_line
			(start -0.12065 -0.2794)
			(end 0.12065 -0.2794)
			(stroke
				(width 0.1)
				(type default)
			)
			(layer "F.Fab")
		)
		(fp_line
			(start -0.12065 0.2794)
			(end -0.12065 0.3048)
			(stroke
				(width 0.1)
				(type default)
			)
			(layer "F.Fab")
		)
		(fp_line
			(start -0.12065 0.3048)
			(end -0.67945 0.3048)
			(stroke
				(width 0.1)
				(type default)
			)
			(layer "F.Fab")
		)
		(fp_line
			(start 0.120396 0.2794)
			(end -0.12065 0.2794)
			(stroke
				(width 0.1)
				(type default)
			)
			(layer "F.Fab")
		)
		(fp_line
			(start 0.120396 0.3048)
			(end 0.120396 0.2794)
			(stroke
				(width 0.1)
				(type default)
			)
			(layer "F.Fab")
		)
		(fp_line
			(start 0.12065 -0.3048)
			(end 0.67945 -0.3048)
			(stroke
				(width 0.1)
				(type default)
			)
			(layer "F.Fab")
		)
		(fp_line
			(start 0.12065 -0.2794)
			(end 0.12065 -0.3048)
			(stroke
				(width 0.1)
				(type default)
			)
			(layer "F.Fab")
		)
		(fp_line
			(start 0.67945 -0.3048)
			(end 0.67945 0.3048)
			(stroke
				(width 0.1)
				(type default)
			)
			(layer "F.Fab")
		)
		(fp_line
			(start 0.67945 0.3048)
			(end 0.120396 0.3048)
			(stroke
				(width 0.1)
				(type default)
			)
			(layer "F.Fab")
		)
		(pad "1" smd circle
			(at -0.40005 0)
			(size 0 0)
			(layers "F.Cu" "F.Mask" "F.Paste")
			(net "PD_PIROM_CPU0_ADDR1")
		)
		(pad "2" smd circle
			(at 0.40005 0)
			(size 0 0)
			(layers "F.Cu" "F.Mask" "F.Paste")
			(net "GND")
		)
	)
	(footprint ""
		(layer "F.Cu")
		(at 215.392 -96.103948)
		(property "Reference" "U325"
			(at -5.08 1.04267 0)
			(unlocked yes)
			(layer "F.SilkS")
			(effects
				(font
					(size 0.7874 0.5842)
					(thickness 0.1524)
				)
			)
		)
		(property "Value" ""
			(at 0 0 0)
			(layer "F.Fab")
			(effects
				(font
					(size 1.27 1.27)
				)
			)
		)
		(duplicate_pad_numbers_are_jumpers no)
		(fp_line
			(start -1.949958 -1.610106)
			(end 1.949958 -1.610106)
			(stroke
				(width 0.1524)
				(type default)
			)
			(layer "F.SilkS")
		)
		(fp_line
			(start -1.949958 1.610106)
			(end -1.949958 -1.610106)
			(stroke
				(width 0.1524)
				(type default)
			)
			(layer "F.SilkS")
		)
		(fp_line
			(start 1.949958 -1.560068)
			(end 1.949958 1.610106)
			(stroke
				(width 0.1524)
				(type default)
			)
			(layer "F.SilkS")
		)
		(fp_line
			(start 1.949958 1.610106)
			(end -1.949958 1.610106)
			(stroke
				(width 0.1524)
				(type default)
			)
			(layer "F.SilkS")
		)
		(fp_line
			(start -0.750062 -1.560068)
			(end 0.750062 -1.560068)
			(stroke
				(width 0.1)
				(type default)
			)
			(layer "F.Fab")
		)
		(fp_line
			(start -0.750062 1.560068)
			(end -0.750062 -1.560068)
			(stroke
				(width 0.1)
				(type default)
			)
			(layer "F.Fab")
		)
		(fp_line
			(start 0.750062 -1.560068)
			(end 0.750062 1.560068)
			(stroke
				(width 0.1)
				(type default)
			)
			(layer "F.Fab")
		)
		(fp_line
			(start 0.750062 1.560068)
			(end -0.750062 1.560068)
			(stroke
				(width 0.1)
				(type default)
			)
			(layer "F.Fab")
		)
		(pad "D" smd rect
			(at 1.100074 0 270)
			(size 1.016 1.4224)
			(layers "F.Cu" "F.Mask" "F.Paste")
			(net "IRQ_UV_DETECT_N")
		)
		(pad "G" smd rect
			(at -1.100074 -0.94996 270)
			(size 1.016 1.4224)
			(layers "F.Cu" "F.Mask" "F.Paste")
			(net "A_P12V_STBY_FPH_GATE")
		)
		(pad "S" smd rect
			(at -1.100074 0.94996 270)
			(size 1.016 1.4224)
			(layers "F.Cu" "F.Mask" "F.Paste")
			(net "GND")
		)
	)
	(footprint ""
		(layer "F.Cu")
		(at 109.144308 -74.863452 -90)
		(property "Reference" "R3071"
			(at 0 0 270)
			(layer "F.SilkS")
			(hide yes)
			(effects
				(font
					(size 1.27 1.27)
				)
			)
		)
		(property "Value" ""
			(at 0 0 270)
			(layer "F.Fab")
			(effects
				(font
					(size 1.27 1.27)
				)
			)
		)
		(duplicate_pad_numbers_are_jumpers no)
		(fp_line
			(start -0.7874 0.4064)
			(end -0.7874 -0.4064)
			(stroke
				(width 0.1524)
				(type default)
			)
			(layer "F.SilkS")
		)
		(fp_line
			(start 0.7874 0.4064)
			(end -0.7874 0.4064)
			(stroke
				(width 0.1524)
				(type default)
			)
			(layer "F.SilkS")
		)
		(fp_line
			(start -0.7874 -0.4064)
			(end 0.7874 -0.4064)
			(stroke
				(width 0.1524)
				(type default)
			)
			(layer "F.SilkS")
		)
		(fp_line
			(start 0.7874 -0.4064)
			(end 0.7874 0.4064)
			(stroke
				(width 0.1524)
				(type default)
			)
			(layer "F.SilkS")
		)
		(fp_line
			(start -0.67945 0.3048)
			(end -0.67945 -0.305054)
			(stroke
				(width 0.1)
				(type default)
			)
			(layer "F.Fab")
		)
		(fp_line
			(start -0.12065 0.3048)
			(end -0.67945 0.3048)
			(stroke
				(width 0.1)
				(type default)
			)
			(layer "F.Fab")
		)
		(fp_line
			(start 0.120396 0.3048)
			(end 0.120396 0.2794)
			(stroke
				(width 0.1)
				(type default)
			)
			(layer "F.Fab")
		)
		(fp_line
			(start 0.67945 0.3048)
			(end 0.120396 0.3048)
			(stroke
				(width 0.1)
				(type default)
			)
			(layer "F.Fab")
		)
		(fp_line
			(start -0.12065 0.2794)
			(end -0.12065 0.3048)
			(stroke
				(width 0.1)
				(type default)
			)
			(layer "F.Fab")
		)
		(fp_line
			(start 0.120396 0.2794)
			(end -0.12065 0.2794)
			(stroke
				(width 0.1)
				(type default)
			)
			(layer "F.Fab")
		)
		(fp_line
			(start -0.12065 -0.2794)
			(end 0.12065 -0.2794)
			(stroke
				(width 0.1)
				(type default)
			)
			(layer "F.Fab")
		)
		(fp_line
			(start 0.12065 -0.2794)
			(end 0.12065 -0.3048)
			(stroke
				(width 0.1)
				(type default)
			)
			(layer "F.Fab")
		)
		(fp_line
			(start 0.12065 -0.3048)
			(end 0.67945 -0.3048)
			(stroke
				(width 0.1)
				(type default)
			)
			(layer "F.Fab")
		)
		(fp_line
			(start 0.67945 -0.3048)
			(end 0.67945 0.3048)
			(stroke
				(width 0.1)
				(type default)
			)
			(layer "F.Fab")
		)
		(fp_line
			(start -0.67945 -0.305054)
			(end -0.12065 -0.305054)
			(stroke
				(width 0.1)
				(type default)
			)
			(layer "F.Fab")
		)
		(fp_line
			(start -0.12065 -0.305054)
			(end -0.12065 -0.2794)
			(stroke
				(width 0.1)
				(type default)
			)
			(layer "F.Fab")
		)
		(pad "1" smd circle
			(at -0.40005 0 270)
			(size 0 0)
			(layers "F.Cu" "F.Mask" "F.Paste")
			(net "LED_PWRGD_P1V8_PCH_AUX")
		)
		(pad "2" smd circle
			(at 0.40005 0 270)
			(size 0 0)
			(layers "F.Cu" "F.Mask" "F.Paste")
			(net "P3V3_AUX")
		)
	)
	(footprint ""
		(layer "F.Cu")
		(at 384.56489 -402.371052 -90)
		(property "Reference" "C942"
			(at 0 0 270)
			(layer "F.SilkS")
			(hide yes)
			(effects
				(font
					(size 1.27 1.27)
				)
			)
		)
		(property "Value" ""
			(at 0 0 270)
			(layer "F.Fab")
			(effects
				(font
					(size 1.27 1.27)
				)
			)
		)
		(duplicate_pad_numbers_are_jumpers no)
		(fp_line
			(start -0.299974 0.150114)
			(end -0.299974 -0.150114)
			(stroke
				(width 0.1)
				(type default)
			)
			(layer "F.Fab")
		)
		(fp_line
			(start 0.299974 0.150114)
			(end -0.299974 0.150114)
			(stroke
				(width 0.1)
				(type default)
			)
			(layer "F.Fab")
		)
		(fp_line
			(start -0.299974 -0.150114)
			(end 0.299974 -0.150114)
			(stroke
				(width 0.1)
				(type default)
			)
			(layer "F.Fab")
		)
		(fp_line
			(start 0.299974 -0.150114)
			(end 0.299974 0.150114)
			(stroke
				(width 0.1)
				(type default)
			)
			(layer "F.Fab")
		)
		(pad "1" smd rect
			(at -0.2667 0 270)
			(size 0.3048 0.381)
			(layers "F.Cu" "F.Mask" "F.Paste")
			(net "P5E_CPU0_PE2_TX_C_DN<11>")
		)
		(pad "2" smd rect
			(at 0.2667 0 270)
			(size 0.3048 0.381)
			(layers "F.Cu" "F.Mask" "F.Paste")
			(net "P5E_CPU0_PE2_TX_DN<11>")
		)
	)
	(footprint ""
		(layer "F.Cu")
		(at 293.078916 -367.345976)
		(property "Reference" "PC723_P0_4"
			(at 0 0 0)
			(layer "F.SilkS")
			(hide yes)
			(effects
				(font
					(size 1.27 1.27)
				)
			)
		)
		(property "Value" ""
			(at 0 0 0)
			(layer "F.Fab")
			(effects
				(font
					(size 1.27 1.27)
				)
			)
		)
		(duplicate_pad_numbers_are_jumpers no)
		(fp_line
			(start -1.524 -0.762)
			(end 1.524 -0.762)
			(stroke
				(width 0.1524)
				(type default)
			)
			(layer "F.SilkS")
		)
		(fp_line
			(start -1.524 0.762)
			(end -1.524 -0.762)
			(stroke
				(width 0.1524)
				(type default)
			)
			(layer "F.SilkS")
		)
		(fp_line
			(start 1.524 -0.762)
			(end 1.524 0.762)
			(stroke
				(width 0.1524)
				(type default)
			)
			(layer "F.SilkS")
		)
		(fp_line
			(start 1.524 0.762)
			(end -1.524 0.762)
			(stroke
				(width 0.1524)
				(type default)
			)
			(layer "F.SilkS")
		)
		(fp_line
			(start -1.1049 -0.724916)
			(end -1.1049 0.724916)
			(stroke
				(width 0.1)
				(type default)
			)
			(layer "F.Fab")
		)
		(fp_line
			(start -1.1049 0.724916)
			(end 1.1049 0.724916)
			(stroke
				(width 0.1)
				(type default)
			)
			(layer "F.Fab")
		)
		(fp_line
			(start 1.1049 -0.724916)
			(end -1.1049 -0.724916)
			(stroke
				(width 0.1)
				(type default)
			)
			(layer "F.Fab")
		)
		(fp_line
			(start 1.1049 0.724916)
			(end 1.1049 -0.724916)
			(stroke
				(width 0.1)
				(type default)
			)
			(layer "F.Fab")
		)
		(pad "1" smd rect
			(at -0.889 0 180)
			(size 1.016 1.27)
			(layers "F.Cu" "F.Mask" "F.Paste")
			(net "SW_P12V_PVCCFA_EHV_FIVRA_CPU0_L")
		)
		(pad "2" smd rect
			(at 0.889 0 180)
			(size 1.016 1.27)
			(layers "F.Cu" "F.Mask" "F.Paste")
			(net "GND")
		)
	)
	(footprint ""
		(layer "F.Cu")
		(at 89.5604 -38.659308)
		(property "Reference" "U53"
			(at -0.28448 -2.553208 0)
			(unlocked yes)
			(layer "F.SilkS")
			(effects
				(font
					(size 0.7874 0.5842)
					(thickness 0.1524)
				)
				(justify left)
			)
		)
		(property "Value" ""
			(at 0 0 0)
			(layer "F.Fab")
			(effects
				(font
					(size 1.27 1.27)
				)
			)
		)
		(duplicate_pad_numbers_are_jumpers no)
		(fp_line
			(start -1.733296 -1.549908)
			(end -1.733296 1.549908)
			(stroke
				(width 0.1524)
				(type default)
			)
			(layer "F.SilkS")
		)
		(fp_line
			(start -1.733296 1.549908)
			(end 1.733296 1.549908)
			(stroke
				(width 0.1524)
				(type default)
			)
			(layer "F.SilkS")
		)
		(fp_line
			(start -0.660908 -1.549908)
			(end -1.733296 -1.549908)
			(stroke
				(width 0.1524)
				(type default)
			)
			(layer "F.SilkS")
		)
		(fp_line
			(start 0 -0.889)
			(end -0.660908 -1.549908)
			(stroke
				(width 0.1524)
				(type default)
			)
			(layer "F.SilkS")
		)
		(fp_line
			(start 0.660908 -1.549908)
			(end 0 -0.889)
			(stroke
				(width 0.1524)
				(type default)
			)
			(layer "F.SilkS")
		)
		(fp_line
			(start 1.733296 -1.549908)
			(end 0.660908 -1.549908)
			(stroke
				(width 0.1524)
				(type default)
			)
			(layer "F.SilkS")
		)
		(fp_line
			(start 1.733296 1.549908)
			(end 1.733296 -1.549908)
			(stroke
				(width 0.1524)
				(type default)
			)
			(layer "F.SilkS")
		)
		(fp_poly
			(pts
				(xy -0.92456 -2.2479) (xy -1.17856 -1.7399) (xy -1.43256 -2.2479)
			)
			(stroke
				(width 0)
				(type default)
			)
			(fill yes)
			(layer "F.SilkS")
		)
		(fp_line
			(start -0.849884 -1.549908)
			(end -0.849884 1.549908)
			(stroke
				(width 0.1)
				(type default)
			)
			(layer "F.Fab")
		)
		(fp_line
			(start -0.849884 1.549908)
			(end 0.849884 1.549908)
			(stroke
				(width 0.1)
				(type default)
			)
			(layer "F.Fab")
		)
		(fp_line
			(start 0.849884 -1.549908)
			(end -0.849884 -1.549908)
			(stroke
				(width 0.1)
				(type default)
			)
			(layer "F.Fab")
		)
		(fp_line
			(start 0.849884 1.549908)
			(end 0.849884 -1.549908)
			(stroke
				(width 0.1)
				(type default)
			)
			(layer "F.Fab")
		)
		(fp_poly
			(pts
				(xy -2.4384 -1.20396) (xy -2.4384 -0.69596) (xy -1.9304 -0.94996)
			)
			(stroke
				(width 0)
				(type default)
			)
			(fill yes)
			(layer "F.Fab")
		)
		(pad "1" smd rect
			(at -1.199896 -0.94996 270)
			(size 0.5588 0.8128)
			(layers "F.Cu" "F.Mask" "F.Paste")
			(net "HP_LVC3_OCP_V3_2_PWRGD_R")
		)
		(pad "2" smd rect
			(at -1.199896 0 270)
			(size 0.5588 0.8128)
			(layers "F.Cu" "F.Mask" "F.Paste")
			(net "RST_OCP_V3_2_N")
		)
		(pad "3" smd rect
			(at -1.199896 0.94996 270)
			(size 0.5588 0.8128)
			(layers "F.Cu" "F.Mask" "F.Paste")
			(net "GND")
		)
		(pad "4" smd rect
			(at 1.199896 0.94996 270)
			(size 0.5588 0.8128)
			(layers "F.Cu" "F.Mask" "F.Paste")
			(net "RST_HP_OCP_V3_2_N")
		)
		(pad "5" smd rect
			(at 1.199896 -0.94996 270)
			(size 0.5588 0.8128)
			(layers "F.Cu" "F.Mask" "F.Paste")
			(net "P3V3_AUX")
		)
	)
	(footprint ""
		(layer "F.Cu")
		(at 186.437524 -353.650296 -90)
		(property "Reference" "PC1193_P1_3"
			(at 0 0 270)
			(layer "F.SilkS")
			(hide yes)
			(effects
				(font
					(size 1.27 1.27)
				)
			)
		)
		(property "Value" ""
			(at 0 0 270)
			(layer "F.Fab")
			(effects
				(font
					(size 1.27 1.27)
				)
			)
		)
		(duplicate_pad_numbers_are_jumpers no)
		(fp_line
			(start -0.7874 0.4064)
			(end -0.7874 -0.4064)
			(stroke
				(width 0.1524)
				(type default)
			)
			(layer "F.SilkS")
		)
		(fp_line
			(start 0.7874 0.4064)
			(end -0.7874 0.4064)
			(stroke
				(width 0.1524)
				(type default)
			)
			(layer "F.SilkS")
		)
		(fp_line
			(start -0.7874 -0.4064)
			(end 0.7874 -0.4064)
			(stroke
				(width 0.1524)
				(type default)
			)
			(layer "F.SilkS")
		)
		(fp_line
			(start 0.7874 -0.4064)
			(end 0.7874 0.4064)
			(stroke
				(width 0.1524)
				(type default)
			)
			(layer "F.SilkS")
		)
		(fp_line
			(start -0.67945 0.3048)
			(end -0.67945 -0.305054)
			(stroke
				(width 0.1)
				(type default)
			)
			(layer "F.Fab")
		)
		(fp_line
			(start -0.12065 0.3048)
			(end -0.67945 0.3048)
			(stroke
				(width 0.1)
				(type default)
			)
			(layer "F.Fab")
		)
		(fp_line
			(start 0.120396 0.3048)
			(end 0.120396 0.2794)
			(stroke
				(width 0.1)
				(type default)
			)
			(layer "F.Fab")
		)
		(fp_line
			(start 0.67945 0.3048)
			(end 0.120396 0.3048)
			(stroke
				(width 0.1)
				(type default)
			)
			(layer "F.Fab")
		)
		(fp_line
			(start -0.12065 0.2794)
			(end -0.12065 0.3048)
			(stroke
				(width 0.1)
				(type default)
			)
			(layer "F.Fab")
		)
		(fp_line
			(start 0.120396 0.2794)
			(end -0.12065 0.2794)
			(stroke
				(width 0.1)
				(type default)
			)
			(layer "F.Fab")
		)
		(fp_line
			(start -0.12065 -0.2794)
			(end 0.12065 -0.2794)
			(stroke
				(width 0.1)
				(type default)
			)
			(layer "F.Fab")
		)
		(fp_line
			(start 0.12065 -0.2794)
			(end 0.12065 -0.3048)
			(stroke
				(width 0.1)
				(type default)
			)
			(layer "F.Fab")
		)
		(fp_line
			(start 0.12065 -0.3048)
			(end 0.67945 -0.3048)
			(stroke
				(width 0.1)
				(type default)
			)
			(layer "F.Fab")
		)
		(fp_line
			(start 0.67945 -0.3048)
			(end 0.67945 0.3048)
			(stroke
				(width 0.1)
				(type default)
			)
			(layer "F.Fab")
		)
		(fp_line
			(start -0.67945 -0.305054)
			(end -0.12065 -0.305054)
			(stroke
				(width 0.1)
				(type default)
			)
			(layer "F.Fab")
		)
		(fp_line
			(start -0.12065 -0.305054)
			(end -0.12065 -0.2794)
			(stroke
				(width 0.1)
				(type default)
			)
			(layer "F.Fab")
		)
		(pad "1" smd circle
			(at -0.40005 0 270)
			(size 0 0)
			(layers "F.Cu" "F.Mask" "F.Paste")
			(net "SW_P12V_PVCCFA_EHV_FIVRA_CPU1_R")
		)
		(pad "2" smd circle
			(at 0.40005 0 270)
			(size 0 0)
			(layers "F.Cu" "F.Mask" "F.Paste")
			(net "GND")
		)
	)
	(footprint ""
		(layer "F.Cu")
		(at 179.939442 -26.240232)
		(property "Reference" "PC2241"
			(at 0 0 0)
			(layer "F.SilkS")
			(hide yes)
			(effects
				(font
					(size 1.27 1.27)
				)
			)
		)
		(property "Value" ""
			(at 0 0 0)
			(layer "F.Fab")
			(effects
				(font
					(size 1.27 1.27)
				)
			)
		)
		(duplicate_pad_numbers_are_jumpers no)
		(fp_line
			(start -0.7874 -0.4064)
			(end 0.7874 -0.4064)
			(stroke
				(width 0.1524)
				(type default)
			)
			(layer "F.SilkS")
		)
		(fp_line
			(start -0.7874 0.4064)
			(end -0.7874 -0.4064)
			(stroke
				(width 0.1524)
				(type default)
			)
			(layer "F.SilkS")
		)
		(fp_line
			(start 0.7874 -0.4064)
			(end 0.7874 0.4064)
			(stroke
				(width 0.1524)
				(type default)
			)
			(layer "F.SilkS")
		)
		(fp_line
			(start 0.7874 0.4064)
			(end -0.7874 0.4064)
			(stroke
				(width 0.1524)
				(type default)
			)
			(layer "F.SilkS")
		)
		(fp_line
			(start -0.67945 -0.305054)
			(end -0.12065 -0.305054)
			(stroke
				(width 0.1)
				(type default)
			)
			(layer "F.Fab")
		)
		(fp_line
			(start -0.67945 0.3048)
			(end -0.67945 -0.305054)
			(stroke
				(width 0.1)
				(type default)
			)
			(layer "F.Fab")
		)
		(fp_line
			(start -0.12065 -0.305054)
			(end -0.12065 -0.2794)
			(stroke
				(width 0.1)
				(type default)
			)
			(layer "F.Fab")
		)
		(fp_line
			(start -0.12065 -0.2794)
			(end 0.12065 -0.2794)
			(stroke
				(width 0.1)
				(type default)
			)
			(layer "F.Fab")
		)
		(fp_line
			(start -0.12065 0.2794)
			(end -0.12065 0.3048)
			(stroke
				(width 0.1)
				(type default)
			)
			(layer "F.Fab")
		)
		(fp_line
			(start -0.12065 0.3048)
			(end -0.67945 0.3048)
			(stroke
				(width 0.1)
				(type default)
			)
			(layer "F.Fab")
		)
		(fp_line
			(start 0.120396 0.2794)
			(end -0.12065 0.2794)
			(stroke
				(width 0.1)
				(type default)
			)
			(layer "F.Fab")
		)
		(fp_line
			(start 0.120396 0.3048)
			(end 0.120396 0.2794)
			(stroke
				(width 0.1)
				(type default)
			)
			(layer "F.Fab")
		)
		(fp_line
			(start 0.12065 -0.3048)
			(end 0.67945 -0.3048)
			(stroke
				(width 0.1)
				(type default)
			)
			(layer "F.Fab")
		)
		(fp_line
			(start 0.12065 -0.2794)
			(end 0.12065 -0.3048)
			(stroke
				(width 0.1)
				(type default)
			)
			(layer "F.Fab")
		)
		(fp_line
			(start 0.67945 -0.3048)
			(end 0.67945 0.3048)
			(stroke
				(width 0.1)
				(type default)
			)
			(layer "F.Fab")
		)
		(fp_line
			(start 0.67945 0.3048)
			(end 0.120396 0.3048)
			(stroke
				(width 0.1)
				(type default)
			)
			(layer "F.Fab")
		)
		(pad "1" smd circle
			(at -0.40005 0)
			(size 0 0)
			(layers "F.Cu" "F.Mask" "F.Paste")
			(net "P12V_SCM_R")
		)
		(pad "2" smd circle
			(at 0.40005 0)
			(size 0 0)
			(layers "F.Cu" "F.Mask" "F.Paste")
			(net "GND")
		)
	)
	(footprint ""
		(layer "F.Cu")
		(at 297.183048 -367.919508)
		(property "Reference" "PR353"
			(at 0 0 0)
			(layer "F.SilkS")
			(hide yes)
			(effects
				(font
					(size 1.27 1.27)
				)
			)
		)
		(property "Value" ""
			(at 0 0 0)
			(layer "F.Fab")
			(effects
				(font
					(size 1.27 1.27)
				)
			)
		)
		(duplicate_pad_numbers_are_jumpers no)
		(fp_line
			(start -0.7874 -0.4064)
			(end 0.7874 -0.4064)
			(stroke
				(width 0.1524)
				(type default)
			)
			(layer "F.SilkS")
		)
		(fp_line
			(start -0.7874 0.4064)
			(end -0.7874 -0.4064)
			(stroke
				(width 0.1524)
				(type default)
			)
			(layer "F.SilkS")
		)
		(fp_line
			(start 0.7874 -0.4064)
			(end 0.7874 0.4064)
			(stroke
				(width 0.1524)
				(type default)
			)
			(layer "F.SilkS")
		)
		(fp_line
			(start 0.7874 0.4064)
			(end -0.7874 0.4064)
			(stroke
				(width 0.1524)
				(type default)
			)
			(layer "F.SilkS")
		)
		(fp_line
			(start -0.67945 -0.305054)
			(end -0.12065 -0.305054)
			(stroke
				(width 0.1)
				(type default)
			)
			(layer "F.Fab")
		)
		(fp_line
			(start -0.67945 0.3048)
			(end -0.67945 -0.305054)
			(stroke
				(width 0.1)
				(type default)
			)
			(layer "F.Fab")
		)
		(fp_line
			(start -0.12065 -0.305054)
			(end -0.12065 -0.2794)
			(stroke
				(width 0.1)
				(type default)
			)
			(layer "F.Fab")
		)
		(fp_line
			(start -0.12065 -0.2794)
			(end 0.12065 -0.2794)
			(stroke
				(width 0.1)
				(type default)
			)
			(layer "F.Fab")
		)
		(fp_line
			(start -0.12065 0.2794)
			(end -0.12065 0.3048)
			(stroke
				(width 0.1)
				(type default)
			)
			(layer "F.Fab")
		)
		(fp_line
			(start -0.12065 0.3048)
			(end -0.67945 0.3048)
			(stroke
				(width 0.1)
				(type default)
			)
			(layer "F.Fab")
		)
		(fp_line
			(start 0.120396 0.2794)
			(end -0.12065 0.2794)
			(stroke
				(width 0.1)
				(type default)
			)
			(layer "F.Fab")
		)
		(fp_line
			(start 0.120396 0.3048)
			(end 0.120396 0.2794)
			(stroke
				(width 0.1)
				(type default)
			)
			(layer "F.Fab")
		)
		(fp_line
			(start 0.12065 -0.3048)
			(end 0.67945 -0.3048)
			(stroke
				(width 0.1)
				(type default)
			)
			(layer "F.Fab")
		)
		(fp_line
			(start 0.12065 -0.2794)
			(end 0.12065 -0.3048)
			(stroke
				(width 0.1)
				(type default)
			)
			(layer "F.Fab")
		)
		(fp_line
			(start 0.67945 -0.3048)
			(end 0.67945 0.3048)
			(stroke
				(width 0.1)
				(type default)
			)
			(layer "F.Fab")
		)
		(fp_line
			(start 0.67945 0.3048)
			(end 0.120396 0.3048)
			(stroke
				(width 0.1)
				(type default)
			)
			(layer "F.Fab")
		)
		(pad "1" smd circle
			(at -0.40005 0)
			(size 0 0)
			(layers "F.Cu" "F.Mask" "F.Paste")
			(net "PVCCFA_EHV_FIVRA_CPU0_LSET2")
		)
		(pad "2" smd circle
			(at 0.40005 0)
			(size 0 0)
			(layers "F.Cu" "F.Mask" "F.Paste")
			(net "GND")
		)
	)
	(footprint ""
		(layer "F.Cu")
		(at 283.32176 -399.04162 90)
		(property "Reference" "U365"
			(at -1.905 -2.25933 90)
			(unlocked yes)
			(layer "F.SilkS")
			(effects
				(font
					(size 0.7874 0.5842)
					(thickness 0.1524)
				)
				(justify left)
			)
		)
		(property "Value" ""
			(at 0 0 90)
			(layer "F.Fab")
			(effects
				(font
					(size 1.27 1.27)
				)
			)
		)
		(duplicate_pad_numbers_are_jumpers no)
		(fp_line
			(start 1.905 -1.651)
			(end 1.905 1.651)
			(stroke
				(width 0.1524)
				(type default)
			)
			(layer "F.SilkS")
		)
		(fp_line
			(start -1.905 -1.651)
			(end 1.905 -1.651)
			(stroke
				(width 0.1524)
				(type default)
			)
			(layer "F.SilkS")
		)
		(fp_line
			(start 1.905 1.651)
			(end -1.905 1.651)
			(stroke
				(width 0.1524)
				(type default)
			)
			(layer "F.SilkS")
		)
		(fp_line
			(start -1.905 1.651)
			(end -1.905 -1.651)
			(stroke
				(width 0.1524)
				(type default)
			)
			(layer "F.SilkS")
		)
		(fp_line
			(start 0.6985 -1.524)
			(end 0.6985 -0.219964)
			(stroke
				(width 0.1)
				(type default)
			)
			(layer "F.Fab")
		)
		(fp_line
			(start -0.649986 -1.524)
			(end 0.6985 -1.524)
			(stroke
				(width 0.1)
				(type default)
			)
			(layer "F.Fab")
		)
		(fp_line
			(start -0.649986 -1.169924)
			(end -0.649986 -1.524)
			(stroke
				(width 0.1)
				(type default)
			)
			(layer "F.Fab")
		)
		(fp_line
			(start -1.249934 -1.169924)
			(end -0.649986 -1.169924)
			(stroke
				(width 0.1)
				(type default)
			)
			(layer "F.Fab")
		)
		(fp_line
			(start -0.6985 -0.729996)
			(end -1.249934 -0.729996)
			(stroke
				(width 0.1)
				(type default)
			)
			(layer "F.Fab")
		)
		(fp_line
			(start -1.249934 -0.729996)
			(end -1.249934 -1.169924)
			(stroke
				(width 0.1)
				(type default)
			)
			(layer "F.Fab")
		)
		(fp_line
			(start 1.249934 -0.219964)
			(end 1.249934 0.219964)
			(stroke
				(width 0.1)
				(type default)
			)
			(layer "F.Fab")
		)
		(fp_line
			(start 0.6985 -0.219964)
			(end 1.249934 -0.219964)
			(stroke
				(width 0.1)
				(type default)
			)
			(layer "F.Fab")
		)
		(fp_line
			(start 1.249934 0.219964)
			(end 0.6985 0.219964)
			(stroke
				(width 0.1)
				(type default)
			)
			(layer "F.Fab")
		)
		(fp_line
			(start 0.6985 0.219964)
			(end 0.6985 1.524)
			(stroke
				(width 0.1)
				(type default)
			)
			(layer "F.Fab")
		)
		(fp_line
			(start -0.6985 0.729996)
			(end -0.6985 -0.729996)
			(stroke
				(width 0.1)
				(type default)
			)
			(layer "F.Fab")
		)
		(fp_line
			(start -1.249934 0.729996)
			(end -0.6985 0.729996)
			(stroke
				(width 0.1)
				(type default)
			)
			(layer "F.Fab")
		)
		(fp_line
			(start -0.649986 1.169924)
			(end -1.249934 1.169924)
			(stroke
				(width 0.1)
				(type default)
			)
			(layer "F.Fab")
		)
		(fp_line
			(start -1.249934 1.169924)
			(end -1.249934 0.729996)
			(stroke
				(width 0.1)
				(type default)
			)
			(layer "F.Fab")
		)
		(fp_line
			(start 0.6985 1.524)
			(end -0.649986 1.524)
			(stroke
				(width 0.1)
				(type default)
			)
			(layer "F.Fab")
		)
		(fp_line
			(start -0.649986 1.524)
			(end -0.649986 1.169924)
			(stroke
				(width 0.1)
				(type default)
			)
			(layer "F.Fab")
		)
		(pad "B" smd rect
			(at -1.1176 -1.016)
			(size 1.016 1.27)
			(layers "F.Cu" "F.Mask" "F.Paste")
			(net "P12V_HSC_TEMP_R")
		)
		(pad "C" smd rect
			(at 1.1176 0)
			(size 1.016 1.27)
			(layers "F.Cu" "F.Mask" "F.Paste")
			(net "P12V_HSC_TEMP_R")
		)
		(pad "E" smd rect
			(at -1.1176 1.016)
			(size 1.016 1.27)
			(layers "F.Cu" "F.Mask" "F.Paste")
			(net "P12V_HSC_TEMP_E")
		)
	)
	(footprint ""
		(layer "F.Cu")
		(at 68.644008 -177.905156 90)
		(property "Reference" "PC2199"
			(at 0 0 90)
			(layer "F.SilkS")
			(hide yes)
			(effects
				(font
					(size 1.27 1.27)
				)
			)
		)
		(property "Value" ""
			(at 0 0 90)
			(layer "F.Fab")
			(effects
				(font
					(size 1.27 1.27)
				)
			)
		)
		(duplicate_pad_numbers_are_jumpers no)
		(fp_line
			(start 2.750058 0.999998)
			(end -2.750058 0.999998)
			(stroke
				(width 0.1524)
				(type default)
			)
			(layer "F.SilkS")
		)
		(fp_circle
			(center 0 0.999998)
			(end 0 3.750056)
			(stroke
				(width 0.1524)
				(type default)
			)
			(fill no)
			(layer "F.SilkS")
		)
		(fp_poly
			(pts
				(arc
					(start 2.750058 0.999998)
					(mid 0 3.750056)
					(end -2.750058 0.999998)
				)
			)
			(stroke
				(width 0)
				(type default)
			)
			(fill yes)
			(layer "F.SilkS")
		)
		(fp_circle
			(center 0 0.999998)
			(end 0 3.750056)
			(stroke
				(width 0.1)
				(type default)
			)
			(fill no)
			(layer "F.Fab")
		)
		(pad "1" thru_hole rect
			(at 0 0 90)
			(size 1.5748 1.5748)
			(drill 1.0668)
			(layers "*.Cu" "*.Mask")
			(remove_unused_layers no)
			(net "PVCCFA_EHV_CPU1")
			(clearance 0)
			(padstack
				(mode front_inner_back)
				(layer "Inner"
					(shape circle)
					(size 1.5748 1.5748)
					(clearance 0)
				)
				(layer "B.Cu"
					(shape rect)
					(size 1.5748 1.5748)
					(clearance 0)
				)
			)
		)
		(pad "2" thru_hole circle
			(at 0 1.999996 90)
			(size 1.5748 1.5748)
			(drill 1.0668)
			(layers "*.Cu" "*.Mask")
			(remove_unused_layers no)
			(net "GND")
			(clearance 0)
		)
	)
	(footprint ""
		(layer "F.Cu")
		(at 63.034164 -160.997392 180)
		(property "Reference" "PR4258"
			(at 0 0 180)
			(layer "F.SilkS")
			(hide yes)
			(effects
				(font
					(size 1.27 1.27)
				)
			)
		)
		(property "Value" ""
			(at 0 0 180)
			(layer "F.Fab")
			(effects
				(font
					(size 1.27 1.27)
				)
			)
		)
		(duplicate_pad_numbers_are_jumpers no)
		(fp_line
			(start 0.7874 0.4064)
			(end -0.7874 0.4064)
			(stroke
				(width 0.1524)
				(type default)
			)
			(layer "F.SilkS")
		)
		(fp_line
			(start 0.7874 -0.4064)
			(end 0.7874 0.4064)
			(stroke
				(width 0.1524)
				(type default)
			)
			(layer "F.SilkS")
		)
		(fp_line
			(start -0.7874 0.4064)
			(end -0.7874 -0.4064)
			(stroke
				(width 0.1524)
				(type default)
			)
			(layer "F.SilkS")
		)
		(fp_line
			(start -0.7874 -0.4064)
			(end 0.7874 -0.4064)
			(stroke
				(width 0.1524)
				(type default)
			)
			(layer "F.SilkS")
		)
		(fp_line
			(start 0.67945 0.3048)
			(end 0.120396 0.3048)
			(stroke
				(width 0.1)
				(type default)
			)
			(layer "F.Fab")
		)
		(fp_line
			(start 0.67945 -0.3048)
			(end 0.67945 0.3048)
			(stroke
				(width 0.1)
				(type default)
			)
			(layer "F.Fab")
		)
		(fp_line
			(start 0.12065 -0.2794)
			(end 0.12065 -0.3048)
			(stroke
				(width 0.1)
				(type default)
			)
			(layer "F.Fab")
		)
		(fp_line
			(start 0.12065 -0.3048)
			(end 0.67945 -0.3048)
			(stroke
				(width 0.1)
				(type default)
			)
			(layer "F.Fab")
		)
		(fp_line
			(start 0.120396 0.3048)
			(end 0.120396 0.2794)
			(stroke
				(width 0.1)
				(type default)
			)
			(layer "F.Fab")
		)
		(fp_line
			(start 0.120396 0.2794)
			(end -0.12065 0.2794)
			(stroke
				(width 0.1)
				(type default)
			)
			(layer "F.Fab")
		)
		(fp_line
			(start -0.12065 0.3048)
			(end -0.67945 0.3048)
			(stroke
				(width 0.1)
				(type default)
			)
			(layer "F.Fab")
		)
		(fp_line
			(start -0.12065 0.2794)
			(end -0.12065 0.3048)
			(stroke
				(width 0.1)
				(type default)
			)
			(layer "F.Fab")
		)
		(fp_line
			(start -0.12065 -0.2794)
			(end 0.12065 -0.2794)
			(stroke
				(width 0.1)
				(type default)
			)
			(layer "F.Fab")
		)
		(fp_line
			(start -0.12065 -0.305054)
			(end -0.12065 -0.2794)
			(stroke
				(width 0.1)
				(type default)
			)
			(layer "F.Fab")
		)
		(fp_line
			(start -0.67945 0.3048)
			(end -0.67945 -0.305054)
			(stroke
				(width 0.1)
				(type default)
			)
			(layer "F.Fab")
		)
		(fp_line
			(start -0.67945 -0.305054)
			(end -0.12065 -0.305054)
			(stroke
				(width 0.1)
				(type default)
			)
			(layer "F.Fab")
		)
		(pad "1" smd circle
			(at -0.40005 0 180)
			(size 0 0)
			(layers "F.Cu" "F.Mask" "F.Paste")
			(net "PVCCD_HV_CPU1")
		)
		(pad "2" smd circle
			(at 0.40005 0 180)
			(size 0 0)
			(layers "F.Cu" "F.Mask" "F.Paste")
			(net "GND")
		)
	)
	(footprint ""
		(layer "F.Cu")
		(at 106.7181 -411.582108 180)
		(property "Reference" "R4479"
			(at 0 0 180)
			(layer "F.SilkS")
			(hide yes)
			(effects
				(font
					(size 1.27 1.27)
				)
			)
		)
		(property "Value" ""
			(at 0 0 180)
			(layer "F.Fab")
			(effects
				(font
					(size 1.27 1.27)
				)
			)
		)
		(duplicate_pad_numbers_are_jumpers no)
		(fp_line
			(start 0.7874 0.4064)
			(end -0.7874 0.4064)
			(stroke
				(width 0.1524)
				(type default)
			)
			(layer "F.SilkS")
		)
		(fp_line
			(start 0.7874 -0.4064)
			(end 0.7874 0.4064)
			(stroke
				(width 0.1524)
				(type default)
			)
			(layer "F.SilkS")
		)
		(fp_line
			(start -0.7874 0.4064)
			(end -0.7874 -0.4064)
			(stroke
				(width 0.1524)
				(type default)
			)
			(layer "F.SilkS")
		)
		(fp_line
			(start -0.7874 -0.4064)
			(end 0.7874 -0.4064)
			(stroke
				(width 0.1524)
				(type default)
			)
			(layer "F.SilkS")
		)
		(fp_line
			(start 0.67945 0.3048)
			(end 0.120396 0.3048)
			(stroke
				(width 0.1)
				(type default)
			)
			(layer "F.Fab")
		)
		(fp_line
			(start 0.67945 -0.3048)
			(end 0.67945 0.3048)
			(stroke
				(width 0.1)
				(type default)
			)
			(layer "F.Fab")
		)
		(fp_line
			(start 0.12065 -0.2794)
			(end 0.12065 -0.3048)
			(stroke
				(width 0.1)
				(type default)
			)
			(layer "F.Fab")
		)
		(fp_line
			(start 0.12065 -0.3048)
			(end 0.67945 -0.3048)
			(stroke
				(width 0.1)
				(type default)
			)
			(layer "F.Fab")
		)
		(fp_line
			(start 0.120396 0.3048)
			(end 0.120396 0.2794)
			(stroke
				(width 0.1)
				(type default)
			)
			(layer "F.Fab")
		)
		(fp_line
			(start 0.120396 0.2794)
			(end -0.12065 0.2794)
			(stroke
				(width 0.1)
				(type default)
			)
			(layer "F.Fab")
		)
		(fp_line
			(start -0.12065 0.3048)
			(end -0.67945 0.3048)
			(stroke
				(width 0.1)
				(type default)
			)
			(layer "F.Fab")
		)
		(fp_line
			(start -0.12065 0.2794)
			(end -0.12065 0.3048)
			(stroke
				(width 0.1)
				(type default)
			)
			(layer "F.Fab")
		)
		(fp_line
			(start -0.12065 -0.2794)
			(end 0.12065 -0.2794)
			(stroke
				(width 0.1)
				(type default)
			)
			(layer "F.Fab")
		)
		(fp_line
			(start -0.12065 -0.305054)
			(end -0.12065 -0.2794)
			(stroke
				(width 0.1)
				(type default)
			)
			(layer "F.Fab")
		)
		(fp_line
			(start -0.67945 0.3048)
			(end -0.67945 -0.305054)
			(stroke
				(width 0.1)
				(type default)
			)
			(layer "F.Fab")
		)
		(fp_line
			(start -0.67945 -0.305054)
			(end -0.12065 -0.305054)
			(stroke
				(width 0.1)
				(type default)
			)
			(layer "F.Fab")
		)
		(pad "1" smd circle
			(at -0.40005 0 180)
			(size 0 0)
			(layers "F.Cu" "F.Mask" "F.Paste")
			(net "FM_9ZXL045_2_OE_N")
		)
		(pad "2" smd circle
			(at 0.40005 0 180)
			(size 0 0)
			(layers "F.Cu" "F.Mask" "F.Paste")
			(net "CLK_GPU_2_OE_N")
		)
	)
	(footprint ""
		(layer "F.Cu")
		(at 434.080158 -118.568216 90)
		(property "Reference" "R2403"
			(at 0 0 90)
			(layer "F.SilkS")
			(hide yes)
			(effects
				(font
					(size 1.27 1.27)
				)
			)
		)
		(property "Value" ""
			(at 0 0 90)
			(layer "F.Fab")
			(effects
				(font
					(size 1.27 1.27)
				)
			)
		)
		(duplicate_pad_numbers_are_jumpers no)
		(fp_line
			(start 0.7874 -0.4064)
			(end 0.7874 0.4064)
			(stroke
				(width 0.1524)
				(type default)
			)
			(layer "F.SilkS")
		)
		(fp_line
			(start -0.7874 -0.4064)
			(end 0.7874 -0.4064)
			(stroke
				(width 0.1524)
				(type default)
			)
			(layer "F.SilkS")
		)
		(fp_line
			(start 0.7874 0.4064)
			(end -0.7874 0.4064)
			(stroke
				(width 0.1524)
				(type default)
			)
			(layer "F.SilkS")
		)
		(fp_line
			(start -0.7874 0.4064)
			(end -0.7874 -0.4064)
			(stroke
				(width 0.1524)
				(type default)
			)
			(layer "F.SilkS")
		)
		(fp_line
			(start -0.12065 -0.305054)
			(end -0.12065 -0.2794)
			(stroke
				(width 0.1)
				(type default)
			)
			(layer "F.Fab")
		)
		(fp_line
			(start -0.67945 -0.305054)
			(end -0.12065 -0.305054)
			(stroke
				(width 0.1)
				(type default)
			)
			(layer "F.Fab")
		)
		(fp_line
			(start 0.67945 -0.3048)
			(end 0.67945 0.3048)
			(stroke
				(width 0.1)
				(type default)
			)
			(layer "F.Fab")
		)
		(fp_line
			(start 0.12065 -0.3048)
			(end 0.67945 -0.3048)
			(stroke
				(width 0.1)
				(type default)
			)
			(layer "F.Fab")
		)
		(fp_line
			(start 0.12065 -0.2794)
			(end 0.12065 -0.3048)
			(stroke
				(width 0.1)
				(type default)
			)
			(layer "F.Fab")
		)
		(fp_line
			(start -0.12065 -0.2794)
			(end 0.12065 -0.2794)
			(stroke
				(width 0.1)
				(type default)
			)
			(layer "F.Fab")
		)
		(fp_line
			(start 0.120396 0.2794)
			(end -0.12065 0.2794)
			(stroke
				(width 0.1)
				(type default)
			)
			(layer "F.Fab")
		)
		(fp_line
			(start -0.12065 0.2794)
			(end -0.12065 0.3048)
			(stroke
				(width 0.1)
				(type default)
			)
			(layer "F.Fab")
		)
		(fp_line
			(start 0.67945 0.3048)
			(end 0.120396 0.3048)
			(stroke
				(width 0.1)
				(type default)
			)
			(layer "F.Fab")
		)
		(fp_line
			(start 0.120396 0.3048)
			(end 0.120396 0.2794)
			(stroke
				(width 0.1)
				(type default)
			)
			(layer "F.Fab")
		)
		(fp_line
			(start -0.12065 0.3048)
			(end -0.67945 0.3048)
			(stroke
				(width 0.1)
				(type default)
			)
			(layer "F.Fab")
		)
		(fp_line
			(start -0.67945 0.3048)
			(end -0.67945 -0.305054)
			(stroke
				(width 0.1)
				(type default)
			)
			(layer "F.Fab")
		)
		(pad "1" smd circle
			(at -0.40005 0 90)
			(size 0 0)
			(layers "F.Cu" "F.Mask" "F.Paste")
			(net "SMB_VR_3V3AUX_SDA_R2")
		)
		(pad "2" smd circle
			(at 0.40005 0 90)
			(size 0 0)
			(layers "F.Cu" "F.Mask" "F.Paste")
			(net "SMB_DIO_PVCCD_HV_CPU0")
		)
	)
	(footprint ""
		(layer "F.Cu")
		(at 379.78461 -408.517344 -90)
		(property "Reference" "C875"
			(at 0 0 270)
			(layer "F.SilkS")
			(hide yes)
			(effects
				(font
					(size 1.27 1.27)
				)
			)
		)
		(property "Value" ""
			(at 0 0 270)
			(layer "F.Fab")
			(effects
				(font
					(size 1.27 1.27)
				)
			)
		)
		(duplicate_pad_numbers_are_jumpers no)
		(fp_line
			(start -0.299974 0.150114)
			(end -0.299974 -0.150114)
			(stroke
				(width 0.1)
				(type default)
			)
			(layer "F.Fab")
		)
		(fp_line
			(start 0.299974 0.150114)
			(end -0.299974 0.150114)
			(stroke
				(width 0.1)
				(type default)
			)
			(layer "F.Fab")
		)
		(fp_line
			(start -0.299974 -0.150114)
			(end 0.299974 -0.150114)
			(stroke
				(width 0.1)
				(type default)
			)
			(layer "F.Fab")
		)
		(fp_line
			(start 0.299974 -0.150114)
			(end 0.299974 0.150114)
			(stroke
				(width 0.1)
				(type default)
			)
			(layer "F.Fab")
		)
		(pad "1" smd rect
			(at -0.2667 0 270)
			(size 0.3048 0.381)
			(layers "F.Cu" "F.Mask" "F.Paste")
			(net "P5E_CPU0_PE3_TX_C_DP<13>")
		)
		(pad "2" smd rect
			(at 0.2667 0 270)
			(size 0.3048 0.381)
			(layers "F.Cu" "F.Mask" "F.Paste")
			(net "P5E_CPU0_PE3_TX_DP<13>")
		)
	)
	(footprint ""
		(layer "F.Cu")
		(at 167.424354 -408.517344 -90)
		(property "Reference" "C1547"
			(at 0 0 270)
			(layer "F.SilkS")
			(hide yes)
			(effects
				(font
					(size 1.27 1.27)
				)
			)
		)
		(property "Value" ""
			(at 0 0 270)
			(layer "F.Fab")
			(effects
				(font
					(size 1.27 1.27)
				)
			)
		)
		(duplicate_pad_numbers_are_jumpers no)
		(fp_line
			(start -0.299974 0.150114)
			(end -0.299974 -0.150114)
			(stroke
				(width 0.1)
				(type default)
			)
			(layer "F.Fab")
		)
		(fp_line
			(start 0.299974 0.150114)
			(end -0.299974 0.150114)
			(stroke
				(width 0.1)
				(type default)
			)
			(layer "F.Fab")
		)
		(fp_line
			(start -0.299974 -0.150114)
			(end 0.299974 -0.150114)
			(stroke
				(width 0.1)
				(type default)
			)
			(layer "F.Fab")
		)
		(fp_line
			(start 0.299974 -0.150114)
			(end 0.299974 0.150114)
			(stroke
				(width 0.1)
				(type default)
			)
			(layer "F.Fab")
		)
		(pad "1" smd rect
			(at -0.2667 0 270)
			(size 0.3048 0.381)
			(layers "F.Cu" "F.Mask" "F.Paste")
			(net "P5E_CPU1_PE3_TX_C_DP<0>")
		)
		(pad "2" smd rect
			(at 0.2667 0 270)
			(size 0.3048 0.381)
			(layers "F.Cu" "F.Mask" "F.Paste")
			(net "P5E_CPU1_PE3_TX_DP<0>")
		)
	)
	(footprint ""
		(layer "F.Cu")
		(at 164.64788 -120.106948 180)
		(property "Reference" "R3176"
			(at 0 0 180)
			(layer "F.SilkS")
			(hide yes)
			(effects
				(font
					(size 1.27 1.27)
				)
			)
		)
		(property "Value" ""
			(at 0 0 180)
			(layer "F.Fab")
			(effects
				(font
					(size 1.27 1.27)
				)
			)
		)
		(duplicate_pad_numbers_are_jumpers no)
		(fp_line
			(start 0.7874 0.4064)
			(end -0.7874 0.4064)
			(stroke
				(width 0.1524)
				(type default)
			)
			(layer "F.SilkS")
		)
		(fp_line
			(start 0.7874 -0.4064)
			(end 0.7874 0.4064)
			(stroke
				(width 0.1524)
				(type default)
			)
			(layer "F.SilkS")
		)
		(fp_line
			(start -0.7874 0.4064)
			(end -0.7874 -0.4064)
			(stroke
				(width 0.1524)
				(type default)
			)
			(layer "F.SilkS")
		)
		(fp_line
			(start -0.7874 -0.4064)
			(end 0.7874 -0.4064)
			(stroke
				(width 0.1524)
				(type default)
			)
			(layer "F.SilkS")
		)
		(fp_line
			(start 0.67945 0.3048)
			(end 0.120396 0.3048)
			(stroke
				(width 0.1)
				(type default)
			)
			(layer "F.Fab")
		)
		(fp_line
			(start 0.67945 -0.3048)
			(end 0.67945 0.3048)
			(stroke
				(width 0.1)
				(type default)
			)
			(layer "F.Fab")
		)
		(fp_line
			(start 0.12065 -0.2794)
			(end 0.12065 -0.3048)
			(stroke
				(width 0.1)
				(type default)
			)
			(layer "F.Fab")
		)
		(fp_line
			(start 0.12065 -0.3048)
			(end 0.67945 -0.3048)
			(stroke
				(width 0.1)
				(type default)
			)
			(layer "F.Fab")
		)
		(fp_line
			(start 0.120396 0.3048)
			(end 0.120396 0.2794)
			(stroke
				(width 0.1)
				(type default)
			)
			(layer "F.Fab")
		)
		(fp_line
			(start 0.120396 0.2794)
			(end -0.12065 0.2794)
			(stroke
				(width 0.1)
				(type default)
			)
			(layer "F.Fab")
		)
		(fp_line
			(start -0.12065 0.3048)
			(end -0.67945 0.3048)
			(stroke
				(width 0.1)
				(type default)
			)
			(layer "F.Fab")
		)
		(fp_line
			(start -0.12065 0.2794)
			(end -0.12065 0.3048)
			(stroke
				(width 0.1)
				(type default)
			)
			(layer "F.Fab")
		)
		(fp_line
			(start -0.12065 -0.2794)
			(end 0.12065 -0.2794)
			(stroke
				(width 0.1)
				(type default)
			)
			(layer "F.Fab")
		)
		(fp_line
			(start -0.12065 -0.305054)
			(end -0.12065 -0.2794)
			(stroke
				(width 0.1)
				(type default)
			)
			(layer "F.Fab")
		)
		(fp_line
			(start -0.67945 0.3048)
			(end -0.67945 -0.305054)
			(stroke
				(width 0.1)
				(type default)
			)
			(layer "F.Fab")
		)
		(fp_line
			(start -0.67945 -0.305054)
			(end -0.12065 -0.305054)
			(stroke
				(width 0.1)
				(type default)
			)
			(layer "F.Fab")
		)
		(pad "1" smd circle
			(at -0.40005 0 180)
			(size 0 0)
			(layers "F.Cu" "F.Mask" "F.Paste")
			(net "SGPIO_OCP_V3_2_CLK")
		)
		(pad "2" smd circle
			(at 0.40005 0 180)
			(size 0 0)
			(layers "F.Cu" "F.Mask" "F.Paste")
			(net "P3V3_OCP_V3_2")
		)
	)
	(footprint ""
		(layer "F.Cu")
		(at 362.646468 -360.83875)
		(property "Reference" "PC330"
			(at 0 0 0)
			(layer "F.SilkS")
			(hide yes)
			(effects
				(font
					(size 1.27 1.27)
				)
			)
		)
		(property "Value" ""
			(at 0 0 0)
			(layer "F.Fab")
			(effects
				(font
					(size 1.27 1.27)
				)
			)
		)
		(duplicate_pad_numbers_are_jumpers no)
		(fp_line
			(start -0.7874 -0.4064)
			(end 0.7874 -0.4064)
			(stroke
				(width 0.1524)
				(type default)
			)
			(layer "F.SilkS")
		)
		(fp_line
			(start -0.7874 0.4064)
			(end -0.7874 -0.4064)
			(stroke
				(width 0.1524)
				(type default)
			)
			(layer "F.SilkS")
		)
		(fp_line
			(start 0.7874 -0.4064)
			(end 0.7874 0.4064)
			(stroke
				(width 0.1524)
				(type default)
			)
			(layer "F.SilkS")
		)
		(fp_line
			(start 0.7874 0.4064)
			(end -0.7874 0.4064)
			(stroke
				(width 0.1524)
				(type default)
			)
			(layer "F.SilkS")
		)
		(fp_line
			(start -0.67945 -0.305054)
			(end -0.12065 -0.305054)
			(stroke
				(width 0.1)
				(type default)
			)
			(layer "F.Fab")
		)
		(fp_line
			(start -0.67945 0.3048)
			(end -0.67945 -0.305054)
			(stroke
				(width 0.1)
				(type default)
			)
			(layer "F.Fab")
		)
		(fp_line
			(start -0.12065 -0.305054)
			(end -0.12065 -0.2794)
			(stroke
				(width 0.1)
				(type default)
			)
			(layer "F.Fab")
		)
		(fp_line
			(start -0.12065 -0.2794)
			(end 0.12065 -0.2794)
			(stroke
				(width 0.1)
				(type default)
			)
			(layer "F.Fab")
		)
		(fp_line
			(start -0.12065 0.2794)
			(end -0.12065 0.3048)
			(stroke
				(width 0.1)
				(type default)
			)
			(layer "F.Fab")
		)
		(fp_line
			(start -0.12065 0.3048)
			(end -0.67945 0.3048)
			(stroke
				(width 0.1)
				(type default)
			)
			(layer "F.Fab")
		)
		(fp_line
			(start 0.120396 0.2794)
			(end -0.12065 0.2794)
			(stroke
				(width 0.1)
				(type default)
			)
			(layer "F.Fab")
		)
		(fp_line
			(start 0.120396 0.3048)
			(end 0.120396 0.2794)
			(stroke
				(width 0.1)
				(type default)
			)
			(layer "F.Fab")
		)
		(fp_line
			(start 0.12065 -0.3048)
			(end 0.67945 -0.3048)
			(stroke
				(width 0.1)
				(type default)
			)
			(layer "F.Fab")
		)
		(fp_line
			(start 0.12065 -0.2794)
			(end 0.12065 -0.3048)
			(stroke
				(width 0.1)
				(type default)
			)
			(layer "F.Fab")
		)
		(fp_line
			(start 0.67945 -0.3048)
			(end 0.67945 0.3048)
			(stroke
				(width 0.1)
				(type default)
			)
			(layer "F.Fab")
		)
		(fp_line
			(start 0.67945 0.3048)
			(end 0.120396 0.3048)
			(stroke
				(width 0.1)
				(type default)
			)
			(layer "F.Fab")
		)
		(pad "1" smd circle
			(at -0.40005 0)
			(size 0 0)
			(layers "F.Cu" "F.Mask" "F.Paste")
			(net "PVCCIN_CPU0_VIN_CSNIN")
		)
		(pad "2" smd circle
			(at 0.40005 0)
			(size 0 0)
			(layers "F.Cu" "F.Mask" "F.Paste")
			(net "GND")
		)
	)
	(footprint ""
		(layer "F.Cu")
		(at 56.282844 -358.11841)
		(property "Reference" "PC725_P1_2"
			(at 0 0 0)
			(layer "F.SilkS")
			(hide yes)
			(effects
				(font
					(size 1.27 1.27)
				)
			)
		)
		(property "Value" ""
			(at 0 0 0)
			(layer "F.Fab")
			(effects
				(font
					(size 1.27 1.27)
				)
			)
		)
		(duplicate_pad_numbers_are_jumpers no)
		(fp_line
			(start -1.524 -0.762)
			(end 1.524 -0.762)
			(stroke
				(width 0.1524)
				(type default)
			)
			(layer "F.SilkS")
		)
		(fp_line
			(start -1.524 0.762)
			(end -1.524 -0.762)
			(stroke
				(width 0.1524)
				(type default)
			)
			(layer "F.SilkS")
		)
		(fp_line
			(start 1.524 -0.762)
			(end 1.524 0.762)
			(stroke
				(width 0.1524)
				(type default)
			)
			(layer "F.SilkS")
		)
		(fp_line
			(start 1.524 0.762)
			(end -1.524 0.762)
			(stroke
				(width 0.1524)
				(type default)
			)
			(layer "F.SilkS")
		)
		(fp_line
			(start -1.1049 -0.724916)
			(end -1.1049 0.724916)
			(stroke
				(width 0.1)
				(type default)
			)
			(layer "F.Fab")
		)
		(fp_line
			(start -1.1049 0.724916)
			(end 1.1049 0.724916)
			(stroke
				(width 0.1)
				(type default)
			)
			(layer "F.Fab")
		)
		(fp_line
			(start 1.1049 -0.724916)
			(end -1.1049 -0.724916)
			(stroke
				(width 0.1)
				(type default)
			)
			(layer "F.Fab")
		)
		(fp_line
			(start 1.1049 0.724916)
			(end 1.1049 -0.724916)
			(stroke
				(width 0.1)
				(type default)
			)
			(layer "F.Fab")
		)
		(pad "1" smd rect
			(at -0.889 0 180)
			(size 1.016 1.27)
			(layers "F.Cu" "F.Mask" "F.Paste")
			(net "SW_P12V_PVCCFA_EHV_FIVRA_CPU1_L")
		)
		(pad "2" smd rect
			(at 0.889 0 180)
			(size 1.016 1.27)
			(layers "F.Cu" "F.Mask" "F.Paste")
			(net "GND")
		)
	)
	(footprint ""
		(layer "F.Cu")
		(at 24.67356 -71.821548)
		(property "Reference" "U59"
			(at -1.4732 -1.768348 0)
			(unlocked yes)
			(layer "F.SilkS")
			(effects
				(font
					(size 0.7874 0.5842)
					(thickness 0.1524)
				)
				(justify left)
			)
		)
		(property "Value" ""
			(at 0 0 0)
			(layer "F.Fab")
			(effects
				(font
					(size 1.27 1.27)
				)
			)
		)
		(duplicate_pad_numbers_are_jumpers no)
		(fp_line
			(start -1.38176 -1.100074)
			(end -1.38176 1.100074)
			(stroke
				(width 0.1524)
				(type default)
			)
			(layer "F.SilkS")
		)
		(fp_line
			(start -1.38176 1.100074)
			(end 1.38176 1.100074)
			(stroke
				(width 0.1524)
				(type default)
			)
			(layer "F.SilkS")
		)
		(fp_line
			(start -0.592074 -1.100074)
			(end -1.38176 -1.100074)
			(stroke
				(width 0.1524)
				(type default)
			)
			(layer "F.SilkS")
		)
		(fp_line
			(start 0 -0.508)
			(end -0.592074 -1.100074)
			(stroke
				(width 0.1524)
				(type default)
			)
			(layer "F.SilkS")
		)
		(fp_line
			(start 0.592074 -1.100074)
			(end 0 -0.508)
			(stroke
				(width 0.1524)
				(type default)
			)
			(layer "F.SilkS")
		)
		(fp_line
			(start 1.38176 -1.100074)
			(end 0.592074 -1.100074)
			(stroke
				(width 0.1524)
				(type default)
			)
			(layer "F.SilkS")
		)
		(fp_line
			(start 1.38176 1.100074)
			(end 1.38176 -1.100074)
			(stroke
				(width 0.1524)
				(type default)
			)
			(layer "F.SilkS")
		)
		(fp_poly
			(pts
				(xy -1.60909 -0.649986) (xy -2.04978 -0.429768) (xy -2.04978 -0.870204)
			)
			(stroke
				(width 0)
				(type default)
			)
			(fill yes)
			(layer "F.SilkS")
		)
		(fp_line
			(start -0.674878 -1.100074)
			(end -0.674878 1.100074)
			(stroke
				(width 0.1)
				(type default)
			)
			(layer "F.Fab")
		)
		(fp_line
			(start -0.674878 1.100074)
			(end 0.674878 1.100074)
			(stroke
				(width 0.1)
				(type default)
			)
			(layer "F.Fab")
		)
		(fp_line
			(start 0.674878 -1.100074)
			(end -0.674878 -1.100074)
			(stroke
				(width 0.1)
				(type default)
			)
			(layer "F.Fab")
		)
		(fp_line
			(start 0.674878 1.100074)
			(end 0.674878 -1.100074)
			(stroke
				(width 0.1)
				(type default)
			)
			(layer "F.Fab")
		)
		(fp_poly
			(pts
				(xy -1.9431 -0.870204) (xy -1.50241 -0.649986) (xy -1.9431 -0.429768)
			)
			(stroke
				(width 0)
				(type default)
			)
			(fill yes)
			(layer "F.Fab")
		)
		(pad "1" smd rect
			(at -0.94996 -0.649986 270)
			(size 0.4318 0.6096)
			(layers "F.Cu" "F.Mask" "F.Paste")
			(net "OCP_V3_2_PRSNT2_R_N")
		)
		(pad "2" smd rect
			(at -0.94996 0 270)
			(size 0.4318 0.6096)
			(layers "F.Cu" "F.Mask" "F.Paste")
			(net "GND")
		)
		(pad "3" smd rect
			(at -0.94996 0.649986 270)
			(size 0.4318 0.6096)
			(layers "F.Cu" "F.Mask" "F.Paste")
			(net "OCP_V3_2_PRSNT3_R_N")
		)
		(pad "4" smd rect
			(at 0.94996 0.649986 270)
			(size 0.4318 0.6096)
			(layers "F.Cu" "F.Mask" "F.Paste")
			(net "HP_LVC3_OCP_V3_2_PRSNT2_N_R")
		)
		(pad "5" smd rect
			(at 0.94996 0 270)
			(size 0.4318 0.6096)
			(layers "F.Cu" "F.Mask" "F.Paste")
			(net "P3V3_AUX")
		)
		(pad "6" smd rect
			(at 0.94996 -0.649986 270)
			(size 0.4318 0.6096)
			(layers "F.Cu" "F.Mask" "F.Paste")
			(net "HP_LVC3_OCP_V3_2_PRSNT2_N_R")
		)
	)
	(footprint ""
		(layer "F.Cu")
		(at 380.899924 -22.29993)
		(property "Reference" "H105"
			(at -6.516624 -4.37896 0)
			(unlocked yes)
			(layer "F.SilkS")
			(effects
				(font
					(size 0.7874 0.5842)
					(thickness 0.1524)
				)
				(justify left)
			)
		)
		(property "Value" ""
			(at 0 0 0)
			(layer "F.Fab")
			(effects
				(font
					(size 1.27 1.27)
				)
			)
		)
		(duplicate_pad_numbers_are_jumpers no)
		(pad "1" thru_hole circle
			(at 0 0)
			(size 10.0076 10.0076)
			(drill 5.6134)
			(layers "*.Cu" "*.Mask")
			(remove_unused_layers no)
			(net "GND")
			(clearance -1.9431)
		)
	)
	(footprint ""
		(layer "F.Cu")
		(at 121.59488 -92.674948 90)
		(property "Reference" "R237"
			(at 0 0 90)
			(layer "F.SilkS")
			(hide yes)
			(effects
				(font
					(size 1.27 1.27)
				)
			)
		)
		(property "Value" ""
			(at 0 0 90)
			(layer "F.Fab")
			(effects
				(font
					(size 1.27 1.27)
				)
			)
		)
		(duplicate_pad_numbers_are_jumpers no)
		(fp_line
			(start 0.7874 -0.4064)
			(end 0.7874 0.4064)
			(stroke
				(width 0.1524)
				(type default)
			)
			(layer "F.SilkS")
		)
		(fp_line
			(start -0.7874 -0.4064)
			(end 0.7874 -0.4064)
			(stroke
				(width 0.1524)
				(type default)
			)
			(layer "F.SilkS")
		)
		(fp_line
			(start 0.7874 0.4064)
			(end -0.7874 0.4064)
			(stroke
				(width 0.1524)
				(type default)
			)
			(layer "F.SilkS")
		)
		(fp_line
			(start -0.7874 0.4064)
			(end -0.7874 -0.4064)
			(stroke
				(width 0.1524)
				(type default)
			)
			(layer "F.SilkS")
		)
		(fp_line
			(start -0.12065 -0.305054)
			(end -0.12065 -0.2794)
			(stroke
				(width 0.1)
				(type default)
			)
			(layer "F.Fab")
		)
		(fp_line
			(start -0.67945 -0.305054)
			(end -0.12065 -0.305054)
			(stroke
				(width 0.1)
				(type default)
			)
			(layer "F.Fab")
		)
		(fp_line
			(start 0.67945 -0.3048)
			(end 0.67945 0.3048)
			(stroke
				(width 0.1)
				(type default)
			)
			(layer "F.Fab")
		)
		(fp_line
			(start 0.12065 -0.3048)
			(end 0.67945 -0.3048)
			(stroke
				(width 0.1)
				(type default)
			)
			(layer "F.Fab")
		)
		(fp_line
			(start 0.12065 -0.2794)
			(end 0.12065 -0.3048)
			(stroke
				(width 0.1)
				(type default)
			)
			(layer "F.Fab")
		)
		(fp_line
			(start -0.12065 -0.2794)
			(end 0.12065 -0.2794)
			(stroke
				(width 0.1)
				(type default)
			)
			(layer "F.Fab")
		)
		(fp_line
			(start 0.120396 0.2794)
			(end -0.12065 0.2794)
			(stroke
				(width 0.1)
				(type default)
			)
			(layer "F.Fab")
		)
		(fp_line
			(start -0.12065 0.2794)
			(end -0.12065 0.3048)
			(stroke
				(width 0.1)
				(type default)
			)
			(layer "F.Fab")
		)
		(fp_line
			(start 0.67945 0.3048)
			(end 0.120396 0.3048)
			(stroke
				(width 0.1)
				(type default)
			)
			(layer "F.Fab")
		)
		(fp_line
			(start 0.120396 0.3048)
			(end 0.120396 0.2794)
			(stroke
				(width 0.1)
				(type default)
			)
			(layer "F.Fab")
		)
		(fp_line
			(start -0.12065 0.3048)
			(end -0.67945 0.3048)
			(stroke
				(width 0.1)
				(type default)
			)
			(layer "F.Fab")
		)
		(fp_line
			(start -0.67945 0.3048)
			(end -0.67945 -0.305054)
			(stroke
				(width 0.1)
				(type default)
			)
			(layer "F.Fab")
		)
		(pad "1" smd circle
			(at -0.40005 0 90)
			(size 0 0)
			(layers "F.Cu" "F.Mask" "F.Paste")
			(net "H_CPU0_THERMTRIP_LVC1_R_N")
		)
		(pad "2" smd circle
			(at 0.40005 0 90)
			(size 0 0)
			(layers "F.Cu" "F.Mask" "F.Paste")
			(net "H_CPU0_THERMTRIP_VT_R_N")
		)
	)
	(footprint ""
		(layer "F.Cu")
		(at 381.750062 -440.489848)
		(property "Reference" "J106"
			(at -7.488682 21.48459 0)
			(unlocked yes)
			(layer "F.SilkS")
			(effects
				(font
					(size 0.7874 0.5842)
					(thickness 0.1524)
				)
				(justify left)
			)
		)
		(property "Value" ""
			(at 0 0 0)
			(layer "F.Fab")
			(effects
				(font
					(size 1.27 1.27)
				)
			)
		)
		(duplicate_pad_numbers_are_jumpers no)
		(fp_line
			(start -4.249928 -11.999976)
			(end 18.64995 -11.999976)
			(stroke
				(width 0.1524)
				(type default)
			)
			(layer "F.SilkS")
		)
		(fp_line
			(start -4.249928 22.400006)
			(end -4.249928 -11.999976)
			(stroke
				(width 0.1524)
				(type default)
			)
			(layer "F.SilkS")
		)
		(fp_line
			(start -1.249934 -8.999982)
			(end -1.249934 19.400012)
			(stroke
				(width 0.1524)
				(type default)
			)
			(layer "F.SilkS")
		)
		(fp_line
			(start -1.249934 -1.500124)
			(end 15.649956 -1.500124)
			(stroke
				(width 0.1524)
				(type default)
			)
			(layer "F.SilkS")
		)
		(fp_line
			(start -1.249934 19.400012)
			(end 15.649956 19.400012)
			(stroke
				(width 0.1524)
				(type default)
			)
			(layer "F.SilkS")
		)
		(fp_line
			(start 0.0254 -0.9144)
			(end 1.0414 -0.9144)
			(stroke
				(width 0.1524)
				(type default)
			)
			(layer "F.SilkS")
		)
		(fp_line
			(start 0.5334 -1.4224)
			(end 0.0254 -0.9144)
			(stroke
				(width 0.1524)
				(type default)
			)
			(layer "F.SilkS")
		)
		(fp_line
			(start 0.5334 -1.4224)
			(end 0.5334 -0.5588)
			(stroke
				(width 0.1524)
				(type default)
			)
			(layer "F.SilkS")
		)
		(fp_line
			(start 0.5334 -0.5588)
			(end 1.8034 -0.5588)
			(stroke
				(width 0.1524)
				(type default)
			)
			(layer "F.SilkS")
		)
		(fp_line
			(start 1.0414 -0.9144)
			(end 0.5334 -1.4224)
			(stroke
				(width 0.1524)
				(type default)
			)
			(layer "F.SilkS")
		)
		(fp_line
			(start 1.8034 -0.5588)
			(end 2.032 -0.7874)
			(stroke
				(width 0.1524)
				(type default)
			)
			(layer "F.SilkS")
		)
		(fp_line
			(start 15.649956 -8.999982)
			(end -1.249934 -8.999982)
			(stroke
				(width 0.1524)
				(type default)
			)
			(layer "F.SilkS")
		)
		(fp_line
			(start 15.649956 19.400012)
			(end 15.649956 -8.999982)
			(stroke
				(width 0.1524)
				(type default)
			)
			(layer "F.SilkS")
		)
		(fp_line
			(start 18.64995 -11.999976)
			(end 18.64995 -2.178812)
			(stroke
				(width 0.1524)
				(type default)
			)
			(layer "F.SilkS")
		)
		(fp_line
			(start 18.64995 17.206468)
			(end 18.64995 22.400006)
			(stroke
				(width 0.1524)
				(type default)
			)
			(layer "F.SilkS")
		)
		(fp_line
			(start 18.64995 22.400006)
			(end -4.249928 22.400006)
			(stroke
				(width 0.1524)
				(type default)
			)
			(layer "F.SilkS")
		)
		(fp_poly
			(pts
				(xy -2.670048 -0.508) (xy -1.654048 0) (xy -2.670048 0.508)
			)
			(stroke
				(width 0)
				(type default)
			)
			(fill yes)
			(layer "F.SilkS")
		)
		(fp_line
			(start -4.249928 -11.999976)
			(end 18.64995 -11.999976)
			(stroke
				(width 0.1524)
				(type default)
			)
			(layer "B.SilkS")
		)
		(fp_line
			(start -4.249928 -0.75438)
			(end -4.249928 -11.999976)
			(stroke
				(width 0.1524)
				(type default)
			)
			(layer "B.SilkS")
		)
		(fp_line
			(start -4.249928 8.88746)
			(end -4.249928 1.38684)
			(stroke
				(width 0.1524)
				(type default)
			)
			(layer "B.SilkS")
		)
		(fp_line
			(start -4.249928 22.400006)
			(end -4.249928 12.6746)
			(stroke
				(width 0.1524)
				(type default)
			)
			(layer "B.SilkS")
		)
		(fp_line
			(start 18.64995 -11.999976)
			(end 18.64995 -0.664972)
			(stroke
				(width 0.1524)
				(type default)
			)
			(layer "B.SilkS")
		)
		(fp_line
			(start 18.64995 17.859248)
			(end 18.64995 22.400006)
			(stroke
				(width 0.1524)
				(type default)
			)
			(layer "B.SilkS")
		)
		(fp_line
			(start 18.64995 22.400006)
			(end -4.249928 22.400006)
			(stroke
				(width 0.1524)
				(type default)
			)
			(layer "B.SilkS")
		)
		(fp_line
			(start -4.249928 -11.999976)
			(end 18.64995 -11.999976)
			(stroke
				(width 0.1)
				(type default)
			)
			(layer "B.Fab")
		)
		(fp_line
			(start -4.249928 22.400006)
			(end -4.249928 -11.999976)
			(stroke
				(width 0.1)
				(type default)
			)
			(layer "B.Fab")
		)
		(fp_line
			(start 18.64995 -11.999976)
			(end 18.64995 22.400006)
			(stroke
				(width 0.1)
				(type default)
			)
			(layer "B.Fab")
		)
		(fp_line
			(start 18.64995 22.400006)
			(end -4.249928 22.400006)
			(stroke
				(width 0.1)
				(type default)
			)
			(layer "B.Fab")
		)
		(fp_line
			(start -1.249934 -8.999982)
			(end -1.249934 19.400012)
			(stroke
				(width 0.1)
				(type default)
			)
			(layer "F.Fab")
		)
		(fp_line
			(start -1.249934 19.400012)
			(end 15.649956 19.400012)
			(stroke
				(width 0.1)
				(type default)
			)
			(layer "F.Fab")
		)
		(fp_line
			(start 15.649956 -8.999982)
			(end -1.249934 -8.999982)
			(stroke
				(width 0.1)
				(type default)
			)
			(layer "F.Fab")
		)
		(fp_line
			(start 15.649956 19.400012)
			(end 15.649956 -8.999982)
			(stroke
				(width 0.1)
				(type default)
			)
			(layer "F.Fab")
		)
		(fp_poly
			(pts
				(xy -2.670048 -0.508) (xy -2.670048 0.508) (xy -1.654048 0)
			)
			(stroke
				(width 0)
				(type default)
			)
			(fill yes)
			(layer "F.Fab")
		)
		(fp_text user "PRESS-FIT"
			(at -4.313682 24.15667 0)
			(unlocked yes)
			(layer "F.SilkS")
			(effects
				(font
					(size 1.905 1.4224)
					(thickness 0.1524)
				)
				(justify left)
			)
		)
		(fp_text user "B"
			(at -1.937512 1.343406 0)
			(unlocked yes)
			(layer "F.SilkS")
			(effects
				(font
					(size 0.7874 0.5842)
					(thickness 0.1524)
				)
			)
		)
		(fp_text user "C"
			(at -1.937512 2.543556 0)
			(unlocked yes)
			(layer "F.SilkS")
			(effects
				(font
					(size 0.7874 0.5842)
					(thickness 0.1524)
				)
			)
		)
		(fp_text user "D"
			(at -1.937512 3.743452 0)
			(unlocked yes)
			(layer "F.SilkS")
			(effects
				(font
					(size 0.7874 0.5842)
					(thickness 0.1524)
				)
			)
		)
		(fp_text user "E"
			(at -1.937512 4.943602 0)
			(unlocked yes)
			(layer "F.SilkS")
			(effects
				(font
					(size 0.7874 0.5842)
					(thickness 0.1524)
				)
			)
		)
		(fp_text user "F"
			(at -1.937512 6.143498 0)
			(unlocked yes)
			(layer "F.SilkS")
			(effects
				(font
					(size 0.7874 0.5842)
					(thickness 0.1524)
				)
			)
		)
		(fp_text user "G"
			(at -1.937512 7.343394 0)
			(unlocked yes)
			(layer "F.SilkS")
			(effects
				(font
					(size 0.7874 0.5842)
					(thickness 0.1524)
				)
			)
		)
		(fp_text user "H"
			(at -1.937512 8.543544 0)
			(unlocked yes)
			(layer "F.SilkS")
			(effects
				(font
					(size 0.7874 0.5842)
					(thickness 0.1524)
				)
			)
		)
		(fp_text user "I"
			(at -1.937512 9.74344 0)
			(unlocked yes)
			(layer "F.SilkS")
			(effects
				(font
					(size 0.7874 0.5842)
					(thickness 0.1524)
				)
			)
		)
		(fp_text user "J"
			(at -1.937512 10.94359 0)
			(unlocked yes)
			(layer "F.SilkS")
			(effects
				(font
					(size 0.7874 0.5842)
					(thickness 0.1524)
				)
			)
		)
		(fp_text user "K"
			(at -1.937512 12.143486 0)
			(unlocked yes)
			(layer "F.SilkS")
			(effects
				(font
					(size 0.7874 0.5842)
					(thickness 0.1524)
				)
			)
		)
		(fp_text user "L"
			(at -1.937512 13.343636 0)
			(unlocked yes)
			(layer "F.SilkS")
			(effects
				(font
					(size 0.7874 0.5842)
					(thickness 0.1524)
				)
			)
		)
		(fp_text user "M"
			(at -1.937512 14.543532 0)
			(unlocked yes)
			(layer "F.SilkS")
			(effects
				(font
					(size 0.7874 0.5842)
					(thickness 0.1524)
				)
			)
		)
		(fp_text user "N"
			(at -1.937512 15.743428 0)
			(unlocked yes)
			(layer "F.SilkS")
			(effects
				(font
					(size 0.7874 0.5842)
					(thickness 0.1524)
				)
			)
		)
		(fp_text user "1"
			(at 0.082042 20.10029 0)
			(unlocked yes)
			(layer "F.SilkS")
			(effects
				(font
					(size 0.7874 0.5842)
					(thickness 0.1524)
				)
			)
		)
		(fp_text user "2"
			(at 2.082038 20.10029 0)
			(unlocked yes)
			(layer "F.SilkS")
			(effects
				(font
					(size 0.7874 0.5842)
					(thickness 0.1524)
				)
			)
		)
		(fp_text user "EDGE OF DAUGHTER CARD"
			(at 2.2479 -0.899668 0)
			(unlocked yes)
			(layer "F.SilkS")
			(effects
				(font
					(size 0.635 0.4064)
					(thickness 0.1524)
				)
				(justify left)
			)
		)
		(fp_text user "3"
			(at 4.082034 20.10029 0)
			(unlocked yes)
			(layer "F.SilkS")
			(effects
				(font
					(size 0.7874 0.5842)
					(thickness 0.1524)
				)
			)
		)
		(fp_text user "4"
			(at 6.08203 20.10029 0)
			(unlocked yes)
			(layer "F.SilkS")
			(effects
				(font
					(size 0.7874 0.5842)
					(thickness 0.1524)
				)
			)
		)
		(fp_text user "5"
			(at 8.082026 20.10029 0)
			(unlocked yes)
			(layer "F.SilkS")
			(effects
				(font
					(size 0.7874 0.5842)
					(thickness 0.1524)
				)
			)
		)
		(fp_text user "6"
			(at 10.082022 20.10029 0)
			(unlocked yes)
			(layer "F.SilkS")
			(effects
				(font
					(size 0.7874 0.5842)
					(thickness 0.1524)
				)
			)
		)
		(fp_text user "7"
			(at 12.082018 20.10029 0)
			(unlocked yes)
			(layer "F.SilkS")
			(effects
				(font
					(size 0.7874 0.5842)
					(thickness 0.1524)
				)
			)
		)
		(fp_text user "8"
			(at 14.082014 20.10029 0)
			(unlocked yes)
			(layer "F.SilkS")
			(effects
				(font
					(size 0.7874 0.5842)
					(thickness 0.1524)
				)
			)
		)
		(fp_text user "A"
			(at -1.304544 -0.04953 0)
			(unlocked yes)
			(layer "B.SilkS")
			(effects
				(font
					(size 0.7874 0.5842)
					(thickness 0.1524)
				)
				(justify mirror)
			)
		)
		(fp_text user "G"
			(at -1.279144 7.36727 0)
			(unlocked yes)
			(layer "B.SilkS")
			(effects
				(font
					(size 0.7874 0.5842)
					(thickness 0.1524)
				)
				(justify mirror)
			)
		)
		(fp_text user "H"
			(at -1.253744 8.58647 0)
			(unlocked yes)
			(layer "B.SilkS")
			(effects
				(font
					(size 0.7874 0.5842)
					(thickness 0.1524)
				)
				(justify mirror)
			)
		)
		(fp_text user "B"
			(at -1.25222 1.277366 0)
			(unlocked yes)
			(layer "B.SilkS")
			(effects
				(font
					(size 0.7874 0.5842)
					(thickness 0.1524)
				)
				(justify mirror)
			)
		)
		(fp_text user "C"
			(at -1.25222 2.477516 0)
			(unlocked yes)
			(layer "B.SilkS")
			(effects
				(font
					(size 0.7874 0.5842)
					(thickness 0.1524)
				)
				(justify mirror)
			)
		)
		(fp_text user "D"
			(at -1.25222 3.677412 0)
			(unlocked yes)
			(layer "B.SilkS")
			(effects
				(font
					(size 0.7874 0.5842)
					(thickness 0.1524)
				)
				(justify mirror)
			)
		)
		(fp_text user "E"
			(at -1.25222 4.877562 0)
			(unlocked yes)
			(layer "B.SilkS")
			(effects
				(font
					(size 0.7874 0.5842)
					(thickness 0.1524)
				)
				(justify mirror)
			)
		)
		(fp_text user "F"
			(at -1.25222 6.077458 0)
			(unlocked yes)
			(layer "B.SilkS")
			(effects
				(font
					(size 0.7874 0.5842)
					(thickness 0.1524)
				)
				(justify mirror)
			)
		)
		(fp_text user "I"
			(at -1.25222 9.6774 0)
			(unlocked yes)
			(layer "B.SilkS")
			(effects
				(font
					(size 0.7874 0.5842)
					(thickness 0.1524)
				)
				(justify mirror)
			)
		)
		(fp_text user "J"
			(at -1.25222 10.87755 0)
			(unlocked yes)
			(layer "B.SilkS")
			(effects
				(font
					(size 0.7874 0.5842)
					(thickness 0.1524)
				)
				(justify mirror)
			)
		)
		(fp_text user "K"
			(at -1.25222 12.077446 0)
			(unlocked yes)
			(layer "B.SilkS")
			(effects
				(font
					(size 0.7874 0.5842)
					(thickness 0.1524)
				)
				(justify mirror)
			)
		)
		(fp_text user "L"
			(at -1.25222 13.277596 0)
			(unlocked yes)
			(layer "B.SilkS")
			(effects
				(font
					(size 0.7874 0.5842)
					(thickness 0.1524)
				)
				(justify mirror)
			)
		)
		(fp_text user "M"
			(at -1.25222 14.477492 0)
			(unlocked yes)
			(layer "B.SilkS")
			(effects
				(font
					(size 0.7874 0.5842)
					(thickness 0.1524)
				)
				(justify mirror)
			)
		)
		(fp_text user "N"
			(at -1.25222 15.677388 0)
			(unlocked yes)
			(layer "B.SilkS")
			(effects
				(font
					(size 0.7874 0.5842)
					(thickness 0.1524)
				)
				(justify mirror)
			)
		)
		(fp_text user "1"
			(at -0.083058 16.94561 0)
			(unlocked yes)
			(layer "B.SilkS")
			(effects
				(font
					(size 0.7874 0.5842)
					(thickness 0.1524)
				)
				(justify mirror)
			)
		)
		(fp_text user "2"
			(at 1.916938 16.94561 0)
			(unlocked yes)
			(layer "B.SilkS")
			(effects
				(font
					(size 0.7874 0.5842)
					(thickness 0.1524)
				)
				(justify mirror)
			)
		)
		(fp_text user "3"
			(at 3.916934 16.94561 0)
			(unlocked yes)
			(layer "B.SilkS")
			(effects
				(font
					(size 0.7874 0.5842)
					(thickness 0.1524)
				)
				(justify mirror)
			)
		)
		(fp_text user "4"
			(at 5.91693 16.94561 0)
			(unlocked yes)
			(layer "B.SilkS")
			(effects
				(font
					(size 0.7874 0.5842)
					(thickness 0.1524)
				)
				(justify mirror)
			)
		)
		(fp_text user "5"
			(at 7.916926 16.94561 0)
			(unlocked yes)
			(layer "B.SilkS")
			(effects
				(font
					(size 0.7874 0.5842)
					(thickness 0.1524)
				)
				(justify mirror)
			)
		)
		(fp_text user "6"
			(at 9.916922 16.94561 0)
			(unlocked yes)
			(layer "B.SilkS")
			(effects
				(font
					(size 0.7874 0.5842)
					(thickness 0.1524)
				)
				(justify mirror)
			)
		)
		(fp_text user "7"
			(at 11.916918 16.94561 0)
			(unlocked yes)
			(layer "B.SilkS")
			(effects
				(font
					(size 0.7874 0.5842)
					(thickness 0.1524)
				)
				(justify mirror)
			)
		)
		(fp_text user "PRESS-FIT"
			(at 12.463018 19.31797 0)
			(unlocked yes)
			(layer "B.SilkS")
			(effects
				(font
					(size 1.905 1.4224)
					(thickness 0.1524)
				)
				(justify left mirror)
			)
		)
		(fp_text user "8"
			(at 13.916914 16.94561 0)
			(unlocked yes)
			(layer "B.SilkS")
			(effects
				(font
					(size 0.7874 0.5842)
					(thickness 0.1524)
				)
				(justify mirror)
			)
		)
		(fp_text user "A"
			(at -1.199134 0 90)
			(unlocked yes)
			(layer "B.Fab")
			(effects
				(font
					(size 0.7874 0.5842)
					(thickness 0.1524)
				)
				(justify mirror)
			)
		)
		(fp_text user "G"
			(at -1.173734 7.4168 90)
			(unlocked yes)
			(layer "B.Fab")
			(effects
				(font
					(size 0.7874 0.5842)
					(thickness 0.1524)
				)
				(justify mirror)
			)
		)
		(fp_text user "H"
			(at -1.148334 8.636 90)
			(unlocked yes)
			(layer "B.Fab")
			(effects
				(font
					(size 0.7874 0.5842)
					(thickness 0.1524)
				)
				(justify mirror)
			)
		)
		(fp_text user "B"
			(at -1.14681 1.326896 90)
			(unlocked yes)
			(layer "B.Fab")
			(effects
				(font
					(size 0.7874 0.5842)
					(thickness 0.1524)
				)
				(justify mirror)
			)
		)
		(fp_text user "C"
			(at -1.14681 2.527046 90)
			(unlocked yes)
			(layer "B.Fab")
			(effects
				(font
					(size 0.7874 0.5842)
					(thickness 0.1524)
				)
				(justify mirror)
			)
		)
		(fp_text user "D"
			(at -1.14681 3.726942 90)
			(unlocked yes)
			(layer "B.Fab")
			(effects
				(font
					(size 0.7874 0.5842)
					(thickness 0.1524)
				)
				(justify mirror)
			)
		)
		(fp_text user "E"
			(at -1.14681 4.927092 90)
			(unlocked yes)
			(layer "B.Fab")
			(effects
				(font
					(size 0.7874 0.5842)
					(thickness 0.1524)
				)
				(justify mirror)
			)
		)
		(fp_text user "F"
			(at -1.14681 6.126988 90)
			(unlocked yes)
			(layer "B.Fab")
			(effects
				(font
					(size 0.7874 0.5842)
					(thickness 0.1524)
				)
				(justify mirror)
			)
		)
		(fp_text user "I"
			(at -1.14681 9.72693 90)
			(unlocked yes)
			(layer "B.Fab")
			(effects
				(font
					(size 0.7874 0.5842)
					(thickness 0.1524)
				)
				(justify mirror)
			)
		)
		(fp_text user "J"
			(at -1.14681 10.92708 90)
			(unlocked yes)
			(layer "B.Fab")
			(effects
				(font
					(size 0.7874 0.5842)
					(thickness 0.1524)
				)
				(justify mirror)
			)
		)
		(fp_text user "K"
			(at -1.14681 12.126976 90)
			(unlocked yes)
			(layer "B.Fab")
			(effects
				(font
					(size 0.7874 0.5842)
					(thickness 0.1524)
				)
				(justify mirror)
			)
		)
		(fp_text user "L"
			(at -1.14681 13.327126 90)
			(unlocked yes)
			(layer "B.Fab")
			(effects
				(font
					(size 0.7874 0.5842)
					(thickness 0.1524)
				)
				(justify mirror)
			)
		)
		(fp_text user "M"
			(at -1.14681 14.527022 90)
			(unlocked yes)
			(layer "B.Fab")
			(effects
				(font
					(size 0.7874 0.5842)
					(thickness 0.1524)
				)
				(justify mirror)
			)
		)
		(fp_text user "N"
			(at -1.14681 15.726918 90)
			(unlocked yes)
			(layer "B.Fab")
			(effects
				(font
					(size 0.7874 0.5842)
					(thickness 0.1524)
				)
				(justify mirror)
			)
		)
		(fp_text user "1"
			(at 0.060452 16.764 90)
			(unlocked yes)
			(layer "B.Fab")
			(effects
				(font
					(size 0.7874 0.5842)
					(thickness 0.1524)
				)
				(justify mirror)
			)
		)
		(fp_text user "2"
			(at 2.060448 16.764 90)
			(unlocked yes)
			(layer "B.Fab")
			(effects
				(font
					(size 0.7874 0.5842)
					(thickness 0.1524)
				)
				(justify mirror)
			)
		)
		(fp_text user "3"
			(at 4.060444 16.764 90)
			(unlocked yes)
			(layer "B.Fab")
			(effects
				(font
					(size 0.7874 0.5842)
					(thickness 0.1524)
				)
				(justify mirror)
			)
		)
		(fp_text user "4"
			(at 6.06044 16.764 90)
			(unlocked yes)
			(layer "B.Fab")
			(effects
				(font
					(size 0.7874 0.5842)
					(thickness 0.1524)
				)
				(justify mirror)
			)
		)
		(fp_text user "5"
			(at 8.060436 16.764 90)
			(unlocked yes)
			(layer "B.Fab")
			(effects
				(font
					(size 0.7874 0.5842)
					(thickness 0.1524)
				)
				(justify mirror)
			)
		)
		(fp_text user "6"
			(at 10.060432 16.764 90)
			(unlocked yes)
			(layer "B.Fab")
			(effects
				(font
					(size 0.7874 0.5842)
					(thickness 0.1524)
				)
				(justify mirror)
			)
		)
		(fp_text user "7"
			(at 12.060428 16.764 90)
			(unlocked yes)
			(layer "B.Fab")
			(effects
				(font
					(size 0.7874 0.5842)
					(thickness 0.1524)
				)
				(justify mirror)
			)
		)
		(fp_text user "8"
			(at 14.060424 16.764 90)
			(unlocked yes)
			(layer "B.Fab")
			(effects
				(font
					(size 0.7874 0.5842)
					(thickness 0.1524)
				)
				(justify mirror)
			)
		)
		(fp_text user "PRESS-FIT"
			(at 17.23771 -0.0762 90)
			(unlocked yes)
			(layer "B.Fab")
			(effects
				(font
					(size 1.905 1.4224)
					(thickness 0.1524)
				)
				(justify left mirror)
			)
		)
		(fp_text user "B"
			(at -2.253742 1.199896 90)
			(unlocked yes)
			(layer "F.Fab")
			(effects
				(font
					(size 0.7874 0.5842)
					(thickness 0.1524)
				)
			)
		)
		(fp_text user "C"
			(at -2.253742 2.400046 90)
			(unlocked yes)
			(layer "F.Fab")
			(effects
				(font
					(size 0.7874 0.5842)
					(thickness 0.1524)
				)
			)
		)
		(fp_text user "D"
			(at -2.253742 3.599942 90)
			(unlocked yes)
			(layer "F.Fab")
			(effects
				(font
					(size 0.7874 0.5842)
					(thickness 0.1524)
				)
			)
		)
		(fp_text user "E"
			(at -2.253742 4.800092 90)
			(unlocked yes)
			(layer "F.Fab")
			(effects
				(font
					(size 0.7874 0.5842)
					(thickness 0.1524)
				)
			)
		)
		(fp_text user "F"
			(at -2.253742 5.999988 90)
			(unlocked yes)
			(layer "F.Fab")
			(effects
				(font
					(size 0.7874 0.5842)
					(thickness 0.1524)
				)
			)
		)
		(fp_text user "G"
			(at -2.253742 7.199884 90)
			(unlocked yes)
			(layer "F.Fab")
			(effects
				(font
					(size 0.7874 0.5842)
					(thickness 0.1524)
				)
			)
		)
		(fp_text user "H"
			(at -2.253742 8.400034 90)
			(unlocked yes)
			(layer "F.Fab")
			(effects
				(font
					(size 0.7874 0.5842)
					(thickness 0.1524)
				)
			)
		)
		(fp_text user "I"
			(at -2.253742 9.59993 90)
			(unlocked yes)
			(layer "F.Fab")
			(effects
				(font
					(size 0.7874 0.5842)
					(thickness 0.1524)
				)
			)
		)
		(fp_text user "J"
			(at -2.253742 10.80008 90)
			(unlocked yes)
			(layer "F.Fab")
			(effects
				(font
					(size 0.7874 0.5842)
					(thickness 0.1524)
				)
			)
		)
		(fp_text user "K"
			(at -2.253742 11.999976 90)
			(unlocked yes)
			(layer "F.Fab")
			(effects
				(font
					(size 0.7874 0.5842)
					(thickness 0.1524)
				)
			)
		)
		(fp_text user "L"
			(at -2.253742 13.200126 90)
			(unlocked yes)
			(layer "F.Fab")
			(effects
				(font
					(size 0.7874 0.5842)
					(thickness 0.1524)
				)
			)
		)
		(fp_text user "M"
			(at -2.253742 14.400022 90)
			(unlocked yes)
			(layer "F.Fab")
			(effects
				(font
					(size 0.7874 0.5842)
					(thickness 0.1524)
				)
			)
		)
		(fp_text user "N"
			(at -2.253742 15.599918 90)
			(unlocked yes)
			(layer "F.Fab")
			(effects
				(font
					(size 0.7874 0.5842)
					(thickness 0.1524)
				)
			)
		)
		(fp_text user "1"
			(at 0.111252 19.8628 90)
			(unlocked yes)
			(layer "F.Fab")
			(effects
				(font
					(size 0.7874 0.5842)
					(thickness 0.1524)
				)
			)
		)
		(fp_text user "2"
			(at 2.111248 19.8628 90)
			(unlocked yes)
			(layer "F.Fab")
			(effects
				(font
					(size 0.7874 0.5842)
					(thickness 0.1524)
				)
			)
		)
		(fp_text user "3"
			(at 4.111244 19.8628 90)
			(unlocked yes)
			(layer "F.Fab")
			(effects
				(font
					(size 0.7874 0.5842)
					(thickness 0.1524)
				)
			)
		)
		(fp_text user "4"
			(at 6.11124 19.8628 90)
			(unlocked yes)
			(layer "F.Fab")
			(effects
				(font
					(size 0.7874 0.5842)
					(thickness 0.1524)
				)
			)
		)
		(fp_text user "5"
			(at 8.111236 19.8628 90)
			(unlocked yes)
			(layer "F.Fab")
			(effects
				(font
					(size 0.7874 0.5842)
					(thickness 0.1524)
				)
			)
		)
		(fp_text user "6"
			(at 10.111232 19.8628 90)
			(unlocked yes)
			(layer "F.Fab")
			(effects
				(font
					(size 0.7874 0.5842)
					(thickness 0.1524)
				)
			)
		)
		(fp_text user "7"
			(at 12.111228 19.8628 90)
			(unlocked yes)
			(layer "F.Fab")
			(effects
				(font
					(size 0.7874 0.5842)
					(thickness 0.1524)
				)
			)
		)
		(fp_text user "8"
			(at 14.111224 19.8628 90)
			(unlocked yes)
			(layer "F.Fab")
			(effects
				(font
					(size 0.7874 0.5842)
					(thickness 0.1524)
				)
			)
		)
		(fp_text user "PRESS-FIT"
			(at 17.240758 16.521684 90)
			(unlocked yes)
			(layer "F.Fab")
			(effects
				(font
					(size 1.905 1.4224)
					(thickness 0.1524)
				)
				(justify left)
			)
		)
		(pad "A1" thru_hole rect
			(at 0 0 180)
			(size 0.766318 0.766318)
			(drill 0.359918)
			(layers "*.Cu" "*.Mask")
			(remove_unused_layers no)
			(net "PRSNT_CABLE_SWB_B1_N")
			(clearance 0.0508)
			(thermal_gap 0.0508)
			(padstack
				(mode front_inner_back)
				(layer "Inner"
					(shape circle)
					(size 0.766318 0.766318)
					(clearance 0.0508)
				)
				(layer "B.Cu"
					(shape rect)
					(size 0.766318 0.766318)
					(clearance 0.0508)
				)
			)
		)
		(pad "A2" thru_hole circle
			(at 1.999996 0.199898 180)
			(size 0.906272 0.906272)
			(drill 0.499872)
			(layers "*.Cu" "*.Mask")
			(remove_unused_layers no)
			(net "GND")
			(clearance 0.0508)
			(thermal_gap 0.0508)
		)
		(pad "A3" thru_hole circle
			(at 3.999992 0 180)
			(size 0.766318 0.766318)
			(drill 0.359918)
			(layers "*.Cu" "*.Mask")
			(remove_unused_layers no)
			(net "FM_SWB_PWRGD")
			(clearance 0.0508)
			(thermal_gap 0.0508)
		)
		(pad "A4" thru_hole circle
			(at 5.999988 0.199898 180)
			(size 0.906272 0.906272)
			(drill 0.499872)
			(layers "*.Cu" "*.Mask")
			(remove_unused_layers no)
			(net "GND")
			(clearance 0.0508)
			(thermal_gap 0.0508)
		)
		(pad "A5" thru_hole circle
			(at 7.999984 0 180)
			(size 0.766318 0.766318)
			(drill 0.359918)
			(layers "*.Cu" "*.Mask")
			(remove_unused_layers no)
			(net "NC_J106_A5")
			(clearance 0.0508)
			(thermal_gap 0.0508)
		)
		(pad "A6" thru_hole circle
			(at 9.99998 0.199898 180)
			(size 0.906272 0.906272)
			(drill 0.499872)
			(layers "*.Cu" "*.Mask")
			(remove_unused_layers no)
			(net "GND")
			(clearance 0.0508)
			(thermal_gap 0.0508)
		)
		(pad "A7" thru_hole circle
			(at 11.999976 0 180)
			(size 0.766318 0.766318)
			(drill 0.359918)
			(layers "*.Cu" "*.Mask")
			(remove_unused_layers no)
			(net "PRSNT_CABLE_GPU_A1_N")
			(clearance 0.0508)
			(thermal_gap 0.0508)
		)
		(pad "A8" thru_hole circle
			(at 13.999972 0.199898 180)
			(size 0.906272 0.906272)
			(drill 0.499872)
			(layers "*.Cu" "*.Mask")
			(remove_unused_layers no)
			(net "GND")
			(clearance 0.0508)
			(thermal_gap 0.0508)
		)
		(pad "B1" thru_hole circle
			(at 0 1.199896 180)
			(size 0.906272 0.906272)
			(drill 0.499872)
			(layers "*.Cu" "*.Mask")
			(remove_unused_layers no)
			(net "GND")
			(clearance 0.0508)
			(thermal_gap 0.0508)
		)
		(pad "B3" thru_hole circle
			(at 3.999992 1.199896 180)
			(size 0.906272 0.906272)
			(drill 0.499872)
			(layers "*.Cu" "*.Mask")
			(remove_unused_layers no)
			(net "GND")
			(clearance 0.0508)
			(thermal_gap 0.0508)
		)
		(pad "B5" thru_hole circle
			(at 7.999984 1.199896 180)
			(size 0.906272 0.906272)
			(drill 0.499872)
			(layers "*.Cu" "*.Mask")
			(remove_unused_layers no)
			(net "GND")
			(clearance 0.0508)
			(thermal_gap 0.0508)
		)
		(pad "B7" thru_hole circle
			(at 11.999976 1.199896 180)
			(size 0.906272 0.906272)
			(drill 0.499872)
			(layers "*.Cu" "*.Mask")
			(remove_unused_layers no)
			(net "GND")
			(clearance 0.0508)
			(thermal_gap 0.0508)
		)
		(pad "D2" thru_hole circle
			(at 1.999996 3.800094 180)
			(size 0.906272 0.906272)
			(drill 0.499872)
			(layers "*.Cu" "*.Mask")
			(remove_unused_layers no)
			(net "GND")
			(clearance 0.0508)
			(thermal_gap 0.0508)
		)
		(pad "D4" thru_hole circle
			(at 5.999988 3.800094 180)
			(size 0.906272 0.906272)
			(drill 0.499872)
			(layers "*.Cu" "*.Mask")
			(remove_unused_layers no)
			(net "GND")
			(clearance 0.0508)
			(thermal_gap 0.0508)
		)
		(pad "D6" thru_hole circle
			(at 9.99998 3.800094 180)
			(size 0.906272 0.906272)
			(drill 0.499872)
			(layers "*.Cu" "*.Mask")
			(remove_unused_layers no)
			(net "GND")
			(clearance 0.0508)
			(thermal_gap 0.0508)
		)
		(pad "D8" thru_hole circle
			(at 13.999972 3.800094 180)
			(size 0.906272 0.906272)
			(drill 0.499872)
			(layers "*.Cu" "*.Mask")
			(remove_unused_layers no)
			(net "GND")
			(clearance 0.0508)
			(thermal_gap 0.0508)
		)
		(pad "E1" thru_hole circle
			(at 0 4.800092 180)
			(size 0.906272 0.906272)
			(drill 0.499872)
			(layers "*.Cu" "*.Mask")
			(remove_unused_layers no)
			(net "GND")
			(clearance 0.0508)
			(thermal_gap 0.0508)
		)
		(pad "E3" thru_hole circle
			(at 3.999992 4.800092 180)
			(size 0.906272 0.906272)
			(drill 0.499872)
			(layers "*.Cu" "*.Mask")
			(remove_unused_layers no)
			(net "GND")
			(clearance 0.0508)
			(thermal_gap 0.0508)
		)
		(pad "E5" thru_hole circle
			(at 7.999984 4.800092 180)
			(size 0.906272 0.906272)
			(drill 0.499872)
			(layers "*.Cu" "*.Mask")
			(remove_unused_layers no)
			(net "GND")
			(clearance 0.0508)
			(thermal_gap 0.0508)
		)
		(pad "E7" thru_hole circle
			(at 11.999976 4.800092 180)
			(size 0.906272 0.906272)
			(drill 0.499872)
			(layers "*.Cu" "*.Mask")
			(remove_unused_layers no)
			(net "GND")
			(clearance 0.0508)
			(thermal_gap 0.0508)
		)
		(pad "G2" thru_hole circle
			(at 1.999996 7.400036 180)
			(size 0.906272 0.906272)
			(drill 0.499872)
			(layers "*.Cu" "*.Mask")
			(remove_unused_layers no)
			(net "GND")
			(clearance 0.0508)
			(thermal_gap 0.0508)
		)
		(pad "G4" thru_hole circle
			(at 5.999988 7.400036 180)
			(size 0.906272 0.906272)
			(drill 0.499872)
			(layers "*.Cu" "*.Mask")
			(remove_unused_layers no)
			(net "GND")
			(clearance 0.0508)
			(thermal_gap 0.0508)
		)
		(pad "G6" thru_hole circle
			(at 9.99998 7.400036 180)
			(size 0.906272 0.906272)
			(drill 0.499872)
			(layers "*.Cu" "*.Mask")
			(remove_unused_layers no)
			(net "GND")
			(clearance 0.0508)
			(thermal_gap 0.0508)
		)
		(pad "G8" thru_hole circle
			(at 13.999972 7.400036 180)
			(size 0.906272 0.906272)
			(drill 0.499872)
			(layers "*.Cu" "*.Mask")
			(remove_unused_layers no)
			(net "GND")
			(clearance 0.0508)
			(thermal_gap 0.0508)
		)
		(pad "H1" thru_hole circle
			(at 0 8.400034 180)
			(size 0.906272 0.906272)
			(drill 0.499872)
			(layers "*.Cu" "*.Mask")
			(remove_unused_layers no)
			(net "GND")
			(clearance 0.0508)
			(thermal_gap 0.0508)
		)
		(pad "H3" thru_hole circle
			(at 3.999992 8.400034 180)
			(size 0.906272 0.906272)
			(drill 0.499872)
			(layers "*.Cu" "*.Mask")
			(remove_unused_layers no)
			(net "GND")
			(clearance 0.0508)
			(thermal_gap 0.0508)
		)
		(pad "H5" thru_hole circle
			(at 7.999984 8.400034 180)
			(size 0.906272 0.906272)
			(drill 0.499872)
			(layers "*.Cu" "*.Mask")
			(remove_unused_layers no)
			(net "GND")
			(clearance 0.0508)
			(thermal_gap 0.0508)
		)
		(pad "H7" thru_hole circle
			(at 11.999976 8.400034 180)
			(size 0.906272 0.906272)
			(drill 0.499872)
			(layers "*.Cu" "*.Mask")
			(remove_unused_layers no)
			(net "GND")
			(clearance 0.0508)
			(thermal_gap 0.0508)
		)
		(pad "J2" thru_hole circle
			(at 1.999996 10.999978 180)
			(size 0.906272 0.906272)
			(drill 0.499872)
			(layers "*.Cu" "*.Mask")
			(remove_unused_layers no)
			(net "GND")
			(clearance 0.0508)
			(thermal_gap 0.0508)
		)
		(pad "J4" thru_hole circle
			(at 5.999988 10.999978 180)
			(size 0.906272 0.906272)
			(drill 0.499872)
			(layers "*.Cu" "*.Mask")
			(remove_unused_layers no)
			(net "GND")
			(clearance 0.0508)
			(thermal_gap 0.0508)
		)
		(pad "J6" thru_hole circle
			(at 9.99998 10.999978 180)
			(size 0.906272 0.906272)
			(drill 0.499872)
			(layers "*.Cu" "*.Mask")
			(remove_unused_layers no)
			(net "GND")
			(clearance 0.0508)
			(thermal_gap 0.0508)
		)
		(pad "J8" thru_hole circle
			(at 13.999972 10.999978 180)
			(size 0.906272 0.906272)
			(drill 0.499872)
			(layers "*.Cu" "*.Mask")
			(remove_unused_layers no)
			(net "GND")
			(clearance 0.0508)
			(thermal_gap 0.0508)
		)
		(pad "K1" thru_hole circle
			(at 0 11.999976 180)
			(size 0.906272 0.906272)
			(drill 0.499872)
			(layers "*.Cu" "*.Mask")
			(remove_unused_layers no)
			(net "GND")
			(clearance 0.0508)
			(thermal_gap 0.0508)
		)
		(pad "K3" thru_hole circle
			(at 3.999992 11.999976 180)
			(size 0.906272 0.906272)
			(drill 0.499872)
			(layers "*.Cu" "*.Mask")
			(remove_unused_layers no)
			(net "GND")
			(clearance 0.0508)
			(thermal_gap 0.0508)
		)
		(pad "K5" thru_hole circle
			(at 7.999984 11.999976 180)
			(size 0.906272 0.906272)
			(drill 0.499872)
			(layers "*.Cu" "*.Mask")
			(remove_unused_layers no)
			(net "GND")
			(clearance 0.0508)
			(thermal_gap 0.0508)
		)
		(pad "K7" thru_hole circle
			(at 11.999976 11.999976 180)
			(size 0.906272 0.906272)
			(drill 0.499872)
			(layers "*.Cu" "*.Mask")
			(remove_unused_layers no)
			(net "GND")
			(clearance 0.0508)
			(thermal_gap 0.0508)
		)
		(pad "M2" thru_hole circle
			(at 1.999996 14.59992 180)
			(size 0.906272 0.906272)
			(drill 0.499872)
			(layers "*.Cu" "*.Mask")
			(remove_unused_layers no)
			(net "GND")
			(clearance 0.0508)
			(thermal_gap 0.0508)
		)
		(pad "M4" thru_hole circle
			(at 5.999988 14.59992 180)
			(size 0.906272 0.906272)
			(drill 0.499872)
			(layers "*.Cu" "*.Mask")
			(remove_unused_layers no)
			(net "GND")
			(clearance 0.0508)
			(thermal_gap 0.0508)
		)
		(pad "M6" thru_hole circle
			(at 9.99998 14.59992 180)
			(size 0.906272 0.906272)
			(drill 0.499872)
			(layers "*.Cu" "*.Mask")
			(remove_unused_layers no)
			(net "GND")
			(clearance 0.0508)
			(thermal_gap 0.0508)
		)
		(pad "M8" thru_hole circle
			(at 13.999972 14.59992 180)
			(size 0.906272 0.906272)
			(drill 0.499872)
			(layers "*.Cu" "*.Mask")
			(remove_unused_layers no)
			(net "GND")
			(clearance 0.0508)
			(thermal_gap 0.0508)
		)
		(pad "N1" thru_hole circle
			(at 0 15.599918 180)
			(size 0.906272 0.906272)
			(drill 0.499872)
			(layers "*.Cu" "*.Mask")
			(remove_unused_layers no)
			(net "GND")
			(clearance 0.0508)
			(thermal_gap 0.0508)
		)
		(pad "N2" thru_hole circle
			(at 1.999996 15.80007 180)
			(size 0.766318 0.766318)
			(drill 0.359918)
			(layers "*.Cu" "*.Mask")
			(remove_unused_layers no)
			(net "I3C_BMC_SWB_BUF_SDA")
			(clearance 0.0508)
			(thermal_gap 0.0508)
		)
		(pad "N3" thru_hole circle
			(at 3.999992 15.599918 180)
			(size 0.906272 0.906272)
			(drill 0.499872)
			(layers "*.Cu" "*.Mask")
			(remove_unused_layers no)
			(net "GND")
			(clearance 0.0508)
			(thermal_gap 0.0508)
		)
		(pad "N4" thru_hole circle
			(at 5.999988 15.80007 180)
			(size 0.766318 0.766318)
			(drill 0.359918)
			(layers "*.Cu" "*.Mask")
			(remove_unused_layers no)
			(net "I3C_BMC_SWB_BUF_SCL")
			(clearance 0.0508)
			(thermal_gap 0.0508)
		)
		(pad "N5" thru_hole circle
			(at 7.999984 15.599918 180)
			(size 0.906272 0.906272)
			(drill 0.499872)
			(layers "*.Cu" "*.Mask")
			(remove_unused_layers no)
			(net "GND")
			(clearance 0.0508)
			(thermal_gap 0.0508)
		)
		(pad "N6" thru_hole circle
			(at 9.99998 15.80007 180)
			(size 0.766318 0.766318)
			(drill 0.359918)
			(layers "*.Cu" "*.Mask")
			(remove_unused_layers no)
			(net "UART_BMC_BIC_RX")
			(clearance 0.0508)
			(thermal_gap 0.0508)
		)
		(pad "N7" thru_hole circle
			(at 11.999976 15.599918 180)
			(size 0.906272 0.906272)
			(drill 0.499872)
			(layers "*.Cu" "*.Mask")
			(remove_unused_layers no)
			(net "GND")
			(clearance 0.0508)
			(thermal_gap 0.0508)
		)
		(pad "N8" thru_hole circle
			(at 13.999972 15.80007 180)
			(size 0.766318 0.766318)
			(drill 0.359918)
			(layers "*.Cu" "*.Mask")
			(remove_unused_layers no)
			(net "UART_BMC_BIC_TX")
			(clearance 0.0508)
			(thermal_gap 0.0508)
		)
	)
	(footprint ""
		(layer "F.Cu")
		(at 53.190902 -174.230792 90)
		(property "Reference" "PU49"
			(at 1.292606 -8.370062 0)
			(unlocked yes)
			(layer "F.SilkS")
			(effects
				(font
					(size 0.7874 0.5842)
					(thickness 0.1524)
				)
				(justify left)
			)
		)
		(property "Value" ""
			(at 0 0 90)
			(layer "F.Fab")
			(effects
				(font
					(size 1.27 1.27)
				)
			)
		)
		(duplicate_pad_numbers_are_jumpers no)
		(fp_line
			(start 2.050034 -2.549906)
			(end 1.916684 -2.549906)
			(stroke
				(width 0.1524)
				(type default)
			)
			(layer "F.SilkS")
		)
		(fp_line
			(start -1.61671 -2.549906)
			(end -2.050034 -2.549906)
			(stroke
				(width 0.1524)
				(type default)
			)
			(layer "F.SilkS")
		)
		(fp_line
			(start -2.050034 -2.549906)
			(end -2.050034 -2.126742)
			(stroke
				(width 0.1524)
				(type default)
			)
			(layer "F.SilkS")
		)
		(fp_line
			(start 2.050034 -1.981708)
			(end 2.050034 -2.549906)
			(stroke
				(width 0.1524)
				(type default)
			)
			(layer "F.SilkS")
		)
		(fp_line
			(start 2.050034 0.08636)
			(end 2.050034 -0.178308)
			(stroke
				(width 0.1524)
				(type default)
			)
			(layer "F.SilkS")
		)
		(fp_line
			(start -2.050034 0.406654)
			(end -2.050034 0.786384)
			(stroke
				(width 0.1524)
				(type default)
			)
			(layer "F.SilkS")
		)
		(fp_line
			(start -2.050034 1.88976)
			(end -2.050034 2.549906)
			(stroke
				(width 0.1524)
				(type default)
			)
			(layer "F.SilkS")
		)
		(fp_line
			(start 2.050034 2.549906)
			(end 2.050034 1.88976)
			(stroke
				(width 0.1524)
				(type default)
			)
			(layer "F.SilkS")
		)
		(fp_line
			(start 1.27 2.549906)
			(end 2.050034 2.549906)
			(stroke
				(width 0.1524)
				(type default)
			)
			(layer "F.SilkS")
		)
		(fp_line
			(start -2.050034 2.549906)
			(end -1.27 2.549906)
			(stroke
				(width 0.1524)
				(type default)
			)
			(layer "F.SilkS")
		)
		(fp_poly
			(pts
				(xy -2.33553 -1.898142) (xy -2.711704 -1.710182) (xy -2.711704 -2.086102)
			)
			(stroke
				(width 0)
				(type default)
			)
			(fill yes)
			(layer "F.SilkS")
		)
		(fp_line
			(start 2.050034 -2.549906)
			(end -2.050034 -2.549906)
			(stroke
				(width 0.1)
				(type default)
			)
			(layer "F.Fab")
		)
		(fp_line
			(start -2.050034 -2.549906)
			(end -2.050034 2.549906)
			(stroke
				(width 0.1)
				(type default)
			)
			(layer "F.Fab")
		)
		(fp_line
			(start 2.050034 2.549906)
			(end 2.050034 -2.549906)
			(stroke
				(width 0.1)
				(type default)
			)
			(layer "F.Fab")
		)
		(fp_line
			(start -2.050034 2.549906)
			(end 2.050034 2.549906)
			(stroke
				(width 0.1)
				(type default)
			)
			(layer "F.Fab")
		)
		(fp_poly
			(pts
				(xy -3.43789 -2.368042) (xy -3.43789 -1.352042) (xy -2.42189 -1.860042)
			)
			(stroke
				(width 0)
				(type default)
			)
			(fill yes)
			(layer "F.Fab")
		)
		(pad "1" smd rect
			(at -1.925066 -1.860042)
			(size 0.254 0.5588)
			(layers "F.Cu" "F.Mask" "F.Paste")
			(net "PVCCFA_EHV_CPU1_BTSEN")
		)
		(pad "2" smd rect
			(at -1.925066 -1.359916)
			(size 0.254 0.5588)
			(layers "F.Cu" "F.Mask" "F.Paste")
			(net "PVCCFA_EHV_CPU1_FAULT")
		)
		(pad "3" smd rect
			(at -1.925066 -0.860044)
			(size 0.254 0.5588)
			(layers "F.Cu" "F.Mask" "F.Paste")
			(net "PVCCFA_EHV_CPU1_NC1")
		)
		(pad "4" smd rect
			(at -1.925066 -0.359918)
			(size 0.254 0.5588)
			(layers "F.Cu" "F.Mask" "F.Paste")
			(net "PVCCFA_EHV_CPU1_VDD1")
		)
		(pad "5" smd rect
			(at -1.925066 0.139954)
			(size 0.254 0.5588)
			(layers "F.Cu" "F.Mask" "F.Paste")
			(net "PVCCFA_EHV_CPU1_LSET1")
		)
		(pad "6_7-13_15-29" smd circle
			(at 0 0.98806 180)
			(size 0 0)
			(layers "F.Cu" "F.Mask" "F.Paste")
			(net "GND")
		)
		(pad "8_12" smd rect
			(at 0 2.400046)
			(size 0.6096 2.2606)
			(layers "F.Cu" "F.Mask" "F.Paste")
			(net "SW_PVCCFA_EHV_CPU1_SW1")
		)
		(pad "16_18-28" smd rect
			(at 1.480566 -1.080008 90)
			(size 1.4478 1.524)
			(layers "F.Cu" "F.Mask" "F.Paste")
			(net "SW_P12V_PVCCINFAON_CPU1_FLT")
		)
		(pad "19" smd rect
			(at 1.649984 -2.424938 90)
			(size 0.254 0.5588)
			(layers "F.Cu" "F.Mask" "F.Paste")
			(net "SW_PVCCFA_EHV_CPU1_BOOTR1")
		)
		(pad "20" smd rect
			(at 1.150112 -2.424938 90)
			(size 0.254 0.5588)
			(layers "F.Cu" "F.Mask" "F.Paste")
			(net "SW_PVCCFA_EHV_CPU1_BOOT1")
		)
		(pad "21" smd rect
			(at 0.649986 -2.424938 90)
			(size 0.254 0.5588)
			(layers "F.Cu" "F.Mask" "F.Paste")
			(net "PVCCFA_EHV_CPU1_BPWM1")
		)
		(pad "22" smd rect
			(at 0.150114 -2.424938 90)
			(size 0.254 0.5588)
			(layers "F.Cu" "F.Mask" "F.Paste")
			(net "PVCCFA_EHV_CPU1_NC2")
		)
		(pad "23" smd rect
			(at -0.350012 -2.424938 90)
			(size 0.254 0.5588)
			(layers "F.Cu" "F.Mask" "F.Paste")
			(net "GND")
		)
		(pad "24" smd rect
			(at -0.849884 -2.424938 90)
			(size 0.254 0.5588)
			(layers "F.Cu" "F.Mask" "F.Paste")
			(net "PVCCINFAON_CPU1_VREF")
		)
		(pad "25" smd rect
			(at -1.35001 -2.424938 90)
			(size 0.254 0.5588)
			(layers "F.Cu" "F.Mask" "F.Paste")
			(net "PVCCFA_EHV_CPU1_BCSP1")
		)
		(pad "26" smd circle
			(at -0.490728 -1.009396 180)
			(size 0 0)
			(layers "F.Cu" "F.Mask" "F.Paste")
			(net "GND")
		)
		(pad "27" smd rect
			(at -1.124966 0.425958)
			(size 0.2032 0.3556)
			(layers "F.Cu" "F.Mask" "F.Paste")
			(net "Net_8493")
		)
		(zone
			(layer "F.Cu")
			(hatch none 0.5)
			(connect_pads
				(clearance 0)
			)
			(min_thickness 0.25)
			(keepout
				(tracks not_allowed)
				(vias allowed)
				(pads allowed)
				(copperpour not_allowed)
				(footprints allowed)
			)
			(placement
				(enabled no)
				(sheetname "")
			)
			(fill
				(thermal_gap 0.5)
				(thermal_bridge_width 0.5)
				(island_removal_mode 0)
			)
			(polygon
				(pts
					(xy 54.991762 -172.43552) (xy 54.991762 -175.979328) (xy 55.235348 -176.222914) (xy 55.235348 -172.191934)
				)
			)
		)
		(zone
			(layer "F.Cu")
			(hatch none 0.5)
			(connect_pads
				(clearance 0)
			)
			(min_thickness 0.25)
			(keepout
				(tracks not_allowed)
				(vias allowed)
				(pads allowed)
				(copperpour not_allowed)
				(footprints allowed)
			)
			(placement
				(enabled no)
				(sheetname "")
			)
			(fill
				(thermal_gap 0.5)
				(thermal_bridge_width 0.5)
				(island_removal_mode 0)
			)
			(polygon
				(pts
					(xy 53.3781 -173.734984) (xy 54.066186 -173.734984) (xy 54.066186 -172.180758) (xy 53.622702 -172.180758)
					(xy 53.622702 -172.877226) (xy 53.76926 -172.877226) (xy 53.76926 -173.334426) (xy 53.46446 -173.334426)
					(xy 53.46446 -172.877226) (xy 53.597302 -172.877226) (xy 53.597302 -172.180758) (xy 53.508656 -172.180758)
					(xy 53.508656 -172.635926) (xy 51.590702 -172.635926) (xy 51.590702 -172.812456) (xy 53.090318 -172.812456)
					(xy 53.090318 -173.561248) (xy 53.3781 -173.561248)
				)
			)
		)
	)
	(footprint ""
		(layer "F.Cu")
		(at 268.645132 -51.999896)
		(property "Reference" "H111"
			(at -9.58596 -6.67131 0)
			(unlocked yes)
			(layer "F.SilkS")
			(effects
				(font
					(size 0.7874 0.5842)
					(thickness 0.1524)
				)
				(justify left)
			)
		)
		(property "Value" ""
			(at 0 0 0)
			(layer "F.Fab")
			(effects
				(font
					(size 1.27 1.27)
				)
			)
		)
		(duplicate_pad_numbers_are_jumpers no)
		(fp_circle
			(center 0 0)
			(end 7.999984 0)
			(stroke
				(width 0.1524)
				(type default)
			)
			(fill no)
			(layer "F.SilkS")
		)
		(fp_circle
			(center 0 0)
			(end 7.999984 0)
			(stroke
				(width 0.1524)
				(type default)
			)
			(fill no)
			(layer "B.SilkS")
		)
		(fp_circle
			(center 0 0)
			(end 7.999984 0)
			(stroke
				(width 0.1)
				(type default)
			)
			(fill no)
			(layer "B.Fab")
		)
		(fp_circle
			(center 0 0)
			(end 7.999984 0)
			(stroke
				(width 0.1)
				(type default)
			)
			(fill no)
			(layer "F.Fab")
		)
		(pad "" np_thru_hole circle
			(at 0 0)
			(size 5.5118 5.5118)
			(drill 5.5118)
			(layers "*.Cu" "*.Mask")
			(clearance 0.381)
			(thermal_gap 0.381)
		)
		(pad "2" thru_hole circle
			(at 0 -3.999992)
			(size 0.762 0.762)
			(drill 0.5588)
			(layers "*.Cu" "*.Mask")
			(remove_unused_layers no)
			(net "GND")
			(clearance 0.1524)
			(thermal_gap 0.1524)
		)
		(pad "3" thru_hole circle
			(at -2.999994 -2.500122)
			(size 0.762 0.762)
			(drill 0.5588)
			(layers "*.Cu" "*.Mask")
			(remove_unused_layers no)
			(net "GND")
			(clearance 0.1524)
			(thermal_gap 0.1524)
		)
		(pad "4" thru_hole circle
			(at -3.999992 0)
			(size 0.762 0.762)
			(drill 0.5588)
			(layers "*.Cu" "*.Mask")
			(remove_unused_layers no)
			(net "GND")
			(clearance 0.1524)
			(thermal_gap 0.1524)
		)
		(pad "5" thru_hole circle
			(at -2.999994 2.500122)
			(size 0.762 0.762)
			(drill 0.5588)
			(layers "*.Cu" "*.Mask")
			(remove_unused_layers no)
			(net "GND")
			(clearance 0.1524)
			(thermal_gap 0.1524)
		)
		(pad "6" thru_hole circle
			(at 0 3.999992)
			(size 0.762 0.762)
			(drill 0.5588)
			(layers "*.Cu" "*.Mask")
			(remove_unused_layers no)
			(net "GND")
			(clearance 0.1524)
			(thermal_gap 0.1524)
		)
		(pad "7" thru_hole circle
			(at 2.999994 2.500122)
			(size 0.762 0.762)
			(drill 0.5588)
			(layers "*.Cu" "*.Mask")
			(remove_unused_layers no)
			(net "GND")
			(clearance 0.1524)
			(thermal_gap 0.1524)
		)
		(pad "8" thru_hole circle
			(at 3.999992 0)
			(size 0.762 0.762)
			(drill 0.5588)
			(layers "*.Cu" "*.Mask")
			(remove_unused_layers no)
			(net "GND")
			(clearance 0.1524)
			(thermal_gap 0.1524)
		)
		(pad "9" thru_hole circle
			(at 2.999994 -2.500122)
			(size 0.762 0.762)
			(drill 0.5588)
			(layers "*.Cu" "*.Mask")
			(remove_unused_layers no)
			(net "GND")
			(clearance 0.1524)
			(thermal_gap 0.1524)
		)
		(zone
			(layer "F.Cu")
			(hatch none 0.5)
			(connect_pads
				(clearance 0)
			)
			(min_thickness 0.25)
			(keepout
				(tracks not_allowed)
				(vias allowed)
				(pads allowed)
				(copperpour not_allowed)
				(footprints allowed)
			)
			(placement
				(enabled no)
				(sheetname "")
			)
			(fill
				(thermal_gap 0.5)
				(thermal_bridge_width 0.5)
				(island_removal_mode 0)
			)
			(polygon
				(pts
					(arc
						(start 268.645132 -59.99988)
						(mid 262.988289 -57.656739)
						(end 260.645148 -51.999896)
					)
					(arc
						(start 260.645148 -51.999896)
						(mid 262.988289 -46.343053)
						(end 268.645132 -43.999912)
					)
					(xy 268.645132 -46.74616) (xy 268.594078 -46.74616)
					(arc
						(start 268.593824 -46.74616)
						(mid 263.391145 -51.999896)
						(end 268.593824 -57.253632)
					)
					(xy 268.594078 -57.253632) (xy 268.645132 -57.253632)
				)
			)
		)
		(zone
			(layer "F.Cu")
			(hatch none 0.5)
			(connect_pads
				(clearance 0)
			)
			(min_thickness 0.25)
			(keepout
				(tracks not_allowed)
				(vias allowed)
				(pads allowed)
				(copperpour not_allowed)
				(footprints allowed)
			)
			(placement
				(enabled no)
				(sheetname "")
			)
			(fill
				(thermal_gap 0.5)
				(thermal_bridge_width 0.5)
				(island_removal_mode 0)
			)
			(polygon
				(pts
					(arc
						(start 268.645132 -59.99988)
						(mid 274.301975 -57.656739)
						(end 276.645116 -51.999896)
					)
					(arc
						(start 276.645116 -51.999896)
						(mid 274.301975 -46.343053)
						(end 268.645132 -43.999912)
					)
					(xy 268.645132 -46.74616) (xy 268.696186 -46.74616)
					(arc
						(start 268.69644 -46.74616)
						(mid 273.899119 -51.999896)
						(end 268.69644 -57.253632)
					)
					(xy 268.696186 -57.253632) (xy 268.645132 -57.253632)
				)
			)
		)
		(zone
			(layers "F.Cu" "B.Cu" "In1.Cu" "In2.Cu" "In3.Cu" "In4.Cu" "In5.Cu" "In6.Cu"
				"In7.Cu" "In8.Cu" "In9.Cu" "In10.Cu" "In11.Cu" "In12.Cu" "In13.Cu" "In14.Cu"
				"In15.Cu" "In16.Cu"
			)
			(hatch none 0.5)
			(connect_pads
				(clearance 0)
			)
			(min_thickness 0.25)
			(keepout
				(tracks not_allowed)
				(vias allowed)
				(pads allowed)
				(copperpour not_allowed)
				(footprints allowed)
			)
			(placement
				(enabled no)
				(sheetname "")
			)
			(fill
				(thermal_gap 0.5)
				(thermal_bridge_width 0.5)
				(island_removal_mode 0)
			)
			(polygon
				(pts
					(arc
						(start 271.921732 -51.999896)
						(mid 265.368532 -51.999896)
						(end 271.921732 -51.999896)
					)
				)
			)
		)
		(zone
			(layer "B.Cu")
			(hatch none 0.5)
			(connect_pads
				(clearance 0)
			)
			(min_thickness 0.25)
			(keepout
				(tracks not_allowed)
				(vias allowed)
				(pads allowed)
				(copperpour not_allowed)
				(footprints allowed)
			)
			(placement
				(enabled no)
				(sheetname "")
			)
			(fill
				(thermal_gap 0.5)
				(thermal_bridge_width 0.5)
				(island_removal_mode 0)
			)
			(polygon
				(pts
					(arc
						(start 268.645132 -57.507886)
						(mid 263.137142 -51.999896)
						(end 268.645132 -46.491906)
					)
					(arc
						(start 268.645132 -46.974506)
						(mid 263.619742 -51.999896)
						(end 268.645132 -57.025286)
					)
				)
			)
		)
		(zone
			(layer "B.Cu")
			(hatch none 0.5)
			(connect_pads
				(clearance 0)
			)
			(min_thickness 0.25)
			(keepout
				(tracks not_allowed)
				(vias allowed)
				(pads allowed)
				(copperpour not_allowed)
				(footprints allowed)
			)
			(placement
				(enabled no)
				(sheetname "")
			)
			(fill
				(thermal_gap 0.5)
				(thermal_bridge_width 0.5)
				(island_removal_mode 0)
			)
			(polygon
				(pts
					(arc
						(start 268.645132 -57.507886)
						(mid 274.153122 -51.999896)
						(end 268.645132 -46.491906)
					)
					(arc
						(start 268.645132 -46.974506)
						(mid 273.670522 -51.999896)
						(end 268.645132 -57.025286)
					)
				)
			)
		)
	)
	(footprint ""
		(layer "F.Cu")
		(at 449.973954 -119.429022 180)
		(property "Reference" "R1921"
			(at 0 0 180)
			(layer "F.SilkS")
			(hide yes)
			(effects
				(font
					(size 1.27 1.27)
				)
			)
		)
		(property "Value" ""
			(at 0 0 180)
			(layer "F.Fab")
			(effects
				(font
					(size 1.27 1.27)
				)
			)
		)
		(duplicate_pad_numbers_are_jumpers no)
		(fp_line
			(start 0.7874 0.4064)
			(end -0.7874 0.4064)
			(stroke
				(width 0.1524)
				(type default)
			)
			(layer "F.SilkS")
		)
		(fp_line
			(start 0.7874 -0.4064)
			(end 0.7874 0.4064)
			(stroke
				(width 0.1524)
				(type default)
			)
			(layer "F.SilkS")
		)
		(fp_line
			(start -0.7874 0.4064)
			(end -0.7874 -0.4064)
			(stroke
				(width 0.1524)
				(type default)
			)
			(layer "F.SilkS")
		)
		(fp_line
			(start -0.7874 -0.4064)
			(end 0.7874 -0.4064)
			(stroke
				(width 0.1524)
				(type default)
			)
			(layer "F.SilkS")
		)
		(fp_line
			(start 0.67945 0.3048)
			(end 0.120396 0.3048)
			(stroke
				(width 0.1)
				(type default)
			)
			(layer "F.Fab")
		)
		(fp_line
			(start 0.67945 -0.3048)
			(end 0.67945 0.3048)
			(stroke
				(width 0.1)
				(type default)
			)
			(layer "F.Fab")
		)
		(fp_line
			(start 0.12065 -0.2794)
			(end 0.12065 -0.3048)
			(stroke
				(width 0.1)
				(type default)
			)
			(layer "F.Fab")
		)
		(fp_line
			(start 0.12065 -0.3048)
			(end 0.67945 -0.3048)
			(stroke
				(width 0.1)
				(type default)
			)
			(layer "F.Fab")
		)
		(fp_line
			(start 0.120396 0.3048)
			(end 0.120396 0.2794)
			(stroke
				(width 0.1)
				(type default)
			)
			(layer "F.Fab")
		)
		(fp_line
			(start 0.120396 0.2794)
			(end -0.12065 0.2794)
			(stroke
				(width 0.1)
				(type default)
			)
			(layer "F.Fab")
		)
		(fp_line
			(start -0.12065 0.3048)
			(end -0.67945 0.3048)
			(stroke
				(width 0.1)
				(type default)
			)
			(layer "F.Fab")
		)
		(fp_line
			(start -0.12065 0.2794)
			(end -0.12065 0.3048)
			(stroke
				(width 0.1)
				(type default)
			)
			(layer "F.Fab")
		)
		(fp_line
			(start -0.12065 -0.2794)
			(end 0.12065 -0.2794)
			(stroke
				(width 0.1)
				(type default)
			)
			(layer "F.Fab")
		)
		(fp_line
			(start -0.12065 -0.305054)
			(end -0.12065 -0.2794)
			(stroke
				(width 0.1)
				(type default)
			)
			(layer "F.Fab")
		)
		(fp_line
			(start -0.67945 0.3048)
			(end -0.67945 -0.305054)
			(stroke
				(width 0.1)
				(type default)
			)
			(layer "F.Fab")
		)
		(fp_line
			(start -0.67945 -0.305054)
			(end -0.12065 -0.305054)
			(stroke
				(width 0.1)
				(type default)
			)
			(layer "F.Fab")
		)
		(pad "1" smd circle
			(at -0.40005 0 180)
			(size 0 0)
			(layers "F.Cu" "F.Mask" "F.Paste")
			(net "FM_SMB_CPU0_ALERT")
		)
		(pad "2" smd circle
			(at 0.40005 0 180)
			(size 0 0)
			(layers "F.Cu" "F.Mask" "F.Paste")
			(net "FM_SMB_PEHPCPU0_PCIE_ALERT_N")
		)
	)
	(footprint ""
		(layer "F.Cu")
		(at 190.41364 -70.185788)
		(property "Reference" "PR3947"
			(at 0 0 0)
			(layer "F.SilkS")
			(hide yes)
			(effects
				(font
					(size 1.27 1.27)
				)
			)
		)
		(property "Value" ""
			(at 0 0 0)
			(layer "F.Fab")
			(effects
				(font
					(size 1.27 1.27)
				)
			)
		)
		(duplicate_pad_numbers_are_jumpers no)
		(fp_line
			(start -0.7874 -0.4064)
			(end 0.7874 -0.4064)
			(stroke
				(width 0.1524)
				(type default)
			)
			(layer "F.SilkS")
		)
		(fp_line
			(start -0.7874 0.4064)
			(end -0.7874 -0.4064)
			(stroke
				(width 0.1524)
				(type default)
			)
			(layer "F.SilkS")
		)
		(fp_line
			(start 0.7874 -0.4064)
			(end 0.7874 0.4064)
			(stroke
				(width 0.1524)
				(type default)
			)
			(layer "F.SilkS")
		)
		(fp_line
			(start 0.7874 0.4064)
			(end -0.7874 0.4064)
			(stroke
				(width 0.1524)
				(type default)
			)
			(layer "F.SilkS")
		)
		(fp_line
			(start -0.67945 -0.305054)
			(end -0.12065 -0.305054)
			(stroke
				(width 0.1)
				(type default)
			)
			(layer "F.Fab")
		)
		(fp_line
			(start -0.67945 0.3048)
			(end -0.67945 -0.305054)
			(stroke
				(width 0.1)
				(type default)
			)
			(layer "F.Fab")
		)
		(fp_line
			(start -0.12065 -0.305054)
			(end -0.12065 -0.2794)
			(stroke
				(width 0.1)
				(type default)
			)
			(layer "F.Fab")
		)
		(fp_line
			(start -0.12065 -0.2794)
			(end 0.12065 -0.2794)
			(stroke
				(width 0.1)
				(type default)
			)
			(layer "F.Fab")
		)
		(fp_line
			(start -0.12065 0.2794)
			(end -0.12065 0.3048)
			(stroke
				(width 0.1)
				(type default)
			)
			(layer "F.Fab")
		)
		(fp_line
			(start -0.12065 0.3048)
			(end -0.67945 0.3048)
			(stroke
				(width 0.1)
				(type default)
			)
			(layer "F.Fab")
		)
		(fp_line
			(start 0.120396 0.2794)
			(end -0.12065 0.2794)
			(stroke
				(width 0.1)
				(type default)
			)
			(layer "F.Fab")
		)
		(fp_line
			(start 0.120396 0.3048)
			(end 0.120396 0.2794)
			(stroke
				(width 0.1)
				(type default)
			)
			(layer "F.Fab")
		)
		(fp_line
			(start 0.12065 -0.3048)
			(end 0.67945 -0.3048)
			(stroke
				(width 0.1)
				(type default)
			)
			(layer "F.Fab")
		)
		(fp_line
			(start 0.12065 -0.2794)
			(end 0.12065 -0.3048)
			(stroke
				(width 0.1)
				(type default)
			)
			(layer "F.Fab")
		)
		(fp_line
			(start 0.67945 -0.3048)
			(end 0.67945 0.3048)
			(stroke
				(width 0.1)
				(type default)
			)
			(layer "F.Fab")
		)
		(fp_line
			(start 0.67945 0.3048)
			(end 0.120396 0.3048)
			(stroke
				(width 0.1)
				(type default)
			)
			(layer "F.Fab")
		)
		(pad "1" smd circle
			(at -0.40005 0)
			(size 0 0)
			(layers "F.Cu" "F.Mask" "F.Paste")
			(net "GND")
		)
		(pad "2" smd circle
			(at 0.40005 0)
			(size 0 0)
			(layers "F.Cu" "F.Mask" "F.Paste")
			(net "P3V3_E1S_ILIMIT_0")
		)
	)
	(footprint ""
		(layer "F.Cu")
		(at 83.55711 -59.242706 90)
		(property "Reference" "PR3822"
			(at 0 0 90)
			(layer "F.SilkS")
			(hide yes)
			(effects
				(font
					(size 1.27 1.27)
				)
			)
		)
		(property "Value" ""
			(at 0 0 90)
			(layer "F.Fab")
			(effects
				(font
					(size 1.27 1.27)
				)
			)
		)
		(duplicate_pad_numbers_are_jumpers no)
		(fp_line
			(start 0.7874 -0.4064)
			(end 0.7874 0.4064)
			(stroke
				(width 0.1524)
				(type default)
			)
			(layer "F.SilkS")
		)
		(fp_line
			(start -0.7874 -0.4064)
			(end 0.7874 -0.4064)
			(stroke
				(width 0.1524)
				(type default)
			)
			(layer "F.SilkS")
		)
		(fp_line
			(start 0.7874 0.4064)
			(end -0.7874 0.4064)
			(stroke
				(width 0.1524)
				(type default)
			)
			(layer "F.SilkS")
		)
		(fp_line
			(start -0.7874 0.4064)
			(end -0.7874 -0.4064)
			(stroke
				(width 0.1524)
				(type default)
			)
			(layer "F.SilkS")
		)
		(fp_line
			(start -0.12065 -0.305054)
			(end -0.12065 -0.2794)
			(stroke
				(width 0.1)
				(type default)
			)
			(layer "F.Fab")
		)
		(fp_line
			(start -0.67945 -0.305054)
			(end -0.12065 -0.305054)
			(stroke
				(width 0.1)
				(type default)
			)
			(layer "F.Fab")
		)
		(fp_line
			(start 0.67945 -0.3048)
			(end 0.67945 0.3048)
			(stroke
				(width 0.1)
				(type default)
			)
			(layer "F.Fab")
		)
		(fp_line
			(start 0.12065 -0.3048)
			(end 0.67945 -0.3048)
			(stroke
				(width 0.1)
				(type default)
			)
			(layer "F.Fab")
		)
		(fp_line
			(start 0.12065 -0.2794)
			(end 0.12065 -0.3048)
			(stroke
				(width 0.1)
				(type default)
			)
			(layer "F.Fab")
		)
		(fp_line
			(start -0.12065 -0.2794)
			(end 0.12065 -0.2794)
			(stroke
				(width 0.1)
				(type default)
			)
			(layer "F.Fab")
		)
		(fp_line
			(start 0.120396 0.2794)
			(end -0.12065 0.2794)
			(stroke
				(width 0.1)
				(type default)
			)
			(layer "F.Fab")
		)
		(fp_line
			(start -0.12065 0.2794)
			(end -0.12065 0.3048)
			(stroke
				(width 0.1)
				(type default)
			)
			(layer "F.Fab")
		)
		(fp_line
			(start 0.67945 0.3048)
			(end 0.120396 0.3048)
			(stroke
				(width 0.1)
				(type default)
			)
			(layer "F.Fab")
		)
		(fp_line
			(start 0.120396 0.3048)
			(end 0.120396 0.2794)
			(stroke
				(width 0.1)
				(type default)
			)
			(layer "F.Fab")
		)
		(fp_line
			(start -0.12065 0.3048)
			(end -0.67945 0.3048)
			(stroke
				(width 0.1)
				(type default)
			)
			(layer "F.Fab")
		)
		(fp_line
			(start -0.67945 0.3048)
			(end -0.67945 -0.305054)
			(stroke
				(width 0.1)
				(type default)
			)
			(layer "F.Fab")
		)
		(pad "1" smd circle
			(at -0.40005 0 90)
			(size 0 0)
			(layers "F.Cu" "F.Mask" "F.Paste")
			(net "P3V3_OCP_CB_2")
		)
		(pad "2" smd circle
			(at 0.40005 0 90)
			(size 0 0)
			(layers "F.Cu" "F.Mask" "F.Paste")
			(net "GND")
		)
	)
	(footprint ""
		(layer "F.Cu")
		(at 252.83287 -41.039542 -90)
		(property "Reference" "PU294"
			(at -0.130556 -1.349502 0)
			(unlocked yes)
			(layer "F.SilkS")
			(effects
				(font
					(size 0.7874 0.5842)
					(thickness 0.1524)
				)
				(justify left)
			)
		)
		(property "Value" ""
			(at 0 0 270)
			(layer "F.Fab")
			(effects
				(font
					(size 1.27 1.27)
				)
			)
		)
		(duplicate_pad_numbers_are_jumpers no)
		(fp_line
			(start -1.774952 1.039876)
			(end 1.774952 1.039876)
			(stroke
				(width 0.1524)
				(type default)
			)
			(layer "F.SilkS")
		)
		(fp_line
			(start 1.774952 1.039876)
			(end 1.774952 -1.039876)
			(stroke
				(width 0.1524)
				(type default)
			)
			(layer "F.SilkS")
		)
		(fp_line
			(start -1.774952 -1.039876)
			(end -1.774952 1.039876)
			(stroke
				(width 0.1524)
				(type default)
			)
			(layer "F.SilkS")
		)
		(fp_line
			(start 1.774952 -1.039876)
			(end -1.774952 -1.039876)
			(stroke
				(width 0.1524)
				(type default)
			)
			(layer "F.SilkS")
		)
		(fp_poly
			(pts
				(xy -1.769872 -1.039876) (xy -1.769872 -0.249936) (xy -2.531872 -0.249936) (xy -2.531872 -1.801876)
				(xy -0.999998 -1.801876) (xy -0.999998 -1.039876)
			)
			(stroke
				(width 0)
				(type default)
			)
			(fill yes)
			(layer "F.SilkS")
		)
		(fp_line
			(start -1.769872 1.039876)
			(end 1.769872 1.039876)
			(stroke
				(width 0.1)
				(type default)
			)
			(layer "F.Fab")
		)
		(fp_line
			(start 1.769872 1.039876)
			(end 1.769872 -1.039876)
			(stroke
				(width 0.1)
				(type default)
			)
			(layer "F.Fab")
		)
		(fp_line
			(start -1.769872 -1.039876)
			(end -1.769872 1.039876)
			(stroke
				(width 0.1)
				(type default)
			)
			(layer "F.Fab")
		)
		(fp_line
			(start 1.769872 -1.039876)
			(end -1.769872 -1.039876)
			(stroke
				(width 0.1)
				(type default)
			)
			(layer "F.Fab")
		)
		(fp_poly
			(pts
				(xy -1.769872 -1.039876) (xy -0.999998 -1.039876) (xy -0.999998 -1.801876) (xy -2.531872 -1.801876)
				(xy -2.531872 -0.249936) (xy -1.769872 -0.249936)
			)
			(stroke
				(width 0)
				(type default)
			)
			(fill yes)
			(layer "F.Fab")
		)
		(pad "A1" smd circle
			(at -1.500124 -0.750062 270)
			(size 0.2286 0.2286)
			(layers "F.Cu" "F.Mask" "F.Paste")
			(net "P12V_E1S_SENSE_0")
		)
		(pad "A2" smd circle
			(at -0.999998 -0.750062 270)
			(size 0.2286 0.2286)
			(layers "F.Cu" "F.Mask" "F.Paste")
			(net "P12V_E1S_VCC_0")
		)
		(pad "A3" smd circle
			(at -0.499872 -0.750062 270)
			(size 0.2286 0.2286)
			(layers "F.Cu" "F.Mask" "F.Paste")
			(net "P12V_AUX")
		)
		(pad "A4" smd circle
			(at 0 -0.750062 270)
			(size 0.2286 0.2286)
			(layers "F.Cu" "F.Mask" "F.Paste")
			(net "P12V_E1S_0")
		)
		(pad "A5" smd circle
			(at 0.499872 -0.750062 270)
			(size 0.2286 0.2286)
			(layers "F.Cu" "F.Mask" "F.Paste")
			(net "P12V_AUX")
		)
		(pad "A6" smd circle
			(at 0.999998 -0.750062 270)
			(size 0.2286 0.2286)
			(layers "F.Cu" "F.Mask" "F.Paste")
			(net "P12V_E1S_GATE_0")
		)
		(pad "A7" smd circle
			(at 1.500124 -0.750062 270)
			(size 0.2286 0.2286)
			(layers "F.Cu" "F.Mask" "F.Paste")
			(net "GND")
		)
		(pad "B1" smd circle
			(at -1.500124 -0.249936 270)
			(size 0.2286 0.2286)
			(layers "F.Cu" "F.Mask" "F.Paste")
			(net "P12V_E1S_CB_0")
		)
		(pad "B2" smd circle
			(at -0.999998 -0.249936 270)
			(size 0.2286 0.2286)
			(layers "F.Cu" "F.Mask" "F.Paste")
			(net "GND")
		)
		(pad "B3" smd circle
			(at -0.499872 -0.249936 270)
			(size 0.2286 0.2286)
			(layers "F.Cu" "F.Mask" "F.Paste")
			(net "P12V_AUX")
		)
		(pad "B4" smd circle
			(at 0 -0.249936 270)
			(size 0.2286 0.2286)
			(layers "F.Cu" "F.Mask" "F.Paste")
			(net "P12V_E1S_0")
		)
		(pad "B5" smd circle
			(at 0.499872 -0.249936 270)
			(size 0.2286 0.2286)
			(layers "F.Cu" "F.Mask" "F.Paste")
			(net "P12V_AUX")
		)
		(pad "B6" smd circle
			(at 0.999998 -0.249936 270)
			(size 0.2286 0.2286)
			(layers "F.Cu" "F.Mask" "F.Paste")
			(net "P12V_E1S_0")
		)
		(pad "B7" smd circle
			(at 1.500124 -0.249936 270)
			(size 0.2286 0.2286)
			(layers "F.Cu" "F.Mask" "F.Paste")
			(net "GND")
		)
		(pad "C1" smd circle
			(at -1.500124 0.249936 270)
			(size 0.2286 0.2286)
			(layers "F.Cu" "F.Mask" "F.Paste")
			(net "GND")
		)
		(pad "C2" smd circle
			(at -0.999998 0.249936 270)
			(size 0.2286 0.2286)
			(layers "F.Cu" "F.Mask" "F.Paste")
			(net "GND")
		)
		(pad "C3" smd circle
			(at -0.499872 0.249936 270)
			(size 0.2286 0.2286)
			(layers "F.Cu" "F.Mask" "F.Paste")
			(net "P12V_AUX")
		)
		(pad "C4" smd circle
			(at 0 0.249936 270)
			(size 0.2286 0.2286)
			(layers "F.Cu" "F.Mask" "F.Paste")
			(net "P12V_E1S_0")
		)
		(pad "C5" smd circle
			(at 0.499872 0.249936 270)
			(size 0.2286 0.2286)
			(layers "F.Cu" "F.Mask" "F.Paste")
			(net "P12V_AUX")
		)
		(pad "C6" smd circle
			(at 0.999998 0.249936 270)
			(size 0.2286 0.2286)
			(layers "F.Cu" "F.Mask" "F.Paste")
			(net "P12V_E1S_0")
		)
		(pad "C7" smd circle
			(at 1.500124 0.249936 270)
			(size 0.2286 0.2286)
			(layers "F.Cu" "F.Mask" "F.Paste")
			(net "P12V_E1S_FAULT_0")
		)
		(pad "D1" smd circle
			(at -1.500124 0.750062 270)
			(size 0.2286 0.2286)
			(layers "F.Cu" "F.Mask" "F.Paste")
			(net "P12V_E1S_REG_0")
		)
		(pad "D2" smd circle
			(at -0.999998 0.750062 270)
			(size 0.2286 0.2286)
			(layers "F.Cu" "F.Mask" "F.Paste")
			(net "P12V_E1S_UV_0")
		)
		(pad "D3" smd circle
			(at -0.499872 0.750062 270)
			(size 0.2286 0.2286)
			(layers "F.Cu" "F.Mask" "F.Paste")
			(net "P12V_E1S_OV_0")
		)
		(pad "D4" smd circle
			(at 0 0.750062 270)
			(size 0.2286 0.2286)
			(layers "F.Cu" "F.Mask" "F.Paste")
			(net "P12V_E1S_0")
		)
		(pad "D5" smd circle
			(at 0.499872 0.750062 270)
			(size 0.2286 0.2286)
			(layers "F.Cu" "F.Mask" "F.Paste")
			(net "P12V_AUX")
		)
		(pad "D6" smd circle
			(at 0.999998 0.750062 270)
			(size 0.2286 0.2286)
			(layers "F.Cu" "F.Mask" "F.Paste")
			(net "P12V_E1S_0")
		)
		(pad "D7" smd circle
			(at 1.500124 0.750062 270)
			(size 0.2286 0.2286)
			(layers "F.Cu" "F.Mask" "F.Paste")
			(net "P12V_E1S_PWRGD_0")
		)
	)
	(footprint ""
		(layer "F.Cu")
		(at 176.078388 -417.745418)
		(property "Reference" "C1975"
			(at 0 0 0)
			(layer "F.SilkS")
			(hide yes)
			(effects
				(font
					(size 1.27 1.27)
				)
			)
		)
		(property "Value" ""
			(at 0 0 0)
			(layer "F.Fab")
			(effects
				(font
					(size 1.27 1.27)
				)
			)
		)
		(duplicate_pad_numbers_are_jumpers no)
		(fp_line
			(start -0.7874 -0.4064)
			(end 0.7874 -0.4064)
			(stroke
				(width 0.1524)
				(type default)
			)
			(layer "F.SilkS")
		)
		(fp_line
			(start -0.7874 0.4064)
			(end -0.7874 -0.4064)
			(stroke
				(width 0.1524)
				(type default)
			)
			(layer "F.SilkS")
		)
		(fp_line
			(start 0.7874 -0.4064)
			(end 0.7874 0.4064)
			(stroke
				(width 0.1524)
				(type default)
			)
			(layer "F.SilkS")
		)
		(fp_line
			(start 0.7874 0.4064)
			(end -0.7874 0.4064)
			(stroke
				(width 0.1524)
				(type default)
			)
			(layer "F.SilkS")
		)
		(fp_line
			(start -0.67945 -0.305054)
			(end -0.12065 -0.305054)
			(stroke
				(width 0.1)
				(type default)
			)
			(layer "F.Fab")
		)
		(fp_line
			(start -0.67945 0.3048)
			(end -0.67945 -0.305054)
			(stroke
				(width 0.1)
				(type default)
			)
			(layer "F.Fab")
		)
		(fp_line
			(start -0.12065 -0.305054)
			(end -0.12065 -0.2794)
			(stroke
				(width 0.1)
				(type default)
			)
			(layer "F.Fab")
		)
		(fp_line
			(start -0.12065 -0.2794)
			(end 0.12065 -0.2794)
			(stroke
				(width 0.1)
				(type default)
			)
			(layer "F.Fab")
		)
		(fp_line
			(start -0.12065 0.2794)
			(end -0.12065 0.3048)
			(stroke
				(width 0.1)
				(type default)
			)
			(layer "F.Fab")
		)
		(fp_line
			(start -0.12065 0.3048)
			(end -0.67945 0.3048)
			(stroke
				(width 0.1)
				(type default)
			)
			(layer "F.Fab")
		)
		(fp_line
			(start 0.120396 0.2794)
			(end -0.12065 0.2794)
			(stroke
				(width 0.1)
				(type default)
			)
			(layer "F.Fab")
		)
		(fp_line
			(start 0.120396 0.3048)
			(end 0.120396 0.2794)
			(stroke
				(width 0.1)
				(type default)
			)
			(layer "F.Fab")
		)
		(fp_line
			(start 0.12065 -0.3048)
			(end 0.67945 -0.3048)
			(stroke
				(width 0.1)
				(type default)
			)
			(layer "F.Fab")
		)
		(fp_line
			(start 0.12065 -0.2794)
			(end 0.12065 -0.3048)
			(stroke
				(width 0.1)
				(type default)
			)
			(layer "F.Fab")
		)
		(fp_line
			(start 0.67945 -0.3048)
			(end 0.67945 0.3048)
			(stroke
				(width 0.1)
				(type default)
			)
			(layer "F.Fab")
		)
		(fp_line
			(start 0.67945 0.3048)
			(end 0.120396 0.3048)
			(stroke
				(width 0.1)
				(type default)
			)
			(layer "F.Fab")
		)
		(pad "1" smd circle
			(at -0.40005 0)
			(size 0 0)
			(layers "F.Cu" "F.Mask" "F.Paste")
			(net "GPU_HMC_PRSNT_ISO_N")
		)
		(pad "2" smd circle
			(at 0.40005 0)
			(size 0 0)
			(layers "F.Cu" "F.Mask" "F.Paste")
			(net "GND")
		)
	)
	(footprint ""
		(layer "F.Cu")
		(at 453.054212 -24.619458 180)
		(property "Reference" "PC2088"
			(at 0 0 180)
			(layer "F.SilkS")
			(hide yes)
			(effects
				(font
					(size 1.27 1.27)
				)
			)
		)
		(property "Value" ""
			(at 0 0 180)
			(layer "F.Fab")
			(effects
				(font
					(size 1.27 1.27)
				)
			)
		)
		(duplicate_pad_numbers_are_jumpers no)
		(fp_line
			(start 0.7874 0.4064)
			(end -0.7874 0.4064)
			(stroke
				(width 0.1524)
				(type default)
			)
			(layer "F.SilkS")
		)
		(fp_line
			(start 0.7874 -0.4064)
			(end 0.7874 0.4064)
			(stroke
				(width 0.1524)
				(type default)
			)
			(layer "F.SilkS")
		)
		(fp_line
			(start -0.7874 0.4064)
			(end -0.7874 -0.4064)
			(stroke
				(width 0.1524)
				(type default)
			)
			(layer "F.SilkS")
		)
		(fp_line
			(start -0.7874 -0.4064)
			(end 0.7874 -0.4064)
			(stroke
				(width 0.1524)
				(type default)
			)
			(layer "F.SilkS")
		)
		(fp_line
			(start 0.67945 0.3048)
			(end 0.120396 0.3048)
			(stroke
				(width 0.1)
				(type default)
			)
			(layer "F.Fab")
		)
		(fp_line
			(start 0.67945 -0.3048)
			(end 0.67945 0.3048)
			(stroke
				(width 0.1)
				(type default)
			)
			(layer "F.Fab")
		)
		(fp_line
			(start 0.12065 -0.2794)
			(end 0.12065 -0.3048)
			(stroke
				(width 0.1)
				(type default)
			)
			(layer "F.Fab")
		)
		(fp_line
			(start 0.12065 -0.3048)
			(end 0.67945 -0.3048)
			(stroke
				(width 0.1)
				(type default)
			)
			(layer "F.Fab")
		)
		(fp_line
			(start 0.120396 0.3048)
			(end 0.120396 0.2794)
			(stroke
				(width 0.1)
				(type default)
			)
			(layer "F.Fab")
		)
		(fp_line
			(start 0.120396 0.2794)
			(end -0.12065 0.2794)
			(stroke
				(width 0.1)
				(type default)
			)
			(layer "F.Fab")
		)
		(fp_line
			(start -0.12065 0.3048)
			(end -0.67945 0.3048)
			(stroke
				(width 0.1)
				(type default)
			)
			(layer "F.Fab")
		)
		(fp_line
			(start -0.12065 0.2794)
			(end -0.12065 0.3048)
			(stroke
				(width 0.1)
				(type default)
			)
			(layer "F.Fab")
		)
		(fp_line
			(start -0.12065 -0.2794)
			(end 0.12065 -0.2794)
			(stroke
				(width 0.1)
				(type default)
			)
			(layer "F.Fab")
		)
		(fp_line
			(start -0.12065 -0.305054)
			(end -0.12065 -0.2794)
			(stroke
				(width 0.1)
				(type default)
			)
			(layer "F.Fab")
		)
		(fp_line
			(start -0.67945 0.3048)
			(end -0.67945 -0.305054)
			(stroke
				(width 0.1)
				(type default)
			)
			(layer "F.Fab")
		)
		(fp_line
			(start -0.67945 -0.305054)
			(end -0.12065 -0.305054)
			(stroke
				(width 0.1)
				(type default)
			)
			(layer "F.Fab")
		)
		(pad "1" smd circle
			(at -0.40005 0 180)
			(size 0 0)
			(layers "F.Cu" "F.Mask" "F.Paste")
			(net "P12V_OCP_SFF")
		)
		(pad "2" smd circle
			(at 0.40005 0 180)
			(size 0 0)
			(layers "F.Cu" "F.Mask" "F.Paste")
			(net "P12V_OCP_GATE_1")
		)
	)
	(footprint ""
		(layer "F.Cu")
		(at 320.8401 -76.585064 90)
		(property "Reference" "R2235"
			(at 0 0 90)
			(layer "F.SilkS")
			(hide yes)
			(effects
				(font
					(size 1.27 1.27)
				)
			)
		)
		(property "Value" ""
			(at 0 0 90)
			(layer "F.Fab")
			(effects
				(font
					(size 1.27 1.27)
				)
			)
		)
		(duplicate_pad_numbers_are_jumpers no)
		(fp_line
			(start 0.7874 -0.4064)
			(end 0.7874 0.4064)
			(stroke
				(width 0.1524)
				(type default)
			)
			(layer "F.SilkS")
		)
		(fp_line
			(start -0.7874 -0.4064)
			(end 0.7874 -0.4064)
			(stroke
				(width 0.1524)
				(type default)
			)
			(layer "F.SilkS")
		)
		(fp_line
			(start 0.7874 0.4064)
			(end -0.7874 0.4064)
			(stroke
				(width 0.1524)
				(type default)
			)
			(layer "F.SilkS")
		)
		(fp_line
			(start -0.7874 0.4064)
			(end -0.7874 -0.4064)
			(stroke
				(width 0.1524)
				(type default)
			)
			(layer "F.SilkS")
		)
		(fp_line
			(start -0.12065 -0.305054)
			(end -0.12065 -0.2794)
			(stroke
				(width 0.1)
				(type default)
			)
			(layer "F.Fab")
		)
		(fp_line
			(start -0.67945 -0.305054)
			(end -0.12065 -0.305054)
			(stroke
				(width 0.1)
				(type default)
			)
			(layer "F.Fab")
		)
		(fp_line
			(start 0.67945 -0.3048)
			(end 0.67945 0.3048)
			(stroke
				(width 0.1)
				(type default)
			)
			(layer "F.Fab")
		)
		(fp_line
			(start 0.12065 -0.3048)
			(end 0.67945 -0.3048)
			(stroke
				(width 0.1)
				(type default)
			)
			(layer "F.Fab")
		)
		(fp_line
			(start 0.12065 -0.2794)
			(end 0.12065 -0.3048)
			(stroke
				(width 0.1)
				(type default)
			)
			(layer "F.Fab")
		)
		(fp_line
			(start -0.12065 -0.2794)
			(end 0.12065 -0.2794)
			(stroke
				(width 0.1)
				(type default)
			)
			(layer "F.Fab")
		)
		(fp_line
			(start 0.120396 0.2794)
			(end -0.12065 0.2794)
			(stroke
				(width 0.1)
				(type default)
			)
			(layer "F.Fab")
		)
		(fp_line
			(start -0.12065 0.2794)
			(end -0.12065 0.3048)
			(stroke
				(width 0.1)
				(type default)
			)
			(layer "F.Fab")
		)
		(fp_line
			(start 0.67945 0.3048)
			(end 0.120396 0.3048)
			(stroke
				(width 0.1)
				(type default)
			)
			(layer "F.Fab")
		)
		(fp_line
			(start 0.120396 0.3048)
			(end 0.120396 0.2794)
			(stroke
				(width 0.1)
				(type default)
			)
			(layer "F.Fab")
		)
		(fp_line
			(start -0.12065 0.3048)
			(end -0.67945 0.3048)
			(stroke
				(width 0.1)
				(type default)
			)
			(layer "F.Fab")
		)
		(fp_line
			(start -0.67945 0.3048)
			(end -0.67945 -0.305054)
			(stroke
				(width 0.1)
				(type default)
			)
			(layer "F.Fab")
		)
		(pad "1" smd circle
			(at -0.40005 0 90)
			(size 0 0)
			(layers "F.Cu" "F.Mask" "F.Paste")
			(net "FM_BOARD_SKU_ID4")
		)
		(pad "2" smd circle
			(at 0.40005 0 90)
			(size 0 0)
			(layers "F.Cu" "F.Mask" "F.Paste")
			(net "GND")
		)
	)
	(footprint ""
		(layer "F.Cu")
		(at 369.369848 -358.430576)
		(property "Reference" "PC1251"
			(at 0 0 0)
			(layer "F.SilkS")
			(hide yes)
			(effects
				(font
					(size 1.27 1.27)
				)
			)
		)
		(property "Value" ""
			(at 0 0 0)
			(layer "F.Fab")
			(effects
				(font
					(size 1.27 1.27)
				)
			)
		)
		(duplicate_pad_numbers_are_jumpers no)
		(fp_line
			(start -0.7874 -0.4064)
			(end 0.7874 -0.4064)
			(stroke
				(width 0.1524)
				(type default)
			)
			(layer "F.SilkS")
		)
		(fp_line
			(start -0.7874 0.4064)
			(end -0.7874 -0.4064)
			(stroke
				(width 0.1524)
				(type default)
			)
			(layer "F.SilkS")
		)
		(fp_line
			(start 0.7874 -0.4064)
			(end 0.7874 0.4064)
			(stroke
				(width 0.1524)
				(type default)
			)
			(layer "F.SilkS")
		)
		(fp_line
			(start 0.7874 0.4064)
			(end -0.7874 0.4064)
			(stroke
				(width 0.1524)
				(type default)
			)
			(layer "F.SilkS")
		)
		(fp_line
			(start -0.67945 -0.305054)
			(end -0.12065 -0.305054)
			(stroke
				(width 0.1)
				(type default)
			)
			(layer "F.Fab")
		)
		(fp_line
			(start -0.67945 0.3048)
			(end -0.67945 -0.305054)
			(stroke
				(width 0.1)
				(type default)
			)
			(layer "F.Fab")
		)
		(fp_line
			(start -0.12065 -0.305054)
			(end -0.12065 -0.2794)
			(stroke
				(width 0.1)
				(type default)
			)
			(layer "F.Fab")
		)
		(fp_line
			(start -0.12065 -0.2794)
			(end 0.12065 -0.2794)
			(stroke
				(width 0.1)
				(type default)
			)
			(layer "F.Fab")
		)
		(fp_line
			(start -0.12065 0.2794)
			(end -0.12065 0.3048)
			(stroke
				(width 0.1)
				(type default)
			)
			(layer "F.Fab")
		)
		(fp_line
			(start -0.12065 0.3048)
			(end -0.67945 0.3048)
			(stroke
				(width 0.1)
				(type default)
			)
			(layer "F.Fab")
		)
		(fp_line
			(start 0.120396 0.2794)
			(end -0.12065 0.2794)
			(stroke
				(width 0.1)
				(type default)
			)
			(layer "F.Fab")
		)
		(fp_line
			(start 0.120396 0.3048)
			(end 0.120396 0.2794)
			(stroke
				(width 0.1)
				(type default)
			)
			(layer "F.Fab")
		)
		(fp_line
			(start 0.12065 -0.3048)
			(end 0.67945 -0.3048)
			(stroke
				(width 0.1)
				(type default)
			)
			(layer "F.Fab")
		)
		(fp_line
			(start 0.12065 -0.2794)
			(end 0.12065 -0.3048)
			(stroke
				(width 0.1)
				(type default)
			)
			(layer "F.Fab")
		)
		(fp_line
			(start 0.67945 -0.3048)
			(end 0.67945 0.3048)
			(stroke
				(width 0.1)
				(type default)
			)
			(layer "F.Fab")
		)
		(fp_line
			(start 0.67945 0.3048)
			(end 0.120396 0.3048)
			(stroke
				(width 0.1)
				(type default)
			)
			(layer "F.Fab")
		)
		(pad "1" smd circle
			(at -0.40005 0)
			(size 0 0)
			(layers "F.Cu" "F.Mask" "F.Paste")
			(net "PVPP_HBM_CPU0_REF")
		)
		(pad "2" smd circle
			(at 0.40005 0)
			(size 0 0)
			(layers "F.Cu" "F.Mask" "F.Paste")
			(net "SH_PVPP_HBM_CPU0_N")
		)
	)
	(footprint ""
		(layer "F.Cu")
		(at 140.70838 -32.458152 180)
		(property "Reference" "R3307"
			(at 0 0 180)
			(layer "F.SilkS")
			(hide yes)
			(effects
				(font
					(size 1.27 1.27)
				)
			)
		)
		(property "Value" ""
			(at 0 0 180)
			(layer "F.Fab")
			(effects
				(font
					(size 1.27 1.27)
				)
			)
		)
		(duplicate_pad_numbers_are_jumpers no)
		(fp_line
			(start 0.7874 0.4064)
			(end -0.7874 0.4064)
			(stroke
				(width 0.1524)
				(type default)
			)
			(layer "F.SilkS")
		)
		(fp_line
			(start 0.7874 -0.4064)
			(end 0.7874 0.4064)
			(stroke
				(width 0.1524)
				(type default)
			)
			(layer "F.SilkS")
		)
		(fp_line
			(start -0.7874 0.4064)
			(end -0.7874 -0.4064)
			(stroke
				(width 0.1524)
				(type default)
			)
			(layer "F.SilkS")
		)
		(fp_line
			(start -0.7874 -0.4064)
			(end 0.7874 -0.4064)
			(stroke
				(width 0.1524)
				(type default)
			)
			(layer "F.SilkS")
		)
		(fp_line
			(start 0.67945 0.3048)
			(end 0.120396 0.3048)
			(stroke
				(width 0.1)
				(type default)
			)
			(layer "F.Fab")
		)
		(fp_line
			(start 0.67945 -0.3048)
			(end 0.67945 0.3048)
			(stroke
				(width 0.1)
				(type default)
			)
			(layer "F.Fab")
		)
		(fp_line
			(start 0.12065 -0.2794)
			(end 0.12065 -0.3048)
			(stroke
				(width 0.1)
				(type default)
			)
			(layer "F.Fab")
		)
		(fp_line
			(start 0.12065 -0.3048)
			(end 0.67945 -0.3048)
			(stroke
				(width 0.1)
				(type default)
			)
			(layer "F.Fab")
		)
		(fp_line
			(start 0.120396 0.3048)
			(end 0.120396 0.2794)
			(stroke
				(width 0.1)
				(type default)
			)
			(layer "F.Fab")
		)
		(fp_line
			(start 0.120396 0.2794)
			(end -0.12065 0.2794)
			(stroke
				(width 0.1)
				(type default)
			)
			(layer "F.Fab")
		)
		(fp_line
			(start -0.12065 0.3048)
			(end -0.67945 0.3048)
			(stroke
				(width 0.1)
				(type default)
			)
			(layer "F.Fab")
		)
		(fp_line
			(start -0.12065 0.2794)
			(end -0.12065 0.3048)
			(stroke
				(width 0.1)
				(type default)
			)
			(layer "F.Fab")
		)
		(fp_line
			(start -0.12065 -0.2794)
			(end 0.12065 -0.2794)
			(stroke
				(width 0.1)
				(type default)
			)
			(layer "F.Fab")
		)
		(fp_line
			(start -0.12065 -0.305054)
			(end -0.12065 -0.2794)
			(stroke
				(width 0.1)
				(type default)
			)
			(layer "F.Fab")
		)
		(fp_line
			(start -0.67945 0.3048)
			(end -0.67945 -0.305054)
			(stroke
				(width 0.1)
				(type default)
			)
			(layer "F.Fab")
		)
		(fp_line
			(start -0.67945 -0.305054)
			(end -0.12065 -0.305054)
			(stroke
				(width 0.1)
				(type default)
			)
			(layer "F.Fab")
		)
		(pad "1" smd circle
			(at -0.40005 0 180)
			(size 0 0)
			(layers "F.Cu" "F.Mask" "F.Paste")
			(net "OCP_SFF_RBT_ARB_IN_MUX2")
		)
		(pad "2" smd circle
			(at 0.40005 0 180)
			(size 0 0)
			(layers "F.Cu" "F.Mask" "F.Paste")
			(net "OCP_SFF_RBT_ARB_IN_MUX2_R")
		)
	)
	(footprint ""
		(layer "F.Cu")
		(at 49.755552 -163.822634 90)
		(property "Reference" "PR1746"
			(at 0 0 90)
			(layer "F.SilkS")
			(hide yes)
			(effects
				(font
					(size 1.27 1.27)
				)
			)
		)
		(property "Value" ""
			(at 0 0 90)
			(layer "F.Fab")
			(effects
				(font
					(size 1.27 1.27)
				)
			)
		)
		(duplicate_pad_numbers_are_jumpers no)
		(fp_line
			(start 0.7874 -0.4064)
			(end 0.7874 0.4064)
			(stroke
				(width 0.1524)
				(type default)
			)
			(layer "F.SilkS")
		)
		(fp_line
			(start -0.7874 -0.4064)
			(end 0.7874 -0.4064)
			(stroke
				(width 0.1524)
				(type default)
			)
			(layer "F.SilkS")
		)
		(fp_line
			(start 0.7874 0.4064)
			(end -0.7874 0.4064)
			(stroke
				(width 0.1524)
				(type default)
			)
			(layer "F.SilkS")
		)
		(fp_line
			(start -0.7874 0.4064)
			(end -0.7874 -0.4064)
			(stroke
				(width 0.1524)
				(type default)
			)
			(layer "F.SilkS")
		)
		(fp_line
			(start -0.12065 -0.305054)
			(end -0.12065 -0.2794)
			(stroke
				(width 0.1)
				(type default)
			)
			(layer "F.Fab")
		)
		(fp_line
			(start -0.67945 -0.305054)
			(end -0.12065 -0.305054)
			(stroke
				(width 0.1)
				(type default)
			)
			(layer "F.Fab")
		)
		(fp_line
			(start 0.67945 -0.3048)
			(end 0.67945 0.3048)
			(stroke
				(width 0.1)
				(type default)
			)
			(layer "F.Fab")
		)
		(fp_line
			(start 0.12065 -0.3048)
			(end 0.67945 -0.3048)
			(stroke
				(width 0.1)
				(type default)
			)
			(layer "F.Fab")
		)
		(fp_line
			(start 0.12065 -0.2794)
			(end 0.12065 -0.3048)
			(stroke
				(width 0.1)
				(type default)
			)
			(layer "F.Fab")
		)
		(fp_line
			(start -0.12065 -0.2794)
			(end 0.12065 -0.2794)
			(stroke
				(width 0.1)
				(type default)
			)
			(layer "F.Fab")
		)
		(fp_line
			(start 0.120396 0.2794)
			(end -0.12065 0.2794)
			(stroke
				(width 0.1)
				(type default)
			)
			(layer "F.Fab")
		)
		(fp_line
			(start -0.12065 0.2794)
			(end -0.12065 0.3048)
			(stroke
				(width 0.1)
				(type default)
			)
			(layer "F.Fab")
		)
		(fp_line
			(start 0.67945 0.3048)
			(end 0.120396 0.3048)
			(stroke
				(width 0.1)
				(type default)
			)
			(layer "F.Fab")
		)
		(fp_line
			(start 0.120396 0.3048)
			(end 0.120396 0.2794)
			(stroke
				(width 0.1)
				(type default)
			)
			(layer "F.Fab")
		)
		(fp_line
			(start -0.12065 0.3048)
			(end -0.67945 0.3048)
			(stroke
				(width 0.1)
				(type default)
			)
			(layer "F.Fab")
		)
		(fp_line
			(start -0.67945 0.3048)
			(end -0.67945 -0.305054)
			(stroke
				(width 0.1)
				(type default)
			)
			(layer "F.Fab")
		)
		(pad "1" smd circle
			(at -0.40005 0 90)
			(size 0 0)
			(layers "F.Cu" "F.Mask" "F.Paste")
			(net "PVCCD_HV_CPU1_LSET1")
		)
		(pad "2" smd circle
			(at 0.40005 0 90)
			(size 0 0)
			(layers "F.Cu" "F.Mask" "F.Paste")
			(net "GND")
		)
	)
	(footprint ""
		(layer "F.Cu")
		(at 150.67788 -45.938948 90)
		(property "Reference" "R3595"
			(at 0 0 90)
			(layer "F.SilkS")
			(hide yes)
			(effects
				(font
					(size 1.27 1.27)
				)
			)
		)
		(property "Value" ""
			(at 0 0 90)
			(layer "F.Fab")
			(effects
				(font
					(size 1.27 1.27)
				)
			)
		)
		(duplicate_pad_numbers_are_jumpers no)
		(fp_line
			(start 0.7874 -0.4064)
			(end 0.7874 0.4064)
			(stroke
				(width 0.1524)
				(type default)
			)
			(layer "F.SilkS")
		)
		(fp_line
			(start -0.7874 -0.4064)
			(end 0.7874 -0.4064)
			(stroke
				(width 0.1524)
				(type default)
			)
			(layer "F.SilkS")
		)
		(fp_line
			(start 0.7874 0.4064)
			(end -0.7874 0.4064)
			(stroke
				(width 0.1524)
				(type default)
			)
			(layer "F.SilkS")
		)
		(fp_line
			(start -0.7874 0.4064)
			(end -0.7874 -0.4064)
			(stroke
				(width 0.1524)
				(type default)
			)
			(layer "F.SilkS")
		)
		(fp_line
			(start -0.12065 -0.305054)
			(end -0.12065 -0.2794)
			(stroke
				(width 0.1)
				(type default)
			)
			(layer "F.Fab")
		)
		(fp_line
			(start -0.67945 -0.305054)
			(end -0.12065 -0.305054)
			(stroke
				(width 0.1)
				(type default)
			)
			(layer "F.Fab")
		)
		(fp_line
			(start 0.67945 -0.3048)
			(end 0.67945 0.3048)
			(stroke
				(width 0.1)
				(type default)
			)
			(layer "F.Fab")
		)
		(fp_line
			(start 0.12065 -0.3048)
			(end 0.67945 -0.3048)
			(stroke
				(width 0.1)
				(type default)
			)
			(layer "F.Fab")
		)
		(fp_line
			(start 0.12065 -0.2794)
			(end 0.12065 -0.3048)
			(stroke
				(width 0.1)
				(type default)
			)
			(layer "F.Fab")
		)
		(fp_line
			(start -0.12065 -0.2794)
			(end 0.12065 -0.2794)
			(stroke
				(width 0.1)
				(type default)
			)
			(layer "F.Fab")
		)
		(fp_line
			(start 0.120396 0.2794)
			(end -0.12065 0.2794)
			(stroke
				(width 0.1)
				(type default)
			)
			(layer "F.Fab")
		)
		(fp_line
			(start -0.12065 0.2794)
			(end -0.12065 0.3048)
			(stroke
				(width 0.1)
				(type default)
			)
			(layer "F.Fab")
		)
		(fp_line
			(start 0.67945 0.3048)
			(end 0.120396 0.3048)
			(stroke
				(width 0.1)
				(type default)
			)
			(layer "F.Fab")
		)
		(fp_line
			(start 0.120396 0.3048)
			(end 0.120396 0.2794)
			(stroke
				(width 0.1)
				(type default)
			)
			(layer "F.Fab")
		)
		(fp_line
			(start -0.12065 0.3048)
			(end -0.67945 0.3048)
			(stroke
				(width 0.1)
				(type default)
			)
			(layer "F.Fab")
		)
		(fp_line
			(start -0.67945 0.3048)
			(end -0.67945 -0.305054)
			(stroke
				(width 0.1)
				(type default)
			)
			(layer "F.Fab")
		)
		(pad "1" smd circle
			(at -0.40005 0 90)
			(size 0 0)
			(layers "F.Cu" "F.Mask" "F.Paste")
			(net "SMB_INA230_3V3AUX_SDA")
		)
		(pad "2" smd circle
			(at 0.40005 0 90)
			(size 0 0)
			(layers "F.Cu" "F.Mask" "F.Paste")
			(net "SMB_INA230_4_3V3AUX_SDA_R")
		)
	)
	(footprint ""
		(layer "F.Cu")
		(at 31.29788 -425.287948)
		(property "Reference" "R3391"
			(at 0 0 0)
			(layer "F.SilkS")
			(hide yes)
			(effects
				(font
					(size 1.27 1.27)
				)
			)
		)
		(property "Value" ""
			(at 0 0 0)
			(layer "F.Fab")
			(effects
				(font
					(size 1.27 1.27)
				)
			)
		)
		(duplicate_pad_numbers_are_jumpers no)
		(fp_line
			(start -0.7874 -0.4064)
			(end 0.7874 -0.4064)
			(stroke
				(width 0.1524)
				(type default)
			)
			(layer "F.SilkS")
		)
		(fp_line
			(start -0.7874 0.4064)
			(end -0.7874 -0.4064)
			(stroke
				(width 0.1524)
				(type default)
			)
			(layer "F.SilkS")
		)
		(fp_line
			(start 0.7874 -0.4064)
			(end 0.7874 0.4064)
			(stroke
				(width 0.1524)
				(type default)
			)
			(layer "F.SilkS")
		)
		(fp_line
			(start 0.7874 0.4064)
			(end -0.7874 0.4064)
			(stroke
				(width 0.1524)
				(type default)
			)
			(layer "F.SilkS")
		)
		(fp_line
			(start -0.67945 -0.305054)
			(end -0.12065 -0.305054)
			(stroke
				(width 0.1)
				(type default)
			)
			(layer "F.Fab")
		)
		(fp_line
			(start -0.67945 0.3048)
			(end -0.67945 -0.305054)
			(stroke
				(width 0.1)
				(type default)
			)
			(layer "F.Fab")
		)
		(fp_line
			(start -0.12065 -0.305054)
			(end -0.12065 -0.2794)
			(stroke
				(width 0.1)
				(type default)
			)
			(layer "F.Fab")
		)
		(fp_line
			(start -0.12065 -0.2794)
			(end 0.12065 -0.2794)
			(stroke
				(width 0.1)
				(type default)
			)
			(layer "F.Fab")
		)
		(fp_line
			(start -0.12065 0.2794)
			(end -0.12065 0.3048)
			(stroke
				(width 0.1)
				(type default)
			)
			(layer "F.Fab")
		)
		(fp_line
			(start -0.12065 0.3048)
			(end -0.67945 0.3048)
			(stroke
				(width 0.1)
				(type default)
			)
			(layer "F.Fab")
		)
		(fp_line
			(start 0.120396 0.2794)
			(end -0.12065 0.2794)
			(stroke
				(width 0.1)
				(type default)
			)
			(layer "F.Fab")
		)
		(fp_line
			(start 0.120396 0.3048)
			(end 0.120396 0.2794)
			(stroke
				(width 0.1)
				(type default)
			)
			(layer "F.Fab")
		)
		(fp_line
			(start 0.12065 -0.3048)
			(end 0.67945 -0.3048)
			(stroke
				(width 0.1)
				(type default)
			)
			(layer "F.Fab")
		)
		(fp_line
			(start 0.12065 -0.2794)
			(end 0.12065 -0.3048)
			(stroke
				(width 0.1)
				(type default)
			)
			(layer "F.Fab")
		)
		(fp_line
			(start 0.67945 -0.3048)
			(end 0.67945 0.3048)
			(stroke
				(width 0.1)
				(type default)
			)
			(layer "F.Fab")
		)
		(fp_line
			(start 0.67945 0.3048)
			(end 0.120396 0.3048)
			(stroke
				(width 0.1)
				(type default)
			)
			(layer "F.Fab")
		)
		(pad "1" smd circle
			(at -0.40005 0)
			(size 0 0)
			(layers "F.Cu" "F.Mask" "F.Paste")
			(net "RST_PERST_1_SWB_BUF_R_N")
		)
		(pad "2" smd circle
			(at 0.40005 0)
			(size 0 0)
			(layers "F.Cu" "F.Mask" "F.Paste")
			(net "RST_PERST_1_SWB_BUF_N")
		)
	)
	(footprint ""
		(layer "F.Cu")
		(at 351.961704 -353.14509)
		(property "Reference" "PR170"
			(at 0 0 0)
			(layer "F.SilkS")
			(hide yes)
			(effects
				(font
					(size 1.27 1.27)
				)
			)
		)
		(property "Value" ""
			(at 0 0 0)
			(layer "F.Fab")
			(effects
				(font
					(size 1.27 1.27)
				)
			)
		)
		(duplicate_pad_numbers_are_jumpers no)
		(fp_line
			(start -0.7874 -0.4064)
			(end 0.7874 -0.4064)
			(stroke
				(width 0.1524)
				(type default)
			)
			(layer "F.SilkS")
		)
		(fp_line
			(start -0.7874 0.4064)
			(end -0.7874 -0.4064)
			(stroke
				(width 0.1524)
				(type default)
			)
			(layer "F.SilkS")
		)
		(fp_line
			(start 0.7874 -0.4064)
			(end 0.7874 0.4064)
			(stroke
				(width 0.1524)
				(type default)
			)
			(layer "F.SilkS")
		)
		(fp_line
			(start 0.7874 0.4064)
			(end -0.7874 0.4064)
			(stroke
				(width 0.1524)
				(type default)
			)
			(layer "F.SilkS")
		)
		(fp_line
			(start -0.67945 -0.305054)
			(end -0.12065 -0.305054)
			(stroke
				(width 0.1)
				(type default)
			)
			(layer "F.Fab")
		)
		(fp_line
			(start -0.67945 0.3048)
			(end -0.67945 -0.305054)
			(stroke
				(width 0.1)
				(type default)
			)
			(layer "F.Fab")
		)
		(fp_line
			(start -0.12065 -0.305054)
			(end -0.12065 -0.2794)
			(stroke
				(width 0.1)
				(type default)
			)
			(layer "F.Fab")
		)
		(fp_line
			(start -0.12065 -0.2794)
			(end 0.12065 -0.2794)
			(stroke
				(width 0.1)
				(type default)
			)
			(layer "F.Fab")
		)
		(fp_line
			(start -0.12065 0.2794)
			(end -0.12065 0.3048)
			(stroke
				(width 0.1)
				(type default)
			)
			(layer "F.Fab")
		)
		(fp_line
			(start -0.12065 0.3048)
			(end -0.67945 0.3048)
			(stroke
				(width 0.1)
				(type default)
			)
			(layer "F.Fab")
		)
		(fp_line
			(start 0.120396 0.2794)
			(end -0.12065 0.2794)
			(stroke
				(width 0.1)
				(type default)
			)
			(layer "F.Fab")
		)
		(fp_line
			(start 0.120396 0.3048)
			(end 0.120396 0.2794)
			(stroke
				(width 0.1)
				(type default)
			)
			(layer "F.Fab")
		)
		(fp_line
			(start 0.12065 -0.3048)
			(end 0.67945 -0.3048)
			(stroke
				(width 0.1)
				(type default)
			)
			(layer "F.Fab")
		)
		(fp_line
			(start 0.12065 -0.2794)
			(end 0.12065 -0.3048)
			(stroke
				(width 0.1)
				(type default)
			)
			(layer "F.Fab")
		)
		(fp_line
			(start 0.67945 -0.3048)
			(end 0.67945 0.3048)
			(stroke
				(width 0.1)
				(type default)
			)
			(layer "F.Fab")
		)
		(fp_line
			(start 0.67945 0.3048)
			(end 0.120396 0.3048)
			(stroke
				(width 0.1)
				(type default)
			)
			(layer "F.Fab")
		)
		(pad "1" smd circle
			(at -0.40005 0)
			(size 0 0)
			(layers "F.Cu" "F.Mask" "F.Paste")
			(net "SH_PVCCIN_CPU0")
		)
		(pad "2" smd circle
			(at 0.40005 0)
			(size 0 0)
			(layers "F.Cu" "F.Mask" "F.Paste")
			(net "SH_PVCCIN_CPU0_R")
		)
	)
	(footprint ""
		(layer "F.Cu")
		(at 147.08378 -126.291848 180)
		(property "Reference" "R3157"
			(at 0 0 180)
			(layer "F.SilkS")
			(hide yes)
			(effects
				(font
					(size 1.27 1.27)
				)
			)
		)
		(property "Value" ""
			(at 0 0 180)
			(layer "F.Fab")
			(effects
				(font
					(size 1.27 1.27)
				)
			)
		)
		(duplicate_pad_numbers_are_jumpers no)
		(fp_line
			(start 0.7874 0.4064)
			(end -0.7874 0.4064)
			(stroke
				(width 0.1524)
				(type default)
			)
			(layer "F.SilkS")
		)
		(fp_line
			(start 0.7874 -0.4064)
			(end 0.7874 0.4064)
			(stroke
				(width 0.1524)
				(type default)
			)
			(layer "F.SilkS")
		)
		(fp_line
			(start -0.7874 0.4064)
			(end -0.7874 -0.4064)
			(stroke
				(width 0.1524)
				(type default)
			)
			(layer "F.SilkS")
		)
		(fp_line
			(start -0.7874 -0.4064)
			(end 0.7874 -0.4064)
			(stroke
				(width 0.1524)
				(type default)
			)
			(layer "F.SilkS")
		)
		(fp_line
			(start 0.67945 0.3048)
			(end 0.120396 0.3048)
			(stroke
				(width 0.1)
				(type default)
			)
			(layer "F.Fab")
		)
		(fp_line
			(start 0.67945 -0.3048)
			(end 0.67945 0.3048)
			(stroke
				(width 0.1)
				(type default)
			)
			(layer "F.Fab")
		)
		(fp_line
			(start 0.12065 -0.2794)
			(end 0.12065 -0.3048)
			(stroke
				(width 0.1)
				(type default)
			)
			(layer "F.Fab")
		)
		(fp_line
			(start 0.12065 -0.3048)
			(end 0.67945 -0.3048)
			(stroke
				(width 0.1)
				(type default)
			)
			(layer "F.Fab")
		)
		(fp_line
			(start 0.120396 0.3048)
			(end 0.120396 0.2794)
			(stroke
				(width 0.1)
				(type default)
			)
			(layer "F.Fab")
		)
		(fp_line
			(start 0.120396 0.2794)
			(end -0.12065 0.2794)
			(stroke
				(width 0.1)
				(type default)
			)
			(layer "F.Fab")
		)
		(fp_line
			(start -0.12065 0.3048)
			(end -0.67945 0.3048)
			(stroke
				(width 0.1)
				(type default)
			)
			(layer "F.Fab")
		)
		(fp_line
			(start -0.12065 0.2794)
			(end -0.12065 0.3048)
			(stroke
				(width 0.1)
				(type default)
			)
			(layer "F.Fab")
		)
		(fp_line
			(start -0.12065 -0.2794)
			(end 0.12065 -0.2794)
			(stroke
				(width 0.1)
				(type default)
			)
			(layer "F.Fab")
		)
		(fp_line
			(start -0.12065 -0.305054)
			(end -0.12065 -0.2794)
			(stroke
				(width 0.1)
				(type default)
			)
			(layer "F.Fab")
		)
		(fp_line
			(start -0.67945 0.3048)
			(end -0.67945 -0.305054)
			(stroke
				(width 0.1)
				(type default)
			)
			(layer "F.Fab")
		)
		(fp_line
			(start -0.67945 -0.305054)
			(end -0.12065 -0.305054)
			(stroke
				(width 0.1)
				(type default)
			)
			(layer "F.Fab")
		)
		(pad "1" smd circle
			(at -0.40005 0 180)
			(size 0 0)
			(layers "F.Cu" "F.Mask" "F.Paste")
			(net "SMB_PEHPCPU1_LVC3_SDA")
		)
		(pad "2" smd circle
			(at 0.40005 0 180)
			(size 0 0)
			(layers "F.Cu" "F.Mask" "F.Paste")
			(net "SMB_PEHPCPU1_LVC3_R3_SDA")
		)
	)
	(footprint ""
		(layer "F.Cu")
		(at 220.100652 -105.226104 180)
		(property "Reference" "R2236"
			(at 0 0 180)
			(layer "F.SilkS")
			(hide yes)
			(effects
				(font
					(size 1.27 1.27)
				)
			)
		)
		(property "Value" ""
			(at 0 0 180)
			(layer "F.Fab")
			(effects
				(font
					(size 1.27 1.27)
				)
			)
		)
		(duplicate_pad_numbers_are_jumpers no)
		(fp_line
			(start 0.7874 0.4064)
			(end -0.7874 0.4064)
			(stroke
				(width 0.1524)
				(type default)
			)
			(layer "F.SilkS")
		)
		(fp_line
			(start 0.7874 -0.4064)
			(end 0.7874 0.4064)
			(stroke
				(width 0.1524)
				(type default)
			)
			(layer "F.SilkS")
		)
		(fp_line
			(start -0.7874 0.4064)
			(end -0.7874 -0.4064)
			(stroke
				(width 0.1524)
				(type default)
			)
			(layer "F.SilkS")
		)
		(fp_line
			(start -0.7874 -0.4064)
			(end 0.7874 -0.4064)
			(stroke
				(width 0.1524)
				(type default)
			)
			(layer "F.SilkS")
		)
		(fp_line
			(start 0.67945 0.3048)
			(end 0.120396 0.3048)
			(stroke
				(width 0.1)
				(type default)
			)
			(layer "F.Fab")
		)
		(fp_line
			(start 0.67945 -0.3048)
			(end 0.67945 0.3048)
			(stroke
				(width 0.1)
				(type default)
			)
			(layer "F.Fab")
		)
		(fp_line
			(start 0.12065 -0.2794)
			(end 0.12065 -0.3048)
			(stroke
				(width 0.1)
				(type default)
			)
			(layer "F.Fab")
		)
		(fp_line
			(start 0.12065 -0.3048)
			(end 0.67945 -0.3048)
			(stroke
				(width 0.1)
				(type default)
			)
			(layer "F.Fab")
		)
		(fp_line
			(start 0.120396 0.3048)
			(end 0.120396 0.2794)
			(stroke
				(width 0.1)
				(type default)
			)
			(layer "F.Fab")
		)
		(fp_line
			(start 0.120396 0.2794)
			(end -0.12065 0.2794)
			(stroke
				(width 0.1)
				(type default)
			)
			(layer "F.Fab")
		)
		(fp_line
			(start -0.12065 0.3048)
			(end -0.67945 0.3048)
			(stroke
				(width 0.1)
				(type default)
			)
			(layer "F.Fab")
		)
		(fp_line
			(start -0.12065 0.2794)
			(end -0.12065 0.3048)
			(stroke
				(width 0.1)
				(type default)
			)
			(layer "F.Fab")
		)
		(fp_line
			(start -0.12065 -0.2794)
			(end 0.12065 -0.2794)
			(stroke
				(width 0.1)
				(type default)
			)
			(layer "F.Fab")
		)
		(fp_line
			(start -0.12065 -0.305054)
			(end -0.12065 -0.2794)
			(stroke
				(width 0.1)
				(type default)
			)
			(layer "F.Fab")
		)
		(fp_line
			(start -0.67945 0.3048)
			(end -0.67945 -0.305054)
			(stroke
				(width 0.1)
				(type default)
			)
			(layer "F.Fab")
		)
		(fp_line
			(start -0.67945 -0.305054)
			(end -0.12065 -0.305054)
			(stroke
				(width 0.1)
				(type default)
			)
			(layer "F.Fab")
		)
		(pad "1" smd circle
			(at -0.40005 0 180)
			(size 0 0)
			(layers "F.Cu" "F.Mask" "F.Paste")
			(net "P12V_AUX")
		)
		(pad "2" smd circle
			(at 0.40005 0 180)
			(size 0 0)
			(layers "F.Cu" "F.Mask" "F.Paste")
			(net "A_HSC_INAP")
		)
	)
	(footprint ""
		(layer "F.Cu")
		(at 120.714008 -66.67754 90)
		(property "Reference" "R805"
			(at 0 0 90)
			(layer "F.SilkS")
			(hide yes)
			(effects
				(font
					(size 1.27 1.27)
				)
			)
		)
		(property "Value" ""
			(at 0 0 90)
			(layer "F.Fab")
			(effects
				(font
					(size 1.27 1.27)
				)
			)
		)
		(duplicate_pad_numbers_are_jumpers no)
		(fp_line
			(start 0.7874 -0.4064)
			(end 0.7874 0.4064)
			(stroke
				(width 0.1524)
				(type default)
			)
			(layer "F.SilkS")
		)
		(fp_line
			(start -0.7874 -0.4064)
			(end 0.7874 -0.4064)
			(stroke
				(width 0.1524)
				(type default)
			)
			(layer "F.SilkS")
		)
		(fp_line
			(start 0.7874 0.4064)
			(end -0.7874 0.4064)
			(stroke
				(width 0.1524)
				(type default)
			)
			(layer "F.SilkS")
		)
		(fp_line
			(start -0.7874 0.4064)
			(end -0.7874 -0.4064)
			(stroke
				(width 0.1524)
				(type default)
			)
			(layer "F.SilkS")
		)
		(fp_line
			(start -0.12065 -0.305054)
			(end -0.12065 -0.2794)
			(stroke
				(width 0.1)
				(type default)
			)
			(layer "F.Fab")
		)
		(fp_line
			(start -0.67945 -0.305054)
			(end -0.12065 -0.305054)
			(stroke
				(width 0.1)
				(type default)
			)
			(layer "F.Fab")
		)
		(fp_line
			(start 0.67945 -0.3048)
			(end 0.67945 0.3048)
			(stroke
				(width 0.1)
				(type default)
			)
			(layer "F.Fab")
		)
		(fp_line
			(start 0.12065 -0.3048)
			(end 0.67945 -0.3048)
			(stroke
				(width 0.1)
				(type default)
			)
			(layer "F.Fab")
		)
		(fp_line
			(start 0.12065 -0.2794)
			(end 0.12065 -0.3048)
			(stroke
				(width 0.1)
				(type default)
			)
			(layer "F.Fab")
		)
		(fp_line
			(start -0.12065 -0.2794)
			(end 0.12065 -0.2794)
			(stroke
				(width 0.1)
				(type default)
			)
			(layer "F.Fab")
		)
		(fp_line
			(start 0.120396 0.2794)
			(end -0.12065 0.2794)
			(stroke
				(width 0.1)
				(type default)
			)
			(layer "F.Fab")
		)
		(fp_line
			(start -0.12065 0.2794)
			(end -0.12065 0.3048)
			(stroke
				(width 0.1)
				(type default)
			)
			(layer "F.Fab")
		)
		(fp_line
			(start 0.67945 0.3048)
			(end 0.120396 0.3048)
			(stroke
				(width 0.1)
				(type default)
			)
			(layer "F.Fab")
		)
		(fp_line
			(start 0.120396 0.3048)
			(end 0.120396 0.2794)
			(stroke
				(width 0.1)
				(type default)
			)
			(layer "F.Fab")
		)
		(fp_line
			(start -0.12065 0.3048)
			(end -0.67945 0.3048)
			(stroke
				(width 0.1)
				(type default)
			)
			(layer "F.Fab")
		)
		(fp_line
			(start -0.67945 0.3048)
			(end -0.67945 -0.305054)
			(stroke
				(width 0.1)
				(type default)
			)
			(layer "F.Fab")
		)
		(pad "1" smd circle
			(at -0.40005 0 90)
			(size 0 0)
			(layers "F.Cu" "F.Mask" "F.Paste")
			(net "JTAG_PLD_TMS_R")
		)
		(pad "2" smd circle
			(at 0.40005 0 90)
			(size 0 0)
			(layers "F.Cu" "F.Mask" "F.Paste")
			(net "JTAG_BMC_PLD_TMS")
		)
	)
	(footprint ""
		(layer "F.Cu")
		(at 443.576964 -72.398128 90)
		(property "Reference" "PR389"
			(at 0 0 90)
			(layer "F.SilkS")
			(hide yes)
			(effects
				(font
					(size 1.27 1.27)
				)
			)
		)
		(property "Value" ""
			(at 0 0 90)
			(layer "F.Fab")
			(effects
				(font
					(size 1.27 1.27)
				)
			)
		)
		(duplicate_pad_numbers_are_jumpers no)
		(fp_line
			(start 0.7874 -0.4064)
			(end 0.7874 0.4064)
			(stroke
				(width 0.1524)
				(type default)
			)
			(layer "F.SilkS")
		)
		(fp_line
			(start -0.7874 -0.4064)
			(end 0.7874 -0.4064)
			(stroke
				(width 0.1524)
				(type default)
			)
			(layer "F.SilkS")
		)
		(fp_line
			(start 0.7874 0.4064)
			(end -0.7874 0.4064)
			(stroke
				(width 0.1524)
				(type default)
			)
			(layer "F.SilkS")
		)
		(fp_line
			(start -0.7874 0.4064)
			(end -0.7874 -0.4064)
			(stroke
				(width 0.1524)
				(type default)
			)
			(layer "F.SilkS")
		)
		(fp_line
			(start -0.12065 -0.305054)
			(end -0.12065 -0.2794)
			(stroke
				(width 0.1)
				(type default)
			)
			(layer "F.Fab")
		)
		(fp_line
			(start -0.67945 -0.305054)
			(end -0.12065 -0.305054)
			(stroke
				(width 0.1)
				(type default)
			)
			(layer "F.Fab")
		)
		(fp_line
			(start 0.67945 -0.3048)
			(end 0.67945 0.3048)
			(stroke
				(width 0.1)
				(type default)
			)
			(layer "F.Fab")
		)
		(fp_line
			(start 0.12065 -0.3048)
			(end 0.67945 -0.3048)
			(stroke
				(width 0.1)
				(type default)
			)
			(layer "F.Fab")
		)
		(fp_line
			(start 0.12065 -0.2794)
			(end 0.12065 -0.3048)
			(stroke
				(width 0.1)
				(type default)
			)
			(layer "F.Fab")
		)
		(fp_line
			(start -0.12065 -0.2794)
			(end 0.12065 -0.2794)
			(stroke
				(width 0.1)
				(type default)
			)
			(layer "F.Fab")
		)
		(fp_line
			(start 0.120396 0.2794)
			(end -0.12065 0.2794)
			(stroke
				(width 0.1)
				(type default)
			)
			(layer "F.Fab")
		)
		(fp_line
			(start -0.12065 0.2794)
			(end -0.12065 0.3048)
			(stroke
				(width 0.1)
				(type default)
			)
			(layer "F.Fab")
		)
		(fp_line
			(start 0.67945 0.3048)
			(end 0.120396 0.3048)
			(stroke
				(width 0.1)
				(type default)
			)
			(layer "F.Fab")
		)
		(fp_line
			(start 0.120396 0.3048)
			(end 0.120396 0.2794)
			(stroke
				(width 0.1)
				(type default)
			)
			(layer "F.Fab")
		)
		(fp_line
			(start -0.12065 0.3048)
			(end -0.67945 0.3048)
			(stroke
				(width 0.1)
				(type default)
			)
			(layer "F.Fab")
		)
		(fp_line
			(start -0.67945 0.3048)
			(end -0.67945 -0.305054)
			(stroke
				(width 0.1)
				(type default)
			)
			(layer "F.Fab")
		)
		(pad "1" smd circle
			(at -0.40005 0 90)
			(size 0 0)
			(layers "F.Cu" "F.Mask" "F.Paste")
			(net "P3V3_AUX_VDRV")
		)
		(pad "2" smd circle
			(at 0.40005 0 90)
			(size 0 0)
			(layers "F.Cu" "F.Mask" "F.Paste")
			(net "P3V3_AUX_VCC")
		)
	)
	(footprint ""
		(layer "F.Cu")
		(at 129.72288 -92.674948 90)
		(property "Reference" "R203"
			(at 0 0 90)
			(layer "F.SilkS")
			(hide yes)
			(effects
				(font
					(size 1.27 1.27)
				)
			)
		)
		(property "Value" ""
			(at 0 0 90)
			(layer "F.Fab")
			(effects
				(font
					(size 1.27 1.27)
				)
			)
		)
		(duplicate_pad_numbers_are_jumpers no)
		(fp_line
			(start 0.7874 -0.4064)
			(end 0.7874 0.4064)
			(stroke
				(width 0.1524)
				(type default)
			)
			(layer "F.SilkS")
		)
		(fp_line
			(start -0.7874 -0.4064)
			(end 0.7874 -0.4064)
			(stroke
				(width 0.1524)
				(type default)
			)
			(layer "F.SilkS")
		)
		(fp_line
			(start 0.7874 0.4064)
			(end -0.7874 0.4064)
			(stroke
				(width 0.1524)
				(type default)
			)
			(layer "F.SilkS")
		)
		(fp_line
			(start -0.7874 0.4064)
			(end -0.7874 -0.4064)
			(stroke
				(width 0.1524)
				(type default)
			)
			(layer "F.SilkS")
		)
		(fp_line
			(start -0.12065 -0.305054)
			(end -0.12065 -0.2794)
			(stroke
				(width 0.1)
				(type default)
			)
			(layer "F.Fab")
		)
		(fp_line
			(start -0.67945 -0.305054)
			(end -0.12065 -0.305054)
			(stroke
				(width 0.1)
				(type default)
			)
			(layer "F.Fab")
		)
		(fp_line
			(start 0.67945 -0.3048)
			(end 0.67945 0.3048)
			(stroke
				(width 0.1)
				(type default)
			)
			(layer "F.Fab")
		)
		(fp_line
			(start 0.12065 -0.3048)
			(end 0.67945 -0.3048)
			(stroke
				(width 0.1)
				(type default)
			)
			(layer "F.Fab")
		)
		(fp_line
			(start 0.12065 -0.2794)
			(end 0.12065 -0.3048)
			(stroke
				(width 0.1)
				(type default)
			)
			(layer "F.Fab")
		)
		(fp_line
			(start -0.12065 -0.2794)
			(end 0.12065 -0.2794)
			(stroke
				(width 0.1)
				(type default)
			)
			(layer "F.Fab")
		)
		(fp_line
			(start 0.120396 0.2794)
			(end -0.12065 0.2794)
			(stroke
				(width 0.1)
				(type default)
			)
			(layer "F.Fab")
		)
		(fp_line
			(start -0.12065 0.2794)
			(end -0.12065 0.3048)
			(stroke
				(width 0.1)
				(type default)
			)
			(layer "F.Fab")
		)
		(fp_line
			(start 0.67945 0.3048)
			(end 0.120396 0.3048)
			(stroke
				(width 0.1)
				(type default)
			)
			(layer "F.Fab")
		)
		(fp_line
			(start 0.120396 0.3048)
			(end 0.120396 0.2794)
			(stroke
				(width 0.1)
				(type default)
			)
			(layer "F.Fab")
		)
		(fp_line
			(start -0.12065 0.3048)
			(end -0.67945 0.3048)
			(stroke
				(width 0.1)
				(type default)
			)
			(layer "F.Fab")
		)
		(fp_line
			(start -0.67945 0.3048)
			(end -0.67945 -0.305054)
			(stroke
				(width 0.1)
				(type default)
			)
			(layer "F.Fab")
		)
		(pad "1" smd circle
			(at -0.40005 0 90)
			(size 0 0)
			(layers "F.Cu" "F.Mask" "F.Paste")
			(net "H_CPU0_MEMHOT_OUT_LVC1_R_N")
		)
		(pad "2" smd circle
			(at 0.40005 0 90)
			(size 0 0)
			(layers "F.Cu" "F.Mask" "F.Paste")
			(net "H_CPU0_MEMHOT_OUT_VT_R_N")
		)
	)
	(footprint ""
		(layer "F.Cu")
		(at 258.25958 -57.911492 90)
		(property "Reference" "R3975"
			(at 0 0 90)
			(layer "F.SilkS")
			(hide yes)
			(effects
				(font
					(size 1.27 1.27)
				)
			)
		)
		(property "Value" ""
			(at 0 0 90)
			(layer "F.Fab")
			(effects
				(font
					(size 1.27 1.27)
				)
			)
		)
		(duplicate_pad_numbers_are_jumpers no)
		(fp_line
			(start 0.7874 -0.4064)
			(end 0.7874 0.4064)
			(stroke
				(width 0.1524)
				(type default)
			)
			(layer "F.SilkS")
		)
		(fp_line
			(start -0.7874 -0.4064)
			(end 0.7874 -0.4064)
			(stroke
				(width 0.1524)
				(type default)
			)
			(layer "F.SilkS")
		)
		(fp_line
			(start 0.7874 0.4064)
			(end -0.7874 0.4064)
			(stroke
				(width 0.1524)
				(type default)
			)
			(layer "F.SilkS")
		)
		(fp_line
			(start -0.7874 0.4064)
			(end -0.7874 -0.4064)
			(stroke
				(width 0.1524)
				(type default)
			)
			(layer "F.SilkS")
		)
		(fp_line
			(start -0.12065 -0.305054)
			(end -0.12065 -0.2794)
			(stroke
				(width 0.1)
				(type default)
			)
			(layer "F.Fab")
		)
		(fp_line
			(start -0.67945 -0.305054)
			(end -0.12065 -0.305054)
			(stroke
				(width 0.1)
				(type default)
			)
			(layer "F.Fab")
		)
		(fp_line
			(start 0.67945 -0.3048)
			(end 0.67945 0.3048)
			(stroke
				(width 0.1)
				(type default)
			)
			(layer "F.Fab")
		)
		(fp_line
			(start 0.12065 -0.3048)
			(end 0.67945 -0.3048)
			(stroke
				(width 0.1)
				(type default)
			)
			(layer "F.Fab")
		)
		(fp_line
			(start 0.12065 -0.2794)
			(end 0.12065 -0.3048)
			(stroke
				(width 0.1)
				(type default)
			)
			(layer "F.Fab")
		)
		(fp_line
			(start -0.12065 -0.2794)
			(end 0.12065 -0.2794)
			(stroke
				(width 0.1)
				(type default)
			)
			(layer "F.Fab")
		)
		(fp_line
			(start 0.120396 0.2794)
			(end -0.12065 0.2794)
			(stroke
				(width 0.1)
				(type default)
			)
			(layer "F.Fab")
		)
		(fp_line
			(start -0.12065 0.2794)
			(end -0.12065 0.3048)
			(stroke
				(width 0.1)
				(type default)
			)
			(layer "F.Fab")
		)
		(fp_line
			(start 0.67945 0.3048)
			(end 0.120396 0.3048)
			(stroke
				(width 0.1)
				(type default)
			)
			(layer "F.Fab")
		)
		(fp_line
			(start 0.120396 0.3048)
			(end 0.120396 0.2794)
			(stroke
				(width 0.1)
				(type default)
			)
			(layer "F.Fab")
		)
		(fp_line
			(start -0.12065 0.3048)
			(end -0.67945 0.3048)
			(stroke
				(width 0.1)
				(type default)
			)
			(layer "F.Fab")
		)
		(fp_line
			(start -0.67945 0.3048)
			(end -0.67945 -0.305054)
			(stroke
				(width 0.1)
				(type default)
			)
			(layer "F.Fab")
		)
		(pad "1" smd rect
			(at -0.40005 0 270)
			(size 0.4572 0.508)
			(layers "F.Cu" "F.Mask" "F.Paste")
			(net "P12V_E1S_SENSE_0")
		)
		(pad "2" smd rect
			(at 0.40005 0 270)
			(size 0.4572 0.508)
			(layers "F.Cu" "F.Mask" "F.Paste")
			(net "P12V_E1S_0_ISENSE_MAM_TIC")
		)
	)
	(footprint ""
		(layer "F.Cu")
		(at 107.87888 -57.241948)
		(property "Reference" "C1292"
			(at 0 0 0)
			(layer "F.SilkS")
			(hide yes)
			(effects
				(font
					(size 1.27 1.27)
				)
			)
		)
		(property "Value" ""
			(at 0 0 0)
			(layer "F.Fab")
			(effects
				(font
					(size 1.27 1.27)
				)
			)
		)
		(duplicate_pad_numbers_are_jumpers no)
		(fp_line
			(start -0.7874 -0.4064)
			(end 0.7874 -0.4064)
			(stroke
				(width 0.1524)
				(type default)
			)
			(layer "F.SilkS")
		)
		(fp_line
			(start -0.7874 0.4064)
			(end -0.7874 -0.4064)
			(stroke
				(width 0.1524)
				(type default)
			)
			(layer "F.SilkS")
		)
		(fp_line
			(start 0.7874 -0.4064)
			(end 0.7874 0.4064)
			(stroke
				(width 0.1524)
				(type default)
			)
			(layer "F.SilkS")
		)
		(fp_line
			(start 0.7874 0.4064)
			(end -0.7874 0.4064)
			(stroke
				(width 0.1524)
				(type default)
			)
			(layer "F.SilkS")
		)
		(fp_line
			(start -0.67945 -0.305054)
			(end -0.12065 -0.305054)
			(stroke
				(width 0.1)
				(type default)
			)
			(layer "F.Fab")
		)
		(fp_line
			(start -0.67945 0.3048)
			(end -0.67945 -0.305054)
			(stroke
				(width 0.1)
				(type default)
			)
			(layer "F.Fab")
		)
		(fp_line
			(start -0.12065 -0.305054)
			(end -0.12065 -0.2794)
			(stroke
				(width 0.1)
				(type default)
			)
			(layer "F.Fab")
		)
		(fp_line
			(start -0.12065 -0.2794)
			(end 0.12065 -0.2794)
			(stroke
				(width 0.1)
				(type default)
			)
			(layer "F.Fab")
		)
		(fp_line
			(start -0.12065 0.2794)
			(end -0.12065 0.3048)
			(stroke
				(width 0.1)
				(type default)
			)
			(layer "F.Fab")
		)
		(fp_line
			(start -0.12065 0.3048)
			(end -0.67945 0.3048)
			(stroke
				(width 0.1)
				(type default)
			)
			(layer "F.Fab")
		)
		(fp_line
			(start 0.120396 0.2794)
			(end -0.12065 0.2794)
			(stroke
				(width 0.1)
				(type default)
			)
			(layer "F.Fab")
		)
		(fp_line
			(start 0.120396 0.3048)
			(end 0.120396 0.2794)
			(stroke
				(width 0.1)
				(type default)
			)
			(layer "F.Fab")
		)
		(fp_line
			(start 0.12065 -0.3048)
			(end 0.67945 -0.3048)
			(stroke
				(width 0.1)
				(type default)
			)
			(layer "F.Fab")
		)
		(fp_line
			(start 0.12065 -0.2794)
			(end 0.12065 -0.3048)
			(stroke
				(width 0.1)
				(type default)
			)
			(layer "F.Fab")
		)
		(fp_line
			(start 0.67945 -0.3048)
			(end 0.67945 0.3048)
			(stroke
				(width 0.1)
				(type default)
			)
			(layer "F.Fab")
		)
		(fp_line
			(start 0.67945 0.3048)
			(end 0.120396 0.3048)
			(stroke
				(width 0.1)
				(type default)
			)
			(layer "F.Fab")
		)
		(pad "1" smd circle
			(at -0.40005 0)
			(size 0 0)
			(layers "F.Cu" "F.Mask" "F.Paste")
			(net "P3V3_AUX")
		)
		(pad "2" smd circle
			(at 0.40005 0)
			(size 0 0)
			(layers "F.Cu" "F.Mask" "F.Paste")
			(net "GND")
		)
	)
	(footprint ""
		(layer "F.Cu")
		(at 165.15715 -432.865276 90)
		(property "Reference" "R2671"
			(at 0 0 90)
			(layer "F.SilkS")
			(hide yes)
			(effects
				(font
					(size 1.27 1.27)
				)
			)
		)
		(property "Value" ""
			(at 0 0 90)
			(layer "F.Fab")
			(effects
				(font
					(size 1.27 1.27)
				)
			)
		)
		(duplicate_pad_numbers_are_jumpers no)
		(fp_line
			(start 0.7874 -0.4064)
			(end 0.7874 0.4064)
			(stroke
				(width 0.1524)
				(type default)
			)
			(layer "F.SilkS")
		)
		(fp_line
			(start -0.7874 -0.4064)
			(end 0.7874 -0.4064)
			(stroke
				(width 0.1524)
				(type default)
			)
			(layer "F.SilkS")
		)
		(fp_line
			(start 0.7874 0.4064)
			(end -0.7874 0.4064)
			(stroke
				(width 0.1524)
				(type default)
			)
			(layer "F.SilkS")
		)
		(fp_line
			(start -0.7874 0.4064)
			(end -0.7874 -0.4064)
			(stroke
				(width 0.1524)
				(type default)
			)
			(layer "F.SilkS")
		)
		(fp_line
			(start -0.12065 -0.305054)
			(end -0.12065 -0.2794)
			(stroke
				(width 0.1)
				(type default)
			)
			(layer "F.Fab")
		)
		(fp_line
			(start -0.67945 -0.305054)
			(end -0.12065 -0.305054)
			(stroke
				(width 0.1)
				(type default)
			)
			(layer "F.Fab")
		)
		(fp_line
			(start 0.67945 -0.3048)
			(end 0.67945 0.3048)
			(stroke
				(width 0.1)
				(type default)
			)
			(layer "F.Fab")
		)
		(fp_line
			(start 0.12065 -0.3048)
			(end 0.67945 -0.3048)
			(stroke
				(width 0.1)
				(type default)
			)
			(layer "F.Fab")
		)
		(fp_line
			(start 0.12065 -0.2794)
			(end 0.12065 -0.3048)
			(stroke
				(width 0.1)
				(type default)
			)
			(layer "F.Fab")
		)
		(fp_line
			(start -0.12065 -0.2794)
			(end 0.12065 -0.2794)
			(stroke
				(width 0.1)
				(type default)
			)
			(layer "F.Fab")
		)
		(fp_line
			(start 0.120396 0.2794)
			(end -0.12065 0.2794)
			(stroke
				(width 0.1)
				(type default)
			)
			(layer "F.Fab")
		)
		(fp_line
			(start -0.12065 0.2794)
			(end -0.12065 0.3048)
			(stroke
				(width 0.1)
				(type default)
			)
			(layer "F.Fab")
		)
		(fp_line
			(start 0.67945 0.3048)
			(end 0.120396 0.3048)
			(stroke
				(width 0.1)
				(type default)
			)
			(layer "F.Fab")
		)
		(fp_line
			(start 0.120396 0.3048)
			(end 0.120396 0.2794)
			(stroke
				(width 0.1)
				(type default)
			)
			(layer "F.Fab")
		)
		(fp_line
			(start -0.12065 0.3048)
			(end -0.67945 0.3048)
			(stroke
				(width 0.1)
				(type default)
			)
			(layer "F.Fab")
		)
		(fp_line
			(start -0.67945 0.3048)
			(end -0.67945 -0.305054)
			(stroke
				(width 0.1)
				(type default)
			)
			(layer "F.Fab")
		)
		(pad "1" smd circle
			(at -0.40005 0 90)
			(size 0 0)
			(layers "F.Cu" "F.Mask" "F.Paste")
			(net "SMB_BMC_SWB_BUF_R_SCL")
		)
		(pad "2" smd circle
			(at 0.40005 0 90)
			(size 0 0)
			(layers "F.Cu" "F.Mask" "F.Paste")
			(net "SMB_BMC_SWB_BUF_SCL")
		)
	)
	(footprint ""
		(layer "F.Cu")
		(at 367.44783 -249.320304 -90)
		(property "Reference" "C981"
			(at 0 0 270)
			(layer "F.SilkS")
			(hide yes)
			(effects
				(font
					(size 1.27 1.27)
				)
			)
		)
		(property "Value" ""
			(at 0 0 270)
			(layer "F.Fab")
			(effects
				(font
					(size 1.27 1.27)
				)
			)
		)
		(duplicate_pad_numbers_are_jumpers no)
		(fp_line
			(start -0.7874 0.4064)
			(end -0.7874 -0.4064)
			(stroke
				(width 0.1524)
				(type default)
			)
			(layer "F.SilkS")
		)
		(fp_line
			(start 0.7874 0.4064)
			(end -0.7874 0.4064)
			(stroke
				(width 0.1524)
				(type default)
			)
			(layer "F.SilkS")
		)
		(fp_line
			(start -0.7874 -0.4064)
			(end 0.7874 -0.4064)
			(stroke
				(width 0.1524)
				(type default)
			)
			(layer "F.SilkS")
		)
		(fp_line
			(start 0.7874 -0.4064)
			(end 0.7874 0.4064)
			(stroke
				(width 0.1524)
				(type default)
			)
			(layer "F.SilkS")
		)
		(fp_line
			(start -0.67945 0.3048)
			(end -0.67945 -0.305054)
			(stroke
				(width 0.1)
				(type default)
			)
			(layer "F.Fab")
		)
		(fp_line
			(start -0.12065 0.3048)
			(end -0.67945 0.3048)
			(stroke
				(width 0.1)
				(type default)
			)
			(layer "F.Fab")
		)
		(fp_line
			(start 0.120396 0.3048)
			(end 0.120396 0.2794)
			(stroke
				(width 0.1)
				(type default)
			)
			(layer "F.Fab")
		)
		(fp_line
			(start 0.67945 0.3048)
			(end 0.120396 0.3048)
			(stroke
				(width 0.1)
				(type default)
			)
			(layer "F.Fab")
		)
		(fp_line
			(start -0.12065 0.2794)
			(end -0.12065 0.3048)
			(stroke
				(width 0.1)
				(type default)
			)
			(layer "F.Fab")
		)
		(fp_line
			(start 0.120396 0.2794)
			(end -0.12065 0.2794)
			(stroke
				(width 0.1)
				(type default)
			)
			(layer "F.Fab")
		)
		(fp_line
			(start -0.12065 -0.2794)
			(end 0.12065 -0.2794)
			(stroke
				(width 0.1)
				(type default)
			)
			(layer "F.Fab")
		)
		(fp_line
			(start 0.12065 -0.2794)
			(end 0.12065 -0.3048)
			(stroke
				(width 0.1)
				(type default)
			)
			(layer "F.Fab")
		)
		(fp_line
			(start 0.12065 -0.3048)
			(end 0.67945 -0.3048)
			(stroke
				(width 0.1)
				(type default)
			)
			(layer "F.Fab")
		)
		(fp_line
			(start 0.67945 -0.3048)
			(end 0.67945 0.3048)
			(stroke
				(width 0.1)
				(type default)
			)
			(layer "F.Fab")
		)
		(fp_line
			(start -0.67945 -0.305054)
			(end -0.12065 -0.305054)
			(stroke
				(width 0.1)
				(type default)
			)
			(layer "F.Fab")
		)
		(fp_line
			(start -0.12065 -0.305054)
			(end -0.12065 -0.2794)
			(stroke
				(width 0.1)
				(type default)
			)
			(layer "F.Fab")
		)
		(pad "1" smd circle
			(at -0.40005 0 270)
			(size 0 0)
			(layers "F.Cu" "F.Mask" "F.Paste")
			(net "PVCCIN_CPU0")
		)
		(pad "2" smd circle
			(at 0.40005 0 270)
			(size 0 0)
			(layers "F.Cu" "F.Mask" "F.Paste")
			(net "GND")
		)
	)
	(footprint ""
		(layer "F.Cu")
		(at 451.923404 -71.019416 -90)
		(property "Reference" "PC577"
			(at 0 0 270)
			(layer "F.SilkS")
			(hide yes)
			(effects
				(font
					(size 1.27 1.27)
				)
			)
		)
		(property "Value" ""
			(at 0 0 270)
			(layer "F.Fab")
			(effects
				(font
					(size 1.27 1.27)
				)
			)
		)
		(duplicate_pad_numbers_are_jumpers no)
		(fp_line
			(start -0.7874 0.4064)
			(end -0.7874 -0.4064)
			(stroke
				(width 0.1524)
				(type default)
			)
			(layer "F.SilkS")
		)
		(fp_line
			(start 0.7874 0.4064)
			(end -0.7874 0.4064)
			(stroke
				(width 0.1524)
				(type default)
			)
			(layer "F.SilkS")
		)
		(fp_line
			(start -0.7874 -0.4064)
			(end 0.7874 -0.4064)
			(stroke
				(width 0.1524)
				(type default)
			)
			(layer "F.SilkS")
		)
		(fp_line
			(start 0.7874 -0.4064)
			(end 0.7874 0.4064)
			(stroke
				(width 0.1524)
				(type default)
			)
			(layer "F.SilkS")
		)
		(fp_line
			(start -0.67945 0.3048)
			(end -0.67945 -0.305054)
			(stroke
				(width 0.1)
				(type default)
			)
			(layer "F.Fab")
		)
		(fp_line
			(start -0.12065 0.3048)
			(end -0.67945 0.3048)
			(stroke
				(width 0.1)
				(type default)
			)
			(layer "F.Fab")
		)
		(fp_line
			(start 0.120396 0.3048)
			(end 0.120396 0.2794)
			(stroke
				(width 0.1)
				(type default)
			)
			(layer "F.Fab")
		)
		(fp_line
			(start 0.67945 0.3048)
			(end 0.120396 0.3048)
			(stroke
				(width 0.1)
				(type default)
			)
			(layer "F.Fab")
		)
		(fp_line
			(start -0.12065 0.2794)
			(end -0.12065 0.3048)
			(stroke
				(width 0.1)
				(type default)
			)
			(layer "F.Fab")
		)
		(fp_line
			(start 0.120396 0.2794)
			(end -0.12065 0.2794)
			(stroke
				(width 0.1)
				(type default)
			)
			(layer "F.Fab")
		)
		(fp_line
			(start -0.12065 -0.2794)
			(end 0.12065 -0.2794)
			(stroke
				(width 0.1)
				(type default)
			)
			(layer "F.Fab")
		)
		(fp_line
			(start 0.12065 -0.2794)
			(end 0.12065 -0.3048)
			(stroke
				(width 0.1)
				(type default)
			)
			(layer "F.Fab")
		)
		(fp_line
			(start 0.12065 -0.3048)
			(end 0.67945 -0.3048)
			(stroke
				(width 0.1)
				(type default)
			)
			(layer "F.Fab")
		)
		(fp_line
			(start 0.67945 -0.3048)
			(end 0.67945 0.3048)
			(stroke
				(width 0.1)
				(type default)
			)
			(layer "F.Fab")
		)
		(fp_line
			(start -0.67945 -0.305054)
			(end -0.12065 -0.305054)
			(stroke
				(width 0.1)
				(type default)
			)
			(layer "F.Fab")
		)
		(fp_line
			(start -0.12065 -0.305054)
			(end -0.12065 -0.2794)
			(stroke
				(width 0.1)
				(type default)
			)
			(layer "F.Fab")
		)
		(pad "1" smd circle
			(at -0.40005 0 270)
			(size 0 0)
			(layers "F.Cu" "F.Mask" "F.Paste")
			(net "SW_P3V3_AUX_FLT")
		)
		(pad "2" smd circle
			(at 0.40005 0 270)
			(size 0 0)
			(layers "F.Cu" "F.Mask" "F.Paste")
			(net "GND")
		)
	)
	(footprint ""
		(layer "F.Cu")
		(at 86.931246 -57.279286 90)
		(property "Reference" "PR3782"
			(at 0 0 90)
			(layer "F.SilkS")
			(hide yes)
			(effects
				(font
					(size 1.27 1.27)
				)
			)
		)
		(property "Value" ""
			(at 0 0 90)
			(layer "F.Fab")
			(effects
				(font
					(size 1.27 1.27)
				)
			)
		)
		(duplicate_pad_numbers_are_jumpers no)
		(fp_line
			(start 0.7874 -0.4064)
			(end 0.7874 0.4064)
			(stroke
				(width 0.1524)
				(type default)
			)
			(layer "F.SilkS")
		)
		(fp_line
			(start -0.7874 -0.4064)
			(end 0.7874 -0.4064)
			(stroke
				(width 0.1524)
				(type default)
			)
			(layer "F.SilkS")
		)
		(fp_line
			(start 0.7874 0.4064)
			(end -0.7874 0.4064)
			(stroke
				(width 0.1524)
				(type default)
			)
			(layer "F.SilkS")
		)
		(fp_line
			(start -0.7874 0.4064)
			(end -0.7874 -0.4064)
			(stroke
				(width 0.1524)
				(type default)
			)
			(layer "F.SilkS")
		)
		(fp_line
			(start -0.12065 -0.305054)
			(end -0.12065 -0.2794)
			(stroke
				(width 0.1)
				(type default)
			)
			(layer "F.Fab")
		)
		(fp_line
			(start -0.67945 -0.305054)
			(end -0.12065 -0.305054)
			(stroke
				(width 0.1)
				(type default)
			)
			(layer "F.Fab")
		)
		(fp_line
			(start 0.67945 -0.3048)
			(end 0.67945 0.3048)
			(stroke
				(width 0.1)
				(type default)
			)
			(layer "F.Fab")
		)
		(fp_line
			(start 0.12065 -0.3048)
			(end 0.67945 -0.3048)
			(stroke
				(width 0.1)
				(type default)
			)
			(layer "F.Fab")
		)
		(fp_line
			(start 0.12065 -0.2794)
			(end 0.12065 -0.3048)
			(stroke
				(width 0.1)
				(type default)
			)
			(layer "F.Fab")
		)
		(fp_line
			(start -0.12065 -0.2794)
			(end 0.12065 -0.2794)
			(stroke
				(width 0.1)
				(type default)
			)
			(layer "F.Fab")
		)
		(fp_line
			(start 0.120396 0.2794)
			(end -0.12065 0.2794)
			(stroke
				(width 0.1)
				(type default)
			)
			(layer "F.Fab")
		)
		(fp_line
			(start -0.12065 0.2794)
			(end -0.12065 0.3048)
			(stroke
				(width 0.1)
				(type default)
			)
			(layer "F.Fab")
		)
		(fp_line
			(start 0.67945 0.3048)
			(end 0.120396 0.3048)
			(stroke
				(width 0.1)
				(type default)
			)
			(layer "F.Fab")
		)
		(fp_line
			(start 0.120396 0.3048)
			(end 0.120396 0.2794)
			(stroke
				(width 0.1)
				(type default)
			)
			(layer "F.Fab")
		)
		(fp_line
			(start -0.12065 0.3048)
			(end -0.67945 0.3048)
			(stroke
				(width 0.1)
				(type default)
			)
			(layer "F.Fab")
		)
		(fp_line
			(start -0.67945 0.3048)
			(end -0.67945 -0.305054)
			(stroke
				(width 0.1)
				(type default)
			)
			(layer "F.Fab")
		)
		(pad "1" smd circle
			(at -0.40005 0 90)
			(size 0 0)
			(layers "F.Cu" "F.Mask" "F.Paste")
			(net "P3V3_AUX")
		)
		(pad "2" smd circle
			(at 0.40005 0 90)
			(size 0 0)
			(layers "F.Cu" "F.Mask" "F.Paste")
			(net "P3V3_OCP_VCC_2")
		)
	)
	(footprint ""
		(layer "F.Cu")
		(at 168.449498 -356.03053 90)
		(property "Reference" "PC395"
			(at 0 0 90)
			(layer "F.SilkS")
			(hide yes)
			(effects
				(font
					(size 1.27 1.27)
				)
			)
		)
		(property "Value" ""
			(at 0 0 90)
			(layer "F.Fab")
			(effects
				(font
					(size 1.27 1.27)
				)
			)
		)
		(duplicate_pad_numbers_are_jumpers no)
		(fp_line
			(start 0.7874 -0.4064)
			(end 0.7874 0.4064)
			(stroke
				(width 0.1524)
				(type default)
			)
			(layer "F.SilkS")
		)
		(fp_line
			(start -0.7874 -0.4064)
			(end 0.7874 -0.4064)
			(stroke
				(width 0.1524)
				(type default)
			)
			(layer "F.SilkS")
		)
		(fp_line
			(start 0.7874 0.4064)
			(end -0.7874 0.4064)
			(stroke
				(width 0.1524)
				(type default)
			)
			(layer "F.SilkS")
		)
		(fp_line
			(start -0.7874 0.4064)
			(end -0.7874 -0.4064)
			(stroke
				(width 0.1524)
				(type default)
			)
			(layer "F.SilkS")
		)
		(fp_line
			(start -0.12065 -0.305054)
			(end -0.12065 -0.2794)
			(stroke
				(width 0.1)
				(type default)
			)
			(layer "F.Fab")
		)
		(fp_line
			(start -0.67945 -0.305054)
			(end -0.12065 -0.305054)
			(stroke
				(width 0.1)
				(type default)
			)
			(layer "F.Fab")
		)
		(fp_line
			(start 0.67945 -0.3048)
			(end 0.67945 0.3048)
			(stroke
				(width 0.1)
				(type default)
			)
			(layer "F.Fab")
		)
		(fp_line
			(start 0.12065 -0.3048)
			(end 0.67945 -0.3048)
			(stroke
				(width 0.1)
				(type default)
			)
			(layer "F.Fab")
		)
		(fp_line
			(start 0.12065 -0.2794)
			(end 0.12065 -0.3048)
			(stroke
				(width 0.1)
				(type default)
			)
			(layer "F.Fab")
		)
		(fp_line
			(start -0.12065 -0.2794)
			(end 0.12065 -0.2794)
			(stroke
				(width 0.1)
				(type default)
			)
			(layer "F.Fab")
		)
		(fp_line
			(start 0.120396 0.2794)
			(end -0.12065 0.2794)
			(stroke
				(width 0.1)
				(type default)
			)
			(layer "F.Fab")
		)
		(fp_line
			(start -0.12065 0.2794)
			(end -0.12065 0.3048)
			(stroke
				(width 0.1)
				(type default)
			)
			(layer "F.Fab")
		)
		(fp_line
			(start 0.67945 0.3048)
			(end 0.120396 0.3048)
			(stroke
				(width 0.1)
				(type default)
			)
			(layer "F.Fab")
		)
		(fp_line
			(start 0.120396 0.3048)
			(end 0.120396 0.2794)
			(stroke
				(width 0.1)
				(type default)
			)
			(layer "F.Fab")
		)
		(fp_line
			(start -0.12065 0.3048)
			(end -0.67945 0.3048)
			(stroke
				(width 0.1)
				(type default)
			)
			(layer "F.Fab")
		)
		(fp_line
			(start -0.67945 0.3048)
			(end -0.67945 -0.305054)
			(stroke
				(width 0.1)
				(type default)
			)
			(layer "F.Fab")
		)
		(pad "1" smd circle
			(at -0.40005 0 90)
			(size 0 0)
			(layers "F.Cu" "F.Mask" "F.Paste")
			(net "PVCCFA_EHV_FIVRA_CPU1_VDD1")
		)
		(pad "2" smd circle
			(at 0.40005 0 90)
			(size 0 0)
			(layers "F.Cu" "F.Mask" "F.Paste")
			(net "GND")
		)
	)
	(footprint ""
		(layer "F.Cu")
		(at 362.646468 -362.618528)
		(property "Reference" "PC334"
			(at 0 0 0)
			(layer "F.SilkS")
			(hide yes)
			(effects
				(font
					(size 1.27 1.27)
				)
			)
		)
		(property "Value" ""
			(at 0 0 0)
			(layer "F.Fab")
			(effects
				(font
					(size 1.27 1.27)
				)
			)
		)
		(duplicate_pad_numbers_are_jumpers no)
		(fp_line
			(start -0.7874 -0.4064)
			(end 0.7874 -0.4064)
			(stroke
				(width 0.1524)
				(type default)
			)
			(layer "F.SilkS")
		)
		(fp_line
			(start -0.7874 0.4064)
			(end -0.7874 -0.4064)
			(stroke
				(width 0.1524)
				(type default)
			)
			(layer "F.SilkS")
		)
		(fp_line
			(start 0.7874 -0.4064)
			(end 0.7874 0.4064)
			(stroke
				(width 0.1524)
				(type default)
			)
			(layer "F.SilkS")
		)
		(fp_line
			(start 0.7874 0.4064)
			(end -0.7874 0.4064)
			(stroke
				(width 0.1524)
				(type default)
			)
			(layer "F.SilkS")
		)
		(fp_line
			(start -0.67945 -0.305054)
			(end -0.12065 -0.305054)
			(stroke
				(width 0.1)
				(type default)
			)
			(layer "F.Fab")
		)
		(fp_line
			(start -0.67945 0.3048)
			(end -0.67945 -0.305054)
			(stroke
				(width 0.1)
				(type default)
			)
			(layer "F.Fab")
		)
		(fp_line
			(start -0.12065 -0.305054)
			(end -0.12065 -0.2794)
			(stroke
				(width 0.1)
				(type default)
			)
			(layer "F.Fab")
		)
		(fp_line
			(start -0.12065 -0.2794)
			(end 0.12065 -0.2794)
			(stroke
				(width 0.1)
				(type default)
			)
			(layer "F.Fab")
		)
		(fp_line
			(start -0.12065 0.2794)
			(end -0.12065 0.3048)
			(stroke
				(width 0.1)
				(type default)
			)
			(layer "F.Fab")
		)
		(fp_line
			(start -0.12065 0.3048)
			(end -0.67945 0.3048)
			(stroke
				(width 0.1)
				(type default)
			)
			(layer "F.Fab")
		)
		(fp_line
			(start 0.120396 0.2794)
			(end -0.12065 0.2794)
			(stroke
				(width 0.1)
				(type default)
			)
			(layer "F.Fab")
		)
		(fp_line
			(start 0.120396 0.3048)
			(end 0.120396 0.2794)
			(stroke
				(width 0.1)
				(type default)
			)
			(layer "F.Fab")
		)
		(fp_line
			(start 0.12065 -0.3048)
			(end 0.67945 -0.3048)
			(stroke
				(width 0.1)
				(type default)
			)
			(layer "F.Fab")
		)
		(fp_line
			(start 0.12065 -0.2794)
			(end 0.12065 -0.3048)
			(stroke
				(width 0.1)
				(type default)
			)
			(layer "F.Fab")
		)
		(fp_line
			(start 0.67945 -0.3048)
			(end 0.67945 0.3048)
			(stroke
				(width 0.1)
				(type default)
			)
			(layer "F.Fab")
		)
		(fp_line
			(start 0.67945 0.3048)
			(end 0.120396 0.3048)
			(stroke
				(width 0.1)
				(type default)
			)
			(layer "F.Fab")
		)
		(pad "1" smd circle
			(at -0.40005 0)
			(size 0 0)
			(layers "F.Cu" "F.Mask" "F.Paste")
			(net "PVCCIN_CPU0_VCC")
		)
		(pad "2" smd circle
			(at 0.40005 0)
			(size 0 0)
			(layers "F.Cu" "F.Mask" "F.Paste")
			(net "GND")
		)
	)
	(footprint ""
		(layer "F.Cu")
		(at 169.422572 -418.479478 180)
		(property "Reference" "C1973"
			(at 0 0 180)
			(layer "F.SilkS")
			(hide yes)
			(effects
				(font
					(size 1.27 1.27)
				)
			)
		)
		(property "Value" ""
			(at 0 0 180)
			(layer "F.Fab")
			(effects
				(font
					(size 1.27 1.27)
				)
			)
		)
		(duplicate_pad_numbers_are_jumpers no)
		(fp_line
			(start 0.7874 0.4064)
			(end -0.7874 0.4064)
			(stroke
				(width 0.1524)
				(type default)
			)
			(layer "F.SilkS")
		)
		(fp_line
			(start 0.7874 -0.4064)
			(end 0.7874 0.4064)
			(stroke
				(width 0.1524)
				(type default)
			)
			(layer "F.SilkS")
		)
		(fp_line
			(start -0.7874 0.4064)
			(end -0.7874 -0.4064)
			(stroke
				(width 0.1524)
				(type default)
			)
			(layer "F.SilkS")
		)
		(fp_line
			(start -0.7874 -0.4064)
			(end 0.7874 -0.4064)
			(stroke
				(width 0.1524)
				(type default)
			)
			(layer "F.SilkS")
		)
		(fp_line
			(start 0.67945 0.3048)
			(end 0.120396 0.3048)
			(stroke
				(width 0.1)
				(type default)
			)
			(layer "F.Fab")
		)
		(fp_line
			(start 0.67945 -0.3048)
			(end 0.67945 0.3048)
			(stroke
				(width 0.1)
				(type default)
			)
			(layer "F.Fab")
		)
		(fp_line
			(start 0.12065 -0.2794)
			(end 0.12065 -0.3048)
			(stroke
				(width 0.1)
				(type default)
			)
			(layer "F.Fab")
		)
		(fp_line
			(start 0.12065 -0.3048)
			(end 0.67945 -0.3048)
			(stroke
				(width 0.1)
				(type default)
			)
			(layer "F.Fab")
		)
		(fp_line
			(start 0.120396 0.3048)
			(end 0.120396 0.2794)
			(stroke
				(width 0.1)
				(type default)
			)
			(layer "F.Fab")
		)
		(fp_line
			(start 0.120396 0.2794)
			(end -0.12065 0.2794)
			(stroke
				(width 0.1)
				(type default)
			)
			(layer "F.Fab")
		)
		(fp_line
			(start -0.12065 0.3048)
			(end -0.67945 0.3048)
			(stroke
				(width 0.1)
				(type default)
			)
			(layer "F.Fab")
		)
		(fp_line
			(start -0.12065 0.2794)
			(end -0.12065 0.3048)
			(stroke
				(width 0.1)
				(type default)
			)
			(layer "F.Fab")
		)
		(fp_line
			(start -0.12065 -0.2794)
			(end 0.12065 -0.2794)
			(stroke
				(width 0.1)
				(type default)
			)
			(layer "F.Fab")
		)
		(fp_line
			(start -0.12065 -0.305054)
			(end -0.12065 -0.2794)
			(stroke
				(width 0.1)
				(type default)
			)
			(layer "F.Fab")
		)
		(fp_line
			(start -0.67945 0.3048)
			(end -0.67945 -0.305054)
			(stroke
				(width 0.1)
				(type default)
			)
			(layer "F.Fab")
		)
		(fp_line
			(start -0.67945 -0.305054)
			(end -0.12065 -0.305054)
			(stroke
				(width 0.1)
				(type default)
			)
			(layer "F.Fab")
		)
		(pad "1" smd circle
			(at -0.40005 0 180)
			(size 0 0)
			(layers "F.Cu" "F.Mask" "F.Paste")
			(net "GPU_BASE_HMC_READY_ISO")
		)
		(pad "2" smd circle
			(at 0.40005 0 180)
			(size 0 0)
			(layers "F.Cu" "F.Mask" "F.Paste")
			(net "GND")
		)
	)
	(footprint ""
		(layer "F.Cu")
		(at 71.194676 -79.078836)
		(property "Reference" "D75"
			(at -37.31641 34.331402 90)
			(unlocked yes)
			(layer "F.SilkS")
			(effects
				(font
					(size 0.635 0.4064)
					(thickness 0.1524)
				)
				(justify left)
			)
		)
		(property "Value" ""
			(at 0 0 0)
			(layer "F.Fab")
			(effects
				(font
					(size 1.27 1.27)
				)
			)
		)
		(duplicate_pad_numbers_are_jumpers no)
		(fp_line
			(start -0.90678 0.4826)
			(end -0.90678 -0.4699)
			(stroke
				(width 0.1524)
				(type default)
			)
			(layer "F.SilkS")
		)
		(fp_line
			(start -0.89408 -0.4826)
			(end 0.90678 -0.4826)
			(stroke
				(width 0.1524)
				(type default)
			)
			(layer "F.SilkS")
		)
		(fp_line
			(start -0.79248 -0.4826)
			(end 1.03378 -0.4826)
			(stroke
				(width 0.1524)
				(type default)
			)
			(layer "F.SilkS")
		)
		(fp_line
			(start -0.64008 -0.4826)
			(end 1.16078 -0.4826)
			(stroke
				(width 0.1524)
				(type default)
			)
			(layer "F.SilkS")
		)
		(fp_line
			(start 0.90678 -0.4826)
			(end 0.90678 0.4826)
			(stroke
				(width 0.1524)
				(type default)
			)
			(layer "F.SilkS")
		)
		(fp_line
			(start 0.90678 0.4826)
			(end -0.90678 0.4826)
			(stroke
				(width 0.1524)
				(type default)
			)
			(layer "F.SilkS")
		)
		(fp_line
			(start 1.03378 -0.4826)
			(end 1.03378 0.4826)
			(stroke
				(width 0.1524)
				(type default)
			)
			(layer "F.SilkS")
		)
		(fp_line
			(start 1.03378 0.4826)
			(end -0.79248 0.4826)
			(stroke
				(width 0.1524)
				(type default)
			)
			(layer "F.SilkS")
		)
		(fp_line
			(start 1.16078 -0.4826)
			(end 1.16078 0.4826)
			(stroke
				(width 0.1524)
				(type default)
			)
			(layer "F.SilkS")
		)
		(fp_line
			(start 1.16078 0.4826)
			(end -0.64008 0.4826)
			(stroke
				(width 0.1524)
				(type default)
			)
			(layer "F.SilkS")
		)
		(fp_line
			(start -0.499872 -0.249936)
			(end 0.499872 -0.249936)
			(stroke
				(width 0.1)
				(type default)
			)
			(layer "F.Fab")
		)
		(fp_line
			(start -0.499872 0.249936)
			(end -0.499872 -0.249936)
			(stroke
				(width 0.1)
				(type default)
			)
			(layer "F.Fab")
		)
		(fp_line
			(start 0.499872 -0.249936)
			(end 0.499872 0.249936)
			(stroke
				(width 0.1)
				(type default)
			)
			(layer "F.Fab")
		)
		(fp_line
			(start 0.499872 0.249936)
			(end -0.499872 0.249936)
			(stroke
				(width 0.1)
				(type default)
			)
			(layer "F.Fab")
		)
		(pad "A" smd rect
			(at -0.47498 0)
			(size 0.6096 0.7112)
			(layers "F.Cu" "F.Mask" "F.Paste")
			(net "LED_PWRGD_PVCCFA_EHV_CPU0")
		)
		(pad "C" smd rect
			(at 0.47498 0)
			(size 0.6096 0.7112)
			(layers "F.Cu" "F.Mask" "F.Paste")
			(net "LED_PWRGD_PVCCFA_EHV_CPU0_D")
		)
	)
	(footprint ""
		(layer "F.Cu")
		(at 123.810522 -14.19733 180)
		(property "Reference" "R4184"
			(at 0 0 180)
			(layer "F.SilkS")
			(hide yes)
			(effects
				(font
					(size 1.27 1.27)
				)
			)
		)
		(property "Value" ""
			(at 0 0 180)
			(layer "F.Fab")
			(effects
				(font
					(size 1.27 1.27)
				)
			)
		)
		(duplicate_pad_numbers_are_jumpers no)
		(fp_line
			(start 0.7874 0.4064)
			(end -0.7874 0.4064)
			(stroke
				(width 0.1524)
				(type default)
			)
			(layer "F.SilkS")
		)
		(fp_line
			(start 0.7874 -0.4064)
			(end 0.7874 0.4064)
			(stroke
				(width 0.1524)
				(type default)
			)
			(layer "F.SilkS")
		)
		(fp_line
			(start -0.7874 0.4064)
			(end -0.7874 -0.4064)
			(stroke
				(width 0.1524)
				(type default)
			)
			(layer "F.SilkS")
		)
		(fp_line
			(start -0.7874 -0.4064)
			(end 0.7874 -0.4064)
			(stroke
				(width 0.1524)
				(type default)
			)
			(layer "F.SilkS")
		)
		(fp_line
			(start 0.67945 0.3048)
			(end 0.120396 0.3048)
			(stroke
				(width 0.1)
				(type default)
			)
			(layer "F.Fab")
		)
		(fp_line
			(start 0.67945 -0.3048)
			(end 0.67945 0.3048)
			(stroke
				(width 0.1)
				(type default)
			)
			(layer "F.Fab")
		)
		(fp_line
			(start 0.12065 -0.2794)
			(end 0.12065 -0.3048)
			(stroke
				(width 0.1)
				(type default)
			)
			(layer "F.Fab")
		)
		(fp_line
			(start 0.12065 -0.3048)
			(end 0.67945 -0.3048)
			(stroke
				(width 0.1)
				(type default)
			)
			(layer "F.Fab")
		)
		(fp_line
			(start 0.120396 0.3048)
			(end 0.120396 0.2794)
			(stroke
				(width 0.1)
				(type default)
			)
			(layer "F.Fab")
		)
		(fp_line
			(start 0.120396 0.2794)
			(end -0.12065 0.2794)
			(stroke
				(width 0.1)
				(type default)
			)
			(layer "F.Fab")
		)
		(fp_line
			(start -0.12065 0.3048)
			(end -0.67945 0.3048)
			(stroke
				(width 0.1)
				(type default)
			)
			(layer "F.Fab")
		)
		(fp_line
			(start -0.12065 0.2794)
			(end -0.12065 0.3048)
			(stroke
				(width 0.1)
				(type default)
			)
			(layer "F.Fab")
		)
		(fp_line
			(start -0.12065 -0.2794)
			(end 0.12065 -0.2794)
			(stroke
				(width 0.1)
				(type default)
			)
			(layer "F.Fab")
		)
		(fp_line
			(start -0.12065 -0.305054)
			(end -0.12065 -0.2794)
			(stroke
				(width 0.1)
				(type default)
			)
			(layer "F.Fab")
		)
		(fp_line
			(start -0.67945 0.3048)
			(end -0.67945 -0.305054)
			(stroke
				(width 0.1)
				(type default)
			)
			(layer "F.Fab")
		)
		(fp_line
			(start -0.67945 -0.305054)
			(end -0.12065 -0.305054)
			(stroke
				(width 0.1)
				(type default)
			)
			(layer "F.Fab")
		)
		(pad "1" smd circle
			(at -0.40005 0 180)
			(size 0 0)
			(layers "F.Cu" "F.Mask" "F.Paste")
			(net "P3V3_AUX")
		)
		(pad "2" smd circle
			(at 0.40005 0 180)
			(size 0 0)
			(layers "F.Cu" "F.Mask" "F.Paste")
			(net "U273_3_ADD2")
		)
	)
	(footprint ""
		(layer "F.Cu")
		(at 163.12515 -432.865276 -90)
		(property "Reference" "R3105"
			(at 0 0 270)
			(layer "F.SilkS")
			(hide yes)
			(effects
				(font
					(size 1.27 1.27)
				)
			)
		)
		(property "Value" ""
			(at 0 0 270)
			(layer "F.Fab")
			(effects
				(font
					(size 1.27 1.27)
				)
			)
		)
		(duplicate_pad_numbers_are_jumpers no)
		(fp_line
			(start -0.7874 0.4064)
			(end -0.7874 -0.4064)
			(stroke
				(width 0.1524)
				(type default)
			)
			(layer "F.SilkS")
		)
		(fp_line
			(start 0.7874 0.4064)
			(end -0.7874 0.4064)
			(stroke
				(width 0.1524)
				(type default)
			)
			(layer "F.SilkS")
		)
		(fp_line
			(start -0.7874 -0.4064)
			(end 0.7874 -0.4064)
			(stroke
				(width 0.1524)
				(type default)
			)
			(layer "F.SilkS")
		)
		(fp_line
			(start 0.7874 -0.4064)
			(end 0.7874 0.4064)
			(stroke
				(width 0.1524)
				(type default)
			)
			(layer "F.SilkS")
		)
		(fp_line
			(start -0.67945 0.3048)
			(end -0.67945 -0.305054)
			(stroke
				(width 0.1)
				(type default)
			)
			(layer "F.Fab")
		)
		(fp_line
			(start -0.12065 0.3048)
			(end -0.67945 0.3048)
			(stroke
				(width 0.1)
				(type default)
			)
			(layer "F.Fab")
		)
		(fp_line
			(start 0.120396 0.3048)
			(end 0.120396 0.2794)
			(stroke
				(width 0.1)
				(type default)
			)
			(layer "F.Fab")
		)
		(fp_line
			(start 0.67945 0.3048)
			(end 0.120396 0.3048)
			(stroke
				(width 0.1)
				(type default)
			)
			(layer "F.Fab")
		)
		(fp_line
			(start -0.12065 0.2794)
			(end -0.12065 0.3048)
			(stroke
				(width 0.1)
				(type default)
			)
			(layer "F.Fab")
		)
		(fp_line
			(start 0.120396 0.2794)
			(end -0.12065 0.2794)
			(stroke
				(width 0.1)
				(type default)
			)
			(layer "F.Fab")
		)
		(fp_line
			(start -0.12065 -0.2794)
			(end 0.12065 -0.2794)
			(stroke
				(width 0.1)
				(type default)
			)
			(layer "F.Fab")
		)
		(fp_line
			(start 0.12065 -0.2794)
			(end 0.12065 -0.3048)
			(stroke
				(width 0.1)
				(type default)
			)
			(layer "F.Fab")
		)
		(fp_line
			(start 0.12065 -0.3048)
			(end 0.67945 -0.3048)
			(stroke
				(width 0.1)
				(type default)
			)
			(layer "F.Fab")
		)
		(fp_line
			(start 0.67945 -0.3048)
			(end 0.67945 0.3048)
			(stroke
				(width 0.1)
				(type default)
			)
			(layer "F.Fab")
		)
		(fp_line
			(start -0.67945 -0.305054)
			(end -0.12065 -0.305054)
			(stroke
				(width 0.1)
				(type default)
			)
			(layer "F.Fab")
		)
		(fp_line
			(start -0.12065 -0.305054)
			(end -0.12065 -0.2794)
			(stroke
				(width 0.1)
				(type default)
			)
			(layer "F.Fab")
		)
		(pad "1" smd circle
			(at -0.40005 0 270)
			(size 0 0)
			(layers "F.Cu" "F.Mask" "F.Paste")
			(net "SMB_BMC_SWB_SCL")
		)
		(pad "2" smd circle
			(at 0.40005 0 270)
			(size 0 0)
			(layers "F.Cu" "F.Mask" "F.Paste")
			(net "SMB_BMC_SWB_R_SCL")
		)
	)
	(footprint ""
		(layer "F.Cu")
		(at 362.1405 -409.654248 180)
		(property "Reference" "R4549"
			(at 0 0 180)
			(layer "F.SilkS")
			(hide yes)
			(effects
				(font
					(size 1.27 1.27)
				)
			)
		)
		(property "Value" ""
			(at 0 0 180)
			(layer "F.Fab")
			(effects
				(font
					(size 1.27 1.27)
				)
			)
		)
		(duplicate_pad_numbers_are_jumpers no)
		(fp_line
			(start 0.7874 0.4064)
			(end -0.7874 0.4064)
			(stroke
				(width 0.1524)
				(type default)
			)
			(layer "F.SilkS")
		)
		(fp_line
			(start 0.7874 -0.4064)
			(end 0.7874 0.4064)
			(stroke
				(width 0.1524)
				(type default)
			)
			(layer "F.SilkS")
		)
		(fp_line
			(start -0.7874 0.4064)
			(end -0.7874 -0.4064)
			(stroke
				(width 0.1524)
				(type default)
			)
			(layer "F.SilkS")
		)
		(fp_line
			(start -0.7874 -0.4064)
			(end 0.7874 -0.4064)
			(stroke
				(width 0.1524)
				(type default)
			)
			(layer "F.SilkS")
		)
		(fp_line
			(start 0.67945 0.3048)
			(end 0.120396 0.3048)
			(stroke
				(width 0.1)
				(type default)
			)
			(layer "F.Fab")
		)
		(fp_line
			(start 0.67945 -0.3048)
			(end 0.67945 0.3048)
			(stroke
				(width 0.1)
				(type default)
			)
			(layer "F.Fab")
		)
		(fp_line
			(start 0.12065 -0.2794)
			(end 0.12065 -0.3048)
			(stroke
				(width 0.1)
				(type default)
			)
			(layer "F.Fab")
		)
		(fp_line
			(start 0.12065 -0.3048)
			(end 0.67945 -0.3048)
			(stroke
				(width 0.1)
				(type default)
			)
			(layer "F.Fab")
		)
		(fp_line
			(start 0.120396 0.3048)
			(end 0.120396 0.2794)
			(stroke
				(width 0.1)
				(type default)
			)
			(layer "F.Fab")
		)
		(fp_line
			(start 0.120396 0.2794)
			(end -0.12065 0.2794)
			(stroke
				(width 0.1)
				(type default)
			)
			(layer "F.Fab")
		)
		(fp_line
			(start -0.12065 0.3048)
			(end -0.67945 0.3048)
			(stroke
				(width 0.1)
				(type default)
			)
			(layer "F.Fab")
		)
		(fp_line
			(start -0.12065 0.2794)
			(end -0.12065 0.3048)
			(stroke
				(width 0.1)
				(type default)
			)
			(layer "F.Fab")
		)
		(fp_line
			(start -0.12065 -0.2794)
			(end 0.12065 -0.2794)
			(stroke
				(width 0.1)
				(type default)
			)
			(layer "F.Fab")
		)
		(fp_line
			(start -0.12065 -0.305054)
			(end -0.12065 -0.2794)
			(stroke
				(width 0.1)
				(type default)
			)
			(layer "F.Fab")
		)
		(fp_line
			(start -0.67945 0.3048)
			(end -0.67945 -0.305054)
			(stroke
				(width 0.1)
				(type default)
			)
			(layer "F.Fab")
		)
		(fp_line
			(start -0.67945 -0.305054)
			(end -0.12065 -0.305054)
			(stroke
				(width 0.1)
				(type default)
			)
			(layer "F.Fab")
		)
		(pad "1" smd circle
			(at -0.40005 0 180)
			(size 0 0)
			(layers "F.Cu" "F.Mask" "F.Paste")
			(net "P3V3_AUX")
		)
		(pad "2" smd circle
			(at 0.40005 0 180)
			(size 0 0)
			(layers "F.Cu" "F.Mask" "F.Paste")
			(net "SWB_HSC_EN_BUF_R")
		)
	)
	(footprint ""
		(layer "F.Cu")
		(at 429.471836 -16.088614 90)
		(property "Reference" "C867"
			(at 0 0 90)
			(layer "F.SilkS")
			(hide yes)
			(effects
				(font
					(size 1.27 1.27)
				)
			)
		)
		(property "Value" ""
			(at 0 0 90)
			(layer "F.Fab")
			(effects
				(font
					(size 1.27 1.27)
				)
			)
		)
		(duplicate_pad_numbers_are_jumpers no)
		(fp_line
			(start 0.299974 -0.150114)
			(end 0.299974 0.150114)
			(stroke
				(width 0.1)
				(type default)
			)
			(layer "F.Fab")
		)
		(fp_line
			(start -0.299974 -0.150114)
			(end 0.299974 -0.150114)
			(stroke
				(width 0.1)
				(type default)
			)
			(layer "F.Fab")
		)
		(fp_line
			(start 0.299974 0.150114)
			(end -0.299974 0.150114)
			(stroke
				(width 0.1)
				(type default)
			)
			(layer "F.Fab")
		)
		(fp_line
			(start -0.299974 0.150114)
			(end -0.299974 -0.150114)
			(stroke
				(width 0.1)
				(type default)
			)
			(layer "F.Fab")
		)
		(pad "1" smd rect
			(at -0.2667 0 90)
			(size 0.3048 0.381)
			(layers "F.Cu" "F.Mask" "F.Paste")
			(net "P5E_CPU0_PE1_TX_C_DP<1>")
		)
		(pad "2" smd rect
			(at 0.2667 0 90)
			(size 0.3048 0.381)
			(layers "F.Cu" "F.Mask" "F.Paste")
			(net "P5E_CPU0_PE1_TX_DP<1>")
		)
	)
	(footprint ""
		(layer "F.Cu")
		(at 459.267814 -381.606552 179.946)
		(property "Reference" "PR91"
			(at 0 0 179.946)
			(layer "F.SilkS")
			(hide yes)
			(effects
				(font
					(size 1.27 1.27)
				)
			)
		)
		(property "Value" ""
			(at 0 0 179.946)
			(layer "F.Fab")
			(effects
				(font
					(size 1.27 1.27)
				)
			)
		)
		(duplicate_pad_numbers_are_jumpers no)
		(fp_line
			(start 0.787525 -0.40638)
			(end 0.787275 0.40642)
			(stroke
				(width 0.1524)
				(type default)
			)
			(layer "F.SilkS")
		)
		(fp_line
			(start 0.787275 0.40642)
			(end -0.787525 0.40638)
			(stroke
				(width 0.1524)
				(type default)
			)
			(layer "F.SilkS")
		)
		(fp_line
			(start -0.787275 -0.40642)
			(end 0.787525 -0.40638)
			(stroke
				(width 0.1524)
				(type default)
			)
			(layer "F.SilkS")
		)
		(fp_line
			(start -0.787525 0.40638)
			(end -0.787275 -0.40642)
			(stroke
				(width 0.1524)
				(type default)
			)
			(layer "F.SilkS")
		)
		(fp_line
			(start 0.679417 -0.304678)
			(end 0.679484 0.304922)
			(stroke
				(width 0.1)
				(type default)
			)
			(layer "F.Fab")
		)
		(fp_line
			(start 0.679484 0.304922)
			(end 0.120429 0.304687)
			(stroke
				(width 0.1)
				(type default)
			)
			(layer "F.Fab")
		)
		(fp_line
			(start 0.120641 -0.279514)
			(end 0.120617 -0.304914)
			(stroke
				(width 0.1)
				(type default)
			)
			(layer "F.Fab")
		)
		(fp_line
			(start 0.120617 -0.304914)
			(end 0.679417 -0.304678)
			(stroke
				(width 0.1)
				(type default)
			)
			(layer "F.Fab")
		)
		(fp_line
			(start 0.120429 0.304687)
			(end 0.120405 0.279287)
			(stroke
				(width 0.1)
				(type default)
			)
			(layer "F.Fab")
		)
		(fp_line
			(start 0.120405 0.279287)
			(end -0.120641 0.279514)
			(stroke
				(width 0.1)
				(type default)
			)
			(layer "F.Fab")
		)
		(fp_line
			(start -0.120659 -0.279286)
			(end 0.120641 -0.279514)
			(stroke
				(width 0.1)
				(type default)
			)
			(layer "F.Fab")
		)
		(fp_line
			(start -0.120683 -0.30494)
			(end -0.120659 -0.279286)
			(stroke
				(width 0.1)
				(type default)
			)
			(layer "F.Fab")
		)
		(fp_line
			(start -0.120617 0.304914)
			(end -0.679417 0.304678)
			(stroke
				(width 0.1)
				(type default)
			)
			(layer "F.Fab")
		)
		(fp_line
			(start -0.120641 0.279514)
			(end -0.120617 0.304914)
			(stroke
				(width 0.1)
				(type default)
			)
			(layer "F.Fab")
		)
		(fp_line
			(start -0.679484 -0.305176)
			(end -0.120683 -0.30494)
			(stroke
				(width 0.1)
				(type default)
			)
			(layer "F.Fab")
		)
		(fp_line
			(start -0.679417 0.304678)
			(end -0.679484 -0.305176)
			(stroke
				(width 0.1)
				(type default)
			)
			(layer "F.Fab")
		)
		(pad "1" smd circle
			(at -0.40005 0 179.946)
			(size 0 0)
			(layers "F.Cu" "F.Mask" "F.Paste")
			(net "P5V_AUX_FB")
		)
		(pad "2" smd circle
			(at 0.40005 0 179.946)
			(size 0 0)
			(layers "F.Cu" "F.Mask" "F.Paste")
			(net "GND")
		)
	)
	(footprint ""
		(layer "F.Cu")
		(at 368.71402 -402.910548)
		(property "Reference" "R3036"
			(at 0 0 0)
			(layer "F.SilkS")
			(hide yes)
			(effects
				(font
					(size 1.27 1.27)
				)
			)
		)
		(property "Value" ""
			(at 0 0 0)
			(layer "F.Fab")
			(effects
				(font
					(size 1.27 1.27)
				)
			)
		)
		(duplicate_pad_numbers_are_jumpers no)
		(fp_line
			(start -0.7874 -0.4064)
			(end 0.7874 -0.4064)
			(stroke
				(width 0.1524)
				(type default)
			)
			(layer "F.SilkS")
		)
		(fp_line
			(start -0.7874 0.4064)
			(end -0.7874 -0.4064)
			(stroke
				(width 0.1524)
				(type default)
			)
			(layer "F.SilkS")
		)
		(fp_line
			(start 0.7874 -0.4064)
			(end 0.7874 0.4064)
			(stroke
				(width 0.1524)
				(type default)
			)
			(layer "F.SilkS")
		)
		(fp_line
			(start 0.7874 0.4064)
			(end -0.7874 0.4064)
			(stroke
				(width 0.1524)
				(type default)
			)
			(layer "F.SilkS")
		)
		(fp_line
			(start -0.67945 -0.305054)
			(end -0.12065 -0.305054)
			(stroke
				(width 0.1)
				(type default)
			)
			(layer "F.Fab")
		)
		(fp_line
			(start -0.67945 0.3048)
			(end -0.67945 -0.305054)
			(stroke
				(width 0.1)
				(type default)
			)
			(layer "F.Fab")
		)
		(fp_line
			(start -0.12065 -0.305054)
			(end -0.12065 -0.2794)
			(stroke
				(width 0.1)
				(type default)
			)
			(layer "F.Fab")
		)
		(fp_line
			(start -0.12065 -0.2794)
			(end 0.12065 -0.2794)
			(stroke
				(width 0.1)
				(type default)
			)
			(layer "F.Fab")
		)
		(fp_line
			(start -0.12065 0.2794)
			(end -0.12065 0.3048)
			(stroke
				(width 0.1)
				(type default)
			)
			(layer "F.Fab")
		)
		(fp_line
			(start -0.12065 0.3048)
			(end -0.67945 0.3048)
			(stroke
				(width 0.1)
				(type default)
			)
			(layer "F.Fab")
		)
		(fp_line
			(start 0.120396 0.2794)
			(end -0.12065 0.2794)
			(stroke
				(width 0.1)
				(type default)
			)
			(layer "F.Fab")
		)
		(fp_line
			(start 0.120396 0.3048)
			(end 0.120396 0.2794)
			(stroke
				(width 0.1)
				(type default)
			)
			(layer "F.Fab")
		)
		(fp_line
			(start 0.12065 -0.3048)
			(end 0.67945 -0.3048)
			(stroke
				(width 0.1)
				(type default)
			)
			(layer "F.Fab")
		)
		(fp_line
			(start 0.12065 -0.2794)
			(end 0.12065 -0.3048)
			(stroke
				(width 0.1)
				(type default)
			)
			(layer "F.Fab")
		)
		(fp_line
			(start 0.67945 -0.3048)
			(end 0.67945 0.3048)
			(stroke
				(width 0.1)
				(type default)
			)
			(layer "F.Fab")
		)
		(fp_line
			(start 0.67945 0.3048)
			(end 0.120396 0.3048)
			(stroke
				(width 0.1)
				(type default)
			)
			(layer "F.Fab")
		)
		(pad "1" smd circle
			(at -0.40005 0)
			(size 0 0)
			(layers "F.Cu" "F.Mask" "F.Paste")
			(net "UART_BMC_BIC_R_BUF_RX")
		)
		(pad "2" smd circle
			(at 0.40005 0)
			(size 0 0)
			(layers "F.Cu" "F.Mask" "F.Paste")
			(net "UART_BMC_BIC_BUF_RX")
		)
	)
	(footprint ""
		(layer "F.Cu")
		(at 58.393076 -79.078836)
		(property "Reference" "D77"
			(at -31.599886 34.341308 90)
			(unlocked yes)
			(layer "F.SilkS")
			(effects
				(font
					(size 0.635 0.4064)
					(thickness 0.1524)
				)
				(justify left)
			)
		)
		(property "Value" ""
			(at 0 0 0)
			(layer "F.Fab")
			(effects
				(font
					(size 1.27 1.27)
				)
			)
		)
		(duplicate_pad_numbers_are_jumpers no)
		(fp_line
			(start -0.90678 0.4826)
			(end -0.90678 -0.4699)
			(stroke
				(width 0.1524)
				(type default)
			)
			(layer "F.SilkS")
		)
		(fp_line
			(start -0.89408 -0.4826)
			(end 0.90678 -0.4826)
			(stroke
				(width 0.1524)
				(type default)
			)
			(layer "F.SilkS")
		)
		(fp_line
			(start -0.79248 -0.4826)
			(end 1.03378 -0.4826)
			(stroke
				(width 0.1524)
				(type default)
			)
			(layer "F.SilkS")
		)
		(fp_line
			(start -0.64008 -0.4826)
			(end 1.16078 -0.4826)
			(stroke
				(width 0.1524)
				(type default)
			)
			(layer "F.SilkS")
		)
		(fp_line
			(start 0.90678 -0.4826)
			(end 0.90678 0.4826)
			(stroke
				(width 0.1524)
				(type default)
			)
			(layer "F.SilkS")
		)
		(fp_line
			(start 0.90678 0.4826)
			(end -0.90678 0.4826)
			(stroke
				(width 0.1524)
				(type default)
			)
			(layer "F.SilkS")
		)
		(fp_line
			(start 1.03378 -0.4826)
			(end 1.03378 0.4826)
			(stroke
				(width 0.1524)
				(type default)
			)
			(layer "F.SilkS")
		)
		(fp_line
			(start 1.03378 0.4826)
			(end -0.79248 0.4826)
			(stroke
				(width 0.1524)
				(type default)
			)
			(layer "F.SilkS")
		)
		(fp_line
			(start 1.16078 -0.4826)
			(end 1.16078 0.4826)
			(stroke
				(width 0.1524)
				(type default)
			)
			(layer "F.SilkS")
		)
		(fp_line
			(start 1.16078 0.4826)
			(end -0.64008 0.4826)
			(stroke
				(width 0.1524)
				(type default)
			)
			(layer "F.SilkS")
		)
		(fp_line
			(start -0.499872 -0.249936)
			(end 0.499872 -0.249936)
			(stroke
				(width 0.1)
				(type default)
			)
			(layer "F.Fab")
		)
		(fp_line
			(start -0.499872 0.249936)
			(end -0.499872 -0.249936)
			(stroke
				(width 0.1)
				(type default)
			)
			(layer "F.Fab")
		)
		(fp_line
			(start 0.499872 -0.249936)
			(end 0.499872 0.249936)
			(stroke
				(width 0.1)
				(type default)
			)
			(layer "F.Fab")
		)
		(fp_line
			(start 0.499872 0.249936)
			(end -0.499872 0.249936)
			(stroke
				(width 0.1)
				(type default)
			)
			(layer "F.Fab")
		)
		(pad "A" smd rect
			(at -0.47498 0)
			(size 0.6096 0.7112)
			(layers "F.Cu" "F.Mask" "F.Paste")
			(net "LED_PWRGD_PVCCINFAON_CPU0")
		)
		(pad "C" smd rect
			(at 0.47498 0)
			(size 0.6096 0.7112)
			(layers "F.Cu" "F.Mask" "F.Paste")
			(net "LED_PWRGD_PVCCINFAON_CPU0_D")
		)
	)
	(footprint ""
		(layer "F.Cu")
		(at 28.578048 -70.83425)
		(property "Reference" "R3142"
			(at 0 0 0)
			(layer "F.SilkS")
			(hide yes)
			(effects
				(font
					(size 1.27 1.27)
				)
			)
		)
		(property "Value" ""
			(at 0 0 0)
			(layer "F.Fab")
			(effects
				(font
					(size 1.27 1.27)
				)
			)
		)
		(duplicate_pad_numbers_are_jumpers no)
		(fp_line
			(start -0.7874 -0.4064)
			(end 0.7874 -0.4064)
			(stroke
				(width 0.1524)
				(type default)
			)
			(layer "F.SilkS")
		)
		(fp_line
			(start -0.7874 0.4064)
			(end -0.7874 -0.4064)
			(stroke
				(width 0.1524)
				(type default)
			)
			(layer "F.SilkS")
		)
		(fp_line
			(start 0.7874 -0.4064)
			(end 0.7874 0.4064)
			(stroke
				(width 0.1524)
				(type default)
			)
			(layer "F.SilkS")
		)
		(fp_line
			(start 0.7874 0.4064)
			(end -0.7874 0.4064)
			(stroke
				(width 0.1524)
				(type default)
			)
			(layer "F.SilkS")
		)
		(fp_line
			(start -0.67945 -0.305054)
			(end -0.12065 -0.305054)
			(stroke
				(width 0.1)
				(type default)
			)
			(layer "F.Fab")
		)
		(fp_line
			(start -0.67945 0.3048)
			(end -0.67945 -0.305054)
			(stroke
				(width 0.1)
				(type default)
			)
			(layer "F.Fab")
		)
		(fp_line
			(start -0.12065 -0.305054)
			(end -0.12065 -0.2794)
			(stroke
				(width 0.1)
				(type default)
			)
			(layer "F.Fab")
		)
		(fp_line
			(start -0.12065 -0.2794)
			(end 0.12065 -0.2794)
			(stroke
				(width 0.1)
				(type default)
			)
			(layer "F.Fab")
		)
		(fp_line
			(start -0.12065 0.2794)
			(end -0.12065 0.3048)
			(stroke
				(width 0.1)
				(type default)
			)
			(layer "F.Fab")
		)
		(fp_line
			(start -0.12065 0.3048)
			(end -0.67945 0.3048)
			(stroke
				(width 0.1)
				(type default)
			)
			(layer "F.Fab")
		)
		(fp_line
			(start 0.120396 0.2794)
			(end -0.12065 0.2794)
			(stroke
				(width 0.1)
				(type default)
			)
			(layer "F.Fab")
		)
		(fp_line
			(start 0.120396 0.3048)
			(end 0.120396 0.2794)
			(stroke
				(width 0.1)
				(type default)
			)
			(layer "F.Fab")
		)
		(fp_line
			(start 0.12065 -0.3048)
			(end 0.67945 -0.3048)
			(stroke
				(width 0.1)
				(type default)
			)
			(layer "F.Fab")
		)
		(fp_line
			(start 0.12065 -0.2794)
			(end 0.12065 -0.3048)
			(stroke
				(width 0.1)
				(type default)
			)
			(layer "F.Fab")
		)
		(fp_line
			(start 0.67945 -0.3048)
			(end 0.67945 0.3048)
			(stroke
				(width 0.1)
				(type default)
			)
			(layer "F.Fab")
		)
		(fp_line
			(start 0.67945 0.3048)
			(end 0.120396 0.3048)
			(stroke
				(width 0.1)
				(type default)
			)
			(layer "F.Fab")
		)
		(pad "1" smd circle
			(at -0.40005 0)
			(size 0 0)
			(layers "F.Cu" "F.Mask" "F.Paste")
			(net "HP_LVC3_OCP_V3_2_PRSNT2_N_R")
		)
		(pad "2" smd circle
			(at 0.40005 0)
			(size 0 0)
			(layers "F.Cu" "F.Mask" "F.Paste")
			(net "HP_LVC3_OCP_V3_2_PRSNT2_N")
		)
	)
	(footprint ""
		(layer "F.Cu")
		(at 317.418212 -62.342268)
		(property "Reference" "R1266"
			(at 0 0 0)
			(layer "F.SilkS")
			(hide yes)
			(effects
				(font
					(size 1.27 1.27)
				)
			)
		)
		(property "Value" ""
			(at 0 0 0)
			(layer "F.Fab")
			(effects
				(font
					(size 1.27 1.27)
				)
			)
		)
		(duplicate_pad_numbers_are_jumpers no)
		(fp_line
			(start -0.7874 -0.4064)
			(end 0.7874 -0.4064)
			(stroke
				(width 0.1524)
				(type default)
			)
			(layer "F.SilkS")
		)
		(fp_line
			(start -0.7874 0.4064)
			(end -0.7874 -0.4064)
			(stroke
				(width 0.1524)
				(type default)
			)
			(layer "F.SilkS")
		)
		(fp_line
			(start 0.7874 -0.4064)
			(end 0.7874 0.4064)
			(stroke
				(width 0.1524)
				(type default)
			)
			(layer "F.SilkS")
		)
		(fp_line
			(start 0.7874 0.4064)
			(end -0.7874 0.4064)
			(stroke
				(width 0.1524)
				(type default)
			)
			(layer "F.SilkS")
		)
		(fp_line
			(start -0.67945 -0.305054)
			(end -0.12065 -0.305054)
			(stroke
				(width 0.1)
				(type default)
			)
			(layer "F.Fab")
		)
		(fp_line
			(start -0.67945 0.3048)
			(end -0.67945 -0.305054)
			(stroke
				(width 0.1)
				(type default)
			)
			(layer "F.Fab")
		)
		(fp_line
			(start -0.12065 -0.305054)
			(end -0.12065 -0.2794)
			(stroke
				(width 0.1)
				(type default)
			)
			(layer "F.Fab")
		)
		(fp_line
			(start -0.12065 -0.2794)
			(end 0.12065 -0.2794)
			(stroke
				(width 0.1)
				(type default)
			)
			(layer "F.Fab")
		)
		(fp_line
			(start -0.12065 0.2794)
			(end -0.12065 0.3048)
			(stroke
				(width 0.1)
				(type default)
			)
			(layer "F.Fab")
		)
		(fp_line
			(start -0.12065 0.3048)
			(end -0.67945 0.3048)
			(stroke
				(width 0.1)
				(type default)
			)
			(layer "F.Fab")
		)
		(fp_line
			(start 0.120396 0.2794)
			(end -0.12065 0.2794)
			(stroke
				(width 0.1)
				(type default)
			)
			(layer "F.Fab")
		)
		(fp_line
			(start 0.120396 0.3048)
			(end 0.120396 0.2794)
			(stroke
				(width 0.1)
				(type default)
			)
			(layer "F.Fab")
		)
		(fp_line
			(start 0.12065 -0.3048)
			(end 0.67945 -0.3048)
			(stroke
				(width 0.1)
				(type default)
			)
			(layer "F.Fab")
		)
		(fp_line
			(start 0.12065 -0.2794)
			(end 0.12065 -0.3048)
			(stroke
				(width 0.1)
				(type default)
			)
			(layer "F.Fab")
		)
		(fp_line
			(start 0.67945 -0.3048)
			(end 0.67945 0.3048)
			(stroke
				(width 0.1)
				(type default)
			)
			(layer "F.Fab")
		)
		(fp_line
			(start 0.67945 0.3048)
			(end 0.120396 0.3048)
			(stroke
				(width 0.1)
				(type default)
			)
			(layer "F.Fab")
		)
		(pad "1" smd circle
			(at -0.40005 0)
			(size 0 0)
			(layers "F.Cu" "F.Mask" "F.Paste")
			(net "P1V05_PCH_AUX")
		)
		(pad "2" smd circle
			(at 0.40005 0)
			(size 0 0)
			(layers "F.Cu" "F.Mask" "F.Paste")
			(net "H_THERMTRIP_LVC1_N")
		)
	)
	(footprint ""
		(layer "F.Cu")
		(at 75.546458 -20.950682 180)
		(property "Reference" "PR3821"
			(at 0 0 180)
			(layer "F.SilkS")
			(hide yes)
			(effects
				(font
					(size 1.27 1.27)
				)
			)
		)
		(property "Value" ""
			(at 0 0 180)
			(layer "F.Fab")
			(effects
				(font
					(size 1.27 1.27)
				)
			)
		)
		(duplicate_pad_numbers_are_jumpers no)
		(fp_line
			(start 0.7874 0.4064)
			(end -0.7874 0.4064)
			(stroke
				(width 0.1524)
				(type default)
			)
			(layer "F.SilkS")
		)
		(fp_line
			(start 0.7874 -0.4064)
			(end 0.7874 0.4064)
			(stroke
				(width 0.1524)
				(type default)
			)
			(layer "F.SilkS")
		)
		(fp_line
			(start -0.7874 0.4064)
			(end -0.7874 -0.4064)
			(stroke
				(width 0.1524)
				(type default)
			)
			(layer "F.SilkS")
		)
		(fp_line
			(start -0.7874 -0.4064)
			(end 0.7874 -0.4064)
			(stroke
				(width 0.1524)
				(type default)
			)
			(layer "F.SilkS")
		)
		(fp_line
			(start 0.67945 0.3048)
			(end 0.120396 0.3048)
			(stroke
				(width 0.1)
				(type default)
			)
			(layer "F.Fab")
		)
		(fp_line
			(start 0.67945 -0.3048)
			(end 0.67945 0.3048)
			(stroke
				(width 0.1)
				(type default)
			)
			(layer "F.Fab")
		)
		(fp_line
			(start 0.12065 -0.2794)
			(end 0.12065 -0.3048)
			(stroke
				(width 0.1)
				(type default)
			)
			(layer "F.Fab")
		)
		(fp_line
			(start 0.12065 -0.3048)
			(end 0.67945 -0.3048)
			(stroke
				(width 0.1)
				(type default)
			)
			(layer "F.Fab")
		)
		(fp_line
			(start 0.120396 0.3048)
			(end 0.120396 0.2794)
			(stroke
				(width 0.1)
				(type default)
			)
			(layer "F.Fab")
		)
		(fp_line
			(start 0.120396 0.2794)
			(end -0.12065 0.2794)
			(stroke
				(width 0.1)
				(type default)
			)
			(layer "F.Fab")
		)
		(fp_line
			(start -0.12065 0.3048)
			(end -0.67945 0.3048)
			(stroke
				(width 0.1)
				(type default)
			)
			(layer "F.Fab")
		)
		(fp_line
			(start -0.12065 0.2794)
			(end -0.12065 0.3048)
			(stroke
				(width 0.1)
				(type default)
			)
			(layer "F.Fab")
		)
		(fp_line
			(start -0.12065 -0.2794)
			(end 0.12065 -0.2794)
			(stroke
				(width 0.1)
				(type default)
			)
			(layer "F.Fab")
		)
		(fp_line
			(start -0.12065 -0.305054)
			(end -0.12065 -0.2794)
			(stroke
				(width 0.1)
				(type default)
			)
			(layer "F.Fab")
		)
		(fp_line
			(start -0.67945 0.3048)
			(end -0.67945 -0.305054)
			(stroke
				(width 0.1)
				(type default)
			)
			(layer "F.Fab")
		)
		(fp_line
			(start -0.67945 -0.305054)
			(end -0.12065 -0.305054)
			(stroke
				(width 0.1)
				(type default)
			)
			(layer "F.Fab")
		)
		(pad "1" smd circle
			(at -0.40005 0 180)
			(size 0 0)
			(layers "F.Cu" "F.Mask" "F.Paste")
			(net "P12V_OCP_CB_2")
		)
		(pad "2" smd circle
			(at 0.40005 0 180)
			(size 0 0)
			(layers "F.Cu" "F.Mask" "F.Paste")
			(net "GND")
		)
	)
	(footprint ""
		(layer "F.Cu")
		(at 166.42588 -436.971948)
		(property "Reference" "U253"
			(at -1.43256 -2.86385 0)
			(unlocked yes)
			(layer "F.SilkS")
			(effects
				(font
					(size 0.7874 0.5842)
					(thickness 0.1524)
				)
				(justify left)
			)
		)
		(property "Value" ""
			(at 0 0 0)
			(layer "F.Fab")
			(effects
				(font
					(size 1.27 1.27)
				)
			)
		)
		(duplicate_pad_numbers_are_jumpers no)
		(fp_line
			(start -1.3462 -1.100074)
			(end -0.670052 -1.100074)
			(stroke
				(width 0.1524)
				(type default)
			)
			(layer "F.SilkS")
		)
		(fp_line
			(start -1.3462 1.100074)
			(end -1.3462 -1.100074)
			(stroke
				(width 0.1524)
				(type default)
			)
			(layer "F.SilkS")
		)
		(fp_line
			(start -0.670052 -1.100074)
			(end 0 -0.381)
			(stroke
				(width 0.1524)
				(type default)
			)
			(layer "F.SilkS")
		)
		(fp_line
			(start 0 -0.381)
			(end 0.670052 -1.100074)
			(stroke
				(width 0.1524)
				(type default)
			)
			(layer "F.SilkS")
		)
		(fp_line
			(start 0.670052 -1.100074)
			(end 1.3462 -1.100074)
			(stroke
				(width 0.1524)
				(type default)
			)
			(layer "F.SilkS")
		)
		(fp_line
			(start 1.3462 -1.100074)
			(end 1.3462 1.100074)
			(stroke
				(width 0.1524)
				(type default)
			)
			(layer "F.SilkS")
		)
		(fp_line
			(start 1.3462 1.100074)
			(end -1.3462 1.100074)
			(stroke
				(width 0.1524)
				(type default)
			)
			(layer "F.SilkS")
		)
		(fp_poly
			(pts
				(xy -1.056894 -1.39446) (xy -1.437894 -2.15646) (xy -0.675894 -2.15646)
			)
			(stroke
				(width 0)
				(type default)
			)
			(fill yes)
			(layer "F.SilkS")
		)
		(fp_line
			(start -1.100074 -0.8001)
			(end -0.670052 -0.8001)
			(stroke
				(width 0.1)
				(type default)
			)
			(layer "F.Fab")
		)
		(fp_line
			(start -1.100074 0.8001)
			(end -1.100074 -0.8001)
			(stroke
				(width 0.1)
				(type default)
			)
			(layer "F.Fab")
		)
		(fp_line
			(start -0.670052 -1.100074)
			(end 0.670052 -1.100074)
			(stroke
				(width 0.1)
				(type default)
			)
			(layer "F.Fab")
		)
		(fp_line
			(start -0.670052 -0.8001)
			(end -0.670052 -1.100074)
			(stroke
				(width 0.1)
				(type default)
			)
			(layer "F.Fab")
		)
		(fp_line
			(start -0.670052 0.8001)
			(end -1.100074 0.8001)
			(stroke
				(width 0.1)
				(type default)
			)
			(layer "F.Fab")
		)
		(fp_line
			(start -0.670052 0.8001)
			(end -0.670052 -0.8001)
			(stroke
				(width 0.1)
				(type default)
			)
			(layer "F.Fab")
		)
		(fp_line
			(start -0.670052 1.100074)
			(end -0.670052 0.8001)
			(stroke
				(width 0.1)
				(type default)
			)
			(layer "F.Fab")
		)
		(fp_line
			(start 0.670052 -1.100074)
			(end 0.670052 -0.8001)
			(stroke
				(width 0.1)
				(type default)
			)
			(layer "F.Fab")
		)
		(fp_line
			(start 0.670052 -0.8001)
			(end 0.670052 0.8001)
			(stroke
				(width 0.1)
				(type default)
			)
			(layer "F.Fab")
		)
		(fp_line
			(start 0.670052 -0.8001)
			(end 1.100074 -0.8001)
			(stroke
				(width 0.1)
				(type default)
			)
			(layer "F.Fab")
		)
		(fp_line
			(start 0.670052 0.8001)
			(end 0.670052 1.100074)
			(stroke
				(width 0.1)
				(type default)
			)
			(layer "F.Fab")
		)
		(fp_line
			(start 0.670052 1.100074)
			(end -0.670052 1.100074)
			(stroke
				(width 0.1)
				(type default)
			)
			(layer "F.Fab")
		)
		(fp_line
			(start 1.100074 -0.8001)
			(end 1.100074 0.8001)
			(stroke
				(width 0.1)
				(type default)
			)
			(layer "F.Fab")
		)
		(fp_line
			(start 1.100074 0.8001)
			(end 0.670052 0.8001)
			(stroke
				(width 0.1)
				(type default)
			)
			(layer "F.Fab")
		)
		(fp_poly
			(pts
				(xy -1.524 -0.649986) (xy -2.286 -1.030986) (xy -2.286 -0.268986)
			)
			(stroke
				(width 0)
				(type default)
			)
			(fill yes)
			(layer "F.Fab")
		)
		(pad "1" smd rect
			(at -0.94996 -0.649986 270)
			(size 0.4064 0.508)
			(layers "F.Cu" "F.Mask" "F.Paste")
			(net "GPU_FPGA_BOOT_EN")
		)
		(pad "2" smd rect
			(at -0.94996 0 270)
			(size 0.4064 0.508)
			(layers "F.Cu" "F.Mask" "F.Paste")
			(net "GND")
		)
		(pad "3" smd rect
			(at -0.94996 0.649986 270)
			(size 0.4064 0.508)
			(layers "F.Cu" "F.Mask" "F.Paste")
			(net "GPU_BASE_STBY_EN")
		)
		(pad "4" smd rect
			(at 0.94996 0.649986 270)
			(size 0.4064 0.508)
			(layers "F.Cu" "F.Mask" "F.Paste")
			(net "GPU_BASE_STBY_EN_BUF_R")
		)
		(pad "5" smd rect
			(at 0.94996 0 270)
			(size 0.4064 0.508)
			(layers "F.Cu" "F.Mask" "F.Paste")
			(net "P3V3_AUX")
		)
		(pad "6" smd rect
			(at 0.94996 -0.649986 270)
			(size 0.4064 0.508)
			(layers "F.Cu" "F.Mask" "F.Paste")
			(net "GPU_FPGA_BOOT_EN_BUF_R")
		)
	)
	(footprint ""
		(layer "F.Cu")
		(at 423.890948 -258.091686)
		(property "Reference" "J12"
			(at -3.683 -81.702148 0)
			(unlocked yes)
			(layer "F.SilkS")
			(effects
				(font
					(size 0.7874 0.5842)
					(thickness 0.1524)
				)
				(justify left)
			)
		)
		(property "Value" ""
			(at 0 0 0)
			(layer "F.Fab")
			(effects
				(font
					(size 1.27 1.27)
				)
			)
		)
		(duplicate_pad_numbers_are_jumpers no)
		(fp_line
			(start -3.24993 -81.000092)
			(end -3.24993 75.033378)
			(stroke
				(width 0.1524)
				(type default)
			)
			(layer "F.SilkS")
		)
		(fp_line
			(start -3.24993 81.000092)
			(end 3.24993 81.000092)
			(stroke
				(width 0.1524)
				(type default)
			)
			(layer "F.SilkS")
		)
		(fp_line
			(start 3.24993 -81.000092)
			(end -3.24993 -81.000092)
			(stroke
				(width 0.1524)
				(type default)
			)
			(layer "F.SilkS")
		)
		(fp_line
			(start 3.24993 -72.00011)
			(end -3.24993 -72.00011)
			(stroke
				(width 0.1524)
				(type default)
			)
			(layer "F.SilkS")
		)
		(fp_line
			(start 3.24993 72.00011)
			(end -3.24993 72.00011)
			(stroke
				(width 0.1524)
				(type default)
			)
			(layer "F.SilkS")
		)
		(fp_line
			(start 3.24993 74.626978)
			(end 3.24993 -81.000092)
			(stroke
				(width 0.1524)
				(type default)
			)
			(layer "F.SilkS")
		)
		(fp_line
			(start 3.24993 81.000092)
			(end 3.24993 78.363318)
			(stroke
				(width 0.1524)
				(type default)
			)
			(layer "F.SilkS")
		)
		(fp_poly
			(pts
				(xy -4.172204 -63.744602) (xy -3.330956 -63.323978) (xy -4.172204 -62.903354)
			)
			(stroke
				(width 0)
				(type default)
			)
			(fill yes)
			(layer "F.SilkS")
		)
		(fp_line
			(start -3.24993 -81.000092)
			(end -3.24993 81.000092)
			(stroke
				(width 0.1)
				(type default)
			)
			(layer "F.Fab")
		)
		(fp_line
			(start -3.24993 81.000092)
			(end 3.24993 81.000092)
			(stroke
				(width 0.1)
				(type default)
			)
			(layer "F.Fab")
		)
		(fp_line
			(start 3.24993 -81.000092)
			(end -3.24993 -81.000092)
			(stroke
				(width 0.1)
				(type default)
			)
			(layer "F.Fab")
		)
		(fp_line
			(start 3.24993 -72.00011)
			(end -3.24993 -72.00011)
			(stroke
				(width 0.1)
				(type default)
			)
			(layer "F.Fab")
		)
		(fp_line
			(start 3.24993 -71.000112)
			(end -3.24993 -71.000112)
			(stroke
				(width 0.1)
				(type default)
			)
			(layer "F.Fab")
		)
		(fp_line
			(start 3.24993 71.000112)
			(end -3.24993 71.000112)
			(stroke
				(width 0.1)
				(type default)
			)
			(layer "F.Fab")
		)
		(fp_line
			(start 3.24993 72.00011)
			(end -3.24993 72.00011)
			(stroke
				(width 0.1)
				(type default)
			)
			(layer "F.Fab")
		)
		(fp_line
			(start 3.24993 81.000092)
			(end 3.24993 -81.000092)
			(stroke
				(width 0.1)
				(type default)
			)
			(layer "F.Fab")
		)
		(fp_poly
			(pts
				(xy -4.445 -63.832994) (xy -4.445 -62.816994) (xy -3.429 -63.324994)
			)
			(stroke
				(width 0)
				(type default)
			)
			(fill yes)
			(layer "F.Fab")
		)
		(pad "1" smd rect
			(at -2.050034 -63.324994 270)
			(size 0.519938 1.4986)
			(layers "F.Cu" "F.Mask" "F.Paste")
			(net "P12V_S3_AUX_CPU0_NVDIMM")
		)
		(pad "2" smd rect
			(at -2.050034 -62.47511 270)
			(size 0.519938 1.4986)
			(layers "F.Cu" "F.Mask" "F.Paste")
			(net "TP_CHF_CPU0_DIMM2_FRU_0")
		)
		(pad "3" smd rect
			(at -2.050034 -61.624972 270)
			(size 0.519938 1.4986)
			(layers "F.Cu" "F.Mask" "F.Paste")
			(net "P3V3_AUX")
		)
		(pad "4" smd rect
			(at -2.050034 -60.775088 270)
			(size 0.519938 1.4986)
			(layers "F.Cu" "F.Mask" "F.Paste")
			(net "I3C_SPD_DDREFGH_CPU0_LVC1_SCL_3")
		)
		(pad "5" smd rect
			(at -2.050034 -59.92495 270)
			(size 0.519938 1.4986)
			(layers "F.Cu" "F.Mask" "F.Paste")
			(net "I3C_SPD_DDREFGH_CPU0_LVC1_SDA")
		)
		(pad "6" smd rect
			(at -2.050034 -59.075066 270)
			(size 0.519938 1.4986)
			(layers "F.Cu" "F.Mask" "F.Paste")
			(net "GND")
		)
		(pad "7" smd rect
			(at -2.050034 -58.224928 270)
			(size 0.519938 1.4986)
			(layers "F.Cu" "F.Mask" "F.Paste")
			(net "M_F_CPU0_SA_DQ<0>")
		)
		(pad "8" smd rect
			(at -2.050034 -57.375044 270)
			(size 0.519938 1.4986)
			(layers "F.Cu" "F.Mask" "F.Paste")
			(net "GND")
		)
		(pad "9" smd rect
			(at -2.050034 -56.524906 270)
			(size 0.519938 1.4986)
			(layers "F.Cu" "F.Mask" "F.Paste")
			(net "M_F_CPU0_SA_DQ<1>")
		)
		(pad "10" smd rect
			(at -2.050034 -55.675022 270)
			(size 0.519938 1.4986)
			(layers "F.Cu" "F.Mask" "F.Paste")
			(net "GND")
		)
		(pad "11" smd rect
			(at -2.050034 -54.824884 270)
			(size 0.519938 1.4986)
			(layers "F.Cu" "F.Mask" "F.Paste")
			(net "M_F_CPU0_SA_DQS_DP<0>")
		)
		(pad "12" smd rect
			(at -2.050034 -53.975 270)
			(size 0.519938 1.4986)
			(layers "F.Cu" "F.Mask" "F.Paste")
			(net "M_F_CPU0_SA_DQS_DN<0>")
		)
		(pad "13" smd rect
			(at -2.050034 -53.125116 270)
			(size 0.519938 1.4986)
			(layers "F.Cu" "F.Mask" "F.Paste")
			(net "GND")
		)
		(pad "14" smd rect
			(at -2.050034 -52.274978 270)
			(size 0.519938 1.4986)
			(layers "F.Cu" "F.Mask" "F.Paste")
			(net "M_F_CPU0_SA_DQ<4>")
		)
		(pad "15" smd rect
			(at -2.050034 -51.425094 270)
			(size 0.519938 1.4986)
			(layers "F.Cu" "F.Mask" "F.Paste")
			(net "GND")
		)
		(pad "16" smd rect
			(at -2.050034 -50.574956 270)
			(size 0.519938 1.4986)
			(layers "F.Cu" "F.Mask" "F.Paste")
			(net "M_F_CPU0_SA_DQ<5>")
		)
		(pad "17" smd rect
			(at -2.050034 -49.725072 270)
			(size 0.519938 1.4986)
			(layers "F.Cu" "F.Mask" "F.Paste")
			(net "GND")
		)
		(pad "18" smd rect
			(at -2.050034 -48.874934 270)
			(size 0.519938 1.4986)
			(layers "F.Cu" "F.Mask" "F.Paste")
			(net "M_F_CPU0_SA_DQ<8>")
		)
		(pad "19" smd rect
			(at -2.050034 -48.02505 270)
			(size 0.519938 1.4986)
			(layers "F.Cu" "F.Mask" "F.Paste")
			(net "GND")
		)
		(pad "20" smd rect
			(at -2.050034 -47.174912 270)
			(size 0.519938 1.4986)
			(layers "F.Cu" "F.Mask" "F.Paste")
			(net "M_F_CPU0_SA_DQ<9>")
		)
		(pad "21" smd rect
			(at -2.050034 -46.325028 270)
			(size 0.519938 1.4986)
			(layers "F.Cu" "F.Mask" "F.Paste")
			(net "GND")
		)
		(pad "22" smd rect
			(at -2.050034 -45.47489 270)
			(size 0.519938 1.4986)
			(layers "F.Cu" "F.Mask" "F.Paste")
			(net "M_F_CPU0_SA_DQS_DP<1>")
		)
		(pad "23" smd rect
			(at -2.050034 -44.625006 270)
			(size 0.519938 1.4986)
			(layers "F.Cu" "F.Mask" "F.Paste")
			(net "M_F_CPU0_SA_DQS_DN<1>")
		)
		(pad "24" smd rect
			(at -2.050034 -43.775122 270)
			(size 0.519938 1.4986)
			(layers "F.Cu" "F.Mask" "F.Paste")
			(net "GND")
		)
		(pad "25" smd rect
			(at -2.050034 -42.924984 270)
			(size 0.519938 1.4986)
			(layers "F.Cu" "F.Mask" "F.Paste")
			(net "M_F_CPU0_SA_DQ<12>")
		)
		(pad "26" smd rect
			(at -2.050034 -42.0751 270)
			(size 0.519938 1.4986)
			(layers "F.Cu" "F.Mask" "F.Paste")
			(net "GND")
		)
		(pad "27" smd rect
			(at -2.050034 -41.224962 270)
			(size 0.519938 1.4986)
			(layers "F.Cu" "F.Mask" "F.Paste")
			(net "M_F_CPU0_SA_DQ<13>")
		)
		(pad "28" smd rect
			(at -2.050034 -40.375078 270)
			(size 0.519938 1.4986)
			(layers "F.Cu" "F.Mask" "F.Paste")
			(net "GND")
		)
		(pad "29" smd rect
			(at -2.050034 -39.52494 270)
			(size 0.519938 1.4986)
			(layers "F.Cu" "F.Mask" "F.Paste")
			(net "M_F_CPU0_SA_DQ<16>")
		)
		(pad "30" smd rect
			(at -2.050034 -38.675056 270)
			(size 0.519938 1.4986)
			(layers "F.Cu" "F.Mask" "F.Paste")
			(net "GND")
		)
		(pad "31" smd rect
			(at -2.050034 -37.824918 270)
			(size 0.519938 1.4986)
			(layers "F.Cu" "F.Mask" "F.Paste")
			(net "M_F_CPU0_SA_DQ<17>")
		)
		(pad "32" smd rect
			(at -2.050034 -36.975034 270)
			(size 0.519938 1.4986)
			(layers "F.Cu" "F.Mask" "F.Paste")
			(net "GND")
		)
		(pad "33" smd rect
			(at -2.050034 -36.124896 270)
			(size 0.519938 1.4986)
			(layers "F.Cu" "F.Mask" "F.Paste")
			(net "M_F_CPU0_SA_DQS_DP<2>")
		)
		(pad "34" smd rect
			(at -2.050034 -35.275012 270)
			(size 0.519938 1.4986)
			(layers "F.Cu" "F.Mask" "F.Paste")
			(net "M_F_CPU0_SA_DQS_DN<2>")
		)
		(pad "35" smd rect
			(at -2.050034 -34.425128 270)
			(size 0.519938 1.4986)
			(layers "F.Cu" "F.Mask" "F.Paste")
			(net "GND")
		)
		(pad "36" smd rect
			(at -2.050034 -33.57499 270)
			(size 0.519938 1.4986)
			(layers "F.Cu" "F.Mask" "F.Paste")
			(net "M_F_CPU0_SA_DQ<20>")
		)
		(pad "37" smd rect
			(at -2.050034 -32.725106 270)
			(size 0.519938 1.4986)
			(layers "F.Cu" "F.Mask" "F.Paste")
			(net "GND")
		)
		(pad "38" smd rect
			(at -2.050034 -31.874968 270)
			(size 0.519938 1.4986)
			(layers "F.Cu" "F.Mask" "F.Paste")
			(net "M_F_CPU0_SA_DQ<21>")
		)
		(pad "39" smd rect
			(at -2.050034 -31.025084 270)
			(size 0.519938 1.4986)
			(layers "F.Cu" "F.Mask" "F.Paste")
			(net "GND")
		)
		(pad "40" smd rect
			(at -2.050034 -30.174946 270)
			(size 0.519938 1.4986)
			(layers "F.Cu" "F.Mask" "F.Paste")
			(net "M_F_CPU0_SA_DQ<24>")
		)
		(pad "41" smd rect
			(at -2.050034 -29.325062 270)
			(size 0.519938 1.4986)
			(layers "F.Cu" "F.Mask" "F.Paste")
			(net "GND")
		)
		(pad "42" smd rect
			(at -2.050034 -28.474924 270)
			(size 0.519938 1.4986)
			(layers "F.Cu" "F.Mask" "F.Paste")
			(net "M_F_CPU0_SA_DQ<25>")
		)
		(pad "43" smd rect
			(at -2.050034 -27.62504 270)
			(size 0.519938 1.4986)
			(layers "F.Cu" "F.Mask" "F.Paste")
			(net "GND")
		)
		(pad "44" smd rect
			(at -2.050034 -26.774902 270)
			(size 0.519938 1.4986)
			(layers "F.Cu" "F.Mask" "F.Paste")
			(net "M_F_CPU0_SA_DQS_DP<3>")
		)
		(pad "45" smd rect
			(at -2.050034 -25.925018 270)
			(size 0.519938 1.4986)
			(layers "F.Cu" "F.Mask" "F.Paste")
			(net "M_F_CPU0_SA_DQS_DN<3>")
		)
		(pad "46" smd rect
			(at -2.050034 -25.07488 270)
			(size 0.519938 1.4986)
			(layers "F.Cu" "F.Mask" "F.Paste")
			(net "GND")
		)
		(pad "47" smd rect
			(at -2.050034 -24.224996 270)
			(size 0.519938 1.4986)
			(layers "F.Cu" "F.Mask" "F.Paste")
			(net "M_F_CPU0_SA_DQ<28>")
		)
		(pad "48" smd rect
			(at -2.050034 -23.375112 270)
			(size 0.519938 1.4986)
			(layers "F.Cu" "F.Mask" "F.Paste")
			(net "GND")
		)
		(pad "49" smd rect
			(at -2.050034 -22.524974 270)
			(size 0.519938 1.4986)
			(layers "F.Cu" "F.Mask" "F.Paste")
			(net "M_F_CPU0_SA_DQ<29>")
		)
		(pad "50" smd rect
			(at -2.050034 -21.67509 270)
			(size 0.519938 1.4986)
			(layers "F.Cu" "F.Mask" "F.Paste")
			(net "GND")
		)
		(pad "51" smd rect
			(at -2.050034 -20.824952 270)
			(size 0.519938 1.4986)
			(layers "F.Cu" "F.Mask" "F.Paste")
			(net "M_F_CPU0_SA_CB<0>")
		)
		(pad "52" smd rect
			(at -2.050034 -19.975068 270)
			(size 0.519938 1.4986)
			(layers "F.Cu" "F.Mask" "F.Paste")
			(net "GND")
		)
		(pad "53" smd rect
			(at -2.050034 -19.12493 270)
			(size 0.519938 1.4986)
			(layers "F.Cu" "F.Mask" "F.Paste")
			(net "M_F_CPU0_SA_CB<1>")
		)
		(pad "54" smd rect
			(at -2.050034 -18.275046 270)
			(size 0.519938 1.4986)
			(layers "F.Cu" "F.Mask" "F.Paste")
			(net "GND")
		)
		(pad "55" smd rect
			(at -2.050034 -17.424908 270)
			(size 0.519938 1.4986)
			(layers "F.Cu" "F.Mask" "F.Paste")
			(net "M_F_CPU0_SA_DQS_DP<4>")
		)
		(pad "56" smd rect
			(at -2.050034 -16.575024 270)
			(size 0.519938 1.4986)
			(layers "F.Cu" "F.Mask" "F.Paste")
			(net "M_F_CPU0_SA_DQS_DN<4>")
		)
		(pad "57" smd rect
			(at -2.050034 -15.724886 270)
			(size 0.519938 1.4986)
			(layers "F.Cu" "F.Mask" "F.Paste")
			(net "GND")
		)
		(pad "58" smd rect
			(at -2.050034 -14.875002 270)
			(size 0.519938 1.4986)
			(layers "F.Cu" "F.Mask" "F.Paste")
			(net "M_F_CPU0_SA_CB<4>")
		)
		(pad "59" smd rect
			(at -2.050034 -14.025118 270)
			(size 0.519938 1.4986)
			(layers "F.Cu" "F.Mask" "F.Paste")
			(net "GND")
		)
		(pad "60" smd rect
			(at -2.050034 -13.17498 270)
			(size 0.519938 1.4986)
			(layers "F.Cu" "F.Mask" "F.Paste")
			(net "M_F_CPU0_SA_CB<5>")
		)
		(pad "61" smd rect
			(at -2.050034 -12.325096 270)
			(size 0.519938 1.4986)
			(layers "F.Cu" "F.Mask" "F.Paste")
			(net "GND")
		)
		(pad "62" smd rect
			(at -2.050034 -11.474958 270)
			(size 0.519938 1.4986)
			(layers "F.Cu" "F.Mask" "F.Paste")
			(net "M_F_CPU0_ALERT_N")
		)
		(pad "63" smd rect
			(at -2.050034 -10.625074 270)
			(size 0.519938 1.4986)
			(layers "F.Cu" "F.Mask" "F.Paste")
			(net "GND")
		)
		(pad "64" smd rect
			(at -2.050034 -9.774936 270)
			(size 0.519938 1.4986)
			(layers "F.Cu" "F.Mask" "F.Paste")
			(net "M_F_CPU0_SA_CS_N<2>")
		)
		(pad "65" smd rect
			(at -2.050034 -8.925052 270)
			(size 0.519938 1.4986)
			(layers "F.Cu" "F.Mask" "F.Paste")
			(net "GND")
		)
		(pad "66" smd rect
			(at -2.050034 -8.074914 270)
			(size 0.519938 1.4986)
			(layers "F.Cu" "F.Mask" "F.Paste")
			(net "M_F_CPU0_SA_CA<0>")
		)
		(pad "67" smd rect
			(at -2.050034 -7.22503 270)
			(size 0.519938 1.4986)
			(layers "F.Cu" "F.Mask" "F.Paste")
			(net "GND")
		)
		(pad "68" smd rect
			(at -2.050034 -6.374892 270)
			(size 0.519938 1.4986)
			(layers "F.Cu" "F.Mask" "F.Paste")
			(net "M_F_CPU0_SA_CA<2>")
		)
		(pad "69" smd rect
			(at -2.050034 -5.525008 270)
			(size 0.519938 1.4986)
			(layers "F.Cu" "F.Mask" "F.Paste")
			(net "GND")
		)
		(pad "70" smd rect
			(at -2.050034 -4.675124 270)
			(size 0.519938 1.4986)
			(layers "F.Cu" "F.Mask" "F.Paste")
			(net "M_F_CPU0_SA_CA<4>")
		)
		(pad "71" smd rect
			(at -2.050034 -3.824986 270)
			(size 0.519938 1.4986)
			(layers "F.Cu" "F.Mask" "F.Paste")
			(net "GND")
		)
		(pad "72" smd rect
			(at -2.050034 -2.975102 270)
			(size 0.519938 1.4986)
			(layers "F.Cu" "F.Mask" "F.Paste")
			(net "M_F_CPU0_SA_CA<6>")
		)
		(pad "73" smd rect
			(at -2.050034 -2.124964 270)
			(size 0.519938 1.4986)
			(layers "F.Cu" "F.Mask" "F.Paste")
			(net "GND")
		)
		(pad "74" smd rect
			(at -2.050034 -1.27508 270)
			(size 0.519938 1.4986)
			(layers "F.Cu" "F.Mask" "F.Paste")
			(net "M_F_CPU0_SA_PAR")
		)
		(pad "75" smd rect
			(at -2.050034 -0.424942 270)
			(size 0.519938 1.4986)
			(layers "F.Cu" "F.Mask" "F.Paste")
			(net "GND")
		)
		(pad "76" smd rect
			(at -2.050034 5.525008 270)
			(size 0.519938 1.4986)
			(layers "F.Cu" "F.Mask" "F.Paste")
			(net "M_F_CPU0_SB_CA<0>")
		)
		(pad "77" smd rect
			(at -2.050034 6.374892 270)
			(size 0.519938 1.4986)
			(layers "F.Cu" "F.Mask" "F.Paste")
			(net "GND")
		)
		(pad "78" smd rect
			(at -2.050034 7.22503 270)
			(size 0.519938 1.4986)
			(layers "F.Cu" "F.Mask" "F.Paste")
			(net "M_F_CPU0_SB_CA<2>")
		)
		(pad "79" smd rect
			(at -2.050034 8.074914 270)
			(size 0.519938 1.4986)
			(layers "F.Cu" "F.Mask" "F.Paste")
			(net "GND")
		)
		(pad "80" smd rect
			(at -2.050034 8.925052 270)
			(size 0.519938 1.4986)
			(layers "F.Cu" "F.Mask" "F.Paste")
			(net "M_F_CPU0_SB_CA<4>")
		)
		(pad "81" smd rect
			(at -2.050034 9.774936 270)
			(size 0.519938 1.4986)
			(layers "F.Cu" "F.Mask" "F.Paste")
			(net "GND")
		)
		(pad "82" smd rect
			(at -2.050034 10.625074 270)
			(size 0.519938 1.4986)
			(layers "F.Cu" "F.Mask" "F.Paste")
			(net "M_F_CPU0_SB_CA<6>")
		)
		(pad "83" smd rect
			(at -2.050034 11.474958 270)
			(size 0.519938 1.4986)
			(layers "F.Cu" "F.Mask" "F.Paste")
			(net "GND")
		)
		(pad "84" smd rect
			(at -2.050034 12.325096 270)
			(size 0.519938 1.4986)
			(layers "F.Cu" "F.Mask" "F.Paste")
			(net "M_F_CPU0_SB_CS_N<2>")
		)
		(pad "85" smd rect
			(at -2.050034 13.17498 270)
			(size 0.519938 1.4986)
			(layers "F.Cu" "F.Mask" "F.Paste")
			(net "GND")
		)
		(pad "86" smd rect
			(at -2.050034 14.025118 270)
			(size 0.519938 1.4986)
			(layers "F.Cu" "F.Mask" "F.Paste")
			(net "M_F_CPU0_SA_RSP<1>")
		)
		(pad "87" smd rect
			(at -2.050034 14.875002 270)
			(size 0.519938 1.4986)
			(layers "F.Cu" "F.Mask" "F.Paste")
			(net "M_F_CPU0_SB_RSP<1>")
		)
		(pad "88" smd rect
			(at -2.050034 15.724886 270)
			(size 0.519938 1.4986)
			(layers "F.Cu" "F.Mask" "F.Paste")
			(net "GND")
		)
		(pad "89" smd rect
			(at -2.050034 16.575024 270)
			(size 0.519938 1.4986)
			(layers "F.Cu" "F.Mask" "F.Paste")
			(net "M_F_CPU0_SB_CB<4>")
		)
		(pad "90" smd rect
			(at -2.050034 17.424908 270)
			(size 0.519938 1.4986)
			(layers "F.Cu" "F.Mask" "F.Paste")
			(net "GND")
		)
		(pad "91" smd rect
			(at -2.050034 18.275046 270)
			(size 0.519938 1.4986)
			(layers "F.Cu" "F.Mask" "F.Paste")
			(net "M_F_CPU0_SB_CB<5>")
		)
		(pad "92" smd rect
			(at -2.050034 19.12493 270)
			(size 0.519938 1.4986)
			(layers "F.Cu" "F.Mask" "F.Paste")
			(net "GND")
		)
		(pad "93" smd rect
			(at -2.050034 19.975068 270)
			(size 0.519938 1.4986)
			(layers "F.Cu" "F.Mask" "F.Paste")
			(net "M_F_CPU0_SB_DQS_DP<9>")
		)
		(pad "94" smd rect
			(at -2.050034 20.824952 270)
			(size 0.519938 1.4986)
			(layers "F.Cu" "F.Mask" "F.Paste")
			(net "M_F_CPU0_SB_DQS_DN<9>")
		)
		(pad "95" smd rect
			(at -2.050034 21.67509 270)
			(size 0.519938 1.4986)
			(layers "F.Cu" "F.Mask" "F.Paste")
			(net "GND")
		)
		(pad "96" smd rect
			(at -2.050034 22.524974 270)
			(size 0.519938 1.4986)
			(layers "F.Cu" "F.Mask" "F.Paste")
			(net "M_F_CPU0_SB_CB<0>")
		)
		(pad "97" smd rect
			(at -2.050034 23.375112 270)
			(size 0.519938 1.4986)
			(layers "F.Cu" "F.Mask" "F.Paste")
			(net "GND")
		)
		(pad "98" smd rect
			(at -2.050034 24.224996 270)
			(size 0.519938 1.4986)
			(layers "F.Cu" "F.Mask" "F.Paste")
			(net "M_F_CPU0_SB_CB<1>")
		)
		(pad "99" smd rect
			(at -2.050034 25.07488 270)
			(size 0.519938 1.4986)
			(layers "F.Cu" "F.Mask" "F.Paste")
			(net "GND")
		)
		(pad "100" smd rect
			(at -2.050034 25.925018 270)
			(size 0.519938 1.4986)
			(layers "F.Cu" "F.Mask" "F.Paste")
			(net "M_F_CPU0_SB_DQ<0>")
		)
		(pad "101" smd rect
			(at -2.050034 26.774902 270)
			(size 0.519938 1.4986)
			(layers "F.Cu" "F.Mask" "F.Paste")
			(net "GND")
		)
		(pad "102" smd rect
			(at -2.050034 27.62504 270)
			(size 0.519938 1.4986)
			(layers "F.Cu" "F.Mask" "F.Paste")
			(net "M_F_CPU0_SB_DQ<1>")
		)
		(pad "103" smd rect
			(at -2.050034 28.474924 270)
			(size 0.519938 1.4986)
			(layers "F.Cu" "F.Mask" "F.Paste")
			(net "GND")
		)
		(pad "104" smd rect
			(at -2.050034 29.325062 270)
			(size 0.519938 1.4986)
			(layers "F.Cu" "F.Mask" "F.Paste")
			(net "M_F_CPU0_SB_DQS_DP<0>")
		)
		(pad "105" smd rect
			(at -2.050034 30.174946 270)
			(size 0.519938 1.4986)
			(layers "F.Cu" "F.Mask" "F.Paste")
			(net "M_F_CPU0_SB_DQS_DN<0>")
		)
		(pad "106" smd rect
			(at -2.050034 31.025084 270)
			(size 0.519938 1.4986)
			(layers "F.Cu" "F.Mask" "F.Paste")
			(net "GND")
		)
		(pad "107" smd rect
			(at -2.050034 31.874968 270)
			(size 0.519938 1.4986)
			(layers "F.Cu" "F.Mask" "F.Paste")
			(net "M_F_CPU0_SB_DQ<4>")
		)
		(pad "108" smd rect
			(at -2.050034 32.725106 270)
			(size 0.519938 1.4986)
			(layers "F.Cu" "F.Mask" "F.Paste")
			(net "GND")
		)
		(pad "109" smd rect
			(at -2.050034 33.57499 270)
			(size 0.519938 1.4986)
			(layers "F.Cu" "F.Mask" "F.Paste")
			(net "M_F_CPU0_SB_DQ<5>")
		)
		(pad "110" smd rect
			(at -2.050034 34.425128 270)
			(size 0.519938 1.4986)
			(layers "F.Cu" "F.Mask" "F.Paste")
			(net "GND")
		)
		(pad "111" smd rect
			(at -2.050034 35.275012 270)
			(size 0.519938 1.4986)
			(layers "F.Cu" "F.Mask" "F.Paste")
			(net "M_F_CPU0_SB_DQ<8>")
		)
		(pad "112" smd rect
			(at -2.050034 36.124896 270)
			(size 0.519938 1.4986)
			(layers "F.Cu" "F.Mask" "F.Paste")
			(net "GND")
		)
		(pad "113" smd rect
			(at -2.050034 36.975034 270)
			(size 0.519938 1.4986)
			(layers "F.Cu" "F.Mask" "F.Paste")
			(net "M_F_CPU0_SB_DQ<9>")
		)
		(pad "114" smd rect
			(at -2.050034 37.824918 270)
			(size 0.519938 1.4986)
			(layers "F.Cu" "F.Mask" "F.Paste")
			(net "GND")
		)
		(pad "115" smd rect
			(at -2.050034 38.675056 270)
			(size 0.519938 1.4986)
			(layers "F.Cu" "F.Mask" "F.Paste")
			(net "M_F_CPU0_SB_DQS_DP<1>")
		)
		(pad "116" smd rect
			(at -2.050034 39.52494 270)
			(size 0.519938 1.4986)
			(layers "F.Cu" "F.Mask" "F.Paste")
			(net "M_F_CPU0_SB_DQS_DN<1>")
		)
		(pad "117" smd rect
			(at -2.050034 40.375078 270)
			(size 0.519938 1.4986)
			(layers "F.Cu" "F.Mask" "F.Paste")
			(net "GND")
		)
		(pad "118" smd rect
			(at -2.050034 41.224962 270)
			(size 0.519938 1.4986)
			(layers "F.Cu" "F.Mask" "F.Paste")
			(net "M_F_CPU0_SB_DQ<12>")
		)
		(pad "119" smd rect
			(at -2.050034 42.0751 270)
			(size 0.519938 1.4986)
			(layers "F.Cu" "F.Mask" "F.Paste")
			(net "GND")
		)
		(pad "120" smd rect
			(at -2.050034 42.924984 270)
			(size 0.519938 1.4986)
			(layers "F.Cu" "F.Mask" "F.Paste")
			(net "M_F_CPU0_SB_DQ<13>")
		)
		(pad "121" smd rect
			(at -2.050034 43.775122 270)
			(size 0.519938 1.4986)
			(layers "F.Cu" "F.Mask" "F.Paste")
			(net "GND")
		)
		(pad "122" smd rect
			(at -2.050034 44.625006 270)
			(size 0.519938 1.4986)
			(layers "F.Cu" "F.Mask" "F.Paste")
			(net "M_F_CPU0_SB_DQ<16>")
		)
		(pad "123" smd rect
			(at -2.050034 45.47489 270)
			(size 0.519938 1.4986)
			(layers "F.Cu" "F.Mask" "F.Paste")
			(net "GND")
		)
		(pad "124" smd rect
			(at -2.050034 46.325028 270)
			(size 0.519938 1.4986)
			(layers "F.Cu" "F.Mask" "F.Paste")
			(net "M_F_CPU0_SB_DQ<17>")
		)
		(pad "125" smd rect
			(at -2.050034 47.174912 270)
			(size 0.519938 1.4986)
			(layers "F.Cu" "F.Mask" "F.Paste")
			(net "GND")
		)
		(pad "126" smd rect
			(at -2.050034 48.02505 270)
			(size 0.519938 1.4986)
			(layers "F.Cu" "F.Mask" "F.Paste")
			(net "M_F_CPU0_SB_DQS_DP<2>")
		)
		(pad "127" smd rect
			(at -2.050034 48.874934 270)
			(size 0.519938 1.4986)
			(layers "F.Cu" "F.Mask" "F.Paste")
			(net "M_F_CPU0_SB_DQS_DN<2>")
		)
		(pad "128" smd rect
			(at -2.050034 49.725072 270)
			(size 0.519938 1.4986)
			(layers "F.Cu" "F.Mask" "F.Paste")
			(net "GND")
		)
		(pad "129" smd rect
			(at -2.050034 50.574956 270)
			(size 0.519938 1.4986)
			(layers "F.Cu" "F.Mask" "F.Paste")
			(net "M_F_CPU0_SB_DQ<20>")
		)
		(pad "130" smd rect
			(at -2.050034 51.425094 270)
			(size 0.519938 1.4986)
			(layers "F.Cu" "F.Mask" "F.Paste")
			(net "GND")
		)
		(pad "131" smd rect
			(at -2.050034 52.274978 270)
			(size 0.519938 1.4986)
			(layers "F.Cu" "F.Mask" "F.Paste")
			(net "M_F_CPU0_SB_DQ<21>")
		)
		(pad "132" smd rect
			(at -2.050034 53.125116 270)
			(size 0.519938 1.4986)
			(layers "F.Cu" "F.Mask" "F.Paste")
			(net "GND")
		)
		(pad "133" smd rect
			(at -2.050034 53.975 270)
			(size 0.519938 1.4986)
			(layers "F.Cu" "F.Mask" "F.Paste")
			(net "M_F_CPU0_SB_DQ<24>")
		)
		(pad "134" smd rect
			(at -2.050034 54.824884 270)
			(size 0.519938 1.4986)
			(layers "F.Cu" "F.Mask" "F.Paste")
			(net "GND")
		)
		(pad "135" smd rect
			(at -2.050034 55.675022 270)
			(size 0.519938 1.4986)
			(layers "F.Cu" "F.Mask" "F.Paste")
			(net "M_F_CPU0_SB_DQ<25>")
		)
		(pad "136" smd rect
			(at -2.050034 56.524906 270)
			(size 0.519938 1.4986)
			(layers "F.Cu" "F.Mask" "F.Paste")
			(net "GND")
		)
		(pad "137" smd rect
			(at -2.050034 57.375044 270)
			(size 0.519938 1.4986)
			(layers "F.Cu" "F.Mask" "F.Paste")
			(net "M_F_CPU0_SB_DQS_DP<3>")
		)
		(pad "138" smd rect
			(at -2.050034 58.224928 270)
			(size 0.519938 1.4986)
			(layers "F.Cu" "F.Mask" "F.Paste")
			(net "M_F_CPU0_SB_DQS_DN<3>")
		)
		(pad "139" smd rect
			(at -2.050034 59.075066 270)
			(size 0.519938 1.4986)
			(layers "F.Cu" "F.Mask" "F.Paste")
			(net "GND")
		)
		(pad "140" smd rect
			(at -2.050034 59.92495 270)
			(size 0.519938 1.4986)
			(layers "F.Cu" "F.Mask" "F.Paste")
			(net "M_F_CPU0_SB_DQ<28>")
		)
		(pad "141" smd rect
			(at -2.050034 60.775088 270)
			(size 0.519938 1.4986)
			(layers "F.Cu" "F.Mask" "F.Paste")
			(net "GND")
		)
		(pad "142" smd rect
			(at -2.050034 61.624972 270)
			(size 0.519938 1.4986)
			(layers "F.Cu" "F.Mask" "F.Paste")
			(net "M_F_CPU0_SB_DQ<29>")
		)
		(pad "143" smd rect
			(at -2.050034 62.47511 270)
			(size 0.519938 1.4986)
			(layers "F.Cu" "F.Mask" "F.Paste")
			(net "GND")
		)
		(pad "144" smd rect
			(at -2.050034 63.324994 270)
			(size 0.519938 1.4986)
			(layers "F.Cu" "F.Mask" "F.Paste")
			(net "TP_CHF_CPU0_DIMM2_FRU_1")
		)
		(pad "145" smd rect
			(at 2.050034 -63.324994 270)
			(size 0.519938 1.4986)
			(layers "F.Cu" "F.Mask" "F.Paste")
			(net "P12V_S3_AUX_CPU0_NVDIMM")
		)
		(pad "146" smd rect
			(at 2.050034 -62.47511 270)
			(size 0.519938 1.4986)
			(layers "F.Cu" "F.Mask" "F.Paste")
			(net "P12V_S3_AUX_CPU0_NVDIMM")
		)
		(pad "147" smd rect
			(at 2.050034 -61.624972 270)
			(size 0.519938 1.4986)
			(layers "F.Cu" "F.Mask" "F.Paste")
			(net "PWRGD_CHF_CPU0_DIMM2")
		)
		(pad "148" smd rect
			(at 2.050034 -60.775088 270)
			(size 0.519938 1.4986)
			(layers "F.Cu" "F.Mask" "F.Paste")
			(net "PD_CHF_CPU0_DIMM2_SAA")
		)
		(pad "149" smd rect
			(at 2.050034 -59.92495 270)
			(size 0.519938 1.4986)
			(layers "F.Cu" "F.Mask" "F.Paste")
			(net "TP_CHF_CPU0_DIMM2_FRU_2")
		)
		(pad "150" smd rect
			(at 2.050034 -59.075066 270)
			(size 0.519938 1.4986)
			(layers "F.Cu" "F.Mask" "F.Paste")
			(net "TP_CHF_CPU0_DIMM2_FRU_3")
		)
		(pad "151" smd rect
			(at 2.050034 -58.224928 270)
			(size 0.519938 1.4986)
			(layers "F.Cu" "F.Mask" "F.Paste")
			(net "GND")
		)
		(pad "152" smd rect
			(at 2.050034 -57.375044 270)
			(size 0.519938 1.4986)
			(layers "F.Cu" "F.Mask" "F.Paste")
			(net "M_F_CPU0_SA_DQ<2>")
		)
		(pad "153" smd rect
			(at 2.050034 -56.524906 270)
			(size 0.519938 1.4986)
			(layers "F.Cu" "F.Mask" "F.Paste")
			(net "GND")
		)
		(pad "154" smd rect
			(at 2.050034 -55.675022 270)
			(size 0.519938 1.4986)
			(layers "F.Cu" "F.Mask" "F.Paste")
			(net "M_F_CPU0_SA_DQ<3>")
		)
		(pad "155" smd rect
			(at 2.050034 -54.824884 270)
			(size 0.519938 1.4986)
			(layers "F.Cu" "F.Mask" "F.Paste")
			(net "GND")
		)
		(pad "156" smd rect
			(at 2.050034 -53.975 270)
			(size 0.519938 1.4986)
			(layers "F.Cu" "F.Mask" "F.Paste")
			(net "M_F_CPU0_SA_DQS_DN<5>")
		)
		(pad "157" smd rect
			(at 2.050034 -53.125116 270)
			(size 0.519938 1.4986)
			(layers "F.Cu" "F.Mask" "F.Paste")
			(net "M_F_CPU0_SA_DQS_DP<5>")
		)
		(pad "158" smd rect
			(at 2.050034 -52.274978 270)
			(size 0.519938 1.4986)
			(layers "F.Cu" "F.Mask" "F.Paste")
			(net "GND")
		)
		(pad "159" smd rect
			(at 2.050034 -51.425094 270)
			(size 0.519938 1.4986)
			(layers "F.Cu" "F.Mask" "F.Paste")
			(net "M_F_CPU0_SA_DQ<6>")
		)
		(pad "160" smd rect
			(at 2.050034 -50.574956 270)
			(size 0.519938 1.4986)
			(layers "F.Cu" "F.Mask" "F.Paste")
			(net "GND")
		)
		(pad "161" smd rect
			(at 2.050034 -49.725072 270)
			(size 0.519938 1.4986)
			(layers "F.Cu" "F.Mask" "F.Paste")
			(net "M_F_CPU0_SA_DQ<7>")
		)
		(pad "162" smd rect
			(at 2.050034 -48.874934 270)
			(size 0.519938 1.4986)
			(layers "F.Cu" "F.Mask" "F.Paste")
			(net "GND")
		)
		(pad "163" smd rect
			(at 2.050034 -48.02505 270)
			(size 0.519938 1.4986)
			(layers "F.Cu" "F.Mask" "F.Paste")
			(net "M_F_CPU0_SA_DQ<10>")
		)
		(pad "164" smd rect
			(at 2.050034 -47.174912 270)
			(size 0.519938 1.4986)
			(layers "F.Cu" "F.Mask" "F.Paste")
			(net "GND")
		)
		(pad "165" smd rect
			(at 2.050034 -46.325028 270)
			(size 0.519938 1.4986)
			(layers "F.Cu" "F.Mask" "F.Paste")
			(net "M_F_CPU0_SA_DQ<11>")
		)
		(pad "166" smd rect
			(at 2.050034 -45.47489 270)
			(size 0.519938 1.4986)
			(layers "F.Cu" "F.Mask" "F.Paste")
			(net "GND")
		)
		(pad "167" smd rect
			(at 2.050034 -44.625006 270)
			(size 0.519938 1.4986)
			(layers "F.Cu" "F.Mask" "F.Paste")
			(net "M_F_CPU0_SA_DQS_DN<6>")
		)
		(pad "168" smd rect
			(at 2.050034 -43.775122 270)
			(size 0.519938 1.4986)
			(layers "F.Cu" "F.Mask" "F.Paste")
			(net "M_F_CPU0_SA_DQS_DP<6>")
		)
		(pad "169" smd rect
			(at 2.050034 -42.924984 270)
			(size 0.519938 1.4986)
			(layers "F.Cu" "F.Mask" "F.Paste")
			(net "GND")
		)
		(pad "170" smd rect
			(at 2.050034 -42.0751 270)
			(size 0.519938 1.4986)
			(layers "F.Cu" "F.Mask" "F.Paste")
			(net "M_F_CPU0_SA_DQ<14>")
		)
		(pad "171" smd rect
			(at 2.050034 -41.224962 270)
			(size 0.519938 1.4986)
			(layers "F.Cu" "F.Mask" "F.Paste")
			(net "GND")
		)
		(pad "172" smd rect
			(at 2.050034 -40.375078 270)
			(size 0.519938 1.4986)
			(layers "F.Cu" "F.Mask" "F.Paste")
			(net "M_F_CPU0_SA_DQ<15>")
		)
		(pad "173" smd rect
			(at 2.050034 -39.52494 270)
			(size 0.519938 1.4986)
			(layers "F.Cu" "F.Mask" "F.Paste")
			(net "GND")
		)
		(pad "174" smd rect
			(at 2.050034 -38.675056 270)
			(size 0.519938 1.4986)
			(layers "F.Cu" "F.Mask" "F.Paste")
			(net "M_F_CPU0_SA_DQ<18>")
		)
		(pad "175" smd rect
			(at 2.050034 -37.824918 270)
			(size 0.519938 1.4986)
			(layers "F.Cu" "F.Mask" "F.Paste")
			(net "GND")
		)
		(pad "176" smd rect
			(at 2.050034 -36.975034 270)
			(size 0.519938 1.4986)
			(layers "F.Cu" "F.Mask" "F.Paste")
			(net "M_F_CPU0_SA_DQ<19>")
		)
		(pad "177" smd rect
			(at 2.050034 -36.124896 270)
			(size 0.519938 1.4986)
			(layers "F.Cu" "F.Mask" "F.Paste")
			(net "GND")
		)
		(pad "178" smd rect
			(at 2.050034 -35.275012 270)
			(size 0.519938 1.4986)
			(layers "F.Cu" "F.Mask" "F.Paste")
			(net "M_F_CPU0_SA_DQS_DN<7>")
		)
		(pad "179" smd rect
			(at 2.050034 -34.425128 270)
			(size 0.519938 1.4986)
			(layers "F.Cu" "F.Mask" "F.Paste")
			(net "M_F_CPU0_SA_DQS_DP<7>")
		)
		(pad "180" smd rect
			(at 2.050034 -33.57499 270)
			(size 0.519938 1.4986)
			(layers "F.Cu" "F.Mask" "F.Paste")
			(net "GND")
		)
		(pad "181" smd rect
			(at 2.050034 -32.725106 270)
			(size 0.519938 1.4986)
			(layers "F.Cu" "F.Mask" "F.Paste")
			(net "M_F_CPU0_SA_DQ<22>")
		)
		(pad "182" smd rect
			(at 2.050034 -31.874968 270)
			(size 0.519938 1.4986)
			(layers "F.Cu" "F.Mask" "F.Paste")
			(net "GND")
		)
		(pad "183" smd rect
			(at 2.050034 -31.025084 270)
			(size 0.519938 1.4986)
			(layers "F.Cu" "F.Mask" "F.Paste")
			(net "M_F_CPU0_SA_DQ<23>")
		)
		(pad "184" smd rect
			(at 2.050034 -30.174946 270)
			(size 0.519938 1.4986)
			(layers "F.Cu" "F.Mask" "F.Paste")
			(net "GND")
		)
		(pad "185" smd rect
			(at 2.050034 -29.325062 270)
			(size 0.519938 1.4986)
			(layers "F.Cu" "F.Mask" "F.Paste")
			(net "M_F_CPU0_SA_DQ<26>")
		)
		(pad "186" smd rect
			(at 2.050034 -28.474924 270)
			(size 0.519938 1.4986)
			(layers "F.Cu" "F.Mask" "F.Paste")
			(net "GND")
		)
		(pad "187" smd rect
			(at 2.050034 -27.62504 270)
			(size 0.519938 1.4986)
			(layers "F.Cu" "F.Mask" "F.Paste")
			(net "M_F_CPU0_SA_DQ<27>")
		)
		(pad "188" smd rect
			(at 2.050034 -26.774902 270)
			(size 0.519938 1.4986)
			(layers "F.Cu" "F.Mask" "F.Paste")
			(net "GND")
		)
		(pad "189" smd rect
			(at 2.050034 -25.925018 270)
			(size 0.519938 1.4986)
			(layers "F.Cu" "F.Mask" "F.Paste")
			(net "M_F_CPU0_SA_DQS_DN<8>")
		)
		(pad "190" smd rect
			(at 2.050034 -25.07488 270)
			(size 0.519938 1.4986)
			(layers "F.Cu" "F.Mask" "F.Paste")
			(net "M_F_CPU0_SA_DQS_DP<8>")
		)
		(pad "191" smd rect
			(at 2.050034 -24.224996 270)
			(size 0.519938 1.4986)
			(layers "F.Cu" "F.Mask" "F.Paste")
			(net "GND")
		)
		(pad "192" smd rect
			(at 2.050034 -23.375112 270)
			(size 0.519938 1.4986)
			(layers "F.Cu" "F.Mask" "F.Paste")
			(net "M_F_CPU0_SA_DQ<30>")
		)
		(pad "193" smd rect
			(at 2.050034 -22.524974 270)
			(size 0.519938 1.4986)
			(layers "F.Cu" "F.Mask" "F.Paste")
			(net "GND")
		)
		(pad "194" smd rect
			(at 2.050034 -21.67509 270)
			(size 0.519938 1.4986)
			(layers "F.Cu" "F.Mask" "F.Paste")
			(net "M_F_CPU0_SA_DQ<31>")
		)
		(pad "195" smd rect
			(at 2.050034 -20.824952 270)
			(size 0.519938 1.4986)
			(layers "F.Cu" "F.Mask" "F.Paste")
			(net "GND")
		)
		(pad "196" smd rect
			(at 2.050034 -19.975068 270)
			(size 0.519938 1.4986)
			(layers "F.Cu" "F.Mask" "F.Paste")
			(net "M_F_CPU0_SA_CB<2>")
		)
		(pad "197" smd rect
			(at 2.050034 -19.12493 270)
			(size 0.519938 1.4986)
			(layers "F.Cu" "F.Mask" "F.Paste")
			(net "GND")
		)
		(pad "198" smd rect
			(at 2.050034 -18.275046 270)
			(size 0.519938 1.4986)
			(layers "F.Cu" "F.Mask" "F.Paste")
			(net "M_F_CPU0_SA_CB<3>")
		)
		(pad "199" smd rect
			(at 2.050034 -17.424908 270)
			(size 0.519938 1.4986)
			(layers "F.Cu" "F.Mask" "F.Paste")
			(net "GND")
		)
		(pad "200" smd rect
			(at 2.050034 -16.575024 270)
			(size 0.519938 1.4986)
			(layers "F.Cu" "F.Mask" "F.Paste")
			(net "M_F_CPU0_SA_DQS_DN<9>")
		)
		(pad "201" smd rect
			(at 2.050034 -15.724886 270)
			(size 0.519938 1.4986)
			(layers "F.Cu" "F.Mask" "F.Paste")
			(net "M_F_CPU0_SA_DQS_DP<9>")
		)
		(pad "202" smd rect
			(at 2.050034 -14.875002 270)
			(size 0.519938 1.4986)
			(layers "F.Cu" "F.Mask" "F.Paste")
			(net "GND")
		)
		(pad "203" smd rect
			(at 2.050034 -14.025118 270)
			(size 0.519938 1.4986)
			(layers "F.Cu" "F.Mask" "F.Paste")
			(net "M_F_CPU0_SA_CB<6>")
		)
		(pad "204" smd rect
			(at 2.050034 -13.17498 270)
			(size 0.519938 1.4986)
			(layers "F.Cu" "F.Mask" "F.Paste")
			(net "GND")
		)
		(pad "205" smd rect
			(at 2.050034 -12.325096 270)
			(size 0.519938 1.4986)
			(layers "F.Cu" "F.Mask" "F.Paste")
			(net "M_F_CPU0_SA_CB<7>")
		)
		(pad "206" smd rect
			(at 2.050034 -11.474958 270)
			(size 0.519938 1.4986)
			(layers "F.Cu" "F.Mask" "F.Paste")
			(net "GND")
		)
		(pad "207" smd rect
			(at 2.050034 -10.625074 270)
			(size 0.519938 1.4986)
			(layers "F.Cu" "F.Mask" "F.Paste")
			(net "RST_M_EF_CPU0_FPGA_N")
		)
		(pad "208" smd rect
			(at 2.050034 -9.774936 270)
			(size 0.519938 1.4986)
			(layers "F.Cu" "F.Mask" "F.Paste")
			(net "GND")
		)
		(pad "209" smd rect
			(at 2.050034 -8.925052 270)
			(size 0.519938 1.4986)
			(layers "F.Cu" "F.Mask" "F.Paste")
			(net "M_F_CPU0_SA_CS_N<3>")
		)
		(pad "210" smd rect
			(at 2.050034 -8.074914 270)
			(size 0.519938 1.4986)
			(layers "F.Cu" "F.Mask" "F.Paste")
			(net "GND")
		)
		(pad "211" smd rect
			(at 2.050034 -7.22503 270)
			(size 0.519938 1.4986)
			(layers "F.Cu" "F.Mask" "F.Paste")
			(net "M_F_CPU0_SA_CA<1>")
		)
		(pad "212" smd rect
			(at 2.050034 -6.374892 270)
			(size 0.519938 1.4986)
			(layers "F.Cu" "F.Mask" "F.Paste")
			(net "GND")
		)
		(pad "213" smd rect
			(at 2.050034 -5.525008 270)
			(size 0.519938 1.4986)
			(layers "F.Cu" "F.Mask" "F.Paste")
			(net "M_F_CPU0_SA_CA<3>")
		)
		(pad "214" smd rect
			(at 2.050034 -4.675124 270)
			(size 0.519938 1.4986)
			(layers "F.Cu" "F.Mask" "F.Paste")
			(net "GND")
		)
		(pad "215" smd rect
			(at 2.050034 -3.824986 270)
			(size 0.519938 1.4986)
			(layers "F.Cu" "F.Mask" "F.Paste")
			(net "M_F_CPU0_SA_CA<5>")
		)
		(pad "216" smd rect
			(at 2.050034 -2.975102 270)
			(size 0.519938 1.4986)
			(layers "F.Cu" "F.Mask" "F.Paste")
			(net "GND")
		)
		(pad "217" smd rect
			(at 2.050034 -2.124964 270)
			(size 0.519938 1.4986)
			(layers "F.Cu" "F.Mask" "F.Paste")
			(net "M_F_CPU0_CLK_DP<1>")
		)
		(pad "218" smd rect
			(at 2.050034 -1.27508 270)
			(size 0.519938 1.4986)
			(layers "F.Cu" "F.Mask" "F.Paste")
			(net "M_F_CPU0_CLK_DN<1>")
		)
		(pad "219" smd rect
			(at 2.050034 -0.424942 270)
			(size 0.519938 1.4986)
			(layers "F.Cu" "F.Mask" "F.Paste")
			(net "GND")
		)
		(pad "220" smd rect
			(at 2.050034 5.525008 270)
			(size 0.519938 1.4986)
			(layers "F.Cu" "F.Mask" "F.Paste")
			(net "TP_CHF_CPU0_DIMM2_FRU_4")
		)
		(pad "221" smd rect
			(at 2.050034 6.374892 270)
			(size 0.519938 1.4986)
			(layers "F.Cu" "F.Mask" "F.Paste")
			(net "M_F_CPU0_SB_CA<1>")
		)
		(pad "222" smd rect
			(at 2.050034 7.22503 270)
			(size 0.519938 1.4986)
			(layers "F.Cu" "F.Mask" "F.Paste")
			(net "GND")
		)
		(pad "223" smd rect
			(at 2.050034 8.074914 270)
			(size 0.519938 1.4986)
			(layers "F.Cu" "F.Mask" "F.Paste")
			(net "M_F_CPU0_SB_CA<3>")
		)
		(pad "224" smd rect
			(at 2.050034 8.925052 270)
			(size 0.519938 1.4986)
			(layers "F.Cu" "F.Mask" "F.Paste")
			(net "GND")
		)
		(pad "225" smd rect
			(at 2.050034 9.774936 270)
			(size 0.519938 1.4986)
			(layers "F.Cu" "F.Mask" "F.Paste")
			(net "M_F_CPU0_SB_CA<5>")
		)
		(pad "226" smd rect
			(at 2.050034 10.625074 270)
			(size 0.519938 1.4986)
			(layers "F.Cu" "F.Mask" "F.Paste")
			(net "GND")
		)
		(pad "227" smd rect
			(at 2.050034 11.474958 270)
			(size 0.519938 1.4986)
			(layers "F.Cu" "F.Mask" "F.Paste")
			(net "M_F_CPU0_SB_PAR")
		)
		(pad "228" smd rect
			(at 2.050034 12.325096 270)
			(size 0.519938 1.4986)
			(layers "F.Cu" "F.Mask" "F.Paste")
			(net "GND")
		)
		(pad "229" smd rect
			(at 2.050034 13.17498 270)
			(size 0.519938 1.4986)
			(layers "F.Cu" "F.Mask" "F.Paste")
			(net "M_F_CPU0_SB_CS_N<3>")
		)
		(pad "230" smd rect
			(at 2.050034 14.025118 270)
			(size 0.519938 1.4986)
			(layers "F.Cu" "F.Mask" "F.Paste")
			(net "GND")
		)
		(pad "231" smd rect
			(at 2.050034 14.875002 270)
			(size 0.519938 1.4986)
			(layers "F.Cu" "F.Mask" "F.Paste")
			(net "TP_CHF_CPU0_DIMM2_FRU_5")
		)
		(pad "232" smd rect
			(at 2.050034 15.724886 270)
			(size 0.519938 1.4986)
			(layers "F.Cu" "F.Mask" "F.Paste")
			(net "TP_CHF_CPU0_DIMM2_FRU_6")
		)
		(pad "233" smd rect
			(at 2.050034 16.575024 270)
			(size 0.519938 1.4986)
			(layers "F.Cu" "F.Mask" "F.Paste")
			(net "GND")
		)
		(pad "234" smd rect
			(at 2.050034 17.424908 270)
			(size 0.519938 1.4986)
			(layers "F.Cu" "F.Mask" "F.Paste")
			(net "M_F_CPU0_SB_CB<6>")
		)
		(pad "235" smd rect
			(at 2.050034 18.275046 270)
			(size 0.519938 1.4986)
			(layers "F.Cu" "F.Mask" "F.Paste")
			(net "GND")
		)
		(pad "236" smd rect
			(at 2.050034 19.12493 270)
			(size 0.519938 1.4986)
			(layers "F.Cu" "F.Mask" "F.Paste")
			(net "M_F_CPU0_SB_CB<7>")
		)
		(pad "237" smd rect
			(at 2.050034 19.975068 270)
			(size 0.519938 1.4986)
			(layers "F.Cu" "F.Mask" "F.Paste")
			(net "GND")
		)
		(pad "238" smd rect
			(at 2.050034 20.824952 270)
			(size 0.519938 1.4986)
			(layers "F.Cu" "F.Mask" "F.Paste")
			(net "M_F_CPU0_SB_DQS_DN<4>")
		)
		(pad "239" smd rect
			(at 2.050034 21.67509 270)
			(size 0.519938 1.4986)
			(layers "F.Cu" "F.Mask" "F.Paste")
			(net "M_F_CPU0_SB_DQS_DP<4>")
		)
		(pad "240" smd rect
			(at 2.050034 22.524974 270)
			(size 0.519938 1.4986)
			(layers "F.Cu" "F.Mask" "F.Paste")
			(net "GND")
		)
		(pad "241" smd rect
			(at 2.050034 23.375112 270)
			(size 0.519938 1.4986)
			(layers "F.Cu" "F.Mask" "F.Paste")
			(net "M_F_CPU0_SB_CB<2>")
		)
		(pad "242" smd rect
			(at 2.050034 24.224996 270)
			(size 0.519938 1.4986)
			(layers "F.Cu" "F.Mask" "F.Paste")
			(net "GND")
		)
		(pad "243" smd rect
			(at 2.050034 25.07488 270)
			(size 0.519938 1.4986)
			(layers "F.Cu" "F.Mask" "F.Paste")
			(net "M_F_CPU0_SB_CB<3>")
		)
		(pad "244" smd rect
			(at 2.050034 25.925018 270)
			(size 0.519938 1.4986)
			(layers "F.Cu" "F.Mask" "F.Paste")
			(net "GND")
		)
		(pad "245" smd rect
			(at 2.050034 26.774902 270)
			(size 0.519938 1.4986)
			(layers "F.Cu" "F.Mask" "F.Paste")
			(net "M_F_CPU0_SB_DQ<2>")
		)
		(pad "246" smd rect
			(at 2.050034 27.62504 270)
			(size 0.519938 1.4986)
			(layers "F.Cu" "F.Mask" "F.Paste")
			(net "GND")
		)
		(pad "247" smd rect
			(at 2.050034 28.474924 270)
			(size 0.519938 1.4986)
			(layers "F.Cu" "F.Mask" "F.Paste")
			(net "M_F_CPU0_SB_DQ<3>")
		)
		(pad "248" smd rect
			(at 2.050034 29.325062 270)
			(size 0.519938 1.4986)
			(layers "F.Cu" "F.Mask" "F.Paste")
			(net "GND")
		)
		(pad "249" smd rect
			(at 2.050034 30.174946 270)
			(size 0.519938 1.4986)
			(layers "F.Cu" "F.Mask" "F.Paste")
			(net "M_F_CPU0_SB_DQS_DN<5>")
		)
		(pad "250" smd rect
			(at 2.050034 31.025084 270)
			(size 0.519938 1.4986)
			(layers "F.Cu" "F.Mask" "F.Paste")
			(net "M_F_CPU0_SB_DQS_DP<5>")
		)
		(pad "251" smd rect
			(at 2.050034 31.874968 270)
			(size 0.519938 1.4986)
			(layers "F.Cu" "F.Mask" "F.Paste")
			(net "GND")
		)
		(pad "252" smd rect
			(at 2.050034 32.725106 270)
			(size 0.519938 1.4986)
			(layers "F.Cu" "F.Mask" "F.Paste")
			(net "M_F_CPU0_SB_DQ<6>")
		)
		(pad "253" smd rect
			(at 2.050034 33.57499 270)
			(size 0.519938 1.4986)
			(layers "F.Cu" "F.Mask" "F.Paste")
			(net "GND")
		)
		(pad "254" smd rect
			(at 2.050034 34.425128 270)
			(size 0.519938 1.4986)
			(layers "F.Cu" "F.Mask" "F.Paste")
			(net "M_F_CPU0_SB_DQ<7>")
		)
		(pad "255" smd rect
			(at 2.050034 35.275012 270)
			(size 0.519938 1.4986)
			(layers "F.Cu" "F.Mask" "F.Paste")
			(net "GND")
		)
		(pad "256" smd rect
			(at 2.050034 36.124896 270)
			(size 0.519938 1.4986)
			(layers "F.Cu" "F.Mask" "F.Paste")
			(net "M_F_CPU0_SB_DQ<10>")
		)
		(pad "257" smd rect
			(at 2.050034 36.975034 270)
			(size 0.519938 1.4986)
			(layers "F.Cu" "F.Mask" "F.Paste")
			(net "GND")
		)
		(pad "258" smd rect
			(at 2.050034 37.824918 270)
			(size 0.519938 1.4986)
			(layers "F.Cu" "F.Mask" "F.Paste")
			(net "M_F_CPU0_SB_DQ<11>")
		)
		(pad "259" smd rect
			(at 2.050034 38.675056 270)
			(size 0.519938 1.4986)
			(layers "F.Cu" "F.Mask" "F.Paste")
			(net "GND")
		)
		(pad "260" smd rect
			(at 2.050034 39.52494 270)
			(size 0.519938 1.4986)
			(layers "F.Cu" "F.Mask" "F.Paste")
			(net "M_F_CPU0_SB_DQS_DN<6>")
		)
		(pad "261" smd rect
			(at 2.050034 40.375078 270)
			(size 0.519938 1.4986)
			(layers "F.Cu" "F.Mask" "F.Paste")
			(net "M_F_CPU0_SB_DQS_DP<6>")
		)
		(pad "262" smd rect
			(at 2.050034 41.224962 270)
			(size 0.519938 1.4986)
			(layers "F.Cu" "F.Mask" "F.Paste")
			(net "GND")
		)
		(pad "263" smd rect
			(at 2.050034 42.0751 270)
			(size 0.519938 1.4986)
			(layers "F.Cu" "F.Mask" "F.Paste")
			(net "M_F_CPU0_SB_DQ<14>")
		)
		(pad "264" smd rect
			(at 2.050034 42.924984 270)
			(size 0.519938 1.4986)
			(layers "F.Cu" "F.Mask" "F.Paste")
			(net "GND")
		)
		(pad "265" smd rect
			(at 2.050034 43.775122 270)
			(size 0.519938 1.4986)
			(layers "F.Cu" "F.Mask" "F.Paste")
			(net "M_F_CPU0_SB_DQ<15>")
		)
		(pad "266" smd rect
			(at 2.050034 44.625006 270)
			(size 0.519938 1.4986)
			(layers "F.Cu" "F.Mask" "F.Paste")
			(net "GND")
		)
		(pad "267" smd rect
			(at 2.050034 45.47489 270)
			(size 0.519938 1.4986)
			(layers "F.Cu" "F.Mask" "F.Paste")
			(net "M_F_CPU0_SB_DQ<18>")
		)
		(pad "268" smd rect
			(at 2.050034 46.325028 270)
			(size 0.519938 1.4986)
			(layers "F.Cu" "F.Mask" "F.Paste")
			(net "GND")
		)
		(pad "269" smd rect
			(at 2.050034 47.174912 270)
			(size 0.519938 1.4986)
			(layers "F.Cu" "F.Mask" "F.Paste")
			(net "M_F_CPU0_SB_DQ<19>")
		)
		(pad "270" smd rect
			(at 2.050034 48.02505 270)
			(size 0.519938 1.4986)
			(layers "F.Cu" "F.Mask" "F.Paste")
			(net "GND")
		)
		(pad "271" smd rect
			(at 2.050034 48.874934 270)
			(size 0.519938 1.4986)
			(layers "F.Cu" "F.Mask" "F.Paste")
			(net "M_F_CPU0_SB_DQS_DN<7>")
		)
		(pad "272" smd rect
			(at 2.050034 49.725072 270)
			(size 0.519938 1.4986)
			(layers "F.Cu" "F.Mask" "F.Paste")
			(net "M_F_CPU0_SB_DQS_DP<7>")
		)
		(pad "273" smd rect
			(at 2.050034 50.574956 270)
			(size 0.519938 1.4986)
			(layers "F.Cu" "F.Mask" "F.Paste")
			(net "GND")
		)
		(pad "274" smd rect
			(at 2.050034 51.425094 270)
			(size 0.519938 1.4986)
			(layers "F.Cu" "F.Mask" "F.Paste")
			(net "M_F_CPU0_SB_DQ<22>")
		)
		(pad "275" smd rect
			(at 2.050034 52.274978 270)
			(size 0.519938 1.4986)
			(layers "F.Cu" "F.Mask" "F.Paste")
			(net "GND")
		)
		(pad "276" smd rect
			(at 2.050034 53.125116 270)
			(size 0.519938 1.4986)
			(layers "F.Cu" "F.Mask" "F.Paste")
			(net "M_F_CPU0_SB_DQ<23>")
		)
		(pad "277" smd rect
			(at 2.050034 53.975 270)
			(size 0.519938 1.4986)
			(layers "F.Cu" "F.Mask" "F.Paste")
			(net "GND")
		)
		(pad "278" smd rect
			(at 2.050034 54.824884 270)
			(size 0.519938 1.4986)
			(layers "F.Cu" "F.Mask" "F.Paste")
			(net "M_F_CPU0_SB_DQ<26>")
		)
		(pad "279" smd rect
			(at 2.050034 55.675022 270)
			(size 0.519938 1.4986)
			(layers "F.Cu" "F.Mask" "F.Paste")
			(net "GND")
		)
		(pad "280" smd rect
			(at 2.050034 56.524906 270)
			(size 0.519938 1.4986)
			(layers "F.Cu" "F.Mask" "F.Paste")
			(net "M_F_CPU0_SB_DQ<27>")
		)
		(pad "281" smd rect
			(at 2.050034 57.375044 270)
			(size 0.519938 1.4986)
			(layers "F.Cu" "F.Mask" "F.Paste")
			(net "GND")
		)
		(pad "282" smd rect
			(at 2.050034 58.224928 270)
			(size 0.519938 1.4986)
			(layers "F.Cu" "F.Mask" "F.Paste")
			(net "M_F_CPU0_SB_DQS_DN<8>")
		)
		(pad "283" smd rect
			(at 2.050034 59.075066 270)
			(size 0.519938 1.4986)
			(layers "F.Cu" "F.Mask" "F.Paste")
			(net "M_F_CPU0_SB_DQS_DP<8>")
		)
		(pad "284" smd rect
			(at 2.050034 59.92495 270)
			(size 0.519938 1.4986)
			(layers "F.Cu" "F.Mask" "F.Paste")
			(net "GND")
		)
		(pad "285" smd rect
			(at 2.050034 60.775088 270)
			(size 0.519938 1.4986)
			(layers "F.Cu" "F.Mask" "F.Paste")
			(net "M_F_CPU0_SB_DQ<30>")
		)
		(pad "286" smd rect
			(at 2.050034 61.624972 270)
			(size 0.519938 1.4986)
			(layers "F.Cu" "F.Mask" "F.Paste")
			(net "GND")
		)
		(pad "287" smd rect
			(at 2.050034 62.47511 270)
			(size 0.519938 1.4986)
			(layers "F.Cu" "F.Mask" "F.Paste")
			(net "M_F_CPU0_SB_DQ<31>")
		)
		(pad "288" smd rect
			(at 2.050034 63.324994 270)
			(size 0.519938 1.4986)
			(layers "F.Cu" "F.Mask" "F.Paste")
			(net "GND")
		)
		(pad "G1" thru_hole oval
			(at 0 -68.97497)
			(size 2.8194 1.5748)
			(drill oval 2.4384 1.1938)
			(layers "*.Cu" "*.Mask")
			(remove_unused_layers no)
			(net "GND")
			(clearance 0.127)
			(thermal_gap 0.127)
		)
		(pad "G2" thru_hole oval
			(at 0 3.875024)
			(size 2.8194 1.5748)
			(drill oval 2.4384 1.1938)
			(layers "*.Cu" "*.Mask")
			(remove_unused_layers no)
			(net "GND")
			(clearance 0.127)
			(thermal_gap 0.127)
		)
		(pad "G3" thru_hole oval
			(at 0 68.97497)
			(size 2.8194 1.5748)
			(drill oval 2.4384 1.1938)
			(layers "*.Cu" "*.Mask")
			(remove_unused_layers no)
			(net "GND")
			(clearance 0.127)
			(thermal_gap 0.127)
		)
	)
	(footprint ""
		(layer "F.Cu")
		(at 279.5778 -72.050148)
		(property "Reference" "PC1230"
			(at 0 0 0)
			(layer "F.SilkS")
			(hide yes)
			(effects
				(font
					(size 1.27 1.27)
				)
			)
		)
		(property "Value" ""
			(at 0 0 0)
			(layer "F.Fab")
			(effects
				(font
					(size 1.27 1.27)
				)
			)
		)
		(duplicate_pad_numbers_are_jumpers no)
		(fp_line
			(start 2.750058 0.999998)
			(end -2.750058 0.999998)
			(stroke
				(width 0.1524)
				(type default)
			)
			(layer "F.SilkS")
		)
		(fp_circle
			(center 0 0.999998)
			(end 2.750058 0.999998)
			(stroke
				(width 0.1524)
				(type default)
			)
			(fill no)
			(layer "F.SilkS")
		)
		(fp_poly
			(pts
				(arc
					(start 2.750058 0.999998)
					(mid 0 3.750056)
					(end -2.750058 0.999998)
				)
			)
			(stroke
				(width 0)
				(type default)
			)
			(fill yes)
			(layer "F.SilkS")
		)
		(fp_circle
			(center 0 0.999998)
			(end 2.750058 0.999998)
			(stroke
				(width 0.1)
				(type default)
			)
			(fill no)
			(layer "F.Fab")
		)
		(pad "1" thru_hole rect
			(at 0 0)
			(size 1.5748 1.5748)
			(drill 1.0668)
			(layers "*.Cu" "*.Mask")
			(remove_unused_layers no)
			(net "P1V05_PCH_AUX")
			(clearance 0)
			(padstack
				(mode front_inner_back)
				(layer "Inner"
					(shape circle)
					(size 1.5748 1.5748)
					(clearance 0)
				)
				(layer "B.Cu"
					(shape rect)
					(size 1.5748 1.5748)
					(clearance 0)
				)
			)
		)
		(pad "2" thru_hole circle
			(at 0 1.999996)
			(size 1.5748 1.5748)
			(drill 1.0668)
			(layers "*.Cu" "*.Mask")
			(remove_unused_layers no)
			(net "GND")
			(clearance 0)
		)
	)
	(footprint ""
		(layer "F.Cu")
		(at 181.7624 -94.338648 90)
		(property "Reference" "R4590"
			(at 0 0 90)
			(layer "F.SilkS")
			(hide yes)
			(effects
				(font
					(size 1.27 1.27)
				)
			)
		)
		(property "Value" ""
			(at 0 0 90)
			(layer "F.Fab")
			(effects
				(font
					(size 1.27 1.27)
				)
			)
		)
		(duplicate_pad_numbers_are_jumpers no)
		(fp_line
			(start 0.7874 -0.4064)
			(end 0.7874 0.4064)
			(stroke
				(width 0.1524)
				(type default)
			)
			(layer "F.SilkS")
		)
		(fp_line
			(start -0.7874 -0.4064)
			(end 0.7874 -0.4064)
			(stroke
				(width 0.1524)
				(type default)
			)
			(layer "F.SilkS")
		)
		(fp_line
			(start 0.7874 0.4064)
			(end -0.7874 0.4064)
			(stroke
				(width 0.1524)
				(type default)
			)
			(layer "F.SilkS")
		)
		(fp_line
			(start -0.7874 0.4064)
			(end -0.7874 -0.4064)
			(stroke
				(width 0.1524)
				(type default)
			)
			(layer "F.SilkS")
		)
		(fp_line
			(start -0.12065 -0.305054)
			(end -0.12065 -0.2794)
			(stroke
				(width 0.1)
				(type default)
			)
			(layer "F.Fab")
		)
		(fp_line
			(start -0.67945 -0.305054)
			(end -0.12065 -0.305054)
			(stroke
				(width 0.1)
				(type default)
			)
			(layer "F.Fab")
		)
		(fp_line
			(start 0.67945 -0.3048)
			(end 0.67945 0.3048)
			(stroke
				(width 0.1)
				(type default)
			)
			(layer "F.Fab")
		)
		(fp_line
			(start 0.12065 -0.3048)
			(end 0.67945 -0.3048)
			(stroke
				(width 0.1)
				(type default)
			)
			(layer "F.Fab")
		)
		(fp_line
			(start 0.12065 -0.2794)
			(end 0.12065 -0.3048)
			(stroke
				(width 0.1)
				(type default)
			)
			(layer "F.Fab")
		)
		(fp_line
			(start -0.12065 -0.2794)
			(end 0.12065 -0.2794)
			(stroke
				(width 0.1)
				(type default)
			)
			(layer "F.Fab")
		)
		(fp_line
			(start 0.120396 0.2794)
			(end -0.12065 0.2794)
			(stroke
				(width 0.1)
				(type default)
			)
			(layer "F.Fab")
		)
		(fp_line
			(start -0.12065 0.2794)
			(end -0.12065 0.3048)
			(stroke
				(width 0.1)
				(type default)
			)
			(layer "F.Fab")
		)
		(fp_line
			(start 0.67945 0.3048)
			(end 0.120396 0.3048)
			(stroke
				(width 0.1)
				(type default)
			)
			(layer "F.Fab")
		)
		(fp_line
			(start 0.120396 0.3048)
			(end 0.120396 0.2794)
			(stroke
				(width 0.1)
				(type default)
			)
			(layer "F.Fab")
		)
		(fp_line
			(start -0.12065 0.3048)
			(end -0.67945 0.3048)
			(stroke
				(width 0.1)
				(type default)
			)
			(layer "F.Fab")
		)
		(fp_line
			(start -0.67945 0.3048)
			(end -0.67945 -0.305054)
			(stroke
				(width 0.1)
				(type default)
			)
			(layer "F.Fab")
		)
		(pad "1" smd rect
			(at -0.40005 0 270)
			(size 0.4572 0.508)
			(layers "F.Cu" "F.Mask" "F.Paste")
			(net "FAB_BMC_REV_ID1")
		)
		(pad "2" smd rect
			(at 0.40005 0 270)
			(size 0.4572 0.508)
			(layers "F.Cu" "F.Mask" "F.Paste")
			(net "GND")
		)
	)
	(footprint ""
		(layer "F.Cu")
		(at 327.129902 -22.661626 -90)
		(property "Reference" "R4096"
			(at 0 0 270)
			(layer "F.SilkS")
			(hide yes)
			(effects
				(font
					(size 1.27 1.27)
				)
			)
		)
		(property "Value" ""
			(at 0 0 270)
			(layer "F.Fab")
			(effects
				(font
					(size 1.27 1.27)
				)
			)
		)
		(duplicate_pad_numbers_are_jumpers no)
		(fp_line
			(start -0.7874 0.4064)
			(end -0.7874 -0.4064)
			(stroke
				(width 0.1524)
				(type default)
			)
			(layer "F.SilkS")
		)
		(fp_line
			(start 0.7874 0.4064)
			(end -0.7874 0.4064)
			(stroke
				(width 0.1524)
				(type default)
			)
			(layer "F.SilkS")
		)
		(fp_line
			(start -0.7874 -0.4064)
			(end 0.7874 -0.4064)
			(stroke
				(width 0.1524)
				(type default)
			)
			(layer "F.SilkS")
		)
		(fp_line
			(start 0.7874 -0.4064)
			(end 0.7874 0.4064)
			(stroke
				(width 0.1524)
				(type default)
			)
			(layer "F.SilkS")
		)
		(fp_line
			(start -0.67945 0.3048)
			(end -0.67945 -0.305054)
			(stroke
				(width 0.1)
				(type default)
			)
			(layer "F.Fab")
		)
		(fp_line
			(start -0.12065 0.3048)
			(end -0.67945 0.3048)
			(stroke
				(width 0.1)
				(type default)
			)
			(layer "F.Fab")
		)
		(fp_line
			(start 0.120396 0.3048)
			(end 0.120396 0.2794)
			(stroke
				(width 0.1)
				(type default)
			)
			(layer "F.Fab")
		)
		(fp_line
			(start 0.67945 0.3048)
			(end 0.120396 0.3048)
			(stroke
				(width 0.1)
				(type default)
			)
			(layer "F.Fab")
		)
		(fp_line
			(start -0.12065 0.2794)
			(end -0.12065 0.3048)
			(stroke
				(width 0.1)
				(type default)
			)
			(layer "F.Fab")
		)
		(fp_line
			(start 0.120396 0.2794)
			(end -0.12065 0.2794)
			(stroke
				(width 0.1)
				(type default)
			)
			(layer "F.Fab")
		)
		(fp_line
			(start -0.12065 -0.2794)
			(end 0.12065 -0.2794)
			(stroke
				(width 0.1)
				(type default)
			)
			(layer "F.Fab")
		)
		(fp_line
			(start 0.12065 -0.2794)
			(end 0.12065 -0.3048)
			(stroke
				(width 0.1)
				(type default)
			)
			(layer "F.Fab")
		)
		(fp_line
			(start 0.12065 -0.3048)
			(end 0.67945 -0.3048)
			(stroke
				(width 0.1)
				(type default)
			)
			(layer "F.Fab")
		)
		(fp_line
			(start 0.67945 -0.3048)
			(end 0.67945 0.3048)
			(stroke
				(width 0.1)
				(type default)
			)
			(layer "F.Fab")
		)
		(fp_line
			(start -0.67945 -0.305054)
			(end -0.12065 -0.305054)
			(stroke
				(width 0.1)
				(type default)
			)
			(layer "F.Fab")
		)
		(fp_line
			(start -0.12065 -0.305054)
			(end -0.12065 -0.2794)
			(stroke
				(width 0.1)
				(type default)
			)
			(layer "F.Fab")
		)
		(pad "1" smd circle
			(at -0.40005 0 270)
			(size 0 0)
			(layers "F.Cu" "F.Mask" "F.Paste")
			(net "PD_PCH_GPPC_A_18")
		)
		(pad "2" smd circle
			(at 0.40005 0 270)
			(size 0 0)
			(layers "F.Cu" "F.Mask" "F.Paste")
			(net "GND")
		)
	)
	(footprint ""
		(layer "F.Cu")
		(at 113.882424 -37.01034 180)
		(property "Reference" "R4514"
			(at 0 0 180)
			(layer "F.SilkS")
			(hide yes)
			(effects
				(font
					(size 1.27 1.27)
				)
			)
		)
		(property "Value" ""
			(at 0 0 180)
			(layer "F.Fab")
			(effects
				(font
					(size 1.27 1.27)
				)
			)
		)
		(duplicate_pad_numbers_are_jumpers no)
		(fp_line
			(start 0.7874 0.4064)
			(end -0.7874 0.4064)
			(stroke
				(width 0.1524)
				(type default)
			)
			(layer "F.SilkS")
		)
		(fp_line
			(start 0.7874 -0.4064)
			(end 0.7874 0.4064)
			(stroke
				(width 0.1524)
				(type default)
			)
			(layer "F.SilkS")
		)
		(fp_line
			(start -0.7874 0.4064)
			(end -0.7874 -0.4064)
			(stroke
				(width 0.1524)
				(type default)
			)
			(layer "F.SilkS")
		)
		(fp_line
			(start -0.7874 -0.4064)
			(end 0.7874 -0.4064)
			(stroke
				(width 0.1524)
				(type default)
			)
			(layer "F.SilkS")
		)
		(fp_line
			(start 0.67945 0.3048)
			(end 0.120396 0.3048)
			(stroke
				(width 0.1)
				(type default)
			)
			(layer "F.Fab")
		)
		(fp_line
			(start 0.67945 -0.3048)
			(end 0.67945 0.3048)
			(stroke
				(width 0.1)
				(type default)
			)
			(layer "F.Fab")
		)
		(fp_line
			(start 0.12065 -0.2794)
			(end 0.12065 -0.3048)
			(stroke
				(width 0.1)
				(type default)
			)
			(layer "F.Fab")
		)
		(fp_line
			(start 0.12065 -0.3048)
			(end 0.67945 -0.3048)
			(stroke
				(width 0.1)
				(type default)
			)
			(layer "F.Fab")
		)
		(fp_line
			(start 0.120396 0.3048)
			(end 0.120396 0.2794)
			(stroke
				(width 0.1)
				(type default)
			)
			(layer "F.Fab")
		)
		(fp_line
			(start 0.120396 0.2794)
			(end -0.12065 0.2794)
			(stroke
				(width 0.1)
				(type default)
			)
			(layer "F.Fab")
		)
		(fp_line
			(start -0.12065 0.3048)
			(end -0.67945 0.3048)
			(stroke
				(width 0.1)
				(type default)
			)
			(layer "F.Fab")
		)
		(fp_line
			(start -0.12065 0.2794)
			(end -0.12065 0.3048)
			(stroke
				(width 0.1)
				(type default)
			)
			(layer "F.Fab")
		)
		(fp_line
			(start -0.12065 -0.2794)
			(end 0.12065 -0.2794)
			(stroke
				(width 0.1)
				(type default)
			)
			(layer "F.Fab")
		)
		(fp_line
			(start -0.12065 -0.305054)
			(end -0.12065 -0.2794)
			(stroke
				(width 0.1)
				(type default)
			)
			(layer "F.Fab")
		)
		(fp_line
			(start -0.67945 0.3048)
			(end -0.67945 -0.305054)
			(stroke
				(width 0.1)
				(type default)
			)
			(layer "F.Fab")
		)
		(fp_line
			(start -0.67945 -0.305054)
			(end -0.12065 -0.305054)
			(stroke
				(width 0.1)
				(type default)
			)
			(layer "F.Fab")
		)
		(pad "1" smd circle
			(at -0.40005 0 180)
			(size 0 0)
			(layers "F.Cu" "F.Mask" "F.Paste")
			(net "CLK_GEN2_GPU_FPGA_OE_R2_N")
		)
		(pad "2" smd circle
			(at 0.40005 0 180)
			(size 0 0)
			(layers "F.Cu" "F.Mask" "F.Paste")
			(net "GND")
		)
	)
	(footprint ""
		(layer "F.Cu")
		(at 423.096436 -366.66932 -90)
		(property "Reference" "PC1351"
			(at 0 0 270)
			(layer "F.SilkS")
			(hide yes)
			(effects
				(font
					(size 1.27 1.27)
				)
			)
		)
		(property "Value" ""
			(at 0 0 270)
			(layer "F.Fab")
			(effects
				(font
					(size 1.27 1.27)
				)
			)
		)
		(duplicate_pad_numbers_are_jumpers no)
		(fp_line
			(start -0.7874 0.4064)
			(end -0.7874 -0.4064)
			(stroke
				(width 0.1524)
				(type default)
			)
			(layer "F.SilkS")
		)
		(fp_line
			(start 0.7874 0.4064)
			(end -0.7874 0.4064)
			(stroke
				(width 0.1524)
				(type default)
			)
			(layer "F.SilkS")
		)
		(fp_line
			(start -0.7874 -0.4064)
			(end 0.7874 -0.4064)
			(stroke
				(width 0.1524)
				(type default)
			)
			(layer "F.SilkS")
		)
		(fp_line
			(start 0.7874 -0.4064)
			(end 0.7874 0.4064)
			(stroke
				(width 0.1524)
				(type default)
			)
			(layer "F.SilkS")
		)
		(fp_line
			(start -0.67945 0.3048)
			(end -0.67945 -0.305054)
			(stroke
				(width 0.1)
				(type default)
			)
			(layer "F.Fab")
		)
		(fp_line
			(start -0.12065 0.3048)
			(end -0.67945 0.3048)
			(stroke
				(width 0.1)
				(type default)
			)
			(layer "F.Fab")
		)
		(fp_line
			(start 0.120396 0.3048)
			(end 0.120396 0.2794)
			(stroke
				(width 0.1)
				(type default)
			)
			(layer "F.Fab")
		)
		(fp_line
			(start 0.67945 0.3048)
			(end 0.120396 0.3048)
			(stroke
				(width 0.1)
				(type default)
			)
			(layer "F.Fab")
		)
		(fp_line
			(start -0.12065 0.2794)
			(end -0.12065 0.3048)
			(stroke
				(width 0.1)
				(type default)
			)
			(layer "F.Fab")
		)
		(fp_line
			(start 0.120396 0.2794)
			(end -0.12065 0.2794)
			(stroke
				(width 0.1)
				(type default)
			)
			(layer "F.Fab")
		)
		(fp_line
			(start -0.12065 -0.2794)
			(end 0.12065 -0.2794)
			(stroke
				(width 0.1)
				(type default)
			)
			(layer "F.Fab")
		)
		(fp_line
			(start 0.12065 -0.2794)
			(end 0.12065 -0.3048)
			(stroke
				(width 0.1)
				(type default)
			)
			(layer "F.Fab")
		)
		(fp_line
			(start 0.12065 -0.3048)
			(end 0.67945 -0.3048)
			(stroke
				(width 0.1)
				(type default)
			)
			(layer "F.Fab")
		)
		(fp_line
			(start 0.67945 -0.3048)
			(end 0.67945 0.3048)
			(stroke
				(width 0.1)
				(type default)
			)
			(layer "F.Fab")
		)
		(fp_line
			(start -0.67945 -0.305054)
			(end -0.12065 -0.305054)
			(stroke
				(width 0.1)
				(type default)
			)
			(layer "F.Fab")
		)
		(fp_line
			(start -0.12065 -0.305054)
			(end -0.12065 -0.2794)
			(stroke
				(width 0.1)
				(type default)
			)
			(layer "F.Fab")
		)
		(pad "1" smd circle
			(at -0.40005 0 270)
			(size 0 0)
			(layers "F.Cu" "F.Mask" "F.Paste")
			(net "GND")
		)
		(pad "2" smd circle
			(at 0.40005 0 270)
			(size 0 0)
			(layers "F.Cu" "F.Mask" "F.Paste")
			(net "PVCCIN_CPU0_VREF")
		)
	)
	(footprint ""
		(layer "F.Cu")
		(at 232.911396 -245.411498 90)
		(property "Reference" "R4076"
			(at 0 0 90)
			(layer "F.SilkS")
			(hide yes)
			(effects
				(font
					(size 1.27 1.27)
				)
			)
		)
		(property "Value" ""
			(at 0 0 90)
			(layer "F.Fab")
			(effects
				(font
					(size 1.27 1.27)
				)
			)
		)
		(duplicate_pad_numbers_are_jumpers no)
		(fp_line
			(start 0.7874 -0.4064)
			(end 0.7874 0.4064)
			(stroke
				(width 0.1524)
				(type default)
			)
			(layer "F.SilkS")
		)
		(fp_line
			(start -0.7874 -0.4064)
			(end 0.7874 -0.4064)
			(stroke
				(width 0.1524)
				(type default)
			)
			(layer "F.SilkS")
		)
		(fp_line
			(start 0.7874 0.4064)
			(end -0.7874 0.4064)
			(stroke
				(width 0.1524)
				(type default)
			)
			(layer "F.SilkS")
		)
		(fp_line
			(start -0.7874 0.4064)
			(end -0.7874 -0.4064)
			(stroke
				(width 0.1524)
				(type default)
			)
			(layer "F.SilkS")
		)
		(fp_line
			(start -0.12065 -0.305054)
			(end -0.12065 -0.2794)
			(stroke
				(width 0.1)
				(type default)
			)
			(layer "F.Fab")
		)
		(fp_line
			(start -0.67945 -0.305054)
			(end -0.12065 -0.305054)
			(stroke
				(width 0.1)
				(type default)
			)
			(layer "F.Fab")
		)
		(fp_line
			(start 0.67945 -0.3048)
			(end 0.67945 0.3048)
			(stroke
				(width 0.1)
				(type default)
			)
			(layer "F.Fab")
		)
		(fp_line
			(start 0.12065 -0.3048)
			(end 0.67945 -0.3048)
			(stroke
				(width 0.1)
				(type default)
			)
			(layer "F.Fab")
		)
		(fp_line
			(start 0.12065 -0.2794)
			(end 0.12065 -0.3048)
			(stroke
				(width 0.1)
				(type default)
			)
			(layer "F.Fab")
		)
		(fp_line
			(start -0.12065 -0.2794)
			(end 0.12065 -0.2794)
			(stroke
				(width 0.1)
				(type default)
			)
			(layer "F.Fab")
		)
		(fp_line
			(start 0.120396 0.2794)
			(end -0.12065 0.2794)
			(stroke
				(width 0.1)
				(type default)
			)
			(layer "F.Fab")
		)
		(fp_line
			(start -0.12065 0.2794)
			(end -0.12065 0.3048)
			(stroke
				(width 0.1)
				(type default)
			)
			(layer "F.Fab")
		)
		(fp_line
			(start 0.67945 0.3048)
			(end 0.120396 0.3048)
			(stroke
				(width 0.1)
				(type default)
			)
			(layer "F.Fab")
		)
		(fp_line
			(start 0.120396 0.3048)
			(end 0.120396 0.2794)
			(stroke
				(width 0.1)
				(type default)
			)
			(layer "F.Fab")
		)
		(fp_line
			(start -0.12065 0.3048)
			(end -0.67945 0.3048)
			(stroke
				(width 0.1)
				(type default)
			)
			(layer "F.Fab")
		)
		(fp_line
			(start -0.67945 0.3048)
			(end -0.67945 -0.305054)
			(stroke
				(width 0.1)
				(type default)
			)
			(layer "F.Fab")
		)
		(pad "1" smd circle
			(at -0.40005 0 90)
			(size 0 0)
			(layers "F.Cu" "F.Mask" "F.Paste")
			(net "CLK_GEN2_GPU_FPGA_OE_OR_N")
		)
		(pad "2" smd circle
			(at 0.40005 0 90)
			(size 0 0)
			(layers "F.Cu" "F.Mask" "F.Paste")
			(net "CLK_GEN2_GPU_OE_N")
		)
	)
	(footprint ""
		(layer "F.Cu")
		(at 194.30619 -43.199558 180)
		(property "Reference" "Q125"
			(at 5.05206 1.580388 0)
			(unlocked yes)
			(layer "F.SilkS")
			(effects
				(font
					(size 0.7874 0.5842)
					(thickness 0.1524)
				)
				(justify left)
			)
		)
		(property "Value" ""
			(at 0 0 180)
			(layer "F.Fab")
			(effects
				(font
					(size 1.27 1.27)
				)
			)
		)
		(duplicate_pad_numbers_are_jumpers no)
		(fp_line
			(start 1.332738 1.100074)
			(end -1.332738 1.100074)
			(stroke
				(width 0.1524)
				(type default)
			)
			(layer "F.SilkS")
		)
		(fp_line
			(start 1.332738 -1.100074)
			(end 1.332738 1.100074)
			(stroke
				(width 0.1524)
				(type default)
			)
			(layer "F.SilkS")
		)
		(fp_line
			(start 0.4826 -1.100074)
			(end 1.332738 -1.100074)
			(stroke
				(width 0.1524)
				(type default)
			)
			(layer "F.SilkS")
		)
		(fp_line
			(start 0 -0.541274)
			(end 0.4826 -1.100074)
			(stroke
				(width 0.1524)
				(type default)
			)
			(layer "F.SilkS")
		)
		(fp_line
			(start -0.4826 -1.100074)
			(end 0 -0.541274)
			(stroke
				(width 0.1524)
				(type default)
			)
			(layer "F.SilkS")
		)
		(fp_line
			(start -1.332738 1.100074)
			(end -1.332738 -1.100074)
			(stroke
				(width 0.1524)
				(type default)
			)
			(layer "F.SilkS")
		)
		(fp_line
			(start -1.332738 -1.100074)
			(end -0.4826 -1.100074)
			(stroke
				(width 0.1524)
				(type default)
			)
			(layer "F.SilkS")
		)
		(fp_poly
			(pts
				(xy -1.928114 -1.29413) (xy -1.495552 -0.639064) (xy -2.279142 -0.686054)
			)
			(stroke
				(width 0)
				(type default)
			)
			(fill yes)
			(layer "F.SilkS")
		)
		(fp_line
			(start 0.674878 1.100074)
			(end -0.674878 1.100074)
			(stroke
				(width 0.1)
				(type default)
			)
			(layer "F.Fab")
		)
		(fp_line
			(start 0.674878 -1.100074)
			(end 0.674878 1.100074)
			(stroke
				(width 0.1)
				(type default)
			)
			(layer "F.Fab")
		)
		(fp_line
			(start -0.674878 1.100074)
			(end -0.674878 -1.100074)
			(stroke
				(width 0.1)
				(type default)
			)
			(layer "F.Fab")
		)
		(fp_line
			(start -0.674878 -1.100074)
			(end 0.674878 -1.100074)
			(stroke
				(width 0.1)
				(type default)
			)
			(layer "F.Fab")
		)
		(fp_poly
			(pts
				(xy -2.2352 -0.298958) (xy -2.2352 -1.001014) (xy -1.533144 -0.649986)
			)
			(stroke
				(width 0)
				(type default)
			)
			(fill yes)
			(layer "F.Fab")
		)
		(pad "1" smd rect
			(at -0.94996 -0.649986 270)
			(size 0.4318 0.508)
			(layers "F.Cu" "F.Mask" "F.Paste")
			(net "GND")
		)
		(pad "2" smd rect
			(at -0.94996 0 270)
			(size 0.4318 0.508)
			(layers "F.Cu" "F.Mask" "F.Paste")
			(net "P12V_SCM_EN_R")
		)
		(pad "3" smd rect
			(at -0.94996 0.649986 270)
			(size 0.4318 0.508)
			(layers "F.Cu" "F.Mask" "F.Paste")
			(net "P12V_SCM_UV_R")
		)
		(pad "4" smd rect
			(at 0.94996 0.649986 270)
			(size 0.4318 0.508)
			(layers "F.Cu" "F.Mask" "F.Paste")
			(net "GND")
		)
		(pad "5" smd rect
			(at 0.94996 0 270)
			(size 0.4318 0.508)
			(layers "F.Cu" "F.Mask" "F.Paste")
			(net "P12V_SCM_EN_G")
		)
		(pad "6" smd rect
			(at 0.94996 -0.649986 270)
			(size 0.4318 0.508)
			(layers "F.Cu" "F.Mask" "F.Paste")
			(net "P12V_SCM_EN_G")
		)
	)
	(footprint ""
		(layer "F.Cu")
		(at 172.7835 -358.15778 90)
		(property "Reference" "PR1800"
			(at 0 0 90)
			(layer "F.SilkS")
			(hide yes)
			(effects
				(font
					(size 1.27 1.27)
				)
			)
		)
		(property "Value" ""
			(at 0 0 90)
			(layer "F.Fab")
			(effects
				(font
					(size 1.27 1.27)
				)
			)
		)
		(duplicate_pad_numbers_are_jumpers no)
		(fp_line
			(start 0.7874 -0.4064)
			(end 0.7874 0.4064)
			(stroke
				(width 0.1524)
				(type default)
			)
			(layer "F.SilkS")
		)
		(fp_line
			(start -0.7874 -0.4064)
			(end 0.7874 -0.4064)
			(stroke
				(width 0.1524)
				(type default)
			)
			(layer "F.SilkS")
		)
		(fp_line
			(start 0.7874 0.4064)
			(end -0.7874 0.4064)
			(stroke
				(width 0.1524)
				(type default)
			)
			(layer "F.SilkS")
		)
		(fp_line
			(start -0.7874 0.4064)
			(end -0.7874 -0.4064)
			(stroke
				(width 0.1524)
				(type default)
			)
			(layer "F.SilkS")
		)
		(fp_line
			(start -0.12065 -0.305054)
			(end -0.12065 -0.2794)
			(stroke
				(width 0.1)
				(type default)
			)
			(layer "F.Fab")
		)
		(fp_line
			(start -0.67945 -0.305054)
			(end -0.12065 -0.305054)
			(stroke
				(width 0.1)
				(type default)
			)
			(layer "F.Fab")
		)
		(fp_line
			(start 0.67945 -0.3048)
			(end 0.67945 0.3048)
			(stroke
				(width 0.1)
				(type default)
			)
			(layer "F.Fab")
		)
		(fp_line
			(start 0.12065 -0.3048)
			(end 0.67945 -0.3048)
			(stroke
				(width 0.1)
				(type default)
			)
			(layer "F.Fab")
		)
		(fp_line
			(start 0.12065 -0.2794)
			(end 0.12065 -0.3048)
			(stroke
				(width 0.1)
				(type default)
			)
			(layer "F.Fab")
		)
		(fp_line
			(start -0.12065 -0.2794)
			(end 0.12065 -0.2794)
			(stroke
				(width 0.1)
				(type default)
			)
			(layer "F.Fab")
		)
		(fp_line
			(start 0.120396 0.2794)
			(end -0.12065 0.2794)
			(stroke
				(width 0.1)
				(type default)
			)
			(layer "F.Fab")
		)
		(fp_line
			(start -0.12065 0.2794)
			(end -0.12065 0.3048)
			(stroke
				(width 0.1)
				(type default)
			)
			(layer "F.Fab")
		)
		(fp_line
			(start 0.67945 0.3048)
			(end 0.120396 0.3048)
			(stroke
				(width 0.1)
				(type default)
			)
			(layer "F.Fab")
		)
		(fp_line
			(start 0.120396 0.3048)
			(end 0.120396 0.2794)
			(stroke
				(width 0.1)
				(type default)
			)
			(layer "F.Fab")
		)
		(fp_line
			(start -0.12065 0.3048)
			(end -0.67945 0.3048)
			(stroke
				(width 0.1)
				(type default)
			)
			(layer "F.Fab")
		)
		(fp_line
			(start -0.67945 0.3048)
			(end -0.67945 -0.305054)
			(stroke
				(width 0.1)
				(type default)
			)
			(layer "F.Fab")
		)
		(pad "1" smd circle
			(at -0.40005 0 90)
			(size 0 0)
			(layers "F.Cu" "F.Mask" "F.Paste")
			(net "SW_PVCCFA_EHV_FIVRA_CPU1_BOOT1")
		)
		(pad "2" smd circle
			(at 0.40005 0 90)
			(size 0 0)
			(layers "F.Cu" "F.Mask" "F.Paste")
			(net "SW_PVCCFA_EHV_FIVRA_CPU1_BOOT1_")
		)
	)
	(footprint ""
		(layer "F.Cu")
		(at 320.81216 -26.700988 -90)
		(property "Reference" "R2412"
			(at 0 0 270)
			(layer "F.SilkS")
			(hide yes)
			(effects
				(font
					(size 1.27 1.27)
				)
			)
		)
		(property "Value" ""
			(at 0 0 270)
			(layer "F.Fab")
			(effects
				(font
					(size 1.27 1.27)
				)
			)
		)
		(duplicate_pad_numbers_are_jumpers no)
		(fp_line
			(start -0.7874 0.4064)
			(end -0.7874 -0.4064)
			(stroke
				(width 0.1524)
				(type default)
			)
			(layer "F.SilkS")
		)
		(fp_line
			(start 0.7874 0.4064)
			(end -0.7874 0.4064)
			(stroke
				(width 0.1524)
				(type default)
			)
			(layer "F.SilkS")
		)
		(fp_line
			(start -0.7874 -0.4064)
			(end 0.7874 -0.4064)
			(stroke
				(width 0.1524)
				(type default)
			)
			(layer "F.SilkS")
		)
		(fp_line
			(start 0.7874 -0.4064)
			(end 0.7874 0.4064)
			(stroke
				(width 0.1524)
				(type default)
			)
			(layer "F.SilkS")
		)
		(fp_line
			(start -0.67945 0.3048)
			(end -0.67945 -0.305054)
			(stroke
				(width 0.1)
				(type default)
			)
			(layer "F.Fab")
		)
		(fp_line
			(start -0.12065 0.3048)
			(end -0.67945 0.3048)
			(stroke
				(width 0.1)
				(type default)
			)
			(layer "F.Fab")
		)
		(fp_line
			(start 0.120396 0.3048)
			(end 0.120396 0.2794)
			(stroke
				(width 0.1)
				(type default)
			)
			(layer "F.Fab")
		)
		(fp_line
			(start 0.67945 0.3048)
			(end 0.120396 0.3048)
			(stroke
				(width 0.1)
				(type default)
			)
			(layer "F.Fab")
		)
		(fp_line
			(start -0.12065 0.2794)
			(end -0.12065 0.3048)
			(stroke
				(width 0.1)
				(type default)
			)
			(layer "F.Fab")
		)
		(fp_line
			(start 0.120396 0.2794)
			(end -0.12065 0.2794)
			(stroke
				(width 0.1)
				(type default)
			)
			(layer "F.Fab")
		)
		(fp_line
			(start -0.12065 -0.2794)
			(end 0.12065 -0.2794)
			(stroke
				(width 0.1)
				(type default)
			)
			(layer "F.Fab")
		)
		(fp_line
			(start 0.12065 -0.2794)
			(end 0.12065 -0.3048)
			(stroke
				(width 0.1)
				(type default)
			)
			(layer "F.Fab")
		)
		(fp_line
			(start 0.12065 -0.3048)
			(end 0.67945 -0.3048)
			(stroke
				(width 0.1)
				(type default)
			)
			(layer "F.Fab")
		)
		(fp_line
			(start 0.67945 -0.3048)
			(end 0.67945 0.3048)
			(stroke
				(width 0.1)
				(type default)
			)
			(layer "F.Fab")
		)
		(fp_line
			(start -0.67945 -0.305054)
			(end -0.12065 -0.305054)
			(stroke
				(width 0.1)
				(type default)
			)
			(layer "F.Fab")
		)
		(fp_line
			(start -0.12065 -0.305054)
			(end -0.12065 -0.2794)
			(stroke
				(width 0.1)
				(type default)
			)
			(layer "F.Fab")
		)
		(pad "1" smd circle
			(at -0.40005 0 270)
			(size 0 0)
			(layers "F.Cu" "F.Mask" "F.Paste")
			(net "PWRGD_DSW_PWROK")
		)
		(pad "2" smd circle
			(at 0.40005 0 270)
			(size 0 0)
			(layers "F.Cu" "F.Mask" "F.Paste")
			(net "PWRGD_DSW_PWROK_R3")
		)
	)
	(footprint ""
		(layer "F.Cu")
		(at 101.58349 -336.192368 90)
		(property "Reference" "PC556"
			(at 0 0 90)
			(layer "F.SilkS")
			(hide yes)
			(effects
				(font
					(size 1.27 1.27)
				)
			)
		)
		(property "Value" ""
			(at 0 0 90)
			(layer "F.Fab")
			(effects
				(font
					(size 1.27 1.27)
				)
			)
		)
		(duplicate_pad_numbers_are_jumpers no)
		(fp_line
			(start 0.7874 -0.4064)
			(end 0.7874 0.4064)
			(stroke
				(width 0.1524)
				(type default)
			)
			(layer "F.SilkS")
		)
		(fp_line
			(start -0.7874 -0.4064)
			(end 0.7874 -0.4064)
			(stroke
				(width 0.1524)
				(type default)
			)
			(layer "F.SilkS")
		)
		(fp_line
			(start 0.7874 0.4064)
			(end -0.7874 0.4064)
			(stroke
				(width 0.1524)
				(type default)
			)
			(layer "F.SilkS")
		)
		(fp_line
			(start -0.7874 0.4064)
			(end -0.7874 -0.4064)
			(stroke
				(width 0.1524)
				(type default)
			)
			(layer "F.SilkS")
		)
		(fp_line
			(start -0.12065 -0.305054)
			(end -0.12065 -0.2794)
			(stroke
				(width 0.1)
				(type default)
			)
			(layer "F.Fab")
		)
		(fp_line
			(start -0.67945 -0.305054)
			(end -0.12065 -0.305054)
			(stroke
				(width 0.1)
				(type default)
			)
			(layer "F.Fab")
		)
		(fp_line
			(start 0.67945 -0.3048)
			(end 0.67945 0.3048)
			(stroke
				(width 0.1)
				(type default)
			)
			(layer "F.Fab")
		)
		(fp_line
			(start 0.12065 -0.3048)
			(end 0.67945 -0.3048)
			(stroke
				(width 0.1)
				(type default)
			)
			(layer "F.Fab")
		)
		(fp_line
			(start 0.12065 -0.2794)
			(end 0.12065 -0.3048)
			(stroke
				(width 0.1)
				(type default)
			)
			(layer "F.Fab")
		)
		(fp_line
			(start -0.12065 -0.2794)
			(end 0.12065 -0.2794)
			(stroke
				(width 0.1)
				(type default)
			)
			(layer "F.Fab")
		)
		(fp_line
			(start 0.120396 0.2794)
			(end -0.12065 0.2794)
			(stroke
				(width 0.1)
				(type default)
			)
			(layer "F.Fab")
		)
		(fp_line
			(start -0.12065 0.2794)
			(end -0.12065 0.3048)
			(stroke
				(width 0.1)
				(type default)
			)
			(layer "F.Fab")
		)
		(fp_line
			(start 0.67945 0.3048)
			(end 0.120396 0.3048)
			(stroke
				(width 0.1)
				(type default)
			)
			(layer "F.Fab")
		)
		(fp_line
			(start 0.120396 0.3048)
			(end 0.120396 0.2794)
			(stroke
				(width 0.1)
				(type default)
			)
			(layer "F.Fab")
		)
		(fp_line
			(start -0.12065 0.3048)
			(end -0.67945 0.3048)
			(stroke
				(width 0.1)
				(type default)
			)
			(layer "F.Fab")
		)
		(fp_line
			(start -0.67945 0.3048)
			(end -0.67945 -0.305054)
			(stroke
				(width 0.1)
				(type default)
			)
			(layer "F.Fab")
		)
		(pad "1" smd circle
			(at -0.40005 0 90)
			(size 0 0)
			(layers "F.Cu" "F.Mask" "F.Paste")
			(net "PVCCIN_CPU1_VDD2")
		)
		(pad "2" smd circle
			(at 0.40005 0 90)
			(size 0 0)
			(layers "F.Cu" "F.Mask" "F.Paste")
			(net "GND")
		)
	)
	(footprint ""
		(layer "F.Cu")
		(at 18.8214 -410.7942 90)
		(property "Reference" "R4728"
			(at 0 0 90)
			(layer "F.SilkS")
			(hide yes)
			(effects
				(font
					(size 1.27 1.27)
				)
			)
		)
		(property "Value" ""
			(at 0 0 90)
			(layer "F.Fab")
			(effects
				(font
					(size 1.27 1.27)
				)
			)
		)
		(duplicate_pad_numbers_are_jumpers no)
		(fp_line
			(start 0.7874 -0.406146)
			(end 0.7874 0.406146)
			(stroke
				(width 0.1524)
				(type default)
			)
			(layer "F.SilkS")
		)
		(fp_line
			(start -0.7874 -0.406146)
			(end 0.7874 -0.406146)
			(stroke
				(width 0.1524)
				(type default)
			)
			(layer "F.SilkS")
		)
		(fp_line
			(start 0.7874 0.406146)
			(end -0.7874 0.406146)
			(stroke
				(width 0.1524)
				(type default)
			)
			(layer "F.SilkS")
		)
		(fp_line
			(start -0.7874 0.406146)
			(end -0.7874 -0.406146)
			(stroke
				(width 0.1524)
				(type default)
			)
			(layer "F.SilkS")
		)
		(fp_line
			(start -0.12065 -0.305054)
			(end -0.12065 -0.2794)
			(stroke
				(width 0.1)
				(type default)
			)
			(layer "F.Fab")
		)
		(fp_line
			(start -0.67945 -0.305054)
			(end -0.12065 -0.305054)
			(stroke
				(width 0.1)
				(type default)
			)
			(layer "F.Fab")
		)
		(fp_line
			(start 0.67945 -0.3048)
			(end 0.67945 0.3048)
			(stroke
				(width 0.1)
				(type default)
			)
			(layer "F.Fab")
		)
		(fp_line
			(start 0.120396 -0.3048)
			(end 0.67945 -0.3048)
			(stroke
				(width 0.1)
				(type default)
			)
			(layer "F.Fab")
		)
		(fp_line
			(start 0.12065 -0.2794)
			(end 0.120396 -0.3048)
			(stroke
				(width 0.1)
				(type default)
			)
			(layer "F.Fab")
		)
		(fp_line
			(start -0.12065 -0.2794)
			(end 0.12065 -0.2794)
			(stroke
				(width 0.1)
				(type default)
			)
			(layer "F.Fab")
		)
		(fp_line
			(start 0.120396 0.2794)
			(end -0.12065 0.2794)
			(stroke
				(width 0.1)
				(type default)
			)
			(layer "F.Fab")
		)
		(fp_line
			(start -0.12065 0.2794)
			(end -0.120396 0.3048)
			(stroke
				(width 0.1)
				(type default)
			)
			(layer "F.Fab")
		)
		(fp_line
			(start 0.67945 0.3048)
			(end 0.120396 0.3048)
			(stroke
				(width 0.1)
				(type default)
			)
			(layer "F.Fab")
		)
		(fp_line
			(start 0.120396 0.3048)
			(end 0.120396 0.2794)
			(stroke
				(width 0.1)
				(type default)
			)
			(layer "F.Fab")
		)
		(fp_line
			(start -0.120396 0.3048)
			(end -0.67945 0.3048)
			(stroke
				(width 0.1)
				(type default)
			)
			(layer "F.Fab")
		)
		(fp_line
			(start -0.67945 0.3048)
			(end -0.67945 -0.305054)
			(stroke
				(width 0.1)
				(type default)
			)
			(layer "F.Fab")
		)
		(pad "1" smd circle
			(at -0.40005 0 90)
			(size 0 0)
			(layers "F.Cu" "F.Mask" "F.Paste")
			(net "PRSNT_SWB_ISO_N")
		)
		(pad "2" smd circle
			(at 0.40005 0 90)
			(size 0 0)
			(layers "F.Cu" "F.Mask" "F.Paste")
			(net "PRSNT_SWB_ISO_R1_N")
		)
	)
	(footprint ""
		(layer "F.Cu")
		(at 228.764592 -124.281946 180)
		(property "Reference" "R566"
			(at 0 0 180)
			(layer "F.SilkS")
			(hide yes)
			(effects
				(font
					(size 1.27 1.27)
				)
			)
		)
		(property "Value" ""
			(at 0 0 180)
			(layer "F.Fab")
			(effects
				(font
					(size 1.27 1.27)
				)
			)
		)
		(duplicate_pad_numbers_are_jumpers no)
		(fp_line
			(start 0.7874 -0.4064)
			(end 0.7874 0.089154)
			(stroke
				(width 0.1524)
				(type default)
			)
			(layer "F.SilkS")
		)
		(fp_line
			(start 0.520192 0.4064)
			(end -0.429768 0.4064)
			(stroke
				(width 0.1524)
				(type default)
			)
			(layer "F.SilkS")
		)
		(fp_line
			(start -0.7874 0.063754)
			(end -0.7874 -0.4064)
			(stroke
				(width 0.1524)
				(type default)
			)
			(layer "F.SilkS")
		)
		(fp_line
			(start -0.7874 -0.4064)
			(end 0.7874 -0.4064)
			(stroke
				(width 0.1524)
				(type default)
			)
			(layer "F.SilkS")
		)
		(fp_line
			(start 0.67945 0.3048)
			(end 0.120396 0.3048)
			(stroke
				(width 0.1)
				(type default)
			)
			(layer "F.Fab")
		)
		(fp_line
			(start 0.67945 -0.3048)
			(end 0.67945 0.3048)
			(stroke
				(width 0.1)
				(type default)
			)
			(layer "F.Fab")
		)
		(fp_line
			(start 0.12065 -0.2794)
			(end 0.12065 -0.3048)
			(stroke
				(width 0.1)
				(type default)
			)
			(layer "F.Fab")
		)
		(fp_line
			(start 0.12065 -0.3048)
			(end 0.67945 -0.3048)
			(stroke
				(width 0.1)
				(type default)
			)
			(layer "F.Fab")
		)
		(fp_line
			(start 0.120396 0.3048)
			(end 0.120396 0.2794)
			(stroke
				(width 0.1)
				(type default)
			)
			(layer "F.Fab")
		)
		(fp_line
			(start 0.120396 0.2794)
			(end -0.12065 0.2794)
			(stroke
				(width 0.1)
				(type default)
			)
			(layer "F.Fab")
		)
		(fp_line
			(start -0.12065 0.3048)
			(end -0.67945 0.3048)
			(stroke
				(width 0.1)
				(type default)
			)
			(layer "F.Fab")
		)
		(fp_line
			(start -0.12065 0.2794)
			(end -0.12065 0.3048)
			(stroke
				(width 0.1)
				(type default)
			)
			(layer "F.Fab")
		)
		(fp_line
			(start -0.12065 -0.2794)
			(end 0.12065 -0.2794)
			(stroke
				(width 0.1)
				(type default)
			)
			(layer "F.Fab")
		)
		(fp_line
			(start -0.12065 -0.305054)
			(end -0.12065 -0.2794)
			(stroke
				(width 0.1)
				(type default)
			)
			(layer "F.Fab")
		)
		(fp_line
			(start -0.67945 0.3048)
			(end -0.67945 -0.305054)
			(stroke
				(width 0.1)
				(type default)
			)
			(layer "F.Fab")
		)
		(fp_line
			(start -0.67945 -0.305054)
			(end -0.12065 -0.305054)
			(stroke
				(width 0.1)
				(type default)
			)
			(layer "F.Fab")
		)
		(pad "1" smd circle
			(at -0.40005 0 180)
			(size 0 0)
			(layers "F.Cu" "F.Mask" "F.Paste")
			(net "CLK_100M_OCP_SFF_1_R_DN")
		)
		(pad "2" smd circle
			(at 0.40005 0 180)
			(size 0 0)
			(layers "F.Cu" "F.Mask" "F.Paste")
			(net "CLK_100M_OCP_SFF_1_DN")
		)
	)
	(footprint ""
		(layer "F.Cu")
		(at 79.356458 -20.694142)
		(property "Reference" "PU201"
			(at -9.250172 -0.290322 0)
			(unlocked yes)
			(layer "F.SilkS")
			(effects
				(font
					(size 0.7874 0.5842)
					(thickness 0.1524)
				)
				(justify left)
			)
		)
		(property "Value" ""
			(at 0 0 0)
			(layer "F.Fab")
			(effects
				(font
					(size 1.27 1.27)
				)
			)
		)
		(duplicate_pad_numbers_are_jumpers no)
		(fp_line
			(start -1.774952 -1.039876)
			(end -1.774952 1.039876)
			(stroke
				(width 0.1524)
				(type default)
			)
			(layer "F.SilkS")
		)
		(fp_line
			(start -1.774952 1.039876)
			(end 1.774952 1.039876)
			(stroke
				(width 0.1524)
				(type default)
			)
			(layer "F.SilkS")
		)
		(fp_line
			(start 1.774952 -1.039876)
			(end -1.774952 -1.039876)
			(stroke
				(width 0.1524)
				(type default)
			)
			(layer "F.SilkS")
		)
		(fp_line
			(start 1.774952 1.039876)
			(end 1.774952 -1.039876)
			(stroke
				(width 0.1524)
				(type default)
			)
			(layer "F.SilkS")
		)
		(fp_poly
			(pts
				(xy -1.769872 -1.039876) (xy -1.769872 -0.249936) (xy -2.531872 -0.249936) (xy -2.531872 -1.801876)
				(xy -0.999998 -1.801876) (xy -0.999998 -1.039876)
			)
			(stroke
				(width 0)
				(type default)
			)
			(fill yes)
			(layer "F.SilkS")
		)
		(fp_line
			(start -1.769872 -1.039876)
			(end -1.769872 1.039876)
			(stroke
				(width 0.1)
				(type default)
			)
			(layer "F.Fab")
		)
		(fp_line
			(start -1.769872 1.039876)
			(end 1.769872 1.039876)
			(stroke
				(width 0.1)
				(type default)
			)
			(layer "F.Fab")
		)
		(fp_line
			(start 1.769872 -1.039876)
			(end -1.769872 -1.039876)
			(stroke
				(width 0.1)
				(type default)
			)
			(layer "F.Fab")
		)
		(fp_line
			(start 1.769872 1.039876)
			(end 1.769872 -1.039876)
			(stroke
				(width 0.1)
				(type default)
			)
			(layer "F.Fab")
		)
		(fp_poly
			(pts
				(xy -1.769872 -1.039876) (xy -0.999998 -1.039876) (xy -0.999998 -1.801876) (xy -2.531872 -1.801876)
				(xy -2.531872 -0.249936) (xy -1.769872 -0.249936)
			)
			(stroke
				(width 0)
				(type default)
			)
			(fill yes)
			(layer "F.Fab")
		)
		(pad "A1" smd circle
			(at -1.500124 -0.750062)
			(size 0.2286 0.2286)
			(layers "F.Cu" "F.Mask" "F.Paste")
			(net "P12V_OCP_SENSE_2")
		)
		(pad "A2" smd circle
			(at -0.999998 -0.750062)
			(size 0.2286 0.2286)
			(layers "F.Cu" "F.Mask" "F.Paste")
			(net "P12V_OCP_VCC_2")
		)
		(pad "A3" smd circle
			(at -0.499872 -0.750062)
			(size 0.2286 0.2286)
			(layers "F.Cu" "F.Mask" "F.Paste")
			(net "P12V_AUX")
		)
		(pad "A4" smd circle
			(at 0 -0.750062)
			(size 0.2286 0.2286)
			(layers "F.Cu" "F.Mask" "F.Paste")
			(net "P12V_OCP_V3_2")
		)
		(pad "A5" smd circle
			(at 0.499872 -0.750062)
			(size 0.2286 0.2286)
			(layers "F.Cu" "F.Mask" "F.Paste")
			(net "P12V_AUX")
		)
		(pad "A6" smd circle
			(at 0.999998 -0.750062)
			(size 0.2286 0.2286)
			(layers "F.Cu" "F.Mask" "F.Paste")
			(net "P12V_OCP_GATE_2")
		)
		(pad "A7" smd circle
			(at 1.500124 -0.750062)
			(size 0.2286 0.2286)
			(layers "F.Cu" "F.Mask" "F.Paste")
			(net "GND")
		)
		(pad "B1" smd circle
			(at -1.500124 -0.249936)
			(size 0.2286 0.2286)
			(layers "F.Cu" "F.Mask" "F.Paste")
			(net "P12V_OCP_CB_2")
		)
		(pad "B2" smd circle
			(at -0.999998 -0.249936)
			(size 0.2286 0.2286)
			(layers "F.Cu" "F.Mask" "F.Paste")
			(net "GND")
		)
		(pad "B3" smd circle
			(at -0.499872 -0.249936)
			(size 0.2286 0.2286)
			(layers "F.Cu" "F.Mask" "F.Paste")
			(net "P12V_AUX")
		)
		(pad "B4" smd circle
			(at 0 -0.249936)
			(size 0.2286 0.2286)
			(layers "F.Cu" "F.Mask" "F.Paste")
			(net "P12V_OCP_V3_2")
		)
		(pad "B5" smd circle
			(at 0.499872 -0.249936)
			(size 0.2286 0.2286)
			(layers "F.Cu" "F.Mask" "F.Paste")
			(net "P12V_AUX")
		)
		(pad "B6" smd circle
			(at 0.999998 -0.249936)
			(size 0.2286 0.2286)
			(layers "F.Cu" "F.Mask" "F.Paste")
			(net "P12V_OCP_V3_2")
		)
		(pad "B7" smd circle
			(at 1.500124 -0.249936)
			(size 0.2286 0.2286)
			(layers "F.Cu" "F.Mask" "F.Paste")
			(net "GND")
		)
		(pad "C1" smd circle
			(at -1.500124 0.249936)
			(size 0.2286 0.2286)
			(layers "F.Cu" "F.Mask" "F.Paste")
			(net "GND")
		)
		(pad "C2" smd circle
			(at -0.999998 0.249936)
			(size 0.2286 0.2286)
			(layers "F.Cu" "F.Mask" "F.Paste")
			(net "GND")
		)
		(pad "C3" smd circle
			(at -0.499872 0.249936)
			(size 0.2286 0.2286)
			(layers "F.Cu" "F.Mask" "F.Paste")
			(net "P12V_AUX")
		)
		(pad "C4" smd circle
			(at 0 0.249936)
			(size 0.2286 0.2286)
			(layers "F.Cu" "F.Mask" "F.Paste")
			(net "P12V_OCP_V3_2")
		)
		(pad "C5" smd circle
			(at 0.499872 0.249936)
			(size 0.2286 0.2286)
			(layers "F.Cu" "F.Mask" "F.Paste")
			(net "P12V_AUX")
		)
		(pad "C6" smd circle
			(at 0.999998 0.249936)
			(size 0.2286 0.2286)
			(layers "F.Cu" "F.Mask" "F.Paste")
			(net "P12V_OCP_V3_2")
		)
		(pad "C7" smd circle
			(at 1.500124 0.249936)
			(size 0.2286 0.2286)
			(layers "F.Cu" "F.Mask" "F.Paste")
			(net "P12V_OCP_FAULT_2")
		)
		(pad "D1" smd circle
			(at -1.500124 0.750062)
			(size 0.2286 0.2286)
			(layers "F.Cu" "F.Mask" "F.Paste")
			(net "P12V_OCP_REG_2")
		)
		(pad "D2" smd circle
			(at -0.999998 0.750062)
			(size 0.2286 0.2286)
			(layers "F.Cu" "F.Mask" "F.Paste")
			(net "P12V_OCP_UV_2")
		)
		(pad "D3" smd circle
			(at -0.499872 0.750062)
			(size 0.2286 0.2286)
			(layers "F.Cu" "F.Mask" "F.Paste")
			(net "P12V_OCP_OV_2")
		)
		(pad "D4" smd circle
			(at 0 0.750062)
			(size 0.2286 0.2286)
			(layers "F.Cu" "F.Mask" "F.Paste")
			(net "P12V_OCP_V3_2")
		)
		(pad "D5" smd circle
			(at 0.499872 0.750062)
			(size 0.2286 0.2286)
			(layers "F.Cu" "F.Mask" "F.Paste")
			(net "P12V_AUX")
		)
		(pad "D6" smd circle
			(at 0.999998 0.750062)
			(size 0.2286 0.2286)
			(layers "F.Cu" "F.Mask" "F.Paste")
			(net "P12V_OCP_V3_2")
		)
		(pad "D7" smd circle
			(at 1.500124 0.750062)
			(size 0.2286 0.2286)
			(layers "F.Cu" "F.Mask" "F.Paste")
			(net "P12V_OCP_PWRGD_2")
		)
	)
	(footprint ""
		(layer "F.Cu")
		(at 439.262266 -122.089926 180)
		(property "Reference" "R2404"
			(at 0 0 180)
			(layer "F.SilkS")
			(hide yes)
			(effects
				(font
					(size 1.27 1.27)
				)
			)
		)
		(property "Value" ""
			(at 0 0 180)
			(layer "F.Fab")
			(effects
				(font
					(size 1.27 1.27)
				)
			)
		)
		(duplicate_pad_numbers_are_jumpers no)
		(fp_line
			(start 0.7874 0.4064)
			(end -0.7874 0.4064)
			(stroke
				(width 0.1524)
				(type default)
			)
			(layer "F.SilkS")
		)
		(fp_line
			(start 0.7874 -0.4064)
			(end 0.7874 0.4064)
			(stroke
				(width 0.1524)
				(type default)
			)
			(layer "F.SilkS")
		)
		(fp_line
			(start -0.7874 0.4064)
			(end -0.7874 -0.4064)
			(stroke
				(width 0.1524)
				(type default)
			)
			(layer "F.SilkS")
		)
		(fp_line
			(start -0.7874 -0.4064)
			(end 0.7874 -0.4064)
			(stroke
				(width 0.1524)
				(type default)
			)
			(layer "F.SilkS")
		)
		(fp_line
			(start 0.67945 0.3048)
			(end 0.120396 0.3048)
			(stroke
				(width 0.1)
				(type default)
			)
			(layer "F.Fab")
		)
		(fp_line
			(start 0.67945 -0.3048)
			(end 0.67945 0.3048)
			(stroke
				(width 0.1)
				(type default)
			)
			(layer "F.Fab")
		)
		(fp_line
			(start 0.12065 -0.2794)
			(end 0.12065 -0.3048)
			(stroke
				(width 0.1)
				(type default)
			)
			(layer "F.Fab")
		)
		(fp_line
			(start 0.12065 -0.3048)
			(end 0.67945 -0.3048)
			(stroke
				(width 0.1)
				(type default)
			)
			(layer "F.Fab")
		)
		(fp_line
			(start 0.120396 0.3048)
			(end 0.120396 0.2794)
			(stroke
				(width 0.1)
				(type default)
			)
			(layer "F.Fab")
		)
		(fp_line
			(start 0.120396 0.2794)
			(end -0.12065 0.2794)
			(stroke
				(width 0.1)
				(type default)
			)
			(layer "F.Fab")
		)
		(fp_line
			(start -0.12065 0.3048)
			(end -0.67945 0.3048)
			(stroke
				(width 0.1)
				(type default)
			)
			(layer "F.Fab")
		)
		(fp_line
			(start -0.12065 0.2794)
			(end -0.12065 0.3048)
			(stroke
				(width 0.1)
				(type default)
			)
			(layer "F.Fab")
		)
		(fp_line
			(start -0.12065 -0.2794)
			(end 0.12065 -0.2794)
			(stroke
				(width 0.1)
				(type default)
			)
			(layer "F.Fab")
		)
		(fp_line
			(start -0.12065 -0.305054)
			(end -0.12065 -0.2794)
			(stroke
				(width 0.1)
				(type default)
			)
			(layer "F.Fab")
		)
		(fp_line
			(start -0.67945 0.3048)
			(end -0.67945 -0.305054)
			(stroke
				(width 0.1)
				(type default)
			)
			(layer "F.Fab")
		)
		(fp_line
			(start -0.67945 -0.305054)
			(end -0.12065 -0.305054)
			(stroke
				(width 0.1)
				(type default)
			)
			(layer "F.Fab")
		)
		(pad "1" smd circle
			(at -0.40005 0 180)
			(size 0 0)
			(layers "F.Cu" "F.Mask" "F.Paste")
			(net "P3V3_AUX")
		)
		(pad "2" smd circle
			(at 0.40005 0 180)
			(size 0 0)
			(layers "F.Cu" "F.Mask" "F.Paste")
			(net "IRQ_PVCCD_CPU0_VRHOT_LVC3_N")
		)
	)
	(footprint ""
		(layer "F.Cu")
		(at 32.761428 -97.554034 180)
		(property "Reference" "C2044"
			(at 0 0 180)
			(layer "F.SilkS")
			(hide yes)
			(effects
				(font
					(size 1.27 1.27)
				)
			)
		)
		(property "Value" ""
			(at 0 0 180)
			(layer "F.Fab")
			(effects
				(font
					(size 1.27 1.27)
				)
			)
		)
		(duplicate_pad_numbers_are_jumpers no)
		(fp_line
			(start 0.7874 0.4064)
			(end -0.7874 0.4064)
			(stroke
				(width 0.1524)
				(type default)
			)
			(layer "F.SilkS")
		)
		(fp_line
			(start 0.7874 -0.4064)
			(end 0.7874 0.4064)
			(stroke
				(width 0.1524)
				(type default)
			)
			(layer "F.SilkS")
		)
		(fp_line
			(start -0.7874 0.4064)
			(end -0.7874 -0.4064)
			(stroke
				(width 0.1524)
				(type default)
			)
			(layer "F.SilkS")
		)
		(fp_line
			(start -0.7874 -0.4064)
			(end 0.7874 -0.4064)
			(stroke
				(width 0.1524)
				(type default)
			)
			(layer "F.SilkS")
		)
		(fp_line
			(start 0.67945 0.3048)
			(end 0.120396 0.3048)
			(stroke
				(width 0.1)
				(type default)
			)
			(layer "F.Fab")
		)
		(fp_line
			(start 0.67945 -0.3048)
			(end 0.67945 0.3048)
			(stroke
				(width 0.1)
				(type default)
			)
			(layer "F.Fab")
		)
		(fp_line
			(start 0.12065 -0.2794)
			(end 0.12065 -0.3048)
			(stroke
				(width 0.1)
				(type default)
			)
			(layer "F.Fab")
		)
		(fp_line
			(start 0.12065 -0.3048)
			(end 0.67945 -0.3048)
			(stroke
				(width 0.1)
				(type default)
			)
			(layer "F.Fab")
		)
		(fp_line
			(start 0.120396 0.3048)
			(end 0.120396 0.2794)
			(stroke
				(width 0.1)
				(type default)
			)
			(layer "F.Fab")
		)
		(fp_line
			(start 0.120396 0.2794)
			(end -0.12065 0.2794)
			(stroke
				(width 0.1)
				(type default)
			)
			(layer "F.Fab")
		)
		(fp_line
			(start -0.12065 0.3048)
			(end -0.67945 0.3048)
			(stroke
				(width 0.1)
				(type default)
			)
			(layer "F.Fab")
		)
		(fp_line
			(start -0.12065 0.2794)
			(end -0.12065 0.3048)
			(stroke
				(width 0.1)
				(type default)
			)
			(layer "F.Fab")
		)
		(fp_line
			(start -0.12065 -0.2794)
			(end 0.12065 -0.2794)
			(stroke
				(width 0.1)
				(type default)
			)
			(layer "F.Fab")
		)
		(fp_line
			(start -0.12065 -0.305054)
			(end -0.12065 -0.2794)
			(stroke
				(width 0.1)
				(type default)
			)
			(layer "F.Fab")
		)
		(fp_line
			(start -0.67945 0.3048)
			(end -0.67945 -0.305054)
			(stroke
				(width 0.1)
				(type default)
			)
			(layer "F.Fab")
		)
		(fp_line
			(start -0.67945 -0.305054)
			(end -0.12065 -0.305054)
			(stroke
				(width 0.1)
				(type default)
			)
			(layer "F.Fab")
		)
		(pad "1" smd circle
			(at -0.40005 0 180)
			(size 0 0)
			(layers "F.Cu" "F.Mask" "F.Paste")
			(net "P5V_ADC_MAM")
		)
		(pad "2" smd circle
			(at 0.40005 0 180)
			(size 0 0)
			(layers "F.Cu" "F.Mask" "F.Paste")
			(net "GND")
		)
	)
	(footprint ""
		(layer "F.Cu")
		(at 118.849902 -410.129228)
		(property "Reference" "C1773"
			(at 0 0 0)
			(layer "F.SilkS")
			(hide yes)
			(effects
				(font
					(size 1.27 1.27)
				)
			)
		)
		(property "Value" ""
			(at 0 0 0)
			(layer "F.Fab")
			(effects
				(font
					(size 1.27 1.27)
				)
			)
		)
		(duplicate_pad_numbers_are_jumpers no)
		(fp_line
			(start -0.7874 -0.4064)
			(end 0.7874 -0.4064)
			(stroke
				(width 0.1524)
				(type default)
			)
			(layer "F.SilkS")
		)
		(fp_line
			(start -0.7874 0.4064)
			(end -0.7874 -0.4064)
			(stroke
				(width 0.1524)
				(type default)
			)
			(layer "F.SilkS")
		)
		(fp_line
			(start 0.7874 -0.4064)
			(end 0.7874 0.4064)
			(stroke
				(width 0.1524)
				(type default)
			)
			(layer "F.SilkS")
		)
		(fp_line
			(start 0.7874 0.4064)
			(end -0.7874 0.4064)
			(stroke
				(width 0.1524)
				(type default)
			)
			(layer "F.SilkS")
		)
		(fp_line
			(start -0.67945 -0.305054)
			(end -0.12065 -0.305054)
			(stroke
				(width 0.1)
				(type default)
			)
			(layer "F.Fab")
		)
		(fp_line
			(start -0.67945 0.3048)
			(end -0.67945 -0.305054)
			(stroke
				(width 0.1)
				(type default)
			)
			(layer "F.Fab")
		)
		(fp_line
			(start -0.12065 -0.305054)
			(end -0.12065 -0.2794)
			(stroke
				(width 0.1)
				(type default)
			)
			(layer "F.Fab")
		)
		(fp_line
			(start -0.12065 -0.2794)
			(end 0.12065 -0.2794)
			(stroke
				(width 0.1)
				(type default)
			)
			(layer "F.Fab")
		)
		(fp_line
			(start -0.12065 0.2794)
			(end -0.12065 0.3048)
			(stroke
				(width 0.1)
				(type default)
			)
			(layer "F.Fab")
		)
		(fp_line
			(start -0.12065 0.3048)
			(end -0.67945 0.3048)
			(stroke
				(width 0.1)
				(type default)
			)
			(layer "F.Fab")
		)
		(fp_line
			(start 0.120396 0.2794)
			(end -0.12065 0.2794)
			(stroke
				(width 0.1)
				(type default)
			)
			(layer "F.Fab")
		)
		(fp_line
			(start 0.120396 0.3048)
			(end 0.120396 0.2794)
			(stroke
				(width 0.1)
				(type default)
			)
			(layer "F.Fab")
		)
		(fp_line
			(start 0.12065 -0.3048)
			(end 0.67945 -0.3048)
			(stroke
				(width 0.1)
				(type default)
			)
			(layer "F.Fab")
		)
		(fp_line
			(start 0.12065 -0.2794)
			(end 0.12065 -0.3048)
			(stroke
				(width 0.1)
				(type default)
			)
			(layer "F.Fab")
		)
		(fp_line
			(start 0.67945 -0.3048)
			(end 0.67945 0.3048)
			(stroke
				(width 0.1)
				(type default)
			)
			(layer "F.Fab")
		)
		(fp_line
			(start 0.67945 0.3048)
			(end 0.120396 0.3048)
			(stroke
				(width 0.1)
				(type default)
			)
			(layer "F.Fab")
		)
		(pad "1" smd circle
			(at -0.40005 0)
			(size 0 0)
			(layers "F.Cu" "F.Mask" "F.Paste")
			(net "BIC_MONITER_ISO")
		)
		(pad "2" smd circle
			(at 0.40005 0)
			(size 0 0)
			(layers "F.Cu" "F.Mask" "F.Paste")
			(net "GND")
		)
	)
	(footprint ""
		(layer "F.Cu")
		(at 365.844328 -336.192368 90)
		(property "Reference" "PC270"
			(at 0 0 90)
			(layer "F.SilkS")
			(hide yes)
			(effects
				(font
					(size 1.27 1.27)
				)
			)
		)
		(property "Value" ""
			(at 0 0 90)
			(layer "F.Fab")
			(effects
				(font
					(size 1.27 1.27)
				)
			)
		)
		(duplicate_pad_numbers_are_jumpers no)
		(fp_line
			(start 0.7874 -0.4064)
			(end 0.7874 0.4064)
			(stroke
				(width 0.1524)
				(type default)
			)
			(layer "F.SilkS")
		)
		(fp_line
			(start -0.7874 -0.4064)
			(end 0.7874 -0.4064)
			(stroke
				(width 0.1524)
				(type default)
			)
			(layer "F.SilkS")
		)
		(fp_line
			(start 0.7874 0.4064)
			(end -0.7874 0.4064)
			(stroke
				(width 0.1524)
				(type default)
			)
			(layer "F.SilkS")
		)
		(fp_line
			(start -0.7874 0.4064)
			(end -0.7874 -0.4064)
			(stroke
				(width 0.1524)
				(type default)
			)
			(layer "F.SilkS")
		)
		(fp_line
			(start -0.12065 -0.305054)
			(end -0.12065 -0.2794)
			(stroke
				(width 0.1)
				(type default)
			)
			(layer "F.Fab")
		)
		(fp_line
			(start -0.67945 -0.305054)
			(end -0.12065 -0.305054)
			(stroke
				(width 0.1)
				(type default)
			)
			(layer "F.Fab")
		)
		(fp_line
			(start 0.67945 -0.3048)
			(end 0.67945 0.3048)
			(stroke
				(width 0.1)
				(type default)
			)
			(layer "F.Fab")
		)
		(fp_line
			(start 0.12065 -0.3048)
			(end 0.67945 -0.3048)
			(stroke
				(width 0.1)
				(type default)
			)
			(layer "F.Fab")
		)
		(fp_line
			(start 0.12065 -0.2794)
			(end 0.12065 -0.3048)
			(stroke
				(width 0.1)
				(type default)
			)
			(layer "F.Fab")
		)
		(fp_line
			(start -0.12065 -0.2794)
			(end 0.12065 -0.2794)
			(stroke
				(width 0.1)
				(type default)
			)
			(layer "F.Fab")
		)
		(fp_line
			(start 0.120396 0.2794)
			(end -0.12065 0.2794)
			(stroke
				(width 0.1)
				(type default)
			)
			(layer "F.Fab")
		)
		(fp_line
			(start -0.12065 0.2794)
			(end -0.12065 0.3048)
			(stroke
				(width 0.1)
				(type default)
			)
			(layer "F.Fab")
		)
		(fp_line
			(start 0.67945 0.3048)
			(end 0.120396 0.3048)
			(stroke
				(width 0.1)
				(type default)
			)
			(layer "F.Fab")
		)
		(fp_line
			(start 0.120396 0.3048)
			(end 0.120396 0.2794)
			(stroke
				(width 0.1)
				(type default)
			)
			(layer "F.Fab")
		)
		(fp_line
			(start -0.12065 0.3048)
			(end -0.67945 0.3048)
			(stroke
				(width 0.1)
				(type default)
			)
			(layer "F.Fab")
		)
		(fp_line
			(start -0.67945 0.3048)
			(end -0.67945 -0.305054)
			(stroke
				(width 0.1)
				(type default)
			)
			(layer "F.Fab")
		)
		(pad "1" smd circle
			(at -0.40005 0 90)
			(size 0 0)
			(layers "F.Cu" "F.Mask" "F.Paste")
			(net "PVCCIN_CPU0_VDD4")
		)
		(pad "2" smd circle
			(at 0.40005 0 90)
			(size 0 0)
			(layers "F.Cu" "F.Mask" "F.Paste")
			(net "GND")
		)
	)
	(footprint ""
		(layer "F.Cu")
		(at 423.513504 -131.975352 -90)
		(property "Reference" "PC224"
			(at 0 0 270)
			(layer "F.SilkS")
			(hide yes)
			(effects
				(font
					(size 1.27 1.27)
				)
			)
		)
		(property "Value" ""
			(at 0 0 270)
			(layer "F.Fab")
			(effects
				(font
					(size 1.27 1.27)
				)
			)
		)
		(duplicate_pad_numbers_are_jumpers no)
		(fp_line
			(start -0.7874 0.4064)
			(end -0.7874 -0.4064)
			(stroke
				(width 0.1524)
				(type default)
			)
			(layer "F.SilkS")
		)
		(fp_line
			(start 0.7874 0.4064)
			(end -0.7874 0.4064)
			(stroke
				(width 0.1524)
				(type default)
			)
			(layer "F.SilkS")
		)
		(fp_line
			(start -0.7874 -0.4064)
			(end 0.7874 -0.4064)
			(stroke
				(width 0.1524)
				(type default)
			)
			(layer "F.SilkS")
		)
		(fp_line
			(start 0.7874 -0.4064)
			(end 0.7874 0.4064)
			(stroke
				(width 0.1524)
				(type default)
			)
			(layer "F.SilkS")
		)
		(fp_line
			(start -0.67945 0.3048)
			(end -0.67945 -0.305054)
			(stroke
				(width 0.1)
				(type default)
			)
			(layer "F.Fab")
		)
		(fp_line
			(start -0.12065 0.3048)
			(end -0.67945 0.3048)
			(stroke
				(width 0.1)
				(type default)
			)
			(layer "F.Fab")
		)
		(fp_line
			(start 0.120396 0.3048)
			(end 0.120396 0.2794)
			(stroke
				(width 0.1)
				(type default)
			)
			(layer "F.Fab")
		)
		(fp_line
			(start 0.67945 0.3048)
			(end 0.120396 0.3048)
			(stroke
				(width 0.1)
				(type default)
			)
			(layer "F.Fab")
		)
		(fp_line
			(start -0.12065 0.2794)
			(end -0.12065 0.3048)
			(stroke
				(width 0.1)
				(type default)
			)
			(layer "F.Fab")
		)
		(fp_line
			(start 0.120396 0.2794)
			(end -0.12065 0.2794)
			(stroke
				(width 0.1)
				(type default)
			)
			(layer "F.Fab")
		)
		(fp_line
			(start -0.12065 -0.2794)
			(end 0.12065 -0.2794)
			(stroke
				(width 0.1)
				(type default)
			)
			(layer "F.Fab")
		)
		(fp_line
			(start 0.12065 -0.2794)
			(end 0.12065 -0.3048)
			(stroke
				(width 0.1)
				(type default)
			)
			(layer "F.Fab")
		)
		(fp_line
			(start 0.12065 -0.3048)
			(end 0.67945 -0.3048)
			(stroke
				(width 0.1)
				(type default)
			)
			(layer "F.Fab")
		)
		(fp_line
			(start 0.67945 -0.3048)
			(end 0.67945 0.3048)
			(stroke
				(width 0.1)
				(type default)
			)
			(layer "F.Fab")
		)
		(fp_line
			(start -0.67945 -0.305054)
			(end -0.12065 -0.305054)
			(stroke
				(width 0.1)
				(type default)
			)
			(layer "F.Fab")
		)
		(fp_line
			(start -0.12065 -0.305054)
			(end -0.12065 -0.2794)
			(stroke
				(width 0.1)
				(type default)
			)
			(layer "F.Fab")
		)
		(pad "1" smd circle
			(at -0.40005 0 270)
			(size 0 0)
			(layers "F.Cu" "F.Mask" "F.Paste")
			(net "PVCCINFAON_CPU0_VREF")
		)
		(pad "2" smd circle
			(at 0.40005 0 270)
			(size 0 0)
			(layers "F.Cu" "F.Mask" "F.Paste")
			(net "GND")
		)
	)
	(footprint ""
		(layer "F.Cu")
		(at 193.4718 -130.419348 90)
		(property "Reference" "R4607"
			(at 0 0 90)
			(layer "F.SilkS")
			(hide yes)
			(effects
				(font
					(size 1.27 1.27)
				)
			)
		)
		(property "Value" ""
			(at 0 0 90)
			(layer "F.Fab")
			(effects
				(font
					(size 1.27 1.27)
				)
			)
		)
		(duplicate_pad_numbers_are_jumpers no)
		(fp_line
			(start 0.7874 -0.4064)
			(end 0.7874 0.4064)
			(stroke
				(width 0.1524)
				(type default)
			)
			(layer "F.SilkS")
		)
		(fp_line
			(start -0.7874 -0.4064)
			(end 0.7874 -0.4064)
			(stroke
				(width 0.1524)
				(type default)
			)
			(layer "F.SilkS")
		)
		(fp_line
			(start 0.7874 0.4064)
			(end -0.7874 0.4064)
			(stroke
				(width 0.1524)
				(type default)
			)
			(layer "F.SilkS")
		)
		(fp_line
			(start -0.7874 0.4064)
			(end -0.7874 -0.4064)
			(stroke
				(width 0.1524)
				(type default)
			)
			(layer "F.SilkS")
		)
		(fp_line
			(start -0.12065 -0.305054)
			(end -0.12065 -0.2794)
			(stroke
				(width 0.1)
				(type default)
			)
			(layer "F.Fab")
		)
		(fp_line
			(start -0.67945 -0.305054)
			(end -0.12065 -0.305054)
			(stroke
				(width 0.1)
				(type default)
			)
			(layer "F.Fab")
		)
		(fp_line
			(start 0.67945 -0.3048)
			(end 0.67945 0.3048)
			(stroke
				(width 0.1)
				(type default)
			)
			(layer "F.Fab")
		)
		(fp_line
			(start 0.12065 -0.3048)
			(end 0.67945 -0.3048)
			(stroke
				(width 0.1)
				(type default)
			)
			(layer "F.Fab")
		)
		(fp_line
			(start 0.12065 -0.2794)
			(end 0.12065 -0.3048)
			(stroke
				(width 0.1)
				(type default)
			)
			(layer "F.Fab")
		)
		(fp_line
			(start -0.12065 -0.2794)
			(end 0.12065 -0.2794)
			(stroke
				(width 0.1)
				(type default)
			)
			(layer "F.Fab")
		)
		(fp_line
			(start 0.120396 0.2794)
			(end -0.12065 0.2794)
			(stroke
				(width 0.1)
				(type default)
			)
			(layer "F.Fab")
		)
		(fp_line
			(start -0.12065 0.2794)
			(end -0.12065 0.3048)
			(stroke
				(width 0.1)
				(type default)
			)
			(layer "F.Fab")
		)
		(fp_line
			(start 0.67945 0.3048)
			(end 0.120396 0.3048)
			(stroke
				(width 0.1)
				(type default)
			)
			(layer "F.Fab")
		)
		(fp_line
			(start 0.120396 0.3048)
			(end 0.120396 0.2794)
			(stroke
				(width 0.1)
				(type default)
			)
			(layer "F.Fab")
		)
		(fp_line
			(start -0.12065 0.3048)
			(end -0.67945 0.3048)
			(stroke
				(width 0.1)
				(type default)
			)
			(layer "F.Fab")
		)
		(fp_line
			(start -0.67945 0.3048)
			(end -0.67945 -0.305054)
			(stroke
				(width 0.1)
				(type default)
			)
			(layer "F.Fab")
		)
		(pad "1" smd circle
			(at -0.40005 0 90)
			(size 0 0)
			(layers "F.Cu" "F.Mask" "F.Paste")
			(net "LED_HDD_ACTIVITY_B_N")
		)
		(pad "2" smd circle
			(at 0.40005 0 90)
			(size 0 0)
			(layers "F.Cu" "F.Mask" "F.Paste")
			(net "LED_HDD_ACTIVITY_B_PLD_N")
		)
	)
	(footprint ""
		(layer "F.Cu")
		(at 420.682166 -134.130034 180)
		(property "Reference" "PC225"
			(at 0 0 180)
			(layer "F.SilkS")
			(hide yes)
			(effects
				(font
					(size 1.27 1.27)
				)
			)
		)
		(property "Value" ""
			(at 0 0 180)
			(layer "F.Fab")
			(effects
				(font
					(size 1.27 1.27)
				)
			)
		)
		(duplicate_pad_numbers_are_jumpers no)
		(fp_line
			(start 0.7874 0.4064)
			(end -0.7874 0.4064)
			(stroke
				(width 0.1524)
				(type default)
			)
			(layer "F.SilkS")
		)
		(fp_line
			(start 0.7874 -0.4064)
			(end 0.7874 0.4064)
			(stroke
				(width 0.1524)
				(type default)
			)
			(layer "F.SilkS")
		)
		(fp_line
			(start -0.7874 0.4064)
			(end -0.7874 -0.4064)
			(stroke
				(width 0.1524)
				(type default)
			)
			(layer "F.SilkS")
		)
		(fp_line
			(start -0.7874 -0.4064)
			(end 0.7874 -0.4064)
			(stroke
				(width 0.1524)
				(type default)
			)
			(layer "F.SilkS")
		)
		(fp_line
			(start 0.67945 0.3048)
			(end 0.120396 0.3048)
			(stroke
				(width 0.1)
				(type default)
			)
			(layer "F.Fab")
		)
		(fp_line
			(start 0.67945 -0.3048)
			(end 0.67945 0.3048)
			(stroke
				(width 0.1)
				(type default)
			)
			(layer "F.Fab")
		)
		(fp_line
			(start 0.12065 -0.2794)
			(end 0.12065 -0.3048)
			(stroke
				(width 0.1)
				(type default)
			)
			(layer "F.Fab")
		)
		(fp_line
			(start 0.12065 -0.3048)
			(end 0.67945 -0.3048)
			(stroke
				(width 0.1)
				(type default)
			)
			(layer "F.Fab")
		)
		(fp_line
			(start 0.120396 0.3048)
			(end 0.120396 0.2794)
			(stroke
				(width 0.1)
				(type default)
			)
			(layer "F.Fab")
		)
		(fp_line
			(start 0.120396 0.2794)
			(end -0.12065 0.2794)
			(stroke
				(width 0.1)
				(type default)
			)
			(layer "F.Fab")
		)
		(fp_line
			(start -0.12065 0.3048)
			(end -0.67945 0.3048)
			(stroke
				(width 0.1)
				(type default)
			)
			(layer "F.Fab")
		)
		(fp_line
			(start -0.12065 0.2794)
			(end -0.12065 0.3048)
			(stroke
				(width 0.1)
				(type default)
			)
			(layer "F.Fab")
		)
		(fp_line
			(start -0.12065 -0.2794)
			(end 0.12065 -0.2794)
			(stroke
				(width 0.1)
				(type default)
			)
			(layer "F.Fab")
		)
		(fp_line
			(start -0.12065 -0.305054)
			(end -0.12065 -0.2794)
			(stroke
				(width 0.1)
				(type default)
			)
			(layer "F.Fab")
		)
		(fp_line
			(start -0.67945 0.3048)
			(end -0.67945 -0.305054)
			(stroke
				(width 0.1)
				(type default)
			)
			(layer "F.Fab")
		)
		(fp_line
			(start -0.67945 -0.305054)
			(end -0.12065 -0.305054)
			(stroke
				(width 0.1)
				(type default)
			)
			(layer "F.Fab")
		)
		(pad "1" smd circle
			(at -0.40005 0 180)
			(size 0 0)
			(layers "F.Cu" "F.Mask" "F.Paste")
			(net "PVCCINFAON_CPU0_VCC")
		)
		(pad "2" smd circle
			(at 0.40005 0 180)
			(size 0 0)
			(layers "F.Cu" "F.Mask" "F.Paste")
			(net "GND")
		)
	)
	(footprint ""
		(layer "F.Cu")
		(at 340.346284 -337.214718 -90)
		(property "Reference" "PC254_P0_6"
			(at 0 0 270)
			(layer "F.SilkS")
			(hide yes)
			(effects
				(font
					(size 1.27 1.27)
				)
			)
		)
		(property "Value" ""
			(at 0 0 270)
			(layer "F.Fab")
			(effects
				(font
					(size 1.27 1.27)
				)
			)
		)
		(duplicate_pad_numbers_are_jumpers no)
		(fp_line
			(start -0.7874 0.4064)
			(end -0.7874 -0.4064)
			(stroke
				(width 0.1524)
				(type default)
			)
			(layer "F.SilkS")
		)
		(fp_line
			(start 0.7874 0.4064)
			(end -0.7874 0.4064)
			(stroke
				(width 0.1524)
				(type default)
			)
			(layer "F.SilkS")
		)
		(fp_line
			(start -0.7874 -0.4064)
			(end 0.7874 -0.4064)
			(stroke
				(width 0.1524)
				(type default)
			)
			(layer "F.SilkS")
		)
		(fp_line
			(start 0.7874 -0.4064)
			(end 0.7874 0.4064)
			(stroke
				(width 0.1524)
				(type default)
			)
			(layer "F.SilkS")
		)
		(fp_line
			(start -0.67945 0.3048)
			(end -0.67945 -0.305054)
			(stroke
				(width 0.1)
				(type default)
			)
			(layer "F.Fab")
		)
		(fp_line
			(start -0.12065 0.3048)
			(end -0.67945 0.3048)
			(stroke
				(width 0.1)
				(type default)
			)
			(layer "F.Fab")
		)
		(fp_line
			(start 0.120396 0.3048)
			(end 0.120396 0.2794)
			(stroke
				(width 0.1)
				(type default)
			)
			(layer "F.Fab")
		)
		(fp_line
			(start 0.67945 0.3048)
			(end 0.120396 0.3048)
			(stroke
				(width 0.1)
				(type default)
			)
			(layer "F.Fab")
		)
		(fp_line
			(start -0.12065 0.2794)
			(end -0.12065 0.3048)
			(stroke
				(width 0.1)
				(type default)
			)
			(layer "F.Fab")
		)
		(fp_line
			(start 0.120396 0.2794)
			(end -0.12065 0.2794)
			(stroke
				(width 0.1)
				(type default)
			)
			(layer "F.Fab")
		)
		(fp_line
			(start -0.12065 -0.2794)
			(end 0.12065 -0.2794)
			(stroke
				(width 0.1)
				(type default)
			)
			(layer "F.Fab")
		)
		(fp_line
			(start 0.12065 -0.2794)
			(end 0.12065 -0.3048)
			(stroke
				(width 0.1)
				(type default)
			)
			(layer "F.Fab")
		)
		(fp_line
			(start 0.12065 -0.3048)
			(end 0.67945 -0.3048)
			(stroke
				(width 0.1)
				(type default)
			)
			(layer "F.Fab")
		)
		(fp_line
			(start 0.67945 -0.3048)
			(end 0.67945 0.3048)
			(stroke
				(width 0.1)
				(type default)
			)
			(layer "F.Fab")
		)
		(fp_line
			(start -0.67945 -0.305054)
			(end -0.12065 -0.305054)
			(stroke
				(width 0.1)
				(type default)
			)
			(layer "F.Fab")
		)
		(fp_line
			(start -0.12065 -0.305054)
			(end -0.12065 -0.2794)
			(stroke
				(width 0.1)
				(type default)
			)
			(layer "F.Fab")
		)
		(pad "1" smd circle
			(at -0.40005 0 270)
			(size 0 0)
			(layers "F.Cu" "F.Mask" "F.Paste")
			(net "SW_P12V_PVCCIN_CPU0_FLT")
		)
		(pad "2" smd circle
			(at 0.40005 0 270)
			(size 0 0)
			(layers "F.Cu" "F.Mask" "F.Paste")
			(net "GND")
		)
	)
	(footprint ""
		(layer "F.Cu")
		(at 73.94448 -160.212278 180)
		(property "Reference" "PR558"
			(at 0 0 180)
			(layer "F.SilkS")
			(hide yes)
			(effects
				(font
					(size 1.27 1.27)
				)
			)
		)
		(property "Value" ""
			(at 0 0 180)
			(layer "F.Fab")
			(effects
				(font
					(size 1.27 1.27)
				)
			)
		)
		(duplicate_pad_numbers_are_jumpers no)
		(fp_line
			(start 0.7874 0.4064)
			(end -0.7874 0.4064)
			(stroke
				(width 0.1524)
				(type default)
			)
			(layer "F.SilkS")
		)
		(fp_line
			(start 0.7874 -0.4064)
			(end 0.7874 0.4064)
			(stroke
				(width 0.1524)
				(type default)
			)
			(layer "F.SilkS")
		)
		(fp_line
			(start -0.7874 0.4064)
			(end -0.7874 -0.4064)
			(stroke
				(width 0.1524)
				(type default)
			)
			(layer "F.SilkS")
		)
		(fp_line
			(start -0.7874 -0.4064)
			(end 0.7874 -0.4064)
			(stroke
				(width 0.1524)
				(type default)
			)
			(layer "F.SilkS")
		)
		(fp_line
			(start 0.67945 0.3048)
			(end 0.120396 0.3048)
			(stroke
				(width 0.1)
				(type default)
			)
			(layer "F.Fab")
		)
		(fp_line
			(start 0.67945 -0.3048)
			(end 0.67945 0.3048)
			(stroke
				(width 0.1)
				(type default)
			)
			(layer "F.Fab")
		)
		(fp_line
			(start 0.12065 -0.2794)
			(end 0.12065 -0.3048)
			(stroke
				(width 0.1)
				(type default)
			)
			(layer "F.Fab")
		)
		(fp_line
			(start 0.12065 -0.3048)
			(end 0.67945 -0.3048)
			(stroke
				(width 0.1)
				(type default)
			)
			(layer "F.Fab")
		)
		(fp_line
			(start 0.120396 0.3048)
			(end 0.120396 0.2794)
			(stroke
				(width 0.1)
				(type default)
			)
			(layer "F.Fab")
		)
		(fp_line
			(start 0.120396 0.2794)
			(end -0.12065 0.2794)
			(stroke
				(width 0.1)
				(type default)
			)
			(layer "F.Fab")
		)
		(fp_line
			(start -0.12065 0.3048)
			(end -0.67945 0.3048)
			(stroke
				(width 0.1)
				(type default)
			)
			(layer "F.Fab")
		)
		(fp_line
			(start -0.12065 0.2794)
			(end -0.12065 0.3048)
			(stroke
				(width 0.1)
				(type default)
			)
			(layer "F.Fab")
		)
		(fp_line
			(start -0.12065 -0.2794)
			(end 0.12065 -0.2794)
			(stroke
				(width 0.1)
				(type default)
			)
			(layer "F.Fab")
		)
		(fp_line
			(start -0.12065 -0.305054)
			(end -0.12065 -0.2794)
			(stroke
				(width 0.1)
				(type default)
			)
			(layer "F.Fab")
		)
		(fp_line
			(start -0.67945 0.3048)
			(end -0.67945 -0.305054)
			(stroke
				(width 0.1)
				(type default)
			)
			(layer "F.Fab")
		)
		(fp_line
			(start -0.67945 -0.305054)
			(end -0.12065 -0.305054)
			(stroke
				(width 0.1)
				(type default)
			)
			(layer "F.Fab")
		)
		(pad "1" smd circle
			(at -0.40005 0 180)
			(size 0 0)
			(layers "F.Cu" "F.Mask" "F.Paste")
			(net "VSENSE_PVCCD_HV_CPU1_DN")
		)
		(pad "2" smd circle
			(at 0.40005 0 180)
			(size 0 0)
			(layers "F.Cu" "F.Mask" "F.Paste")
			(net "GND")
		)
	)
	(footprint ""
		(layer "F.Cu")
		(at 479.84537 -121.640092 -90)
		(property "Reference" "X36"
			(at 2.387092 -2.4003 90)
			(unlocked yes)
			(layer "F.SilkS")
			(effects
				(font
					(size 0.7874 0.5842)
					(thickness 0.1524)
				)
				(justify left)
			)
		)
		(property "Value" ""
			(at 0 0 270)
			(layer "F.Fab")
			(effects
				(font
					(size 1.27 1.27)
				)
			)
		)
		(property "Device Type" "TP_TDR_4P_FTS_TH-TP_TDR_4P_DIPA"
			(at 1.30175 1.27 0)
			(unlocked yes)
			(layer "F.Fab")
			(hide yes)
			(effects
				(font
					(size 0.635 0.4064)
					(thickness 0.1524)
				)
			)
		)
		(property "User Part Number" "N_A"
			(at 1.30175 1.27 0)
			(unlocked yes)
			(layer "Cmts.User")
			(hide yes)
			(effects
				(font
					(size 0.635 0.4064)
					(thickness 0.1524)
				)
			)
		)
		(duplicate_pad_numbers_are_jumpers no)
		(fp_line
			(start 0 3.81)
			(end 2.54 3.81)
			(stroke
				(width 0.1524)
				(type default)
			)
			(layer "F.SilkS")
		)
		(fp_line
			(start 2.54 3.81)
			(end 2.54 3.6703)
			(stroke
				(width 0.1524)
				(type default)
			)
			(layer "F.SilkS")
		)
		(fp_line
			(start 0 3.175)
			(end 0 3.81)
			(stroke
				(width 0.1524)
				(type default)
			)
			(layer "F.SilkS")
		)
		(fp_line
			(start 2.54 1.4097)
			(end 2.54 1.1303)
			(stroke
				(width 0.1524)
				(type default)
			)
			(layer "F.SilkS")
		)
		(fp_line
			(start 0 0.635)
			(end 0 1.905)
			(stroke
				(width 0.1524)
				(type default)
			)
			(layer "F.SilkS")
		)
		(fp_line
			(start 2.54 -1.1303)
			(end 2.54 -1.27)
			(stroke
				(width 0.1524)
				(type default)
			)
			(layer "F.SilkS")
		)
		(fp_line
			(start 0 -1.27)
			(end 0 -0.635)
			(stroke
				(width 0.1524)
				(type default)
			)
			(layer "F.SilkS")
		)
		(fp_line
			(start 2.54 -1.27)
			(end 0 -1.27)
			(stroke
				(width 0.1524)
				(type default)
			)
			(layer "F.SilkS")
		)
		(fp_poly
			(pts
				(xy -0.761746 0) (xy -2.285746 -0.762) (xy -2.285746 0.762)
			)
			(stroke
				(width 0)
				(type default)
			)
			(fill yes)
			(layer "F.SilkS")
		)
		(fp_line
			(start 0 3.81)
			(end 2.54 3.81)
			(stroke
				(width 0.1)
				(type default)
			)
			(layer "F.Fab")
		)
		(fp_line
			(start 2.54 3.81)
			(end 2.54 -1.27)
			(stroke
				(width 0.1)
				(type default)
			)
			(layer "F.Fab")
		)
		(fp_line
			(start 0 -1.27)
			(end 0 3.81)
			(stroke
				(width 0.1)
				(type default)
			)
			(layer "F.Fab")
		)
		(fp_line
			(start 2.54 -1.27)
			(end 0 -1.27)
			(stroke
				(width 0.1)
				(type default)
			)
			(layer "F.Fab")
		)
		(fp_poly
			(pts
				(xy -0.761746 0) (xy -2.285746 -0.762) (xy -2.285746 0.762)
			)
			(stroke
				(width 0)
				(type default)
			)
			(fill yes)
			(layer "F.Fab")
		)
		(pad "1" thru_hole circle
			(at 0 0 270)
			(size 1.0033 1.0033)
			(drill 0.249936)
			(layers "*.Cu" "*.Mask")
			(remove_unused_layers no)
			(net "TDR_DIFF_85_NECK_IN3_DP")
			(clearance 0.10795)
			(thermal_gap 0.10795)
			(padstack
				(mode front_inner_back)
				(layer "Inner"
					(shape circle)
					(size 0.8001 0.8001)
					(clearance 0.1524)
				)
				(layer "B.Cu"
					(shape circle)
					(size 1.0033 1.0033)
					(clearance 0.10795)
				)
			)
		)
		(pad "2" thru_hole circle
			(at 2.54 0 270)
			(size 1.9939 1.9939)
			(drill 0.249936)
			(layers "*.Cu" "*.Mask")
			(remove_unused_layers no)
			(net "T1_GND")
			(clearance 0.10795)
			(thermal_gap 0.10795)
			(padstack
				(mode front_inner_back)
				(layer "Inner"
					(shape circle)
					(size 0.8001 0.8001)
					(clearance 0.1524)
				)
				(layer "B.Cu"
					(shape circle)
					(size 1.9939 1.9939)
					(clearance 0.10795)
				)
			)
		)
		(pad "3" thru_hole circle
			(at 2.54 2.54 270)
			(size 1.9939 1.9939)
			(drill 0.249936)
			(layers "*.Cu" "*.Mask")
			(remove_unused_layers no)
			(net "T1_GND")
			(clearance 0.10795)
			(thermal_gap 0.10795)
			(padstack
				(mode front_inner_back)
				(layer "Inner"
					(shape circle)
					(size 0.8001 0.8001)
					(clearance 0.1524)
				)
				(layer "B.Cu"
					(shape circle)
					(size 1.9939 1.9939)
					(clearance 0.10795)
				)
			)
		)
		(pad "4" thru_hole circle
			(at 0 2.54 270)
			(size 1.0033 1.0033)
			(drill 0.249936)
			(layers "*.Cu" "*.Mask")
			(remove_unused_layers no)
			(net "TDR_DIFF_85_NECK_IN3_DN")
			(clearance 0.10795)
			(thermal_gap 0.10795)
			(padstack
				(mode front_inner_back)
				(layer "Inner"
					(shape circle)
					(size 0.8001 0.8001)
					(clearance 0.1524)
				)
				(layer "B.Cu"
					(shape circle)
					(size 1.0033 1.0033)
					(clearance 0.10795)
				)
			)
		)
	)
	(footprint ""
		(layer "F.Cu")
		(at 174.1424 -93.538548 90)
		(property "Reference" "R4597"
			(at 0 0 90)
			(layer "F.SilkS")
			(hide yes)
			(effects
				(font
					(size 1.27 1.27)
				)
			)
		)
		(property "Value" ""
			(at 0 0 90)
			(layer "F.Fab")
			(effects
				(font
					(size 1.27 1.27)
				)
			)
		)
		(duplicate_pad_numbers_are_jumpers no)
		(fp_line
			(start 0.7874 -0.4064)
			(end 0.7874 0.4064)
			(stroke
				(width 0.1524)
				(type default)
			)
			(layer "F.SilkS")
		)
		(fp_line
			(start -0.7874 -0.4064)
			(end 0.7874 -0.4064)
			(stroke
				(width 0.1524)
				(type default)
			)
			(layer "F.SilkS")
		)
		(fp_line
			(start 0.7874 0.4064)
			(end -0.7874 0.4064)
			(stroke
				(width 0.1524)
				(type default)
			)
			(layer "F.SilkS")
		)
		(fp_line
			(start -0.7874 0.4064)
			(end -0.7874 -0.4064)
			(stroke
				(width 0.1524)
				(type default)
			)
			(layer "F.SilkS")
		)
		(fp_line
			(start -0.12065 -0.305054)
			(end -0.12065 -0.2794)
			(stroke
				(width 0.1)
				(type default)
			)
			(layer "F.Fab")
		)
		(fp_line
			(start -0.67945 -0.305054)
			(end -0.12065 -0.305054)
			(stroke
				(width 0.1)
				(type default)
			)
			(layer "F.Fab")
		)
		(fp_line
			(start 0.67945 -0.3048)
			(end 0.67945 0.3048)
			(stroke
				(width 0.1)
				(type default)
			)
			(layer "F.Fab")
		)
		(fp_line
			(start 0.12065 -0.3048)
			(end 0.67945 -0.3048)
			(stroke
				(width 0.1)
				(type default)
			)
			(layer "F.Fab")
		)
		(fp_line
			(start 0.12065 -0.2794)
			(end 0.12065 -0.3048)
			(stroke
				(width 0.1)
				(type default)
			)
			(layer "F.Fab")
		)
		(fp_line
			(start -0.12065 -0.2794)
			(end 0.12065 -0.2794)
			(stroke
				(width 0.1)
				(type default)
			)
			(layer "F.Fab")
		)
		(fp_line
			(start 0.120396 0.2794)
			(end -0.12065 0.2794)
			(stroke
				(width 0.1)
				(type default)
			)
			(layer "F.Fab")
		)
		(fp_line
			(start -0.12065 0.2794)
			(end -0.12065 0.3048)
			(stroke
				(width 0.1)
				(type default)
			)
			(layer "F.Fab")
		)
		(fp_line
			(start 0.67945 0.3048)
			(end 0.120396 0.3048)
			(stroke
				(width 0.1)
				(type default)
			)
			(layer "F.Fab")
		)
		(fp_line
			(start 0.120396 0.3048)
			(end 0.120396 0.2794)
			(stroke
				(width 0.1)
				(type default)
			)
			(layer "F.Fab")
		)
		(fp_line
			(start -0.12065 0.3048)
			(end -0.67945 0.3048)
			(stroke
				(width 0.1)
				(type default)
			)
			(layer "F.Fab")
		)
		(fp_line
			(start -0.67945 0.3048)
			(end -0.67945 -0.305054)
			(stroke
				(width 0.1)
				(type default)
			)
			(layer "F.Fab")
		)
		(pad "1" smd rect
			(at -0.40005 0 270)
			(size 0.4572 0.508)
			(layers "F.Cu" "F.Mask" "F.Paste")
			(net "P3V3_AUX")
		)
		(pad "2" smd rect
			(at 0.40005 0 270)
			(size 0.4572 0.508)
			(layers "F.Cu" "F.Mask" "F.Paste")
			(net "FM_BOARD_BMC_SKU_ID2")
		)
	)
	(footprint ""
		(layer "F.Cu")
		(at 215.98128 -41.341548)
		(property "Reference" "C1997"
			(at 0 0 0)
			(layer "F.SilkS")
			(hide yes)
			(effects
				(font
					(size 1.27 1.27)
				)
			)
		)
		(property "Value" ""
			(at 0 0 0)
			(layer "F.Fab")
			(effects
				(font
					(size 1.27 1.27)
				)
			)
		)
		(duplicate_pad_numbers_are_jumpers no)
		(fp_line
			(start -0.7874 -0.4064)
			(end 0.7874 -0.4064)
			(stroke
				(width 0.1524)
				(type default)
			)
			(layer "F.SilkS")
		)
		(fp_line
			(start -0.7874 0.4064)
			(end -0.7874 -0.4064)
			(stroke
				(width 0.1524)
				(type default)
			)
			(layer "F.SilkS")
		)
		(fp_line
			(start 0.7874 -0.4064)
			(end 0.7874 0.4064)
			(stroke
				(width 0.1524)
				(type default)
			)
			(layer "F.SilkS")
		)
		(fp_line
			(start 0.7874 0.4064)
			(end -0.7874 0.4064)
			(stroke
				(width 0.1524)
				(type default)
			)
			(layer "F.SilkS")
		)
		(fp_line
			(start -0.67945 -0.305054)
			(end -0.12065 -0.305054)
			(stroke
				(width 0.1)
				(type default)
			)
			(layer "F.Fab")
		)
		(fp_line
			(start -0.67945 0.3048)
			(end -0.67945 -0.305054)
			(stroke
				(width 0.1)
				(type default)
			)
			(layer "F.Fab")
		)
		(fp_line
			(start -0.12065 -0.305054)
			(end -0.12065 -0.2794)
			(stroke
				(width 0.1)
				(type default)
			)
			(layer "F.Fab")
		)
		(fp_line
			(start -0.12065 -0.2794)
			(end 0.12065 -0.2794)
			(stroke
				(width 0.1)
				(type default)
			)
			(layer "F.Fab")
		)
		(fp_line
			(start -0.12065 0.2794)
			(end -0.12065 0.3048)
			(stroke
				(width 0.1)
				(type default)
			)
			(layer "F.Fab")
		)
		(fp_line
			(start -0.12065 0.3048)
			(end -0.67945 0.3048)
			(stroke
				(width 0.1)
				(type default)
			)
			(layer "F.Fab")
		)
		(fp_line
			(start 0.120396 0.2794)
			(end -0.12065 0.2794)
			(stroke
				(width 0.1)
				(type default)
			)
			(layer "F.Fab")
		)
		(fp_line
			(start 0.120396 0.3048)
			(end 0.120396 0.2794)
			(stroke
				(width 0.1)
				(type default)
			)
			(layer "F.Fab")
		)
		(fp_line
			(start 0.12065 -0.3048)
			(end 0.67945 -0.3048)
			(stroke
				(width 0.1)
				(type default)
			)
			(layer "F.Fab")
		)
		(fp_line
			(start 0.12065 -0.2794)
			(end 0.12065 -0.3048)
			(stroke
				(width 0.1)
				(type default)
			)
			(layer "F.Fab")
		)
		(fp_line
			(start 0.67945 -0.3048)
			(end 0.67945 0.3048)
			(stroke
				(width 0.1)
				(type default)
			)
			(layer "F.Fab")
		)
		(fp_line
			(start 0.67945 0.3048)
			(end 0.120396 0.3048)
			(stroke
				(width 0.1)
				(type default)
			)
			(layer "F.Fab")
		)
		(pad "1" smd circle
			(at -0.40005 0)
			(size 0 0)
			(layers "F.Cu" "F.Mask" "F.Paste")
			(net "P3V3_AUX")
		)
		(pad "2" smd circle
			(at 0.40005 0)
			(size 0 0)
			(layers "F.Cu" "F.Mask" "F.Paste")
			(net "GND")
		)
	)
	(footprint ""
		(layer "F.Cu")
		(at 387.262116 -14.25321 90)
		(property "Reference" "R445"
			(at 0 0 90)
			(layer "F.SilkS")
			(hide yes)
			(effects
				(font
					(size 1.27 1.27)
				)
			)
		)
		(property "Value" ""
			(at 0 0 90)
			(layer "F.Fab")
			(effects
				(font
					(size 1.27 1.27)
				)
			)
		)
		(duplicate_pad_numbers_are_jumpers no)
		(fp_line
			(start 0.7874 -0.4064)
			(end 0.7874 0.4064)
			(stroke
				(width 0.1524)
				(type default)
			)
			(layer "F.SilkS")
		)
		(fp_line
			(start -0.7874 -0.4064)
			(end 0.7874 -0.4064)
			(stroke
				(width 0.1524)
				(type default)
			)
			(layer "F.SilkS")
		)
		(fp_line
			(start 0.7874 0.4064)
			(end -0.7874 0.4064)
			(stroke
				(width 0.1524)
				(type default)
			)
			(layer "F.SilkS")
		)
		(fp_line
			(start -0.7874 0.4064)
			(end -0.7874 -0.4064)
			(stroke
				(width 0.1524)
				(type default)
			)
			(layer "F.SilkS")
		)
		(fp_line
			(start -0.12065 -0.305054)
			(end -0.12065 -0.2794)
			(stroke
				(width 0.1)
				(type default)
			)
			(layer "F.Fab")
		)
		(fp_line
			(start -0.67945 -0.305054)
			(end -0.12065 -0.305054)
			(stroke
				(width 0.1)
				(type default)
			)
			(layer "F.Fab")
		)
		(fp_line
			(start 0.67945 -0.3048)
			(end 0.67945 0.3048)
			(stroke
				(width 0.1)
				(type default)
			)
			(layer "F.Fab")
		)
		(fp_line
			(start 0.12065 -0.3048)
			(end 0.67945 -0.3048)
			(stroke
				(width 0.1)
				(type default)
			)
			(layer "F.Fab")
		)
		(fp_line
			(start 0.12065 -0.2794)
			(end 0.12065 -0.3048)
			(stroke
				(width 0.1)
				(type default)
			)
			(layer "F.Fab")
		)
		(fp_line
			(start -0.12065 -0.2794)
			(end 0.12065 -0.2794)
			(stroke
				(width 0.1)
				(type default)
			)
			(layer "F.Fab")
		)
		(fp_line
			(start 0.120396 0.2794)
			(end -0.12065 0.2794)
			(stroke
				(width 0.1)
				(type default)
			)
			(layer "F.Fab")
		)
		(fp_line
			(start -0.12065 0.2794)
			(end -0.12065 0.3048)
			(stroke
				(width 0.1)
				(type default)
			)
			(layer "F.Fab")
		)
		(fp_line
			(start 0.67945 0.3048)
			(end 0.120396 0.3048)
			(stroke
				(width 0.1)
				(type default)
			)
			(layer "F.Fab")
		)
		(fp_line
			(start 0.120396 0.3048)
			(end 0.120396 0.2794)
			(stroke
				(width 0.1)
				(type default)
			)
			(layer "F.Fab")
		)
		(fp_line
			(start -0.12065 0.3048)
			(end -0.67945 0.3048)
			(stroke
				(width 0.1)
				(type default)
			)
			(layer "F.Fab")
		)
		(fp_line
			(start -0.67945 0.3048)
			(end -0.67945 -0.305054)
			(stroke
				(width 0.1)
				(type default)
			)
			(layer "F.Fab")
		)
		(pad "1" smd circle
			(at -0.40005 0 90)
			(size 0 0)
			(layers "F.Cu" "F.Mask" "F.Paste")
			(net "OCP_SFF_USB2_3_DP")
		)
		(pad "2" smd circle
			(at 0.40005 0 90)
			(size 0 0)
			(layers "F.Cu" "F.Mask" "F.Paste")
			(net "USB2_3_DP")
		)
	)
	(footprint ""
		(layer "F.Cu")
		(at 424.223942 -396.635478)
		(property "Reference" "R3464"
			(at 0 0 0)
			(layer "F.SilkS")
			(hide yes)
			(effects
				(font
					(size 1.27 1.27)
				)
			)
		)
		(property "Value" ""
			(at 0 0 0)
			(layer "F.Fab")
			(effects
				(font
					(size 1.27 1.27)
				)
			)
		)
		(duplicate_pad_numbers_are_jumpers no)
		(fp_line
			(start -0.7874 -0.4064)
			(end 0.7874 -0.4064)
			(stroke
				(width 0.1524)
				(type default)
			)
			(layer "F.SilkS")
		)
		(fp_line
			(start -0.7874 0.4064)
			(end -0.7874 -0.4064)
			(stroke
				(width 0.1524)
				(type default)
			)
			(layer "F.SilkS")
		)
		(fp_line
			(start 0.7874 -0.4064)
			(end 0.7874 0.4064)
			(stroke
				(width 0.1524)
				(type default)
			)
			(layer "F.SilkS")
		)
		(fp_line
			(start 0.7874 0.4064)
			(end -0.7874 0.4064)
			(stroke
				(width 0.1524)
				(type default)
			)
			(layer "F.SilkS")
		)
		(fp_line
			(start -0.67945 -0.305054)
			(end -0.12065 -0.305054)
			(stroke
				(width 0.1)
				(type default)
			)
			(layer "F.Fab")
		)
		(fp_line
			(start -0.67945 0.3048)
			(end -0.67945 -0.305054)
			(stroke
				(width 0.1)
				(type default)
			)
			(layer "F.Fab")
		)
		(fp_line
			(start -0.12065 -0.305054)
			(end -0.12065 -0.2794)
			(stroke
				(width 0.1)
				(type default)
			)
			(layer "F.Fab")
		)
		(fp_line
			(start -0.12065 -0.2794)
			(end 0.12065 -0.2794)
			(stroke
				(width 0.1)
				(type default)
			)
			(layer "F.Fab")
		)
		(fp_line
			(start -0.12065 0.2794)
			(end -0.12065 0.3048)
			(stroke
				(width 0.1)
				(type default)
			)
			(layer "F.Fab")
		)
		(fp_line
			(start -0.12065 0.3048)
			(end -0.67945 0.3048)
			(stroke
				(width 0.1)
				(type default)
			)
			(layer "F.Fab")
		)
		(fp_line
			(start 0.120396 0.2794)
			(end -0.12065 0.2794)
			(stroke
				(width 0.1)
				(type default)
			)
			(layer "F.Fab")
		)
		(fp_line
			(start 0.120396 0.3048)
			(end 0.120396 0.2794)
			(stroke
				(width 0.1)
				(type default)
			)
			(layer "F.Fab")
		)
		(fp_line
			(start 0.12065 -0.3048)
			(end 0.67945 -0.3048)
			(stroke
				(width 0.1)
				(type default)
			)
			(layer "F.Fab")
		)
		(fp_line
			(start 0.12065 -0.2794)
			(end 0.12065 -0.3048)
			(stroke
				(width 0.1)
				(type default)
			)
			(layer "F.Fab")
		)
		(fp_line
			(start 0.67945 -0.3048)
			(end 0.67945 0.3048)
			(stroke
				(width 0.1)
				(type default)
			)
			(layer "F.Fab")
		)
		(fp_line
			(start 0.67945 0.3048)
			(end 0.120396 0.3048)
			(stroke
				(width 0.1)
				(type default)
			)
			(layer "F.Fab")
		)
		(pad "1" smd circle
			(at -0.40005 0)
			(size 0 0)
			(layers "F.Cu" "F.Mask" "F.Paste")
			(net "P3V3_AUX")
		)
		(pad "2" smd circle
			(at 0.40005 0)
			(size 0 0)
			(layers "F.Cu" "F.Mask" "F.Paste")
			(net "GPU_FPGA_OVERT_N")
		)
	)
	(footprint ""
		(layer "F.Cu")
		(at 147.447 -130.647948)
		(property "Reference" "R4604"
			(at 0 0 0)
			(layer "F.SilkS")
			(hide yes)
			(effects
				(font
					(size 1.27 1.27)
				)
			)
		)
		(property "Value" ""
			(at 0 0 0)
			(layer "F.Fab")
			(effects
				(font
					(size 1.27 1.27)
				)
			)
		)
		(duplicate_pad_numbers_are_jumpers no)
		(fp_line
			(start -0.7874 -0.4064)
			(end 0.7874 -0.4064)
			(stroke
				(width 0.1524)
				(type default)
			)
			(layer "F.SilkS")
		)
		(fp_line
			(start -0.7874 0.4064)
			(end -0.7874 -0.4064)
			(stroke
				(width 0.1524)
				(type default)
			)
			(layer "F.SilkS")
		)
		(fp_line
			(start 0.7874 -0.4064)
			(end 0.7874 0.4064)
			(stroke
				(width 0.1524)
				(type default)
			)
			(layer "F.SilkS")
		)
		(fp_line
			(start 0.7874 0.4064)
			(end -0.7874 0.4064)
			(stroke
				(width 0.1524)
				(type default)
			)
			(layer "F.SilkS")
		)
		(fp_line
			(start -0.67945 -0.305054)
			(end -0.12065 -0.305054)
			(stroke
				(width 0.1)
				(type default)
			)
			(layer "F.Fab")
		)
		(fp_line
			(start -0.67945 0.3048)
			(end -0.67945 -0.305054)
			(stroke
				(width 0.1)
				(type default)
			)
			(layer "F.Fab")
		)
		(fp_line
			(start -0.12065 -0.305054)
			(end -0.12065 -0.2794)
			(stroke
				(width 0.1)
				(type default)
			)
			(layer "F.Fab")
		)
		(fp_line
			(start -0.12065 -0.2794)
			(end 0.12065 -0.2794)
			(stroke
				(width 0.1)
				(type default)
			)
			(layer "F.Fab")
		)
		(fp_line
			(start -0.12065 0.2794)
			(end -0.12065 0.3048)
			(stroke
				(width 0.1)
				(type default)
			)
			(layer "F.Fab")
		)
		(fp_line
			(start -0.12065 0.3048)
			(end -0.67945 0.3048)
			(stroke
				(width 0.1)
				(type default)
			)
			(layer "F.Fab")
		)
		(fp_line
			(start 0.120396 0.2794)
			(end -0.12065 0.2794)
			(stroke
				(width 0.1)
				(type default)
			)
			(layer "F.Fab")
		)
		(fp_line
			(start 0.120396 0.3048)
			(end 0.120396 0.2794)
			(stroke
				(width 0.1)
				(type default)
			)
			(layer "F.Fab")
		)
		(fp_line
			(start 0.12065 -0.3048)
			(end 0.67945 -0.3048)
			(stroke
				(width 0.1)
				(type default)
			)
			(layer "F.Fab")
		)
		(fp_line
			(start 0.12065 -0.2794)
			(end 0.12065 -0.3048)
			(stroke
				(width 0.1)
				(type default)
			)
			(layer "F.Fab")
		)
		(fp_line
			(start 0.67945 -0.3048)
			(end 0.67945 0.3048)
			(stroke
				(width 0.1)
				(type default)
			)
			(layer "F.Fab")
		)
		(fp_line
			(start 0.67945 0.3048)
			(end 0.120396 0.3048)
			(stroke
				(width 0.1)
				(type default)
			)
			(layer "F.Fab")
		)
		(pad "1" smd circle
			(at -0.40005 0)
			(size 0 0)
			(layers "F.Cu" "F.Mask" "F.Paste")
			(net "P3V3_AUX")
		)
		(pad "2" smd circle
			(at 0.40005 0)
			(size 0 0)
			(layers "F.Cu" "F.Mask" "F.Paste")
			(net "PWRGD_PS_PWROK_PLD_N")
		)
	)
	(footprint ""
		(layer "F.Cu")
		(at 418.26053 -402.371052 -90)
		(property "Reference" "C964"
			(at 0 0 270)
			(layer "F.SilkS")
			(hide yes)
			(effects
				(font
					(size 1.27 1.27)
				)
			)
		)
		(property "Value" ""
			(at 0 0 270)
			(layer "F.Fab")
			(effects
				(font
					(size 1.27 1.27)
				)
			)
		)
		(duplicate_pad_numbers_are_jumpers no)
		(fp_line
			(start -0.299974 0.150114)
			(end -0.299974 -0.150114)
			(stroke
				(width 0.1)
				(type default)
			)
			(layer "F.Fab")
		)
		(fp_line
			(start 0.299974 0.150114)
			(end -0.299974 0.150114)
			(stroke
				(width 0.1)
				(type default)
			)
			(layer "F.Fab")
		)
		(fp_line
			(start -0.299974 -0.150114)
			(end 0.299974 -0.150114)
			(stroke
				(width 0.1)
				(type default)
			)
			(layer "F.Fab")
		)
		(fp_line
			(start 0.299974 -0.150114)
			(end 0.299974 0.150114)
			(stroke
				(width 0.1)
				(type default)
			)
			(layer "F.Fab")
		)
		(pad "1" smd rect
			(at -0.2667 0 270)
			(size 0.3048 0.381)
			(layers "F.Cu" "F.Mask" "F.Paste")
			(net "P5E_CPU0_PE2_TX_C_DN<0>")
		)
		(pad "2" smd rect
			(at 0.2667 0 270)
			(size 0.3048 0.381)
			(layers "F.Cu" "F.Mask" "F.Paste")
			(net "P5E_CPU0_PE2_TX_DN<0>")
		)
	)
	(footprint ""
		(layer "F.Cu")
		(at 193.60388 -101.145848 180)
		(property "Reference" "R3046"
			(at 0 0 180)
			(layer "F.SilkS")
			(hide yes)
			(effects
				(font
					(size 1.27 1.27)
				)
			)
		)
		(property "Value" ""
			(at 0 0 180)
			(layer "F.Fab")
			(effects
				(font
					(size 1.27 1.27)
				)
			)
		)
		(duplicate_pad_numbers_are_jumpers no)
		(fp_line
			(start 0.7874 0.4064)
			(end -0.7874 0.4064)
			(stroke
				(width 0.1524)
				(type default)
			)
			(layer "F.SilkS")
		)
		(fp_line
			(start 0.7874 -0.4064)
			(end 0.7874 0.4064)
			(stroke
				(width 0.1524)
				(type default)
			)
			(layer "F.SilkS")
		)
		(fp_line
			(start -0.7874 0.4064)
			(end -0.7874 -0.4064)
			(stroke
				(width 0.1524)
				(type default)
			)
			(layer "F.SilkS")
		)
		(fp_line
			(start -0.7874 -0.4064)
			(end 0.7874 -0.4064)
			(stroke
				(width 0.1524)
				(type default)
			)
			(layer "F.SilkS")
		)
		(fp_line
			(start 0.67945 0.3048)
			(end 0.120396 0.3048)
			(stroke
				(width 0.1)
				(type default)
			)
			(layer "F.Fab")
		)
		(fp_line
			(start 0.67945 -0.3048)
			(end 0.67945 0.3048)
			(stroke
				(width 0.1)
				(type default)
			)
			(layer "F.Fab")
		)
		(fp_line
			(start 0.12065 -0.2794)
			(end 0.12065 -0.3048)
			(stroke
				(width 0.1)
				(type default)
			)
			(layer "F.Fab")
		)
		(fp_line
			(start 0.12065 -0.3048)
			(end 0.67945 -0.3048)
			(stroke
				(width 0.1)
				(type default)
			)
			(layer "F.Fab")
		)
		(fp_line
			(start 0.120396 0.3048)
			(end 0.120396 0.2794)
			(stroke
				(width 0.1)
				(type default)
			)
			(layer "F.Fab")
		)
		(fp_line
			(start 0.120396 0.2794)
			(end -0.12065 0.2794)
			(stroke
				(width 0.1)
				(type default)
			)
			(layer "F.Fab")
		)
		(fp_line
			(start -0.12065 0.3048)
			(end -0.67945 0.3048)
			(stroke
				(width 0.1)
				(type default)
			)
			(layer "F.Fab")
		)
		(fp_line
			(start -0.12065 0.2794)
			(end -0.12065 0.3048)
			(stroke
				(width 0.1)
				(type default)
			)
			(layer "F.Fab")
		)
		(fp_line
			(start -0.12065 -0.2794)
			(end 0.12065 -0.2794)
			(stroke
				(width 0.1)
				(type default)
			)
			(layer "F.Fab")
		)
		(fp_line
			(start -0.12065 -0.305054)
			(end -0.12065 -0.2794)
			(stroke
				(width 0.1)
				(type default)
			)
			(layer "F.Fab")
		)
		(fp_line
			(start -0.67945 0.3048)
			(end -0.67945 -0.305054)
			(stroke
				(width 0.1)
				(type default)
			)
			(layer "F.Fab")
		)
		(fp_line
			(start -0.67945 -0.305054)
			(end -0.12065 -0.305054)
			(stroke
				(width 0.1)
				(type default)
			)
			(layer "F.Fab")
		)
		(pad "1" smd circle
			(at -0.40005 0 180)
			(size 0 0)
			(layers "F.Cu" "F.Mask" "F.Paste")
			(net "FM_UV_ADR_TRIGGER_N")
		)
		(pad "2" smd circle
			(at 0.40005 0 180)
			(size 0 0)
			(layers "F.Cu" "F.Mask" "F.Paste")
			(net "FM_UV_ADR_TRIGGER_R_N")
		)
	)
	(footprint ""
		(layer "F.Cu")
		(at 236.599984 -245.411498 -90)
		(property "Reference" "R4079"
			(at 0 0 270)
			(layer "F.SilkS")
			(hide yes)
			(effects
				(font
					(size 1.27 1.27)
				)
			)
		)
		(property "Value" ""
			(at 0 0 270)
			(layer "F.Fab")
			(effects
				(font
					(size 1.27 1.27)
				)
			)
		)
		(duplicate_pad_numbers_are_jumpers no)
		(fp_line
			(start -0.7874 0.4064)
			(end -0.7874 -0.4064)
			(stroke
				(width 0.1524)
				(type default)
			)
			(layer "F.SilkS")
		)
		(fp_line
			(start 0.7874 0.4064)
			(end -0.7874 0.4064)
			(stroke
				(width 0.1524)
				(type default)
			)
			(layer "F.SilkS")
		)
		(fp_line
			(start -0.7874 -0.4064)
			(end 0.7874 -0.4064)
			(stroke
				(width 0.1524)
				(type default)
			)
			(layer "F.SilkS")
		)
		(fp_line
			(start 0.7874 -0.4064)
			(end 0.7874 0.4064)
			(stroke
				(width 0.1524)
				(type default)
			)
			(layer "F.SilkS")
		)
		(fp_line
			(start -0.67945 0.3048)
			(end -0.67945 -0.305054)
			(stroke
				(width 0.1)
				(type default)
			)
			(layer "F.Fab")
		)
		(fp_line
			(start -0.12065 0.3048)
			(end -0.67945 0.3048)
			(stroke
				(width 0.1)
				(type default)
			)
			(layer "F.Fab")
		)
		(fp_line
			(start 0.120396 0.3048)
			(end 0.120396 0.2794)
			(stroke
				(width 0.1)
				(type default)
			)
			(layer "F.Fab")
		)
		(fp_line
			(start 0.67945 0.3048)
			(end 0.120396 0.3048)
			(stroke
				(width 0.1)
				(type default)
			)
			(layer "F.Fab")
		)
		(fp_line
			(start -0.12065 0.2794)
			(end -0.12065 0.3048)
			(stroke
				(width 0.1)
				(type default)
			)
			(layer "F.Fab")
		)
		(fp_line
			(start 0.120396 0.2794)
			(end -0.12065 0.2794)
			(stroke
				(width 0.1)
				(type default)
			)
			(layer "F.Fab")
		)
		(fp_line
			(start -0.12065 -0.2794)
			(end 0.12065 -0.2794)
			(stroke
				(width 0.1)
				(type default)
			)
			(layer "F.Fab")
		)
		(fp_line
			(start 0.12065 -0.2794)
			(end 0.12065 -0.3048)
			(stroke
				(width 0.1)
				(type default)
			)
			(layer "F.Fab")
		)
		(fp_line
			(start 0.12065 -0.3048)
			(end 0.67945 -0.3048)
			(stroke
				(width 0.1)
				(type default)
			)
			(layer "F.Fab")
		)
		(fp_line
			(start 0.67945 -0.3048)
			(end 0.67945 0.3048)
			(stroke
				(width 0.1)
				(type default)
			)
			(layer "F.Fab")
		)
		(fp_line
			(start -0.67945 -0.305054)
			(end -0.12065 -0.305054)
			(stroke
				(width 0.1)
				(type default)
			)
			(layer "F.Fab")
		)
		(fp_line
			(start -0.12065 -0.305054)
			(end -0.12065 -0.2794)
			(stroke
				(width 0.1)
				(type default)
			)
			(layer "F.Fab")
		)
		(pad "1" smd circle
			(at -0.40005 0 270)
			(size 0 0)
			(layers "F.Cu" "F.Mask" "F.Paste")
			(net "FG_SS_EN")
		)
		(pad "2" smd circle
			(at 0.40005 0 270)
			(size 0 0)
			(layers "F.Cu" "F.Mask" "F.Paste")
			(net "GND")
		)
	)
	(footprint ""
		(layer "F.Cu")
		(at 166.17823 -73.754234)
		(property "Reference" "R2905"
			(at 0 0 0)
			(layer "F.SilkS")
			(hide yes)
			(effects
				(font
					(size 1.27 1.27)
				)
			)
		)
		(property "Value" ""
			(at 0 0 0)
			(layer "F.Fab")
			(effects
				(font
					(size 1.27 1.27)
				)
			)
		)
		(duplicate_pad_numbers_are_jumpers no)
		(fp_line
			(start -0.7874 -0.4064)
			(end 0.7874 -0.4064)
			(stroke
				(width 0.1524)
				(type default)
			)
			(layer "F.SilkS")
		)
		(fp_line
			(start -0.7874 0.4064)
			(end -0.7874 -0.4064)
			(stroke
				(width 0.1524)
				(type default)
			)
			(layer "F.SilkS")
		)
		(fp_line
			(start 0.7874 -0.4064)
			(end 0.7874 0.4064)
			(stroke
				(width 0.1524)
				(type default)
			)
			(layer "F.SilkS")
		)
		(fp_line
			(start 0.7874 0.4064)
			(end -0.7874 0.4064)
			(stroke
				(width 0.1524)
				(type default)
			)
			(layer "F.SilkS")
		)
		(fp_line
			(start -0.67945 -0.305054)
			(end -0.12065 -0.305054)
			(stroke
				(width 0.1)
				(type default)
			)
			(layer "F.Fab")
		)
		(fp_line
			(start -0.67945 0.3048)
			(end -0.67945 -0.305054)
			(stroke
				(width 0.1)
				(type default)
			)
			(layer "F.Fab")
		)
		(fp_line
			(start -0.12065 -0.305054)
			(end -0.12065 -0.2794)
			(stroke
				(width 0.1)
				(type default)
			)
			(layer "F.Fab")
		)
		(fp_line
			(start -0.12065 -0.2794)
			(end 0.12065 -0.2794)
			(stroke
				(width 0.1)
				(type default)
			)
			(layer "F.Fab")
		)
		(fp_line
			(start -0.12065 0.2794)
			(end -0.12065 0.3048)
			(stroke
				(width 0.1)
				(type default)
			)
			(layer "F.Fab")
		)
		(fp_line
			(start -0.12065 0.3048)
			(end -0.67945 0.3048)
			(stroke
				(width 0.1)
				(type default)
			)
			(layer "F.Fab")
		)
		(fp_line
			(start 0.120396 0.2794)
			(end -0.12065 0.2794)
			(stroke
				(width 0.1)
				(type default)
			)
			(layer "F.Fab")
		)
		(fp_line
			(start 0.120396 0.3048)
			(end 0.120396 0.2794)
			(stroke
				(width 0.1)
				(type default)
			)
			(layer "F.Fab")
		)
		(fp_line
			(start 0.12065 -0.3048)
			(end 0.67945 -0.3048)
			(stroke
				(width 0.1)
				(type default)
			)
			(layer "F.Fab")
		)
		(fp_line
			(start 0.12065 -0.2794)
			(end 0.12065 -0.3048)
			(stroke
				(width 0.1)
				(type default)
			)
			(layer "F.Fab")
		)
		(fp_line
			(start 0.67945 -0.3048)
			(end 0.67945 0.3048)
			(stroke
				(width 0.1)
				(type default)
			)
			(layer "F.Fab")
		)
		(fp_line
			(start 0.67945 0.3048)
			(end 0.120396 0.3048)
			(stroke
				(width 0.1)
				(type default)
			)
			(layer "F.Fab")
		)
		(pad "1" smd circle
			(at -0.40005 0)
			(size 0 0)
			(layers "F.Cu" "F.Mask" "F.Paste")
			(net "RST_SMB_SWITCH_N")
		)
		(pad "2" smd circle
			(at 0.40005 0)
			(size 0 0)
			(layers "F.Cu" "F.Mask" "F.Paste")
			(net "RST_SMB_SWITCH_R_N")
		)
	)
	(footprint ""
		(layer "F.Cu")
		(at 461.445356 -382.077214)
		(property "Reference" "R2316"
			(at 0 0 0)
			(layer "F.SilkS")
			(hide yes)
			(effects
				(font
					(size 1.27 1.27)
				)
			)
		)
		(property "Value" ""
			(at 0 0 0)
			(layer "F.Fab")
			(effects
				(font
					(size 1.27 1.27)
				)
			)
		)
		(duplicate_pad_numbers_are_jumpers no)
		(fp_line
			(start -0.7874 -0.4064)
			(end 0.7874 -0.4064)
			(stroke
				(width 0.1524)
				(type default)
			)
			(layer "F.SilkS")
		)
		(fp_line
			(start -0.7874 0.4064)
			(end -0.7874 -0.4064)
			(stroke
				(width 0.1524)
				(type default)
			)
			(layer "F.SilkS")
		)
		(fp_line
			(start 0.7874 -0.4064)
			(end 0.7874 0.4064)
			(stroke
				(width 0.1524)
				(type default)
			)
			(layer "F.SilkS")
		)
		(fp_line
			(start 0.7874 0.4064)
			(end -0.7874 0.4064)
			(stroke
				(width 0.1524)
				(type default)
			)
			(layer "F.SilkS")
		)
		(fp_line
			(start -0.67945 -0.305054)
			(end -0.12065 -0.305054)
			(stroke
				(width 0.1)
				(type default)
			)
			(layer "F.Fab")
		)
		(fp_line
			(start -0.67945 0.3048)
			(end -0.67945 -0.305054)
			(stroke
				(width 0.1)
				(type default)
			)
			(layer "F.Fab")
		)
		(fp_line
			(start -0.12065 -0.305054)
			(end -0.12065 -0.2794)
			(stroke
				(width 0.1)
				(type default)
			)
			(layer "F.Fab")
		)
		(fp_line
			(start -0.12065 -0.2794)
			(end 0.12065 -0.2794)
			(stroke
				(width 0.1)
				(type default)
			)
			(layer "F.Fab")
		)
		(fp_line
			(start -0.12065 0.2794)
			(end -0.12065 0.3048)
			(stroke
				(width 0.1)
				(type default)
			)
			(layer "F.Fab")
		)
		(fp_line
			(start -0.12065 0.3048)
			(end -0.67945 0.3048)
			(stroke
				(width 0.1)
				(type default)
			)
			(layer "F.Fab")
		)
		(fp_line
			(start 0.120396 0.2794)
			(end -0.12065 0.2794)
			(stroke
				(width 0.1)
				(type default)
			)
			(layer "F.Fab")
		)
		(fp_line
			(start 0.120396 0.3048)
			(end 0.120396 0.2794)
			(stroke
				(width 0.1)
				(type default)
			)
			(layer "F.Fab")
		)
		(fp_line
			(start 0.12065 -0.3048)
			(end 0.67945 -0.3048)
			(stroke
				(width 0.1)
				(type default)
			)
			(layer "F.Fab")
		)
		(fp_line
			(start 0.12065 -0.2794)
			(end 0.12065 -0.3048)
			(stroke
				(width 0.1)
				(type default)
			)
			(layer "F.Fab")
		)
		(fp_line
			(start 0.67945 -0.3048)
			(end 0.67945 0.3048)
			(stroke
				(width 0.1)
				(type default)
			)
			(layer "F.Fab")
		)
		(fp_line
			(start 0.67945 0.3048)
			(end 0.120396 0.3048)
			(stroke
				(width 0.1)
				(type default)
			)
			(layer "F.Fab")
		)
		(pad "1" smd circle
			(at -0.40005 0)
			(size 0 0)
			(layers "F.Cu" "F.Mask" "F.Paste")
			(net "PWRGD_P5V_AUX_R")
		)
		(pad "2" smd circle
			(at 0.40005 0)
			(size 0 0)
			(layers "F.Cu" "F.Mask" "F.Paste")
			(net "PWRGD_P5V_AUX")
		)
	)
	(footprint ""
		(layer "F.Cu")
		(at 22.010878 -16.099536 90)
		(property "Reference" "C810"
			(at 0 0 90)
			(layer "F.SilkS")
			(hide yes)
			(effects
				(font
					(size 1.27 1.27)
				)
			)
		)
		(property "Value" ""
			(at 0 0 90)
			(layer "F.Fab")
			(effects
				(font
					(size 1.27 1.27)
				)
			)
		)
		(duplicate_pad_numbers_are_jumpers no)
		(fp_line
			(start 0.299974 -0.150114)
			(end 0.299974 0.150114)
			(stroke
				(width 0.1)
				(type default)
			)
			(layer "F.Fab")
		)
		(fp_line
			(start -0.299974 -0.150114)
			(end 0.299974 -0.150114)
			(stroke
				(width 0.1)
				(type default)
			)
			(layer "F.Fab")
		)
		(fp_line
			(start 0.299974 0.150114)
			(end -0.299974 0.150114)
			(stroke
				(width 0.1)
				(type default)
			)
			(layer "F.Fab")
		)
		(fp_line
			(start -0.299974 0.150114)
			(end -0.299974 -0.150114)
			(stroke
				(width 0.1)
				(type default)
			)
			(layer "F.Fab")
		)
		(pad "1" smd rect
			(at -0.2667 0 90)
			(size 0.3048 0.381)
			(layers "F.Cu" "F.Mask" "F.Paste")
			(net "P5E_CPU1_PE1_TX_C_DN<13>")
		)
		(pad "2" smd rect
			(at 0.2667 0 90)
			(size 0.3048 0.381)
			(layers "F.Cu" "F.Mask" "F.Paste")
			(net "P5E_CPU1_PE1_TX_DN<13>")
		)
	)
	(footprint ""
		(layer "F.Cu")
		(at 209.74558 -131.846828 180)
		(property "Reference" "R1689"
			(at 0 0 180)
			(layer "F.SilkS")
			(hide yes)
			(effects
				(font
					(size 1.27 1.27)
				)
			)
		)
		(property "Value" ""
			(at 0 0 180)
			(layer "F.Fab")
			(effects
				(font
					(size 1.27 1.27)
				)
			)
		)
		(duplicate_pad_numbers_are_jumpers no)
		(fp_line
			(start 0.7874 0.4064)
			(end -0.7874 0.4064)
			(stroke
				(width 0.1524)
				(type default)
			)
			(layer "F.SilkS")
		)
		(fp_line
			(start 0.7874 -0.4064)
			(end 0.7874 0.4064)
			(stroke
				(width 0.1524)
				(type default)
			)
			(layer "F.SilkS")
		)
		(fp_line
			(start -0.7874 0.4064)
			(end -0.7874 -0.4064)
			(stroke
				(width 0.1524)
				(type default)
			)
			(layer "F.SilkS")
		)
		(fp_line
			(start -0.7874 -0.4064)
			(end 0.7874 -0.4064)
			(stroke
				(width 0.1524)
				(type default)
			)
			(layer "F.SilkS")
		)
		(fp_line
			(start 0.67945 0.3048)
			(end 0.120396 0.3048)
			(stroke
				(width 0.1)
				(type default)
			)
			(layer "F.Fab")
		)
		(fp_line
			(start 0.67945 -0.3048)
			(end 0.67945 0.3048)
			(stroke
				(width 0.1)
				(type default)
			)
			(layer "F.Fab")
		)
		(fp_line
			(start 0.12065 -0.2794)
			(end 0.12065 -0.3048)
			(stroke
				(width 0.1)
				(type default)
			)
			(layer "F.Fab")
		)
		(fp_line
			(start 0.12065 -0.3048)
			(end 0.67945 -0.3048)
			(stroke
				(width 0.1)
				(type default)
			)
			(layer "F.Fab")
		)
		(fp_line
			(start 0.120396 0.3048)
			(end 0.120396 0.2794)
			(stroke
				(width 0.1)
				(type default)
			)
			(layer "F.Fab")
		)
		(fp_line
			(start 0.120396 0.2794)
			(end -0.12065 0.2794)
			(stroke
				(width 0.1)
				(type default)
			)
			(layer "F.Fab")
		)
		(fp_line
			(start -0.12065 0.3048)
			(end -0.67945 0.3048)
			(stroke
				(width 0.1)
				(type default)
			)
			(layer "F.Fab")
		)
		(fp_line
			(start -0.12065 0.2794)
			(end -0.12065 0.3048)
			(stroke
				(width 0.1)
				(type default)
			)
			(layer "F.Fab")
		)
		(fp_line
			(start -0.12065 -0.2794)
			(end 0.12065 -0.2794)
			(stroke
				(width 0.1)
				(type default)
			)
			(layer "F.Fab")
		)
		(fp_line
			(start -0.12065 -0.305054)
			(end -0.12065 -0.2794)
			(stroke
				(width 0.1)
				(type default)
			)
			(layer "F.Fab")
		)
		(fp_line
			(start -0.67945 0.3048)
			(end -0.67945 -0.305054)
			(stroke
				(width 0.1)
				(type default)
			)
			(layer "F.Fab")
		)
		(fp_line
			(start -0.67945 -0.305054)
			(end -0.12065 -0.305054)
			(stroke
				(width 0.1)
				(type default)
			)
			(layer "F.Fab")
		)
		(pad "1" smd circle
			(at -0.40005 0 180)
			(size 0 0)
			(layers "F.Cu" "F.Mask" "F.Paste")
			(net "FM_COMP_P3V3_AUX_VIN")
		)
		(pad "2" smd circle
			(at 0.40005 0 180)
			(size 0 0)
			(layers "F.Cu" "F.Mask" "F.Paste")
			(net "GND")
		)
	)
	(footprint ""
		(layer "F.Cu")
		(at 327.770998 -190.74511 90)
		(property "Reference" "R4262"
			(at 0 0 90)
			(layer "F.SilkS")
			(hide yes)
			(effects
				(font
					(size 1.27 1.27)
				)
			)
		)
		(property "Value" ""
			(at 0 0 90)
			(layer "F.Fab")
			(effects
				(font
					(size 1.27 1.27)
				)
			)
		)
		(duplicate_pad_numbers_are_jumpers no)
		(fp_line
			(start 0.7874 -0.4064)
			(end 0.7874 0.4064)
			(stroke
				(width 0.1524)
				(type default)
			)
			(layer "F.SilkS")
		)
		(fp_line
			(start -0.7874 -0.4064)
			(end 0.7874 -0.4064)
			(stroke
				(width 0.1524)
				(type default)
			)
			(layer "F.SilkS")
		)
		(fp_line
			(start 0.7874 0.4064)
			(end -0.7874 0.4064)
			(stroke
				(width 0.1524)
				(type default)
			)
			(layer "F.SilkS")
		)
		(fp_line
			(start -0.7874 0.4064)
			(end -0.7874 -0.4064)
			(stroke
				(width 0.1524)
				(type default)
			)
			(layer "F.SilkS")
		)
		(fp_line
			(start -0.12065 -0.305054)
			(end -0.12065 -0.2794)
			(stroke
				(width 0.1)
				(type default)
			)
			(layer "F.Fab")
		)
		(fp_line
			(start -0.67945 -0.305054)
			(end -0.12065 -0.305054)
			(stroke
				(width 0.1)
				(type default)
			)
			(layer "F.Fab")
		)
		(fp_line
			(start 0.67945 -0.3048)
			(end 0.67945 0.3048)
			(stroke
				(width 0.1)
				(type default)
			)
			(layer "F.Fab")
		)
		(fp_line
			(start 0.12065 -0.3048)
			(end 0.67945 -0.3048)
			(stroke
				(width 0.1)
				(type default)
			)
			(layer "F.Fab")
		)
		(fp_line
			(start 0.12065 -0.2794)
			(end 0.12065 -0.3048)
			(stroke
				(width 0.1)
				(type default)
			)
			(layer "F.Fab")
		)
		(fp_line
			(start -0.12065 -0.2794)
			(end 0.12065 -0.2794)
			(stroke
				(width 0.1)
				(type default)
			)
			(layer "F.Fab")
		)
		(fp_line
			(start 0.120396 0.2794)
			(end -0.12065 0.2794)
			(stroke
				(width 0.1)
				(type default)
			)
			(layer "F.Fab")
		)
		(fp_line
			(start -0.12065 0.2794)
			(end -0.12065 0.3048)
			(stroke
				(width 0.1)
				(type default)
			)
			(layer "F.Fab")
		)
		(fp_line
			(start 0.67945 0.3048)
			(end 0.120396 0.3048)
			(stroke
				(width 0.1)
				(type default)
			)
			(layer "F.Fab")
		)
		(fp_line
			(start 0.120396 0.3048)
			(end 0.120396 0.2794)
			(stroke
				(width 0.1)
				(type default)
			)
			(layer "F.Fab")
		)
		(fp_line
			(start -0.12065 0.3048)
			(end -0.67945 0.3048)
			(stroke
				(width 0.1)
				(type default)
			)
			(layer "F.Fab")
		)
		(fp_line
			(start -0.67945 0.3048)
			(end -0.67945 -0.305054)
			(stroke
				(width 0.1)
				(type default)
			)
			(layer "F.Fab")
		)
		(pad "1" smd circle
			(at -0.40005 0 90)
			(size 0 0)
			(layers "F.Cu" "F.Mask" "F.Paste")
			(net "PVNN_TERM_CPU0")
		)
		(pad "2" smd circle
			(at 0.40005 0 90)
			(size 0 0)
			(layers "F.Cu" "F.Mask" "F.Paste")
			(net "PD_CPU0_BIST_ENABLE")
		)
	)
	(footprint ""
		(layer "F.Cu")
		(at 446.740026 -184.028842)
		(property "Reference" "PC1277"
			(at 0 0 0)
			(layer "F.SilkS")
			(hide yes)
			(effects
				(font
					(size 1.27 1.27)
				)
			)
		)
		(property "Value" ""
			(at 0 0 0)
			(layer "F.Fab")
			(effects
				(font
					(size 1.27 1.27)
				)
			)
		)
		(duplicate_pad_numbers_are_jumpers no)
		(fp_line
			(start -1.524 -0.762)
			(end 1.524 -0.762)
			(stroke
				(width 0.1524)
				(type default)
			)
			(layer "F.SilkS")
		)
		(fp_line
			(start -1.524 0.762)
			(end -1.524 -0.762)
			(stroke
				(width 0.1524)
				(type default)
			)
			(layer "F.SilkS")
		)
		(fp_line
			(start 1.524 -0.762)
			(end 1.524 0.762)
			(stroke
				(width 0.1524)
				(type default)
			)
			(layer "F.SilkS")
		)
		(fp_line
			(start 1.524 0.762)
			(end -1.524 0.762)
			(stroke
				(width 0.1524)
				(type default)
			)
			(layer "F.SilkS")
		)
		(fp_line
			(start -1.1049 -0.724916)
			(end -1.1049 0.724916)
			(stroke
				(width 0.1)
				(type default)
			)
			(layer "F.Fab")
		)
		(fp_line
			(start -1.1049 0.724916)
			(end 1.1049 0.724916)
			(stroke
				(width 0.1)
				(type default)
			)
			(layer "F.Fab")
		)
		(fp_line
			(start 1.1049 -0.724916)
			(end -1.1049 -0.724916)
			(stroke
				(width 0.1)
				(type default)
			)
			(layer "F.Fab")
		)
		(fp_line
			(start 1.1049 0.724916)
			(end 1.1049 -0.724916)
			(stroke
				(width 0.1)
				(type default)
			)
			(layer "F.Fab")
		)
		(pad "1" smd rect
			(at -0.889 0 180)
			(size 1.016 1.27)
			(layers "F.Cu" "F.Mask" "F.Paste")
			(net "PVNN_MAIN_CPU0")
		)
		(pad "2" smd rect
			(at 0.889 0 180)
			(size 1.016 1.27)
			(layers "F.Cu" "F.Mask" "F.Paste")
			(net "GND")
		)
	)
	(footprint ""
		(layer "F.Cu")
		(at 401.191984 -16.088614 90)
		(property "Reference" "C847"
			(at 0 0 90)
			(layer "F.SilkS")
			(hide yes)
			(effects
				(font
					(size 1.27 1.27)
				)
			)
		)
		(property "Value" ""
			(at 0 0 90)
			(layer "F.Fab")
			(effects
				(font
					(size 1.27 1.27)
				)
			)
		)
		(duplicate_pad_numbers_are_jumpers no)
		(fp_line
			(start 0.299974 -0.150114)
			(end 0.299974 0.150114)
			(stroke
				(width 0.1)
				(type default)
			)
			(layer "F.Fab")
		)
		(fp_line
			(start -0.299974 -0.150114)
			(end 0.299974 -0.150114)
			(stroke
				(width 0.1)
				(type default)
			)
			(layer "F.Fab")
		)
		(fp_line
			(start 0.299974 0.150114)
			(end -0.299974 0.150114)
			(stroke
				(width 0.1)
				(type default)
			)
			(layer "F.Fab")
		)
		(fp_line
			(start -0.299974 0.150114)
			(end -0.299974 -0.150114)
			(stroke
				(width 0.1)
				(type default)
			)
			(layer "F.Fab")
		)
		(pad "1" smd rect
			(at -0.2667 0 90)
			(size 0.3048 0.381)
			(layers "F.Cu" "F.Mask" "F.Paste")
			(net "P5E_CPU0_PE1_TX_C_DP<11>")
		)
		(pad "2" smd rect
			(at 0.2667 0 90)
			(size 0.3048 0.381)
			(layers "F.Cu" "F.Mask" "F.Paste")
			(net "P5E_CPU0_PE1_TX_DP<11>")
		)
	)
	(footprint ""
		(layer "F.Cu")
		(at 406.124664 -365.294926)
		(property "Reference" "R997"
			(at 0 0 0)
			(layer "F.SilkS")
			(hide yes)
			(effects
				(font
					(size 1.27 1.27)
				)
			)
		)
		(property "Value" ""
			(at 0 0 0)
			(layer "F.Fab")
			(effects
				(font
					(size 1.27 1.27)
				)
			)
		)
		(duplicate_pad_numbers_are_jumpers no)
		(fp_line
			(start -0.7874 -0.4064)
			(end 0.7874 -0.4064)
			(stroke
				(width 0.1524)
				(type default)
			)
			(layer "F.SilkS")
		)
		(fp_line
			(start -0.7874 0.4064)
			(end -0.7874 -0.4064)
			(stroke
				(width 0.1524)
				(type default)
			)
			(layer "F.SilkS")
		)
		(fp_line
			(start 0.7874 -0.4064)
			(end 0.7874 0.4064)
			(stroke
				(width 0.1524)
				(type default)
			)
			(layer "F.SilkS")
		)
		(fp_line
			(start 0.7874 0.4064)
			(end -0.7874 0.4064)
			(stroke
				(width 0.1524)
				(type default)
			)
			(layer "F.SilkS")
		)
		(fp_line
			(start -0.67945 -0.305054)
			(end -0.12065 -0.305054)
			(stroke
				(width 0.1)
				(type default)
			)
			(layer "F.Fab")
		)
		(fp_line
			(start -0.67945 0.3048)
			(end -0.67945 -0.305054)
			(stroke
				(width 0.1)
				(type default)
			)
			(layer "F.Fab")
		)
		(fp_line
			(start -0.12065 -0.305054)
			(end -0.12065 -0.2794)
			(stroke
				(width 0.1)
				(type default)
			)
			(layer "F.Fab")
		)
		(fp_line
			(start -0.12065 -0.2794)
			(end 0.12065 -0.2794)
			(stroke
				(width 0.1)
				(type default)
			)
			(layer "F.Fab")
		)
		(fp_line
			(start -0.12065 0.2794)
			(end -0.12065 0.3048)
			(stroke
				(width 0.1)
				(type default)
			)
			(layer "F.Fab")
		)
		(fp_line
			(start -0.12065 0.3048)
			(end -0.67945 0.3048)
			(stroke
				(width 0.1)
				(type default)
			)
			(layer "F.Fab")
		)
		(fp_line
			(start 0.120396 0.2794)
			(end -0.12065 0.2794)
			(stroke
				(width 0.1)
				(type default)
			)
			(layer "F.Fab")
		)
		(fp_line
			(start 0.120396 0.3048)
			(end 0.120396 0.2794)
			(stroke
				(width 0.1)
				(type default)
			)
			(layer "F.Fab")
		)
		(fp_line
			(start 0.12065 -0.3048)
			(end 0.67945 -0.3048)
			(stroke
				(width 0.1)
				(type default)
			)
			(layer "F.Fab")
		)
		(fp_line
			(start 0.12065 -0.2794)
			(end 0.12065 -0.3048)
			(stroke
				(width 0.1)
				(type default)
			)
			(layer "F.Fab")
		)
		(fp_line
			(start 0.67945 -0.3048)
			(end 0.67945 0.3048)
			(stroke
				(width 0.1)
				(type default)
			)
			(layer "F.Fab")
		)
		(fp_line
			(start 0.67945 0.3048)
			(end 0.120396 0.3048)
			(stroke
				(width 0.1)
				(type default)
			)
			(layer "F.Fab")
		)
		(pad "1" smd circle
			(at -0.40005 0)
			(size 0 0)
			(layers "F.Cu" "F.Mask" "F.Paste")
			(net "PU_PIROM_CPU0_SM_WP")
		)
		(pad "2" smd circle
			(at 0.40005 0)
			(size 0 0)
			(layers "F.Cu" "F.Mask" "F.Paste")
			(net "GND")
		)
	)
	(footprint ""
		(layer "F.Cu")
		(at 211.4296 -107.4166 -90)
		(property "Reference" "R4785"
			(at 0 0 270)
			(layer "F.SilkS")
			(hide yes)
			(effects
				(font
					(size 1.27 1.27)
				)
			)
		)
		(property "Value" ""
			(at 0 0 270)
			(layer "F.Fab")
			(effects
				(font
					(size 1.27 1.27)
				)
			)
		)
		(duplicate_pad_numbers_are_jumpers no)
		(fp_line
			(start -0.7874 0.4064)
			(end -0.7874 -0.4064)
			(stroke
				(width 0.1524)
				(type default)
			)
			(layer "F.SilkS")
		)
		(fp_line
			(start 0.7874 0.4064)
			(end -0.7874 0.4064)
			(stroke
				(width 0.1524)
				(type default)
			)
			(layer "F.SilkS")
		)
		(fp_line
			(start -0.7874 -0.4064)
			(end 0.7874 -0.4064)
			(stroke
				(width 0.1524)
				(type default)
			)
			(layer "F.SilkS")
		)
		(fp_line
			(start 0.7874 -0.4064)
			(end 0.7874 0.4064)
			(stroke
				(width 0.1524)
				(type default)
			)
			(layer "F.SilkS")
		)
		(fp_line
			(start -0.67945 0.3048)
			(end -0.67945 -0.305054)
			(stroke
				(width 0.1)
				(type default)
			)
			(layer "F.Fab")
		)
		(fp_line
			(start -0.12065 0.3048)
			(end -0.67945 0.3048)
			(stroke
				(width 0.1)
				(type default)
			)
			(layer "F.Fab")
		)
		(fp_line
			(start 0.120396 0.3048)
			(end 0.120396 0.2794)
			(stroke
				(width 0.1)
				(type default)
			)
			(layer "F.Fab")
		)
		(fp_line
			(start 0.67945 0.3048)
			(end 0.120396 0.3048)
			(stroke
				(width 0.1)
				(type default)
			)
			(layer "F.Fab")
		)
		(fp_line
			(start -0.12065 0.2794)
			(end -0.12065 0.3048)
			(stroke
				(width 0.1)
				(type default)
			)
			(layer "F.Fab")
		)
		(fp_line
			(start 0.120396 0.2794)
			(end -0.12065 0.2794)
			(stroke
				(width 0.1)
				(type default)
			)
			(layer "F.Fab")
		)
		(fp_line
			(start -0.12065 -0.2794)
			(end 0.12065 -0.2794)
			(stroke
				(width 0.1)
				(type default)
			)
			(layer "F.Fab")
		)
		(fp_line
			(start 0.12065 -0.2794)
			(end 0.12065 -0.3048)
			(stroke
				(width 0.1)
				(type default)
			)
			(layer "F.Fab")
		)
		(fp_line
			(start 0.12065 -0.3048)
			(end 0.67945 -0.3048)
			(stroke
				(width 0.1)
				(type default)
			)
			(layer "F.Fab")
		)
		(fp_line
			(start 0.67945 -0.3048)
			(end 0.67945 0.3048)
			(stroke
				(width 0.1)
				(type default)
			)
			(layer "F.Fab")
		)
		(fp_line
			(start -0.67945 -0.305054)
			(end -0.12065 -0.305054)
			(stroke
				(width 0.1)
				(type default)
			)
			(layer "F.Fab")
		)
		(fp_line
			(start -0.12065 -0.305054)
			(end -0.12065 -0.2794)
			(stroke
				(width 0.1)
				(type default)
			)
			(layer "F.Fab")
		)
		(pad "1" smd circle
			(at -0.40005 0 270)
			(size 0 0)
			(layers "F.Cu" "F.Mask" "F.Paste")
			(net "P3V3_AUX")
		)
		(pad "2" smd circle
			(at 0.40005 0 270)
			(size 0 0)
			(layers "F.Cu" "F.Mask" "F.Paste")
			(net "IRQ_UV_DETECT_N")
		)
	)
	(footprint ""
		(layer "F.Cu")
		(at 39.960042 -392.430254 180)
		(property "Reference" "U328"
			(at 6.072124 -4.195318 0)
			(unlocked yes)
			(layer "F.SilkS")
			(effects
				(font
					(size 0.7874 0.5842)
					(thickness 0.1524)
				)
				(justify left)
			)
		)
		(property "Value" ""
			(at 0 0 180)
			(layer "F.Fab")
			(effects
				(font
					(size 1.27 1.27)
				)
			)
		)
		(duplicate_pad_numbers_are_jumpers no)
		(fp_line
			(start 2.050034 2.050034)
			(end 1.524 2.050034)
			(stroke
				(width 0.1524)
				(type default)
			)
			(layer "F.SilkS")
		)
		(fp_line
			(start 2.050034 1.524)
			(end 2.050034 2.050034)
			(stroke
				(width 0.1524)
				(type default)
			)
			(layer "F.SilkS")
		)
		(fp_line
			(start 2.050034 -2.050034)
			(end 2.050034 -1.524)
			(stroke
				(width 0.1524)
				(type default)
			)
			(layer "F.SilkS")
		)
		(fp_line
			(start 1.524 -2.050034)
			(end 2.050034 -2.050034)
			(stroke
				(width 0.1524)
				(type default)
			)
			(layer "F.SilkS")
		)
		(fp_line
			(start -1.524 2.050034)
			(end -2.050034 2.050034)
			(stroke
				(width 0.1524)
				(type default)
			)
			(layer "F.SilkS")
		)
		(fp_line
			(start -2.050034 2.050034)
			(end -2.050034 1.524)
			(stroke
				(width 0.1524)
				(type default)
			)
			(layer "F.SilkS")
		)
		(fp_line
			(start -2.050034 -1.524)
			(end -2.050034 -2.050034)
			(stroke
				(width 0.1524)
				(type default)
			)
			(layer "F.SilkS")
		)
		(fp_line
			(start -2.050034 -2.050034)
			(end -1.524 -2.050034)
			(stroke
				(width 0.1524)
				(type default)
			)
			(layer "F.SilkS")
		)
		(fp_poly
			(pts
				(xy -2.634234 -1.542034) (xy -2.050034 -1.542034) (xy -2.050034 -2.126234) (xy -2.634234 -2.126234)
			)
			(stroke
				(width 0)
				(type default)
			)
			(fill yes)
			(layer "F.SilkS")
		)
		(fp_line
			(start 2.050034 2.050034)
			(end -2.050034 2.050034)
			(stroke
				(width 0.1)
				(type default)
			)
			(layer "F.Fab")
		)
		(fp_line
			(start 2.050034 -2.050034)
			(end 2.050034 2.050034)
			(stroke
				(width 0.1)
				(type default)
			)
			(layer "F.Fab")
		)
		(fp_line
			(start -2.050034 2.050034)
			(end -2.050034 -2.050034)
			(stroke
				(width 0.1)
				(type default)
			)
			(layer "F.Fab")
		)
		(fp_line
			(start -2.050034 -2.050034)
			(end 2.050034 -2.050034)
			(stroke
				(width 0.1)
				(type default)
			)
			(layer "F.Fab")
		)
		(fp_poly
			(pts
				(xy -2.634234 -1.542034) (xy -2.050034 -1.542034) (xy -2.050034 -2.126234) (xy -2.634234 -2.126234)
			)
			(stroke
				(width 0)
				(type default)
			)
			(fill yes)
			(layer "F.Fab")
		)
		(pad "1" smd circle
			(at -1.89992 -1.249934 90)
			(size 0 0)
			(layers "F.Cu" "F.Mask" "F.Paste")
			(net "FM_P2E_BUF2_EQB0")
		)
		(pad "2" smd circle
			(at -1.89992 -0.750062 90)
			(size 0 0)
			(layers "F.Cu" "F.Mask" "F.Paste")
			(net "FM_P2E_BUF2_EQB1")
		)
		(pad "3" smd circle
			(at -1.89992 -0.249936 90)
			(size 0 0)
			(layers "F.Cu" "F.Mask" "F.Paste")
			(net "PD_P2E_BUF2_ENSMB")
		)
		(pad "4" smd circle
			(at -1.89992 0.249936 90)
			(size 0 0)
			(layers "F.Cu" "F.Mask" "F.Paste")
			(net "FM_P2E_BUF2_VODA_DB")
		)
		(pad "5" smd circle
			(at -1.89992 0.750062 90)
			(size 0 0)
			(layers "F.Cu" "F.Mask" "F.Paste")
			(net "FM_P2E_BUF2_VODB_DB")
		)
		(pad "6" smd circle
			(at -1.89992 1.249934 90)
			(size 0 0)
			(layers "F.Cu" "F.Mask" "F.Paste")
			(net "FM_P2E_EN2_N")
		)
		(pad "7" smd circle
			(at -1.249934 1.89992 180)
			(size 0 0)
			(layers "F.Cu" "F.Mask" "F.Paste")
			(net "P2E_MB_BMC_TX_BUF2_DP<0>")
		)
		(pad "8" smd circle
			(at -0.750062 1.89992 180)
			(size 0 0)
			(layers "F.Cu" "F.Mask" "F.Paste")
			(net "P2E_MB_BMC_TX_BUF2_DN<0>")
		)
		(pad "9" smd circle
			(at -0.249936 1.89992 180)
			(size 0 0)
			(layers "F.Cu" "F.Mask" "F.Paste")
			(net "FM_P2E_BUF2_EQA1")
		)
		(pad "10" smd circle
			(at 0.249936 1.89992 180)
			(size 0 0)
			(layers "F.Cu" "F.Mask" "F.Paste")
			(net "FM_P2E_BUF2_EQA0")
		)
		(pad "11" smd circle
			(at 0.750062 1.89992 180)
			(size 0 0)
			(layers "F.Cu" "F.Mask" "F.Paste")
			(net "P2E_MB_BMC_RX_R2_DP<0>")
		)
		(pad "12" smd circle
			(at 1.249934 1.89992 180)
			(size 0 0)
			(layers "F.Cu" "F.Mask" "F.Paste")
			(net "P2E_MB_BMC_RX_R2_DN<0>")
		)
		(pad "13" smd circle
			(at 1.89992 1.249934 90)
			(size 0 0)
			(layers "F.Cu" "F.Mask" "F.Paste")
			(net "NC_RES")
		)
		(pad "14" smd circle
			(at 1.89992 0.750062 90)
			(size 0 0)
			(layers "F.Cu" "F.Mask" "F.Paste")
			(net "FM_P2E_BUF2_SD_TH")
		)
		(pad "15" smd circle
			(at 1.89992 0.249936 90)
			(size 0 0)
			(layers "F.Cu" "F.Mask" "F.Paste")
			(net "P3V3_AUX")
		)
		(pad "16" smd circle
			(at 1.89992 -0.249936 90)
			(size 0 0)
			(layers "F.Cu" "F.Mask" "F.Paste")
			(net "GND")
		)
		(pad "17" smd circle
			(at 1.89992 -0.750062 90)
			(size 0 0)
			(layers "F.Cu" "F.Mask" "F.Paste")
			(net "FM_P2E_BUF2_VOD_SEL")
		)
		(pad "18" smd circle
			(at 1.89992 -1.249934 90)
			(size 0 0)
			(layers "F.Cu" "F.Mask" "F.Paste")
			(net "FM_P2E_BUF2_RXDET")
		)
		(pad "19" smd circle
			(at 1.249934 -1.89992 180)
			(size 0 0)
			(layers "F.Cu" "F.Mask" "F.Paste")
			(net "P2E_MB_BMC_RX_BUF2_C_DN<0>")
		)
		(pad "20" smd circle
			(at 0.750062 -1.89992 180)
			(size 0 0)
			(layers "F.Cu" "F.Mask" "F.Paste")
			(net "P2E_MB_BMC_RX_BUF2_C_DP<0>")
		)
		(pad "21" smd circle
			(at 0.249936 -1.89992 180)
			(size 0 0)
			(layers "F.Cu" "F.Mask" "F.Paste")
			(net "P2E_BUF2_VDD")
		)
		(pad "22" smd circle
			(at -0.249936 -1.89992 180)
			(size 0 0)
			(layers "F.Cu" "F.Mask" "F.Paste")
			(net "P2E_BUF2_VDD")
		)
		(pad "23" smd circle
			(at -0.750062 -1.89992 180)
			(size 0 0)
			(layers "F.Cu" "F.Mask" "F.Paste")
			(net "P2E_MB_BMC_TX_C_R2_DN<0>")
		)
		(pad "24" smd circle
			(at -1.249934 -1.89992 180)
			(size 0 0)
			(layers "F.Cu" "F.Mask" "F.Paste")
			(net "P2E_MB_BMC_TX_C_R2_DP<0>")
		)
		(pad "25" smd circle
			(at 0 0 180)
			(size 0 0)
			(layers "F.Cu" "F.Mask" "F.Paste")
			(net "GND")
		)
	)
	(footprint ""
		(layer "F.Cu")
		(at 373.654828 -358.460548)
		(property "Reference" "PU79"
			(at 2.394966 2.31775 0)
			(unlocked yes)
			(layer "F.SilkS")
			(effects
				(font
					(size 0.7874 0.5842)
					(thickness 0.1524)
				)
				(justify left)
			)
		)
		(property "Value" ""
			(at 0 0 0)
			(layer "F.Fab")
			(effects
				(font
					(size 1.27 1.27)
				)
			)
		)
		(duplicate_pad_numbers_are_jumpers no)
		(fp_line
			(start -1.549908 -2.050034)
			(end -1.549908 -1.9812)
			(stroke
				(width 0.1524)
				(type default)
			)
			(layer "F.SilkS")
		)
		(fp_line
			(start -1.549908 1.9812)
			(end -1.549908 2.050034)
			(stroke
				(width 0.1524)
				(type default)
			)
			(layer "F.SilkS")
		)
		(fp_line
			(start -1.549908 2.050034)
			(end -0.5842 2.050034)
			(stroke
				(width 0.1524)
				(type default)
			)
			(layer "F.SilkS")
		)
		(fp_line
			(start -0.5842 -2.050034)
			(end -1.549908 -2.050034)
			(stroke
				(width 0.1524)
				(type default)
			)
			(layer "F.SilkS")
		)
		(fp_line
			(start 0 2.050034)
			(end 1.549908 2.050034)
			(stroke
				(width 0.1524)
				(type default)
			)
			(layer "F.SilkS")
		)
		(fp_line
			(start 1.549908 -2.050034)
			(end 0.5842 -2.050034)
			(stroke
				(width 0.1524)
				(type default)
			)
			(layer "F.SilkS")
		)
		(fp_line
			(start 1.549908 -1.9812)
			(end 1.549908 -2.050034)
			(stroke
				(width 0.1524)
				(type default)
			)
			(layer "F.SilkS")
		)
		(fp_line
			(start 1.549908 2.050034)
			(end 1.549908 1.9304)
			(stroke
				(width 0.1524)
				(type default)
			)
			(layer "F.SilkS")
		)
		(fp_poly
			(pts
				(xy -3.216402 -2.222246) (xy -3.216402 -1.206246) (xy -2.200402 -1.714246)
			)
			(stroke
				(width 0)
				(type default)
			)
			(fill yes)
			(layer "F.SilkS")
		)
		(fp_line
			(start -1.549908 -2.050034)
			(end -1.549908 2.050034)
			(stroke
				(width 0.1)
				(type default)
			)
			(layer "F.Fab")
		)
		(fp_line
			(start -1.549908 2.050034)
			(end 1.549908 2.050034)
			(stroke
				(width 0.1)
				(type default)
			)
			(layer "F.Fab")
		)
		(fp_line
			(start 1.549908 -2.050034)
			(end -1.549908 -2.050034)
			(stroke
				(width 0.1)
				(type default)
			)
			(layer "F.Fab")
		)
		(fp_line
			(start 1.549908 2.050034)
			(end 1.549908 -2.050034)
			(stroke
				(width 0.1)
				(type default)
			)
			(layer "F.Fab")
		)
		(fp_poly
			(pts
				(xy -2.9464 -2.208022) (xy -2.9464 -1.192022) (xy -1.9304 -1.700022)
			)
			(stroke
				(width 0)
				(type default)
			)
			(fill yes)
			(layer "F.Fab")
		)
		(pad "1" smd circle
			(at -1.35001 -1.700022)
			(size 0 0)
			(layers "F.Cu" "F.Mask" "F.Paste")
			(net "SW_PVPP_HBM_CPU0_BST")
		)
		(pad "2" smd rect
			(at -1.400048 -1.199896 90)
			(size 0.1778 0.8128)
			(layers "F.Cu" "F.Mask" "F.Paste")
			(net "GND")
		)
		(pad "3" smd rect
			(at -1.400048 -0.8001 90)
			(size 0.1778 0.8128)
			(layers "F.Cu" "F.Mask" "F.Paste")
			(net "PVPP_HBM_CPU0_CS")
		)
		(pad "4" smd rect
			(at -1.400048 -0.40005 90)
			(size 0.1778 0.8128)
			(layers "F.Cu" "F.Mask" "F.Paste")
			(net "PVPP_HBM_CPU0_MODE")
		)
		(pad "5" smd rect
			(at -1.400048 0 90)
			(size 0.1778 0.8128)
			(layers "F.Cu" "F.Mask" "F.Paste")
			(net "PVPP_HBM_CPU0_REF")
		)
		(pad "6" smd rect
			(at -1.400048 0.40005 90)
			(size 0.1778 0.8128)
			(layers "F.Cu" "F.Mask" "F.Paste")
			(net "SH_PVPP_HBM_CPU0_N")
		)
		(pad "7" smd rect
			(at -1.400048 0.8001 90)
			(size 0.1778 0.8128)
			(layers "F.Cu" "F.Mask" "F.Paste")
			(net "PVPP_HBM_CPU0_FB")
		)
		(pad "8" smd rect
			(at -1.400048 1.199896 90)
			(size 0.1778 0.8128)
			(layers "F.Cu" "F.Mask" "F.Paste")
			(net "FM_PVPP_HBM_CPU0_EN")
		)
		(pad "9" smd rect
			(at -1.400048 1.700022 90)
			(size 0.3048 0.8128)
			(layers "F.Cu" "F.Mask" "F.Paste")
			(net "PWRGD_PVPP_HBM_CPU0_R")
		)
		(pad "10" smd rect
			(at -0.299974 1.299972)
			(size 0.3048 2.0066)
			(layers "F.Cu" "F.Mask" "F.Paste")
			(net "SW_P12V_PVCCIN_CPU0_FLT")
		)
		(pad "11_18" smd circle
			(at 1.175004 0.275082)
			(size 0 0)
			(layers "F.Cu" "F.Mask" "F.Paste")
			(net "GND")
		)
		(pad "19" smd rect
			(at 1.400048 -1.700022 270)
			(size 0.3048 0.8128)
			(layers "F.Cu" "F.Mask" "F.Paste")
			(net "PVPP_HBM_CPU0_VCC")
		)
		(pad "20" smd rect
			(at 0.299974 -1.299972)
			(size 0.3048 2.0066)
			(layers "F.Cu" "F.Mask" "F.Paste")
			(net "SW_PVPP_HBM_CPU0_SW")
		)
		(pad "21" smd rect
			(at -0.299974 -1.299972)
			(size 0.3048 2.0066)
			(layers "F.Cu" "F.Mask" "F.Paste")
			(net "SW_P12V_PVCCIN_CPU0_FLT")
		)
	)
	(footprint ""
		(layer "F.Cu")
		(at 190.4238 -42.554398)
		(property "Reference" "R4071"
			(at 0 0 0)
			(layer "F.SilkS")
			(hide yes)
			(effects
				(font
					(size 1.27 1.27)
				)
			)
		)
		(property "Value" ""
			(at 0 0 0)
			(layer "F.Fab")
			(effects
				(font
					(size 1.27 1.27)
				)
			)
		)
		(duplicate_pad_numbers_are_jumpers no)
		(fp_line
			(start -0.7874 -0.4064)
			(end 0.7874 -0.4064)
			(stroke
				(width 0.1524)
				(type default)
			)
			(layer "F.SilkS")
		)
		(fp_line
			(start -0.7874 0.4064)
			(end -0.7874 -0.4064)
			(stroke
				(width 0.1524)
				(type default)
			)
			(layer "F.SilkS")
		)
		(fp_line
			(start 0.7874 -0.4064)
			(end 0.7874 0.4064)
			(stroke
				(width 0.1524)
				(type default)
			)
			(layer "F.SilkS")
		)
		(fp_line
			(start 0.7874 0.4064)
			(end -0.7874 0.4064)
			(stroke
				(width 0.1524)
				(type default)
			)
			(layer "F.SilkS")
		)
		(fp_line
			(start -0.67945 -0.305054)
			(end -0.12065 -0.305054)
			(stroke
				(width 0.1)
				(type default)
			)
			(layer "F.Fab")
		)
		(fp_line
			(start -0.67945 0.3048)
			(end -0.67945 -0.305054)
			(stroke
				(width 0.1)
				(type default)
			)
			(layer "F.Fab")
		)
		(fp_line
			(start -0.12065 -0.305054)
			(end -0.12065 -0.2794)
			(stroke
				(width 0.1)
				(type default)
			)
			(layer "F.Fab")
		)
		(fp_line
			(start -0.12065 -0.2794)
			(end 0.12065 -0.2794)
			(stroke
				(width 0.1)
				(type default)
			)
			(layer "F.Fab")
		)
		(fp_line
			(start -0.12065 0.2794)
			(end -0.12065 0.3048)
			(stroke
				(width 0.1)
				(type default)
			)
			(layer "F.Fab")
		)
		(fp_line
			(start -0.12065 0.3048)
			(end -0.67945 0.3048)
			(stroke
				(width 0.1)
				(type default)
			)
			(layer "F.Fab")
		)
		(fp_line
			(start 0.120396 0.2794)
			(end -0.12065 0.2794)
			(stroke
				(width 0.1)
				(type default)
			)
			(layer "F.Fab")
		)
		(fp_line
			(start 0.120396 0.3048)
			(end 0.120396 0.2794)
			(stroke
				(width 0.1)
				(type default)
			)
			(layer "F.Fab")
		)
		(fp_line
			(start 0.12065 -0.3048)
			(end 0.67945 -0.3048)
			(stroke
				(width 0.1)
				(type default)
			)
			(layer "F.Fab")
		)
		(fp_line
			(start 0.12065 -0.2794)
			(end 0.12065 -0.3048)
			(stroke
				(width 0.1)
				(type default)
			)
			(layer "F.Fab")
		)
		(fp_line
			(start 0.67945 -0.3048)
			(end 0.67945 0.3048)
			(stroke
				(width 0.1)
				(type default)
			)
			(layer "F.Fab")
		)
		(fp_line
			(start 0.67945 0.3048)
			(end 0.120396 0.3048)
			(stroke
				(width 0.1)
				(type default)
			)
			(layer "F.Fab")
		)
		(pad "1" smd circle
			(at -0.40005 0)
			(size 0 0)
			(layers "F.Cu" "F.Mask" "F.Paste")
			(net "P12V_AUX")
		)
		(pad "2" smd circle
			(at 0.40005 0)
			(size 0 0)
			(layers "F.Cu" "F.Mask" "F.Paste")
			(net "P12V_SCM_EN_G")
		)
	)
	(footprint ""
		(layer "F.Cu")
		(at 116.561616 -255.0541 90)
		(property "Reference" "C305"
			(at 0 0 90)
			(layer "F.SilkS")
			(hide yes)
			(effects
				(font
					(size 1.27 1.27)
				)
			)
		)
		(property "Value" ""
			(at 0 0 90)
			(layer "F.Fab")
			(effects
				(font
					(size 1.27 1.27)
				)
			)
		)
		(duplicate_pad_numbers_are_jumpers no)
		(fp_line
			(start 0.7874 -0.4064)
			(end 0.7874 0.4064)
			(stroke
				(width 0.1524)
				(type default)
			)
			(layer "F.SilkS")
		)
		(fp_line
			(start -0.7874 -0.4064)
			(end 0.7874 -0.4064)
			(stroke
				(width 0.1524)
				(type default)
			)
			(layer "F.SilkS")
		)
		(fp_line
			(start 0.7874 0.4064)
			(end -0.7874 0.4064)
			(stroke
				(width 0.1524)
				(type default)
			)
			(layer "F.SilkS")
		)
		(fp_line
			(start -0.7874 0.4064)
			(end -0.7874 -0.4064)
			(stroke
				(width 0.1524)
				(type default)
			)
			(layer "F.SilkS")
		)
		(fp_line
			(start -0.12065 -0.305054)
			(end -0.12065 -0.2794)
			(stroke
				(width 0.1)
				(type default)
			)
			(layer "F.Fab")
		)
		(fp_line
			(start -0.67945 -0.305054)
			(end -0.12065 -0.305054)
			(stroke
				(width 0.1)
				(type default)
			)
			(layer "F.Fab")
		)
		(fp_line
			(start 0.67945 -0.3048)
			(end 0.67945 0.3048)
			(stroke
				(width 0.1)
				(type default)
			)
			(layer "F.Fab")
		)
		(fp_line
			(start 0.12065 -0.3048)
			(end 0.67945 -0.3048)
			(stroke
				(width 0.1)
				(type default)
			)
			(layer "F.Fab")
		)
		(fp_line
			(start 0.12065 -0.2794)
			(end 0.12065 -0.3048)
			(stroke
				(width 0.1)
				(type default)
			)
			(layer "F.Fab")
		)
		(fp_line
			(start -0.12065 -0.2794)
			(end 0.12065 -0.2794)
			(stroke
				(width 0.1)
				(type default)
			)
			(layer "F.Fab")
		)
		(fp_line
			(start 0.120396 0.2794)
			(end -0.12065 0.2794)
			(stroke
				(width 0.1)
				(type default)
			)
			(layer "F.Fab")
		)
		(fp_line
			(start -0.12065 0.2794)
			(end -0.12065 0.3048)
			(stroke
				(width 0.1)
				(type default)
			)
			(layer "F.Fab")
		)
		(fp_line
			(start 0.67945 0.3048)
			(end 0.120396 0.3048)
			(stroke
				(width 0.1)
				(type default)
			)
			(layer "F.Fab")
		)
		(fp_line
			(start 0.120396 0.3048)
			(end 0.120396 0.2794)
			(stroke
				(width 0.1)
				(type default)
			)
			(layer "F.Fab")
		)
		(fp_line
			(start -0.12065 0.3048)
			(end -0.67945 0.3048)
			(stroke
				(width 0.1)
				(type default)
			)
			(layer "F.Fab")
		)
		(fp_line
			(start -0.67945 0.3048)
			(end -0.67945 -0.305054)
			(stroke
				(width 0.1)
				(type default)
			)
			(layer "F.Fab")
		)
		(pad "1" smd circle
			(at -0.40005 0 90)
			(size 0 0)
			(layers "F.Cu" "F.Mask" "F.Paste")
			(net "PVCCIN_CPU1")
		)
		(pad "2" smd circle
			(at 0.40005 0 90)
			(size 0 0)
			(layers "F.Cu" "F.Mask" "F.Paste")
			(net "GND")
		)
	)
	(footprint ""
		(layer "F.Cu")
		(at 354.261928 -260.364986 -90)
		(property "Reference" "C400"
			(at 0 0 270)
			(layer "F.SilkS")
			(hide yes)
			(effects
				(font
					(size 1.27 1.27)
				)
			)
		)
		(property "Value" ""
			(at 0 0 270)
			(layer "F.Fab")
			(effects
				(font
					(size 1.27 1.27)
				)
			)
		)
		(duplicate_pad_numbers_are_jumpers no)
		(fp_line
			(start -0.7874 0.4064)
			(end -0.7874 -0.4064)
			(stroke
				(width 0.1524)
				(type default)
			)
			(layer "F.SilkS")
		)
		(fp_line
			(start 0.7874 0.4064)
			(end -0.7874 0.4064)
			(stroke
				(width 0.1524)
				(type default)
			)
			(layer "F.SilkS")
		)
		(fp_line
			(start -0.7874 -0.4064)
			(end 0.7874 -0.4064)
			(stroke
				(width 0.1524)
				(type default)
			)
			(layer "F.SilkS")
		)
		(fp_line
			(start 0.7874 -0.4064)
			(end 0.7874 0.4064)
			(stroke
				(width 0.1524)
				(type default)
			)
			(layer "F.SilkS")
		)
		(fp_line
			(start -0.67945 0.3048)
			(end -0.67945 -0.305054)
			(stroke
				(width 0.1)
				(type default)
			)
			(layer "F.Fab")
		)
		(fp_line
			(start -0.12065 0.3048)
			(end -0.67945 0.3048)
			(stroke
				(width 0.1)
				(type default)
			)
			(layer "F.Fab")
		)
		(fp_line
			(start 0.120396 0.3048)
			(end 0.120396 0.2794)
			(stroke
				(width 0.1)
				(type default)
			)
			(layer "F.Fab")
		)
		(fp_line
			(start 0.67945 0.3048)
			(end 0.120396 0.3048)
			(stroke
				(width 0.1)
				(type default)
			)
			(layer "F.Fab")
		)
		(fp_line
			(start -0.12065 0.2794)
			(end -0.12065 0.3048)
			(stroke
				(width 0.1)
				(type default)
			)
			(layer "F.Fab")
		)
		(fp_line
			(start 0.120396 0.2794)
			(end -0.12065 0.2794)
			(stroke
				(width 0.1)
				(type default)
			)
			(layer "F.Fab")
		)
		(fp_line
			(start -0.12065 -0.2794)
			(end 0.12065 -0.2794)
			(stroke
				(width 0.1)
				(type default)
			)
			(layer "F.Fab")
		)
		(fp_line
			(start 0.12065 -0.2794)
			(end 0.12065 -0.3048)
			(stroke
				(width 0.1)
				(type default)
			)
			(layer "F.Fab")
		)
		(fp_line
			(start 0.12065 -0.3048)
			(end 0.67945 -0.3048)
			(stroke
				(width 0.1)
				(type default)
			)
			(layer "F.Fab")
		)
		(fp_line
			(start 0.67945 -0.3048)
			(end 0.67945 0.3048)
			(stroke
				(width 0.1)
				(type default)
			)
			(layer "F.Fab")
		)
		(fp_line
			(start -0.67945 -0.305054)
			(end -0.12065 -0.305054)
			(stroke
				(width 0.1)
				(type default)
			)
			(layer "F.Fab")
		)
		(fp_line
			(start -0.12065 -0.305054)
			(end -0.12065 -0.2794)
			(stroke
				(width 0.1)
				(type default)
			)
			(layer "F.Fab")
		)
		(pad "1" smd circle
			(at -0.40005 0 270)
			(size 0 0)
			(layers "F.Cu" "F.Mask" "F.Paste")
			(net "PVCCFA_EHV_FIVRA_CPU0")
		)
		(pad "2" smd circle
			(at 0.40005 0 270)
			(size 0 0)
			(layers "F.Cu" "F.Mask" "F.Paste")
			(net "GND")
		)
	)
	(footprint ""
		(layer "F.Cu")
		(at 117.526816 -245.634256 -90)
		(property "Reference" "C259"
			(at 0 0 270)
			(layer "F.SilkS")
			(hide yes)
			(effects
				(font
					(size 1.27 1.27)
				)
			)
		)
		(property "Value" ""
			(at 0 0 270)
			(layer "F.Fab")
			(effects
				(font
					(size 1.27 1.27)
				)
			)
		)
		(duplicate_pad_numbers_are_jumpers no)
		(fp_line
			(start -0.7874 0.4064)
			(end -0.7874 -0.4064)
			(stroke
				(width 0.1524)
				(type default)
			)
			(layer "F.SilkS")
		)
		(fp_line
			(start 0.7874 0.4064)
			(end -0.7874 0.4064)
			(stroke
				(width 0.1524)
				(type default)
			)
			(layer "F.SilkS")
		)
		(fp_line
			(start -0.7874 -0.4064)
			(end 0.7874 -0.4064)
			(stroke
				(width 0.1524)
				(type default)
			)
			(layer "F.SilkS")
		)
		(fp_line
			(start 0.7874 -0.4064)
			(end 0.7874 0.4064)
			(stroke
				(width 0.1524)
				(type default)
			)
			(layer "F.SilkS")
		)
		(fp_line
			(start -0.67945 0.3048)
			(end -0.67945 -0.305054)
			(stroke
				(width 0.1)
				(type default)
			)
			(layer "F.Fab")
		)
		(fp_line
			(start -0.12065 0.3048)
			(end -0.67945 0.3048)
			(stroke
				(width 0.1)
				(type default)
			)
			(layer "F.Fab")
		)
		(fp_line
			(start 0.120396 0.3048)
			(end 0.120396 0.2794)
			(stroke
				(width 0.1)
				(type default)
			)
			(layer "F.Fab")
		)
		(fp_line
			(start 0.67945 0.3048)
			(end 0.120396 0.3048)
			(stroke
				(width 0.1)
				(type default)
			)
			(layer "F.Fab")
		)
		(fp_line
			(start -0.12065 0.2794)
			(end -0.12065 0.3048)
			(stroke
				(width 0.1)
				(type default)
			)
			(layer "F.Fab")
		)
		(fp_line
			(start 0.120396 0.2794)
			(end -0.12065 0.2794)
			(stroke
				(width 0.1)
				(type default)
			)
			(layer "F.Fab")
		)
		(fp_line
			(start -0.12065 -0.2794)
			(end 0.12065 -0.2794)
			(stroke
				(width 0.1)
				(type default)
			)
			(layer "F.Fab")
		)
		(fp_line
			(start 0.12065 -0.2794)
			(end 0.12065 -0.3048)
			(stroke
				(width 0.1)
				(type default)
			)
			(layer "F.Fab")
		)
		(fp_line
			(start 0.12065 -0.3048)
			(end 0.67945 -0.3048)
			(stroke
				(width 0.1)
				(type default)
			)
			(layer "F.Fab")
		)
		(fp_line
			(start 0.67945 -0.3048)
			(end 0.67945 0.3048)
			(stroke
				(width 0.1)
				(type default)
			)
			(layer "F.Fab")
		)
		(fp_line
			(start -0.67945 -0.305054)
			(end -0.12065 -0.305054)
			(stroke
				(width 0.1)
				(type default)
			)
			(layer "F.Fab")
		)
		(fp_line
			(start -0.12065 -0.305054)
			(end -0.12065 -0.2794)
			(stroke
				(width 0.1)
				(type default)
			)
			(layer "F.Fab")
		)
		(pad "1" smd circle
			(at -0.40005 0 270)
			(size 0 0)
			(layers "F.Cu" "F.Mask" "F.Paste")
			(net "PVCCIN_CPU1")
		)
		(pad "2" smd circle
			(at 0.40005 0 270)
			(size 0 0)
			(layers "F.Cu" "F.Mask" "F.Paste")
			(net "GND")
		)
	)
	(footprint ""
		(layer "F.Cu")
		(at 457.723748 -114.966496)
		(property "Reference" "U209"
			(at -0.853948 -4.849114 0)
			(unlocked yes)
			(layer "F.SilkS")
			(effects
				(font
					(size 0.7874 0.5842)
					(thickness 0.1524)
				)
				(justify left)
			)
		)
		(property "Value" ""
			(at 0 0 0)
			(layer "F.Fab")
			(effects
				(font
					(size 1.27 1.27)
				)
			)
		)
		(duplicate_pad_numbers_are_jumpers no)
		(fp_line
			(start -2.097532 -3.949954)
			(end -2.097532 3.949954)
			(stroke
				(width 0.1524)
				(type default)
			)
			(layer "F.SilkS")
		)
		(fp_line
			(start -2.097532 3.949954)
			(end 2.097532 3.949954)
			(stroke
				(width 0.1524)
				(type default)
			)
			(layer "F.SilkS")
		)
		(fp_line
			(start -1.409954 -3.949954)
			(end -2.097532 -3.949954)
			(stroke
				(width 0.1524)
				(type default)
			)
			(layer "F.SilkS")
		)
		(fp_line
			(start 0 -2.54)
			(end -1.409954 -3.949954)
			(stroke
				(width 0.1524)
				(type default)
			)
			(layer "F.SilkS")
		)
		(fp_line
			(start 1.409954 -3.949954)
			(end 0 -2.54)
			(stroke
				(width 0.1524)
				(type default)
			)
			(layer "F.SilkS")
		)
		(fp_line
			(start 2.097532 -3.949954)
			(end 1.409954 -3.949954)
			(stroke
				(width 0.1524)
				(type default)
			)
			(layer "F.SilkS")
		)
		(fp_line
			(start 2.097532 3.949954)
			(end 2.097532 -3.949954)
			(stroke
				(width 0.1524)
				(type default)
			)
			(layer "F.SilkS")
		)
		(fp_poly
			(pts
				(xy -4.7498 -4.182872) (xy -4.7498 -3.166872) (xy -3.7338 -3.674872)
			)
			(stroke
				(width 0)
				(type default)
			)
			(fill yes)
			(layer "F.SilkS")
		)
		(fp_line
			(start -2.249932 -3.949954)
			(end -2.249932 3.949954)
			(stroke
				(width 0.1)
				(type default)
			)
			(layer "F.Fab")
		)
		(fp_line
			(start -2.249932 3.949954)
			(end 2.249932 3.949954)
			(stroke
				(width 0.1)
				(type default)
			)
			(layer "F.Fab")
		)
		(fp_line
			(start 2.249932 -3.949954)
			(end -2.249932 -3.949954)
			(stroke
				(width 0.1)
				(type default)
			)
			(layer "F.Fab")
		)
		(fp_line
			(start 2.249932 3.949954)
			(end 2.249932 -3.949954)
			(stroke
				(width 0.1)
				(type default)
			)
			(layer "F.Fab")
		)
		(fp_poly
			(pts
				(xy -4.7498 -4.182872) (xy -4.7498 -3.166872) (xy -3.7338 -3.674872)
			)
			(stroke
				(width 0)
				(type default)
			)
			(fill yes)
			(layer "F.Fab")
		)
		(pad "1" smd rect
			(at -2.925064 -3.674872 270)
			(size 0.6096 1.3716)
			(layers "F.Cu" "F.Mask" "F.Paste")
			(net "FM_SMB_CPU0_ALERT")
		)
		(pad "2" smd rect
			(at -2.925064 -2.925064 270)
			(size 0.4064 1.3716)
			(layers "F.Cu" "F.Mask" "F.Paste")
			(net "PD_SMB_OCP1_HP_ADD1")
		)
		(pad "3" smd rect
			(at -2.925064 -2.275078 270)
			(size 0.4064 1.3716)
			(layers "F.Cu" "F.Mask" "F.Paste")
			(net "PD_SMB_OCP1_HP_ADD2")
		)
		(pad "4" smd rect
			(at -2.925064 -1.625092 270)
			(size 0.4064 1.3716)
			(layers "F.Cu" "F.Mask" "F.Paste")
			(net "TP_PCA9555_0_P00")
		)
		(pad "5" smd rect
			(at -2.925064 -0.975106 270)
			(size 0.4064 1.3716)
			(layers "F.Cu" "F.Mask" "F.Paste")
			(net "TP_PCA9555_0_P01")
		)
		(pad "6" smd rect
			(at -2.925064 -0.32512 270)
			(size 0.4064 1.3716)
			(layers "F.Cu" "F.Mask" "F.Paste")
			(net "HP_OCP_V3_1_EN")
		)
		(pad "7" smd rect
			(at -2.925064 0.32512 270)
			(size 0.4064 1.3716)
			(layers "F.Cu" "F.Mask" "F.Paste")
			(net "HP_LVC3_OCP_V3_1_ATTN_OUT_SW_N")
		)
		(pad "8" smd rect
			(at -2.925064 0.975106 270)
			(size 0.4064 1.3716)
			(layers "F.Cu" "F.Mask" "F.Paste")
			(net "HP_LVC3_OCP_V3_1_PRSNT2_N")
		)
		(pad "9" smd rect
			(at -2.925064 1.625092 270)
			(size 0.4064 1.3716)
			(layers "F.Cu" "F.Mask" "F.Paste")
			(net "TP_PCA9555_0_P5")
		)
		(pad "10" smd rect
			(at -2.925064 2.275078 270)
			(size 0.4064 1.3716)
			(layers "F.Cu" "F.Mask" "F.Paste")
			(net "TP_PCA9555_0_P6")
		)
		(pad "11" smd rect
			(at -2.925064 2.925064 270)
			(size 0.4064 1.3716)
			(layers "F.Cu" "F.Mask" "F.Paste")
			(net "TP_PCA9555_0_P7")
		)
		(pad "12" smd rect
			(at -2.925064 3.674872 270)
			(size 0.6096 1.3716)
			(layers "F.Cu" "F.Mask" "F.Paste")
			(net "GND")
		)
		(pad "13" smd rect
			(at 2.925064 3.674872 270)
			(size 0.6096 1.3716)
			(layers "F.Cu" "F.Mask" "F.Paste")
			(net "TP_PCA9555_0_P10")
		)
		(pad "14" smd rect
			(at 2.925064 2.925064 270)
			(size 0.4064 1.3716)
			(layers "F.Cu" "F.Mask" "F.Paste")
			(net "TP_PCA9555_0_P11")
		)
		(pad "15" smd rect
			(at 2.925064 2.275078 270)
			(size 0.4064 1.3716)
			(layers "F.Cu" "F.Mask" "F.Paste")
			(net "TP_PCA9555_0_P12")
		)
		(pad "16" smd rect
			(at 2.925064 1.625092 270)
			(size 0.4064 1.3716)
			(layers "F.Cu" "F.Mask" "F.Paste")
			(net "TP_PCA9555_0_P13")
		)
		(pad "17" smd rect
			(at 2.925064 0.975106 270)
			(size 0.4064 1.3716)
			(layers "F.Cu" "F.Mask" "F.Paste")
			(net "TP_PCA9555_0_P14")
		)
		(pad "18" smd rect
			(at 2.925064 0.32512 270)
			(size 0.4064 1.3716)
			(layers "F.Cu" "F.Mask" "F.Paste")
			(net "TP_PCA9555_0_P15")
		)
		(pad "19" smd rect
			(at 2.925064 -0.32512 270)
			(size 0.4064 1.3716)
			(layers "F.Cu" "F.Mask" "F.Paste")
			(net "TP_PCA9555_0_P16")
		)
		(pad "20" smd rect
			(at 2.925064 -0.975106 270)
			(size 0.4064 1.3716)
			(layers "F.Cu" "F.Mask" "F.Paste")
			(net "TP_PCA9555_0_P17")
		)
		(pad "21" smd rect
			(at 2.925064 -1.625092 270)
			(size 0.4064 1.3716)
			(layers "F.Cu" "F.Mask" "F.Paste")
			(net "PD_SMB_OCP1_HP_ADD0")
		)
		(pad "22" smd rect
			(at 2.925064 -2.275078 270)
			(size 0.4064 1.3716)
			(layers "F.Cu" "F.Mask" "F.Paste")
			(net "SMB_PEHPCPU0_LVC3_R_SCL")
		)
		(pad "23" smd rect
			(at 2.925064 -2.925064 270)
			(size 0.4064 1.3716)
			(layers "F.Cu" "F.Mask" "F.Paste")
			(net "SMB_PEHPCPU0_LVC3_R_SDA")
		)
		(pad "24" smd rect
			(at 2.925064 -3.674872 270)
			(size 0.6096 1.3716)
			(layers "F.Cu" "F.Mask" "F.Paste")
			(net "P3V3_AUX")
		)
	)
	(footprint ""
		(layer "F.Cu")
		(at 46.828964 -104.279446)
		(property "Reference" "C1768"
			(at 0 0 0)
			(layer "F.SilkS")
			(hide yes)
			(effects
				(font
					(size 1.27 1.27)
				)
			)
		)
		(property "Value" ""
			(at 0 0 0)
			(layer "F.Fab")
			(effects
				(font
					(size 1.27 1.27)
				)
			)
		)
		(duplicate_pad_numbers_are_jumpers no)
		(fp_line
			(start -1.524 -0.762)
			(end 1.524 -0.762)
			(stroke
				(width 0.1524)
				(type default)
			)
			(layer "F.SilkS")
		)
		(fp_line
			(start -1.524 0.762)
			(end -1.524 -0.762)
			(stroke
				(width 0.1524)
				(type default)
			)
			(layer "F.SilkS")
		)
		(fp_line
			(start 1.524 -0.762)
			(end 1.524 0.762)
			(stroke
				(width 0.1524)
				(type default)
			)
			(layer "F.SilkS")
		)
		(fp_line
			(start 1.524 0.762)
			(end -1.524 0.762)
			(stroke
				(width 0.1524)
				(type default)
			)
			(layer "F.SilkS")
		)
		(fp_line
			(start -1.1049 -0.724916)
			(end -1.1049 0.724916)
			(stroke
				(width 0.1)
				(type default)
			)
			(layer "F.Fab")
		)
		(fp_line
			(start -1.1049 0.724916)
			(end 1.1049 0.724916)
			(stroke
				(width 0.1)
				(type default)
			)
			(layer "F.Fab")
		)
		(fp_line
			(start 1.1049 -0.724916)
			(end -1.1049 -0.724916)
			(stroke
				(width 0.1)
				(type default)
			)
			(layer "F.Fab")
		)
		(fp_line
			(start 1.1049 0.724916)
			(end 1.1049 -0.724916)
			(stroke
				(width 0.1)
				(type default)
			)
			(layer "F.Fab")
		)
		(pad "1" smd rect
			(at -0.889 0 180)
			(size 1.016 1.27)
			(layers "F.Cu" "F.Mask" "F.Paste")
			(net "P3V3_MAX11617_VDD")
		)
		(pad "2" smd rect
			(at 0.889 0 180)
			(size 1.016 1.27)
			(layers "F.Cu" "F.Mask" "F.Paste")
			(net "GND")
		)
	)
	(footprint ""
		(layer "F.Cu")
		(at 180.42128 -358.698292)
		(property "Reference" "PR1305"
			(at 0 0 0)
			(layer "F.SilkS")
			(hide yes)
			(effects
				(font
					(size 1.27 1.27)
				)
			)
		)
		(property "Value" ""
			(at 0 0 0)
			(layer "F.Fab")
			(effects
				(font
					(size 1.27 1.27)
				)
			)
		)
		(duplicate_pad_numbers_are_jumpers no)
		(fp_line
			(start -0.7874 -0.4064)
			(end 0.7874 -0.4064)
			(stroke
				(width 0.1524)
				(type default)
			)
			(layer "F.SilkS")
		)
		(fp_line
			(start -0.7874 0.4064)
			(end -0.7874 -0.4064)
			(stroke
				(width 0.1524)
				(type default)
			)
			(layer "F.SilkS")
		)
		(fp_line
			(start 0.7874 -0.4064)
			(end 0.7874 0.4064)
			(stroke
				(width 0.1524)
				(type default)
			)
			(layer "F.SilkS")
		)
		(fp_line
			(start 0.7874 0.4064)
			(end -0.7874 0.4064)
			(stroke
				(width 0.1524)
				(type default)
			)
			(layer "F.SilkS")
		)
		(fp_line
			(start -0.67945 -0.305054)
			(end -0.12065 -0.305054)
			(stroke
				(width 0.1)
				(type default)
			)
			(layer "F.Fab")
		)
		(fp_line
			(start -0.67945 0.3048)
			(end -0.67945 -0.305054)
			(stroke
				(width 0.1)
				(type default)
			)
			(layer "F.Fab")
		)
		(fp_line
			(start -0.12065 -0.305054)
			(end -0.12065 -0.2794)
			(stroke
				(width 0.1)
				(type default)
			)
			(layer "F.Fab")
		)
		(fp_line
			(start -0.12065 -0.2794)
			(end 0.12065 -0.2794)
			(stroke
				(width 0.1)
				(type default)
			)
			(layer "F.Fab")
		)
		(fp_line
			(start -0.12065 0.2794)
			(end -0.12065 0.3048)
			(stroke
				(width 0.1)
				(type default)
			)
			(layer "F.Fab")
		)
		(fp_line
			(start -0.12065 0.3048)
			(end -0.67945 0.3048)
			(stroke
				(width 0.1)
				(type default)
			)
			(layer "F.Fab")
		)
		(fp_line
			(start 0.120396 0.2794)
			(end -0.12065 0.2794)
			(stroke
				(width 0.1)
				(type default)
			)
			(layer "F.Fab")
		)
		(fp_line
			(start 0.120396 0.3048)
			(end 0.120396 0.2794)
			(stroke
				(width 0.1)
				(type default)
			)
			(layer "F.Fab")
		)
		(fp_line
			(start 0.12065 -0.3048)
			(end 0.67945 -0.3048)
			(stroke
				(width 0.1)
				(type default)
			)
			(layer "F.Fab")
		)
		(fp_line
			(start 0.12065 -0.2794)
			(end 0.12065 -0.3048)
			(stroke
				(width 0.1)
				(type default)
			)
			(layer "F.Fab")
		)
		(fp_line
			(start 0.67945 -0.3048)
			(end 0.67945 0.3048)
			(stroke
				(width 0.1)
				(type default)
			)
			(layer "F.Fab")
		)
		(fp_line
			(start 0.67945 0.3048)
			(end 0.120396 0.3048)
			(stroke
				(width 0.1)
				(type default)
			)
			(layer "F.Fab")
		)
		(pad "1" smd circle
			(at -0.40005 0)
			(size 0 0)
			(layers "F.Cu" "F.Mask" "F.Paste")
			(net "PVCCFA_EHV_FIVRA_CPU1_LSET3")
		)
		(pad "2" smd circle
			(at 0.40005 0)
			(size 0 0)
			(layers "F.Cu" "F.Mask" "F.Paste")
			(net "GND")
		)
	)
	(footprint ""
		(layer "F.Cu")
		(at 447.565272 -19.506438)
		(property "Reference" "PC2087"
			(at 0 0 0)
			(layer "F.SilkS")
			(hide yes)
			(effects
				(font
					(size 1.27 1.27)
				)
			)
		)
		(property "Value" ""
			(at 0 0 0)
			(layer "F.Fab")
			(effects
				(font
					(size 1.27 1.27)
				)
			)
		)
		(duplicate_pad_numbers_are_jumpers no)
		(fp_line
			(start -0.7874 -0.4064)
			(end 0.7874 -0.4064)
			(stroke
				(width 0.1524)
				(type default)
			)
			(layer "F.SilkS")
		)
		(fp_line
			(start -0.7874 0.4064)
			(end -0.7874 -0.4064)
			(stroke
				(width 0.1524)
				(type default)
			)
			(layer "F.SilkS")
		)
		(fp_line
			(start 0.7874 -0.4064)
			(end 0.7874 0.4064)
			(stroke
				(width 0.1524)
				(type default)
			)
			(layer "F.SilkS")
		)
		(fp_line
			(start 0.7874 0.4064)
			(end -0.7874 0.4064)
			(stroke
				(width 0.1524)
				(type default)
			)
			(layer "F.SilkS")
		)
		(fp_line
			(start -0.67945 -0.305054)
			(end -0.12065 -0.305054)
			(stroke
				(width 0.1)
				(type default)
			)
			(layer "F.Fab")
		)
		(fp_line
			(start -0.67945 0.3048)
			(end -0.67945 -0.305054)
			(stroke
				(width 0.1)
				(type default)
			)
			(layer "F.Fab")
		)
		(fp_line
			(start -0.12065 -0.305054)
			(end -0.12065 -0.2794)
			(stroke
				(width 0.1)
				(type default)
			)
			(layer "F.Fab")
		)
		(fp_line
			(start -0.12065 -0.2794)
			(end 0.12065 -0.2794)
			(stroke
				(width 0.1)
				(type default)
			)
			(layer "F.Fab")
		)
		(fp_line
			(start -0.12065 0.2794)
			(end -0.12065 0.3048)
			(stroke
				(width 0.1)
				(type default)
			)
			(layer "F.Fab")
		)
		(fp_line
			(start -0.12065 0.3048)
			(end -0.67945 0.3048)
			(stroke
				(width 0.1)
				(type default)
			)
			(layer "F.Fab")
		)
		(fp_line
			(start 0.120396 0.2794)
			(end -0.12065 0.2794)
			(stroke
				(width 0.1)
				(type default)
			)
			(layer "F.Fab")
		)
		(fp_line
			(start 0.120396 0.3048)
			(end 0.120396 0.2794)
			(stroke
				(width 0.1)
				(type default)
			)
			(layer "F.Fab")
		)
		(fp_line
			(start 0.12065 -0.3048)
			(end 0.67945 -0.3048)
			(stroke
				(width 0.1)
				(type default)
			)
			(layer "F.Fab")
		)
		(fp_line
			(start 0.12065 -0.2794)
			(end 0.12065 -0.3048)
			(stroke
				(width 0.1)
				(type default)
			)
			(layer "F.Fab")
		)
		(fp_line
			(start 0.67945 -0.3048)
			(end 0.67945 0.3048)
			(stroke
				(width 0.1)
				(type default)
			)
			(layer "F.Fab")
		)
		(fp_line
			(start 0.67945 0.3048)
			(end 0.120396 0.3048)
			(stroke
				(width 0.1)
				(type default)
			)
			(layer "F.Fab")
		)
		(pad "1" smd circle
			(at -0.40005 0)
			(size 0 0)
			(layers "F.Cu" "F.Mask" "F.Paste")
			(net "GND")
		)
		(pad "2" smd circle
			(at 0.40005 0)
			(size 0 0)
			(layers "F.Cu" "F.Mask" "F.Paste")
			(net "P12V_OCP_REG_1")
		)
	)
	(footprint ""
		(layer "F.Cu")
		(at 136.3853 -113.384584)
		(property "Reference" "R4756"
			(at 0 0 0)
			(layer "F.SilkS")
			(hide yes)
			(effects
				(font
					(size 1.27 1.27)
				)
			)
		)
		(property "Value" ""
			(at 0 0 0)
			(layer "F.Fab")
			(effects
				(font
					(size 1.27 1.27)
				)
			)
		)
		(duplicate_pad_numbers_are_jumpers no)
		(fp_line
			(start -0.7874 -0.4064)
			(end 0.7874 -0.4064)
			(stroke
				(width 0.1524)
				(type default)
			)
			(layer "F.SilkS")
		)
		(fp_line
			(start -0.7874 0.4064)
			(end -0.7874 -0.4064)
			(stroke
				(width 0.1524)
				(type default)
			)
			(layer "F.SilkS")
		)
		(fp_line
			(start 0.7874 -0.4064)
			(end 0.7874 0.4064)
			(stroke
				(width 0.1524)
				(type default)
			)
			(layer "F.SilkS")
		)
		(fp_line
			(start 0.7874 0.4064)
			(end -0.7874 0.4064)
			(stroke
				(width 0.1524)
				(type default)
			)
			(layer "F.SilkS")
		)
		(fp_line
			(start -0.67945 -0.305054)
			(end -0.12065 -0.305054)
			(stroke
				(width 0.1)
				(type default)
			)
			(layer "F.Fab")
		)
		(fp_line
			(start -0.67945 0.3048)
			(end -0.67945 -0.305054)
			(stroke
				(width 0.1)
				(type default)
			)
			(layer "F.Fab")
		)
		(fp_line
			(start -0.12065 -0.305054)
			(end -0.12065 -0.2794)
			(stroke
				(width 0.1)
				(type default)
			)
			(layer "F.Fab")
		)
		(fp_line
			(start -0.12065 -0.2794)
			(end 0.12065 -0.2794)
			(stroke
				(width 0.1)
				(type default)
			)
			(layer "F.Fab")
		)
		(fp_line
			(start -0.12065 0.2794)
			(end -0.12065 0.3048)
			(stroke
				(width 0.1)
				(type default)
			)
			(layer "F.Fab")
		)
		(fp_line
			(start -0.12065 0.3048)
			(end -0.67945 0.3048)
			(stroke
				(width 0.1)
				(type default)
			)
			(layer "F.Fab")
		)
		(fp_line
			(start 0.120396 0.2794)
			(end -0.12065 0.2794)
			(stroke
				(width 0.1)
				(type default)
			)
			(layer "F.Fab")
		)
		(fp_line
			(start 0.120396 0.3048)
			(end 0.120396 0.2794)
			(stroke
				(width 0.1)
				(type default)
			)
			(layer "F.Fab")
		)
		(fp_line
			(start 0.12065 -0.3048)
			(end 0.67945 -0.3048)
			(stroke
				(width 0.1)
				(type default)
			)
			(layer "F.Fab")
		)
		(fp_line
			(start 0.12065 -0.2794)
			(end 0.12065 -0.3048)
			(stroke
				(width 0.1)
				(type default)
			)
			(layer "F.Fab")
		)
		(fp_line
			(start 0.67945 -0.3048)
			(end 0.67945 0.3048)
			(stroke
				(width 0.1)
				(type default)
			)
			(layer "F.Fab")
		)
		(fp_line
			(start 0.67945 0.3048)
			(end 0.120396 0.3048)
			(stroke
				(width 0.1)
				(type default)
			)
			(layer "F.Fab")
		)
		(pad "1" smd circle
			(at -0.40005 0)
			(size 0 0)
			(layers "F.Cu" "F.Mask" "F.Paste")
			(net "P3V3_AUX")
		)
		(pad "2" smd circle
			(at 0.40005 0)
			(size 0 0)
			(layers "F.Cu" "F.Mask" "F.Paste")
			(net "OCP_V3_2_AUX_PWR_PLD_EN_R")
		)
	)
	(footprint ""
		(layer "F.Cu")
		(at 415.62909 -408.517344 -90)
		(property "Reference" "C898"
			(at 0 0 270)
			(layer "F.SilkS")
			(hide yes)
			(effects
				(font
					(size 1.27 1.27)
				)
			)
		)
		(property "Value" ""
			(at 0 0 270)
			(layer "F.Fab")
			(effects
				(font
					(size 1.27 1.27)
				)
			)
		)
		(duplicate_pad_numbers_are_jumpers no)
		(fp_line
			(start -0.299974 0.150114)
			(end -0.299974 -0.150114)
			(stroke
				(width 0.1)
				(type default)
			)
			(layer "F.Fab")
		)
		(fp_line
			(start 0.299974 0.150114)
			(end -0.299974 0.150114)
			(stroke
				(width 0.1)
				(type default)
			)
			(layer "F.Fab")
		)
		(fp_line
			(start -0.299974 -0.150114)
			(end 0.299974 -0.150114)
			(stroke
				(width 0.1)
				(type default)
			)
			(layer "F.Fab")
		)
		(fp_line
			(start 0.299974 -0.150114)
			(end 0.299974 0.150114)
			(stroke
				(width 0.1)
				(type default)
			)
			(layer "F.Fab")
		)
		(pad "1" smd rect
			(at -0.2667 0 270)
			(size 0.3048 0.381)
			(layers "F.Cu" "F.Mask" "F.Paste")
			(net "P5E_CPU0_PE3_TX_C_DN<1>")
		)
		(pad "2" smd rect
			(at 0.2667 0 270)
			(size 0.3048 0.381)
			(layers "F.Cu" "F.Mask" "F.Paste")
			(net "P5E_CPU0_PE3_TX_DN<1>")
		)
	)
	(footprint ""
		(layer "F.Cu")
		(at 142.42288 -42.446448)
		(property "Reference" "R3294"
			(at 0 0 0)
			(layer "F.SilkS")
			(hide yes)
			(effects
				(font
					(size 1.27 1.27)
				)
			)
		)
		(property "Value" ""
			(at 0 0 0)
			(layer "F.Fab")
			(effects
				(font
					(size 1.27 1.27)
				)
			)
		)
		(duplicate_pad_numbers_are_jumpers no)
		(fp_line
			(start -0.7874 -0.4064)
			(end 0.7874 -0.4064)
			(stroke
				(width 0.1524)
				(type default)
			)
			(layer "F.SilkS")
		)
		(fp_line
			(start -0.7874 0.4064)
			(end -0.7874 -0.4064)
			(stroke
				(width 0.1524)
				(type default)
			)
			(layer "F.SilkS")
		)
		(fp_line
			(start 0.7874 -0.4064)
			(end 0.7874 0.4064)
			(stroke
				(width 0.1524)
				(type default)
			)
			(layer "F.SilkS")
		)
		(fp_line
			(start 0.7874 0.4064)
			(end -0.7874 0.4064)
			(stroke
				(width 0.1524)
				(type default)
			)
			(layer "F.SilkS")
		)
		(fp_line
			(start -0.67945 -0.305054)
			(end -0.12065 -0.305054)
			(stroke
				(width 0.1)
				(type default)
			)
			(layer "F.Fab")
		)
		(fp_line
			(start -0.67945 0.3048)
			(end -0.67945 -0.305054)
			(stroke
				(width 0.1)
				(type default)
			)
			(layer "F.Fab")
		)
		(fp_line
			(start -0.12065 -0.305054)
			(end -0.12065 -0.2794)
			(stroke
				(width 0.1)
				(type default)
			)
			(layer "F.Fab")
		)
		(fp_line
			(start -0.12065 -0.2794)
			(end 0.12065 -0.2794)
			(stroke
				(width 0.1)
				(type default)
			)
			(layer "F.Fab")
		)
		(fp_line
			(start -0.12065 0.2794)
			(end -0.12065 0.3048)
			(stroke
				(width 0.1)
				(type default)
			)
			(layer "F.Fab")
		)
		(fp_line
			(start -0.12065 0.3048)
			(end -0.67945 0.3048)
			(stroke
				(width 0.1)
				(type default)
			)
			(layer "F.Fab")
		)
		(fp_line
			(start 0.120396 0.2794)
			(end -0.12065 0.2794)
			(stroke
				(width 0.1)
				(type default)
			)
			(layer "F.Fab")
		)
		(fp_line
			(start 0.120396 0.3048)
			(end 0.120396 0.2794)
			(stroke
				(width 0.1)
				(type default)
			)
			(layer "F.Fab")
		)
		(fp_line
			(start 0.12065 -0.3048)
			(end 0.67945 -0.3048)
			(stroke
				(width 0.1)
				(type default)
			)
			(layer "F.Fab")
		)
		(fp_line
			(start 0.12065 -0.2794)
			(end 0.12065 -0.3048)
			(stroke
				(width 0.1)
				(type default)
			)
			(layer "F.Fab")
		)
		(fp_line
			(start 0.67945 -0.3048)
			(end 0.67945 0.3048)
			(stroke
				(width 0.1)
				(type default)
			)
			(layer "F.Fab")
		)
		(fp_line
			(start 0.67945 0.3048)
			(end 0.120396 0.3048)
			(stroke
				(width 0.1)
				(type default)
			)
			(layer "F.Fab")
		)
		(pad "1" smd circle
			(at -0.40005 0)
			(size 0 0)
			(layers "F.Cu" "F.Mask" "F.Paste")
			(net "LED_M2_SSD_0_ACT_N")
		)
		(pad "2" smd circle
			(at 0.40005 0)
			(size 0 0)
			(layers "F.Cu" "F.Mask" "F.Paste")
			(net "LED_HDD_ACTIVITY_N")
		)
	)
	(footprint ""
		(layer "F.Cu")
		(at 333.20228 -336.935572 -90)
		(property "Reference" "PC250_P0_6"
			(at 0 0 270)
			(layer "F.SilkS")
			(hide yes)
			(effects
				(font
					(size 1.27 1.27)
				)
			)
		)
		(property "Value" ""
			(at 0 0 270)
			(layer "F.Fab")
			(effects
				(font
					(size 1.27 1.27)
				)
			)
		)
		(duplicate_pad_numbers_are_jumpers no)
		(fp_line
			(start -0.7874 0.4064)
			(end -0.7874 -0.4064)
			(stroke
				(width 0.1524)
				(type default)
			)
			(layer "F.SilkS")
		)
		(fp_line
			(start 0.7874 0.4064)
			(end -0.7874 0.4064)
			(stroke
				(width 0.1524)
				(type default)
			)
			(layer "F.SilkS")
		)
		(fp_line
			(start -0.7874 -0.4064)
			(end 0.7874 -0.4064)
			(stroke
				(width 0.1524)
				(type default)
			)
			(layer "F.SilkS")
		)
		(fp_line
			(start 0.7874 -0.4064)
			(end 0.7874 0.4064)
			(stroke
				(width 0.1524)
				(type default)
			)
			(layer "F.SilkS")
		)
		(fp_line
			(start -0.67945 0.3048)
			(end -0.67945 -0.305054)
			(stroke
				(width 0.1)
				(type default)
			)
			(layer "F.Fab")
		)
		(fp_line
			(start -0.12065 0.3048)
			(end -0.67945 0.3048)
			(stroke
				(width 0.1)
				(type default)
			)
			(layer "F.Fab")
		)
		(fp_line
			(start 0.120396 0.3048)
			(end 0.120396 0.2794)
			(stroke
				(width 0.1)
				(type default)
			)
			(layer "F.Fab")
		)
		(fp_line
			(start 0.67945 0.3048)
			(end 0.120396 0.3048)
			(stroke
				(width 0.1)
				(type default)
			)
			(layer "F.Fab")
		)
		(fp_line
			(start -0.12065 0.2794)
			(end -0.12065 0.3048)
			(stroke
				(width 0.1)
				(type default)
			)
			(layer "F.Fab")
		)
		(fp_line
			(start 0.120396 0.2794)
			(end -0.12065 0.2794)
			(stroke
				(width 0.1)
				(type default)
			)
			(layer "F.Fab")
		)
		(fp_line
			(start -0.12065 -0.2794)
			(end 0.12065 -0.2794)
			(stroke
				(width 0.1)
				(type default)
			)
			(layer "F.Fab")
		)
		(fp_line
			(start 0.12065 -0.2794)
			(end 0.12065 -0.3048)
			(stroke
				(width 0.1)
				(type default)
			)
			(layer "F.Fab")
		)
		(fp_line
			(start 0.12065 -0.3048)
			(end 0.67945 -0.3048)
			(stroke
				(width 0.1)
				(type default)
			)
			(layer "F.Fab")
		)
		(fp_line
			(start 0.67945 -0.3048)
			(end 0.67945 0.3048)
			(stroke
				(width 0.1)
				(type default)
			)
			(layer "F.Fab")
		)
		(fp_line
			(start -0.67945 -0.305054)
			(end -0.12065 -0.305054)
			(stroke
				(width 0.1)
				(type default)
			)
			(layer "F.Fab")
		)
		(fp_line
			(start -0.12065 -0.305054)
			(end -0.12065 -0.2794)
			(stroke
				(width 0.1)
				(type default)
			)
			(layer "F.Fab")
		)
		(pad "1" smd circle
			(at -0.40005 0 270)
			(size 0 0)
			(layers "F.Cu" "F.Mask" "F.Paste")
			(net "PVCCIN_CPU0_PVCC")
		)
		(pad "2" smd circle
			(at 0.40005 0 270)
			(size 0 0)
			(layers "F.Cu" "F.Mask" "F.Paste")
			(net "GND")
		)
	)
	(footprint ""
		(layer "F.Cu")
		(at 133.728714 -408.517344 -90)
		(property "Reference" "C1524"
			(at 0 0 270)
			(layer "F.SilkS")
			(hide yes)
			(effects
				(font
					(size 1.27 1.27)
				)
			)
		)
		(property "Value" ""
			(at 0 0 270)
			(layer "F.Fab")
			(effects
				(font
					(size 1.27 1.27)
				)
			)
		)
		(duplicate_pad_numbers_are_jumpers no)
		(fp_line
			(start -0.299974 0.150114)
			(end -0.299974 -0.150114)
			(stroke
				(width 0.1)
				(type default)
			)
			(layer "F.Fab")
		)
		(fp_line
			(start 0.299974 0.150114)
			(end -0.299974 0.150114)
			(stroke
				(width 0.1)
				(type default)
			)
			(layer "F.Fab")
		)
		(fp_line
			(start -0.299974 -0.150114)
			(end 0.299974 -0.150114)
			(stroke
				(width 0.1)
				(type default)
			)
			(layer "F.Fab")
		)
		(fp_line
			(start 0.299974 -0.150114)
			(end 0.299974 0.150114)
			(stroke
				(width 0.1)
				(type default)
			)
			(layer "F.Fab")
		)
		(pad "1" smd rect
			(at -0.2667 0 270)
			(size 0.3048 0.381)
			(layers "F.Cu" "F.Mask" "F.Paste")
			(net "P5E_CPU1_PE3_TX_C_DN<11>")
		)
		(pad "2" smd rect
			(at 0.2667 0 270)
			(size 0.3048 0.381)
			(layers "F.Cu" "F.Mask" "F.Paste")
			(net "P5E_CPU1_PE3_TX_DN<11>")
		)
	)
	(footprint ""
		(layer "F.Cu")
		(at 368.105182 -343.902284 90)
		(property "Reference" "PC321"
			(at 0 0 90)
			(layer "F.SilkS")
			(hide yes)
			(effects
				(font
					(size 1.27 1.27)
				)
			)
		)
		(property "Value" ""
			(at 0 0 90)
			(layer "F.Fab")
			(effects
				(font
					(size 1.27 1.27)
				)
			)
		)
		(duplicate_pad_numbers_are_jumpers no)
		(fp_line
			(start -3.400044 1.249934)
			(end 3.400044 1.249934)
			(stroke
				(width 0.1524)
				(type default)
			)
			(layer "F.SilkS")
		)
		(fp_circle
			(center 0 1.249934)
			(end 0 4.649978)
			(stroke
				(width 0.1524)
				(type default)
			)
			(fill no)
			(layer "F.SilkS")
		)
		(fp_poly
			(pts
				(arc
					(start -3.400044 1.249934)
					(mid 0 4.649978)
					(end 3.400044 1.249934)
				)
			)
			(stroke
				(width 0)
				(type default)
			)
			(fill yes)
			(layer "F.SilkS")
		)
		(fp_circle
			(center 0 1.249934)
			(end 0 4.649978)
			(stroke
				(width 0.1)
				(type default)
			)
			(fill no)
			(layer "F.Fab")
		)
		(pad "1" thru_hole rect
			(at 0 0 90)
			(size 1.524 1.524)
			(drill 1.016)
			(layers "*.Cu" "*.Mask")
			(remove_unused_layers no)
			(net "SW_P12V_PVCCIN_CPU0_FLT")
			(clearance 0)
			(padstack
				(mode front_inner_back)
				(layer "Inner"
					(shape circle)
					(size 1.524 1.524)
					(clearance 0)
				)
				(layer "B.Cu"
					(shape rect)
					(size 1.524 1.524)
					(clearance 0)
				)
			)
		)
		(pad "2" thru_hole circle
			(at 0 2.500122 90)
			(size 1.524 1.524)
			(drill 1.016)
			(layers "*.Cu" "*.Mask")
			(remove_unused_layers no)
			(net "GND")
			(clearance 0)
		)
	)
	(footprint ""
		(layer "F.Cu")
		(at 303.553368 -367.337848)
		(property "Reference" "PC721_P0_2"
			(at 0 0 0)
			(layer "F.SilkS")
			(hide yes)
			(effects
				(font
					(size 1.27 1.27)
				)
			)
		)
		(property "Value" ""
			(at 0 0 0)
			(layer "F.Fab")
			(effects
				(font
					(size 1.27 1.27)
				)
			)
		)
		(duplicate_pad_numbers_are_jumpers no)
		(fp_line
			(start -1.524 -0.762)
			(end 1.524 -0.762)
			(stroke
				(width 0.1524)
				(type default)
			)
			(layer "F.SilkS")
		)
		(fp_line
			(start -1.524 0.762)
			(end -1.524 -0.762)
			(stroke
				(width 0.1524)
				(type default)
			)
			(layer "F.SilkS")
		)
		(fp_line
			(start 1.524 -0.762)
			(end 1.524 0.762)
			(stroke
				(width 0.1524)
				(type default)
			)
			(layer "F.SilkS")
		)
		(fp_line
			(start 1.524 0.762)
			(end -1.524 0.762)
			(stroke
				(width 0.1524)
				(type default)
			)
			(layer "F.SilkS")
		)
		(fp_line
			(start -1.1049 -0.724916)
			(end -1.1049 0.724916)
			(stroke
				(width 0.1)
				(type default)
			)
			(layer "F.Fab")
		)
		(fp_line
			(start -1.1049 0.724916)
			(end 1.1049 0.724916)
			(stroke
				(width 0.1)
				(type default)
			)
			(layer "F.Fab")
		)
		(fp_line
			(start 1.1049 -0.724916)
			(end -1.1049 -0.724916)
			(stroke
				(width 0.1)
				(type default)
			)
			(layer "F.Fab")
		)
		(fp_line
			(start 1.1049 0.724916)
			(end 1.1049 -0.724916)
			(stroke
				(width 0.1)
				(type default)
			)
			(layer "F.Fab")
		)
		(pad "1" smd rect
			(at -0.889 0 180)
			(size 1.016 1.27)
			(layers "F.Cu" "F.Mask" "F.Paste")
			(net "SW_P12V_PVCCFA_EHV_FIVRA_CPU0_L")
		)
		(pad "2" smd rect
			(at 0.889 0 180)
			(size 1.016 1.27)
			(layers "F.Cu" "F.Mask" "F.Paste")
			(net "GND")
		)
	)
	(footprint ""
		(layer "F.Cu")
		(at 107.307634 -247.715278 90)
		(property "Reference" "C295"
			(at 0 0 90)
			(layer "F.SilkS")
			(hide yes)
			(effects
				(font
					(size 1.27 1.27)
				)
			)
		)
		(property "Value" ""
			(at 0 0 90)
			(layer "F.Fab")
			(effects
				(font
					(size 1.27 1.27)
				)
			)
		)
		(duplicate_pad_numbers_are_jumpers no)
		(fp_line
			(start 0.7874 -0.4064)
			(end 0.7874 0.4064)
			(stroke
				(width 0.1524)
				(type default)
			)
			(layer "F.SilkS")
		)
		(fp_line
			(start -0.7874 -0.4064)
			(end 0.7874 -0.4064)
			(stroke
				(width 0.1524)
				(type default)
			)
			(layer "F.SilkS")
		)
		(fp_line
			(start 0.7874 0.4064)
			(end -0.7874 0.4064)
			(stroke
				(width 0.1524)
				(type default)
			)
			(layer "F.SilkS")
		)
		(fp_line
			(start -0.7874 0.4064)
			(end -0.7874 -0.4064)
			(stroke
				(width 0.1524)
				(type default)
			)
			(layer "F.SilkS")
		)
		(fp_line
			(start -0.12065 -0.305054)
			(end -0.12065 -0.2794)
			(stroke
				(width 0.1)
				(type default)
			)
			(layer "F.Fab")
		)
		(fp_line
			(start -0.67945 -0.305054)
			(end -0.12065 -0.305054)
			(stroke
				(width 0.1)
				(type default)
			)
			(layer "F.Fab")
		)
		(fp_line
			(start 0.67945 -0.3048)
			(end 0.67945 0.3048)
			(stroke
				(width 0.1)
				(type default)
			)
			(layer "F.Fab")
		)
		(fp_line
			(start 0.12065 -0.3048)
			(end 0.67945 -0.3048)
			(stroke
				(width 0.1)
				(type default)
			)
			(layer "F.Fab")
		)
		(fp_line
			(start 0.12065 -0.2794)
			(end 0.12065 -0.3048)
			(stroke
				(width 0.1)
				(type default)
			)
			(layer "F.Fab")
		)
		(fp_line
			(start -0.12065 -0.2794)
			(end 0.12065 -0.2794)
			(stroke
				(width 0.1)
				(type default)
			)
			(layer "F.Fab")
		)
		(fp_line
			(start 0.120396 0.2794)
			(end -0.12065 0.2794)
			(stroke
				(width 0.1)
				(type default)
			)
			(layer "F.Fab")
		)
		(fp_line
			(start -0.12065 0.2794)
			(end -0.12065 0.3048)
			(stroke
				(width 0.1)
				(type default)
			)
			(layer "F.Fab")
		)
		(fp_line
			(start 0.67945 0.3048)
			(end 0.120396 0.3048)
			(stroke
				(width 0.1)
				(type default)
			)
			(layer "F.Fab")
		)
		(fp_line
			(start 0.120396 0.3048)
			(end 0.120396 0.2794)
			(stroke
				(width 0.1)
				(type default)
			)
			(layer "F.Fab")
		)
		(fp_line
			(start -0.12065 0.3048)
			(end -0.67945 0.3048)
			(stroke
				(width 0.1)
				(type default)
			)
			(layer "F.Fab")
		)
		(fp_line
			(start -0.67945 0.3048)
			(end -0.67945 -0.305054)
			(stroke
				(width 0.1)
				(type default)
			)
			(layer "F.Fab")
		)
		(pad "1" smd circle
			(at -0.40005 0 90)
			(size 0 0)
			(layers "F.Cu" "F.Mask" "F.Paste")
			(net "PVCCIN_CPU1")
		)
		(pad "2" smd circle
			(at 0.40005 0 90)
			(size 0 0)
			(layers "F.Cu" "F.Mask" "F.Paste")
			(net "GND")
		)
	)
	(footprint ""
		(layer "F.Cu")
		(at 459.267814 -379.556772)
		(property "Reference" "PC1877"
			(at 0 0 0)
			(layer "F.SilkS")
			(hide yes)
			(effects
				(font
					(size 1.27 1.27)
				)
			)
		)
		(property "Value" ""
			(at 0 0 0)
			(layer "F.Fab")
			(effects
				(font
					(size 1.27 1.27)
				)
			)
		)
		(duplicate_pad_numbers_are_jumpers no)
		(fp_line
			(start -0.7874 -0.4064)
			(end 0.7874 -0.4064)
			(stroke
				(width 0.1524)
				(type default)
			)
			(layer "F.SilkS")
		)
		(fp_line
			(start -0.7874 0.4064)
			(end -0.7874 -0.4064)
			(stroke
				(width 0.1524)
				(type default)
			)
			(layer "F.SilkS")
		)
		(fp_line
			(start 0.7874 -0.4064)
			(end 0.7874 0.4064)
			(stroke
				(width 0.1524)
				(type default)
			)
			(layer "F.SilkS")
		)
		(fp_line
			(start 0.7874 0.4064)
			(end -0.7874 0.4064)
			(stroke
				(width 0.1524)
				(type default)
			)
			(layer "F.SilkS")
		)
		(fp_line
			(start -0.67945 -0.305054)
			(end -0.12065 -0.305054)
			(stroke
				(width 0.1)
				(type default)
			)
			(layer "F.Fab")
		)
		(fp_line
			(start -0.67945 0.3048)
			(end -0.67945 -0.305054)
			(stroke
				(width 0.1)
				(type default)
			)
			(layer "F.Fab")
		)
		(fp_line
			(start -0.12065 -0.305054)
			(end -0.12065 -0.2794)
			(stroke
				(width 0.1)
				(type default)
			)
			(layer "F.Fab")
		)
		(fp_line
			(start -0.12065 -0.2794)
			(end 0.12065 -0.2794)
			(stroke
				(width 0.1)
				(type default)
			)
			(layer "F.Fab")
		)
		(fp_line
			(start -0.12065 0.2794)
			(end -0.12065 0.3048)
			(stroke
				(width 0.1)
				(type default)
			)
			(layer "F.Fab")
		)
		(fp_line
			(start -0.12065 0.3048)
			(end -0.67945 0.3048)
			(stroke
				(width 0.1)
				(type default)
			)
			(layer "F.Fab")
		)
		(fp_line
			(start 0.120396 0.2794)
			(end -0.12065 0.2794)
			(stroke
				(width 0.1)
				(type default)
			)
			(layer "F.Fab")
		)
		(fp_line
			(start 0.120396 0.3048)
			(end 0.120396 0.2794)
			(stroke
				(width 0.1)
				(type default)
			)
			(layer "F.Fab")
		)
		(fp_line
			(start 0.12065 -0.3048)
			(end 0.67945 -0.3048)
			(stroke
				(width 0.1)
				(type default)
			)
			(layer "F.Fab")
		)
		(fp_line
			(start 0.12065 -0.2794)
			(end 0.12065 -0.3048)
			(stroke
				(width 0.1)
				(type default)
			)
			(layer "F.Fab")
		)
		(fp_line
			(start 0.67945 -0.3048)
			(end 0.67945 0.3048)
			(stroke
				(width 0.1)
				(type default)
			)
			(layer "F.Fab")
		)
		(fp_line
			(start 0.67945 0.3048)
			(end 0.120396 0.3048)
			(stroke
				(width 0.1)
				(type default)
			)
			(layer "F.Fab")
		)
		(pad "1" smd circle
			(at -0.40005 0)
			(size 0 0)
			(layers "F.Cu" "F.Mask" "F.Paste")
			(net "P5V_AUX_FB")
		)
		(pad "2" smd circle
			(at 0.40005 0)
			(size 0 0)
			(layers "F.Cu" "F.Mask" "F.Paste")
			(net "P5V_AUX")
		)
	)
	(footprint ""
		(layer "F.Cu")
		(at 328.123042 -22.674326 -90)
		(property "Reference" "R4098"
			(at 0 0 270)
			(layer "F.SilkS")
			(hide yes)
			(effects
				(font
					(size 1.27 1.27)
				)
			)
		)
		(property "Value" ""
			(at 0 0 270)
			(layer "F.Fab")
			(effects
				(font
					(size 1.27 1.27)
				)
			)
		)
		(duplicate_pad_numbers_are_jumpers no)
		(fp_line
			(start -0.7874 0.4064)
			(end -0.7874 -0.4064)
			(stroke
				(width 0.1524)
				(type default)
			)
			(layer "F.SilkS")
		)
		(fp_line
			(start 0.7874 0.4064)
			(end -0.7874 0.4064)
			(stroke
				(width 0.1524)
				(type default)
			)
			(layer "F.SilkS")
		)
		(fp_line
			(start -0.7874 -0.4064)
			(end 0.7874 -0.4064)
			(stroke
				(width 0.1524)
				(type default)
			)
			(layer "F.SilkS")
		)
		(fp_line
			(start 0.7874 -0.4064)
			(end 0.7874 0.4064)
			(stroke
				(width 0.1524)
				(type default)
			)
			(layer "F.SilkS")
		)
		(fp_line
			(start -0.67945 0.3048)
			(end -0.67945 -0.305054)
			(stroke
				(width 0.1)
				(type default)
			)
			(layer "F.Fab")
		)
		(fp_line
			(start -0.12065 0.3048)
			(end -0.67945 0.3048)
			(stroke
				(width 0.1)
				(type default)
			)
			(layer "F.Fab")
		)
		(fp_line
			(start 0.120396 0.3048)
			(end 0.120396 0.2794)
			(stroke
				(width 0.1)
				(type default)
			)
			(layer "F.Fab")
		)
		(fp_line
			(start 0.67945 0.3048)
			(end 0.120396 0.3048)
			(stroke
				(width 0.1)
				(type default)
			)
			(layer "F.Fab")
		)
		(fp_line
			(start -0.12065 0.2794)
			(end -0.12065 0.3048)
			(stroke
				(width 0.1)
				(type default)
			)
			(layer "F.Fab")
		)
		(fp_line
			(start 0.120396 0.2794)
			(end -0.12065 0.2794)
			(stroke
				(width 0.1)
				(type default)
			)
			(layer "F.Fab")
		)
		(fp_line
			(start -0.12065 -0.2794)
			(end 0.12065 -0.2794)
			(stroke
				(width 0.1)
				(type default)
			)
			(layer "F.Fab")
		)
		(fp_line
			(start 0.12065 -0.2794)
			(end 0.12065 -0.3048)
			(stroke
				(width 0.1)
				(type default)
			)
			(layer "F.Fab")
		)
		(fp_line
			(start 0.12065 -0.3048)
			(end 0.67945 -0.3048)
			(stroke
				(width 0.1)
				(type default)
			)
			(layer "F.Fab")
		)
		(fp_line
			(start 0.67945 -0.3048)
			(end 0.67945 0.3048)
			(stroke
				(width 0.1)
				(type default)
			)
			(layer "F.Fab")
		)
		(fp_line
			(start -0.67945 -0.305054)
			(end -0.12065 -0.305054)
			(stroke
				(width 0.1)
				(type default)
			)
			(layer "F.Fab")
		)
		(fp_line
			(start -0.12065 -0.305054)
			(end -0.12065 -0.2794)
			(stroke
				(width 0.1)
				(type default)
			)
			(layer "F.Fab")
		)
		(pad "1" smd circle
			(at -0.40005 0 270)
			(size 0 0)
			(layers "F.Cu" "F.Mask" "F.Paste")
			(net "PD_PCH_GPPC_A_14")
		)
		(pad "2" smd circle
			(at 0.40005 0 270)
			(size 0 0)
			(layers "F.Cu" "F.Mask" "F.Paste")
			(net "GND")
		)
	)
	(footprint ""
		(layer "F.Cu")
		(at 36.956238 -132.79374)
		(property "Reference" "C2452"
			(at 0 0 0)
			(layer "F.SilkS")
			(hide yes)
			(effects
				(font
					(size 1.27 1.27)
				)
			)
		)
		(property "Value" ""
			(at 0 0 0)
			(layer "F.Fab")
			(effects
				(font
					(size 1.27 1.27)
				)
			)
		)
		(duplicate_pad_numbers_are_jumpers no)
		(fp_line
			(start -0.7874 -0.4064)
			(end 0.7874 -0.4064)
			(stroke
				(width 0.1524)
				(type default)
			)
			(layer "F.SilkS")
		)
		(fp_line
			(start -0.7874 0.4064)
			(end -0.7874 -0.4064)
			(stroke
				(width 0.1524)
				(type default)
			)
			(layer "F.SilkS")
		)
		(fp_line
			(start 0.7874 -0.4064)
			(end 0.7874 0.4064)
			(stroke
				(width 0.1524)
				(type default)
			)
			(layer "F.SilkS")
		)
		(fp_line
			(start 0.7874 0.4064)
			(end -0.7874 0.4064)
			(stroke
				(width 0.1524)
				(type default)
			)
			(layer "F.SilkS")
		)
		(fp_line
			(start -0.67945 -0.305054)
			(end -0.12065 -0.305054)
			(stroke
				(width 0.1)
				(type default)
			)
			(layer "F.Fab")
		)
		(fp_line
			(start -0.67945 0.3048)
			(end -0.67945 -0.305054)
			(stroke
				(width 0.1)
				(type default)
			)
			(layer "F.Fab")
		)
		(fp_line
			(start -0.12065 -0.305054)
			(end -0.12065 -0.2794)
			(stroke
				(width 0.1)
				(type default)
			)
			(layer "F.Fab")
		)
		(fp_line
			(start -0.12065 -0.2794)
			(end 0.12065 -0.2794)
			(stroke
				(width 0.1)
				(type default)
			)
			(layer "F.Fab")
		)
		(fp_line
			(start -0.12065 0.2794)
			(end -0.12065 0.3048)
			(stroke
				(width 0.1)
				(type default)
			)
			(layer "F.Fab")
		)
		(fp_line
			(start -0.12065 0.3048)
			(end -0.67945 0.3048)
			(stroke
				(width 0.1)
				(type default)
			)
			(layer "F.Fab")
		)
		(fp_line
			(start 0.120396 0.2794)
			(end -0.12065 0.2794)
			(stroke
				(width 0.1)
				(type default)
			)
			(layer "F.Fab")
		)
		(fp_line
			(start 0.120396 0.3048)
			(end 0.120396 0.2794)
			(stroke
				(width 0.1)
				(type default)
			)
			(layer "F.Fab")
		)
		(fp_line
			(start 0.12065 -0.3048)
			(end 0.67945 -0.3048)
			(stroke
				(width 0.1)
				(type default)
			)
			(layer "F.Fab")
		)
		(fp_line
			(start 0.12065 -0.2794)
			(end 0.12065 -0.3048)
			(stroke
				(width 0.1)
				(type default)
			)
			(layer "F.Fab")
		)
		(fp_line
			(start 0.67945 -0.3048)
			(end 0.67945 0.3048)
			(stroke
				(width 0.1)
				(type default)
			)
			(layer "F.Fab")
		)
		(fp_line
			(start 0.67945 0.3048)
			(end 0.120396 0.3048)
			(stroke
				(width 0.1)
				(type default)
			)
			(layer "F.Fab")
		)
		(pad "1" smd circle
			(at -0.40005 0)
			(size 0 0)
			(layers "F.Cu" "F.Mask" "F.Paste")
			(net "PVCCFA_EHV_CPU1_EN_R")
		)
		(pad "2" smd circle
			(at 0.40005 0)
			(size 0 0)
			(layers "F.Cu" "F.Mask" "F.Paste")
			(net "GND")
		)
	)
	(footprint ""
		(layer "F.Cu")
		(at 258.192524 -108.154216 90)
		(property "Reference" "R554"
			(at 0 0 90)
			(layer "F.SilkS")
			(hide yes)
			(effects
				(font
					(size 1.27 1.27)
				)
			)
		)
		(property "Value" ""
			(at 0 0 90)
			(layer "F.Fab")
			(effects
				(font
					(size 1.27 1.27)
				)
			)
		)
		(duplicate_pad_numbers_are_jumpers no)
		(fp_line
			(start 0.7874 -0.4064)
			(end 0.7874 0.4064)
			(stroke
				(width 0.1524)
				(type default)
			)
			(layer "F.SilkS")
		)
		(fp_line
			(start -0.7874 -0.4064)
			(end 0.7874 -0.4064)
			(stroke
				(width 0.1524)
				(type default)
			)
			(layer "F.SilkS")
		)
		(fp_line
			(start 0.7874 0.4064)
			(end -0.7874 0.4064)
			(stroke
				(width 0.1524)
				(type default)
			)
			(layer "F.SilkS")
		)
		(fp_line
			(start -0.7874 0.4064)
			(end -0.7874 -0.4064)
			(stroke
				(width 0.1524)
				(type default)
			)
			(layer "F.SilkS")
		)
		(fp_line
			(start -0.12065 -0.305054)
			(end -0.12065 -0.2794)
			(stroke
				(width 0.1)
				(type default)
			)
			(layer "F.Fab")
		)
		(fp_line
			(start -0.67945 -0.305054)
			(end -0.12065 -0.305054)
			(stroke
				(width 0.1)
				(type default)
			)
			(layer "F.Fab")
		)
		(fp_line
			(start 0.67945 -0.3048)
			(end 0.67945 0.3048)
			(stroke
				(width 0.1)
				(type default)
			)
			(layer "F.Fab")
		)
		(fp_line
			(start 0.12065 -0.3048)
			(end 0.67945 -0.3048)
			(stroke
				(width 0.1)
				(type default)
			)
			(layer "F.Fab")
		)
		(fp_line
			(start 0.12065 -0.2794)
			(end 0.12065 -0.3048)
			(stroke
				(width 0.1)
				(type default)
			)
			(layer "F.Fab")
		)
		(fp_line
			(start -0.12065 -0.2794)
			(end 0.12065 -0.2794)
			(stroke
				(width 0.1)
				(type default)
			)
			(layer "F.Fab")
		)
		(fp_line
			(start 0.120396 0.2794)
			(end -0.12065 0.2794)
			(stroke
				(width 0.1)
				(type default)
			)
			(layer "F.Fab")
		)
		(fp_line
			(start -0.12065 0.2794)
			(end -0.12065 0.3048)
			(stroke
				(width 0.1)
				(type default)
			)
			(layer "F.Fab")
		)
		(fp_line
			(start 0.67945 0.3048)
			(end 0.120396 0.3048)
			(stroke
				(width 0.1)
				(type default)
			)
			(layer "F.Fab")
		)
		(fp_line
			(start 0.120396 0.3048)
			(end 0.120396 0.2794)
			(stroke
				(width 0.1)
				(type default)
			)
			(layer "F.Fab")
		)
		(fp_line
			(start -0.12065 0.3048)
			(end -0.67945 0.3048)
			(stroke
				(width 0.1)
				(type default)
			)
			(layer "F.Fab")
		)
		(fp_line
			(start -0.67945 0.3048)
			(end -0.67945 -0.305054)
			(stroke
				(width 0.1)
				(type default)
			)
			(layer "F.Fab")
		)
		(pad "1" smd circle
			(at -0.40005 0 90)
			(size 0 0)
			(layers "F.Cu" "F.Mask" "F.Paste")
			(net "CLK_100M_CK440_PCH_EXTCLK_R_DN")
		)
		(pad "2" smd circle
			(at 0.40005 0 90)
			(size 0 0)
			(layers "F.Cu" "F.Mask" "F.Paste")
			(net "CLK_100M_CK440_PCH_EXTCLK_DN")
		)
	)
	(footprint ""
		(layer "F.Cu")
		(at 39.80688 -435.955948)
		(property "Reference" "R2899"
			(at 0 0 0)
			(layer "F.SilkS")
			(hide yes)
			(effects
				(font
					(size 1.27 1.27)
				)
			)
		)
		(property "Value" ""
			(at 0 0 0)
			(layer "F.Fab")
			(effects
				(font
					(size 1.27 1.27)
				)
			)
		)
		(duplicate_pad_numbers_are_jumpers no)
		(fp_line
			(start -0.7874 -0.4064)
			(end 0.7874 -0.4064)
			(stroke
				(width 0.1524)
				(type default)
			)
			(layer "F.SilkS")
		)
		(fp_line
			(start -0.7874 0.4064)
			(end -0.7874 -0.4064)
			(stroke
				(width 0.1524)
				(type default)
			)
			(layer "F.SilkS")
		)
		(fp_line
			(start 0.7874 -0.4064)
			(end 0.7874 0.4064)
			(stroke
				(width 0.1524)
				(type default)
			)
			(layer "F.SilkS")
		)
		(fp_line
			(start 0.7874 0.4064)
			(end -0.7874 0.4064)
			(stroke
				(width 0.1524)
				(type default)
			)
			(layer "F.SilkS")
		)
		(fp_line
			(start -0.67945 -0.305054)
			(end -0.12065 -0.305054)
			(stroke
				(width 0.1)
				(type default)
			)
			(layer "F.Fab")
		)
		(fp_line
			(start -0.67945 0.3048)
			(end -0.67945 -0.305054)
			(stroke
				(width 0.1)
				(type default)
			)
			(layer "F.Fab")
		)
		(fp_line
			(start -0.12065 -0.305054)
			(end -0.12065 -0.2794)
			(stroke
				(width 0.1)
				(type default)
			)
			(layer "F.Fab")
		)
		(fp_line
			(start -0.12065 -0.2794)
			(end 0.12065 -0.2794)
			(stroke
				(width 0.1)
				(type default)
			)
			(layer "F.Fab")
		)
		(fp_line
			(start -0.12065 0.2794)
			(end -0.12065 0.3048)
			(stroke
				(width 0.1)
				(type default)
			)
			(layer "F.Fab")
		)
		(fp_line
			(start -0.12065 0.3048)
			(end -0.67945 0.3048)
			(stroke
				(width 0.1)
				(type default)
			)
			(layer "F.Fab")
		)
		(fp_line
			(start 0.120396 0.2794)
			(end -0.12065 0.2794)
			(stroke
				(width 0.1)
				(type default)
			)
			(layer "F.Fab")
		)
		(fp_line
			(start 0.120396 0.3048)
			(end 0.120396 0.2794)
			(stroke
				(width 0.1)
				(type default)
			)
			(layer "F.Fab")
		)
		(fp_line
			(start 0.12065 -0.3048)
			(end 0.67945 -0.3048)
			(stroke
				(width 0.1)
				(type default)
			)
			(layer "F.Fab")
		)
		(fp_line
			(start 0.12065 -0.2794)
			(end 0.12065 -0.3048)
			(stroke
				(width 0.1)
				(type default)
			)
			(layer "F.Fab")
		)
		(fp_line
			(start 0.67945 -0.3048)
			(end 0.67945 0.3048)
			(stroke
				(width 0.1)
				(type default)
			)
			(layer "F.Fab")
		)
		(fp_line
			(start 0.67945 0.3048)
			(end 0.120396 0.3048)
			(stroke
				(width 0.1)
				(type default)
			)
			(layer "F.Fab")
		)
		(pad "1" smd circle
			(at -0.40005 0)
			(size 0 0)
			(layers "F.Cu" "F.Mask" "F.Paste")
			(net "SMB_BMC_GPU_EN")
		)
		(pad "2" smd circle
			(at 0.40005 0)
			(size 0 0)
			(layers "F.Cu" "F.Mask" "F.Paste")
			(net "SMB_BMC_GPU_EN_R1")
		)
	)
	(footprint ""
		(layer "F.Cu")
		(at 159.655256 -66.091308)
		(property "Reference" "R3772"
			(at 0 0 0)
			(layer "F.SilkS")
			(hide yes)
			(effects
				(font
					(size 1.27 1.27)
				)
			)
		)
		(property "Value" ""
			(at 0 0 0)
			(layer "F.Fab")
			(effects
				(font
					(size 1.27 1.27)
				)
			)
		)
		(duplicate_pad_numbers_are_jumpers no)
		(fp_line
			(start -0.7874 -0.4064)
			(end 0.7874 -0.4064)
			(stroke
				(width 0.1524)
				(type default)
			)
			(layer "F.SilkS")
		)
		(fp_line
			(start -0.7874 0.4064)
			(end -0.7874 -0.4064)
			(stroke
				(width 0.1524)
				(type default)
			)
			(layer "F.SilkS")
		)
		(fp_line
			(start 0.7874 -0.4064)
			(end 0.7874 0.4064)
			(stroke
				(width 0.1524)
				(type default)
			)
			(layer "F.SilkS")
		)
		(fp_line
			(start 0.7874 0.4064)
			(end -0.7874 0.4064)
			(stroke
				(width 0.1524)
				(type default)
			)
			(layer "F.SilkS")
		)
		(fp_line
			(start -0.67945 -0.305054)
			(end -0.12065 -0.305054)
			(stroke
				(width 0.1)
				(type default)
			)
			(layer "F.Fab")
		)
		(fp_line
			(start -0.67945 0.3048)
			(end -0.67945 -0.305054)
			(stroke
				(width 0.1)
				(type default)
			)
			(layer "F.Fab")
		)
		(fp_line
			(start -0.12065 -0.305054)
			(end -0.12065 -0.2794)
			(stroke
				(width 0.1)
				(type default)
			)
			(layer "F.Fab")
		)
		(fp_line
			(start -0.12065 -0.2794)
			(end 0.12065 -0.2794)
			(stroke
				(width 0.1)
				(type default)
			)
			(layer "F.Fab")
		)
		(fp_line
			(start -0.12065 0.2794)
			(end -0.12065 0.3048)
			(stroke
				(width 0.1)
				(type default)
			)
			(layer "F.Fab")
		)
		(fp_line
			(start -0.12065 0.3048)
			(end -0.67945 0.3048)
			(stroke
				(width 0.1)
				(type default)
			)
			(layer "F.Fab")
		)
		(fp_line
			(start 0.120396 0.2794)
			(end -0.12065 0.2794)
			(stroke
				(width 0.1)
				(type default)
			)
			(layer "F.Fab")
		)
		(fp_line
			(start 0.120396 0.3048)
			(end 0.120396 0.2794)
			(stroke
				(width 0.1)
				(type default)
			)
			(layer "F.Fab")
		)
		(fp_line
			(start 0.12065 -0.3048)
			(end 0.67945 -0.3048)
			(stroke
				(width 0.1)
				(type default)
			)
			(layer "F.Fab")
		)
		(fp_line
			(start 0.12065 -0.2794)
			(end 0.12065 -0.3048)
			(stroke
				(width 0.1)
				(type default)
			)
			(layer "F.Fab")
		)
		(fp_line
			(start 0.67945 -0.3048)
			(end 0.67945 0.3048)
			(stroke
				(width 0.1)
				(type default)
			)
			(layer "F.Fab")
		)
		(fp_line
			(start 0.67945 0.3048)
			(end 0.120396 0.3048)
			(stroke
				(width 0.1)
				(type default)
			)
			(layer "F.Fab")
		)
		(pad "1" smd circle
			(at -0.40005 0)
			(size 0 0)
			(layers "F.Cu" "F.Mask" "F.Paste")
			(net "RST_SMB_BUF_E1S_0_N")
		)
		(pad "2" smd circle
			(at 0.40005 0)
			(size 0 0)
			(layers "F.Cu" "F.Mask" "F.Paste")
			(net "RST_SMB_E1S_0_N")
		)
	)
	(footprint ""
		(layer "F.Cu")
		(at 366.48263 -249.320304 -90)
		(property "Reference" "C977"
			(at 0 0 270)
			(layer "F.SilkS")
			(hide yes)
			(effects
				(font
					(size 1.27 1.27)
				)
			)
		)
		(property "Value" ""
			(at 0 0 270)
			(layer "F.Fab")
			(effects
				(font
					(size 1.27 1.27)
				)
			)
		)
		(duplicate_pad_numbers_are_jumpers no)
		(fp_line
			(start -0.7874 0.4064)
			(end -0.7874 -0.4064)
			(stroke
				(width 0.1524)
				(type default)
			)
			(layer "F.SilkS")
		)
		(fp_line
			(start 0.7874 0.4064)
			(end -0.7874 0.4064)
			(stroke
				(width 0.1524)
				(type default)
			)
			(layer "F.SilkS")
		)
		(fp_line
			(start -0.7874 -0.4064)
			(end 0.7874 -0.4064)
			(stroke
				(width 0.1524)
				(type default)
			)
			(layer "F.SilkS")
		)
		(fp_line
			(start 0.7874 -0.4064)
			(end 0.7874 0.4064)
			(stroke
				(width 0.1524)
				(type default)
			)
			(layer "F.SilkS")
		)
		(fp_line
			(start -0.67945 0.3048)
			(end -0.67945 -0.305054)
			(stroke
				(width 0.1)
				(type default)
			)
			(layer "F.Fab")
		)
		(fp_line
			(start -0.12065 0.3048)
			(end -0.67945 0.3048)
			(stroke
				(width 0.1)
				(type default)
			)
			(layer "F.Fab")
		)
		(fp_line
			(start 0.120396 0.3048)
			(end 0.120396 0.2794)
			(stroke
				(width 0.1)
				(type default)
			)
			(layer "F.Fab")
		)
		(fp_line
			(start 0.67945 0.3048)
			(end 0.120396 0.3048)
			(stroke
				(width 0.1)
				(type default)
			)
			(layer "F.Fab")
		)
		(fp_line
			(start -0.12065 0.2794)
			(end -0.12065 0.3048)
			(stroke
				(width 0.1)
				(type default)
			)
			(layer "F.Fab")
		)
		(fp_line
			(start 0.120396 0.2794)
			(end -0.12065 0.2794)
			(stroke
				(width 0.1)
				(type default)
			)
			(layer "F.Fab")
		)
		(fp_line
			(start -0.12065 -0.2794)
			(end 0.12065 -0.2794)
			(stroke
				(width 0.1)
				(type default)
			)
			(layer "F.Fab")
		)
		(fp_line
			(start 0.12065 -0.2794)
			(end 0.12065 -0.3048)
			(stroke
				(width 0.1)
				(type default)
			)
			(layer "F.Fab")
		)
		(fp_line
			(start 0.12065 -0.3048)
			(end 0.67945 -0.3048)
			(stroke
				(width 0.1)
				(type default)
			)
			(layer "F.Fab")
		)
		(fp_line
			(start 0.67945 -0.3048)
			(end 0.67945 0.3048)
			(stroke
				(width 0.1)
				(type default)
			)
			(layer "F.Fab")
		)
		(fp_line
			(start -0.67945 -0.305054)
			(end -0.12065 -0.305054)
			(stroke
				(width 0.1)
				(type default)
			)
			(layer "F.Fab")
		)
		(fp_line
			(start -0.12065 -0.305054)
			(end -0.12065 -0.2794)
			(stroke
				(width 0.1)
				(type default)
			)
			(layer "F.Fab")
		)
		(pad "1" smd circle
			(at -0.40005 0 270)
			(size 0 0)
			(layers "F.Cu" "F.Mask" "F.Paste")
			(net "PVCCIN_CPU0")
		)
		(pad "2" smd circle
			(at 0.40005 0 270)
			(size 0 0)
			(layers "F.Cu" "F.Mask" "F.Paste")
			(net "GND")
		)
	)
	(footprint ""
		(layer "F.Cu")
		(at 49.324514 -394.44676 180)
		(property "Reference" "R4642"
			(at 0 0 180)
			(layer "F.SilkS")
			(hide yes)
			(effects
				(font
					(size 1.27 1.27)
				)
			)
		)
		(property "Value" ""
			(at 0 0 180)
			(layer "F.Fab")
			(effects
				(font
					(size 1.27 1.27)
				)
			)
		)
		(duplicate_pad_numbers_are_jumpers no)
		(fp_line
			(start 0.7874 0.4064)
			(end -0.7874 0.4064)
			(stroke
				(width 0.1524)
				(type default)
			)
			(layer "F.SilkS")
		)
		(fp_line
			(start 0.7874 -0.4064)
			(end 0.7874 0.4064)
			(stroke
				(width 0.1524)
				(type default)
			)
			(layer "F.SilkS")
		)
		(fp_line
			(start -0.7874 0.4064)
			(end -0.7874 -0.4064)
			(stroke
				(width 0.1524)
				(type default)
			)
			(layer "F.SilkS")
		)
		(fp_line
			(start -0.7874 -0.4064)
			(end 0.7874 -0.4064)
			(stroke
				(width 0.1524)
				(type default)
			)
			(layer "F.SilkS")
		)
		(fp_line
			(start 0.67945 0.3048)
			(end 0.120396 0.3048)
			(stroke
				(width 0.1)
				(type default)
			)
			(layer "F.Fab")
		)
		(fp_line
			(start 0.67945 -0.3048)
			(end 0.67945 0.3048)
			(stroke
				(width 0.1)
				(type default)
			)
			(layer "F.Fab")
		)
		(fp_line
			(start 0.12065 -0.2794)
			(end 0.12065 -0.3048)
			(stroke
				(width 0.1)
				(type default)
			)
			(layer "F.Fab")
		)
		(fp_line
			(start 0.12065 -0.3048)
			(end 0.67945 -0.3048)
			(stroke
				(width 0.1)
				(type default)
			)
			(layer "F.Fab")
		)
		(fp_line
			(start 0.120396 0.3048)
			(end 0.120396 0.2794)
			(stroke
				(width 0.1)
				(type default)
			)
			(layer "F.Fab")
		)
		(fp_line
			(start 0.120396 0.2794)
			(end -0.12065 0.2794)
			(stroke
				(width 0.1)
				(type default)
			)
			(layer "F.Fab")
		)
		(fp_line
			(start -0.12065 0.3048)
			(end -0.67945 0.3048)
			(stroke
				(width 0.1)
				(type default)
			)
			(layer "F.Fab")
		)
		(fp_line
			(start -0.12065 0.2794)
			(end -0.12065 0.3048)
			(stroke
				(width 0.1)
				(type default)
			)
			(layer "F.Fab")
		)
		(fp_line
			(start -0.12065 -0.2794)
			(end 0.12065 -0.2794)
			(stroke
				(width 0.1)
				(type default)
			)
			(layer "F.Fab")
		)
		(fp_line
			(start -0.12065 -0.305054)
			(end -0.12065 -0.2794)
			(stroke
				(width 0.1)
				(type default)
			)
			(layer "F.Fab")
		)
		(fp_line
			(start -0.67945 0.3048)
			(end -0.67945 -0.305054)
			(stroke
				(width 0.1)
				(type default)
			)
			(layer "F.Fab")
		)
		(fp_line
			(start -0.67945 -0.305054)
			(end -0.12065 -0.305054)
			(stroke
				(width 0.1)
				(type default)
			)
			(layer "F.Fab")
		)
		(pad "1" smd circle
			(at -0.40005 0 180)
			(size 0 0)
			(layers "F.Cu" "F.Mask" "F.Paste")
			(net "P3V3_AUX")
		)
		(pad "2" smd circle
			(at 0.40005 0 180)
			(size 0 0)
			(layers "F.Cu" "F.Mask" "F.Paste")
			(net "FM_P2E_BUF2_VODB_DB")
		)
	)
	(footprint ""
		(layer "F.Cu")
		(at 132.29082 -97.125028 90)
		(property "Reference" "R4404"
			(at 0 0 90)
			(layer "F.SilkS")
			(hide yes)
			(effects
				(font
					(size 1.27 1.27)
				)
			)
		)
		(property "Value" ""
			(at 0 0 90)
			(layer "F.Fab")
			(effects
				(font
					(size 1.27 1.27)
				)
			)
		)
		(duplicate_pad_numbers_are_jumpers no)
		(fp_line
			(start 0.7874 -0.4064)
			(end 0.7874 0.4064)
			(stroke
				(width 0.1524)
				(type default)
			)
			(layer "F.SilkS")
		)
		(fp_line
			(start -0.7874 -0.4064)
			(end 0.7874 -0.4064)
			(stroke
				(width 0.1524)
				(type default)
			)
			(layer "F.SilkS")
		)
		(fp_line
			(start 0.7874 0.4064)
			(end -0.7874 0.4064)
			(stroke
				(width 0.1524)
				(type default)
			)
			(layer "F.SilkS")
		)
		(fp_line
			(start -0.7874 0.4064)
			(end -0.7874 -0.4064)
			(stroke
				(width 0.1524)
				(type default)
			)
			(layer "F.SilkS")
		)
		(fp_line
			(start -0.12065 -0.305054)
			(end -0.12065 -0.2794)
			(stroke
				(width 0.1)
				(type default)
			)
			(layer "F.Fab")
		)
		(fp_line
			(start -0.67945 -0.305054)
			(end -0.12065 -0.305054)
			(stroke
				(width 0.1)
				(type default)
			)
			(layer "F.Fab")
		)
		(fp_line
			(start 0.67945 -0.3048)
			(end 0.67945 0.3048)
			(stroke
				(width 0.1)
				(type default)
			)
			(layer "F.Fab")
		)
		(fp_line
			(start 0.12065 -0.3048)
			(end 0.67945 -0.3048)
			(stroke
				(width 0.1)
				(type default)
			)
			(layer "F.Fab")
		)
		(fp_line
			(start 0.12065 -0.2794)
			(end 0.12065 -0.3048)
			(stroke
				(width 0.1)
				(type default)
			)
			(layer "F.Fab")
		)
		(fp_line
			(start -0.12065 -0.2794)
			(end 0.12065 -0.2794)
			(stroke
				(width 0.1)
				(type default)
			)
			(layer "F.Fab")
		)
		(fp_line
			(start 0.120396 0.2794)
			(end -0.12065 0.2794)
			(stroke
				(width 0.1)
				(type default)
			)
			(layer "F.Fab")
		)
		(fp_line
			(start -0.12065 0.2794)
			(end -0.12065 0.3048)
			(stroke
				(width 0.1)
				(type default)
			)
			(layer "F.Fab")
		)
		(fp_line
			(start 0.67945 0.3048)
			(end 0.120396 0.3048)
			(stroke
				(width 0.1)
				(type default)
			)
			(layer "F.Fab")
		)
		(fp_line
			(start 0.120396 0.3048)
			(end 0.120396 0.2794)
			(stroke
				(width 0.1)
				(type default)
			)
			(layer "F.Fab")
		)
		(fp_line
			(start -0.12065 0.3048)
			(end -0.67945 0.3048)
			(stroke
				(width 0.1)
				(type default)
			)
			(layer "F.Fab")
		)
		(fp_line
			(start -0.67945 0.3048)
			(end -0.67945 -0.305054)
			(stroke
				(width 0.1)
				(type default)
			)
			(layer "F.Fab")
		)
		(pad "1" smd circle
			(at -0.40005 0 90)
			(size 0 0)
			(layers "F.Cu" "F.Mask" "F.Paste")
			(net "H_CPU1_MEMHOT_OUT")
		)
		(pad "2" smd circle
			(at 0.40005 0 90)
			(size 0 0)
			(layers "F.Cu" "F.Mask" "F.Paste")
			(net "H_CPU1_MEMHOT_OUT_R")
		)
	)
	(footprint ""
		(layer "F.Cu")
		(at 236.015784 -391.837164 90)
		(property "Reference" "PD17"
			(at -2.8956 -3.343148 90)
			(unlocked yes)
			(layer "F.SilkS")
			(effects
				(font
					(size 0.7874 0.5842)
					(thickness 0.1524)
				)
			)
		)
		(property "Value" ""
			(at 0 0 90)
			(layer "F.Fab")
			(effects
				(font
					(size 1.27 1.27)
				)
			)
		)
		(duplicate_pad_numbers_are_jumpers no)
		(fp_line
			(start 3.541776 -2.54)
			(end 3.541776 2.54)
			(stroke
				(width 0.1524)
				(type default)
			)
			(layer "F.SilkS")
		)
		(fp_line
			(start -3.539744 -2.54)
			(end 3.541776 -2.54)
			(stroke
				(width 0.1524)
				(type default)
			)
			(layer "F.SilkS")
		)
		(fp_line
			(start 3.541776 2.54)
			(end -3.539744 2.54)
			(stroke
				(width 0.1524)
				(type default)
			)
			(layer "F.SilkS")
		)
		(fp_line
			(start -3.539744 2.54)
			(end -3.539744 -2.54)
			(stroke
				(width 0.1524)
				(type default)
			)
			(layer "F.SilkS")
		)
		(fp_poly
			(pts
				(xy -4.699 0.531876) (xy -4.699 1.547876) (xy -3.683 1.039876)
			)
			(stroke
				(width 0)
				(type default)
			)
			(fill yes)
			(layer "F.SilkS")
		)
		(fp_line
			(start 3.074924 -2.175002)
			(end 3.074924 2.175002)
			(stroke
				(width 0.1)
				(type default)
			)
			(layer "F.Fab")
		)
		(fp_line
			(start -3.074924 -2.175002)
			(end 3.074924 -2.175002)
			(stroke
				(width 0.1)
				(type default)
			)
			(layer "F.Fab")
		)
		(fp_line
			(start 3.074924 2.175002)
			(end -3.074924 2.175002)
			(stroke
				(width 0.1)
				(type default)
			)
			(layer "F.Fab")
		)
		(fp_line
			(start -3.074924 2.175002)
			(end -3.074924 -2.175002)
			(stroke
				(width 0.1)
				(type default)
			)
			(layer "F.Fab")
		)
		(fp_poly
			(pts
				(xy -4.699 0.531876) (xy -4.699 1.547876) (xy -3.683 1.039876)
			)
			(stroke
				(width 0)
				(type default)
			)
			(fill yes)
			(layer "F.Fab")
		)
		(pad "1" smd rect
			(at -2.765044 1.039876 270)
			(size 1.27 1.4224)
			(layers "F.Cu" "F.Mask" "F.Paste")
			(net "GND")
		)
		(pad "2" smd rect
			(at -2.765044 -1.039876 270)
			(size 1.27 1.4224)
			(layers "F.Cu" "F.Mask" "F.Paste")
			(net "GND")
		)
		(pad "K" smd rect
			(at 1.039876 0 270)
			(size 4.7244 4.8006)
			(layers "F.Cu" "F.Mask" "F.Paste")
			(net "P12V_AUX")
		)
	)
	(footprint ""
		(layer "F.Cu")
		(at 51.017678 -402.371052 -90)
		(property "Reference" "C712"
			(at 0 0 270)
			(layer "F.SilkS")
			(hide yes)
			(effects
				(font
					(size 1.27 1.27)
				)
			)
		)
		(property "Value" ""
			(at 0 0 270)
			(layer "F.Fab")
			(effects
				(font
					(size 1.27 1.27)
				)
			)
		)
		(duplicate_pad_numbers_are_jumpers no)
		(fp_line
			(start -0.299974 0.150114)
			(end -0.299974 -0.150114)
			(stroke
				(width 0.1)
				(type default)
			)
			(layer "F.Fab")
		)
		(fp_line
			(start 0.299974 0.150114)
			(end -0.299974 0.150114)
			(stroke
				(width 0.1)
				(type default)
			)
			(layer "F.Fab")
		)
		(fp_line
			(start -0.299974 -0.150114)
			(end 0.299974 -0.150114)
			(stroke
				(width 0.1)
				(type default)
			)
			(layer "F.Fab")
		)
		(fp_line
			(start 0.299974 -0.150114)
			(end 0.299974 0.150114)
			(stroke
				(width 0.1)
				(type default)
			)
			(layer "F.Fab")
		)
		(pad "1" smd rect
			(at -0.2667 0 270)
			(size 0.3048 0.381)
			(layers "F.Cu" "F.Mask" "F.Paste")
			(net "P5E_CPU1_PE0_TX_C_DN<14>")
		)
		(pad "2" smd rect
			(at 0.2667 0 270)
			(size 0.3048 0.381)
			(layers "F.Cu" "F.Mask" "F.Paste")
			(net "P5E_CPU1_PE0_TX_DN<14>")
		)
	)
	(footprint ""
		(layer "F.Cu")
		(at 372.871238 -361.704382 180)
		(property "Reference" "PC1249"
			(at 0 0 180)
			(layer "F.SilkS")
			(hide yes)
			(effects
				(font
					(size 1.27 1.27)
				)
			)
		)
		(property "Value" ""
			(at 0 0 180)
			(layer "F.Fab")
			(effects
				(font
					(size 1.27 1.27)
				)
			)
		)
		(duplicate_pad_numbers_are_jumpers no)
		(fp_line
			(start 0.7874 0.4064)
			(end -0.7874 0.4064)
			(stroke
				(width 0.1524)
				(type default)
			)
			(layer "F.SilkS")
		)
		(fp_line
			(start 0.7874 -0.4064)
			(end 0.7874 0.4064)
			(stroke
				(width 0.1524)
				(type default)
			)
			(layer "F.SilkS")
		)
		(fp_line
			(start -0.7874 0.4064)
			(end -0.7874 -0.4064)
			(stroke
				(width 0.1524)
				(type default)
			)
			(layer "F.SilkS")
		)
		(fp_line
			(start -0.7874 -0.4064)
			(end 0.7874 -0.4064)
			(stroke
				(width 0.1524)
				(type default)
			)
			(layer "F.SilkS")
		)
		(fp_line
			(start 0.67945 0.3048)
			(end 0.120396 0.3048)
			(stroke
				(width 0.1)
				(type default)
			)
			(layer "F.Fab")
		)
		(fp_line
			(start 0.67945 -0.3048)
			(end 0.67945 0.3048)
			(stroke
				(width 0.1)
				(type default)
			)
			(layer "F.Fab")
		)
		(fp_line
			(start 0.12065 -0.2794)
			(end 0.12065 -0.3048)
			(stroke
				(width 0.1)
				(type default)
			)
			(layer "F.Fab")
		)
		(fp_line
			(start 0.12065 -0.3048)
			(end 0.67945 -0.3048)
			(stroke
				(width 0.1)
				(type default)
			)
			(layer "F.Fab")
		)
		(fp_line
			(start 0.120396 0.3048)
			(end 0.120396 0.2794)
			(stroke
				(width 0.1)
				(type default)
			)
			(layer "F.Fab")
		)
		(fp_line
			(start 0.120396 0.2794)
			(end -0.12065 0.2794)
			(stroke
				(width 0.1)
				(type default)
			)
			(layer "F.Fab")
		)
		(fp_line
			(start -0.12065 0.3048)
			(end -0.67945 0.3048)
			(stroke
				(width 0.1)
				(type default)
			)
			(layer "F.Fab")
		)
		(fp_line
			(start -0.12065 0.2794)
			(end -0.12065 0.3048)
			(stroke
				(width 0.1)
				(type default)
			)
			(layer "F.Fab")
		)
		(fp_line
			(start -0.12065 -0.2794)
			(end 0.12065 -0.2794)
			(stroke
				(width 0.1)
				(type default)
			)
			(layer "F.Fab")
		)
		(fp_line
			(start -0.12065 -0.305054)
			(end -0.12065 -0.2794)
			(stroke
				(width 0.1)
				(type default)
			)
			(layer "F.Fab")
		)
		(fp_line
			(start -0.67945 0.3048)
			(end -0.67945 -0.305054)
			(stroke
				(width 0.1)
				(type default)
			)
			(layer "F.Fab")
		)
		(fp_line
			(start -0.67945 -0.305054)
			(end -0.12065 -0.305054)
			(stroke
				(width 0.1)
				(type default)
			)
			(layer "F.Fab")
		)
		(pad "1" smd circle
			(at -0.40005 0 180)
			(size 0 0)
			(layers "F.Cu" "F.Mask" "F.Paste")
			(net "SW_P12V_PVCCIN_CPU0_FLT")
		)
		(pad "2" smd circle
			(at 0.40005 0 180)
			(size 0 0)
			(layers "F.Cu" "F.Mask" "F.Paste")
			(net "GND")
		)
	)
	(footprint ""
		(layer "F.Cu")
		(at 320.95567 -338.218526 90)
		(property "Reference" "PL105"
			(at -4.399788 -2.95021 0)
			(unlocked yes)
			(layer "F.SilkS")
			(effects
				(font
					(size 0.7874 0.5842)
					(thickness 0.1524)
				)
				(justify left)
			)
		)
		(property "Value" ""
			(at 0 0 90)
			(layer "F.Fab")
			(effects
				(font
					(size 1.27 1.27)
				)
			)
		)
		(duplicate_pad_numbers_are_jumpers no)
		(fp_line
			(start 3.24993 -3.24993)
			(end 3.24993 -2.2352)
			(stroke
				(width 0.1524)
				(type default)
			)
			(layer "F.SilkS")
		)
		(fp_line
			(start -3.24993 -3.24993)
			(end 3.24993 -3.24993)
			(stroke
				(width 0.1524)
				(type default)
			)
			(layer "F.SilkS")
		)
		(fp_line
			(start -3.24993 -2.2352)
			(end -3.24993 -3.24993)
			(stroke
				(width 0.1524)
				(type default)
			)
			(layer "F.SilkS")
		)
		(fp_line
			(start 3.24993 2.2352)
			(end 3.24993 3.24993)
			(stroke
				(width 0.1524)
				(type default)
			)
			(layer "F.SilkS")
		)
		(fp_line
			(start 3.24993 3.24993)
			(end 0.201422 3.24993)
			(stroke
				(width 0.1524)
				(type default)
			)
			(layer "F.SilkS")
		)
		(fp_line
			(start -0.814578 3.24993)
			(end -3.24993 3.24993)
			(stroke
				(width 0.1524)
				(type default)
			)
			(layer "F.SilkS")
		)
		(fp_line
			(start -3.24993 3.24993)
			(end -3.24993 2.2352)
			(stroke
				(width 0.1524)
				(type default)
			)
			(layer "F.SilkS")
		)
		(fp_line
			(start 3.24993 -3.24993)
			(end 3.24993 3.24993)
			(stroke
				(width 0.1)
				(type default)
			)
			(layer "F.Fab")
		)
		(fp_line
			(start -3.24993 -3.24993)
			(end 3.24993 -3.24993)
			(stroke
				(width 0.1)
				(type default)
			)
			(layer "F.Fab")
		)
		(fp_line
			(start 3.24993 3.24993)
			(end -3.24993 3.24993)
			(stroke
				(width 0.1)
				(type default)
			)
			(layer "F.Fab")
		)
		(fp_line
			(start -3.24993 3.24993)
			(end -3.24993 -3.24993)
			(stroke
				(width 0.1)
				(type default)
			)
			(layer "F.Fab")
		)
		(pad "1" smd rect
			(at -2.29997 0 90)
			(size 2.0066 4.2164)
			(layers "F.Cu" "F.Mask" "F.Paste")
			(net "IND_P0_CPL7")
		)
		(pad "2" smd rect
			(at 2.29997 0 90)
			(size 2.0066 4.2164)
			(layers "F.Cu" "F.Mask" "F.Paste")
			(net "GND")
		)
	)
	(footprint ""
		(layer "F.Cu")
		(at 161.163 -20.665948 -90)
		(property "Reference" "R4509"
			(at 0 0 270)
			(layer "F.SilkS")
			(hide yes)
			(effects
				(font
					(size 1.27 1.27)
				)
			)
		)
		(property "Value" ""
			(at 0 0 270)
			(layer "F.Fab")
			(effects
				(font
					(size 1.27 1.27)
				)
			)
		)
		(duplicate_pad_numbers_are_jumpers no)
		(fp_line
			(start -0.7874 0.4064)
			(end -0.7874 -0.4064)
			(stroke
				(width 0.1524)
				(type default)
			)
			(layer "F.SilkS")
		)
		(fp_line
			(start 0.7874 0.4064)
			(end -0.7874 0.4064)
			(stroke
				(width 0.1524)
				(type default)
			)
			(layer "F.SilkS")
		)
		(fp_line
			(start -0.7874 -0.4064)
			(end 0.7874 -0.4064)
			(stroke
				(width 0.1524)
				(type default)
			)
			(layer "F.SilkS")
		)
		(fp_line
			(start 0.7874 -0.4064)
			(end 0.7874 0.4064)
			(stroke
				(width 0.1524)
				(type default)
			)
			(layer "F.SilkS")
		)
		(fp_line
			(start -0.67945 0.3048)
			(end -0.67945 -0.305054)
			(stroke
				(width 0.1)
				(type default)
			)
			(layer "F.Fab")
		)
		(fp_line
			(start -0.12065 0.3048)
			(end -0.67945 0.3048)
			(stroke
				(width 0.1)
				(type default)
			)
			(layer "F.Fab")
		)
		(fp_line
			(start 0.120396 0.3048)
			(end 0.120396 0.2794)
			(stroke
				(width 0.1)
				(type default)
			)
			(layer "F.Fab")
		)
		(fp_line
			(start 0.67945 0.3048)
			(end 0.120396 0.3048)
			(stroke
				(width 0.1)
				(type default)
			)
			(layer "F.Fab")
		)
		(fp_line
			(start -0.12065 0.2794)
			(end -0.12065 0.3048)
			(stroke
				(width 0.1)
				(type default)
			)
			(layer "F.Fab")
		)
		(fp_line
			(start 0.120396 0.2794)
			(end -0.12065 0.2794)
			(stroke
				(width 0.1)
				(type default)
			)
			(layer "F.Fab")
		)
		(fp_line
			(start -0.12065 -0.2794)
			(end 0.12065 -0.2794)
			(stroke
				(width 0.1)
				(type default)
			)
			(layer "F.Fab")
		)
		(fp_line
			(start 0.12065 -0.2794)
			(end 0.12065 -0.3048)
			(stroke
				(width 0.1)
				(type default)
			)
			(layer "F.Fab")
		)
		(fp_line
			(start 0.12065 -0.3048)
			(end 0.67945 -0.3048)
			(stroke
				(width 0.1)
				(type default)
			)
			(layer "F.Fab")
		)
		(fp_line
			(start 0.67945 -0.3048)
			(end 0.67945 0.3048)
			(stroke
				(width 0.1)
				(type default)
			)
			(layer "F.Fab")
		)
		(fp_line
			(start -0.67945 -0.305054)
			(end -0.12065 -0.305054)
			(stroke
				(width 0.1)
				(type default)
			)
			(layer "F.Fab")
		)
		(fp_line
			(start -0.12065 -0.305054)
			(end -0.12065 -0.2794)
			(stroke
				(width 0.1)
				(type default)
			)
			(layer "F.Fab")
		)
		(pad "1" smd circle
			(at -0.40005 0 270)
			(size 0 0)
			(layers "F.Cu" "F.Mask" "F.Paste")
			(net "SMB_1_PLD_3V3AUX_SDA")
		)
		(pad "2" smd circle
			(at 0.40005 0 270)
			(size 0 0)
			(layers "F.Cu" "F.Mask" "F.Paste")
			(net "SMB_1_PLD_3V3AUX_SDA_R3")
		)
	)
	(footprint ""
		(layer "F.Cu")
		(at 385.572 -29.581348)
		(property "Reference" "C2346"
			(at 0 0 0)
			(layer "F.SilkS")
			(hide yes)
			(effects
				(font
					(size 1.27 1.27)
				)
			)
		)
		(property "Value" ""
			(at 0 0 0)
			(layer "F.Fab")
			(effects
				(font
					(size 1.27 1.27)
				)
			)
		)
		(duplicate_pad_numbers_are_jumpers no)
		(fp_line
			(start -0.7874 -0.4064)
			(end 0.7874 -0.4064)
			(stroke
				(width 0.1524)
				(type default)
			)
			(layer "F.SilkS")
		)
		(fp_line
			(start -0.7874 0.4064)
			(end -0.7874 -0.4064)
			(stroke
				(width 0.1524)
				(type default)
			)
			(layer "F.SilkS")
		)
		(fp_line
			(start 0.7874 -0.4064)
			(end 0.7874 0.4064)
			(stroke
				(width 0.1524)
				(type default)
			)
			(layer "F.SilkS")
		)
		(fp_line
			(start 0.7874 0.4064)
			(end -0.7874 0.4064)
			(stroke
				(width 0.1524)
				(type default)
			)
			(layer "F.SilkS")
		)
		(fp_line
			(start -0.67945 -0.305054)
			(end -0.12065 -0.305054)
			(stroke
				(width 0.1)
				(type default)
			)
			(layer "F.Fab")
		)
		(fp_line
			(start -0.67945 0.3048)
			(end -0.67945 -0.305054)
			(stroke
				(width 0.1)
				(type default)
			)
			(layer "F.Fab")
		)
		(fp_line
			(start -0.12065 -0.305054)
			(end -0.12065 -0.2794)
			(stroke
				(width 0.1)
				(type default)
			)
			(layer "F.Fab")
		)
		(fp_line
			(start -0.12065 -0.2794)
			(end 0.12065 -0.2794)
			(stroke
				(width 0.1)
				(type default)
			)
			(layer "F.Fab")
		)
		(fp_line
			(start -0.12065 0.2794)
			(end -0.12065 0.3048)
			(stroke
				(width 0.1)
				(type default)
			)
			(layer "F.Fab")
		)
		(fp_line
			(start -0.12065 0.3048)
			(end -0.67945 0.3048)
			(stroke
				(width 0.1)
				(type default)
			)
			(layer "F.Fab")
		)
		(fp_line
			(start 0.120396 0.2794)
			(end -0.12065 0.2794)
			(stroke
				(width 0.1)
				(type default)
			)
			(layer "F.Fab")
		)
		(fp_line
			(start 0.120396 0.3048)
			(end 0.120396 0.2794)
			(stroke
				(width 0.1)
				(type default)
			)
			(layer "F.Fab")
		)
		(fp_line
			(start 0.12065 -0.3048)
			(end 0.67945 -0.3048)
			(stroke
				(width 0.1)
				(type default)
			)
			(layer "F.Fab")
		)
		(fp_line
			(start 0.12065 -0.2794)
			(end 0.12065 -0.3048)
			(stroke
				(width 0.1)
				(type default)
			)
			(layer "F.Fab")
		)
		(fp_line
			(start 0.67945 -0.3048)
			(end 0.67945 0.3048)
			(stroke
				(width 0.1)
				(type default)
			)
			(layer "F.Fab")
		)
		(fp_line
			(start 0.67945 0.3048)
			(end 0.120396 0.3048)
			(stroke
				(width 0.1)
				(type default)
			)
			(layer "F.Fab")
		)
		(pad "1" smd circle
			(at -0.40005 0)
			(size 0 0)
			(layers "F.Cu" "F.Mask" "F.Paste")
			(net "P3V3_AUX")
		)
		(pad "2" smd circle
			(at 0.40005 0)
			(size 0 0)
			(layers "F.Cu" "F.Mask" "F.Paste")
			(net "GND")
		)
	)
	(footprint ""
		(layer "F.Cu")
		(at 129.639822 -337.126326)
		(property "Reference" "PU26_P1_5"
			(at -3.267202 -6.948932 0)
			(unlocked yes)
			(layer "F.SilkS")
			(effects
				(font
					(size 0.7874 0.5842)
					(thickness 0.1524)
				)
				(justify left)
			)
		)
		(property "Value" ""
			(at 0 0 0)
			(layer "F.Fab")
			(effects
				(font
					(size 1.27 1.27)
				)
			)
		)
		(duplicate_pad_numbers_are_jumpers no)
		(fp_line
			(start -2.500122 -2.999994)
			(end -2.24409 -2.999994)
			(stroke
				(width 0.1524)
				(type default)
			)
			(layer "F.SilkS")
		)
		(fp_line
			(start -2.500122 -2.529078)
			(end -2.500122 -2.999994)
			(stroke
				(width 0.1524)
				(type default)
			)
			(layer "F.SilkS")
		)
		(fp_line
			(start -2.500122 0.6604)
			(end -2.500122 0.229108)
			(stroke
				(width 0.1524)
				(type default)
			)
			(layer "F.SilkS")
		)
		(fp_line
			(start -2.500122 2.999994)
			(end -2.500122 2.339594)
			(stroke
				(width 0.1524)
				(type default)
			)
			(layer "F.SilkS")
		)
		(fp_line
			(start -2.2987 2.999994)
			(end -2.500122 2.999994)
			(stroke
				(width 0.1524)
				(type default)
			)
			(layer "F.SilkS")
		)
		(fp_line
			(start 2.31394 -2.999994)
			(end 2.500122 -2.999994)
			(stroke
				(width 0.1524)
				(type default)
			)
			(layer "F.SilkS")
		)
		(fp_line
			(start 2.500122 -2.999994)
			(end 2.500122 -2.44348)
			(stroke
				(width 0.1524)
				(type default)
			)
			(layer "F.SilkS")
		)
		(fp_line
			(start 2.500122 2.339594)
			(end 2.500122 2.999994)
			(stroke
				(width 0.1524)
				(type default)
			)
			(layer "F.SilkS")
		)
		(fp_line
			(start 2.500122 2.999994)
			(end 2.2987 2.999994)
			(stroke
				(width 0.1524)
				(type default)
			)
			(layer "F.SilkS")
		)
		(fp_poly
			(pts
				(xy -2.181606 -3.555492) (xy -2.689606 -2.539492) (xy -3.197606 -3.555492)
			)
			(stroke
				(width 0)
				(type default)
			)
			(fill yes)
			(layer "F.SilkS")
		)
		(fp_line
			(start -2.500122 -2.999994)
			(end 2.500122 -2.999994)
			(stroke
				(width 0.1)
				(type default)
			)
			(layer "F.Fab")
		)
		(fp_line
			(start -2.500122 2.999994)
			(end -2.500122 -2.999994)
			(stroke
				(width 0.1)
				(type default)
			)
			(layer "F.Fab")
		)
		(fp_line
			(start 2.500122 -2.999994)
			(end 2.500122 2.999994)
			(stroke
				(width 0.1)
				(type default)
			)
			(layer "F.Fab")
		)
		(fp_line
			(start 2.500122 2.999994)
			(end -2.500122 2.999994)
			(stroke
				(width 0.1)
				(type default)
			)
			(layer "F.Fab")
		)
		(fp_poly
			(pts
				(xy -4.218432 -2.783078) (xy -4.218432 -1.767078) (xy -3.202432 -2.275078)
			)
			(stroke
				(width 0)
				(type default)
			)
			(fill yes)
			(layer "F.Fab")
		)
		(pad "1" smd rect
			(at -2.400046 -2.275078 90)
			(size 0.2286 0.6096)
			(layers "F.Cu" "F.Mask" "F.Paste")
			(net "PVCCIN_CPU1_VOS5")
		)
		(pad "2" smd rect
			(at -2.400046 -1.82499 90)
			(size 0.2286 0.6096)
			(layers "F.Cu" "F.Mask" "F.Paste")
			(net "GND")
		)
		(pad "3" smd rect
			(at -2.400046 -1.374902 90)
			(size 0.2286 0.6096)
			(layers "F.Cu" "F.Mask" "F.Paste")
			(net "PVCCIN_CPU1_VDD5")
		)
		(pad "4" smd rect
			(at -2.400046 -0.925068 90)
			(size 0.2286 0.6096)
			(layers "F.Cu" "F.Mask" "F.Paste")
			(net "PVCCIN_CPU1_PVCC")
		)
		(pad "5" smd rect
			(at -2.400046 -0.47498 90)
			(size 0.2286 0.6096)
			(layers "F.Cu" "F.Mask" "F.Paste")
			(net "GND")
		)
		(pad "6" smd rect
			(at -2.400046 -0.024892 90)
			(size 0.2286 0.6096)
			(layers "F.Cu" "F.Mask" "F.Paste")
			(net "Net_8532")
		)
		(pad "7_9-20_24" smd circle
			(at 0 1.150112 90)
			(size 0 0)
			(layers "F.Cu" "F.Mask" "F.Paste")
			(net "GND")
		)
		(pad "10_19" smd rect
			(at 0 2.899918 90)
			(size 0.6096 4.318)
			(layers "F.Cu" "F.Mask" "F.Paste")
			(net "SW_PVCCIN_CPU1_SW5")
		)
		(pad "25_29" smd rect
			(at 1.549908 -1.279906 270)
			(size 2.0574 2.3114)
			(layers "F.Cu" "F.Mask" "F.Paste")
			(net "SW_P12V_PVCCIN_CPU1_FLT")
		)
		(pad "30" smd rect
			(at 2.05994 -2.899918)
			(size 0.2286 0.6096)
			(layers "F.Cu" "F.Mask" "F.Paste")
			(net "SW_P12V_PVCCIN_CPU1_FLT")
		)
		(pad "31" smd rect
			(at 1.610106 -2.899918)
			(size 0.2286 0.6096)
			(layers "F.Cu" "F.Mask" "F.Paste")
			(net "Net_8533")
		)
		(pad "32" smd rect
			(at 1.160018 -2.899918)
			(size 0.2286 0.6096)
			(layers "F.Cu" "F.Mask" "F.Paste")
			(net "SW_PVCCIN_CPU1_BOOTR5")
		)
		(pad "33" smd rect
			(at 0.70993 -2.899918)
			(size 0.2286 0.6096)
			(layers "F.Cu" "F.Mask" "F.Paste")
			(net "SW_PVCCIN_CPU1_BOOT5")
		)
		(pad "34" smd rect
			(at 0.260096 -2.899918)
			(size 0.2286 0.6096)
			(layers "F.Cu" "F.Mask" "F.Paste")
			(net "PVCCIN_CPU1_PWM5")
		)
		(pad "35" smd rect
			(at -0.189992 -2.899918)
			(size 0.2286 0.6096)
			(layers "F.Cu" "F.Mask" "F.Paste")
			(net "PVCCIN_CPU1_VDD5")
		)
		(pad "36" smd rect
			(at -0.64008 -2.899918)
			(size 0.2286 0.6096)
			(layers "F.Cu" "F.Mask" "F.Paste")
			(net "PVCCIN_CPU1_ATSEN")
		)
		(pad "37" smd rect
			(at -1.089914 -2.899918)
			(size 0.2286 0.6096)
			(layers "F.Cu" "F.Mask" "F.Paste")
			(net "PVCCIN_CPU1_LSET5")
		)
		(pad "38" smd rect
			(at -1.540002 -2.899918)
			(size 0.2286 0.6096)
			(layers "F.Cu" "F.Mask" "F.Paste")
			(net "PVCCIN_CPU1_IMON5")
		)
		(pad "39" smd rect
			(at -1.99009 -2.899918)
			(size 0.2286 0.6096)
			(layers "F.Cu" "F.Mask" "F.Paste")
			(net "PVCCIN_CPU1_VREF")
		)
		(pad "40" smd rect
			(at -0.87503 -1.27508)
			(size 1.7526 1.9558)
			(layers "F.Cu" "F.Mask" "F.Paste")
			(net "GND")
		)
		(pad "41" smd rect
			(at -1.525016 0.249936 270)
			(size 0.3048 0.4572)
			(layers "F.Cu" "F.Mask" "F.Paste")
			(net "Net_8531")
		)
		(zone
			(layer "F.Cu")
			(hatch none 0.5)
			(connect_pads
				(clearance 0)
			)
			(min_thickness 0.25)
			(keepout
				(tracks not_allowed)
				(vias allowed)
				(pads allowed)
				(copperpour not_allowed)
				(footprints allowed)
			)
			(placement
				(enabled no)
				(sheetname "")
			)
			(fill
				(thermal_gap 0.5)
				(thermal_bridge_width 0.5)
				(island_removal_mode 0)
			)
			(polygon
				(pts
					(xy 127.595376 -338.699348) (xy 127.837692 -338.699348) (xy 127.837692 -337.746848) (xy 127.595376 -337.746848)
				)
			)
		)
		(zone
			(layer "F.Cu")
			(hatch none 0.5)
			(connect_pads
				(clearance 0)
			)
			(min_thickness 0.25)
			(keepout
				(tracks not_allowed)
				(vias allowed)
				(pads allowed)
				(copperpour not_allowed)
				(footprints allowed)
			)
			(placement
				(enabled no)
				(sheetname "")
			)
			(fill
				(thermal_gap 0.5)
				(thermal_bridge_width 0.5)
				(island_removal_mode 0)
			)
			(polygon
				(pts
					(xy 127.1397 -334.126332) (xy 127.1397 -334.875632) (xy 132.139944 -334.875632) (xy 132.139944 -334.126332)
					(xy 131.849622 -334.126332) (xy 131.849622 -334.582008) (xy 127.430022 -334.582008) (xy 127.430022 -334.126332)
				)
			)
		)
	)
	(footprint ""
		(layer "F.Cu")
		(at 502.47169 -469.569546)
		(property "Reference" "JP15_23"
			(at -1.6764 -1.07823 0)
			(unlocked yes)
			(layer "F.SilkS")
			(effects
				(font
					(size 0.7874 0.5842)
					(thickness 0.1524)
				)
				(justify left)
			)
		)
		(property "Value" ""
			(at 0 0 0)
			(layer "F.Fab")
			(effects
				(font
					(size 1.27 1.27)
				)
			)
		)
		(duplicate_pad_numbers_are_jumpers no)
		(pad "1" smd circle
			(at 0 0)
			(size 0.762 0.762)
			(layers "F.Cu" "F.Mask" "F.Paste")
			(net "Net_8622")
		)
	)
	(footprint ""
		(layer "F.Cu")
		(at 285.714948 -411.2895 90)
		(property "Reference" "R4554"
			(at 0 0 90)
			(layer "F.SilkS")
			(hide yes)
			(effects
				(font
					(size 1.27 1.27)
				)
			)
		)
		(property "Value" ""
			(at 0 0 90)
			(layer "F.Fab")
			(effects
				(font
					(size 1.27 1.27)
				)
			)
		)
		(duplicate_pad_numbers_are_jumpers no)
		(fp_line
			(start 0.7874 -0.4064)
			(end 0.7874 0.4064)
			(stroke
				(width 0.1524)
				(type default)
			)
			(layer "F.SilkS")
		)
		(fp_line
			(start -0.7874 -0.4064)
			(end 0.7874 -0.4064)
			(stroke
				(width 0.1524)
				(type default)
			)
			(layer "F.SilkS")
		)
		(fp_line
			(start 0.7874 0.4064)
			(end -0.7874 0.4064)
			(stroke
				(width 0.1524)
				(type default)
			)
			(layer "F.SilkS")
		)
		(fp_line
			(start -0.7874 0.4064)
			(end -0.7874 -0.4064)
			(stroke
				(width 0.1524)
				(type default)
			)
			(layer "F.SilkS")
		)
		(fp_line
			(start -0.12065 -0.305054)
			(end -0.12065 -0.2794)
			(stroke
				(width 0.1)
				(type default)
			)
			(layer "F.Fab")
		)
		(fp_line
			(start -0.67945 -0.305054)
			(end -0.12065 -0.305054)
			(stroke
				(width 0.1)
				(type default)
			)
			(layer "F.Fab")
		)
		(fp_line
			(start 0.67945 -0.3048)
			(end 0.67945 0.3048)
			(stroke
				(width 0.1)
				(type default)
			)
			(layer "F.Fab")
		)
		(fp_line
			(start 0.12065 -0.3048)
			(end 0.67945 -0.3048)
			(stroke
				(width 0.1)
				(type default)
			)
			(layer "F.Fab")
		)
		(fp_line
			(start 0.12065 -0.2794)
			(end 0.12065 -0.3048)
			(stroke
				(width 0.1)
				(type default)
			)
			(layer "F.Fab")
		)
		(fp_line
			(start -0.12065 -0.2794)
			(end 0.12065 -0.2794)
			(stroke
				(width 0.1)
				(type default)
			)
			(layer "F.Fab")
		)
		(fp_line
			(start 0.120396 0.2794)
			(end -0.12065 0.2794)
			(stroke
				(width 0.1)
				(type default)
			)
			(layer "F.Fab")
		)
		(fp_line
			(start -0.12065 0.2794)
			(end -0.12065 0.3048)
			(stroke
				(width 0.1)
				(type default)
			)
			(layer "F.Fab")
		)
		(fp_line
			(start 0.67945 0.3048)
			(end 0.120396 0.3048)
			(stroke
				(width 0.1)
				(type default)
			)
			(layer "F.Fab")
		)
		(fp_line
			(start 0.120396 0.3048)
			(end 0.120396 0.2794)
			(stroke
				(width 0.1)
				(type default)
			)
			(layer "F.Fab")
		)
		(fp_line
			(start -0.12065 0.3048)
			(end -0.67945 0.3048)
			(stroke
				(width 0.1)
				(type default)
			)
			(layer "F.Fab")
		)
		(fp_line
			(start -0.67945 0.3048)
			(end -0.67945 -0.305054)
			(stroke
				(width 0.1)
				(type default)
			)
			(layer "F.Fab")
		)
		(pad "1" smd circle
			(at -0.40005 0 90)
			(size 0 0)
			(layers "F.Cu" "F.Mask" "F.Paste")
			(net "P3V3_AUX")
		)
		(pad "2" smd circle
			(at 0.40005 0 90)
			(size 0 0)
			(layers "F.Cu" "F.Mask" "F.Paste")
			(net "HPDB_HSC_PWRGD_ISO")
		)
	)
	(footprint ""
		(layer "F.Cu")
		(at 160.83788 -113.756948)
		(property "Reference" "R3484"
			(at 0 0 0)
			(layer "F.SilkS")
			(hide yes)
			(effects
				(font
					(size 1.27 1.27)
				)
			)
		)
		(property "Value" ""
			(at 0 0 0)
			(layer "F.Fab")
			(effects
				(font
					(size 1.27 1.27)
				)
			)
		)
		(duplicate_pad_numbers_are_jumpers no)
		(fp_line
			(start -0.7874 -0.4064)
			(end 0.7874 -0.4064)
			(stroke
				(width 0.1524)
				(type default)
			)
			(layer "F.SilkS")
		)
		(fp_line
			(start -0.7874 0.4064)
			(end -0.7874 -0.4064)
			(stroke
				(width 0.1524)
				(type default)
			)
			(layer "F.SilkS")
		)
		(fp_line
			(start 0.7874 -0.4064)
			(end 0.7874 0.4064)
			(stroke
				(width 0.1524)
				(type default)
			)
			(layer "F.SilkS")
		)
		(fp_line
			(start 0.7874 0.4064)
			(end -0.7874 0.4064)
			(stroke
				(width 0.1524)
				(type default)
			)
			(layer "F.SilkS")
		)
		(fp_line
			(start -0.67945 -0.305054)
			(end -0.12065 -0.305054)
			(stroke
				(width 0.1)
				(type default)
			)
			(layer "F.Fab")
		)
		(fp_line
			(start -0.67945 0.3048)
			(end -0.67945 -0.305054)
			(stroke
				(width 0.1)
				(type default)
			)
			(layer "F.Fab")
		)
		(fp_line
			(start -0.12065 -0.305054)
			(end -0.12065 -0.2794)
			(stroke
				(width 0.1)
				(type default)
			)
			(layer "F.Fab")
		)
		(fp_line
			(start -0.12065 -0.2794)
			(end 0.12065 -0.2794)
			(stroke
				(width 0.1)
				(type default)
			)
			(layer "F.Fab")
		)
		(fp_line
			(start -0.12065 0.2794)
			(end -0.12065 0.3048)
			(stroke
				(width 0.1)
				(type default)
			)
			(layer "F.Fab")
		)
		(fp_line
			(start -0.12065 0.3048)
			(end -0.67945 0.3048)
			(stroke
				(width 0.1)
				(type default)
			)
			(layer "F.Fab")
		)
		(fp_line
			(start 0.120396 0.2794)
			(end -0.12065 0.2794)
			(stroke
				(width 0.1)
				(type default)
			)
			(layer "F.Fab")
		)
		(fp_line
			(start 0.120396 0.3048)
			(end 0.120396 0.2794)
			(stroke
				(width 0.1)
				(type default)
			)
			(layer "F.Fab")
		)
		(fp_line
			(start 0.12065 -0.3048)
			(end 0.67945 -0.3048)
			(stroke
				(width 0.1)
				(type default)
			)
			(layer "F.Fab")
		)
		(fp_line
			(start 0.12065 -0.2794)
			(end 0.12065 -0.3048)
			(stroke
				(width 0.1)
				(type default)
			)
			(layer "F.Fab")
		)
		(fp_line
			(start 0.67945 -0.3048)
			(end 0.67945 0.3048)
			(stroke
				(width 0.1)
				(type default)
			)
			(layer "F.Fab")
		)
		(fp_line
			(start 0.67945 0.3048)
			(end 0.120396 0.3048)
			(stroke
				(width 0.1)
				(type default)
			)
			(layer "F.Fab")
		)
		(pad "1" smd circle
			(at -0.40005 0)
			(size 0 0)
			(layers "F.Cu" "F.Mask" "F.Paste")
			(net "GPU_FPGA_OVERT_ISO_N")
		)
		(pad "2" smd circle
			(at 0.40005 0)
			(size 0 0)
			(layers "F.Cu" "F.Mask" "F.Paste")
			(net "GPU_FPGA_OVERT_ISO_R_N")
		)
	)
	(footprint ""
		(layer "F.Cu")
		(at 226.733608 -400.759422)
		(property "Reference" "PR3992"
			(at 0 0 0)
			(layer "F.SilkS")
			(hide yes)
			(effects
				(font
					(size 1.27 1.27)
				)
			)
		)
		(property "Value" ""
			(at 0 0 0)
			(layer "F.Fab")
			(effects
				(font
					(size 1.27 1.27)
				)
			)
		)
		(duplicate_pad_numbers_are_jumpers no)
		(fp_line
			(start -0.7874 -0.4064)
			(end 0.7874 -0.4064)
			(stroke
				(width 0.1524)
				(type default)
			)
			(layer "F.SilkS")
		)
		(fp_line
			(start -0.7874 0.4064)
			(end -0.7874 -0.4064)
			(stroke
				(width 0.1524)
				(type default)
			)
			(layer "F.SilkS")
		)
		(fp_line
			(start 0.7874 -0.4064)
			(end 0.7874 0.4064)
			(stroke
				(width 0.1524)
				(type default)
			)
			(layer "F.SilkS")
		)
		(fp_line
			(start 0.7874 0.4064)
			(end -0.7874 0.4064)
			(stroke
				(width 0.1524)
				(type default)
			)
			(layer "F.SilkS")
		)
		(fp_line
			(start -0.67945 -0.305054)
			(end -0.12065 -0.305054)
			(stroke
				(width 0.1)
				(type default)
			)
			(layer "F.Fab")
		)
		(fp_line
			(start -0.67945 0.3048)
			(end -0.67945 -0.305054)
			(stroke
				(width 0.1)
				(type default)
			)
			(layer "F.Fab")
		)
		(fp_line
			(start -0.12065 -0.305054)
			(end -0.12065 -0.2794)
			(stroke
				(width 0.1)
				(type default)
			)
			(layer "F.Fab")
		)
		(fp_line
			(start -0.12065 -0.2794)
			(end 0.12065 -0.2794)
			(stroke
				(width 0.1)
				(type default)
			)
			(layer "F.Fab")
		)
		(fp_line
			(start -0.12065 0.2794)
			(end -0.12065 0.3048)
			(stroke
				(width 0.1)
				(type default)
			)
			(layer "F.Fab")
		)
		(fp_line
			(start -0.12065 0.3048)
			(end -0.67945 0.3048)
			(stroke
				(width 0.1)
				(type default)
			)
			(layer "F.Fab")
		)
		(fp_line
			(start 0.120396 0.2794)
			(end -0.12065 0.2794)
			(stroke
				(width 0.1)
				(type default)
			)
			(layer "F.Fab")
		)
		(fp_line
			(start 0.120396 0.3048)
			(end 0.120396 0.2794)
			(stroke
				(width 0.1)
				(type default)
			)
			(layer "F.Fab")
		)
		(fp_line
			(start 0.12065 -0.3048)
			(end 0.67945 -0.3048)
			(stroke
				(width 0.1)
				(type default)
			)
			(layer "F.Fab")
		)
		(fp_line
			(start 0.12065 -0.2794)
			(end 0.12065 -0.3048)
			(stroke
				(width 0.1)
				(type default)
			)
			(layer "F.Fab")
		)
		(fp_line
			(start 0.67945 -0.3048)
			(end 0.67945 0.3048)
			(stroke
				(width 0.1)
				(type default)
			)
			(layer "F.Fab")
		)
		(fp_line
			(start 0.67945 0.3048)
			(end 0.120396 0.3048)
			(stroke
				(width 0.1)
				(type default)
			)
			(layer "F.Fab")
		)
		(pad "1" smd circle
			(at -0.40005 0)
			(size 0 0)
			(layers "F.Cu" "F.Mask" "F.Paste")
			(net "HSC_D_OC_3")
		)
		(pad "2" smd circle
			(at 0.40005 0)
			(size 0 0)
			(layers "F.Cu" "F.Mask" "F.Paste")
			(net "HSC_D_OC_R")
		)
	)
	(footprint ""
		(layer "F.Cu")
		(at 321.8561 -76.585064 90)
		(property "Reference" "R2975"
			(at 0 0 90)
			(layer "F.SilkS")
			(hide yes)
			(effects
				(font
					(size 1.27 1.27)
				)
			)
		)
		(property "Value" ""
			(at 0 0 90)
			(layer "F.Fab")
			(effects
				(font
					(size 1.27 1.27)
				)
			)
		)
		(duplicate_pad_numbers_are_jumpers no)
		(fp_line
			(start 0.7874 -0.4064)
			(end 0.7874 0.4064)
			(stroke
				(width 0.1524)
				(type default)
			)
			(layer "F.SilkS")
		)
		(fp_line
			(start -0.7874 -0.4064)
			(end 0.7874 -0.4064)
			(stroke
				(width 0.1524)
				(type default)
			)
			(layer "F.SilkS")
		)
		(fp_line
			(start 0.7874 0.4064)
			(end -0.7874 0.4064)
			(stroke
				(width 0.1524)
				(type default)
			)
			(layer "F.SilkS")
		)
		(fp_line
			(start -0.7874 0.4064)
			(end -0.7874 -0.4064)
			(stroke
				(width 0.1524)
				(type default)
			)
			(layer "F.SilkS")
		)
		(fp_line
			(start -0.12065 -0.305054)
			(end -0.12065 -0.2794)
			(stroke
				(width 0.1)
				(type default)
			)
			(layer "F.Fab")
		)
		(fp_line
			(start -0.67945 -0.305054)
			(end -0.12065 -0.305054)
			(stroke
				(width 0.1)
				(type default)
			)
			(layer "F.Fab")
		)
		(fp_line
			(start 0.67945 -0.3048)
			(end 0.67945 0.3048)
			(stroke
				(width 0.1)
				(type default)
			)
			(layer "F.Fab")
		)
		(fp_line
			(start 0.12065 -0.3048)
			(end 0.67945 -0.3048)
			(stroke
				(width 0.1)
				(type default)
			)
			(layer "F.Fab")
		)
		(fp_line
			(start 0.12065 -0.2794)
			(end 0.12065 -0.3048)
			(stroke
				(width 0.1)
				(type default)
			)
			(layer "F.Fab")
		)
		(fp_line
			(start -0.12065 -0.2794)
			(end 0.12065 -0.2794)
			(stroke
				(width 0.1)
				(type default)
			)
			(layer "F.Fab")
		)
		(fp_line
			(start 0.120396 0.2794)
			(end -0.12065 0.2794)
			(stroke
				(width 0.1)
				(type default)
			)
			(layer "F.Fab")
		)
		(fp_line
			(start -0.12065 0.2794)
			(end -0.12065 0.3048)
			(stroke
				(width 0.1)
				(type default)
			)
			(layer "F.Fab")
		)
		(fp_line
			(start 0.67945 0.3048)
			(end 0.120396 0.3048)
			(stroke
				(width 0.1)
				(type default)
			)
			(layer "F.Fab")
		)
		(fp_line
			(start 0.120396 0.3048)
			(end 0.120396 0.2794)
			(stroke
				(width 0.1)
				(type default)
			)
			(layer "F.Fab")
		)
		(fp_line
			(start -0.12065 0.3048)
			(end -0.67945 0.3048)
			(stroke
				(width 0.1)
				(type default)
			)
			(layer "F.Fab")
		)
		(fp_line
			(start -0.67945 0.3048)
			(end -0.67945 -0.305054)
			(stroke
				(width 0.1)
				(type default)
			)
			(layer "F.Fab")
		)
		(pad "1" smd circle
			(at -0.40005 0 90)
			(size 0 0)
			(layers "F.Cu" "F.Mask" "F.Paste")
			(net "FAB_REV_ID1")
		)
		(pad "2" smd circle
			(at 0.40005 0 90)
			(size 0 0)
			(layers "F.Cu" "F.Mask" "F.Paste")
			(net "GND")
		)
	)
	(footprint ""
		(layer "F.Cu")
		(at 13.800582 -410.802836 90)
		(property "Reference" "R2693"
			(at 0 0 90)
			(layer "F.SilkS")
			(hide yes)
			(effects
				(font
					(size 1.27 1.27)
				)
			)
		)
		(property "Value" ""
			(at 0 0 90)
			(layer "F.Fab")
			(effects
				(font
					(size 1.27 1.27)
				)
			)
		)
		(duplicate_pad_numbers_are_jumpers no)
		(fp_line
			(start 0.7874 -0.4064)
			(end 0.7874 0.4064)
			(stroke
				(width 0.1524)
				(type default)
			)
			(layer "F.SilkS")
		)
		(fp_line
			(start -0.7874 -0.4064)
			(end 0.7874 -0.4064)
			(stroke
				(width 0.1524)
				(type default)
			)
			(layer "F.SilkS")
		)
		(fp_line
			(start 0.7874 0.4064)
			(end -0.7874 0.4064)
			(stroke
				(width 0.1524)
				(type default)
			)
			(layer "F.SilkS")
		)
		(fp_line
			(start -0.7874 0.4064)
			(end -0.7874 -0.4064)
			(stroke
				(width 0.1524)
				(type default)
			)
			(layer "F.SilkS")
		)
		(fp_line
			(start -0.12065 -0.305054)
			(end -0.12065 -0.2794)
			(stroke
				(width 0.1)
				(type default)
			)
			(layer "F.Fab")
		)
		(fp_line
			(start -0.67945 -0.305054)
			(end -0.12065 -0.305054)
			(stroke
				(width 0.1)
				(type default)
			)
			(layer "F.Fab")
		)
		(fp_line
			(start 0.67945 -0.3048)
			(end 0.67945 0.3048)
			(stroke
				(width 0.1)
				(type default)
			)
			(layer "F.Fab")
		)
		(fp_line
			(start 0.12065 -0.3048)
			(end 0.67945 -0.3048)
			(stroke
				(width 0.1)
				(type default)
			)
			(layer "F.Fab")
		)
		(fp_line
			(start 0.12065 -0.2794)
			(end 0.12065 -0.3048)
			(stroke
				(width 0.1)
				(type default)
			)
			(layer "F.Fab")
		)
		(fp_line
			(start -0.12065 -0.2794)
			(end 0.12065 -0.2794)
			(stroke
				(width 0.1)
				(type default)
			)
			(layer "F.Fab")
		)
		(fp_line
			(start 0.120396 0.2794)
			(end -0.12065 0.2794)
			(stroke
				(width 0.1)
				(type default)
			)
			(layer "F.Fab")
		)
		(fp_line
			(start -0.12065 0.2794)
			(end -0.12065 0.3048)
			(stroke
				(width 0.1)
				(type default)
			)
			(layer "F.Fab")
		)
		(fp_line
			(start 0.67945 0.3048)
			(end 0.120396 0.3048)
			(stroke
				(width 0.1)
				(type default)
			)
			(layer "F.Fab")
		)
		(fp_line
			(start 0.120396 0.3048)
			(end 0.120396 0.2794)
			(stroke
				(width 0.1)
				(type default)
			)
			(layer "F.Fab")
		)
		(fp_line
			(start -0.12065 0.3048)
			(end -0.67945 0.3048)
			(stroke
				(width 0.1)
				(type default)
			)
			(layer "F.Fab")
		)
		(fp_line
			(start -0.67945 0.3048)
			(end -0.67945 -0.305054)
			(stroke
				(width 0.1)
				(type default)
			)
			(layer "F.Fab")
		)
		(pad "1" smd circle
			(at -0.40005 0 90)
			(size 0 0)
			(layers "F.Cu" "F.Mask" "F.Paste")
			(net "P3V3_AUX")
		)
		(pad "2" smd circle
			(at 0.40005 0 90)
			(size 0 0)
			(layers "F.Cu" "F.Mask" "F.Paste")
			(net "TCA9539_0_ADD1")
		)
	)
	(footprint ""
		(layer "F.Cu")
		(at 164.52088 -42.255948)
		(property "Reference" "R486"
			(at 0 0 0)
			(layer "F.SilkS")
			(hide yes)
			(effects
				(font
					(size 1.27 1.27)
				)
			)
		)
		(property "Value" ""
			(at 0 0 0)
			(layer "F.Fab")
			(effects
				(font
					(size 1.27 1.27)
				)
			)
		)
		(duplicate_pad_numbers_are_jumpers no)
		(fp_line
			(start -0.7874 -0.4064)
			(end 0.7874 -0.4064)
			(stroke
				(width 0.1524)
				(type default)
			)
			(layer "F.SilkS")
		)
		(fp_line
			(start -0.7874 0.4064)
			(end -0.7874 -0.4064)
			(stroke
				(width 0.1524)
				(type default)
			)
			(layer "F.SilkS")
		)
		(fp_line
			(start 0.7874 -0.4064)
			(end 0.7874 0.4064)
			(stroke
				(width 0.1524)
				(type default)
			)
			(layer "F.SilkS")
		)
		(fp_line
			(start 0.7874 0.4064)
			(end -0.7874 0.4064)
			(stroke
				(width 0.1524)
				(type default)
			)
			(layer "F.SilkS")
		)
		(fp_line
			(start -0.67945 -0.305054)
			(end -0.12065 -0.305054)
			(stroke
				(width 0.1)
				(type default)
			)
			(layer "F.Fab")
		)
		(fp_line
			(start -0.67945 0.3048)
			(end -0.67945 -0.305054)
			(stroke
				(width 0.1)
				(type default)
			)
			(layer "F.Fab")
		)
		(fp_line
			(start -0.12065 -0.305054)
			(end -0.12065 -0.2794)
			(stroke
				(width 0.1)
				(type default)
			)
			(layer "F.Fab")
		)
		(fp_line
			(start -0.12065 -0.2794)
			(end 0.12065 -0.2794)
			(stroke
				(width 0.1)
				(type default)
			)
			(layer "F.Fab")
		)
		(fp_line
			(start -0.12065 0.2794)
			(end -0.12065 0.3048)
			(stroke
				(width 0.1)
				(type default)
			)
			(layer "F.Fab")
		)
		(fp_line
			(start -0.12065 0.3048)
			(end -0.67945 0.3048)
			(stroke
				(width 0.1)
				(type default)
			)
			(layer "F.Fab")
		)
		(fp_line
			(start 0.120396 0.2794)
			(end -0.12065 0.2794)
			(stroke
				(width 0.1)
				(type default)
			)
			(layer "F.Fab")
		)
		(fp_line
			(start 0.120396 0.3048)
			(end 0.120396 0.2794)
			(stroke
				(width 0.1)
				(type default)
			)
			(layer "F.Fab")
		)
		(fp_line
			(start 0.12065 -0.3048)
			(end 0.67945 -0.3048)
			(stroke
				(width 0.1)
				(type default)
			)
			(layer "F.Fab")
		)
		(fp_line
			(start 0.12065 -0.2794)
			(end 0.12065 -0.3048)
			(stroke
				(width 0.1)
				(type default)
			)
			(layer "F.Fab")
		)
		(fp_line
			(start 0.67945 -0.3048)
			(end 0.67945 0.3048)
			(stroke
				(width 0.1)
				(type default)
			)
			(layer "F.Fab")
		)
		(fp_line
			(start 0.67945 0.3048)
			(end 0.120396 0.3048)
			(stroke
				(width 0.1)
				(type default)
			)
			(layer "F.Fab")
		)
		(pad "1" smd circle
			(at -0.40005 0)
			(size 0 0)
			(layers "F.Cu" "F.Mask" "F.Paste")
			(net "M2_SSD0_CLKREQ_EN_N")
		)
		(pad "2" smd circle
			(at 0.40005 0)
			(size 0 0)
			(layers "F.Cu" "F.Mask" "F.Paste")
			(net "M2_SSD0_CLKREQ_EN_N_BUF")
		)
	)
	(footprint ""
		(layer "F.Cu")
		(at 107.3658 -408.686)
		(property "Reference" "Q151"
			(at 2.76098 0.738632 0)
			(unlocked yes)
			(layer "F.SilkS")
			(effects
				(font
					(size 0.7874 0.5842)
					(thickness 0.1524)
				)
				(justify left)
			)
		)
		(property "Value" ""
			(at 0 0 0)
			(layer "F.Fab")
			(effects
				(font
					(size 1.27 1.27)
				)
			)
		)
		(duplicate_pad_numbers_are_jumpers no)
		(fp_line
			(start -1.332738 -1.100074)
			(end -0.4826 -1.100074)
			(stroke
				(width 0.1524)
				(type default)
			)
			(layer "F.SilkS")
		)
		(fp_line
			(start -1.332738 1.100074)
			(end -1.332738 -1.100074)
			(stroke
				(width 0.1524)
				(type default)
			)
			(layer "F.SilkS")
		)
		(fp_line
			(start -0.4826 -1.100074)
			(end 0 -0.541274)
			(stroke
				(width 0.1524)
				(type default)
			)
			(layer "F.SilkS")
		)
		(fp_line
			(start 0 -0.541274)
			(end 0.4826 -1.100074)
			(stroke
				(width 0.1524)
				(type default)
			)
			(layer "F.SilkS")
		)
		(fp_line
			(start 0.4826 -1.100074)
			(end 1.332738 -1.100074)
			(stroke
				(width 0.1524)
				(type default)
			)
			(layer "F.SilkS")
		)
		(fp_line
			(start 1.332738 -1.100074)
			(end 1.332738 1.100074)
			(stroke
				(width 0.1524)
				(type default)
			)
			(layer "F.SilkS")
		)
		(fp_line
			(start 1.332738 1.100074)
			(end -1.332738 1.100074)
			(stroke
				(width 0.1524)
				(type default)
			)
			(layer "F.SilkS")
		)
		(fp_poly
			(pts
				(xy -2.2352 -0.298958) (xy -2.2352 -1.001014) (xy -1.533144 -0.649986)
			)
			(stroke
				(width 0)
				(type default)
			)
			(fill yes)
			(layer "F.SilkS")
		)
		(fp_line
			(start -0.674878 -1.100074)
			(end 0.674878 -1.100074)
			(stroke
				(width 0.1)
				(type default)
			)
			(layer "F.Fab")
		)
		(fp_line
			(start -0.674878 1.100074)
			(end -0.674878 -1.100074)
			(stroke
				(width 0.1)
				(type default)
			)
			(layer "F.Fab")
		)
		(fp_line
			(start 0.674878 -1.100074)
			(end 0.674878 1.100074)
			(stroke
				(width 0.1)
				(type default)
			)
			(layer "F.Fab")
		)
		(fp_line
			(start 0.674878 1.100074)
			(end -0.674878 1.100074)
			(stroke
				(width 0.1)
				(type default)
			)
			(layer "F.Fab")
		)
		(fp_poly
			(pts
				(xy -2.2352 -0.298958) (xy -2.2352 -1.001014) (xy -1.533144 -0.649986)
			)
			(stroke
				(width 0)
				(type default)
			)
			(fill yes)
			(layer "F.Fab")
		)
		(pad "1" smd rect
			(at -0.94996 -0.649986 90)
			(size 0.4318 0.508)
			(layers "F.Cu" "F.Mask" "F.Paste")
			(net "GND")
		)
		(pad "2" smd rect
			(at -0.94996 0 90)
			(size 0.4318 0.508)
			(layers "F.Cu" "F.Mask" "F.Paste")
			(net "PRSNT_SWB_N")
		)
		(pad "3" smd rect
			(at -0.94996 0.649986 90)
			(size 0.4318 0.508)
			(layers "F.Cu" "F.Mask" "F.Paste")
			(net "PRSNT_SWB_ISO_N")
		)
		(pad "4" smd rect
			(at 0.94996 0.649986 90)
			(size 0.4318 0.508)
			(layers "F.Cu" "F.Mask" "F.Paste")
			(net "GND")
		)
		(pad "5" smd rect
			(at 0.94996 0 90)
			(size 0.4318 0.508)
			(layers "F.Cu" "F.Mask" "F.Paste")
			(net "PRSNT_SWB")
		)
		(pad "6" smd rect
			(at 0.94996 -0.649986 90)
			(size 0.4318 0.508)
			(layers "F.Cu" "F.Mask" "F.Paste")
			(net "PRSNT_SWB")
		)
	)
	(footprint ""
		(layer "F.Cu")
		(at 446.851024 -175.956468)
		(property "Reference" "PC1276"
			(at 0 0 0)
			(layer "F.SilkS")
			(hide yes)
			(effects
				(font
					(size 1.27 1.27)
				)
			)
		)
		(property "Value" ""
			(at 0 0 0)
			(layer "F.Fab")
			(effects
				(font
					(size 1.27 1.27)
				)
			)
		)
		(duplicate_pad_numbers_are_jumpers no)
		(fp_line
			(start -0.7874 -0.4064)
			(end 0.7874 -0.4064)
			(stroke
				(width 0.1524)
				(type default)
			)
			(layer "F.SilkS")
		)
		(fp_line
			(start -0.7874 0.4064)
			(end -0.7874 -0.4064)
			(stroke
				(width 0.1524)
				(type default)
			)
			(layer "F.SilkS")
		)
		(fp_line
			(start 0.7874 -0.4064)
			(end 0.7874 0.4064)
			(stroke
				(width 0.1524)
				(type default)
			)
			(layer "F.SilkS")
		)
		(fp_line
			(start 0.7874 0.4064)
			(end -0.7874 0.4064)
			(stroke
				(width 0.1524)
				(type default)
			)
			(layer "F.SilkS")
		)
		(fp_line
			(start -0.67945 -0.305054)
			(end -0.12065 -0.305054)
			(stroke
				(width 0.1)
				(type default)
			)
			(layer "F.Fab")
		)
		(fp_line
			(start -0.67945 0.3048)
			(end -0.67945 -0.305054)
			(stroke
				(width 0.1)
				(type default)
			)
			(layer "F.Fab")
		)
		(fp_line
			(start -0.12065 -0.305054)
			(end -0.12065 -0.2794)
			(stroke
				(width 0.1)
				(type default)
			)
			(layer "F.Fab")
		)
		(fp_line
			(start -0.12065 -0.2794)
			(end 0.12065 -0.2794)
			(stroke
				(width 0.1)
				(type default)
			)
			(layer "F.Fab")
		)
		(fp_line
			(start -0.12065 0.2794)
			(end -0.12065 0.3048)
			(stroke
				(width 0.1)
				(type default)
			)
			(layer "F.Fab")
		)
		(fp_line
			(start -0.12065 0.3048)
			(end -0.67945 0.3048)
			(stroke
				(width 0.1)
				(type default)
			)
			(layer "F.Fab")
		)
		(fp_line
			(start 0.120396 0.2794)
			(end -0.12065 0.2794)
			(stroke
				(width 0.1)
				(type default)
			)
			(layer "F.Fab")
		)
		(fp_line
			(start 0.120396 0.3048)
			(end 0.120396 0.2794)
			(stroke
				(width 0.1)
				(type default)
			)
			(layer "F.Fab")
		)
		(fp_line
			(start 0.12065 -0.3048)
			(end 0.67945 -0.3048)
			(stroke
				(width 0.1)
				(type default)
			)
			(layer "F.Fab")
		)
		(fp_line
			(start 0.12065 -0.2794)
			(end 0.12065 -0.3048)
			(stroke
				(width 0.1)
				(type default)
			)
			(layer "F.Fab")
		)
		(fp_line
			(start 0.67945 -0.3048)
			(end 0.67945 0.3048)
			(stroke
				(width 0.1)
				(type default)
			)
			(layer "F.Fab")
		)
		(fp_line
			(start 0.67945 0.3048)
			(end 0.120396 0.3048)
			(stroke
				(width 0.1)
				(type default)
			)
			(layer "F.Fab")
		)
		(pad "1" smd circle
			(at -0.40005 0)
			(size 0 0)
			(layers "F.Cu" "F.Mask" "F.Paste")
			(net "PVNN_MAIN_CPU0")
		)
		(pad "2" smd circle
			(at 0.40005 0)
			(size 0 0)
			(layers "F.Cu" "F.Mask" "F.Paste")
			(net "GND")
		)
	)
	(footprint ""
		(layer "F.Cu")
		(at 125.264926 -122.096784 90)
		(property "Reference" "R937"
			(at 0 0 90)
			(layer "F.SilkS")
			(hide yes)
			(effects
				(font
					(size 1.27 1.27)
				)
			)
		)
		(property "Value" ""
			(at 0 0 90)
			(layer "F.Fab")
			(effects
				(font
					(size 1.27 1.27)
				)
			)
		)
		(duplicate_pad_numbers_are_jumpers no)
		(fp_line
			(start 0.7874 -0.4064)
			(end 0.7874 0.4064)
			(stroke
				(width 0.1524)
				(type default)
			)
			(layer "F.SilkS")
		)
		(fp_line
			(start -0.7874 -0.4064)
			(end 0.7874 -0.4064)
			(stroke
				(width 0.1524)
				(type default)
			)
			(layer "F.SilkS")
		)
		(fp_line
			(start 0.7874 0.4064)
			(end -0.7874 0.4064)
			(stroke
				(width 0.1524)
				(type default)
			)
			(layer "F.SilkS")
		)
		(fp_line
			(start -0.7874 0.4064)
			(end -0.7874 -0.4064)
			(stroke
				(width 0.1524)
				(type default)
			)
			(layer "F.SilkS")
		)
		(fp_line
			(start -0.12065 -0.305054)
			(end -0.12065 -0.2794)
			(stroke
				(width 0.1)
				(type default)
			)
			(layer "F.Fab")
		)
		(fp_line
			(start -0.67945 -0.305054)
			(end -0.12065 -0.305054)
			(stroke
				(width 0.1)
				(type default)
			)
			(layer "F.Fab")
		)
		(fp_line
			(start 0.67945 -0.3048)
			(end 0.67945 0.3048)
			(stroke
				(width 0.1)
				(type default)
			)
			(layer "F.Fab")
		)
		(fp_line
			(start 0.12065 -0.3048)
			(end 0.67945 -0.3048)
			(stroke
				(width 0.1)
				(type default)
			)
			(layer "F.Fab")
		)
		(fp_line
			(start 0.12065 -0.2794)
			(end 0.12065 -0.3048)
			(stroke
				(width 0.1)
				(type default)
			)
			(layer "F.Fab")
		)
		(fp_line
			(start -0.12065 -0.2794)
			(end 0.12065 -0.2794)
			(stroke
				(width 0.1)
				(type default)
			)
			(layer "F.Fab")
		)
		(fp_line
			(start 0.120396 0.2794)
			(end -0.12065 0.2794)
			(stroke
				(width 0.1)
				(type default)
			)
			(layer "F.Fab")
		)
		(fp_line
			(start -0.12065 0.2794)
			(end -0.12065 0.3048)
			(stroke
				(width 0.1)
				(type default)
			)
			(layer "F.Fab")
		)
		(fp_line
			(start 0.67945 0.3048)
			(end 0.120396 0.3048)
			(stroke
				(width 0.1)
				(type default)
			)
			(layer "F.Fab")
		)
		(fp_line
			(start 0.120396 0.3048)
			(end 0.120396 0.2794)
			(stroke
				(width 0.1)
				(type default)
			)
			(layer "F.Fab")
		)
		(fp_line
			(start -0.12065 0.3048)
			(end -0.67945 0.3048)
			(stroke
				(width 0.1)
				(type default)
			)
			(layer "F.Fab")
		)
		(fp_line
			(start -0.67945 0.3048)
			(end -0.67945 -0.305054)
			(stroke
				(width 0.1)
				(type default)
			)
			(layer "F.Fab")
		)
		(pad "1" smd circle
			(at -0.40005 0 90)
			(size 0 0)
			(layers "F.Cu" "F.Mask" "F.Paste")
			(net "RST_CPU1_DRAM_EF_N")
		)
		(pad "2" smd circle
			(at 0.40005 0 90)
			(size 0 0)
			(layers "F.Cu" "F.Mask" "F.Paste")
			(net "GND")
		)
	)
	(footprint ""
		(layer "F.Cu")
		(at 128.516634 -408.517344 -90)
		(property "Reference" "C1521"
			(at 0 0 270)
			(layer "F.SilkS")
			(hide yes)
			(effects
				(font
					(size 1.27 1.27)
				)
			)
		)
		(property "Value" ""
			(at 0 0 270)
			(layer "F.Fab")
			(effects
				(font
					(size 1.27 1.27)
				)
			)
		)
		(duplicate_pad_numbers_are_jumpers no)
		(fp_line
			(start -0.299974 0.150114)
			(end -0.299974 -0.150114)
			(stroke
				(width 0.1)
				(type default)
			)
			(layer "F.Fab")
		)
		(fp_line
			(start 0.299974 0.150114)
			(end -0.299974 0.150114)
			(stroke
				(width 0.1)
				(type default)
			)
			(layer "F.Fab")
		)
		(fp_line
			(start -0.299974 -0.150114)
			(end 0.299974 -0.150114)
			(stroke
				(width 0.1)
				(type default)
			)
			(layer "F.Fab")
		)
		(fp_line
			(start 0.299974 -0.150114)
			(end 0.299974 0.150114)
			(stroke
				(width 0.1)
				(type default)
			)
			(layer "F.Fab")
		)
		(pad "1" smd rect
			(at -0.2667 0 270)
			(size 0.3048 0.381)
			(layers "F.Cu" "F.Mask" "F.Paste")
			(net "P5E_CPU1_PE3_TX_C_DP<13>")
		)
		(pad "2" smd rect
			(at 0.2667 0 270)
			(size 0.3048 0.381)
			(layers "F.Cu" "F.Mask" "F.Paste")
			(net "P5E_CPU1_PE3_TX_DP<13>")
		)
	)
	(footprint ""
		(layer "F.Cu")
		(at 234.885738 -119.183658 -90)
		(property "Reference" "R3195"
			(at 0 0 270)
			(layer "F.SilkS")
			(hide yes)
			(effects
				(font
					(size 1.27 1.27)
				)
			)
		)
		(property "Value" ""
			(at 0 0 270)
			(layer "F.Fab")
			(effects
				(font
					(size 1.27 1.27)
				)
			)
		)
		(duplicate_pad_numbers_are_jumpers no)
		(fp_line
			(start 0.410718 0.4064)
			(end -0.363982 0.4064)
			(stroke
				(width 0.1524)
				(type default)
			)
			(layer "F.SilkS")
		)
		(fp_line
			(start -0.7874 0.105918)
			(end -0.7874 -0.4064)
			(stroke
				(width 0.1524)
				(type default)
			)
			(layer "F.SilkS")
		)
		(fp_line
			(start -0.7874 -0.4064)
			(end 0.7874 -0.4064)
			(stroke
				(width 0.1524)
				(type default)
			)
			(layer "F.SilkS")
		)
		(fp_line
			(start 0.7874 -0.4064)
			(end 0.7874 0.123698)
			(stroke
				(width 0.1524)
				(type default)
			)
			(layer "F.SilkS")
		)
		(fp_line
			(start -0.67945 0.3048)
			(end -0.67945 -0.305054)
			(stroke
				(width 0.1)
				(type default)
			)
			(layer "F.Fab")
		)
		(fp_line
			(start -0.12065 0.3048)
			(end -0.67945 0.3048)
			(stroke
				(width 0.1)
				(type default)
			)
			(layer "F.Fab")
		)
		(fp_line
			(start 0.120396 0.3048)
			(end 0.120396 0.2794)
			(stroke
				(width 0.1)
				(type default)
			)
			(layer "F.Fab")
		)
		(fp_line
			(start 0.67945 0.3048)
			(end 0.120396 0.3048)
			(stroke
				(width 0.1)
				(type default)
			)
			(layer "F.Fab")
		)
		(fp_line
			(start -0.12065 0.2794)
			(end -0.12065 0.3048)
			(stroke
				(width 0.1)
				(type default)
			)
			(layer "F.Fab")
		)
		(fp_line
			(start 0.120396 0.2794)
			(end -0.12065 0.2794)
			(stroke
				(width 0.1)
				(type default)
			)
			(layer "F.Fab")
		)
		(fp_line
			(start -0.12065 -0.2794)
			(end 0.12065 -0.2794)
			(stroke
				(width 0.1)
				(type default)
			)
			(layer "F.Fab")
		)
		(fp_line
			(start 0.12065 -0.2794)
			(end 0.12065 -0.3048)
			(stroke
				(width 0.1)
				(type default)
			)
			(layer "F.Fab")
		)
		(fp_line
			(start 0.12065 -0.3048)
			(end 0.67945 -0.3048)
			(stroke
				(width 0.1)
				(type default)
			)
			(layer "F.Fab")
		)
		(fp_line
			(start 0.67945 -0.3048)
			(end 0.67945 0.3048)
			(stroke
				(width 0.1)
				(type default)
			)
			(layer "F.Fab")
		)
		(fp_line
			(start -0.67945 -0.305054)
			(end -0.12065 -0.305054)
			(stroke
				(width 0.1)
				(type default)
			)
			(layer "F.Fab")
		)
		(fp_line
			(start -0.12065 -0.305054)
			(end -0.12065 -0.2794)
			(stroke
				(width 0.1)
				(type default)
			)
			(layer "F.Fab")
		)
		(pad "1" smd circle
			(at -0.40005 0 270)
			(size 0 0)
			(layers "F.Cu" "F.Mask" "F.Paste")
			(net "CLK_100M_OCP_V3_2_A_R_DN")
		)
		(pad "2" smd circle
			(at 0.40005 0 270)
			(size 0 0)
			(layers "F.Cu" "F.Mask" "F.Paste")
			(net "CLK_100M_OCP_V3_2_A_DN")
		)
	)
	(footprint ""
		(layer "F.Cu")
		(at 440.50966 -106.38536 90)
		(property "Reference" "R4750"
			(at 0 0 90)
			(layer "F.SilkS")
			(hide yes)
			(effects
				(font
					(size 1.27 1.27)
				)
			)
		)
		(property "Value" ""
			(at 0 0 90)
			(layer "F.Fab")
			(effects
				(font
					(size 1.27 1.27)
				)
			)
		)
		(duplicate_pad_numbers_are_jumpers no)
		(fp_line
			(start 0.7874 -0.4064)
			(end 0.7874 0.4064)
			(stroke
				(width 0.1524)
				(type default)
			)
			(layer "F.SilkS")
		)
		(fp_line
			(start -0.7874 -0.4064)
			(end 0.7874 -0.4064)
			(stroke
				(width 0.1524)
				(type default)
			)
			(layer "F.SilkS")
		)
		(fp_line
			(start 0.7874 0.4064)
			(end -0.7874 0.4064)
			(stroke
				(width 0.1524)
				(type default)
			)
			(layer "F.SilkS")
		)
		(fp_line
			(start -0.7874 0.4064)
			(end -0.7874 -0.4064)
			(stroke
				(width 0.1524)
				(type default)
			)
			(layer "F.SilkS")
		)
		(fp_line
			(start -0.12065 -0.305054)
			(end -0.12065 -0.2794)
			(stroke
				(width 0.1)
				(type default)
			)
			(layer "F.Fab")
		)
		(fp_line
			(start -0.67945 -0.305054)
			(end -0.12065 -0.305054)
			(stroke
				(width 0.1)
				(type default)
			)
			(layer "F.Fab")
		)
		(fp_line
			(start 0.67945 -0.3048)
			(end 0.67945 0.3048)
			(stroke
				(width 0.1)
				(type default)
			)
			(layer "F.Fab")
		)
		(fp_line
			(start 0.12065 -0.3048)
			(end 0.67945 -0.3048)
			(stroke
				(width 0.1)
				(type default)
			)
			(layer "F.Fab")
		)
		(fp_line
			(start 0.12065 -0.2794)
			(end 0.12065 -0.3048)
			(stroke
				(width 0.1)
				(type default)
			)
			(layer "F.Fab")
		)
		(fp_line
			(start -0.12065 -0.2794)
			(end 0.12065 -0.2794)
			(stroke
				(width 0.1)
				(type default)
			)
			(layer "F.Fab")
		)
		(fp_line
			(start 0.120396 0.2794)
			(end -0.12065 0.2794)
			(stroke
				(width 0.1)
				(type default)
			)
			(layer "F.Fab")
		)
		(fp_line
			(start -0.12065 0.2794)
			(end -0.12065 0.3048)
			(stroke
				(width 0.1)
				(type default)
			)
			(layer "F.Fab")
		)
		(fp_line
			(start 0.67945 0.3048)
			(end 0.120396 0.3048)
			(stroke
				(width 0.1)
				(type default)
			)
			(layer "F.Fab")
		)
		(fp_line
			(start 0.120396 0.3048)
			(end 0.120396 0.2794)
			(stroke
				(width 0.1)
				(type default)
			)
			(layer "F.Fab")
		)
		(fp_line
			(start -0.12065 0.3048)
			(end -0.67945 0.3048)
			(stroke
				(width 0.1)
				(type default)
			)
			(layer "F.Fab")
		)
		(fp_line
			(start -0.67945 0.3048)
			(end -0.67945 -0.305054)
			(stroke
				(width 0.1)
				(type default)
			)
			(layer "F.Fab")
		)
		(pad "1" smd circle
			(at -0.40005 0 90)
			(size 0 0)
			(layers "F.Cu" "F.Mask" "F.Paste")
			(net "OCP_SFF_AUX_PWR_EN_R2")
		)
		(pad "2" smd circle
			(at 0.40005 0 90)
			(size 0 0)
			(layers "F.Cu" "F.Mask" "F.Paste")
			(net "OCP_SFF_AUX_PWR_EN")
		)
	)
	(footprint ""
		(layer "F.Cu")
		(at 15.508478 -16.099536 90)
		(property "Reference" "C807"
			(at 0 0 90)
			(layer "F.SilkS")
			(hide yes)
			(effects
				(font
					(size 1.27 1.27)
				)
			)
		)
		(property "Value" ""
			(at 0 0 90)
			(layer "F.Fab")
			(effects
				(font
					(size 1.27 1.27)
				)
			)
		)
		(duplicate_pad_numbers_are_jumpers no)
		(fp_line
			(start 0.299974 -0.150114)
			(end 0.299974 0.150114)
			(stroke
				(width 0.1)
				(type default)
			)
			(layer "F.Fab")
		)
		(fp_line
			(start -0.299974 -0.150114)
			(end 0.299974 -0.150114)
			(stroke
				(width 0.1)
				(type default)
			)
			(layer "F.Fab")
		)
		(fp_line
			(start 0.299974 0.150114)
			(end -0.299974 0.150114)
			(stroke
				(width 0.1)
				(type default)
			)
			(layer "F.Fab")
		)
		(fp_line
			(start -0.299974 0.150114)
			(end -0.299974 -0.150114)
			(stroke
				(width 0.1)
				(type default)
			)
			(layer "F.Fab")
		)
		(pad "1" smd rect
			(at -0.2667 0 90)
			(size 0.3048 0.381)
			(layers "F.Cu" "F.Mask" "F.Paste")
			(net "P5E_CPU1_PE1_TX_C_DP<15>")
		)
		(pad "2" smd rect
			(at 0.2667 0 90)
			(size 0.3048 0.381)
			(layers "F.Cu" "F.Mask" "F.Paste")
			(net "P5E_CPU1_PE1_TX_DP<15>")
		)
	)
	(footprint ""
		(layer "F.Cu")
		(at 127.69088 -92.674948 90)
		(property "Reference" "R242"
			(at 0 0 90)
			(layer "F.SilkS")
			(hide yes)
			(effects
				(font
					(size 1.27 1.27)
				)
			)
		)
		(property "Value" ""
			(at 0 0 90)
			(layer "F.Fab")
			(effects
				(font
					(size 1.27 1.27)
				)
			)
		)
		(duplicate_pad_numbers_are_jumpers no)
		(fp_line
			(start 0.7874 -0.4064)
			(end 0.7874 0.4064)
			(stroke
				(width 0.1524)
				(type default)
			)
			(layer "F.SilkS")
		)
		(fp_line
			(start -0.7874 -0.4064)
			(end 0.7874 -0.4064)
			(stroke
				(width 0.1524)
				(type default)
			)
			(layer "F.SilkS")
		)
		(fp_line
			(start 0.7874 0.4064)
			(end -0.7874 0.4064)
			(stroke
				(width 0.1524)
				(type default)
			)
			(layer "F.SilkS")
		)
		(fp_line
			(start -0.7874 0.4064)
			(end -0.7874 -0.4064)
			(stroke
				(width 0.1524)
				(type default)
			)
			(layer "F.SilkS")
		)
		(fp_line
			(start -0.12065 -0.305054)
			(end -0.12065 -0.2794)
			(stroke
				(width 0.1)
				(type default)
			)
			(layer "F.Fab")
		)
		(fp_line
			(start -0.67945 -0.305054)
			(end -0.12065 -0.305054)
			(stroke
				(width 0.1)
				(type default)
			)
			(layer "F.Fab")
		)
		(fp_line
			(start 0.67945 -0.3048)
			(end 0.67945 0.3048)
			(stroke
				(width 0.1)
				(type default)
			)
			(layer "F.Fab")
		)
		(fp_line
			(start 0.12065 -0.3048)
			(end 0.67945 -0.3048)
			(stroke
				(width 0.1)
				(type default)
			)
			(layer "F.Fab")
		)
		(fp_line
			(start 0.12065 -0.2794)
			(end 0.12065 -0.3048)
			(stroke
				(width 0.1)
				(type default)
			)
			(layer "F.Fab")
		)
		(fp_line
			(start -0.12065 -0.2794)
			(end 0.12065 -0.2794)
			(stroke
				(width 0.1)
				(type default)
			)
			(layer "F.Fab")
		)
		(fp_line
			(start 0.120396 0.2794)
			(end -0.12065 0.2794)
			(stroke
				(width 0.1)
				(type default)
			)
			(layer "F.Fab")
		)
		(fp_line
			(start -0.12065 0.2794)
			(end -0.12065 0.3048)
			(stroke
				(width 0.1)
				(type default)
			)
			(layer "F.Fab")
		)
		(fp_line
			(start 0.67945 0.3048)
			(end 0.120396 0.3048)
			(stroke
				(width 0.1)
				(type default)
			)
			(layer "F.Fab")
		)
		(fp_line
			(start 0.120396 0.3048)
			(end 0.120396 0.2794)
			(stroke
				(width 0.1)
				(type default)
			)
			(layer "F.Fab")
		)
		(fp_line
			(start -0.12065 0.3048)
			(end -0.67945 0.3048)
			(stroke
				(width 0.1)
				(type default)
			)
			(layer "F.Fab")
		)
		(fp_line
			(start -0.67945 0.3048)
			(end -0.67945 -0.305054)
			(stroke
				(width 0.1)
				(type default)
			)
			(layer "F.Fab")
		)
		(pad "1" smd circle
			(at -0.40005 0 90)
			(size 0 0)
			(layers "F.Cu" "F.Mask" "F.Paste")
			(net "P3V3")
		)
		(pad "2" smd circle
			(at 0.40005 0 90)
			(size 0 0)
			(layers "F.Cu" "F.Mask" "F.Paste")
			(net "H_CPU1_THERMTRIP_VT_N")
		)
	)
	(footprint ""
		(layer "F.Cu")
		(at 148.98243 -77.229208)
		(property "Reference" "R3131"
			(at 0 0 0)
			(layer "F.SilkS")
			(hide yes)
			(effects
				(font
					(size 1.27 1.27)
				)
			)
		)
		(property "Value" ""
			(at 0 0 0)
			(layer "F.Fab")
			(effects
				(font
					(size 1.27 1.27)
				)
			)
		)
		(duplicate_pad_numbers_are_jumpers no)
		(fp_line
			(start -0.7874 -0.4064)
			(end 0.7874 -0.4064)
			(stroke
				(width 0.1524)
				(type default)
			)
			(layer "F.SilkS")
		)
		(fp_line
			(start -0.7874 0.4064)
			(end -0.7874 -0.4064)
			(stroke
				(width 0.1524)
				(type default)
			)
			(layer "F.SilkS")
		)
		(fp_line
			(start 0.7874 -0.4064)
			(end 0.7874 0.4064)
			(stroke
				(width 0.1524)
				(type default)
			)
			(layer "F.SilkS")
		)
		(fp_line
			(start 0.7874 0.4064)
			(end -0.7874 0.4064)
			(stroke
				(width 0.1524)
				(type default)
			)
			(layer "F.SilkS")
		)
		(fp_line
			(start -0.67945 -0.305054)
			(end -0.12065 -0.305054)
			(stroke
				(width 0.1)
				(type default)
			)
			(layer "F.Fab")
		)
		(fp_line
			(start -0.67945 0.3048)
			(end -0.67945 -0.305054)
			(stroke
				(width 0.1)
				(type default)
			)
			(layer "F.Fab")
		)
		(fp_line
			(start -0.12065 -0.305054)
			(end -0.12065 -0.2794)
			(stroke
				(width 0.1)
				(type default)
			)
			(layer "F.Fab")
		)
		(fp_line
			(start -0.12065 -0.2794)
			(end 0.12065 -0.2794)
			(stroke
				(width 0.1)
				(type default)
			)
			(layer "F.Fab")
		)
		(fp_line
			(start -0.12065 0.2794)
			(end -0.12065 0.3048)
			(stroke
				(width 0.1)
				(type default)
			)
			(layer "F.Fab")
		)
		(fp_line
			(start -0.12065 0.3048)
			(end -0.67945 0.3048)
			(stroke
				(width 0.1)
				(type default)
			)
			(layer "F.Fab")
		)
		(fp_line
			(start 0.120396 0.2794)
			(end -0.12065 0.2794)
			(stroke
				(width 0.1)
				(type default)
			)
			(layer "F.Fab")
		)
		(fp_line
			(start 0.120396 0.3048)
			(end 0.120396 0.2794)
			(stroke
				(width 0.1)
				(type default)
			)
			(layer "F.Fab")
		)
		(fp_line
			(start 0.12065 -0.3048)
			(end 0.67945 -0.3048)
			(stroke
				(width 0.1)
				(type default)
			)
			(layer "F.Fab")
		)
		(fp_line
			(start 0.12065 -0.2794)
			(end 0.12065 -0.3048)
			(stroke
				(width 0.1)
				(type default)
			)
			(layer "F.Fab")
		)
		(fp_line
			(start 0.67945 -0.3048)
			(end 0.67945 0.3048)
			(stroke
				(width 0.1)
				(type default)
			)
			(layer "F.Fab")
		)
		(fp_line
			(start 0.67945 0.3048)
			(end 0.120396 0.3048)
			(stroke
				(width 0.1)
				(type default)
			)
			(layer "F.Fab")
		)
		(pad "1" smd circle
			(at -0.40005 0)
			(size 0 0)
			(layers "F.Cu" "F.Mask" "F.Paste")
			(net "P3V3_AUX")
		)
		(pad "2" smd circle
			(at 0.40005 0)
			(size 0 0)
			(layers "F.Cu" "F.Mask" "F.Paste")
			(net "PCA9543_S3M_INT3_N")
		)
	)
	(footprint ""
		(layer "F.Cu")
		(at 437.242966 -123.664726 180)
		(property "Reference" "R2399"
			(at 0 0 180)
			(layer "F.SilkS")
			(hide yes)
			(effects
				(font
					(size 1.27 1.27)
				)
			)
		)
		(property "Value" ""
			(at 0 0 180)
			(layer "F.Fab")
			(effects
				(font
					(size 1.27 1.27)
				)
			)
		)
		(duplicate_pad_numbers_are_jumpers no)
		(fp_line
			(start 0.7874 0.4064)
			(end -0.7874 0.4064)
			(stroke
				(width 0.1524)
				(type default)
			)
			(layer "F.SilkS")
		)
		(fp_line
			(start 0.7874 -0.4064)
			(end 0.7874 0.4064)
			(stroke
				(width 0.1524)
				(type default)
			)
			(layer "F.SilkS")
		)
		(fp_line
			(start -0.7874 0.4064)
			(end -0.7874 -0.4064)
			(stroke
				(width 0.1524)
				(type default)
			)
			(layer "F.SilkS")
		)
		(fp_line
			(start -0.7874 -0.4064)
			(end 0.7874 -0.4064)
			(stroke
				(width 0.1524)
				(type default)
			)
			(layer "F.SilkS")
		)
		(fp_line
			(start 0.67945 0.3048)
			(end 0.120396 0.3048)
			(stroke
				(width 0.1)
				(type default)
			)
			(layer "F.Fab")
		)
		(fp_line
			(start 0.67945 -0.3048)
			(end 0.67945 0.3048)
			(stroke
				(width 0.1)
				(type default)
			)
			(layer "F.Fab")
		)
		(fp_line
			(start 0.12065 -0.2794)
			(end 0.12065 -0.3048)
			(stroke
				(width 0.1)
				(type default)
			)
			(layer "F.Fab")
		)
		(fp_line
			(start 0.12065 -0.3048)
			(end 0.67945 -0.3048)
			(stroke
				(width 0.1)
				(type default)
			)
			(layer "F.Fab")
		)
		(fp_line
			(start 0.120396 0.3048)
			(end 0.120396 0.2794)
			(stroke
				(width 0.1)
				(type default)
			)
			(layer "F.Fab")
		)
		(fp_line
			(start 0.120396 0.2794)
			(end -0.12065 0.2794)
			(stroke
				(width 0.1)
				(type default)
			)
			(layer "F.Fab")
		)
		(fp_line
			(start -0.12065 0.3048)
			(end -0.67945 0.3048)
			(stroke
				(width 0.1)
				(type default)
			)
			(layer "F.Fab")
		)
		(fp_line
			(start -0.12065 0.2794)
			(end -0.12065 0.3048)
			(stroke
				(width 0.1)
				(type default)
			)
			(layer "F.Fab")
		)
		(fp_line
			(start -0.12065 -0.2794)
			(end 0.12065 -0.2794)
			(stroke
				(width 0.1)
				(type default)
			)
			(layer "F.Fab")
		)
		(fp_line
			(start -0.12065 -0.305054)
			(end -0.12065 -0.2794)
			(stroke
				(width 0.1)
				(type default)
			)
			(layer "F.Fab")
		)
		(fp_line
			(start -0.67945 0.3048)
			(end -0.67945 -0.305054)
			(stroke
				(width 0.1)
				(type default)
			)
			(layer "F.Fab")
		)
		(fp_line
			(start -0.67945 -0.305054)
			(end -0.12065 -0.305054)
			(stroke
				(width 0.1)
				(type default)
			)
			(layer "F.Fab")
		)
		(pad "1" smd circle
			(at -0.40005 0 180)
			(size 0 0)
			(layers "F.Cu" "F.Mask" "F.Paste")
			(net "SVID_CLK1_CPU0_R")
		)
		(pad "2" smd circle
			(at 0.40005 0 180)
			(size 0 0)
			(layers "F.Cu" "F.Mask" "F.Paste")
			(net "SVID_CLK_PVCCD_HV_CPU0_R")
		)
	)
	(footprint ""
		(layer "F.Cu")
		(at 354.251514 -255.053846 90)
		(property "Reference" "C990"
			(at 0 0 90)
			(layer "F.SilkS")
			(hide yes)
			(effects
				(font
					(size 1.27 1.27)
				)
			)
		)
		(property "Value" ""
			(at 0 0 90)
			(layer "F.Fab")
			(effects
				(font
					(size 1.27 1.27)
				)
			)
		)
		(duplicate_pad_numbers_are_jumpers no)
		(fp_line
			(start 0.7874 -0.4064)
			(end 0.7874 0.4064)
			(stroke
				(width 0.1524)
				(type default)
			)
			(layer "F.SilkS")
		)
		(fp_line
			(start -0.7874 -0.4064)
			(end 0.7874 -0.4064)
			(stroke
				(width 0.1524)
				(type default)
			)
			(layer "F.SilkS")
		)
		(fp_line
			(start 0.7874 0.4064)
			(end -0.7874 0.4064)
			(stroke
				(width 0.1524)
				(type default)
			)
			(layer "F.SilkS")
		)
		(fp_line
			(start -0.7874 0.4064)
			(end -0.7874 -0.4064)
			(stroke
				(width 0.1524)
				(type default)
			)
			(layer "F.SilkS")
		)
		(fp_line
			(start -0.12065 -0.305054)
			(end -0.12065 -0.2794)
			(stroke
				(width 0.1)
				(type default)
			)
			(layer "F.Fab")
		)
		(fp_line
			(start -0.67945 -0.305054)
			(end -0.12065 -0.305054)
			(stroke
				(width 0.1)
				(type default)
			)
			(layer "F.Fab")
		)
		(fp_line
			(start 0.67945 -0.3048)
			(end 0.67945 0.3048)
			(stroke
				(width 0.1)
				(type default)
			)
			(layer "F.Fab")
		)
		(fp_line
			(start 0.12065 -0.3048)
			(end 0.67945 -0.3048)
			(stroke
				(width 0.1)
				(type default)
			)
			(layer "F.Fab")
		)
		(fp_line
			(start 0.12065 -0.2794)
			(end 0.12065 -0.3048)
			(stroke
				(width 0.1)
				(type default)
			)
			(layer "F.Fab")
		)
		(fp_line
			(start -0.12065 -0.2794)
			(end 0.12065 -0.2794)
			(stroke
				(width 0.1)
				(type default)
			)
			(layer "F.Fab")
		)
		(fp_line
			(start 0.120396 0.2794)
			(end -0.12065 0.2794)
			(stroke
				(width 0.1)
				(type default)
			)
			(layer "F.Fab")
		)
		(fp_line
			(start -0.12065 0.2794)
			(end -0.12065 0.3048)
			(stroke
				(width 0.1)
				(type default)
			)
			(layer "F.Fab")
		)
		(fp_line
			(start 0.67945 0.3048)
			(end 0.120396 0.3048)
			(stroke
				(width 0.1)
				(type default)
			)
			(layer "F.Fab")
		)
		(fp_line
			(start 0.120396 0.3048)
			(end 0.120396 0.2794)
			(stroke
				(width 0.1)
				(type default)
			)
			(layer "F.Fab")
		)
		(fp_line
			(start -0.12065 0.3048)
			(end -0.67945 0.3048)
			(stroke
				(width 0.1)
				(type default)
			)
			(layer "F.Fab")
		)
		(fp_line
			(start -0.67945 0.3048)
			(end -0.67945 -0.305054)
			(stroke
				(width 0.1)
				(type default)
			)
			(layer "F.Fab")
		)
		(pad "1" smd circle
			(at -0.40005 0 90)
			(size 0 0)
			(layers "F.Cu" "F.Mask" "F.Paste")
			(net "PVCCIN_CPU0")
		)
		(pad "2" smd circle
			(at 0.40005 0 90)
			(size 0 0)
			(layers "F.Cu" "F.Mask" "F.Paste")
			(net "GND")
		)
	)
	(footprint ""
		(layer "F.Cu")
		(at 116.561616 -238.162592 90)
		(property "Reference" "C434"
			(at 0 0 90)
			(layer "F.SilkS")
			(hide yes)
			(effects
				(font
					(size 1.27 1.27)
				)
			)
		)
		(property "Value" ""
			(at 0 0 90)
			(layer "F.Fab")
			(effects
				(font
					(size 1.27 1.27)
				)
			)
		)
		(duplicate_pad_numbers_are_jumpers no)
		(fp_line
			(start 0.7874 -0.4064)
			(end 0.7874 0.4064)
			(stroke
				(width 0.1524)
				(type default)
			)
			(layer "F.SilkS")
		)
		(fp_line
			(start -0.7874 -0.4064)
			(end 0.7874 -0.4064)
			(stroke
				(width 0.1524)
				(type default)
			)
			(layer "F.SilkS")
		)
		(fp_line
			(start 0.7874 0.4064)
			(end -0.7874 0.4064)
			(stroke
				(width 0.1524)
				(type default)
			)
			(layer "F.SilkS")
		)
		(fp_line
			(start -0.7874 0.4064)
			(end -0.7874 -0.4064)
			(stroke
				(width 0.1524)
				(type default)
			)
			(layer "F.SilkS")
		)
		(fp_line
			(start -0.12065 -0.305054)
			(end -0.12065 -0.2794)
			(stroke
				(width 0.1)
				(type default)
			)
			(layer "F.Fab")
		)
		(fp_line
			(start -0.67945 -0.305054)
			(end -0.12065 -0.305054)
			(stroke
				(width 0.1)
				(type default)
			)
			(layer "F.Fab")
		)
		(fp_line
			(start 0.67945 -0.3048)
			(end 0.67945 0.3048)
			(stroke
				(width 0.1)
				(type default)
			)
			(layer "F.Fab")
		)
		(fp_line
			(start 0.12065 -0.3048)
			(end 0.67945 -0.3048)
			(stroke
				(width 0.1)
				(type default)
			)
			(layer "F.Fab")
		)
		(fp_line
			(start 0.12065 -0.2794)
			(end 0.12065 -0.3048)
			(stroke
				(width 0.1)
				(type default)
			)
			(layer "F.Fab")
		)
		(fp_line
			(start -0.12065 -0.2794)
			(end 0.12065 -0.2794)
			(stroke
				(width 0.1)
				(type default)
			)
			(layer "F.Fab")
		)
		(fp_line
			(start 0.120396 0.2794)
			(end -0.12065 0.2794)
			(stroke
				(width 0.1)
				(type default)
			)
			(layer "F.Fab")
		)
		(fp_line
			(start -0.12065 0.2794)
			(end -0.12065 0.3048)
			(stroke
				(width 0.1)
				(type default)
			)
			(layer "F.Fab")
		)
		(fp_line
			(start 0.67945 0.3048)
			(end 0.120396 0.3048)
			(stroke
				(width 0.1)
				(type default)
			)
			(layer "F.Fab")
		)
		(fp_line
			(start 0.120396 0.3048)
			(end 0.120396 0.2794)
			(stroke
				(width 0.1)
				(type default)
			)
			(layer "F.Fab")
		)
		(fp_line
			(start -0.12065 0.3048)
			(end -0.67945 0.3048)
			(stroke
				(width 0.1)
				(type default)
			)
			(layer "F.Fab")
		)
		(fp_line
			(start -0.67945 0.3048)
			(end -0.67945 -0.305054)
			(stroke
				(width 0.1)
				(type default)
			)
			(layer "F.Fab")
		)
		(pad "1" smd circle
			(at -0.40005 0 90)
			(size 0 0)
			(layers "F.Cu" "F.Mask" "F.Paste")
			(net "PVCCINFAON_CPU1")
		)
		(pad "2" smd circle
			(at 0.40005 0 90)
			(size 0 0)
			(layers "F.Cu" "F.Mask" "F.Paste")
			(net "GND")
		)
	)
	(footprint ""
		(layer "F.Cu")
		(at 194.35064 -69.423788 -90)
		(property "Reference" "PU293"
			(at 3.817112 3.85572 0)
			(unlocked yes)
			(layer "F.SilkS")
			(effects
				(font
					(size 0.7874 0.5842)
					(thickness 0.1524)
				)
			)
		)
		(property "Value" ""
			(at 0 0 270)
			(layer "F.Fab")
			(effects
				(font
					(size 1.27 1.27)
				)
			)
		)
		(duplicate_pad_numbers_are_jumpers no)
		(fp_line
			(start -1.239774 1.495298)
			(end -1.239774 -1.495298)
			(stroke
				(width 0.1524)
				(type default)
			)
			(layer "F.SilkS")
		)
		(fp_line
			(start 1.239774 1.495298)
			(end -1.239774 1.495298)
			(stroke
				(width 0.1524)
				(type default)
			)
			(layer "F.SilkS")
		)
		(fp_line
			(start -1.239774 -1.495298)
			(end 1.239774 -1.495298)
			(stroke
				(width 0.1524)
				(type default)
			)
			(layer "F.SilkS")
		)
		(fp_line
			(start 1.239774 -1.495298)
			(end 1.239774 1.495298)
			(stroke
				(width 0.1524)
				(type default)
			)
			(layer "F.SilkS")
		)
		(fp_poly
			(pts
				(xy -1.754124 -1.697228) (xy -1.394968 -0.619506) (xy -2.472436 -0.978662)
			)
			(stroke
				(width 0)
				(type default)
			)
			(fill yes)
			(layer "F.SilkS")
		)
		(fp_line
			(start -0.8001 1.050036)
			(end -0.8001 -1.050036)
			(stroke
				(width 0.1)
				(type default)
			)
			(layer "F.Fab")
		)
		(fp_line
			(start 0.8001 1.050036)
			(end -0.8001 1.050036)
			(stroke
				(width 0.1)
				(type default)
			)
			(layer "F.Fab")
		)
		(fp_line
			(start -0.8001 -1.050036)
			(end 0.8001 -1.050036)
			(stroke
				(width 0.1)
				(type default)
			)
			(layer "F.Fab")
		)
		(fp_line
			(start 0.8001 -1.050036)
			(end 0.8001 1.050036)
			(stroke
				(width 0.1)
				(type default)
			)
			(layer "F.Fab")
		)
		(fp_poly
			(pts
				(xy -2.458974 -0.508) (xy -2.458974 0.508) (xy -1.442974 0)
			)
			(stroke
				(width 0)
				(type default)
			)
			(fill yes)
			(layer "F.Fab")
		)
		(pad "1_2" smd circle
			(at -0.374904 0)
			(size 0 0)
			(layers "F.Cu" "F.Mask" "F.Paste")
			(net "P3V3_AUX")
		)
		(pad "3" smd rect
			(at -0.499872 0.999998 270)
			(size 0.254 0.7112)
			(layers "F.Cu" "F.Mask" "F.Paste")
			(net "GND")
		)
		(pad "4" smd rect
			(at 0 0.999998 270)
			(size 0.254 0.7112)
			(layers "F.Cu" "F.Mask" "F.Paste")
			(net "P3V3_E1S_ILIMIT_0")
		)
		(pad "5" smd rect
			(at 0.499872 0.999998 270)
			(size 0.254 0.7112)
			(layers "F.Cu" "F.Mask" "F.Paste")
			(net "P3V3_E1S_MODE_0")
		)
		(pad "6_7" smd circle
			(at 0.374904 0 180)
			(size 0 0)
			(layers "F.Cu" "F.Mask" "F.Paste")
			(net "P3V3_E1S_0_R")
		)
		(pad "8" smd rect
			(at 0.499872 -0.999998 270)
			(size 0.254 0.7112)
			(layers "F.Cu" "F.Mask" "F.Paste")
			(net "P3V3_E1S_GATE_0_PU293")
		)
		(pad "9" smd rect
			(at 0 -0.999998 270)
			(size 0.254 0.7112)
			(layers "F.Cu" "F.Mask" "F.Paste")
			(net "P3V3_E1S_EN_0_R2")
		)
		(pad "10" smd rect
			(at -0.499872 -0.999998 270)
			(size 0.254 0.7112)
			(layers "F.Cu" "F.Mask" "F.Paste")
			(net "P3V3_E1S_DVDT_0")
		)
	)
	(footprint ""
		(layer "F.Cu")
		(at 345.27871 -343.902284 90)
		(property "Reference" "PC318"
			(at 0 0 90)
			(layer "F.SilkS")
			(hide yes)
			(effects
				(font
					(size 1.27 1.27)
				)
			)
		)
		(property "Value" ""
			(at 0 0 90)
			(layer "F.Fab")
			(effects
				(font
					(size 1.27 1.27)
				)
			)
		)
		(duplicate_pad_numbers_are_jumpers no)
		(fp_line
			(start -3.400044 1.249934)
			(end 3.400044 1.249934)
			(stroke
				(width 0.1524)
				(type default)
			)
			(layer "F.SilkS")
		)
		(fp_circle
			(center 0 1.249934)
			(end 0 4.649978)
			(stroke
				(width 0.1524)
				(type default)
			)
			(fill no)
			(layer "F.SilkS")
		)
		(fp_poly
			(pts
				(arc
					(start -3.400044 1.249934)
					(mid 0 4.649978)
					(end 3.400044 1.249934)
				)
			)
			(stroke
				(width 0)
				(type default)
			)
			(fill yes)
			(layer "F.SilkS")
		)
		(fp_circle
			(center 0 1.249934)
			(end 0 4.649978)
			(stroke
				(width 0.1)
				(type default)
			)
			(fill no)
			(layer "F.Fab")
		)
		(pad "1" thru_hole rect
			(at 0 0 90)
			(size 1.524 1.524)
			(drill 1.016)
			(layers "*.Cu" "*.Mask")
			(remove_unused_layers no)
			(net "SW_P12V_PVCCIN_CPU0_FLT")
			(clearance 0)
			(padstack
				(mode front_inner_back)
				(layer "Inner"
					(shape circle)
					(size 1.524 1.524)
					(clearance 0)
				)
				(layer "B.Cu"
					(shape rect)
					(size 1.524 1.524)
					(clearance 0)
				)
			)
		)
		(pad "2" thru_hole circle
			(at 0 2.500122 90)
			(size 1.524 1.524)
			(drill 1.016)
			(layers "*.Cu" "*.Mask")
			(remove_unused_layers no)
			(net "GND")
			(clearance 0)
		)
	)
	(footprint ""
		(layer "F.Cu")
		(at 197.41388 -106.225848)
		(property "Reference" "R990"
			(at 0 0 0)
			(layer "F.SilkS")
			(hide yes)
			(effects
				(font
					(size 1.27 1.27)
				)
			)
		)
		(property "Value" ""
			(at 0 0 0)
			(layer "F.Fab")
			(effects
				(font
					(size 1.27 1.27)
				)
			)
		)
		(duplicate_pad_numbers_are_jumpers no)
		(fp_line
			(start -0.7874 -0.4064)
			(end 0.7874 -0.4064)
			(stroke
				(width 0.1524)
				(type default)
			)
			(layer "F.SilkS")
		)
		(fp_line
			(start -0.7874 0.4064)
			(end -0.7874 -0.4064)
			(stroke
				(width 0.1524)
				(type default)
			)
			(layer "F.SilkS")
		)
		(fp_line
			(start 0.7874 -0.4064)
			(end 0.7874 0.4064)
			(stroke
				(width 0.1524)
				(type default)
			)
			(layer "F.SilkS")
		)
		(fp_line
			(start 0.7874 0.4064)
			(end -0.7874 0.4064)
			(stroke
				(width 0.1524)
				(type default)
			)
			(layer "F.SilkS")
		)
		(fp_line
			(start -0.67945 -0.305054)
			(end -0.12065 -0.305054)
			(stroke
				(width 0.1)
				(type default)
			)
			(layer "F.Fab")
		)
		(fp_line
			(start -0.67945 0.3048)
			(end -0.67945 -0.305054)
			(stroke
				(width 0.1)
				(type default)
			)
			(layer "F.Fab")
		)
		(fp_line
			(start -0.12065 -0.305054)
			(end -0.12065 -0.2794)
			(stroke
				(width 0.1)
				(type default)
			)
			(layer "F.Fab")
		)
		(fp_line
			(start -0.12065 -0.2794)
			(end 0.12065 -0.2794)
			(stroke
				(width 0.1)
				(type default)
			)
			(layer "F.Fab")
		)
		(fp_line
			(start -0.12065 0.2794)
			(end -0.12065 0.3048)
			(stroke
				(width 0.1)
				(type default)
			)
			(layer "F.Fab")
		)
		(fp_line
			(start -0.12065 0.3048)
			(end -0.67945 0.3048)
			(stroke
				(width 0.1)
				(type default)
			)
			(layer "F.Fab")
		)
		(fp_line
			(start 0.120396 0.2794)
			(end -0.12065 0.2794)
			(stroke
				(width 0.1)
				(type default)
			)
			(layer "F.Fab")
		)
		(fp_line
			(start 0.120396 0.3048)
			(end 0.120396 0.2794)
			(stroke
				(width 0.1)
				(type default)
			)
			(layer "F.Fab")
		)
		(fp_line
			(start 0.12065 -0.3048)
			(end 0.67945 -0.3048)
			(stroke
				(width 0.1)
				(type default)
			)
			(layer "F.Fab")
		)
		(fp_line
			(start 0.12065 -0.2794)
			(end 0.12065 -0.3048)
			(stroke
				(width 0.1)
				(type default)
			)
			(layer "F.Fab")
		)
		(fp_line
			(start 0.67945 -0.3048)
			(end 0.67945 0.3048)
			(stroke
				(width 0.1)
				(type default)
			)
			(layer "F.Fab")
		)
		(fp_line
			(start 0.67945 0.3048)
			(end 0.120396 0.3048)
			(stroke
				(width 0.1)
				(type default)
			)
			(layer "F.Fab")
		)
		(pad "1" smd circle
			(at -0.40005 0)
			(size 0 0)
			(layers "F.Cu" "F.Mask" "F.Paste")
			(net "FM_PLD_CLK_25M_R_EN")
		)
		(pad "2" smd circle
			(at 0.40005 0)
			(size 0 0)
			(layers "F.Cu" "F.Mask" "F.Paste")
			(net "GND")
		)
	)
	(footprint ""
		(layer "F.Cu")
		(at 376.296936 -92.910152 -90)
		(property "Reference" "R483"
			(at 0 0 270)
			(layer "F.SilkS")
			(hide yes)
			(effects
				(font
					(size 1.27 1.27)
				)
			)
		)
		(property "Value" ""
			(at 0 0 270)
			(layer "F.Fab")
			(effects
				(font
					(size 1.27 1.27)
				)
			)
		)
		(duplicate_pad_numbers_are_jumpers no)
		(fp_line
			(start -0.7874 0.4064)
			(end -0.7874 -0.4064)
			(stroke
				(width 0.1524)
				(type default)
			)
			(layer "F.SilkS")
		)
		(fp_line
			(start 0.7874 0.4064)
			(end -0.7874 0.4064)
			(stroke
				(width 0.1524)
				(type default)
			)
			(layer "F.SilkS")
		)
		(fp_line
			(start -0.7874 -0.4064)
			(end 0.7874 -0.4064)
			(stroke
				(width 0.1524)
				(type default)
			)
			(layer "F.SilkS")
		)
		(fp_line
			(start 0.7874 -0.4064)
			(end 0.7874 0.4064)
			(stroke
				(width 0.1524)
				(type default)
			)
			(layer "F.SilkS")
		)
		(fp_line
			(start -0.67945 0.3048)
			(end -0.67945 -0.305054)
			(stroke
				(width 0.1)
				(type default)
			)
			(layer "F.Fab")
		)
		(fp_line
			(start -0.12065 0.3048)
			(end -0.67945 0.3048)
			(stroke
				(width 0.1)
				(type default)
			)
			(layer "F.Fab")
		)
		(fp_line
			(start 0.120396 0.3048)
			(end 0.120396 0.2794)
			(stroke
				(width 0.1)
				(type default)
			)
			(layer "F.Fab")
		)
		(fp_line
			(start 0.67945 0.3048)
			(end 0.120396 0.3048)
			(stroke
				(width 0.1)
				(type default)
			)
			(layer "F.Fab")
		)
		(fp_line
			(start -0.12065 0.2794)
			(end -0.12065 0.3048)
			(stroke
				(width 0.1)
				(type default)
			)
			(layer "F.Fab")
		)
		(fp_line
			(start 0.120396 0.2794)
			(end -0.12065 0.2794)
			(stroke
				(width 0.1)
				(type default)
			)
			(layer "F.Fab")
		)
		(fp_line
			(start -0.12065 -0.2794)
			(end 0.12065 -0.2794)
			(stroke
				(width 0.1)
				(type default)
			)
			(layer "F.Fab")
		)
		(fp_line
			(start 0.12065 -0.2794)
			(end 0.12065 -0.3048)
			(stroke
				(width 0.1)
				(type default)
			)
			(layer "F.Fab")
		)
		(fp_line
			(start 0.12065 -0.3048)
			(end 0.67945 -0.3048)
			(stroke
				(width 0.1)
				(type default)
			)
			(layer "F.Fab")
		)
		(fp_line
			(start 0.67945 -0.3048)
			(end 0.67945 0.3048)
			(stroke
				(width 0.1)
				(type default)
			)
			(layer "F.Fab")
		)
		(fp_line
			(start -0.67945 -0.305054)
			(end -0.12065 -0.305054)
			(stroke
				(width 0.1)
				(type default)
			)
			(layer "F.Fab")
		)
		(fp_line
			(start -0.12065 -0.305054)
			(end -0.12065 -0.2794)
			(stroke
				(width 0.1)
				(type default)
			)
			(layer "F.Fab")
		)
		(pad "1" smd circle
			(at -0.40005 0 270)
			(size 0 0)
			(layers "F.Cu" "F.Mask" "F.Paste")
			(net "JTAG_BMC_DBP_TDO_R")
		)
		(pad "2" smd circle
			(at 0.40005 0 270)
			(size 0 0)
			(layers "F.Cu" "F.Mask" "F.Paste")
			(net "JTAG_BMC_DBP_TDO")
		)
	)
	(footprint ""
		(layer "F.Cu")
		(at 121.708926 -119.810784 -90)
		(property "Reference" "R860"
			(at 0 0 270)
			(layer "F.SilkS")
			(hide yes)
			(effects
				(font
					(size 1.27 1.27)
				)
			)
		)
		(property "Value" ""
			(at 0 0 270)
			(layer "F.Fab")
			(effects
				(font
					(size 1.27 1.27)
				)
			)
		)
		(duplicate_pad_numbers_are_jumpers no)
		(fp_line
			(start -0.7874 0.4064)
			(end -0.7874 -0.4064)
			(stroke
				(width 0.1524)
				(type default)
			)
			(layer "F.SilkS")
		)
		(fp_line
			(start 0.7874 0.4064)
			(end -0.7874 0.4064)
			(stroke
				(width 0.1524)
				(type default)
			)
			(layer "F.SilkS")
		)
		(fp_line
			(start -0.7874 -0.4064)
			(end 0.7874 -0.4064)
			(stroke
				(width 0.1524)
				(type default)
			)
			(layer "F.SilkS")
		)
		(fp_line
			(start 0.7874 -0.4064)
			(end 0.7874 0.4064)
			(stroke
				(width 0.1524)
				(type default)
			)
			(layer "F.SilkS")
		)
		(fp_line
			(start -0.67945 0.3048)
			(end -0.67945 -0.305054)
			(stroke
				(width 0.1)
				(type default)
			)
			(layer "F.Fab")
		)
		(fp_line
			(start -0.12065 0.3048)
			(end -0.67945 0.3048)
			(stroke
				(width 0.1)
				(type default)
			)
			(layer "F.Fab")
		)
		(fp_line
			(start 0.120396 0.3048)
			(end 0.120396 0.2794)
			(stroke
				(width 0.1)
				(type default)
			)
			(layer "F.Fab")
		)
		(fp_line
			(start 0.67945 0.3048)
			(end 0.120396 0.3048)
			(stroke
				(width 0.1)
				(type default)
			)
			(layer "F.Fab")
		)
		(fp_line
			(start -0.12065 0.2794)
			(end -0.12065 0.3048)
			(stroke
				(width 0.1)
				(type default)
			)
			(layer "F.Fab")
		)
		(fp_line
			(start 0.120396 0.2794)
			(end -0.12065 0.2794)
			(stroke
				(width 0.1)
				(type default)
			)
			(layer "F.Fab")
		)
		(fp_line
			(start -0.12065 -0.2794)
			(end 0.12065 -0.2794)
			(stroke
				(width 0.1)
				(type default)
			)
			(layer "F.Fab")
		)
		(fp_line
			(start 0.12065 -0.2794)
			(end 0.12065 -0.3048)
			(stroke
				(width 0.1)
				(type default)
			)
			(layer "F.Fab")
		)
		(fp_line
			(start 0.12065 -0.3048)
			(end 0.67945 -0.3048)
			(stroke
				(width 0.1)
				(type default)
			)
			(layer "F.Fab")
		)
		(fp_line
			(start 0.67945 -0.3048)
			(end 0.67945 0.3048)
			(stroke
				(width 0.1)
				(type default)
			)
			(layer "F.Fab")
		)
		(fp_line
			(start -0.67945 -0.305054)
			(end -0.12065 -0.305054)
			(stroke
				(width 0.1)
				(type default)
			)
			(layer "F.Fab")
		)
		(fp_line
			(start -0.12065 -0.305054)
			(end -0.12065 -0.2794)
			(stroke
				(width 0.1)
				(type default)
			)
			(layer "F.Fab")
		)
		(pad "1" smd circle
			(at -0.40005 0 270)
			(size 0 0)
			(layers "F.Cu" "F.Mask" "F.Paste")
			(net "RST_CPU1_DRAM_CD_N")
		)
		(pad "2" smd circle
			(at 0.40005 0 270)
			(size 0 0)
			(layers "F.Cu" "F.Mask" "F.Paste")
			(net "RST_CPU1_DRAM_CD_PLD_N")
		)
	)
	(footprint ""
		(layer "F.Cu")
		(at 293.80688 -46.954948 90)
		(property "Reference" "R4064"
			(at 0 0 90)
			(layer "F.SilkS")
			(hide yes)
			(effects
				(font
					(size 1.27 1.27)
				)
			)
		)
		(property "Value" ""
			(at 0 0 90)
			(layer "F.Fab")
			(effects
				(font
					(size 1.27 1.27)
				)
			)
		)
		(duplicate_pad_numbers_are_jumpers no)
		(fp_line
			(start 0.7874 -0.4064)
			(end 0.7874 0.4064)
			(stroke
				(width 0.1524)
				(type default)
			)
			(layer "F.SilkS")
		)
		(fp_line
			(start -0.7874 -0.4064)
			(end 0.7874 -0.4064)
			(stroke
				(width 0.1524)
				(type default)
			)
			(layer "F.SilkS")
		)
		(fp_line
			(start 0.7874 0.4064)
			(end -0.7874 0.4064)
			(stroke
				(width 0.1524)
				(type default)
			)
			(layer "F.SilkS")
		)
		(fp_line
			(start -0.7874 0.4064)
			(end -0.7874 -0.4064)
			(stroke
				(width 0.1524)
				(type default)
			)
			(layer "F.SilkS")
		)
		(fp_line
			(start -0.12065 -0.305054)
			(end -0.12065 -0.2794)
			(stroke
				(width 0.1)
				(type default)
			)
			(layer "F.Fab")
		)
		(fp_line
			(start -0.67945 -0.305054)
			(end -0.12065 -0.305054)
			(stroke
				(width 0.1)
				(type default)
			)
			(layer "F.Fab")
		)
		(fp_line
			(start 0.67945 -0.3048)
			(end 0.67945 0.3048)
			(stroke
				(width 0.1)
				(type default)
			)
			(layer "F.Fab")
		)
		(fp_line
			(start 0.12065 -0.3048)
			(end 0.67945 -0.3048)
			(stroke
				(width 0.1)
				(type default)
			)
			(layer "F.Fab")
		)
		(fp_line
			(start 0.12065 -0.2794)
			(end 0.12065 -0.3048)
			(stroke
				(width 0.1)
				(type default)
			)
			(layer "F.Fab")
		)
		(fp_line
			(start -0.12065 -0.2794)
			(end 0.12065 -0.2794)
			(stroke
				(width 0.1)
				(type default)
			)
			(layer "F.Fab")
		)
		(fp_line
			(start 0.120396 0.2794)
			(end -0.12065 0.2794)
			(stroke
				(width 0.1)
				(type default)
			)
			(layer "F.Fab")
		)
		(fp_line
			(start -0.12065 0.2794)
			(end -0.12065 0.3048)
			(stroke
				(width 0.1)
				(type default)
			)
			(layer "F.Fab")
		)
		(fp_line
			(start 0.67945 0.3048)
			(end 0.120396 0.3048)
			(stroke
				(width 0.1)
				(type default)
			)
			(layer "F.Fab")
		)
		(fp_line
			(start 0.120396 0.3048)
			(end 0.120396 0.2794)
			(stroke
				(width 0.1)
				(type default)
			)
			(layer "F.Fab")
		)
		(fp_line
			(start -0.12065 0.3048)
			(end -0.67945 0.3048)
			(stroke
				(width 0.1)
				(type default)
			)
			(layer "F.Fab")
		)
		(fp_line
			(start -0.67945 0.3048)
			(end -0.67945 -0.305054)
			(stroke
				(width 0.1)
				(type default)
			)
			(layer "F.Fab")
		)
		(pad "1" smd circle
			(at -0.40005 0 90)
			(size 0 0)
			(layers "F.Cu" "F.Mask" "F.Paste")
			(net "E1S_0_EN")
		)
		(pad "2" smd circle
			(at 0.40005 0 90)
			(size 0 0)
			(layers "F.Cu" "F.Mask" "F.Paste")
			(net "P12V_E1S_EN_0_R")
		)
	)
	(footprint ""
		(layer "F.Cu")
		(at 305.92014 -435.6481 90)
		(property "Reference" "Q133"
			(at -7.36346 -4.155948 90)
			(unlocked yes)
			(layer "F.SilkS")
			(effects
				(font
					(size 0.7874 0.5842)
					(thickness 0.1524)
				)
				(justify left)
			)
		)
		(property "Value" ""
			(at 0 0 90)
			(layer "F.Fab")
			(effects
				(font
					(size 1.27 1.27)
				)
			)
		)
		(duplicate_pad_numbers_are_jumpers no)
		(fp_line
			(start 1.332738 -1.100074)
			(end 1.332738 1.100074)
			(stroke
				(width 0.1524)
				(type default)
			)
			(layer "F.SilkS")
		)
		(fp_line
			(start 0.4826 -1.100074)
			(end 1.332738 -1.100074)
			(stroke
				(width 0.1524)
				(type default)
			)
			(layer "F.SilkS")
		)
		(fp_line
			(start -0.4826 -1.100074)
			(end 0 -0.541274)
			(stroke
				(width 0.1524)
				(type default)
			)
			(layer "F.SilkS")
		)
		(fp_line
			(start -1.332738 -1.100074)
			(end -0.4826 -1.100074)
			(stroke
				(width 0.1524)
				(type default)
			)
			(layer "F.SilkS")
		)
		(fp_line
			(start 0 -0.541274)
			(end 0.4826 -1.100074)
			(stroke
				(width 0.1524)
				(type default)
			)
			(layer "F.SilkS")
		)
		(fp_line
			(start 1.332738 1.100074)
			(end -1.332738 1.100074)
			(stroke
				(width 0.1524)
				(type default)
			)
			(layer "F.SilkS")
		)
		(fp_line
			(start -1.332738 1.100074)
			(end -1.332738 -1.100074)
			(stroke
				(width 0.1524)
				(type default)
			)
			(layer "F.SilkS")
		)
		(fp_poly
			(pts
				(xy -2.29362 -1.321054) (xy -1.591564 -0.970026) (xy -2.29362 -0.618998)
			)
			(stroke
				(width 0)
				(type default)
			)
			(fill yes)
			(layer "F.SilkS")
		)
		(fp_line
			(start 0.674878 -1.100074)
			(end 0.674878 1.100074)
			(stroke
				(width 0.1)
				(type default)
			)
			(layer "F.Fab")
		)
		(fp_line
			(start -0.674878 -1.100074)
			(end 0.674878 -1.100074)
			(stroke
				(width 0.1)
				(type default)
			)
			(layer "F.Fab")
		)
		(fp_line
			(start 0.674878 1.100074)
			(end -0.674878 1.100074)
			(stroke
				(width 0.1)
				(type default)
			)
			(layer "F.Fab")
		)
		(fp_line
			(start -0.674878 1.100074)
			(end -0.674878 -1.100074)
			(stroke
				(width 0.1)
				(type default)
			)
			(layer "F.Fab")
		)
		(fp_poly
			(pts
				(xy -2.2352 -0.298958) (xy -2.2352 -1.001014) (xy -1.533144 -0.649986)
			)
			(stroke
				(width 0)
				(type default)
			)
			(fill yes)
			(layer "F.Fab")
		)
		(pad "1" smd rect
			(at -0.94996 -0.649986 180)
			(size 0.4318 0.508)
			(layers "F.Cu" "F.Mask" "F.Paste")
			(net "GND")
		)
		(pad "2" smd rect
			(at -0.94996 0 180)
			(size 0.4318 0.508)
			(layers "F.Cu" "F.Mask" "F.Paste")
			(net "PRSNT_CABLE_GPU_A2_N")
		)
		(pad "3" smd rect
			(at -0.94996 0.649986 180)
			(size 0.4318 0.508)
			(layers "F.Cu" "F.Mask" "F.Paste")
			(net "PRSNT_CABLE_GPU_A2_ISO_N")
		)
		(pad "4" smd rect
			(at 0.94996 0.649986 180)
			(size 0.4318 0.508)
			(layers "F.Cu" "F.Mask" "F.Paste")
			(net "GND")
		)
		(pad "5" smd rect
			(at 0.94996 0 180)
			(size 0.4318 0.508)
			(layers "F.Cu" "F.Mask" "F.Paste")
			(net "PRSNT_CABLE_GPU_A2")
		)
		(pad "6" smd rect
			(at 0.94996 -0.649986 180)
			(size 0.4318 0.508)
			(layers "F.Cu" "F.Mask" "F.Paste")
			(net "PRSNT_CABLE_GPU_A2")
		)
	)
	(footprint ""
		(layer "F.Cu")
		(at 292.928802 -57.509918 -90)
		(property "Reference" "Q126"
			(at 0.4572 7.436612 0)
			(unlocked yes)
			(layer "F.SilkS")
			(effects
				(font
					(size 0.7874 0.5842)
					(thickness 0.1524)
				)
				(justify left)
			)
		)
		(property "Value" ""
			(at 0 0 270)
			(layer "F.Fab")
			(effects
				(font
					(size 1.27 1.27)
				)
			)
		)
		(duplicate_pad_numbers_are_jumpers no)
		(fp_line
			(start -1.332738 1.100074)
			(end -1.332738 -1.100074)
			(stroke
				(width 0.1524)
				(type default)
			)
			(layer "F.SilkS")
		)
		(fp_line
			(start 1.332738 1.100074)
			(end -1.332738 1.100074)
			(stroke
				(width 0.1524)
				(type default)
			)
			(layer "F.SilkS")
		)
		(fp_line
			(start 0 -0.541274)
			(end 0.4826 -1.100074)
			(stroke
				(width 0.1524)
				(type default)
			)
			(layer "F.SilkS")
		)
		(fp_line
			(start -1.332738 -1.100074)
			(end -0.4826 -1.100074)
			(stroke
				(width 0.1524)
				(type default)
			)
			(layer "F.SilkS")
		)
		(fp_line
			(start -0.4826 -1.100074)
			(end 0 -0.541274)
			(stroke
				(width 0.1524)
				(type default)
			)
			(layer "F.SilkS")
		)
		(fp_line
			(start 0.4826 -1.100074)
			(end 1.332738 -1.100074)
			(stroke
				(width 0.1524)
				(type default)
			)
			(layer "F.SilkS")
		)
		(fp_line
			(start 1.332738 -1.100074)
			(end 1.332738 1.100074)
			(stroke
				(width 0.1524)
				(type default)
			)
			(layer "F.SilkS")
		)
		(fp_poly
			(pts
				(xy -2.2352 -1.001014) (xy -1.533144 -0.649986) (xy -2.2352 -0.298958)
			)
			(stroke
				(width 0)
				(type default)
			)
			(fill yes)
			(layer "F.SilkS")
		)
		(fp_line
			(start -0.674878 1.100074)
			(end -0.674878 -1.100074)
			(stroke
				(width 0.1)
				(type default)
			)
			(layer "F.Fab")
		)
		(fp_line
			(start 0.674878 1.100074)
			(end -0.674878 1.100074)
			(stroke
				(width 0.1)
				(type default)
			)
			(layer "F.Fab")
		)
		(fp_line
			(start -0.674878 -1.100074)
			(end 0.674878 -1.100074)
			(stroke
				(width 0.1)
				(type default)
			)
			(layer "F.Fab")
		)
		(fp_line
			(start 0.674878 -1.100074)
			(end 0.674878 1.100074)
			(stroke
				(width 0.1)
				(type default)
			)
			(layer "F.Fab")
		)
		(fp_poly
			(pts
				(xy -2.2352 -0.298958) (xy -2.2352 -1.001014) (xy -1.533144 -0.649986)
			)
			(stroke
				(width 0)
				(type default)
			)
			(fill yes)
			(layer "F.Fab")
		)
		(pad "1" smd rect
			(at -0.94996 -0.649986)
			(size 0.4318 0.508)
			(layers "F.Cu" "F.Mask" "F.Paste")
			(net "GND")
		)
		(pad "2" smd rect
			(at -0.94996 0)
			(size 0.4318 0.508)
			(layers "F.Cu" "F.Mask" "F.Paste")
			(net "P3V3_E1S_EN_1_R")
		)
		(pad "3" smd rect
			(at -0.94996 0.649986)
			(size 0.4318 0.508)
			(layers "F.Cu" "F.Mask" "F.Paste")
			(net "P3V3_E1S_UV_0_R")
		)
		(pad "4" smd rect
			(at 0.94996 0.649986)
			(size 0.4318 0.508)
			(layers "F.Cu" "F.Mask" "F.Paste")
			(net "GND")
		)
		(pad "5" smd rect
			(at 0.94996 0)
			(size 0.4318 0.508)
			(layers "F.Cu" "F.Mask" "F.Paste")
			(net "P3V3_E1S_0_EN_G")
		)
		(pad "6" smd rect
			(at 0.94996 -0.649986)
			(size 0.4318 0.508)
			(layers "F.Cu" "F.Mask" "F.Paste")
			(net "P3V3_E1S_0_EN_G")
		)
	)
	(footprint ""
		(layer "F.Cu")
		(at 74.593958 -61.883798)
		(property "Reference" "PD109"
			(at 5.9944 -0.462788 0)
			(unlocked yes)
			(layer "F.SilkS")
			(effects
				(font
					(size 0.7874 0.5842)
					(thickness 0.1524)
				)
				(justify left)
			)
		)
		(property "Value" ""
			(at 0 0 0)
			(layer "F.Fab")
			(effects
				(font
					(size 1.27 1.27)
				)
			)
		)
		(duplicate_pad_numbers_are_jumpers no)
		(fp_line
			(start -3.400044 -1.459992)
			(end 4.107942 -1.459992)
			(stroke
				(width 0.1524)
				(type default)
			)
			(layer "F.SilkS")
		)
		(fp_line
			(start -3.400044 1.459992)
			(end -3.400044 -1.459992)
			(stroke
				(width 0.1524)
				(type default)
			)
			(layer "F.SilkS")
		)
		(fp_line
			(start 4.107942 -1.459992)
			(end 4.107942 1.459992)
			(stroke
				(width 0.1524)
				(type default)
			)
			(layer "F.SilkS")
		)
		(fp_line
			(start 4.107942 1.459992)
			(end -3.400044 1.459992)
			(stroke
				(width 0.1524)
				(type default)
			)
			(layer "F.SilkS")
		)
		(fp_rect
			(start 3.308096 1.459992)
			(end 4.107942 -1.459992)
			(stroke
				(width 0)
				(type default)
			)
			(fill yes)
			(layer "F.SilkS")
		)
		(fp_line
			(start -2.29997 -1.459992)
			(end 2.29997 -1.459992)
			(stroke
				(width 0.1)
				(type default)
			)
			(layer "F.Fab")
		)
		(fp_line
			(start -2.29997 1.459992)
			(end -2.29997 -1.459992)
			(stroke
				(width 0.1)
				(type default)
			)
			(layer "F.Fab")
		)
		(fp_line
			(start 2.29997 -1.459992)
			(end 2.29997 1.459992)
			(stroke
				(width 0.1)
				(type default)
			)
			(layer "F.Fab")
		)
		(fp_line
			(start 2.29997 1.459992)
			(end -2.29997 1.459992)
			(stroke
				(width 0.1)
				(type default)
			)
			(layer "F.Fab")
		)
		(fp_text user "+"
			(at -4.876038 -1.1557 0)
			(unlocked yes)
			(layer "F.SilkS")
			(effects
				(font
					(size 1.905 1.4224)
					(thickness 0.1524)
				)
				(justify left)
			)
		)
		(fp_text user "-"
			(at 5.4102 0.29845 180)
			(unlocked yes)
			(layer "F.SilkS")
			(effects
				(font
					(size 1.905 1.4224)
					(thickness 0.1524)
				)
				(justify left)
			)
		)
		(fp_text user "+"
			(at -4.7752 -0.12065 0)
			(unlocked yes)
			(layer "F.Fab")
			(effects
				(font
					(size 1.905 1.4224)
					(thickness 0.1524)
				)
				(justify left)
			)
		)
		(fp_text user "-"
			(at 5.4102 0.29845 180)
			(unlocked yes)
			(layer "F.Fab")
			(effects
				(font
					(size 1.905 1.4224)
					(thickness 0.1524)
				)
				(justify left)
			)
		)
		(pad "A" smd rect
			(at -1.999996 0 90)
			(size 1.7018 2.5146)
			(layers "F.Cu" "F.Mask" "F.Paste")
			(net "GND")
		)
		(pad "C" smd rect
			(at 1.999996 0 90)
			(size 1.7018 2.5146)
			(layers "F.Cu" "F.Mask" "F.Paste")
			(net "P3V3_OCP_V3_2_R")
		)
	)
	(footprint ""
		(layer "F.Cu")
		(at 42.324274 -358.38003 90)
		(property "Reference" "PR1803"
			(at 0 0 90)
			(layer "F.SilkS")
			(hide yes)
			(effects
				(font
					(size 1.27 1.27)
				)
			)
		)
		(property "Value" ""
			(at 0 0 90)
			(layer "F.Fab")
			(effects
				(font
					(size 1.27 1.27)
				)
			)
		)
		(duplicate_pad_numbers_are_jumpers no)
		(fp_line
			(start 0.7874 -0.4064)
			(end 0.7874 0.4064)
			(stroke
				(width 0.1524)
				(type default)
			)
			(layer "F.SilkS")
		)
		(fp_line
			(start -0.7874 -0.4064)
			(end 0.7874 -0.4064)
			(stroke
				(width 0.1524)
				(type default)
			)
			(layer "F.SilkS")
		)
		(fp_line
			(start 0.7874 0.4064)
			(end -0.7874 0.4064)
			(stroke
				(width 0.1524)
				(type default)
			)
			(layer "F.SilkS")
		)
		(fp_line
			(start -0.7874 0.4064)
			(end -0.7874 -0.4064)
			(stroke
				(width 0.1524)
				(type default)
			)
			(layer "F.SilkS")
		)
		(fp_line
			(start -0.12065 -0.305054)
			(end -0.12065 -0.2794)
			(stroke
				(width 0.1)
				(type default)
			)
			(layer "F.Fab")
		)
		(fp_line
			(start -0.67945 -0.305054)
			(end -0.12065 -0.305054)
			(stroke
				(width 0.1)
				(type default)
			)
			(layer "F.Fab")
		)
		(fp_line
			(start 0.67945 -0.3048)
			(end 0.67945 0.3048)
			(stroke
				(width 0.1)
				(type default)
			)
			(layer "F.Fab")
		)
		(fp_line
			(start 0.12065 -0.3048)
			(end 0.67945 -0.3048)
			(stroke
				(width 0.1)
				(type default)
			)
			(layer "F.Fab")
		)
		(fp_line
			(start 0.12065 -0.2794)
			(end 0.12065 -0.3048)
			(stroke
				(width 0.1)
				(type default)
			)
			(layer "F.Fab")
		)
		(fp_line
			(start -0.12065 -0.2794)
			(end 0.12065 -0.2794)
			(stroke
				(width 0.1)
				(type default)
			)
			(layer "F.Fab")
		)
		(fp_line
			(start 0.120396 0.2794)
			(end -0.12065 0.2794)
			(stroke
				(width 0.1)
				(type default)
			)
			(layer "F.Fab")
		)
		(fp_line
			(start -0.12065 0.2794)
			(end -0.12065 0.3048)
			(stroke
				(width 0.1)
				(type default)
			)
			(layer "F.Fab")
		)
		(fp_line
			(start 0.67945 0.3048)
			(end 0.120396 0.3048)
			(stroke
				(width 0.1)
				(type default)
			)
			(layer "F.Fab")
		)
		(fp_line
			(start 0.120396 0.3048)
			(end 0.120396 0.2794)
			(stroke
				(width 0.1)
				(type default)
			)
			(layer "F.Fab")
		)
		(fp_line
			(start -0.12065 0.3048)
			(end -0.67945 0.3048)
			(stroke
				(width 0.1)
				(type default)
			)
			(layer "F.Fab")
		)
		(fp_line
			(start -0.67945 0.3048)
			(end -0.67945 -0.305054)
			(stroke
				(width 0.1)
				(type default)
			)
			(layer "F.Fab")
		)
		(pad "1" smd circle
			(at -0.40005 0 90)
			(size 0 0)
			(layers "F.Cu" "F.Mask" "F.Paste")
			(net "SW_PVCCFA_EHV_FIVRA_CPU1_BOOT4")
		)
		(pad "2" smd circle
			(at 0.40005 0 90)
			(size 0 0)
			(layers "F.Cu" "F.Mask" "F.Paste")
			(net "SW_PVCCFA_EHV_FIVRA_CPU1_BOOT4_")
		)
	)
	(footprint ""
		(layer "F.Cu")
		(at 15.436596 -394.231876 180)
		(property "Reference" "R3272"
			(at 0 0 180)
			(layer "F.SilkS")
			(hide yes)
			(effects
				(font
					(size 1.27 1.27)
				)
			)
		)
		(property "Value" ""
			(at 0 0 180)
			(layer "F.Fab")
			(effects
				(font
					(size 1.27 1.27)
				)
			)
		)
		(duplicate_pad_numbers_are_jumpers no)
		(fp_line
			(start 0.7874 0.4064)
			(end -0.7874 0.4064)
			(stroke
				(width 0.1524)
				(type default)
			)
			(layer "F.SilkS")
		)
		(fp_line
			(start 0.7874 -0.4064)
			(end 0.7874 0.4064)
			(stroke
				(width 0.1524)
				(type default)
			)
			(layer "F.SilkS")
		)
		(fp_line
			(start -0.7874 0.4064)
			(end -0.7874 -0.4064)
			(stroke
				(width 0.1524)
				(type default)
			)
			(layer "F.SilkS")
		)
		(fp_line
			(start -0.7874 -0.4064)
			(end 0.7874 -0.4064)
			(stroke
				(width 0.1524)
				(type default)
			)
			(layer "F.SilkS")
		)
		(fp_line
			(start 0.67945 0.3048)
			(end 0.120396 0.3048)
			(stroke
				(width 0.1)
				(type default)
			)
			(layer "F.Fab")
		)
		(fp_line
			(start 0.67945 -0.3048)
			(end 0.67945 0.3048)
			(stroke
				(width 0.1)
				(type default)
			)
			(layer "F.Fab")
		)
		(fp_line
			(start 0.12065 -0.2794)
			(end 0.12065 -0.3048)
			(stroke
				(width 0.1)
				(type default)
			)
			(layer "F.Fab")
		)
		(fp_line
			(start 0.12065 -0.3048)
			(end 0.67945 -0.3048)
			(stroke
				(width 0.1)
				(type default)
			)
			(layer "F.Fab")
		)
		(fp_line
			(start 0.120396 0.3048)
			(end 0.120396 0.2794)
			(stroke
				(width 0.1)
				(type default)
			)
			(layer "F.Fab")
		)
		(fp_line
			(start 0.120396 0.2794)
			(end -0.12065 0.2794)
			(stroke
				(width 0.1)
				(type default)
			)
			(layer "F.Fab")
		)
		(fp_line
			(start -0.12065 0.3048)
			(end -0.67945 0.3048)
			(stroke
				(width 0.1)
				(type default)
			)
			(layer "F.Fab")
		)
		(fp_line
			(start -0.12065 0.2794)
			(end -0.12065 0.3048)
			(stroke
				(width 0.1)
				(type default)
			)
			(layer "F.Fab")
		)
		(fp_line
			(start -0.12065 -0.2794)
			(end 0.12065 -0.2794)
			(stroke
				(width 0.1)
				(type default)
			)
			(layer "F.Fab")
		)
		(fp_line
			(start -0.12065 -0.305054)
			(end -0.12065 -0.2794)
			(stroke
				(width 0.1)
				(type default)
			)
			(layer "F.Fab")
		)
		(fp_line
			(start -0.67945 0.3048)
			(end -0.67945 -0.305054)
			(stroke
				(width 0.1)
				(type default)
			)
			(layer "F.Fab")
		)
		(fp_line
			(start -0.67945 -0.305054)
			(end -0.12065 -0.305054)
			(stroke
				(width 0.1)
				(type default)
			)
			(layer "F.Fab")
		)
		(pad "1" smd circle
			(at -0.40005 0 180)
			(size 0 0)
			(layers "F.Cu" "F.Mask" "F.Paste")
			(net "FM_P2E_EQA1")
		)
		(pad "2" smd circle
			(at 0.40005 0 180)
			(size 0 0)
			(layers "F.Cu" "F.Mask" "F.Paste")
			(net "GND")
		)
	)
	(footprint ""
		(layer "F.Cu")
		(at 106.322114 -258.72694 90)
		(property "Reference" "C226"
			(at 0 0 90)
			(layer "F.SilkS")
			(hide yes)
			(effects
				(font
					(size 1.27 1.27)
				)
			)
		)
		(property "Value" ""
			(at 0 0 90)
			(layer "F.Fab")
			(effects
				(font
					(size 1.27 1.27)
				)
			)
		)
		(duplicate_pad_numbers_are_jumpers no)
		(fp_line
			(start 0.7874 -0.4064)
			(end 0.7874 0.4064)
			(stroke
				(width 0.1524)
				(type default)
			)
			(layer "F.SilkS")
		)
		(fp_line
			(start -0.7874 -0.4064)
			(end 0.7874 -0.4064)
			(stroke
				(width 0.1524)
				(type default)
			)
			(layer "F.SilkS")
		)
		(fp_line
			(start 0.7874 0.4064)
			(end -0.7874 0.4064)
			(stroke
				(width 0.1524)
				(type default)
			)
			(layer "F.SilkS")
		)
		(fp_line
			(start -0.7874 0.4064)
			(end -0.7874 -0.4064)
			(stroke
				(width 0.1524)
				(type default)
			)
			(layer "F.SilkS")
		)
		(fp_line
			(start -0.12065 -0.305054)
			(end -0.12065 -0.2794)
			(stroke
				(width 0.1)
				(type default)
			)
			(layer "F.Fab")
		)
		(fp_line
			(start -0.67945 -0.305054)
			(end -0.12065 -0.305054)
			(stroke
				(width 0.1)
				(type default)
			)
			(layer "F.Fab")
		)
		(fp_line
			(start 0.67945 -0.3048)
			(end 0.67945 0.3048)
			(stroke
				(width 0.1)
				(type default)
			)
			(layer "F.Fab")
		)
		(fp_line
			(start 0.12065 -0.3048)
			(end 0.67945 -0.3048)
			(stroke
				(width 0.1)
				(type default)
			)
			(layer "F.Fab")
		)
		(fp_line
			(start 0.12065 -0.2794)
			(end 0.12065 -0.3048)
			(stroke
				(width 0.1)
				(type default)
			)
			(layer "F.Fab")
		)
		(fp_line
			(start -0.12065 -0.2794)
			(end 0.12065 -0.2794)
			(stroke
				(width 0.1)
				(type default)
			)
			(layer "F.Fab")
		)
		(fp_line
			(start 0.120396 0.2794)
			(end -0.12065 0.2794)
			(stroke
				(width 0.1)
				(type default)
			)
			(layer "F.Fab")
		)
		(fp_line
			(start -0.12065 0.2794)
			(end -0.12065 0.3048)
			(stroke
				(width 0.1)
				(type default)
			)
			(layer "F.Fab")
		)
		(fp_line
			(start 0.67945 0.3048)
			(end 0.120396 0.3048)
			(stroke
				(width 0.1)
				(type default)
			)
			(layer "F.Fab")
		)
		(fp_line
			(start 0.120396 0.3048)
			(end 0.120396 0.2794)
			(stroke
				(width 0.1)
				(type default)
			)
			(layer "F.Fab")
		)
		(fp_line
			(start -0.12065 0.3048)
			(end -0.67945 0.3048)
			(stroke
				(width 0.1)
				(type default)
			)
			(layer "F.Fab")
		)
		(fp_line
			(start -0.67945 0.3048)
			(end -0.67945 -0.305054)
			(stroke
				(width 0.1)
				(type default)
			)
			(layer "F.Fab")
		)
		(pad "1" smd circle
			(at -0.40005 0 90)
			(size 0 0)
			(layers "F.Cu" "F.Mask" "F.Paste")
			(net "PVCCIN_CPU1")
		)
		(pad "2" smd circle
			(at 0.40005 0 90)
			(size 0 0)
			(layers "F.Cu" "F.Mask" "F.Paste")
			(net "GND")
		)
	)
	(footprint ""
		(layer "F.Cu")
		(at 40.627554 -112.603026)
		(property "Reference" "R3679"
			(at 0 0 0)
			(layer "F.SilkS")
			(hide yes)
			(effects
				(font
					(size 1.27 1.27)
				)
			)
		)
		(property "Value" ""
			(at 0 0 0)
			(layer "F.Fab")
			(effects
				(font
					(size 1.27 1.27)
				)
			)
		)
		(duplicate_pad_numbers_are_jumpers no)
		(fp_line
			(start -0.7874 -0.4064)
			(end 0.7874 -0.4064)
			(stroke
				(width 0.1524)
				(type default)
			)
			(layer "F.SilkS")
		)
		(fp_line
			(start -0.7874 0.4064)
			(end -0.7874 -0.4064)
			(stroke
				(width 0.1524)
				(type default)
			)
			(layer "F.SilkS")
		)
		(fp_line
			(start 0.7874 -0.4064)
			(end 0.7874 0.4064)
			(stroke
				(width 0.1524)
				(type default)
			)
			(layer "F.SilkS")
		)
		(fp_line
			(start 0.7874 0.4064)
			(end -0.7874 0.4064)
			(stroke
				(width 0.1524)
				(type default)
			)
			(layer "F.SilkS")
		)
		(fp_line
			(start -0.67945 -0.305054)
			(end -0.12065 -0.305054)
			(stroke
				(width 0.1)
				(type default)
			)
			(layer "F.Fab")
		)
		(fp_line
			(start -0.67945 0.3048)
			(end -0.67945 -0.305054)
			(stroke
				(width 0.1)
				(type default)
			)
			(layer "F.Fab")
		)
		(fp_line
			(start -0.12065 -0.305054)
			(end -0.12065 -0.2794)
			(stroke
				(width 0.1)
				(type default)
			)
			(layer "F.Fab")
		)
		(fp_line
			(start -0.12065 -0.2794)
			(end 0.12065 -0.2794)
			(stroke
				(width 0.1)
				(type default)
			)
			(layer "F.Fab")
		)
		(fp_line
			(start -0.12065 0.2794)
			(end -0.12065 0.3048)
			(stroke
				(width 0.1)
				(type default)
			)
			(layer "F.Fab")
		)
		(fp_line
			(start -0.12065 0.3048)
			(end -0.67945 0.3048)
			(stroke
				(width 0.1)
				(type default)
			)
			(layer "F.Fab")
		)
		(fp_line
			(start 0.120396 0.2794)
			(end -0.12065 0.2794)
			(stroke
				(width 0.1)
				(type default)
			)
			(layer "F.Fab")
		)
		(fp_line
			(start 0.120396 0.3048)
			(end 0.120396 0.2794)
			(stroke
				(width 0.1)
				(type default)
			)
			(layer "F.Fab")
		)
		(fp_line
			(start 0.12065 -0.3048)
			(end 0.67945 -0.3048)
			(stroke
				(width 0.1)
				(type default)
			)
			(layer "F.Fab")
		)
		(fp_line
			(start 0.12065 -0.2794)
			(end 0.12065 -0.3048)
			(stroke
				(width 0.1)
				(type default)
			)
			(layer "F.Fab")
		)
		(fp_line
			(start 0.67945 -0.3048)
			(end 0.67945 0.3048)
			(stroke
				(width 0.1)
				(type default)
			)
			(layer "F.Fab")
		)
		(fp_line
			(start 0.67945 0.3048)
			(end 0.120396 0.3048)
			(stroke
				(width 0.1)
				(type default)
			)
			(layer "F.Fab")
		)
		(pad "1" smd rect
			(at -0.40005 0 180)
			(size 0.4572 0.508)
			(layers "F.Cu" "F.Mask" "F.Paste")
			(net "P12V_AUX_ADC")
		)
		(pad "2" smd rect
			(at 0.40005 0 180)
			(size 0.4572 0.508)
			(layers "F.Cu" "F.Mask" "F.Paste")
			(net "P12V_AUX_ADC_MAM")
		)
	)
	(footprint ""
		(layer "F.Cu")
		(at 266.031472 -398.78 90)
		(property "Reference" "PPQ7"
			(at -8.177784 -1.879092 0)
			(unlocked yes)
			(layer "F.SilkS")
			(effects
				(font
					(size 0.7874 0.5842)
					(thickness 0.1524)
				)
				(justify left)
			)
		)
		(property "Value" ""
			(at 0 0 90)
			(layer "F.Fab")
			(effects
				(font
					(size 1.27 1.27)
				)
			)
		)
		(duplicate_pad_numbers_are_jumpers no)
		(fp_line
			(start 2.350008 -2.649982)
			(end 2.350008 -2.4892)
			(stroke
				(width 0.1524)
				(type default)
			)
			(layer "F.SilkS")
		)
		(fp_line
			(start -2.350008 -2.649982)
			(end 2.350008 -2.649982)
			(stroke
				(width 0.1524)
				(type default)
			)
			(layer "F.SilkS")
		)
		(fp_line
			(start -2.350008 -2.4384)
			(end -2.350008 -2.649982)
			(stroke
				(width 0.1524)
				(type default)
			)
			(layer "F.SilkS")
		)
		(fp_line
			(start 2.350008 2.4892)
			(end 2.350008 2.649982)
			(stroke
				(width 0.1524)
				(type default)
			)
			(layer "F.SilkS")
		)
		(fp_line
			(start 2.350008 2.649982)
			(end -2.350008 2.649982)
			(stroke
				(width 0.1524)
				(type default)
			)
			(layer "F.SilkS")
		)
		(fp_line
			(start -2.350008 2.649982)
			(end -2.350008 2.413)
			(stroke
				(width 0.1524)
				(type default)
			)
			(layer "F.SilkS")
		)
		(fp_poly
			(pts
				(xy -3.717544 -1.905) (xy -4.758944 -2.3241) (xy -4.758944 -1.524)
			)
			(stroke
				(width 0)
				(type default)
			)
			(fill yes)
			(layer "F.SilkS")
		)
		(fp_line
			(start 2.350008 -2.649982)
			(end 2.350008 2.649982)
			(stroke
				(width 0.1)
				(type default)
			)
			(layer "F.Fab")
		)
		(fp_line
			(start -2.350008 -2.649982)
			(end 2.350008 -2.649982)
			(stroke
				(width 0.1)
				(type default)
			)
			(layer "F.Fab")
		)
		(fp_line
			(start 2.350008 2.649982)
			(end -2.350008 2.649982)
			(stroke
				(width 0.1)
				(type default)
			)
			(layer "F.Fab")
		)
		(fp_line
			(start -2.350008 2.649982)
			(end -2.350008 -2.649982)
			(stroke
				(width 0.1)
				(type default)
			)
			(layer "F.Fab")
		)
		(fp_poly
			(pts
				(xy -3.717544 -1.905) (xy -4.758944 -2.3241) (xy -4.758944 -1.524)
			)
			(stroke
				(width 0)
				(type default)
			)
			(fill yes)
			(layer "F.Fab")
		)
		(pad "1" smd rect
			(at -2.999994 -1.905)
			(size 0.7112 1.1684)
			(layers "F.Cu" "F.Mask" "F.Paste")
			(net "P12V_AUX")
		)
		(pad "2" smd rect
			(at -2.999994 -0.635)
			(size 0.7112 1.1684)
			(layers "F.Cu" "F.Mask" "F.Paste")
			(net "P12V_AUX")
		)
		(pad "3" smd rect
			(at -2.999994 0.635)
			(size 0.7112 1.1684)
			(layers "F.Cu" "F.Mask" "F.Paste")
			(net "P12V_AUX")
		)
		(pad "4" smd rect
			(at -2.999994 1.905)
			(size 0.7112 1.1684)
			(layers "F.Cu" "F.Mask" "F.Paste")
			(net "P12V_HSC_GATE_G3")
		)
		(pad "5" smd circle
			(at 0.925068 0)
			(size 0 0)
			(layers "F.Cu" "F.Mask" "F.Paste")
			(net "P12V_MAIN_R")
		)
		(zone
			(layer "F.Cu")
			(hatch none 0.5)
			(connect_pads
				(clearance 0)
			)
			(min_thickness 0.25)
			(keepout
				(tracks not_allowed)
				(vias allowed)
				(pads allowed)
				(copperpour not_allowed)
				(footprints allowed)
			)
			(placement
				(enabled no)
				(sheetname "")
			)
			(fill
				(thermal_gap 0.5)
				(thermal_bridge_width 0.5)
				(island_removal_mode 0)
			)
			(polygon
				(pts
					(xy 263.872472 -397.3322) (xy 268.190472 -397.3322) (xy 268.673072 -397.3322) (xy 268.673072 -396.4305)
					(xy 263.389872 -396.4305) (xy 263.389872 -397.3322)
				)
			)
		)
	)
	(footprint ""
		(layer "F.Cu")
		(at 75.523598 -402.371052 -90)
		(property "Reference" "C728"
			(at 0 0 270)
			(layer "F.SilkS")
			(hide yes)
			(effects
				(font
					(size 1.27 1.27)
				)
			)
		)
		(property "Value" ""
			(at 0 0 270)
			(layer "F.Fab")
			(effects
				(font
					(size 1.27 1.27)
				)
			)
		)
		(duplicate_pad_numbers_are_jumpers no)
		(fp_line
			(start -0.299974 0.150114)
			(end -0.299974 -0.150114)
			(stroke
				(width 0.1)
				(type default)
			)
			(layer "F.Fab")
		)
		(fp_line
			(start 0.299974 0.150114)
			(end -0.299974 0.150114)
			(stroke
				(width 0.1)
				(type default)
			)
			(layer "F.Fab")
		)
		(fp_line
			(start -0.299974 -0.150114)
			(end 0.299974 -0.150114)
			(stroke
				(width 0.1)
				(type default)
			)
			(layer "F.Fab")
		)
		(fp_line
			(start 0.299974 -0.150114)
			(end 0.299974 0.150114)
			(stroke
				(width 0.1)
				(type default)
			)
			(layer "F.Fab")
		)
		(pad "1" smd rect
			(at -0.2667 0 270)
			(size 0.3048 0.381)
			(layers "F.Cu" "F.Mask" "F.Paste")
			(net "P5E_CPU1_PE0_TX_C_DN<6>")
		)
		(pad "2" smd rect
			(at 0.2667 0 270)
			(size 0.3048 0.381)
			(layers "F.Cu" "F.Mask" "F.Paste")
			(net "P5E_CPU1_PE0_TX_DN<6>")
		)
	)
	(footprint ""
		(layer "F.Cu")
		(at 100.924614 -96.123506)
		(property "Reference" "Q87"
			(at 1.59766 -0.765048 0)
			(unlocked yes)
			(layer "F.SilkS")
			(effects
				(font
					(size 0.7874 0.5842)
					(thickness 0.1524)
				)
				(justify left)
			)
		)
		(property "Value" ""
			(at 0 0 0)
			(layer "F.Fab")
			(effects
				(font
					(size 1.27 1.27)
				)
			)
		)
		(duplicate_pad_numbers_are_jumpers no)
		(fp_line
			(start -1.332738 -1.100074)
			(end -0.4826 -1.100074)
			(stroke
				(width 0.1524)
				(type default)
			)
			(layer "F.SilkS")
		)
		(fp_line
			(start -1.332738 1.100074)
			(end -1.332738 -1.100074)
			(stroke
				(width 0.1524)
				(type default)
			)
			(layer "F.SilkS")
		)
		(fp_line
			(start -0.4826 -1.100074)
			(end 0 -0.541274)
			(stroke
				(width 0.1524)
				(type default)
			)
			(layer "F.SilkS")
		)
		(fp_line
			(start 0 -0.541274)
			(end 0.4826 -1.100074)
			(stroke
				(width 0.1524)
				(type default)
			)
			(layer "F.SilkS")
		)
		(fp_line
			(start 0.4826 -1.100074)
			(end 1.332738 -1.100074)
			(stroke
				(width 0.1524)
				(type default)
			)
			(layer "F.SilkS")
		)
		(fp_line
			(start 1.332738 -1.100074)
			(end 1.332738 1.100074)
			(stroke
				(width 0.1524)
				(type default)
			)
			(layer "F.SilkS")
		)
		(fp_line
			(start 1.332738 1.100074)
			(end -1.332738 1.100074)
			(stroke
				(width 0.1524)
				(type default)
			)
			(layer "F.SilkS")
		)
		(fp_poly
			(pts
				(xy -0.600202 -1.933448) (xy -0.95123 -1.231392) (xy -1.302258 -1.933448)
			)
			(stroke
				(width 0)
				(type default)
			)
			(fill yes)
			(layer "F.SilkS")
		)
		(fp_line
			(start -0.674878 -1.100074)
			(end 0.674878 -1.100074)
			(stroke
				(width 0.1)
				(type default)
			)
			(layer "F.Fab")
		)
		(fp_line
			(start -0.674878 1.100074)
			(end -0.674878 -1.100074)
			(stroke
				(width 0.1)
				(type default)
			)
			(layer "F.Fab")
		)
		(fp_line
			(start 0.674878 -1.100074)
			(end 0.674878 1.100074)
			(stroke
				(width 0.1)
				(type default)
			)
			(layer "F.Fab")
		)
		(fp_line
			(start 0.674878 1.100074)
			(end -0.674878 1.100074)
			(stroke
				(width 0.1)
				(type default)
			)
			(layer "F.Fab")
		)
		(fp_poly
			(pts
				(xy -2.2352 -0.298958) (xy -2.2352 -1.001014) (xy -1.533144 -0.649986)
			)
			(stroke
				(width 0)
				(type default)
			)
			(fill yes)
			(layer "F.Fab")
		)
		(pad "1" smd rect
			(at -0.94996 -0.649986 90)
			(size 0.4318 0.508)
			(layers "F.Cu" "F.Mask" "F.Paste")
			(net "GND")
		)
		(pad "2" smd rect
			(at -0.94996 0 90)
			(size 0.4318 0.508)
			(layers "F.Cu" "F.Mask" "F.Paste")
			(net "PWRGD_PCH_PWROK_R")
		)
		(pad "3" smd rect
			(at -0.94996 0.649986 90)
			(size 0.4318 0.508)
			(layers "F.Cu" "F.Mask" "F.Paste")
			(net "LED_PWRGD_SYS_PWROK_R_D")
		)
		(pad "4" smd rect
			(at 0.94996 0.649986 90)
			(size 0.4318 0.508)
			(layers "F.Cu" "F.Mask" "F.Paste")
			(net "GND")
		)
		(pad "5" smd rect
			(at 0.94996 0 90)
			(size 0.4318 0.508)
			(layers "F.Cu" "F.Mask" "F.Paste")
			(net "PWRGD_SYS_PWROK_R")
		)
		(pad "6" smd rect
			(at 0.94996 -0.649986 90)
			(size 0.4318 0.508)
			(layers "F.Cu" "F.Mask" "F.Paste")
			(net "LED_PWRGD_PCH_PWROK_R_D")
		)
	)
	(footprint ""
		(layer "F.Cu")
		(at 31.29788 -428.843948)
		(property "Reference" "R3467"
			(at 0 0 0)
			(layer "F.SilkS")
			(hide yes)
			(effects
				(font
					(size 1.27 1.27)
				)
			)
		)
		(property "Value" ""
			(at 0 0 0)
			(layer "F.Fab")
			(effects
				(font
					(size 1.27 1.27)
				)
			)
		)
		(duplicate_pad_numbers_are_jumpers no)
		(fp_line
			(start -0.7874 -0.4064)
			(end 0.7874 -0.4064)
			(stroke
				(width 0.1524)
				(type default)
			)
			(layer "F.SilkS")
		)
		(fp_line
			(start -0.7874 0.4064)
			(end -0.7874 -0.4064)
			(stroke
				(width 0.1524)
				(type default)
			)
			(layer "F.SilkS")
		)
		(fp_line
			(start 0.7874 -0.4064)
			(end 0.7874 0.4064)
			(stroke
				(width 0.1524)
				(type default)
			)
			(layer "F.SilkS")
		)
		(fp_line
			(start 0.7874 0.4064)
			(end -0.7874 0.4064)
			(stroke
				(width 0.1524)
				(type default)
			)
			(layer "F.SilkS")
		)
		(fp_line
			(start -0.67945 -0.305054)
			(end -0.12065 -0.305054)
			(stroke
				(width 0.1)
				(type default)
			)
			(layer "F.Fab")
		)
		(fp_line
			(start -0.67945 0.3048)
			(end -0.67945 -0.305054)
			(stroke
				(width 0.1)
				(type default)
			)
			(layer "F.Fab")
		)
		(fp_line
			(start -0.12065 -0.305054)
			(end -0.12065 -0.2794)
			(stroke
				(width 0.1)
				(type default)
			)
			(layer "F.Fab")
		)
		(fp_line
			(start -0.12065 -0.2794)
			(end 0.12065 -0.2794)
			(stroke
				(width 0.1)
				(type default)
			)
			(layer "F.Fab")
		)
		(fp_line
			(start -0.12065 0.2794)
			(end -0.12065 0.3048)
			(stroke
				(width 0.1)
				(type default)
			)
			(layer "F.Fab")
		)
		(fp_line
			(start -0.12065 0.3048)
			(end -0.67945 0.3048)
			(stroke
				(width 0.1)
				(type default)
			)
			(layer "F.Fab")
		)
		(fp_line
			(start 0.120396 0.2794)
			(end -0.12065 0.2794)
			(stroke
				(width 0.1)
				(type default)
			)
			(layer "F.Fab")
		)
		(fp_line
			(start 0.120396 0.3048)
			(end 0.120396 0.2794)
			(stroke
				(width 0.1)
				(type default)
			)
			(layer "F.Fab")
		)
		(fp_line
			(start 0.12065 -0.3048)
			(end 0.67945 -0.3048)
			(stroke
				(width 0.1)
				(type default)
			)
			(layer "F.Fab")
		)
		(fp_line
			(start 0.12065 -0.2794)
			(end 0.12065 -0.3048)
			(stroke
				(width 0.1)
				(type default)
			)
			(layer "F.Fab")
		)
		(fp_line
			(start 0.67945 -0.3048)
			(end 0.67945 0.3048)
			(stroke
				(width 0.1)
				(type default)
			)
			(layer "F.Fab")
		)
		(fp_line
			(start 0.67945 0.3048)
			(end 0.120396 0.3048)
			(stroke
				(width 0.1)
				(type default)
			)
			(layer "F.Fab")
		)
		(pad "1" smd circle
			(at -0.40005 0)
			(size 0 0)
			(layers "F.Cu" "F.Mask" "F.Paste")
			(net "RST_PERST_0_SWB_BUF_R_N")
		)
		(pad "2" smd circle
			(at 0.40005 0)
			(size 0 0)
			(layers "F.Cu" "F.Mask" "F.Paste")
			(net "GND")
		)
	)
	(footprint ""
		(layer "F.Cu")
		(at 300.99762 -413.756094 90)
		(property "Reference" "C2363"
			(at 0 0 90)
			(layer "F.SilkS")
			(hide yes)
			(effects
				(font
					(size 1.27 1.27)
				)
			)
		)
		(property "Value" ""
			(at 0 0 90)
			(layer "F.Fab")
			(effects
				(font
					(size 1.27 1.27)
				)
			)
		)
		(duplicate_pad_numbers_are_jumpers no)
		(fp_line
			(start 0.7874 -0.4064)
			(end 0.7874 0.4064)
			(stroke
				(width 0.1524)
				(type default)
			)
			(layer "F.SilkS")
		)
		(fp_line
			(start -0.7874 -0.4064)
			(end 0.7874 -0.4064)
			(stroke
				(width 0.1524)
				(type default)
			)
			(layer "F.SilkS")
		)
		(fp_line
			(start 0.7874 0.4064)
			(end -0.7874 0.4064)
			(stroke
				(width 0.1524)
				(type default)
			)
			(layer "F.SilkS")
		)
		(fp_line
			(start -0.7874 0.4064)
			(end -0.7874 -0.4064)
			(stroke
				(width 0.1524)
				(type default)
			)
			(layer "F.SilkS")
		)
		(fp_line
			(start -0.12065 -0.305054)
			(end -0.12065 -0.2794)
			(stroke
				(width 0.1)
				(type default)
			)
			(layer "F.Fab")
		)
		(fp_line
			(start -0.67945 -0.305054)
			(end -0.12065 -0.305054)
			(stroke
				(width 0.1)
				(type default)
			)
			(layer "F.Fab")
		)
		(fp_line
			(start 0.67945 -0.3048)
			(end 0.67945 0.3048)
			(stroke
				(width 0.1)
				(type default)
			)
			(layer "F.Fab")
		)
		(fp_line
			(start 0.12065 -0.3048)
			(end 0.67945 -0.3048)
			(stroke
				(width 0.1)
				(type default)
			)
			(layer "F.Fab")
		)
		(fp_line
			(start 0.12065 -0.2794)
			(end 0.12065 -0.3048)
			(stroke
				(width 0.1)
				(type default)
			)
			(layer "F.Fab")
		)
		(fp_line
			(start -0.12065 -0.2794)
			(end 0.12065 -0.2794)
			(stroke
				(width 0.1)
				(type default)
			)
			(layer "F.Fab")
		)
		(fp_line
			(start 0.120396 0.2794)
			(end -0.12065 0.2794)
			(stroke
				(width 0.1)
				(type default)
			)
			(layer "F.Fab")
		)
		(fp_line
			(start -0.12065 0.2794)
			(end -0.12065 0.3048)
			(stroke
				(width 0.1)
				(type default)
			)
			(layer "F.Fab")
		)
		(fp_line
			(start 0.67945 0.3048)
			(end 0.120396 0.3048)
			(stroke
				(width 0.1)
				(type default)
			)
			(layer "F.Fab")
		)
		(fp_line
			(start 0.120396 0.3048)
			(end 0.120396 0.2794)
			(stroke
				(width 0.1)
				(type default)
			)
			(layer "F.Fab")
		)
		(fp_line
			(start -0.12065 0.3048)
			(end -0.67945 0.3048)
			(stroke
				(width 0.1)
				(type default)
			)
			(layer "F.Fab")
		)
		(fp_line
			(start -0.67945 0.3048)
			(end -0.67945 -0.305054)
			(stroke
				(width 0.1)
				(type default)
			)
			(layer "F.Fab")
		)
		(pad "1" smd circle
			(at -0.40005 0 90)
			(size 0 0)
			(layers "F.Cu" "F.Mask" "F.Paste")
			(net "HSC_TYPE_ADC")
		)
		(pad "2" smd circle
			(at 0.40005 0 90)
			(size 0 0)
			(layers "F.Cu" "F.Mask" "F.Paste")
			(net "GND")
		)
	)
	(footprint ""
		(layer "F.Cu")
		(at 454.847452 -19.427698 -90)
		(property "Reference" "R3797"
			(at 0 0 270)
			(layer "F.SilkS")
			(hide yes)
			(effects
				(font
					(size 1.27 1.27)
				)
			)
		)
		(property "Value" ""
			(at 0 0 270)
			(layer "F.Fab")
			(effects
				(font
					(size 1.27 1.27)
				)
			)
		)
		(duplicate_pad_numbers_are_jumpers no)
		(fp_line
			(start -0.7874 0.4064)
			(end -0.7874 -0.4064)
			(stroke
				(width 0.1524)
				(type default)
			)
			(layer "F.SilkS")
		)
		(fp_line
			(start 0.7874 0.4064)
			(end -0.7874 0.4064)
			(stroke
				(width 0.1524)
				(type default)
			)
			(layer "F.SilkS")
		)
		(fp_line
			(start -0.7874 -0.4064)
			(end 0.7874 -0.4064)
			(stroke
				(width 0.1524)
				(type default)
			)
			(layer "F.SilkS")
		)
		(fp_line
			(start 0.7874 -0.4064)
			(end 0.7874 0.4064)
			(stroke
				(width 0.1524)
				(type default)
			)
			(layer "F.SilkS")
		)
		(fp_line
			(start -0.67945 0.3048)
			(end -0.67945 -0.305054)
			(stroke
				(width 0.1)
				(type default)
			)
			(layer "F.Fab")
		)
		(fp_line
			(start -0.12065 0.3048)
			(end -0.67945 0.3048)
			(stroke
				(width 0.1)
				(type default)
			)
			(layer "F.Fab")
		)
		(fp_line
			(start 0.120396 0.3048)
			(end 0.120396 0.2794)
			(stroke
				(width 0.1)
				(type default)
			)
			(layer "F.Fab")
		)
		(fp_line
			(start 0.67945 0.3048)
			(end 0.120396 0.3048)
			(stroke
				(width 0.1)
				(type default)
			)
			(layer "F.Fab")
		)
		(fp_line
			(start -0.12065 0.2794)
			(end -0.12065 0.3048)
			(stroke
				(width 0.1)
				(type default)
			)
			(layer "F.Fab")
		)
		(fp_line
			(start 0.120396 0.2794)
			(end -0.12065 0.2794)
			(stroke
				(width 0.1)
				(type default)
			)
			(layer "F.Fab")
		)
		(fp_line
			(start -0.12065 -0.2794)
			(end 0.12065 -0.2794)
			(stroke
				(width 0.1)
				(type default)
			)
			(layer "F.Fab")
		)
		(fp_line
			(start 0.12065 -0.2794)
			(end 0.12065 -0.3048)
			(stroke
				(width 0.1)
				(type default)
			)
			(layer "F.Fab")
		)
		(fp_line
			(start 0.12065 -0.3048)
			(end 0.67945 -0.3048)
			(stroke
				(width 0.1)
				(type default)
			)
			(layer "F.Fab")
		)
		(fp_line
			(start 0.67945 -0.3048)
			(end 0.67945 0.3048)
			(stroke
				(width 0.1)
				(type default)
			)
			(layer "F.Fab")
		)
		(fp_line
			(start -0.67945 -0.305054)
			(end -0.12065 -0.305054)
			(stroke
				(width 0.1)
				(type default)
			)
			(layer "F.Fab")
		)
		(fp_line
			(start -0.12065 -0.305054)
			(end -0.12065 -0.2794)
			(stroke
				(width 0.1)
				(type default)
			)
			(layer "F.Fab")
		)
		(pad "1" smd circle
			(at -0.40005 0 270)
			(size 0 0)
			(layers "F.Cu" "F.Mask" "F.Paste")
			(net "P3V3_AUX")
		)
		(pad "2" smd circle
			(at 0.40005 0 270)
			(size 0 0)
			(layers "F.Cu" "F.Mask" "F.Paste")
			(net "HP_LVC3_OCP_V3_1_P12V_PWRGD")
		)
	)
	(footprint ""
		(layer "F.Cu")
		(at 193.809366 -37.43325 90)
		(property "Reference" "Q39"
			(at -2.314702 -0.629158 0)
			(unlocked yes)
			(layer "F.SilkS")
			(effects
				(font
					(size 0.7874 0.5842)
					(thickness 0.1524)
				)
			)
		)
		(property "Value" ""
			(at 0 0 90)
			(layer "F.Fab")
			(effects
				(font
					(size 1.27 1.27)
				)
			)
		)
		(duplicate_pad_numbers_are_jumpers no)
		(fp_line
			(start 1.603248 -1.500124)
			(end 1.603248 1.500124)
			(stroke
				(width 0.1524)
				(type default)
			)
			(layer "F.SilkS")
		)
		(fp_line
			(start -1.603248 -1.500124)
			(end 1.603248 -1.500124)
			(stroke
				(width 0.1524)
				(type default)
			)
			(layer "F.SilkS")
		)
		(fp_line
			(start 1.603248 1.500124)
			(end -1.603248 1.500124)
			(stroke
				(width 0.1524)
				(type default)
			)
			(layer "F.SilkS")
		)
		(fp_line
			(start -1.603248 1.500124)
			(end -1.603248 -1.500124)
			(stroke
				(width 0.1524)
				(type default)
			)
			(layer "F.SilkS")
		)
		(fp_line
			(start 0.700024 -1.500124)
			(end -0.700024 -1.500124)
			(stroke
				(width 0.1)
				(type default)
			)
			(layer "F.Fab")
		)
		(fp_line
			(start -0.700024 -1.500124)
			(end -0.700024 -1.169924)
			(stroke
				(width 0.1)
				(type default)
			)
			(layer "F.Fab")
		)
		(fp_line
			(start -0.700024 -1.169924)
			(end -1.249934 -1.169924)
			(stroke
				(width 0.1)
				(type default)
			)
			(layer "F.Fab")
		)
		(fp_line
			(start -1.249934 -1.169924)
			(end -1.249934 -0.729996)
			(stroke
				(width 0.1)
				(type default)
			)
			(layer "F.Fab")
		)
		(fp_line
			(start -0.6985 -0.729996)
			(end -0.6985 0.729996)
			(stroke
				(width 0.1)
				(type default)
			)
			(layer "F.Fab")
		)
		(fp_line
			(start -1.249934 -0.729996)
			(end -0.6985 -0.729996)
			(stroke
				(width 0.1)
				(type default)
			)
			(layer "F.Fab")
		)
		(fp_line
			(start 1.249934 -0.219964)
			(end 0.700024 -0.219964)
			(stroke
				(width 0.1)
				(type default)
			)
			(layer "F.Fab")
		)
		(fp_line
			(start 0.700024 -0.219964)
			(end 0.700024 -1.500124)
			(stroke
				(width 0.1)
				(type default)
			)
			(layer "F.Fab")
		)
		(fp_line
			(start 1.249934 0.219964)
			(end 1.249934 -0.219964)
			(stroke
				(width 0.1)
				(type default)
			)
			(layer "F.Fab")
		)
		(fp_line
			(start 0.700024 0.219964)
			(end 1.249934 0.219964)
			(stroke
				(width 0.1)
				(type default)
			)
			(layer "F.Fab")
		)
		(fp_line
			(start -0.6985 0.729996)
			(end -1.249934 0.729996)
			(stroke
				(width 0.1)
				(type default)
			)
			(layer "F.Fab")
		)
		(fp_line
			(start -1.249934 0.729996)
			(end -1.249934 1.169924)
			(stroke
				(width 0.1)
				(type default)
			)
			(layer "F.Fab")
		)
		(fp_line
			(start -0.700024 1.169924)
			(end -0.700024 1.500124)
			(stroke
				(width 0.1)
				(type default)
			)
			(layer "F.Fab")
		)
		(fp_line
			(start -1.249934 1.169924)
			(end -0.700024 1.169924)
			(stroke
				(width 0.1)
				(type default)
			)
			(layer "F.Fab")
		)
		(fp_line
			(start 0.700024 1.500124)
			(end 0.700024 0.219964)
			(stroke
				(width 0.1)
				(type default)
			)
			(layer "F.Fab")
		)
		(fp_line
			(start -0.700024 1.500124)
			(end 0.700024 1.500124)
			(stroke
				(width 0.1)
				(type default)
			)
			(layer "F.Fab")
		)
		(fp_rect
			(start -0.700024 -1.500124)
			(end 0.700024 1.500124)
			(stroke
				(width 0)
				(type default)
			)
			(fill no)
			(layer "F.Fab")
		)
		(pad "D" smd rect
			(at 0.999998 0)
			(size 0.8128 0.9144)
			(layers "F.Cu" "F.Mask" "F.Paste")
			(net "P12V_SCM_EN")
		)
		(pad "G" smd rect
			(at -0.999998 -0.94996)
			(size 0.8128 0.9144)
			(layers "F.Cu" "F.Mask" "F.Paste")
			(net "FM_SCM_PRSNT1_R_N")
		)
		(pad "S" smd rect
			(at -0.999998 0.94996)
			(size 0.8128 0.9144)
			(layers "F.Cu" "F.Mask" "F.Paste")
			(net "GND")
		)
	)
	(footprint ""
		(layer "F.Cu")
		(at 96.997774 -333.716122)
		(property "Reference" "PU31_P1_1"
			(at -2.685796 -6.321298 0)
			(unlocked yes)
			(layer "F.SilkS")
			(effects
				(font
					(size 0.7874 0.5842)
					(thickness 0.1524)
				)
				(justify left)
			)
		)
		(property "Value" ""
			(at 0 0 0)
			(layer "F.Fab")
			(effects
				(font
					(size 1.27 1.27)
				)
			)
		)
		(duplicate_pad_numbers_are_jumpers no)
		(fp_line
			(start -2.500122 -2.999994)
			(end -2.24409 -2.999994)
			(stroke
				(width 0.1524)
				(type default)
			)
			(layer "F.SilkS")
		)
		(fp_line
			(start -2.500122 -2.529078)
			(end -2.500122 -2.999994)
			(stroke
				(width 0.1524)
				(type default)
			)
			(layer "F.SilkS")
		)
		(fp_line
			(start -2.500122 0.6604)
			(end -2.500122 0.229108)
			(stroke
				(width 0.1524)
				(type default)
			)
			(layer "F.SilkS")
		)
		(fp_line
			(start -2.500122 2.999994)
			(end -2.500122 2.339594)
			(stroke
				(width 0.1524)
				(type default)
			)
			(layer "F.SilkS")
		)
		(fp_line
			(start -2.2987 2.999994)
			(end -2.500122 2.999994)
			(stroke
				(width 0.1524)
				(type default)
			)
			(layer "F.SilkS")
		)
		(fp_line
			(start 2.31394 -2.999994)
			(end 2.500122 -2.999994)
			(stroke
				(width 0.1524)
				(type default)
			)
			(layer "F.SilkS")
		)
		(fp_line
			(start 2.500122 -2.999994)
			(end 2.500122 -2.44348)
			(stroke
				(width 0.1524)
				(type default)
			)
			(layer "F.SilkS")
		)
		(fp_line
			(start 2.500122 2.339594)
			(end 2.500122 2.999994)
			(stroke
				(width 0.1524)
				(type default)
			)
			(layer "F.SilkS")
		)
		(fp_line
			(start 2.500122 2.999994)
			(end 2.2987 2.999994)
			(stroke
				(width 0.1524)
				(type default)
			)
			(layer "F.SilkS")
		)
		(fp_poly
			(pts
				(xy -2.162302 -3.588004) (xy -2.670302 -2.572004) (xy -3.178302 -3.588004)
			)
			(stroke
				(width 0)
				(type default)
			)
			(fill yes)
			(layer "F.SilkS")
		)
		(fp_line
			(start -2.500122 -2.999994)
			(end 2.500122 -2.999994)
			(stroke
				(width 0.1)
				(type default)
			)
			(layer "F.Fab")
		)
		(fp_line
			(start -2.500122 2.999994)
			(end -2.500122 -2.999994)
			(stroke
				(width 0.1)
				(type default)
			)
			(layer "F.Fab")
		)
		(fp_line
			(start 2.500122 -2.999994)
			(end 2.500122 2.999994)
			(stroke
				(width 0.1)
				(type default)
			)
			(layer "F.Fab")
		)
		(fp_line
			(start 2.500122 2.999994)
			(end -2.500122 2.999994)
			(stroke
				(width 0.1)
				(type default)
			)
			(layer "F.Fab")
		)
		(fp_poly
			(pts
				(xy -4.218432 -2.783078) (xy -4.218432 -1.767078) (xy -3.202432 -2.275078)
			)
			(stroke
				(width 0)
				(type default)
			)
			(fill yes)
			(layer "F.Fab")
		)
		(pad "1" smd rect
			(at -2.400046 -2.275078 90)
			(size 0.2286 0.6096)
			(layers "F.Cu" "F.Mask" "F.Paste")
			(net "PVCCIN_CPU1_VOS1")
		)
		(pad "2" smd rect
			(at -2.400046 -1.82499 90)
			(size 0.2286 0.6096)
			(layers "F.Cu" "F.Mask" "F.Paste")
			(net "GND")
		)
		(pad "3" smd rect
			(at -2.400046 -1.374902 90)
			(size 0.2286 0.6096)
			(layers "F.Cu" "F.Mask" "F.Paste")
			(net "PVCCIN_CPU1_VDD1")
		)
		(pad "4" smd rect
			(at -2.400046 -0.925068 90)
			(size 0.2286 0.6096)
			(layers "F.Cu" "F.Mask" "F.Paste")
			(net "PVCCIN_CPU1_PVCC")
		)
		(pad "5" smd rect
			(at -2.400046 -0.47498 90)
			(size 0.2286 0.6096)
			(layers "F.Cu" "F.Mask" "F.Paste")
			(net "GND")
		)
		(pad "6" smd rect
			(at -2.400046 -0.024892 90)
			(size 0.2286 0.6096)
			(layers "F.Cu" "F.Mask" "F.Paste")
			(net "Net_8520")
		)
		(pad "7_9-20_24" smd circle
			(at 0 1.150112 90)
			(size 0 0)
			(layers "F.Cu" "F.Mask" "F.Paste")
			(net "GND")
		)
		(pad "10_19" smd rect
			(at 0 2.899918 90)
			(size 0.6096 4.318)
			(layers "F.Cu" "F.Mask" "F.Paste")
			(net "SW_PVCCIN_CPU1_SW1")
		)
		(pad "25_29" smd rect
			(at 1.549908 -1.279906 270)
			(size 2.0574 2.3114)
			(layers "F.Cu" "F.Mask" "F.Paste")
			(net "SW_P12V_PVCCIN_CPU1_FLT")
		)
		(pad "30" smd rect
			(at 2.05994 -2.899918)
			(size 0.2286 0.6096)
			(layers "F.Cu" "F.Mask" "F.Paste")
			(net "SW_P12V_PVCCIN_CPU1_FLT")
		)
		(pad "31" smd rect
			(at 1.610106 -2.899918)
			(size 0.2286 0.6096)
			(layers "F.Cu" "F.Mask" "F.Paste")
			(net "Net_8521")
		)
		(pad "32" smd rect
			(at 1.160018 -2.899918)
			(size 0.2286 0.6096)
			(layers "F.Cu" "F.Mask" "F.Paste")
			(net "SW_PVCCIN_CPU1_BOOTR1")
		)
		(pad "33" smd rect
			(at 0.70993 -2.899918)
			(size 0.2286 0.6096)
			(layers "F.Cu" "F.Mask" "F.Paste")
			(net "SW_PVCCIN_CPU1_BOOT1")
		)
		(pad "34" smd rect
			(at 0.260096 -2.899918)
			(size 0.2286 0.6096)
			(layers "F.Cu" "F.Mask" "F.Paste")
			(net "PVCCIN_CPU1_PWM1")
		)
		(pad "35" smd rect
			(at -0.189992 -2.899918)
			(size 0.2286 0.6096)
			(layers "F.Cu" "F.Mask" "F.Paste")
			(net "PVCCIN_CPU1_VDD1")
		)
		(pad "36" smd rect
			(at -0.64008 -2.899918)
			(size 0.2286 0.6096)
			(layers "F.Cu" "F.Mask" "F.Paste")
			(net "PVCCIN_CPU1_ATSEN")
		)
		(pad "37" smd rect
			(at -1.089914 -2.899918)
			(size 0.2286 0.6096)
			(layers "F.Cu" "F.Mask" "F.Paste")
			(net "PVCCIN_CPU1_LSET1")
		)
		(pad "38" smd rect
			(at -1.540002 -2.899918)
			(size 0.2286 0.6096)
			(layers "F.Cu" "F.Mask" "F.Paste")
			(net "PVCCIN_CPU1_IMON1")
		)
		(pad "39" smd rect
			(at -1.99009 -2.899918)
			(size 0.2286 0.6096)
			(layers "F.Cu" "F.Mask" "F.Paste")
			(net "PVCCIN_CPU1_VREF")
		)
		(pad "40" smd rect
			(at -0.87503 -1.27508)
			(size 1.7526 1.9558)
			(layers "F.Cu" "F.Mask" "F.Paste")
			(net "GND")
		)
		(pad "41" smd rect
			(at -1.525016 0.249936 270)
			(size 0.3048 0.4572)
			(layers "F.Cu" "F.Mask" "F.Paste")
			(net "Net_8519")
		)
		(zone
			(layer "F.Cu")
			(hatch none 0.5)
			(connect_pads
				(clearance 0)
			)
			(min_thickness 0.25)
			(keepout
				(tracks not_allowed)
				(vias allowed)
				(pads allowed)
				(copperpour not_allowed)
				(footprints allowed)
			)
			(placement
				(enabled no)
				(sheetname "")
			)
			(fill
				(thermal_gap 0.5)
				(thermal_bridge_width 0.5)
				(island_removal_mode 0)
			)
			(polygon
				(pts
					(xy 94.497652 -330.716128) (xy 94.497652 -331.465428) (xy 99.497896 -331.465428) (xy 99.497896 -330.716128)
					(xy 99.207574 -330.716128) (xy 99.207574 -331.171804) (xy 94.787974 -331.171804) (xy 94.787974 -330.716128)
				)
			)
		)
		(zone
			(layer "F.Cu")
			(hatch none 0.5)
			(connect_pads
				(clearance 0)
			)
			(min_thickness 0.25)
			(keepout
				(tracks not_allowed)
				(vias allowed)
				(pads allowed)
				(copperpour not_allowed)
				(footprints allowed)
			)
			(placement
				(enabled no)
				(sheetname "")
			)
			(fill
				(thermal_gap 0.5)
				(thermal_bridge_width 0.5)
				(island_removal_mode 0)
			)
			(polygon
				(pts
					(xy 94.953328 -334.040988) (xy 95.195644 -334.040988) (xy 95.195644 -333.962502) (xy 95.96374 -333.962502)
					(xy 95.96374 -333.637128) (xy 96.047052 -333.637128) (xy 96.047052 -332.966822) (xy 94.497652 -332.966822)
					(xy 94.497652 -333.423514) (xy 95.193358 -333.423514) (xy 95.193358 -333.262986) (xy 95.752158 -333.262986)
					(xy 95.752158 -333.669386) (xy 95.193358 -333.669386) (xy 95.193358 -333.448914) (xy 94.497652 -333.448914)
					(xy 94.497652 -333.575914) (xy 94.953328 -333.575914)
				)
			)
		)
	)
	(footprint ""
		(layer "F.Cu")
		(at 438.558432 -27.275536 -90)
		(property "Reference" "PR3842"
			(at 0 0 270)
			(layer "F.SilkS")
			(hide yes)
			(effects
				(font
					(size 1.27 1.27)
				)
			)
		)
		(property "Value" ""
			(at 0 0 270)
			(layer "F.Fab")
			(effects
				(font
					(size 1.27 1.27)
				)
			)
		)
		(duplicate_pad_numbers_are_jumpers no)
		(fp_line
			(start -0.7874 0.4064)
			(end -0.7874 -0.4064)
			(stroke
				(width 0.1524)
				(type default)
			)
			(layer "F.SilkS")
		)
		(fp_line
			(start 0.7874 0.4064)
			(end -0.7874 0.4064)
			(stroke
				(width 0.1524)
				(type default)
			)
			(layer "F.SilkS")
		)
		(fp_line
			(start -0.7874 -0.4064)
			(end 0.7874 -0.4064)
			(stroke
				(width 0.1524)
				(type default)
			)
			(layer "F.SilkS")
		)
		(fp_line
			(start 0.7874 -0.4064)
			(end 0.7874 0.4064)
			(stroke
				(width 0.1524)
				(type default)
			)
			(layer "F.SilkS")
		)
		(fp_line
			(start -0.67945 0.3048)
			(end -0.67945 -0.305054)
			(stroke
				(width 0.1)
				(type default)
			)
			(layer "F.Fab")
		)
		(fp_line
			(start -0.12065 0.3048)
			(end -0.67945 0.3048)
			(stroke
				(width 0.1)
				(type default)
			)
			(layer "F.Fab")
		)
		(fp_line
			(start 0.120396 0.3048)
			(end 0.120396 0.2794)
			(stroke
				(width 0.1)
				(type default)
			)
			(layer "F.Fab")
		)
		(fp_line
			(start 0.67945 0.3048)
			(end 0.120396 0.3048)
			(stroke
				(width 0.1)
				(type default)
			)
			(layer "F.Fab")
		)
		(fp_line
			(start -0.12065 0.2794)
			(end -0.12065 0.3048)
			(stroke
				(width 0.1)
				(type default)
			)
			(layer "F.Fab")
		)
		(fp_line
			(start 0.120396 0.2794)
			(end -0.12065 0.2794)
			(stroke
				(width 0.1)
				(type default)
			)
			(layer "F.Fab")
		)
		(fp_line
			(start -0.12065 -0.2794)
			(end 0.12065 -0.2794)
			(stroke
				(width 0.1)
				(type default)
			)
			(layer "F.Fab")
		)
		(fp_line
			(start 0.12065 -0.2794)
			(end 0.12065 -0.3048)
			(stroke
				(width 0.1)
				(type default)
			)
			(layer "F.Fab")
		)
		(fp_line
			(start 0.12065 -0.3048)
			(end 0.67945 -0.3048)
			(stroke
				(width 0.1)
				(type default)
			)
			(layer "F.Fab")
		)
		(fp_line
			(start 0.67945 -0.3048)
			(end 0.67945 0.3048)
			(stroke
				(width 0.1)
				(type default)
			)
			(layer "F.Fab")
		)
		(fp_line
			(start -0.67945 -0.305054)
			(end -0.12065 -0.305054)
			(stroke
				(width 0.1)
				(type default)
			)
			(layer "F.Fab")
		)
		(fp_line
			(start -0.12065 -0.305054)
			(end -0.12065 -0.2794)
			(stroke
				(width 0.1)
				(type default)
			)
			(layer "F.Fab")
		)
		(pad "1" smd circle
			(at -0.40005 0 270)
			(size 0 0)
			(layers "F.Cu" "F.Mask" "F.Paste")
			(net "P12V_OCP_OV_FB_1")
		)
		(pad "2" smd circle
			(at 0.40005 0 270)
			(size 0 0)
			(layers "F.Cu" "F.Mask" "F.Paste")
			(net "GND")
		)
	)
	(footprint ""
		(layer "F.Cu")
		(at 330.432918 -347.580458 -90)
		(property "Reference" "PC235"
			(at 0 0 270)
			(layer "F.SilkS")
			(hide yes)
			(effects
				(font
					(size 1.27 1.27)
				)
			)
		)
		(property "Value" ""
			(at 0 0 270)
			(layer "F.Fab")
			(effects
				(font
					(size 1.27 1.27)
				)
			)
		)
		(duplicate_pad_numbers_are_jumpers no)
		(fp_line
			(start -0.7874 0.4064)
			(end -0.7874 -0.4064)
			(stroke
				(width 0.1524)
				(type default)
			)
			(layer "F.SilkS")
		)
		(fp_line
			(start 0.7874 0.4064)
			(end -0.7874 0.4064)
			(stroke
				(width 0.1524)
				(type default)
			)
			(layer "F.SilkS")
		)
		(fp_line
			(start -0.7874 -0.4064)
			(end 0.7874 -0.4064)
			(stroke
				(width 0.1524)
				(type default)
			)
			(layer "F.SilkS")
		)
		(fp_line
			(start 0.7874 -0.4064)
			(end 0.7874 0.4064)
			(stroke
				(width 0.1524)
				(type default)
			)
			(layer "F.SilkS")
		)
		(fp_line
			(start -0.67945 0.3048)
			(end -0.67945 -0.305054)
			(stroke
				(width 0.1)
				(type default)
			)
			(layer "F.Fab")
		)
		(fp_line
			(start -0.12065 0.3048)
			(end -0.67945 0.3048)
			(stroke
				(width 0.1)
				(type default)
			)
			(layer "F.Fab")
		)
		(fp_line
			(start 0.120396 0.3048)
			(end 0.120396 0.2794)
			(stroke
				(width 0.1)
				(type default)
			)
			(layer "F.Fab")
		)
		(fp_line
			(start 0.67945 0.3048)
			(end 0.120396 0.3048)
			(stroke
				(width 0.1)
				(type default)
			)
			(layer "F.Fab")
		)
		(fp_line
			(start -0.12065 0.2794)
			(end -0.12065 0.3048)
			(stroke
				(width 0.1)
				(type default)
			)
			(layer "F.Fab")
		)
		(fp_line
			(start 0.120396 0.2794)
			(end -0.12065 0.2794)
			(stroke
				(width 0.1)
				(type default)
			)
			(layer "F.Fab")
		)
		(fp_line
			(start -0.12065 -0.2794)
			(end 0.12065 -0.2794)
			(stroke
				(width 0.1)
				(type default)
			)
			(layer "F.Fab")
		)
		(fp_line
			(start 0.12065 -0.2794)
			(end 0.12065 -0.3048)
			(stroke
				(width 0.1)
				(type default)
			)
			(layer "F.Fab")
		)
		(fp_line
			(start 0.12065 -0.3048)
			(end 0.67945 -0.3048)
			(stroke
				(width 0.1)
				(type default)
			)
			(layer "F.Fab")
		)
		(fp_line
			(start 0.67945 -0.3048)
			(end 0.67945 0.3048)
			(stroke
				(width 0.1)
				(type default)
			)
			(layer "F.Fab")
		)
		(fp_line
			(start -0.67945 -0.305054)
			(end -0.12065 -0.305054)
			(stroke
				(width 0.1)
				(type default)
			)
			(layer "F.Fab")
		)
		(fp_line
			(start -0.12065 -0.305054)
			(end -0.12065 -0.2794)
			(stroke
				(width 0.1)
				(type default)
			)
			(layer "F.Fab")
		)
		(pad "1" smd circle
			(at -0.40005 0 270)
			(size 0 0)
			(layers "F.Cu" "F.Mask" "F.Paste")
			(net "SW_PVCCIN_CPU0_BOOT7_R")
		)
		(pad "2" smd circle
			(at 0.40005 0 270)
			(size 0 0)
			(layers "F.Cu" "F.Mask" "F.Paste")
			(net "SW_PVCCIN_CPU0_BOOTR7")
		)
	)
	(footprint ""
		(layer "F.Cu")
		(at 408.554682 -162.185858 180)
		(property "Reference" "PL35"
			(at -0.979678 4.10464 0)
			(unlocked yes)
			(layer "F.SilkS")
			(effects
				(font
					(size 0.7874 0.5842)
					(thickness 0.1524)
				)
				(justify left)
			)
		)
		(property "Value" ""
			(at 0 0 180)
			(layer "F.Fab")
			(effects
				(font
					(size 1.27 1.27)
				)
			)
		)
		(duplicate_pad_numbers_are_jumpers no)
		(fp_line
			(start 3.24993 3.24993)
			(end -3.24993 3.24993)
			(stroke
				(width 0.1524)
				(type default)
			)
			(layer "F.SilkS")
		)
		(fp_line
			(start 3.24993 2.2352)
			(end 3.24993 3.24993)
			(stroke
				(width 0.1524)
				(type default)
			)
			(layer "F.SilkS")
		)
		(fp_line
			(start 3.24993 -3.24993)
			(end 3.24993 -2.2352)
			(stroke
				(width 0.1524)
				(type default)
			)
			(layer "F.SilkS")
		)
		(fp_line
			(start -3.24993 3.24993)
			(end -3.24993 2.2352)
			(stroke
				(width 0.1524)
				(type default)
			)
			(layer "F.SilkS")
		)
		(fp_line
			(start -3.24993 -2.2352)
			(end -3.24993 -3.24993)
			(stroke
				(width 0.1524)
				(type default)
			)
			(layer "F.SilkS")
		)
		(fp_line
			(start -3.24993 -3.24993)
			(end 3.24993 -3.24993)
			(stroke
				(width 0.1524)
				(type default)
			)
			(layer "F.SilkS")
		)
		(fp_line
			(start 3.24993 3.24993)
			(end -3.24993 3.24993)
			(stroke
				(width 0.1)
				(type default)
			)
			(layer "F.Fab")
		)
		(fp_line
			(start 3.24993 -3.24993)
			(end 3.24993 3.24993)
			(stroke
				(width 0.1)
				(type default)
			)
			(layer "F.Fab")
		)
		(fp_line
			(start -3.24993 3.24993)
			(end -3.24993 -3.24993)
			(stroke
				(width 0.1)
				(type default)
			)
			(layer "F.Fab")
		)
		(fp_line
			(start -3.24993 -3.24993)
			(end 3.24993 -3.24993)
			(stroke
				(width 0.1)
				(type default)
			)
			(layer "F.Fab")
		)
		(pad "1" smd rect
			(at -2.29997 0 180)
			(size 2.0066 4.2164)
			(layers "F.Cu" "F.Mask" "F.Paste")
			(net "SW_PVCCD_HV_CPU0_SW1")
		)
		(pad "2" smd rect
			(at 2.29997 0 180)
			(size 2.0066 4.2164)
			(layers "F.Cu" "F.Mask" "F.Paste")
			(net "PVCCD_HV_CPU0")
		)
	)
	(footprint ""
		(layer "F.Cu")
		(at 397.24965 -408.517344 -90)
		(property "Reference" "C886"
			(at 0 0 270)
			(layer "F.SilkS")
			(hide yes)
			(effects
				(font
					(size 1.27 1.27)
				)
			)
		)
		(property "Value" ""
			(at 0 0 270)
			(layer "F.Fab")
			(effects
				(font
					(size 1.27 1.27)
				)
			)
		)
		(duplicate_pad_numbers_are_jumpers no)
		(fp_line
			(start -0.299974 0.150114)
			(end -0.299974 -0.150114)
			(stroke
				(width 0.1)
				(type default)
			)
			(layer "F.Fab")
		)
		(fp_line
			(start 0.299974 0.150114)
			(end -0.299974 0.150114)
			(stroke
				(width 0.1)
				(type default)
			)
			(layer "F.Fab")
		)
		(fp_line
			(start -0.299974 -0.150114)
			(end 0.299974 -0.150114)
			(stroke
				(width 0.1)
				(type default)
			)
			(layer "F.Fab")
		)
		(fp_line
			(start 0.299974 -0.150114)
			(end 0.299974 0.150114)
			(stroke
				(width 0.1)
				(type default)
			)
			(layer "F.Fab")
		)
		(pad "1" smd rect
			(at -0.2667 0 270)
			(size 0.3048 0.381)
			(layers "F.Cu" "F.Mask" "F.Paste")
			(net "P5E_CPU0_PE3_TX_C_DN<7>")
		)
		(pad "2" smd rect
			(at 0.2667 0 270)
			(size 0.3048 0.381)
			(layers "F.Cu" "F.Mask" "F.Paste")
			(net "P5E_CPU0_PE3_TX_DN<7>")
		)
	)
	(footprint ""
		(layer "F.Cu")
		(at 107.2896 -249.320558 -90)
		(property "Reference" "C307"
			(at 0 0 270)
			(layer "F.SilkS")
			(hide yes)
			(effects
				(font
					(size 1.27 1.27)
				)
			)
		)
		(property "Value" ""
			(at 0 0 270)
			(layer "F.Fab")
			(effects
				(font
					(size 1.27 1.27)
				)
			)
		)
		(duplicate_pad_numbers_are_jumpers no)
		(fp_line
			(start -0.7874 0.4064)
			(end -0.7874 -0.4064)
			(stroke
				(width 0.1524)
				(type default)
			)
			(layer "F.SilkS")
		)
		(fp_line
			(start 0.7874 0.4064)
			(end -0.7874 0.4064)
			(stroke
				(width 0.1524)
				(type default)
			)
			(layer "F.SilkS")
		)
		(fp_line
			(start -0.7874 -0.4064)
			(end 0.7874 -0.4064)
			(stroke
				(width 0.1524)
				(type default)
			)
			(layer "F.SilkS")
		)
		(fp_line
			(start 0.7874 -0.4064)
			(end 0.7874 0.4064)
			(stroke
				(width 0.1524)
				(type default)
			)
			(layer "F.SilkS")
		)
		(fp_line
			(start -0.67945 0.3048)
			(end -0.67945 -0.305054)
			(stroke
				(width 0.1)
				(type default)
			)
			(layer "F.Fab")
		)
		(fp_line
			(start -0.12065 0.3048)
			(end -0.67945 0.3048)
			(stroke
				(width 0.1)
				(type default)
			)
			(layer "F.Fab")
		)
		(fp_line
			(start 0.120396 0.3048)
			(end 0.120396 0.2794)
			(stroke
				(width 0.1)
				(type default)
			)
			(layer "F.Fab")
		)
		(fp_line
			(start 0.67945 0.3048)
			(end 0.120396 0.3048)
			(stroke
				(width 0.1)
				(type default)
			)
			(layer "F.Fab")
		)
		(fp_line
			(start -0.12065 0.2794)
			(end -0.12065 0.3048)
			(stroke
				(width 0.1)
				(type default)
			)
			(layer "F.Fab")
		)
		(fp_line
			(start 0.120396 0.2794)
			(end -0.12065 0.2794)
			(stroke
				(width 0.1)
				(type default)
			)
			(layer "F.Fab")
		)
		(fp_line
			(start -0.12065 -0.2794)
			(end 0.12065 -0.2794)
			(stroke
				(width 0.1)
				(type default)
			)
			(layer "F.Fab")
		)
		(fp_line
			(start 0.12065 -0.2794)
			(end 0.12065 -0.3048)
			(stroke
				(width 0.1)
				(type default)
			)
			(layer "F.Fab")
		)
		(fp_line
			(start 0.12065 -0.3048)
			(end 0.67945 -0.3048)
			(stroke
				(width 0.1)
				(type default)
			)
			(layer "F.Fab")
		)
		(fp_line
			(start 0.67945 -0.3048)
			(end 0.67945 0.3048)
			(stroke
				(width 0.1)
				(type default)
			)
			(layer "F.Fab")
		)
		(fp_line
			(start -0.67945 -0.305054)
			(end -0.12065 -0.305054)
			(stroke
				(width 0.1)
				(type default)
			)
			(layer "F.Fab")
		)
		(fp_line
			(start -0.12065 -0.305054)
			(end -0.12065 -0.2794)
			(stroke
				(width 0.1)
				(type default)
			)
			(layer "F.Fab")
		)
		(pad "1" smd circle
			(at -0.40005 0 270)
			(size 0 0)
			(layers "F.Cu" "F.Mask" "F.Paste")
			(net "PVCCIN_CPU1")
		)
		(pad "2" smd circle
			(at 0.40005 0 270)
			(size 0 0)
			(layers "F.Cu" "F.Mask" "F.Paste")
			(net "GND")
		)
	)
	(footprint ""
		(layer "F.Cu")
		(at 194.856608 -400.784822 180)
		(property "Reference" "PR3914"
			(at 0 0 180)
			(layer "F.SilkS")
			(hide yes)
			(effects
				(font
					(size 1.27 1.27)
				)
			)
		)
		(property "Value" ""
			(at 0 0 180)
			(layer "F.Fab")
			(effects
				(font
					(size 1.27 1.27)
				)
			)
		)
		(duplicate_pad_numbers_are_jumpers no)
		(fp_line
			(start 0.7874 0.4064)
			(end -0.7874 0.4064)
			(stroke
				(width 0.1524)
				(type default)
			)
			(layer "F.SilkS")
		)
		(fp_line
			(start 0.7874 -0.4064)
			(end 0.7874 0.4064)
			(stroke
				(width 0.1524)
				(type default)
			)
			(layer "F.SilkS")
		)
		(fp_line
			(start -0.7874 0.4064)
			(end -0.7874 -0.4064)
			(stroke
				(width 0.1524)
				(type default)
			)
			(layer "F.SilkS")
		)
		(fp_line
			(start -0.7874 -0.4064)
			(end 0.7874 -0.4064)
			(stroke
				(width 0.1524)
				(type default)
			)
			(layer "F.SilkS")
		)
		(fp_line
			(start 0.67945 0.3048)
			(end 0.120396 0.3048)
			(stroke
				(width 0.1)
				(type default)
			)
			(layer "F.Fab")
		)
		(fp_line
			(start 0.67945 -0.3048)
			(end 0.67945 0.3048)
			(stroke
				(width 0.1)
				(type default)
			)
			(layer "F.Fab")
		)
		(fp_line
			(start 0.12065 -0.2794)
			(end 0.12065 -0.3048)
			(stroke
				(width 0.1)
				(type default)
			)
			(layer "F.Fab")
		)
		(fp_line
			(start 0.12065 -0.3048)
			(end 0.67945 -0.3048)
			(stroke
				(width 0.1)
				(type default)
			)
			(layer "F.Fab")
		)
		(fp_line
			(start 0.120396 0.3048)
			(end 0.120396 0.2794)
			(stroke
				(width 0.1)
				(type default)
			)
			(layer "F.Fab")
		)
		(fp_line
			(start 0.120396 0.2794)
			(end -0.12065 0.2794)
			(stroke
				(width 0.1)
				(type default)
			)
			(layer "F.Fab")
		)
		(fp_line
			(start -0.12065 0.3048)
			(end -0.67945 0.3048)
			(stroke
				(width 0.1)
				(type default)
			)
			(layer "F.Fab")
		)
		(fp_line
			(start -0.12065 0.2794)
			(end -0.12065 0.3048)
			(stroke
				(width 0.1)
				(type default)
			)
			(layer "F.Fab")
		)
		(fp_line
			(start -0.12065 -0.2794)
			(end 0.12065 -0.2794)
			(stroke
				(width 0.1)
				(type default)
			)
			(layer "F.Fab")
		)
		(fp_line
			(start -0.12065 -0.305054)
			(end -0.12065 -0.2794)
			(stroke
				(width 0.1)
				(type default)
			)
			(layer "F.Fab")
		)
		(fp_line
			(start -0.67945 0.3048)
			(end -0.67945 -0.305054)
			(stroke
				(width 0.1)
				(type default)
			)
			(layer "F.Fab")
		)
		(fp_line
			(start -0.67945 -0.305054)
			(end -0.12065 -0.305054)
			(stroke
				(width 0.1)
				(type default)
			)
			(layer "F.Fab")
		)
		(pad "1" smd circle
			(at -0.40005 0 180)
			(size 0 0)
			(layers "F.Cu" "F.Mask" "F.Paste")
			(net "HSC_CS_1")
		)
		(pad "2" smd circle
			(at 0.40005 0 180)
			(size 0 0)
			(layers "F.Cu" "F.Mask" "F.Paste")
			(net "AGND_HSC")
		)
	)
	(footprint ""
		(layer "F.Cu")
		(at 30.392878 -17.623536 90)
		(property "Reference" "C817"
			(at 0 0 90)
			(layer "F.SilkS")
			(hide yes)
			(effects
				(font
					(size 1.27 1.27)
				)
			)
		)
		(property "Value" ""
			(at 0 0 90)
			(layer "F.Fab")
			(effects
				(font
					(size 1.27 1.27)
				)
			)
		)
		(duplicate_pad_numbers_are_jumpers no)
		(fp_line
			(start 0.299974 -0.150114)
			(end 0.299974 0.150114)
			(stroke
				(width 0.1)
				(type default)
			)
			(layer "F.Fab")
		)
		(fp_line
			(start -0.299974 -0.150114)
			(end 0.299974 -0.150114)
			(stroke
				(width 0.1)
				(type default)
			)
			(layer "F.Fab")
		)
		(fp_line
			(start 0.299974 0.150114)
			(end -0.299974 0.150114)
			(stroke
				(width 0.1)
				(type default)
			)
			(layer "F.Fab")
		)
		(fp_line
			(start -0.299974 0.150114)
			(end -0.299974 -0.150114)
			(stroke
				(width 0.1)
				(type default)
			)
			(layer "F.Fab")
		)
		(pad "1" smd rect
			(at -0.2667 0 90)
			(size 0.3048 0.381)
			(layers "F.Cu" "F.Mask" "F.Paste")
			(net "P5E_CPU1_PE1_TX_C_DP<10>")
		)
		(pad "2" smd rect
			(at 0.2667 0 90)
			(size 0.3048 0.381)
			(layers "F.Cu" "F.Mask" "F.Paste")
			(net "P5E_CPU1_PE1_TX_DP<10>")
		)
	)
	(footprint ""
		(layer "F.Cu")
		(at 80.77073 -59.372246 -90)
		(property "Reference" "PR3795"
			(at 0 0 270)
			(layer "F.SilkS")
			(hide yes)
			(effects
				(font
					(size 1.27 1.27)
				)
			)
		)
		(property "Value" ""
			(at 0 0 270)
			(layer "F.Fab")
			(effects
				(font
					(size 1.27 1.27)
				)
			)
		)
		(duplicate_pad_numbers_are_jumpers no)
		(fp_line
			(start -0.7874 0.4064)
			(end -0.7874 -0.4064)
			(stroke
				(width 0.1524)
				(type default)
			)
			(layer "F.SilkS")
		)
		(fp_line
			(start 0.7874 0.4064)
			(end -0.7874 0.4064)
			(stroke
				(width 0.1524)
				(type default)
			)
			(layer "F.SilkS")
		)
		(fp_line
			(start -0.7874 -0.4064)
			(end 0.7874 -0.4064)
			(stroke
				(width 0.1524)
				(type default)
			)
			(layer "F.SilkS")
		)
		(fp_line
			(start 0.7874 -0.4064)
			(end 0.7874 0.4064)
			(stroke
				(width 0.1524)
				(type default)
			)
			(layer "F.SilkS")
		)
		(fp_line
			(start -0.67945 0.3048)
			(end -0.67945 -0.305054)
			(stroke
				(width 0.1)
				(type default)
			)
			(layer "F.Fab")
		)
		(fp_line
			(start -0.12065 0.3048)
			(end -0.67945 0.3048)
			(stroke
				(width 0.1)
				(type default)
			)
			(layer "F.Fab")
		)
		(fp_line
			(start 0.120396 0.3048)
			(end 0.120396 0.2794)
			(stroke
				(width 0.1)
				(type default)
			)
			(layer "F.Fab")
		)
		(fp_line
			(start 0.67945 0.3048)
			(end 0.120396 0.3048)
			(stroke
				(width 0.1)
				(type default)
			)
			(layer "F.Fab")
		)
		(fp_line
			(start -0.12065 0.2794)
			(end -0.12065 0.3048)
			(stroke
				(width 0.1)
				(type default)
			)
			(layer "F.Fab")
		)
		(fp_line
			(start 0.120396 0.2794)
			(end -0.12065 0.2794)
			(stroke
				(width 0.1)
				(type default)
			)
			(layer "F.Fab")
		)
		(fp_line
			(start -0.12065 -0.2794)
			(end 0.12065 -0.2794)
			(stroke
				(width 0.1)
				(type default)
			)
			(layer "F.Fab")
		)
		(fp_line
			(start 0.12065 -0.2794)
			(end 0.12065 -0.3048)
			(stroke
				(width 0.1)
				(type default)
			)
			(layer "F.Fab")
		)
		(fp_line
			(start 0.12065 -0.3048)
			(end 0.67945 -0.3048)
			(stroke
				(width 0.1)
				(type default)
			)
			(layer "F.Fab")
		)
		(fp_line
			(start 0.67945 -0.3048)
			(end 0.67945 0.3048)
			(stroke
				(width 0.1)
				(type default)
			)
			(layer "F.Fab")
		)
		(fp_line
			(start -0.67945 -0.305054)
			(end -0.12065 -0.305054)
			(stroke
				(width 0.1)
				(type default)
			)
			(layer "F.Fab")
		)
		(fp_line
			(start -0.12065 -0.305054)
			(end -0.12065 -0.2794)
			(stroke
				(width 0.1)
				(type default)
			)
			(layer "F.Fab")
		)
		(pad "1" smd circle
			(at -0.40005 0 270)
			(size 0 0)
			(layers "F.Cu" "F.Mask" "F.Paste")
			(net "P3V3_AUX")
		)
		(pad "2" smd circle
			(at 0.40005 0 270)
			(size 0 0)
			(layers "F.Cu" "F.Mask" "F.Paste")
			(net "P3V3_OCP_UV_2")
		)
	)
	(footprint ""
		(layer "F.Cu")
		(at 193.60388 -108.765848)
		(property "Reference" "R1558"
			(at 0 0 0)
			(layer "F.SilkS")
			(hide yes)
			(effects
				(font
					(size 1.27 1.27)
				)
			)
		)
		(property "Value" ""
			(at 0 0 0)
			(layer "F.Fab")
			(effects
				(font
					(size 1.27 1.27)
				)
			)
		)
		(duplicate_pad_numbers_are_jumpers no)
		(fp_line
			(start -0.7874 -0.4064)
			(end 0.7874 -0.4064)
			(stroke
				(width 0.1524)
				(type default)
			)
			(layer "F.SilkS")
		)
		(fp_line
			(start -0.7874 0.4064)
			(end -0.7874 -0.4064)
			(stroke
				(width 0.1524)
				(type default)
			)
			(layer "F.SilkS")
		)
		(fp_line
			(start 0.7874 -0.4064)
			(end 0.7874 0.4064)
			(stroke
				(width 0.1524)
				(type default)
			)
			(layer "F.SilkS")
		)
		(fp_line
			(start 0.7874 0.4064)
			(end -0.7874 0.4064)
			(stroke
				(width 0.1524)
				(type default)
			)
			(layer "F.SilkS")
		)
		(fp_line
			(start -0.67945 -0.305054)
			(end -0.12065 -0.305054)
			(stroke
				(width 0.1)
				(type default)
			)
			(layer "F.Fab")
		)
		(fp_line
			(start -0.67945 0.3048)
			(end -0.67945 -0.305054)
			(stroke
				(width 0.1)
				(type default)
			)
			(layer "F.Fab")
		)
		(fp_line
			(start -0.12065 -0.305054)
			(end -0.12065 -0.2794)
			(stroke
				(width 0.1)
				(type default)
			)
			(layer "F.Fab")
		)
		(fp_line
			(start -0.12065 -0.2794)
			(end 0.12065 -0.2794)
			(stroke
				(width 0.1)
				(type default)
			)
			(layer "F.Fab")
		)
		(fp_line
			(start -0.12065 0.2794)
			(end -0.12065 0.3048)
			(stroke
				(width 0.1)
				(type default)
			)
			(layer "F.Fab")
		)
		(fp_line
			(start -0.12065 0.3048)
			(end -0.67945 0.3048)
			(stroke
				(width 0.1)
				(type default)
			)
			(layer "F.Fab")
		)
		(fp_line
			(start 0.120396 0.2794)
			(end -0.12065 0.2794)
			(stroke
				(width 0.1)
				(type default)
			)
			(layer "F.Fab")
		)
		(fp_line
			(start 0.120396 0.3048)
			(end 0.120396 0.2794)
			(stroke
				(width 0.1)
				(type default)
			)
			(layer "F.Fab")
		)
		(fp_line
			(start 0.12065 -0.3048)
			(end 0.67945 -0.3048)
			(stroke
				(width 0.1)
				(type default)
			)
			(layer "F.Fab")
		)
		(fp_line
			(start 0.12065 -0.2794)
			(end 0.12065 -0.3048)
			(stroke
				(width 0.1)
				(type default)
			)
			(layer "F.Fab")
		)
		(fp_line
			(start 0.67945 -0.3048)
			(end 0.67945 0.3048)
			(stroke
				(width 0.1)
				(type default)
			)
			(layer "F.Fab")
		)
		(fp_line
			(start 0.67945 0.3048)
			(end 0.120396 0.3048)
			(stroke
				(width 0.1)
				(type default)
			)
			(layer "F.Fab")
		)
		(pad "1" smd circle
			(at -0.40005 0)
			(size 0 0)
			(layers "F.Cu" "F.Mask" "F.Paste")
			(net "FM_CPU_RMCA_CATERR_LVT3_R_N")
		)
		(pad "2" smd circle
			(at 0.40005 0)
			(size 0 0)
			(layers "F.Cu" "F.Mask" "F.Paste")
			(net "P3V3_AUX")
		)
	)
	(footprint ""
		(layer "F.Cu")
		(at 205.6892 -92.6338 -90)
		(property "Reference" "R4775"
			(at 0 0 270)
			(layer "F.SilkS")
			(hide yes)
			(effects
				(font
					(size 1.27 1.27)
				)
			)
		)
		(property "Value" ""
			(at 0 0 270)
			(layer "F.Fab")
			(effects
				(font
					(size 1.27 1.27)
				)
			)
		)
		(duplicate_pad_numbers_are_jumpers no)
		(fp_line
			(start -0.7874 0.4064)
			(end -0.7874 -0.4064)
			(stroke
				(width 0.1524)
				(type default)
			)
			(layer "F.SilkS")
		)
		(fp_line
			(start 0.7874 0.4064)
			(end -0.7874 0.4064)
			(stroke
				(width 0.1524)
				(type default)
			)
			(layer "F.SilkS")
		)
		(fp_line
			(start -0.7874 -0.4064)
			(end 0.7874 -0.4064)
			(stroke
				(width 0.1524)
				(type default)
			)
			(layer "F.SilkS")
		)
		(fp_line
			(start 0.7874 -0.4064)
			(end 0.7874 0.4064)
			(stroke
				(width 0.1524)
				(type default)
			)
			(layer "F.SilkS")
		)
		(fp_line
			(start -0.67945 0.3048)
			(end -0.67945 -0.305054)
			(stroke
				(width 0.1)
				(type default)
			)
			(layer "F.Fab")
		)
		(fp_line
			(start -0.12065 0.3048)
			(end -0.67945 0.3048)
			(stroke
				(width 0.1)
				(type default)
			)
			(layer "F.Fab")
		)
		(fp_line
			(start 0.120396 0.3048)
			(end 0.120396 0.2794)
			(stroke
				(width 0.1)
				(type default)
			)
			(layer "F.Fab")
		)
		(fp_line
			(start 0.67945 0.3048)
			(end 0.120396 0.3048)
			(stroke
				(width 0.1)
				(type default)
			)
			(layer "F.Fab")
		)
		(fp_line
			(start -0.12065 0.2794)
			(end -0.12065 0.3048)
			(stroke
				(width 0.1)
				(type default)
			)
			(layer "F.Fab")
		)
		(fp_line
			(start 0.120396 0.2794)
			(end -0.12065 0.2794)
			(stroke
				(width 0.1)
				(type default)
			)
			(layer "F.Fab")
		)
		(fp_line
			(start -0.12065 -0.2794)
			(end 0.12065 -0.2794)
			(stroke
				(width 0.1)
				(type default)
			)
			(layer "F.Fab")
		)
		(fp_line
			(start 0.12065 -0.2794)
			(end 0.12065 -0.3048)
			(stroke
				(width 0.1)
				(type default)
			)
			(layer "F.Fab")
		)
		(fp_line
			(start 0.12065 -0.3048)
			(end 0.67945 -0.3048)
			(stroke
				(width 0.1)
				(type default)
			)
			(layer "F.Fab")
		)
		(fp_line
			(start 0.67945 -0.3048)
			(end 0.67945 0.3048)
			(stroke
				(width 0.1)
				(type default)
			)
			(layer "F.Fab")
		)
		(fp_line
			(start -0.67945 -0.305054)
			(end -0.12065 -0.305054)
			(stroke
				(width 0.1)
				(type default)
			)
			(layer "F.Fab")
		)
		(fp_line
			(start -0.12065 -0.305054)
			(end -0.12065 -0.2794)
			(stroke
				(width 0.1)
				(type default)
			)
			(layer "F.Fab")
		)
		(pad "1" smd circle
			(at -0.40005 0 270)
			(size 0 0)
			(layers "F.Cu" "F.Mask" "F.Paste")
			(net "P12V_AUX_UV_ADR_TRIGGER")
		)
		(pad "2" smd circle
			(at 0.40005 0 270)
			(size 0 0)
			(layers "F.Cu" "F.Mask" "F.Paste")
			(net "GND")
		)
	)
	(footprint ""
		(layer "F.Cu")
		(at 21.920708 -162.20567 90)
		(property "Reference" "PR216"
			(at 0 0 90)
			(layer "F.SilkS")
			(hide yes)
			(effects
				(font
					(size 1.27 1.27)
				)
			)
		)
		(property "Value" ""
			(at 0 0 90)
			(layer "F.Fab")
			(effects
				(font
					(size 1.27 1.27)
				)
			)
		)
		(duplicate_pad_numbers_are_jumpers no)
		(fp_line
			(start 0.7874 -0.4064)
			(end 0.7874 0.4064)
			(stroke
				(width 0.1524)
				(type default)
			)
			(layer "F.SilkS")
		)
		(fp_line
			(start -0.7874 -0.4064)
			(end 0.7874 -0.4064)
			(stroke
				(width 0.1524)
				(type default)
			)
			(layer "F.SilkS")
		)
		(fp_line
			(start 0.7874 0.4064)
			(end -0.7874 0.4064)
			(stroke
				(width 0.1524)
				(type default)
			)
			(layer "F.SilkS")
		)
		(fp_line
			(start -0.7874 0.4064)
			(end -0.7874 -0.4064)
			(stroke
				(width 0.1524)
				(type default)
			)
			(layer "F.SilkS")
		)
		(fp_line
			(start -0.12065 -0.305054)
			(end -0.12065 -0.2794)
			(stroke
				(width 0.1)
				(type default)
			)
			(layer "F.Fab")
		)
		(fp_line
			(start -0.67945 -0.305054)
			(end -0.12065 -0.305054)
			(stroke
				(width 0.1)
				(type default)
			)
			(layer "F.Fab")
		)
		(fp_line
			(start 0.67945 -0.3048)
			(end 0.67945 0.3048)
			(stroke
				(width 0.1)
				(type default)
			)
			(layer "F.Fab")
		)
		(fp_line
			(start 0.12065 -0.3048)
			(end 0.67945 -0.3048)
			(stroke
				(width 0.1)
				(type default)
			)
			(layer "F.Fab")
		)
		(fp_line
			(start 0.12065 -0.2794)
			(end 0.12065 -0.3048)
			(stroke
				(width 0.1)
				(type default)
			)
			(layer "F.Fab")
		)
		(fp_line
			(start -0.12065 -0.2794)
			(end 0.12065 -0.2794)
			(stroke
				(width 0.1)
				(type default)
			)
			(layer "F.Fab")
		)
		(fp_line
			(start 0.120396 0.2794)
			(end -0.12065 0.2794)
			(stroke
				(width 0.1)
				(type default)
			)
			(layer "F.Fab")
		)
		(fp_line
			(start -0.12065 0.2794)
			(end -0.12065 0.3048)
			(stroke
				(width 0.1)
				(type default)
			)
			(layer "F.Fab")
		)
		(fp_line
			(start 0.67945 0.3048)
			(end 0.120396 0.3048)
			(stroke
				(width 0.1)
				(type default)
			)
			(layer "F.Fab")
		)
		(fp_line
			(start 0.120396 0.3048)
			(end 0.120396 0.2794)
			(stroke
				(width 0.1)
				(type default)
			)
			(layer "F.Fab")
		)
		(fp_line
			(start -0.12065 0.3048)
			(end -0.67945 0.3048)
			(stroke
				(width 0.1)
				(type default)
			)
			(layer "F.Fab")
		)
		(fp_line
			(start -0.67945 0.3048)
			(end -0.67945 -0.305054)
			(stroke
				(width 0.1)
				(type default)
			)
			(layer "F.Fab")
		)
		(pad "1" smd circle
			(at -0.40005 0 90)
			(size 0 0)
			(layers "F.Cu" "F.Mask" "F.Paste")
			(net "SH_PVCCD_HV_CPU1")
		)
		(pad "2" smd circle
			(at 0.40005 0 90)
			(size 0 0)
			(layers "F.Cu" "F.Mask" "F.Paste")
			(net "SH_PVCCD_HV_CPU1_R")
		)
	)
	(footprint ""
		(layer "F.Cu")
		(at 172.77588 -130.266948 -90)
		(property "Reference" "R1446"
			(at 0 0 270)
			(layer "F.SilkS")
			(hide yes)
			(effects
				(font
					(size 1.27 1.27)
				)
			)
		)
		(property "Value" ""
			(at 0 0 270)
			(layer "F.Fab")
			(effects
				(font
					(size 1.27 1.27)
				)
			)
		)
		(duplicate_pad_numbers_are_jumpers no)
		(fp_line
			(start -0.7874 0.4064)
			(end -0.7874 -0.4064)
			(stroke
				(width 0.1524)
				(type default)
			)
			(layer "F.SilkS")
		)
		(fp_line
			(start 0.7874 0.4064)
			(end -0.7874 0.4064)
			(stroke
				(width 0.1524)
				(type default)
			)
			(layer "F.SilkS")
		)
		(fp_line
			(start -0.7874 -0.4064)
			(end 0.7874 -0.4064)
			(stroke
				(width 0.1524)
				(type default)
			)
			(layer "F.SilkS")
		)
		(fp_line
			(start 0.7874 -0.4064)
			(end 0.7874 0.4064)
			(stroke
				(width 0.1524)
				(type default)
			)
			(layer "F.SilkS")
		)
		(fp_line
			(start -0.67945 0.3048)
			(end -0.67945 -0.305054)
			(stroke
				(width 0.1)
				(type default)
			)
			(layer "F.Fab")
		)
		(fp_line
			(start -0.12065 0.3048)
			(end -0.67945 0.3048)
			(stroke
				(width 0.1)
				(type default)
			)
			(layer "F.Fab")
		)
		(fp_line
			(start 0.120396 0.3048)
			(end 0.120396 0.2794)
			(stroke
				(width 0.1)
				(type default)
			)
			(layer "F.Fab")
		)
		(fp_line
			(start 0.67945 0.3048)
			(end 0.120396 0.3048)
			(stroke
				(width 0.1)
				(type default)
			)
			(layer "F.Fab")
		)
		(fp_line
			(start -0.12065 0.2794)
			(end -0.12065 0.3048)
			(stroke
				(width 0.1)
				(type default)
			)
			(layer "F.Fab")
		)
		(fp_line
			(start 0.120396 0.2794)
			(end -0.12065 0.2794)
			(stroke
				(width 0.1)
				(type default)
			)
			(layer "F.Fab")
		)
		(fp_line
			(start -0.12065 -0.2794)
			(end 0.12065 -0.2794)
			(stroke
				(width 0.1)
				(type default)
			)
			(layer "F.Fab")
		)
		(fp_line
			(start 0.12065 -0.2794)
			(end 0.12065 -0.3048)
			(stroke
				(width 0.1)
				(type default)
			)
			(layer "F.Fab")
		)
		(fp_line
			(start 0.12065 -0.3048)
			(end 0.67945 -0.3048)
			(stroke
				(width 0.1)
				(type default)
			)
			(layer "F.Fab")
		)
		(fp_line
			(start 0.67945 -0.3048)
			(end 0.67945 0.3048)
			(stroke
				(width 0.1)
				(type default)
			)
			(layer "F.Fab")
		)
		(fp_line
			(start -0.67945 -0.305054)
			(end -0.12065 -0.305054)
			(stroke
				(width 0.1)
				(type default)
			)
			(layer "F.Fab")
		)
		(fp_line
			(start -0.12065 -0.305054)
			(end -0.12065 -0.2794)
			(stroke
				(width 0.1)
				(type default)
			)
			(layer "F.Fab")
		)
		(pad "1" smd circle
			(at -0.40005 0 270)
			(size 0 0)
			(layers "F.Cu" "F.Mask" "F.Paste")
			(net "PWRGD_PS_PWROK_PLD_ISO")
		)
		(pad "2" smd circle
			(at 0.40005 0 270)
			(size 0 0)
			(layers "F.Cu" "F.Mask" "F.Paste")
			(net "PWRGD_PS_PWROK_PLD_ISO_R")
		)
	)
	(footprint ""
		(layer "F.Cu")
		(at 86.68893 -74.730356 -90)
		(property "Reference" "R3100"
			(at 0 0 270)
			(layer "F.SilkS")
			(hide yes)
			(effects
				(font
					(size 1.27 1.27)
				)
			)
		)
		(property "Value" ""
			(at 0 0 270)
			(layer "F.Fab")
			(effects
				(font
					(size 1.27 1.27)
				)
			)
		)
		(duplicate_pad_numbers_are_jumpers no)
		(fp_line
			(start -0.7874 0.4064)
			(end -0.7874 -0.4064)
			(stroke
				(width 0.1524)
				(type default)
			)
			(layer "F.SilkS")
		)
		(fp_line
			(start 0.7874 0.4064)
			(end -0.7874 0.4064)
			(stroke
				(width 0.1524)
				(type default)
			)
			(layer "F.SilkS")
		)
		(fp_line
			(start -0.7874 -0.4064)
			(end 0.7874 -0.4064)
			(stroke
				(width 0.1524)
				(type default)
			)
			(layer "F.SilkS")
		)
		(fp_line
			(start 0.7874 -0.4064)
			(end 0.7874 0.4064)
			(stroke
				(width 0.1524)
				(type default)
			)
			(layer "F.SilkS")
		)
		(fp_line
			(start -0.67945 0.3048)
			(end -0.67945 -0.305054)
			(stroke
				(width 0.1)
				(type default)
			)
			(layer "F.Fab")
		)
		(fp_line
			(start -0.12065 0.3048)
			(end -0.67945 0.3048)
			(stroke
				(width 0.1)
				(type default)
			)
			(layer "F.Fab")
		)
		(fp_line
			(start 0.120396 0.3048)
			(end 0.120396 0.2794)
			(stroke
				(width 0.1)
				(type default)
			)
			(layer "F.Fab")
		)
		(fp_line
			(start 0.67945 0.3048)
			(end 0.120396 0.3048)
			(stroke
				(width 0.1)
				(type default)
			)
			(layer "F.Fab")
		)
		(fp_line
			(start -0.12065 0.2794)
			(end -0.12065 0.3048)
			(stroke
				(width 0.1)
				(type default)
			)
			(layer "F.Fab")
		)
		(fp_line
			(start 0.120396 0.2794)
			(end -0.12065 0.2794)
			(stroke
				(width 0.1)
				(type default)
			)
			(layer "F.Fab")
		)
		(fp_line
			(start -0.12065 -0.2794)
			(end 0.12065 -0.2794)
			(stroke
				(width 0.1)
				(type default)
			)
			(layer "F.Fab")
		)
		(fp_line
			(start 0.12065 -0.2794)
			(end 0.12065 -0.3048)
			(stroke
				(width 0.1)
				(type default)
			)
			(layer "F.Fab")
		)
		(fp_line
			(start 0.12065 -0.3048)
			(end 0.67945 -0.3048)
			(stroke
				(width 0.1)
				(type default)
			)
			(layer "F.Fab")
		)
		(fp_line
			(start 0.67945 -0.3048)
			(end 0.67945 0.3048)
			(stroke
				(width 0.1)
				(type default)
			)
			(layer "F.Fab")
		)
		(fp_line
			(start -0.67945 -0.305054)
			(end -0.12065 -0.305054)
			(stroke
				(width 0.1)
				(type default)
			)
			(layer "F.Fab")
		)
		(fp_line
			(start -0.12065 -0.305054)
			(end -0.12065 -0.2794)
			(stroke
				(width 0.1)
				(type default)
			)
			(layer "F.Fab")
		)
		(pad "1" smd circle
			(at -0.40005 0 270)
			(size 0 0)
			(layers "F.Cu" "F.Mask" "F.Paste")
			(net "LED_P3V3")
		)
		(pad "2" smd circle
			(at 0.40005 0 270)
			(size 0 0)
			(layers "F.Cu" "F.Mask" "F.Paste")
			(net "P3V3")
		)
	)
	(footprint ""
		(layer "F.Cu")
		(at 96.959674 -324.445376)
		(property "Reference" "PL31"
			(at -5.761228 7.068566 90)
			(unlocked yes)
			(layer "F.SilkS")
			(effects
				(font
					(size 0.7874 0.5842)
					(thickness 0.1524)
				)
				(justify left)
			)
		)
		(property "Value" ""
			(at 0 0 0)
			(layer "F.Fab")
			(effects
				(font
					(size 1.27 1.27)
				)
			)
		)
		(duplicate_pad_numbers_are_jumpers no)
		(fp_line
			(start -3.750056 -5.500116)
			(end -2.393442 -5.500116)
			(stroke
				(width 0.1524)
				(type default)
			)
			(layer "F.SilkS")
		)
		(fp_line
			(start -3.750056 5.500116)
			(end -3.750056 -5.500116)
			(stroke
				(width 0.1524)
				(type default)
			)
			(layer "F.SilkS")
		)
		(fp_line
			(start -2.393442 5.500116)
			(end -3.750056 5.500116)
			(stroke
				(width 0.1524)
				(type default)
			)
			(layer "F.SilkS")
		)
		(fp_line
			(start 2.393442 5.500116)
			(end 3.750056 5.500116)
			(stroke
				(width 0.1524)
				(type default)
			)
			(layer "F.SilkS")
		)
		(fp_line
			(start 3.750056 -5.500116)
			(end 2.393442 -5.500116)
			(stroke
				(width 0.1524)
				(type default)
			)
			(layer "F.SilkS")
		)
		(fp_line
			(start 3.750056 5.500116)
			(end 3.750056 -5.500116)
			(stroke
				(width 0.1524)
				(type default)
			)
			(layer "F.SilkS")
		)
		(fp_poly
			(pts
				(xy -3.34391 -6.96722) (xy -2.984754 -5.889498) (xy -4.062222 -6.248654)
			)
			(stroke
				(width 0)
				(type default)
			)
			(fill yes)
			(layer "F.SilkS")
		)
		(fp_line
			(start -3.750056 -5.500116)
			(end -3.750056 5.500116)
			(stroke
				(width 0.1)
				(type default)
			)
			(layer "F.Fab")
		)
		(fp_line
			(start -3.750056 5.500116)
			(end 3.750056 5.500116)
			(stroke
				(width 0.1)
				(type default)
			)
			(layer "F.Fab")
		)
		(fp_line
			(start 3.750056 -5.500116)
			(end -3.750056 -5.500116)
			(stroke
				(width 0.1)
				(type default)
			)
			(layer "F.Fab")
		)
		(fp_line
			(start 3.750056 5.500116)
			(end 3.750056 -5.500116)
			(stroke
				(width 0.1)
				(type default)
			)
			(layer "F.Fab")
		)
		(fp_poly
			(pts
				(xy -4.9276 -4.757928) (xy -4.9276 -3.741928) (xy -3.9116 -4.249928)
			)
			(stroke
				(width 0)
				(type default)
			)
			(fill yes)
			(layer "F.Fab")
		)
		(pad "1" smd rect
			(at 0 -4.249928 270)
			(size 2.413 4.5212)
			(layers "F.Cu" "F.Mask" "F.Paste")
			(net "SW_PVCCIN_CPU1_SW1")
		)
		(pad "2" smd rect
			(at 0 -1.175004 270)
			(size 1.3716 4.5212)
			(layers "F.Cu" "F.Mask" "F.Paste")
			(net "IND_P1_CPL1")
		)
		(pad "3" smd rect
			(at 0 1.175004 270)
			(size 1.3716 4.5212)
			(layers "F.Cu" "F.Mask" "F.Paste")
			(net "IND_P1_CPL6")
		)
		(pad "4" smd rect
			(at 0 4.249928 270)
			(size 2.413 4.5212)
			(layers "F.Cu" "F.Mask" "F.Paste")
			(net "PVCCIN_CPU1")
		)
	)
	(footprint ""
		(layer "F.Cu")
		(at 95.94088 -32.626808)
		(property "Reference" "R3229"
			(at 0 0 0)
			(layer "F.SilkS")
			(hide yes)
			(effects
				(font
					(size 1.27 1.27)
				)
			)
		)
		(property "Value" ""
			(at 0 0 0)
			(layer "F.Fab")
			(effects
				(font
					(size 1.27 1.27)
				)
			)
		)
		(duplicate_pad_numbers_are_jumpers no)
		(fp_line
			(start -0.7874 -0.4064)
			(end 0.7874 -0.4064)
			(stroke
				(width 0.1524)
				(type default)
			)
			(layer "F.SilkS")
		)
		(fp_line
			(start -0.7874 0.4064)
			(end -0.7874 -0.4064)
			(stroke
				(width 0.1524)
				(type default)
			)
			(layer "F.SilkS")
		)
		(fp_line
			(start 0.7874 -0.4064)
			(end 0.7874 0.4064)
			(stroke
				(width 0.1524)
				(type default)
			)
			(layer "F.SilkS")
		)
		(fp_line
			(start 0.7874 0.4064)
			(end -0.7874 0.4064)
			(stroke
				(width 0.1524)
				(type default)
			)
			(layer "F.SilkS")
		)
		(fp_line
			(start -0.67945 -0.305054)
			(end -0.12065 -0.305054)
			(stroke
				(width 0.1)
				(type default)
			)
			(layer "F.Fab")
		)
		(fp_line
			(start -0.67945 0.3048)
			(end -0.67945 -0.305054)
			(stroke
				(width 0.1)
				(type default)
			)
			(layer "F.Fab")
		)
		(fp_line
			(start -0.12065 -0.305054)
			(end -0.12065 -0.2794)
			(stroke
				(width 0.1)
				(type default)
			)
			(layer "F.Fab")
		)
		(fp_line
			(start -0.12065 -0.2794)
			(end 0.12065 -0.2794)
			(stroke
				(width 0.1)
				(type default)
			)
			(layer "F.Fab")
		)
		(fp_line
			(start -0.12065 0.2794)
			(end -0.12065 0.3048)
			(stroke
				(width 0.1)
				(type default)
			)
			(layer "F.Fab")
		)
		(fp_line
			(start -0.12065 0.3048)
			(end -0.67945 0.3048)
			(stroke
				(width 0.1)
				(type default)
			)
			(layer "F.Fab")
		)
		(fp_line
			(start 0.120396 0.2794)
			(end -0.12065 0.2794)
			(stroke
				(width 0.1)
				(type default)
			)
			(layer "F.Fab")
		)
		(fp_line
			(start 0.120396 0.3048)
			(end 0.120396 0.2794)
			(stroke
				(width 0.1)
				(type default)
			)
			(layer "F.Fab")
		)
		(fp_line
			(start 0.12065 -0.3048)
			(end 0.67945 -0.3048)
			(stroke
				(width 0.1)
				(type default)
			)
			(layer "F.Fab")
		)
		(fp_line
			(start 0.12065 -0.2794)
			(end 0.12065 -0.3048)
			(stroke
				(width 0.1)
				(type default)
			)
			(layer "F.Fab")
		)
		(fp_line
			(start 0.67945 -0.3048)
			(end 0.67945 0.3048)
			(stroke
				(width 0.1)
				(type default)
			)
			(layer "F.Fab")
		)
		(fp_line
			(start 0.67945 0.3048)
			(end 0.120396 0.3048)
			(stroke
				(width 0.1)
				(type default)
			)
			(layer "F.Fab")
		)
		(pad "1" smd circle
			(at -0.40005 0)
			(size 0 0)
			(layers "F.Cu" "F.Mask" "F.Paste")
			(net "SMB_OCP_V3_2_3V3AUX_BUF_R_SDA")
		)
		(pad "2" smd circle
			(at 0.40005 0)
			(size 0 0)
			(layers "F.Cu" "F.Mask" "F.Paste")
			(net "SMB_OCP_V3_2_3V3AUX_BUF_SDA")
		)
	)
	(footprint ""
		(layer "F.Cu")
		(at 368.915188 -360.043222 90)
		(property "Reference" "PC2001"
			(at 0 0 90)
			(layer "F.SilkS")
			(hide yes)
			(effects
				(font
					(size 1.27 1.27)
				)
			)
		)
		(property "Value" ""
			(at 0 0 90)
			(layer "F.Fab")
			(effects
				(font
					(size 1.27 1.27)
				)
			)
		)
		(duplicate_pad_numbers_are_jumpers no)
		(fp_line
			(start 0.7874 -0.4064)
			(end 0.7874 0.4064)
			(stroke
				(width 0.1524)
				(type default)
			)
			(layer "F.SilkS")
		)
		(fp_line
			(start -0.7874 -0.4064)
			(end 0.7874 -0.4064)
			(stroke
				(width 0.1524)
				(type default)
			)
			(layer "F.SilkS")
		)
		(fp_line
			(start 0.7874 0.4064)
			(end -0.7874 0.4064)
			(stroke
				(width 0.1524)
				(type default)
			)
			(layer "F.SilkS")
		)
		(fp_line
			(start -0.7874 0.4064)
			(end -0.7874 -0.4064)
			(stroke
				(width 0.1524)
				(type default)
			)
			(layer "F.SilkS")
		)
		(fp_line
			(start -0.12065 -0.305054)
			(end -0.12065 -0.2794)
			(stroke
				(width 0.1)
				(type default)
			)
			(layer "F.Fab")
		)
		(fp_line
			(start -0.67945 -0.305054)
			(end -0.12065 -0.305054)
			(stroke
				(width 0.1)
				(type default)
			)
			(layer "F.Fab")
		)
		(fp_line
			(start 0.67945 -0.3048)
			(end 0.67945 0.3048)
			(stroke
				(width 0.1)
				(type default)
			)
			(layer "F.Fab")
		)
		(fp_line
			(start 0.12065 -0.3048)
			(end 0.67945 -0.3048)
			(stroke
				(width 0.1)
				(type default)
			)
			(layer "F.Fab")
		)
		(fp_line
			(start 0.12065 -0.2794)
			(end 0.12065 -0.3048)
			(stroke
				(width 0.1)
				(type default)
			)
			(layer "F.Fab")
		)
		(fp_line
			(start -0.12065 -0.2794)
			(end 0.12065 -0.2794)
			(stroke
				(width 0.1)
				(type default)
			)
			(layer "F.Fab")
		)
		(fp_line
			(start 0.120396 0.2794)
			(end -0.12065 0.2794)
			(stroke
				(width 0.1)
				(type default)
			)
			(layer "F.Fab")
		)
		(fp_line
			(start -0.12065 0.2794)
			(end -0.12065 0.3048)
			(stroke
				(width 0.1)
				(type default)
			)
			(layer "F.Fab")
		)
		(fp_line
			(start 0.67945 0.3048)
			(end 0.120396 0.3048)
			(stroke
				(width 0.1)
				(type default)
			)
			(layer "F.Fab")
		)
		(fp_line
			(start 0.120396 0.3048)
			(end 0.120396 0.2794)
			(stroke
				(width 0.1)
				(type default)
			)
			(layer "F.Fab")
		)
		(fp_line
			(start -0.12065 0.3048)
			(end -0.67945 0.3048)
			(stroke
				(width 0.1)
				(type default)
			)
			(layer "F.Fab")
		)
		(fp_line
			(start -0.67945 0.3048)
			(end -0.67945 -0.305054)
			(stroke
				(width 0.1)
				(type default)
			)
			(layer "F.Fab")
		)
		(pad "1" smd circle
			(at -0.40005 0 90)
			(size 0 0)
			(layers "F.Cu" "F.Mask" "F.Paste")
			(net "PVPP_HBM_CPU0_REF")
		)
		(pad "2" smd circle
			(at 0.40005 0 90)
			(size 0 0)
			(layers "F.Cu" "F.Mask" "F.Paste")
			(net "GND")
		)
	)
	(footprint ""
		(layer "F.Cu")
		(at 432.265836 -17.612614 90)
		(property "Reference" "C869"
			(at 0 0 90)
			(layer "F.SilkS")
			(hide yes)
			(effects
				(font
					(size 1.27 1.27)
				)
			)
		)
		(property "Value" ""
			(at 0 0 90)
			(layer "F.Fab")
			(effects
				(font
					(size 1.27 1.27)
				)
			)
		)
		(duplicate_pad_numbers_are_jumpers no)
		(fp_line
			(start 0.299974 -0.150114)
			(end 0.299974 0.150114)
			(stroke
				(width 0.1)
				(type default)
			)
			(layer "F.Fab")
		)
		(fp_line
			(start -0.299974 -0.150114)
			(end 0.299974 -0.150114)
			(stroke
				(width 0.1)
				(type default)
			)
			(layer "F.Fab")
		)
		(fp_line
			(start 0.299974 0.150114)
			(end -0.299974 0.150114)
			(stroke
				(width 0.1)
				(type default)
			)
			(layer "F.Fab")
		)
		(fp_line
			(start -0.299974 0.150114)
			(end -0.299974 -0.150114)
			(stroke
				(width 0.1)
				(type default)
			)
			(layer "F.Fab")
		)
		(pad "1" smd rect
			(at -0.2667 0 90)
			(size 0.3048 0.381)
			(layers "F.Cu" "F.Mask" "F.Paste")
			(net "P5E_CPU0_PE1_TX_C_DP<0>")
		)
		(pad "2" smd rect
			(at 0.2667 0 90)
			(size 0.3048 0.381)
			(layers "F.Cu" "F.Mask" "F.Paste")
			(net "P5E_CPU0_PE1_TX_DP<0>")
		)
	)
	(footprint ""
		(layer "F.Cu")
		(at 366.48263 -241.976656 -90)
		(property "Reference" "C1033"
			(at 0 0 270)
			(layer "F.SilkS")
			(hide yes)
			(effects
				(font
					(size 1.27 1.27)
				)
			)
		)
		(property "Value" ""
			(at 0 0 270)
			(layer "F.Fab")
			(effects
				(font
					(size 1.27 1.27)
				)
			)
		)
		(duplicate_pad_numbers_are_jumpers no)
		(fp_line
			(start -0.7874 0.4064)
			(end -0.7874 -0.4064)
			(stroke
				(width 0.1524)
				(type default)
			)
			(layer "F.SilkS")
		)
		(fp_line
			(start 0.7874 0.4064)
			(end -0.7874 0.4064)
			(stroke
				(width 0.1524)
				(type default)
			)
			(layer "F.SilkS")
		)
		(fp_line
			(start -0.7874 -0.4064)
			(end 0.7874 -0.4064)
			(stroke
				(width 0.1524)
				(type default)
			)
			(layer "F.SilkS")
		)
		(fp_line
			(start 0.7874 -0.4064)
			(end 0.7874 0.4064)
			(stroke
				(width 0.1524)
				(type default)
			)
			(layer "F.SilkS")
		)
		(fp_line
			(start -0.67945 0.3048)
			(end -0.67945 -0.305054)
			(stroke
				(width 0.1)
				(type default)
			)
			(layer "F.Fab")
		)
		(fp_line
			(start -0.12065 0.3048)
			(end -0.67945 0.3048)
			(stroke
				(width 0.1)
				(type default)
			)
			(layer "F.Fab")
		)
		(fp_line
			(start 0.120396 0.3048)
			(end 0.120396 0.2794)
			(stroke
				(width 0.1)
				(type default)
			)
			(layer "F.Fab")
		)
		(fp_line
			(start 0.67945 0.3048)
			(end 0.120396 0.3048)
			(stroke
				(width 0.1)
				(type default)
			)
			(layer "F.Fab")
		)
		(fp_line
			(start -0.12065 0.2794)
			(end -0.12065 0.3048)
			(stroke
				(width 0.1)
				(type default)
			)
			(layer "F.Fab")
		)
		(fp_line
			(start 0.120396 0.2794)
			(end -0.12065 0.2794)
			(stroke
				(width 0.1)
				(type default)
			)
			(layer "F.Fab")
		)
		(fp_line
			(start -0.12065 -0.2794)
			(end 0.12065 -0.2794)
			(stroke
				(width 0.1)
				(type default)
			)
			(layer "F.Fab")
		)
		(fp_line
			(start 0.12065 -0.2794)
			(end 0.12065 -0.3048)
			(stroke
				(width 0.1)
				(type default)
			)
			(layer "F.Fab")
		)
		(fp_line
			(start 0.12065 -0.3048)
			(end 0.67945 -0.3048)
			(stroke
				(width 0.1)
				(type default)
			)
			(layer "F.Fab")
		)
		(fp_line
			(start 0.67945 -0.3048)
			(end 0.67945 0.3048)
			(stroke
				(width 0.1)
				(type default)
			)
			(layer "F.Fab")
		)
		(fp_line
			(start -0.67945 -0.305054)
			(end -0.12065 -0.305054)
			(stroke
				(width 0.1)
				(type default)
			)
			(layer "F.Fab")
		)
		(fp_line
			(start -0.12065 -0.305054)
			(end -0.12065 -0.2794)
			(stroke
				(width 0.1)
				(type default)
			)
			(layer "F.Fab")
		)
		(pad "1" smd circle
			(at -0.40005 0 270)
			(size 0 0)
			(layers "F.Cu" "F.Mask" "F.Paste")
			(net "PVCCIN_CPU0")
		)
		(pad "2" smd circle
			(at 0.40005 0 270)
			(size 0 0)
			(layers "F.Cu" "F.Mask" "F.Paste")
			(net "GND")
		)
	)
	(footprint ""
		(layer "F.Cu")
		(at 193.38036 -120.614948 180)
		(property "Reference" "R1313"
			(at 0 0 180)
			(layer "F.SilkS")
			(hide yes)
			(effects
				(font
					(size 1.27 1.27)
				)
			)
		)
		(property "Value" ""
			(at 0 0 180)
			(layer "F.Fab")
			(effects
				(font
					(size 1.27 1.27)
				)
			)
		)
		(duplicate_pad_numbers_are_jumpers no)
		(fp_line
			(start 0.7874 0.4064)
			(end -0.7874 0.4064)
			(stroke
				(width 0.1524)
				(type default)
			)
			(layer "F.SilkS")
		)
		(fp_line
			(start 0.7874 -0.4064)
			(end 0.7874 0.4064)
			(stroke
				(width 0.1524)
				(type default)
			)
			(layer "F.SilkS")
		)
		(fp_line
			(start -0.7874 0.4064)
			(end -0.7874 -0.4064)
			(stroke
				(width 0.1524)
				(type default)
			)
			(layer "F.SilkS")
		)
		(fp_line
			(start -0.7874 -0.4064)
			(end 0.7874 -0.4064)
			(stroke
				(width 0.1524)
				(type default)
			)
			(layer "F.SilkS")
		)
		(fp_line
			(start 0.67945 0.3048)
			(end 0.120396 0.3048)
			(stroke
				(width 0.1)
				(type default)
			)
			(layer "F.Fab")
		)
		(fp_line
			(start 0.67945 -0.3048)
			(end 0.67945 0.3048)
			(stroke
				(width 0.1)
				(type default)
			)
			(layer "F.Fab")
		)
		(fp_line
			(start 0.12065 -0.2794)
			(end 0.12065 -0.3048)
			(stroke
				(width 0.1)
				(type default)
			)
			(layer "F.Fab")
		)
		(fp_line
			(start 0.12065 -0.3048)
			(end 0.67945 -0.3048)
			(stroke
				(width 0.1)
				(type default)
			)
			(layer "F.Fab")
		)
		(fp_line
			(start 0.120396 0.3048)
			(end 0.120396 0.2794)
			(stroke
				(width 0.1)
				(type default)
			)
			(layer "F.Fab")
		)
		(fp_line
			(start 0.120396 0.2794)
			(end -0.12065 0.2794)
			(stroke
				(width 0.1)
				(type default)
			)
			(layer "F.Fab")
		)
		(fp_line
			(start -0.12065 0.3048)
			(end -0.67945 0.3048)
			(stroke
				(width 0.1)
				(type default)
			)
			(layer "F.Fab")
		)
		(fp_line
			(start -0.12065 0.2794)
			(end -0.12065 0.3048)
			(stroke
				(width 0.1)
				(type default)
			)
			(layer "F.Fab")
		)
		(fp_line
			(start -0.12065 -0.2794)
			(end 0.12065 -0.2794)
			(stroke
				(width 0.1)
				(type default)
			)
			(layer "F.Fab")
		)
		(fp_line
			(start -0.12065 -0.305054)
			(end -0.12065 -0.2794)
			(stroke
				(width 0.1)
				(type default)
			)
			(layer "F.Fab")
		)
		(fp_line
			(start -0.67945 0.3048)
			(end -0.67945 -0.305054)
			(stroke
				(width 0.1)
				(type default)
			)
			(layer "F.Fab")
		)
		(fp_line
			(start -0.67945 -0.305054)
			(end -0.12065 -0.305054)
			(stroke
				(width 0.1)
				(type default)
			)
			(layer "F.Fab")
		)
		(pad "1" smd circle
			(at -0.40005 0 180)
			(size 0 0)
			(layers "F.Cu" "F.Mask" "F.Paste")
			(net "FM_PCH_GLB_RST_WARN_N")
		)
		(pad "2" smd circle
			(at 0.40005 0 180)
			(size 0 0)
			(layers "F.Cu" "F.Mask" "F.Paste")
			(net "FM_PCH_PLD_GLB_RST_WARN_N")
		)
	)
	(footprint ""
		(layer "F.Cu")
		(at 370.618258 -417.17341 90)
		(property "Reference" "R4198"
			(at 0 0 90)
			(layer "F.SilkS")
			(hide yes)
			(effects
				(font
					(size 1.27 1.27)
				)
			)
		)
		(property "Value" ""
			(at 0 0 90)
			(layer "F.Fab")
			(effects
				(font
					(size 1.27 1.27)
				)
			)
		)
		(duplicate_pad_numbers_are_jumpers no)
		(fp_line
			(start 0.7874 -0.4064)
			(end 0.7874 0.4064)
			(stroke
				(width 0.1524)
				(type default)
			)
			(layer "F.SilkS")
		)
		(fp_line
			(start -0.7874 -0.4064)
			(end 0.7874 -0.4064)
			(stroke
				(width 0.1524)
				(type default)
			)
			(layer "F.SilkS")
		)
		(fp_line
			(start 0.7874 0.4064)
			(end -0.7874 0.4064)
			(stroke
				(width 0.1524)
				(type default)
			)
			(layer "F.SilkS")
		)
		(fp_line
			(start -0.7874 0.4064)
			(end -0.7874 -0.4064)
			(stroke
				(width 0.1524)
				(type default)
			)
			(layer "F.SilkS")
		)
		(fp_line
			(start -0.12065 -0.305054)
			(end -0.12065 -0.2794)
			(stroke
				(width 0.1)
				(type default)
			)
			(layer "F.Fab")
		)
		(fp_line
			(start -0.67945 -0.305054)
			(end -0.12065 -0.305054)
			(stroke
				(width 0.1)
				(type default)
			)
			(layer "F.Fab")
		)
		(fp_line
			(start 0.67945 -0.3048)
			(end 0.67945 0.3048)
			(stroke
				(width 0.1)
				(type default)
			)
			(layer "F.Fab")
		)
		(fp_line
			(start 0.12065 -0.3048)
			(end 0.67945 -0.3048)
			(stroke
				(width 0.1)
				(type default)
			)
			(layer "F.Fab")
		)
		(fp_line
			(start 0.12065 -0.2794)
			(end 0.12065 -0.3048)
			(stroke
				(width 0.1)
				(type default)
			)
			(layer "F.Fab")
		)
		(fp_line
			(start -0.12065 -0.2794)
			(end 0.12065 -0.2794)
			(stroke
				(width 0.1)
				(type default)
			)
			(layer "F.Fab")
		)
		(fp_line
			(start 0.120396 0.2794)
			(end -0.12065 0.2794)
			(stroke
				(width 0.1)
				(type default)
			)
			(layer "F.Fab")
		)
		(fp_line
			(start -0.12065 0.2794)
			(end -0.12065 0.3048)
			(stroke
				(width 0.1)
				(type default)
			)
			(layer "F.Fab")
		)
		(fp_line
			(start 0.67945 0.3048)
			(end 0.120396 0.3048)
			(stroke
				(width 0.1)
				(type default)
			)
			(layer "F.Fab")
		)
		(fp_line
			(start 0.120396 0.3048)
			(end 0.120396 0.2794)
			(stroke
				(width 0.1)
				(type default)
			)
			(layer "F.Fab")
		)
		(fp_line
			(start -0.12065 0.3048)
			(end -0.67945 0.3048)
			(stroke
				(width 0.1)
				(type default)
			)
			(layer "F.Fab")
		)
		(fp_line
			(start -0.67945 0.3048)
			(end -0.67945 -0.305054)
			(stroke
				(width 0.1)
				(type default)
			)
			(layer "F.Fab")
		)
		(pad "1" smd circle
			(at -0.40005 0 90)
			(size 0 0)
			(layers "F.Cu" "F.Mask" "F.Paste")
			(net "P3V3_AUX")
		)
		(pad "2" smd circle
			(at 0.40005 0 90)
			(size 0 0)
			(layers "F.Cu" "F.Mask" "F.Paste")
			(net "U270_0_ADD1")
		)
	)
	(footprint ""
		(layer "F.Cu")
		(at 102.818946 -352.02114 180)
		(property "Reference" "PJ52"
			(at 1.986788 -1.20904 0)
			(unlocked yes)
			(layer "F.SilkS")
			(effects
				(font
					(size 0.7874 0.5842)
					(thickness 0.1524)
				)
				(justify left)
			)
		)
		(property "Value" ""
			(at 0 0 180)
			(layer "F.Fab")
			(effects
				(font
					(size 1.27 1.27)
				)
			)
		)
		(duplicate_pad_numbers_are_jumpers no)
		(pad "1" smd circle
			(at -0.7493 0 270)
			(size 0 0)
			(layers "F.Cu" "F.Mask" "F.Paste")
			(net "VSENSE_PVCCIN_CPU1_DP")
		)
		(pad "2" smd rect
			(at 0.7493 0 90)
			(size 0.7112 0.8128)
			(layers "F.Cu" "F.Mask" "F.Paste")
			(net "SH_PVCCIN_CPU1")
		)
		(zone
			(layer "F.Cu")
			(hatch none 0.5)
			(connect_pads
				(clearance 0)
			)
			(min_thickness 0.25)
			(keepout
				(tracks allowed)
				(vias not_allowed)
				(pads allowed)
				(copperpour not_allowed)
				(footprints allowed)
			)
			(placement
				(enabled no)
				(sheetname "")
			)
			(fill
				(thermal_gap 0.5)
				(thermal_bridge_width 0.5)
				(island_removal_mode 0)
			)
			(polygon
				(pts
					(xy 101.612446 -351.61474) (xy 104.000046 -351.61474) (xy 104.000046 -352.432366) (xy 101.612446 -352.432366)
				)
			)
		)
	)
	(footprint ""
		(layer "F.Cu")
		(at 215.90381 -23.304754 -90)
		(property "Reference" "R1139"
			(at 0 0 270)
			(layer "F.SilkS")
			(hide yes)
			(effects
				(font
					(size 1.27 1.27)
				)
			)
		)
		(property "Value" ""
			(at 0 0 270)
			(layer "F.Fab")
			(effects
				(font
					(size 1.27 1.27)
				)
			)
		)
		(duplicate_pad_numbers_are_jumpers no)
		(fp_line
			(start -0.7874 0.4064)
			(end -0.7874 -0.4064)
			(stroke
				(width 0.1524)
				(type default)
			)
			(layer "F.SilkS")
		)
		(fp_line
			(start 0.7874 0.4064)
			(end -0.7874 0.4064)
			(stroke
				(width 0.1524)
				(type default)
			)
			(layer "F.SilkS")
		)
		(fp_line
			(start -0.7874 -0.4064)
			(end 0.7874 -0.4064)
			(stroke
				(width 0.1524)
				(type default)
			)
			(layer "F.SilkS")
		)
		(fp_line
			(start 0.7874 -0.4064)
			(end 0.7874 0.4064)
			(stroke
				(width 0.1524)
				(type default)
			)
			(layer "F.SilkS")
		)
		(fp_line
			(start -0.67945 0.3048)
			(end -0.67945 -0.305054)
			(stroke
				(width 0.1)
				(type default)
			)
			(layer "F.Fab")
		)
		(fp_line
			(start -0.12065 0.3048)
			(end -0.67945 0.3048)
			(stroke
				(width 0.1)
				(type default)
			)
			(layer "F.Fab")
		)
		(fp_line
			(start 0.120396 0.3048)
			(end 0.120396 0.2794)
			(stroke
				(width 0.1)
				(type default)
			)
			(layer "F.Fab")
		)
		(fp_line
			(start 0.67945 0.3048)
			(end 0.120396 0.3048)
			(stroke
				(width 0.1)
				(type default)
			)
			(layer "F.Fab")
		)
		(fp_line
			(start -0.12065 0.2794)
			(end -0.12065 0.3048)
			(stroke
				(width 0.1)
				(type default)
			)
			(layer "F.Fab")
		)
		(fp_line
			(start 0.120396 0.2794)
			(end -0.12065 0.2794)
			(stroke
				(width 0.1)
				(type default)
			)
			(layer "F.Fab")
		)
		(fp_line
			(start -0.12065 -0.2794)
			(end 0.12065 -0.2794)
			(stroke
				(width 0.1)
				(type default)
			)
			(layer "F.Fab")
		)
		(fp_line
			(start 0.12065 -0.2794)
			(end 0.12065 -0.3048)
			(stroke
				(width 0.1)
				(type default)
			)
			(layer "F.Fab")
		)
		(fp_line
			(start 0.12065 -0.3048)
			(end 0.67945 -0.3048)
			(stroke
				(width 0.1)
				(type default)
			)
			(layer "F.Fab")
		)
		(fp_line
			(start 0.67945 -0.3048)
			(end 0.67945 0.3048)
			(stroke
				(width 0.1)
				(type default)
			)
			(layer "F.Fab")
		)
		(fp_line
			(start -0.67945 -0.305054)
			(end -0.12065 -0.305054)
			(stroke
				(width 0.1)
				(type default)
			)
			(layer "F.Fab")
		)
		(fp_line
			(start -0.12065 -0.305054)
			(end -0.12065 -0.2794)
			(stroke
				(width 0.1)
				(type default)
			)
			(layer "F.Fab")
		)
		(pad "1" smd circle
			(at -0.40005 0 270)
			(size 0 0)
			(layers "F.Cu" "F.Mask" "F.Paste")
			(net "CLK_50M_RMII")
		)
		(pad "2" smd circle
			(at 0.40005 0 270)
			(size 0 0)
			(layers "F.Cu" "F.Mask" "F.Paste")
			(net "CLK_50M_RMII_R")
		)
	)
	(footprint ""
		(layer "F.Cu")
		(at 129.411984 -66.938906 90)
		(property "Reference" "R928"
			(at 0 0 90)
			(layer "F.SilkS")
			(hide yes)
			(effects
				(font
					(size 1.27 1.27)
				)
			)
		)
		(property "Value" ""
			(at 0 0 90)
			(layer "F.Fab")
			(effects
				(font
					(size 1.27 1.27)
				)
			)
		)
		(duplicate_pad_numbers_are_jumpers no)
		(fp_line
			(start 0.7874 -0.4064)
			(end 0.7874 0.4064)
			(stroke
				(width 0.1524)
				(type default)
			)
			(layer "F.SilkS")
		)
		(fp_line
			(start -0.7874 -0.4064)
			(end 0.7874 -0.4064)
			(stroke
				(width 0.1524)
				(type default)
			)
			(layer "F.SilkS")
		)
		(fp_line
			(start 0.7874 0.4064)
			(end -0.7874 0.4064)
			(stroke
				(width 0.1524)
				(type default)
			)
			(layer "F.SilkS")
		)
		(fp_line
			(start -0.7874 0.4064)
			(end -0.7874 -0.4064)
			(stroke
				(width 0.1524)
				(type default)
			)
			(layer "F.SilkS")
		)
		(fp_line
			(start -0.12065 -0.305054)
			(end -0.12065 -0.2794)
			(stroke
				(width 0.1)
				(type default)
			)
			(layer "F.Fab")
		)
		(fp_line
			(start -0.67945 -0.305054)
			(end -0.12065 -0.305054)
			(stroke
				(width 0.1)
				(type default)
			)
			(layer "F.Fab")
		)
		(fp_line
			(start 0.67945 -0.3048)
			(end 0.67945 0.3048)
			(stroke
				(width 0.1)
				(type default)
			)
			(layer "F.Fab")
		)
		(fp_line
			(start 0.12065 -0.3048)
			(end 0.67945 -0.3048)
			(stroke
				(width 0.1)
				(type default)
			)
			(layer "F.Fab")
		)
		(fp_line
			(start 0.12065 -0.2794)
			(end 0.12065 -0.3048)
			(stroke
				(width 0.1)
				(type default)
			)
			(layer "F.Fab")
		)
		(fp_line
			(start -0.12065 -0.2794)
			(end 0.12065 -0.2794)
			(stroke
				(width 0.1)
				(type default)
			)
			(layer "F.Fab")
		)
		(fp_line
			(start 0.120396 0.2794)
			(end -0.12065 0.2794)
			(stroke
				(width 0.1)
				(type default)
			)
			(layer "F.Fab")
		)
		(fp_line
			(start -0.12065 0.2794)
			(end -0.12065 0.3048)
			(stroke
				(width 0.1)
				(type default)
			)
			(layer "F.Fab")
		)
		(fp_line
			(start 0.67945 0.3048)
			(end 0.120396 0.3048)
			(stroke
				(width 0.1)
				(type default)
			)
			(layer "F.Fab")
		)
		(fp_line
			(start 0.120396 0.3048)
			(end 0.120396 0.2794)
			(stroke
				(width 0.1)
				(type default)
			)
			(layer "F.Fab")
		)
		(fp_line
			(start -0.12065 0.3048)
			(end -0.67945 0.3048)
			(stroke
				(width 0.1)
				(type default)
			)
			(layer "F.Fab")
		)
		(fp_line
			(start -0.67945 0.3048)
			(end -0.67945 -0.305054)
			(stroke
				(width 0.1)
				(type default)
			)
			(layer "F.Fab")
		)
		(pad "1" smd circle
			(at -0.40005 0 90)
			(size 0 0)
			(layers "F.Cu" "F.Mask" "F.Paste")
			(net "P3V3_AUX")
		)
		(pad "2" smd circle
			(at 0.40005 0 90)
			(size 0 0)
			(layers "F.Cu" "F.Mask" "F.Paste")
			(net "JTAG_BMC_PLD_TDO")
		)
	)
	(footprint ""
		(layer "F.Cu")
		(at 448.672458 -93.509592 180)
		(property "Reference" "R3617"
			(at 0 0 180)
			(layer "F.SilkS")
			(hide yes)
			(effects
				(font
					(size 1.27 1.27)
				)
			)
		)
		(property "Value" ""
			(at 0 0 180)
			(layer "F.Fab")
			(effects
				(font
					(size 1.27 1.27)
				)
			)
		)
		(duplicate_pad_numbers_are_jumpers no)
		(fp_line
			(start 0.7874 0.4064)
			(end -0.7874 0.4064)
			(stroke
				(width 0.1524)
				(type default)
			)
			(layer "F.SilkS")
		)
		(fp_line
			(start 0.7874 -0.4064)
			(end 0.7874 0.4064)
			(stroke
				(width 0.1524)
				(type default)
			)
			(layer "F.SilkS")
		)
		(fp_line
			(start -0.7874 0.4064)
			(end -0.7874 -0.4064)
			(stroke
				(width 0.1524)
				(type default)
			)
			(layer "F.SilkS")
		)
		(fp_line
			(start -0.7874 -0.4064)
			(end 0.7874 -0.4064)
			(stroke
				(width 0.1524)
				(type default)
			)
			(layer "F.SilkS")
		)
		(fp_line
			(start 0.67945 0.3048)
			(end 0.120396 0.3048)
			(stroke
				(width 0.1)
				(type default)
			)
			(layer "F.Fab")
		)
		(fp_line
			(start 0.67945 -0.3048)
			(end 0.67945 0.3048)
			(stroke
				(width 0.1)
				(type default)
			)
			(layer "F.Fab")
		)
		(fp_line
			(start 0.12065 -0.2794)
			(end 0.12065 -0.3048)
			(stroke
				(width 0.1)
				(type default)
			)
			(layer "F.Fab")
		)
		(fp_line
			(start 0.12065 -0.3048)
			(end 0.67945 -0.3048)
			(stroke
				(width 0.1)
				(type default)
			)
			(layer "F.Fab")
		)
		(fp_line
			(start 0.120396 0.3048)
			(end 0.120396 0.2794)
			(stroke
				(width 0.1)
				(type default)
			)
			(layer "F.Fab")
		)
		(fp_line
			(start 0.120396 0.2794)
			(end -0.12065 0.2794)
			(stroke
				(width 0.1)
				(type default)
			)
			(layer "F.Fab")
		)
		(fp_line
			(start -0.12065 0.3048)
			(end -0.67945 0.3048)
			(stroke
				(width 0.1)
				(type default)
			)
			(layer "F.Fab")
		)
		(fp_line
			(start -0.12065 0.2794)
			(end -0.12065 0.3048)
			(stroke
				(width 0.1)
				(type default)
			)
			(layer "F.Fab")
		)
		(fp_line
			(start -0.12065 -0.2794)
			(end 0.12065 -0.2794)
			(stroke
				(width 0.1)
				(type default)
			)
			(layer "F.Fab")
		)
		(fp_line
			(start -0.12065 -0.305054)
			(end -0.12065 -0.2794)
			(stroke
				(width 0.1)
				(type default)
			)
			(layer "F.Fab")
		)
		(fp_line
			(start -0.67945 0.3048)
			(end -0.67945 -0.305054)
			(stroke
				(width 0.1)
				(type default)
			)
			(layer "F.Fab")
		)
		(fp_line
			(start -0.67945 -0.305054)
			(end -0.12065 -0.305054)
			(stroke
				(width 0.1)
				(type default)
			)
			(layer "F.Fab")
		)
		(pad "1" smd circle
			(at -0.40005 0 180)
			(size 0 0)
			(layers "F.Cu" "F.Mask" "F.Paste")
			(net "GND")
		)
		(pad "2" smd circle
			(at 0.40005 0 180)
			(size 0 0)
			(layers "F.Cu" "F.Mask" "F.Paste")
			(net "INA230_1_A0")
		)
	)
	(footprint ""
		(layer "F.Cu")
		(at 145.65884 -92.634308 -90)
		(property "Reference" "R4052"
			(at 0 0 270)
			(layer "F.SilkS")
			(hide yes)
			(effects
				(font
					(size 1.27 1.27)
				)
			)
		)
		(property "Value" ""
			(at 0 0 270)
			(layer "F.Fab")
			(effects
				(font
					(size 1.27 1.27)
				)
			)
		)
		(duplicate_pad_numbers_are_jumpers no)
		(fp_line
			(start -0.7874 0.4064)
			(end -0.7874 -0.4064)
			(stroke
				(width 0.1524)
				(type default)
			)
			(layer "F.SilkS")
		)
		(fp_line
			(start 0.7874 0.4064)
			(end -0.7874 0.4064)
			(stroke
				(width 0.1524)
				(type default)
			)
			(layer "F.SilkS")
		)
		(fp_line
			(start -0.7874 -0.4064)
			(end 0.7874 -0.4064)
			(stroke
				(width 0.1524)
				(type default)
			)
			(layer "F.SilkS")
		)
		(fp_line
			(start 0.7874 -0.4064)
			(end 0.7874 0.4064)
			(stroke
				(width 0.1524)
				(type default)
			)
			(layer "F.SilkS")
		)
		(fp_line
			(start -0.67945 0.3048)
			(end -0.67945 -0.305054)
			(stroke
				(width 0.1)
				(type default)
			)
			(layer "F.Fab")
		)
		(fp_line
			(start -0.12065 0.3048)
			(end -0.67945 0.3048)
			(stroke
				(width 0.1)
				(type default)
			)
			(layer "F.Fab")
		)
		(fp_line
			(start 0.120396 0.3048)
			(end 0.120396 0.2794)
			(stroke
				(width 0.1)
				(type default)
			)
			(layer "F.Fab")
		)
		(fp_line
			(start 0.67945 0.3048)
			(end 0.120396 0.3048)
			(stroke
				(width 0.1)
				(type default)
			)
			(layer "F.Fab")
		)
		(fp_line
			(start -0.12065 0.2794)
			(end -0.12065 0.3048)
			(stroke
				(width 0.1)
				(type default)
			)
			(layer "F.Fab")
		)
		(fp_line
			(start 0.120396 0.2794)
			(end -0.12065 0.2794)
			(stroke
				(width 0.1)
				(type default)
			)
			(layer "F.Fab")
		)
		(fp_line
			(start -0.12065 -0.2794)
			(end 0.12065 -0.2794)
			(stroke
				(width 0.1)
				(type default)
			)
			(layer "F.Fab")
		)
		(fp_line
			(start 0.12065 -0.2794)
			(end 0.12065 -0.3048)
			(stroke
				(width 0.1)
				(type default)
			)
			(layer "F.Fab")
		)
		(fp_line
			(start 0.12065 -0.3048)
			(end 0.67945 -0.3048)
			(stroke
				(width 0.1)
				(type default)
			)
			(layer "F.Fab")
		)
		(fp_line
			(start 0.67945 -0.3048)
			(end 0.67945 0.3048)
			(stroke
				(width 0.1)
				(type default)
			)
			(layer "F.Fab")
		)
		(fp_line
			(start -0.67945 -0.305054)
			(end -0.12065 -0.305054)
			(stroke
				(width 0.1)
				(type default)
			)
			(layer "F.Fab")
		)
		(fp_line
			(start -0.12065 -0.305054)
			(end -0.12065 -0.2794)
			(stroke
				(width 0.1)
				(type default)
			)
			(layer "F.Fab")
		)
		(pad "1" smd circle
			(at -0.40005 0 270)
			(size 0 0)
			(layers "F.Cu" "F.Mask" "F.Paste")
			(net "H_CPU_ERR2_LVC2_R_N")
		)
		(pad "2" smd circle
			(at 0.40005 0 270)
			(size 0 0)
			(layers "F.Cu" "F.Mask" "F.Paste")
			(net "H_CPU_ERR2_LVC2_N")
		)
	)
	(footprint ""
		(layer "F.Cu")
		(at 180.01488 -97.119948 -90)
		(property "Reference" "R4293"
			(at 0 0 270)
			(layer "F.SilkS")
			(hide yes)
			(effects
				(font
					(size 1.27 1.27)
				)
			)
		)
		(property "Value" ""
			(at 0 0 270)
			(layer "F.Fab")
			(effects
				(font
					(size 1.27 1.27)
				)
			)
		)
		(duplicate_pad_numbers_are_jumpers no)
		(fp_line
			(start -0.7874 0.4064)
			(end -0.7874 -0.4064)
			(stroke
				(width 0.1524)
				(type default)
			)
			(layer "F.SilkS")
		)
		(fp_line
			(start 0.7874 0.4064)
			(end -0.7874 0.4064)
			(stroke
				(width 0.1524)
				(type default)
			)
			(layer "F.SilkS")
		)
		(fp_line
			(start -0.7874 -0.4064)
			(end 0.7874 -0.4064)
			(stroke
				(width 0.1524)
				(type default)
			)
			(layer "F.SilkS")
		)
		(fp_line
			(start 0.7874 -0.4064)
			(end 0.7874 0.4064)
			(stroke
				(width 0.1524)
				(type default)
			)
			(layer "F.SilkS")
		)
		(fp_line
			(start -0.67945 0.3048)
			(end -0.67945 -0.305054)
			(stroke
				(width 0.1)
				(type default)
			)
			(layer "F.Fab")
		)
		(fp_line
			(start -0.12065 0.3048)
			(end -0.67945 0.3048)
			(stroke
				(width 0.1)
				(type default)
			)
			(layer "F.Fab")
		)
		(fp_line
			(start 0.120396 0.3048)
			(end 0.120396 0.2794)
			(stroke
				(width 0.1)
				(type default)
			)
			(layer "F.Fab")
		)
		(fp_line
			(start 0.67945 0.3048)
			(end 0.120396 0.3048)
			(stroke
				(width 0.1)
				(type default)
			)
			(layer "F.Fab")
		)
		(fp_line
			(start -0.12065 0.2794)
			(end -0.12065 0.3048)
			(stroke
				(width 0.1)
				(type default)
			)
			(layer "F.Fab")
		)
		(fp_line
			(start 0.120396 0.2794)
			(end -0.12065 0.2794)
			(stroke
				(width 0.1)
				(type default)
			)
			(layer "F.Fab")
		)
		(fp_line
			(start -0.12065 -0.2794)
			(end 0.12065 -0.2794)
			(stroke
				(width 0.1)
				(type default)
			)
			(layer "F.Fab")
		)
		(fp_line
			(start 0.12065 -0.2794)
			(end 0.12065 -0.3048)
			(stroke
				(width 0.1)
				(type default)
			)
			(layer "F.Fab")
		)
		(fp_line
			(start 0.12065 -0.3048)
			(end 0.67945 -0.3048)
			(stroke
				(width 0.1)
				(type default)
			)
			(layer "F.Fab")
		)
		(fp_line
			(start 0.67945 -0.3048)
			(end 0.67945 0.3048)
			(stroke
				(width 0.1)
				(type default)
			)
			(layer "F.Fab")
		)
		(fp_line
			(start -0.67945 -0.305054)
			(end -0.12065 -0.305054)
			(stroke
				(width 0.1)
				(type default)
			)
			(layer "F.Fab")
		)
		(fp_line
			(start -0.12065 -0.305054)
			(end -0.12065 -0.2794)
			(stroke
				(width 0.1)
				(type default)
			)
			(layer "F.Fab")
		)
		(pad "1" smd circle
			(at -0.40005 0 270)
			(size 0 0)
			(layers "F.Cu" "F.Mask" "F.Paste")
			(net "H_CPU0_MEMHOT_IN_LVC1_R1_N")
		)
		(pad "2" smd circle
			(at 0.40005 0 270)
			(size 0 0)
			(layers "F.Cu" "F.Mask" "F.Paste")
			(net "H_CPU0_MEMHOT_IN_LVC1_N")
		)
	)
	(footprint ""
		(layer "F.Cu")
		(at 211.102956 -30.276292 90)
		(property "Reference" "R3613"
			(at 0 0 90)
			(layer "F.SilkS")
			(hide yes)
			(effects
				(font
					(size 1.27 1.27)
				)
			)
		)
		(property "Value" ""
			(at 0 0 90)
			(layer "F.Fab")
			(effects
				(font
					(size 1.27 1.27)
				)
			)
		)
		(duplicate_pad_numbers_are_jumpers no)
		(fp_line
			(start 0.7874 -0.4064)
			(end 0.7874 0.4064)
			(stroke
				(width 0.1524)
				(type default)
			)
			(layer "F.SilkS")
		)
		(fp_line
			(start -0.7874 -0.4064)
			(end 0.7874 -0.4064)
			(stroke
				(width 0.1524)
				(type default)
			)
			(layer "F.SilkS")
		)
		(fp_line
			(start 0.7874 0.4064)
			(end -0.7874 0.4064)
			(stroke
				(width 0.1524)
				(type default)
			)
			(layer "F.SilkS")
		)
		(fp_line
			(start -0.7874 0.4064)
			(end -0.7874 -0.4064)
			(stroke
				(width 0.1524)
				(type default)
			)
			(layer "F.SilkS")
		)
		(fp_line
			(start -0.12065 -0.305054)
			(end -0.12065 -0.2794)
			(stroke
				(width 0.1)
				(type default)
			)
			(layer "F.Fab")
		)
		(fp_line
			(start -0.67945 -0.305054)
			(end -0.12065 -0.305054)
			(stroke
				(width 0.1)
				(type default)
			)
			(layer "F.Fab")
		)
		(fp_line
			(start 0.67945 -0.3048)
			(end 0.67945 0.3048)
			(stroke
				(width 0.1)
				(type default)
			)
			(layer "F.Fab")
		)
		(fp_line
			(start 0.12065 -0.3048)
			(end 0.67945 -0.3048)
			(stroke
				(width 0.1)
				(type default)
			)
			(layer "F.Fab")
		)
		(fp_line
			(start 0.12065 -0.2794)
			(end 0.12065 -0.3048)
			(stroke
				(width 0.1)
				(type default)
			)
			(layer "F.Fab")
		)
		(fp_line
			(start -0.12065 -0.2794)
			(end 0.12065 -0.2794)
			(stroke
				(width 0.1)
				(type default)
			)
			(layer "F.Fab")
		)
		(fp_line
			(start 0.120396 0.2794)
			(end -0.12065 0.2794)
			(stroke
				(width 0.1)
				(type default)
			)
			(layer "F.Fab")
		)
		(fp_line
			(start -0.12065 0.2794)
			(end -0.12065 0.3048)
			(stroke
				(width 0.1)
				(type default)
			)
			(layer "F.Fab")
		)
		(fp_line
			(start 0.67945 0.3048)
			(end 0.120396 0.3048)
			(stroke
				(width 0.1)
				(type default)
			)
			(layer "F.Fab")
		)
		(fp_line
			(start 0.120396 0.3048)
			(end 0.120396 0.2794)
			(stroke
				(width 0.1)
				(type default)
			)
			(layer "F.Fab")
		)
		(fp_line
			(start -0.12065 0.3048)
			(end -0.67945 0.3048)
			(stroke
				(width 0.1)
				(type default)
			)
			(layer "F.Fab")
		)
		(fp_line
			(start -0.67945 0.3048)
			(end -0.67945 -0.305054)
			(stroke
				(width 0.1)
				(type default)
			)
			(layer "F.Fab")
		)
		(pad "1" smd circle
			(at -0.40005 0 90)
			(size 0 0)
			(layers "F.Cu" "F.Mask" "F.Paste")
			(net "GND")
		)
		(pad "2" smd circle
			(at 0.40005 0 90)
			(size 0 0)
			(layers "F.Cu" "F.Mask" "F.Paste")
			(net "INA230_5_A0")
		)
	)
	(footprint ""
		(layer "F.Cu")
		(at 106.476038 -41.012364)
		(property "Reference" "R3187"
			(at 0 0 0)
			(layer "F.SilkS")
			(hide yes)
			(effects
				(font
					(size 1.27 1.27)
				)
			)
		)
		(property "Value" ""
			(at 0 0 0)
			(layer "F.Fab")
			(effects
				(font
					(size 1.27 1.27)
				)
			)
		)
		(duplicate_pad_numbers_are_jumpers no)
		(fp_line
			(start -0.7874 -0.4064)
			(end 0.7874 -0.4064)
			(stroke
				(width 0.1524)
				(type default)
			)
			(layer "F.SilkS")
		)
		(fp_line
			(start -0.7874 0.4064)
			(end -0.7874 -0.4064)
			(stroke
				(width 0.1524)
				(type default)
			)
			(layer "F.SilkS")
		)
		(fp_line
			(start 0.7874 -0.4064)
			(end 0.7874 0.4064)
			(stroke
				(width 0.1524)
				(type default)
			)
			(layer "F.SilkS")
		)
		(fp_line
			(start 0.7874 0.4064)
			(end -0.7874 0.4064)
			(stroke
				(width 0.1524)
				(type default)
			)
			(layer "F.SilkS")
		)
		(fp_line
			(start -0.67945 -0.305054)
			(end -0.12065 -0.305054)
			(stroke
				(width 0.1)
				(type default)
			)
			(layer "F.Fab")
		)
		(fp_line
			(start -0.67945 0.3048)
			(end -0.67945 -0.305054)
			(stroke
				(width 0.1)
				(type default)
			)
			(layer "F.Fab")
		)
		(fp_line
			(start -0.12065 -0.305054)
			(end -0.12065 -0.2794)
			(stroke
				(width 0.1)
				(type default)
			)
			(layer "F.Fab")
		)
		(fp_line
			(start -0.12065 -0.2794)
			(end 0.12065 -0.2794)
			(stroke
				(width 0.1)
				(type default)
			)
			(layer "F.Fab")
		)
		(fp_line
			(start -0.12065 0.2794)
			(end -0.12065 0.3048)
			(stroke
				(width 0.1)
				(type default)
			)
			(layer "F.Fab")
		)
		(fp_line
			(start -0.12065 0.3048)
			(end -0.67945 0.3048)
			(stroke
				(width 0.1)
				(type default)
			)
			(layer "F.Fab")
		)
		(fp_line
			(start 0.120396 0.2794)
			(end -0.12065 0.2794)
			(stroke
				(width 0.1)
				(type default)
			)
			(layer "F.Fab")
		)
		(fp_line
			(start 0.120396 0.3048)
			(end 0.120396 0.2794)
			(stroke
				(width 0.1)
				(type default)
			)
			(layer "F.Fab")
		)
		(fp_line
			(start 0.12065 -0.3048)
			(end 0.67945 -0.3048)
			(stroke
				(width 0.1)
				(type default)
			)
			(layer "F.Fab")
		)
		(fp_line
			(start 0.12065 -0.2794)
			(end 0.12065 -0.3048)
			(stroke
				(width 0.1)
				(type default)
			)
			(layer "F.Fab")
		)
		(fp_line
			(start 0.67945 -0.3048)
			(end 0.67945 0.3048)
			(stroke
				(width 0.1)
				(type default)
			)
			(layer "F.Fab")
		)
		(fp_line
			(start 0.67945 0.3048)
			(end 0.120396 0.3048)
			(stroke
				(width 0.1)
				(type default)
			)
			(layer "F.Fab")
		)
		(pad "1" smd circle
			(at -0.40005 0)
			(size 0 0)
			(layers "F.Cu" "F.Mask" "F.Paste")
			(net "RST_OCP_V3_2_BUF_N")
		)
		(pad "2" smd circle
			(at 0.40005 0)
			(size 0 0)
			(layers "F.Cu" "F.Mask" "F.Paste")
			(net "RST_PERST1_OCP_V3_2_N")
		)
	)
	(footprint ""
		(layer "F.Cu")
		(at 213.06155 -22.974554 180)
		(property "Reference" "R1140"
			(at 0 0 180)
			(layer "F.SilkS")
			(hide yes)
			(effects
				(font
					(size 1.27 1.27)
				)
			)
		)
		(property "Value" ""
			(at 0 0 180)
			(layer "F.Fab")
			(effects
				(font
					(size 1.27 1.27)
				)
			)
		)
		(duplicate_pad_numbers_are_jumpers no)
		(fp_line
			(start 0.7874 0.4064)
			(end -0.7874 0.4064)
			(stroke
				(width 0.1524)
				(type default)
			)
			(layer "F.SilkS")
		)
		(fp_line
			(start 0.7874 -0.4064)
			(end 0.7874 0.4064)
			(stroke
				(width 0.1524)
				(type default)
			)
			(layer "F.SilkS")
		)
		(fp_line
			(start -0.7874 0.4064)
			(end -0.7874 -0.4064)
			(stroke
				(width 0.1524)
				(type default)
			)
			(layer "F.SilkS")
		)
		(fp_line
			(start -0.7874 -0.4064)
			(end 0.7874 -0.4064)
			(stroke
				(width 0.1524)
				(type default)
			)
			(layer "F.SilkS")
		)
		(fp_line
			(start 0.67945 0.3048)
			(end 0.120396 0.3048)
			(stroke
				(width 0.1)
				(type default)
			)
			(layer "F.Fab")
		)
		(fp_line
			(start 0.67945 -0.3048)
			(end 0.67945 0.3048)
			(stroke
				(width 0.1)
				(type default)
			)
			(layer "F.Fab")
		)
		(fp_line
			(start 0.12065 -0.2794)
			(end 0.12065 -0.3048)
			(stroke
				(width 0.1)
				(type default)
			)
			(layer "F.Fab")
		)
		(fp_line
			(start 0.12065 -0.3048)
			(end 0.67945 -0.3048)
			(stroke
				(width 0.1)
				(type default)
			)
			(layer "F.Fab")
		)
		(fp_line
			(start 0.120396 0.3048)
			(end 0.120396 0.2794)
			(stroke
				(width 0.1)
				(type default)
			)
			(layer "F.Fab")
		)
		(fp_line
			(start 0.120396 0.2794)
			(end -0.12065 0.2794)
			(stroke
				(width 0.1)
				(type default)
			)
			(layer "F.Fab")
		)
		(fp_line
			(start -0.12065 0.3048)
			(end -0.67945 0.3048)
			(stroke
				(width 0.1)
				(type default)
			)
			(layer "F.Fab")
		)
		(fp_line
			(start -0.12065 0.2794)
			(end -0.12065 0.3048)
			(stroke
				(width 0.1)
				(type default)
			)
			(layer "F.Fab")
		)
		(fp_line
			(start -0.12065 -0.2794)
			(end 0.12065 -0.2794)
			(stroke
				(width 0.1)
				(type default)
			)
			(layer "F.Fab")
		)
		(fp_line
			(start -0.12065 -0.305054)
			(end -0.12065 -0.2794)
			(stroke
				(width 0.1)
				(type default)
			)
			(layer "F.Fab")
		)
		(fp_line
			(start -0.67945 0.3048)
			(end -0.67945 -0.305054)
			(stroke
				(width 0.1)
				(type default)
			)
			(layer "F.Fab")
		)
		(fp_line
			(start -0.67945 -0.305054)
			(end -0.12065 -0.305054)
			(stroke
				(width 0.1)
				(type default)
			)
			(layer "F.Fab")
		)
		(pad "1" smd circle
			(at -0.40005 0 180)
			(size 0 0)
			(layers "F.Cu" "F.Mask" "F.Paste")
			(net "CLK_50M_BMC_MAC_R")
		)
		(pad "2" smd circle
			(at 0.40005 0 180)
			(size 0 0)
			(layers "F.Cu" "F.Mask" "F.Paste")
			(net "CLK_50M_RMII_BMC_OCP")
		)
	)
	(footprint ""
		(layer "F.Cu")
		(at 295.86682 -421.41521 90)
		(property "Reference" "R4156"
			(at 0 0 90)
			(layer "F.SilkS")
			(hide yes)
			(effects
				(font
					(size 1.27 1.27)
				)
			)
		)
		(property "Value" ""
			(at 0 0 90)
			(layer "F.Fab")
			(effects
				(font
					(size 1.27 1.27)
				)
			)
		)
		(duplicate_pad_numbers_are_jumpers no)
		(fp_line
			(start 0.7874 -0.4064)
			(end 0.7874 0.4064)
			(stroke
				(width 0.1524)
				(type default)
			)
			(layer "F.SilkS")
		)
		(fp_line
			(start -0.7874 -0.4064)
			(end 0.7874 -0.4064)
			(stroke
				(width 0.1524)
				(type default)
			)
			(layer "F.SilkS")
		)
		(fp_line
			(start 0.7874 0.4064)
			(end -0.7874 0.4064)
			(stroke
				(width 0.1524)
				(type default)
			)
			(layer "F.SilkS")
		)
		(fp_line
			(start -0.7874 0.4064)
			(end -0.7874 -0.4064)
			(stroke
				(width 0.1524)
				(type default)
			)
			(layer "F.SilkS")
		)
		(fp_line
			(start -0.12065 -0.305054)
			(end -0.12065 -0.2794)
			(stroke
				(width 0.1)
				(type default)
			)
			(layer "F.Fab")
		)
		(fp_line
			(start -0.67945 -0.305054)
			(end -0.12065 -0.305054)
			(stroke
				(width 0.1)
				(type default)
			)
			(layer "F.Fab")
		)
		(fp_line
			(start 0.67945 -0.3048)
			(end 0.67945 0.3048)
			(stroke
				(width 0.1)
				(type default)
			)
			(layer "F.Fab")
		)
		(fp_line
			(start 0.12065 -0.3048)
			(end 0.67945 -0.3048)
			(stroke
				(width 0.1)
				(type default)
			)
			(layer "F.Fab")
		)
		(fp_line
			(start 0.12065 -0.2794)
			(end 0.12065 -0.3048)
			(stroke
				(width 0.1)
				(type default)
			)
			(layer "F.Fab")
		)
		(fp_line
			(start -0.12065 -0.2794)
			(end 0.12065 -0.2794)
			(stroke
				(width 0.1)
				(type default)
			)
			(layer "F.Fab")
		)
		(fp_line
			(start 0.120396 0.2794)
			(end -0.12065 0.2794)
			(stroke
				(width 0.1)
				(type default)
			)
			(layer "F.Fab")
		)
		(fp_line
			(start -0.12065 0.2794)
			(end -0.12065 0.3048)
			(stroke
				(width 0.1)
				(type default)
			)
			(layer "F.Fab")
		)
		(fp_line
			(start 0.67945 0.3048)
			(end 0.120396 0.3048)
			(stroke
				(width 0.1)
				(type default)
			)
			(layer "F.Fab")
		)
		(fp_line
			(start 0.120396 0.3048)
			(end 0.120396 0.2794)
			(stroke
				(width 0.1)
				(type default)
			)
			(layer "F.Fab")
		)
		(fp_line
			(start -0.12065 0.3048)
			(end -0.67945 0.3048)
			(stroke
				(width 0.1)
				(type default)
			)
			(layer "F.Fab")
		)
		(fp_line
			(start -0.67945 0.3048)
			(end -0.67945 -0.305054)
			(stroke
				(width 0.1)
				(type default)
			)
			(layer "F.Fab")
		)
		(pad "1" smd circle
			(at -0.40005 0 90)
			(size 0 0)
			(layers "F.Cu" "F.Mask" "F.Paste")
			(net "P3V3_AUX")
		)
		(pad "2" smd circle
			(at 0.40005 0 90)
			(size 0 0)
			(layers "F.Cu" "F.Mask" "F.Paste")
			(net "PRSNT_CABLE_GPU_A1_ISO_N")
		)
	)
	(footprint ""
		(layer "F.Cu")
		(at 366.454182 -423.03573)
		(property "Reference" "R4215"
			(at 0 0 0)
			(layer "F.SilkS")
			(hide yes)
			(effects
				(font
					(size 1.27 1.27)
				)
			)
		)
		(property "Value" ""
			(at 0 0 0)
			(layer "F.Fab")
			(effects
				(font
					(size 1.27 1.27)
				)
			)
		)
		(duplicate_pad_numbers_are_jumpers no)
		(fp_line
			(start -0.7874 -0.4064)
			(end 0.7874 -0.4064)
			(stroke
				(width 0.1524)
				(type default)
			)
			(layer "F.SilkS")
		)
		(fp_line
			(start -0.7874 0.4064)
			(end -0.7874 -0.4064)
			(stroke
				(width 0.1524)
				(type default)
			)
			(layer "F.SilkS")
		)
		(fp_line
			(start 0.7874 -0.4064)
			(end 0.7874 0.4064)
			(stroke
				(width 0.1524)
				(type default)
			)
			(layer "F.SilkS")
		)
		(fp_line
			(start 0.7874 0.4064)
			(end -0.7874 0.4064)
			(stroke
				(width 0.1524)
				(type default)
			)
			(layer "F.SilkS")
		)
		(fp_line
			(start -0.67945 -0.305054)
			(end -0.12065 -0.305054)
			(stroke
				(width 0.1)
				(type default)
			)
			(layer "F.Fab")
		)
		(fp_line
			(start -0.67945 0.3048)
			(end -0.67945 -0.305054)
			(stroke
				(width 0.1)
				(type default)
			)
			(layer "F.Fab")
		)
		(fp_line
			(start -0.12065 -0.305054)
			(end -0.12065 -0.2794)
			(stroke
				(width 0.1)
				(type default)
			)
			(layer "F.Fab")
		)
		(fp_line
			(start -0.12065 -0.2794)
			(end 0.12065 -0.2794)
			(stroke
				(width 0.1)
				(type default)
			)
			(layer "F.Fab")
		)
		(fp_line
			(start -0.12065 0.2794)
			(end -0.12065 0.3048)
			(stroke
				(width 0.1)
				(type default)
			)
			(layer "F.Fab")
		)
		(fp_line
			(start -0.12065 0.3048)
			(end -0.67945 0.3048)
			(stroke
				(width 0.1)
				(type default)
			)
			(layer "F.Fab")
		)
		(fp_line
			(start 0.120396 0.2794)
			(end -0.12065 0.2794)
			(stroke
				(width 0.1)
				(type default)
			)
			(layer "F.Fab")
		)
		(fp_line
			(start 0.120396 0.3048)
			(end 0.120396 0.2794)
			(stroke
				(width 0.1)
				(type default)
			)
			(layer "F.Fab")
		)
		(fp_line
			(start 0.12065 -0.3048)
			(end 0.67945 -0.3048)
			(stroke
				(width 0.1)
				(type default)
			)
			(layer "F.Fab")
		)
		(fp_line
			(start 0.12065 -0.2794)
			(end 0.12065 -0.3048)
			(stroke
				(width 0.1)
				(type default)
			)
			(layer "F.Fab")
		)
		(fp_line
			(start 0.67945 -0.3048)
			(end 0.67945 0.3048)
			(stroke
				(width 0.1)
				(type default)
			)
			(layer "F.Fab")
		)
		(fp_line
			(start 0.67945 0.3048)
			(end 0.120396 0.3048)
			(stroke
				(width 0.1)
				(type default)
			)
			(layer "F.Fab")
		)
		(pad "1" smd circle
			(at -0.40005 0)
			(size 0 0)
			(layers "F.Cu" "F.Mask" "F.Paste")
			(net "FM_THERMAL_ALERT_N")
		)
		(pad "2" smd circle
			(at 0.40005 0)
			(size 0 0)
			(layers "F.Cu" "F.Mask" "F.Paste")
			(net "FM_G751_0_ALERT_N")
		)
	)
	(footprint ""
		(layer "F.Cu")
		(at 420.774114 -362.155994 -90)
		(property "Reference" "PC602_P0_1"
			(at 0 0 270)
			(layer "F.SilkS")
			(hide yes)
			(effects
				(font
					(size 1.27 1.27)
				)
			)
		)
		(property "Value" ""
			(at 0 0 270)
			(layer "F.Fab")
			(effects
				(font
					(size 1.27 1.27)
				)
			)
		)
		(duplicate_pad_numbers_are_jumpers no)
		(fp_line
			(start -0.7874 0.4064)
			(end -0.7874 -0.4064)
			(stroke
				(width 0.1524)
				(type default)
			)
			(layer "F.SilkS")
		)
		(fp_line
			(start 0.7874 0.4064)
			(end -0.7874 0.4064)
			(stroke
				(width 0.1524)
				(type default)
			)
			(layer "F.SilkS")
		)
		(fp_line
			(start -0.7874 -0.4064)
			(end 0.7874 -0.4064)
			(stroke
				(width 0.1524)
				(type default)
			)
			(layer "F.SilkS")
		)
		(fp_line
			(start 0.7874 -0.4064)
			(end 0.7874 0.4064)
			(stroke
				(width 0.1524)
				(type default)
			)
			(layer "F.SilkS")
		)
		(fp_line
			(start -0.67945 0.3048)
			(end -0.67945 -0.305054)
			(stroke
				(width 0.1)
				(type default)
			)
			(layer "F.Fab")
		)
		(fp_line
			(start -0.12065 0.3048)
			(end -0.67945 0.3048)
			(stroke
				(width 0.1)
				(type default)
			)
			(layer "F.Fab")
		)
		(fp_line
			(start 0.120396 0.3048)
			(end 0.120396 0.2794)
			(stroke
				(width 0.1)
				(type default)
			)
			(layer "F.Fab")
		)
		(fp_line
			(start 0.67945 0.3048)
			(end 0.120396 0.3048)
			(stroke
				(width 0.1)
				(type default)
			)
			(layer "F.Fab")
		)
		(fp_line
			(start -0.12065 0.2794)
			(end -0.12065 0.3048)
			(stroke
				(width 0.1)
				(type default)
			)
			(layer "F.Fab")
		)
		(fp_line
			(start 0.120396 0.2794)
			(end -0.12065 0.2794)
			(stroke
				(width 0.1)
				(type default)
			)
			(layer "F.Fab")
		)
		(fp_line
			(start -0.12065 -0.2794)
			(end 0.12065 -0.2794)
			(stroke
				(width 0.1)
				(type default)
			)
			(layer "F.Fab")
		)
		(fp_line
			(start 0.12065 -0.2794)
			(end 0.12065 -0.3048)
			(stroke
				(width 0.1)
				(type default)
			)
			(layer "F.Fab")
		)
		(fp_line
			(start 0.12065 -0.3048)
			(end 0.67945 -0.3048)
			(stroke
				(width 0.1)
				(type default)
			)
			(layer "F.Fab")
		)
		(fp_line
			(start 0.67945 -0.3048)
			(end 0.67945 0.3048)
			(stroke
				(width 0.1)
				(type default)
			)
			(layer "F.Fab")
		)
		(fp_line
			(start -0.67945 -0.305054)
			(end -0.12065 -0.305054)
			(stroke
				(width 0.1)
				(type default)
			)
			(layer "F.Fab")
		)
		(fp_line
			(start -0.12065 -0.305054)
			(end -0.12065 -0.2794)
			(stroke
				(width 0.1)
				(type default)
			)
			(layer "F.Fab")
		)
		(pad "1" smd circle
			(at -0.40005 0 270)
			(size 0 0)
			(layers "F.Cu" "F.Mask" "F.Paste")
			(net "SW_P12V_PVCCFA_EHV_FIVRA_CPU0_R")
		)
		(pad "2" smd circle
			(at 0.40005 0 270)
			(size 0 0)
			(layers "F.Cu" "F.Mask" "F.Paste")
			(net "GND")
		)
	)
	(footprint ""
		(layer "F.Cu")
		(at 366.432338 -424.085766)
		(property "Reference" "R4180"
			(at 0 0 0)
			(layer "F.SilkS")
			(hide yes)
			(effects
				(font
					(size 1.27 1.27)
				)
			)
		)
		(property "Value" ""
			(at 0 0 0)
			(layer "F.Fab")
			(effects
				(font
					(size 1.27 1.27)
				)
			)
		)
		(duplicate_pad_numbers_are_jumpers no)
		(fp_line
			(start -0.7874 -0.4064)
			(end 0.7874 -0.4064)
			(stroke
				(width 0.1524)
				(type default)
			)
			(layer "F.SilkS")
		)
		(fp_line
			(start -0.7874 0.4064)
			(end -0.7874 -0.4064)
			(stroke
				(width 0.1524)
				(type default)
			)
			(layer "F.SilkS")
		)
		(fp_line
			(start 0.7874 -0.4064)
			(end 0.7874 0.4064)
			(stroke
				(width 0.1524)
				(type default)
			)
			(layer "F.SilkS")
		)
		(fp_line
			(start 0.7874 0.4064)
			(end -0.7874 0.4064)
			(stroke
				(width 0.1524)
				(type default)
			)
			(layer "F.SilkS")
		)
		(fp_line
			(start -0.67945 -0.305054)
			(end -0.12065 -0.305054)
			(stroke
				(width 0.1)
				(type default)
			)
			(layer "F.Fab")
		)
		(fp_line
			(start -0.67945 0.3048)
			(end -0.67945 -0.305054)
			(stroke
				(width 0.1)
				(type default)
			)
			(layer "F.Fab")
		)
		(fp_line
			(start -0.12065 -0.305054)
			(end -0.12065 -0.2794)
			(stroke
				(width 0.1)
				(type default)
			)
			(layer "F.Fab")
		)
		(fp_line
			(start -0.12065 -0.2794)
			(end 0.12065 -0.2794)
			(stroke
				(width 0.1)
				(type default)
			)
			(layer "F.Fab")
		)
		(fp_line
			(start -0.12065 0.2794)
			(end -0.12065 0.3048)
			(stroke
				(width 0.1)
				(type default)
			)
			(layer "F.Fab")
		)
		(fp_line
			(start -0.12065 0.3048)
			(end -0.67945 0.3048)
			(stroke
				(width 0.1)
				(type default)
			)
			(layer "F.Fab")
		)
		(fp_line
			(start 0.120396 0.2794)
			(end -0.12065 0.2794)
			(stroke
				(width 0.1)
				(type default)
			)
			(layer "F.Fab")
		)
		(fp_line
			(start 0.120396 0.3048)
			(end 0.120396 0.2794)
			(stroke
				(width 0.1)
				(type default)
			)
			(layer "F.Fab")
		)
		(fp_line
			(start 0.12065 -0.3048)
			(end 0.67945 -0.3048)
			(stroke
				(width 0.1)
				(type default)
			)
			(layer "F.Fab")
		)
		(fp_line
			(start 0.12065 -0.2794)
			(end 0.12065 -0.3048)
			(stroke
				(width 0.1)
				(type default)
			)
			(layer "F.Fab")
		)
		(fp_line
			(start 0.67945 -0.3048)
			(end 0.67945 0.3048)
			(stroke
				(width 0.1)
				(type default)
			)
			(layer "F.Fab")
		)
		(fp_line
			(start 0.67945 0.3048)
			(end 0.120396 0.3048)
			(stroke
				(width 0.1)
				(type default)
			)
			(layer "F.Fab")
		)
		(pad "1" smd circle
			(at -0.40005 0)
			(size 0 0)
			(layers "F.Cu" "F.Mask" "F.Paste")
			(net "SMB_LM75_0_3V3AUX_SCL")
		)
		(pad "2" smd circle
			(at 0.40005 0)
			(size 0 0)
			(layers "F.Cu" "F.Mask" "F.Paste")
			(net "SMB_LM75_0_3V3AUX_SCL_R1")
		)
	)
	(footprint ""
		(layer "F.Cu")
		(at 309.57774 -433.12461 90)
		(property "Reference" "R4130"
			(at 0 0 90)
			(layer "F.SilkS")
			(hide yes)
			(effects
				(font
					(size 1.27 1.27)
				)
			)
		)
		(property "Value" ""
			(at 0 0 90)
			(layer "F.Fab")
			(effects
				(font
					(size 1.27 1.27)
				)
			)
		)
		(duplicate_pad_numbers_are_jumpers no)
		(fp_line
			(start 0.7874 -0.4064)
			(end 0.7874 0.4064)
			(stroke
				(width 0.1524)
				(type default)
			)
			(layer "F.SilkS")
		)
		(fp_line
			(start -0.7874 -0.4064)
			(end 0.7874 -0.4064)
			(stroke
				(width 0.1524)
				(type default)
			)
			(layer "F.SilkS")
		)
		(fp_line
			(start 0.7874 0.4064)
			(end -0.7874 0.4064)
			(stroke
				(width 0.1524)
				(type default)
			)
			(layer "F.SilkS")
		)
		(fp_line
			(start -0.7874 0.4064)
			(end -0.7874 -0.4064)
			(stroke
				(width 0.1524)
				(type default)
			)
			(layer "F.SilkS")
		)
		(fp_line
			(start -0.12065 -0.305054)
			(end -0.12065 -0.2794)
			(stroke
				(width 0.1)
				(type default)
			)
			(layer "F.Fab")
		)
		(fp_line
			(start -0.67945 -0.305054)
			(end -0.12065 -0.305054)
			(stroke
				(width 0.1)
				(type default)
			)
			(layer "F.Fab")
		)
		(fp_line
			(start 0.67945 -0.3048)
			(end 0.67945 0.3048)
			(stroke
				(width 0.1)
				(type default)
			)
			(layer "F.Fab")
		)
		(fp_line
			(start 0.12065 -0.3048)
			(end 0.67945 -0.3048)
			(stroke
				(width 0.1)
				(type default)
			)
			(layer "F.Fab")
		)
		(fp_line
			(start 0.12065 -0.2794)
			(end 0.12065 -0.3048)
			(stroke
				(width 0.1)
				(type default)
			)
			(layer "F.Fab")
		)
		(fp_line
			(start -0.12065 -0.2794)
			(end 0.12065 -0.2794)
			(stroke
				(width 0.1)
				(type default)
			)
			(layer "F.Fab")
		)
		(fp_line
			(start 0.120396 0.2794)
			(end -0.12065 0.2794)
			(stroke
				(width 0.1)
				(type default)
			)
			(layer "F.Fab")
		)
		(fp_line
			(start -0.12065 0.2794)
			(end -0.12065 0.3048)
			(stroke
				(width 0.1)
				(type default)
			)
			(layer "F.Fab")
		)
		(fp_line
			(start 0.67945 0.3048)
			(end 0.120396 0.3048)
			(stroke
				(width 0.1)
				(type default)
			)
			(layer "F.Fab")
		)
		(fp_line
			(start 0.120396 0.3048)
			(end 0.120396 0.2794)
			(stroke
				(width 0.1)
				(type default)
			)
			(layer "F.Fab")
		)
		(fp_line
			(start -0.12065 0.3048)
			(end -0.67945 0.3048)
			(stroke
				(width 0.1)
				(type default)
			)
			(layer "F.Fab")
		)
		(fp_line
			(start -0.67945 0.3048)
			(end -0.67945 -0.305054)
			(stroke
				(width 0.1)
				(type default)
			)
			(layer "F.Fab")
		)
		(pad "1" smd circle
			(at -0.40005 0 90)
			(size 0 0)
			(layers "F.Cu" "F.Mask" "F.Paste")
			(net "P3V3_AUX")
		)
		(pad "2" smd circle
			(at 0.40005 0 90)
			(size 0 0)
			(layers "F.Cu" "F.Mask" "F.Paste")
			(net "GPU_3V3IO_RSVD1_FFU_ISO")
		)
	)
	(footprint ""
		(layer "F.Cu")
		(at 240.60785 -248.515378 -90)
		(property "Reference" "C2255"
			(at 0 0 270)
			(layer "F.SilkS")
			(hide yes)
			(effects
				(font
					(size 1.27 1.27)
				)
			)
		)
		(property "Value" ""
			(at 0 0 270)
			(layer "F.Fab")
			(effects
				(font
					(size 1.27 1.27)
				)
			)
		)
		(duplicate_pad_numbers_are_jumpers no)
		(fp_line
			(start -0.7874 0.4064)
			(end -0.7874 -0.4064)
			(stroke
				(width 0.1524)
				(type default)
			)
			(layer "F.SilkS")
		)
		(fp_line
			(start 0.7874 0.4064)
			(end -0.7874 0.4064)
			(stroke
				(width 0.1524)
				(type default)
			)
			(layer "F.SilkS")
		)
		(fp_line
			(start -0.7874 -0.4064)
			(end 0.7874 -0.4064)
			(stroke
				(width 0.1524)
				(type default)
			)
			(layer "F.SilkS")
		)
		(fp_line
			(start 0.7874 -0.4064)
			(end 0.7874 0.4064)
			(stroke
				(width 0.1524)
				(type default)
			)
			(layer "F.SilkS")
		)
		(fp_line
			(start -0.67945 0.3048)
			(end -0.67945 -0.305054)
			(stroke
				(width 0.1)
				(type default)
			)
			(layer "F.Fab")
		)
		(fp_line
			(start -0.12065 0.3048)
			(end -0.67945 0.3048)
			(stroke
				(width 0.1)
				(type default)
			)
			(layer "F.Fab")
		)
		(fp_line
			(start 0.120396 0.3048)
			(end 0.120396 0.2794)
			(stroke
				(width 0.1)
				(type default)
			)
			(layer "F.Fab")
		)
		(fp_line
			(start 0.67945 0.3048)
			(end 0.120396 0.3048)
			(stroke
				(width 0.1)
				(type default)
			)
			(layer "F.Fab")
		)
		(fp_line
			(start -0.12065 0.2794)
			(end -0.12065 0.3048)
			(stroke
				(width 0.1)
				(type default)
			)
			(layer "F.Fab")
		)
		(fp_line
			(start 0.120396 0.2794)
			(end -0.12065 0.2794)
			(stroke
				(width 0.1)
				(type default)
			)
			(layer "F.Fab")
		)
		(fp_line
			(start -0.12065 -0.2794)
			(end 0.12065 -0.2794)
			(stroke
				(width 0.1)
				(type default)
			)
			(layer "F.Fab")
		)
		(fp_line
			(start 0.12065 -0.2794)
			(end 0.12065 -0.3048)
			(stroke
				(width 0.1)
				(type default)
			)
			(layer "F.Fab")
		)
		(fp_line
			(start 0.12065 -0.3048)
			(end 0.67945 -0.3048)
			(stroke
				(width 0.1)
				(type default)
			)
			(layer "F.Fab")
		)
		(fp_line
			(start 0.67945 -0.3048)
			(end 0.67945 0.3048)
			(stroke
				(width 0.1)
				(type default)
			)
			(layer "F.Fab")
		)
		(fp_line
			(start -0.67945 -0.305054)
			(end -0.12065 -0.305054)
			(stroke
				(width 0.1)
				(type default)
			)
			(layer "F.Fab")
		)
		(fp_line
			(start -0.12065 -0.305054)
			(end -0.12065 -0.2794)
			(stroke
				(width 0.1)
				(type default)
			)
			(layer "F.Fab")
		)
		(pad "1" smd circle
			(at -0.40005 0 270)
			(size 0 0)
			(layers "F.Cu" "F.Mask" "F.Paste")
			(net "CLK_GEN2_XTAL_IN_R")
		)
		(pad "2" smd circle
			(at 0.40005 0 270)
			(size 0 0)
			(layers "F.Cu" "F.Mask" "F.Paste")
			(net "GND")
		)
	)
	(footprint ""
		(layer "F.Cu")
		(at 134.2136 -124.234448)
		(property "Reference" "R3149"
			(at 0 0 0)
			(layer "F.SilkS")
			(hide yes)
			(effects
				(font
					(size 1.27 1.27)
				)
			)
		)
		(property "Value" ""
			(at 0 0 0)
			(layer "F.Fab")
			(effects
				(font
					(size 1.27 1.27)
				)
			)
		)
		(duplicate_pad_numbers_are_jumpers no)
		(fp_line
			(start -0.7874 -0.4064)
			(end 0.7874 -0.4064)
			(stroke
				(width 0.1524)
				(type default)
			)
			(layer "F.SilkS")
		)
		(fp_line
			(start -0.7874 0.4064)
			(end -0.7874 -0.4064)
			(stroke
				(width 0.1524)
				(type default)
			)
			(layer "F.SilkS")
		)
		(fp_line
			(start 0.7874 -0.4064)
			(end 0.7874 0.4064)
			(stroke
				(width 0.1524)
				(type default)
			)
			(layer "F.SilkS")
		)
		(fp_line
			(start 0.7874 0.4064)
			(end -0.7874 0.4064)
			(stroke
				(width 0.1524)
				(type default)
			)
			(layer "F.SilkS")
		)
		(fp_line
			(start -0.67945 -0.305054)
			(end -0.12065 -0.305054)
			(stroke
				(width 0.1)
				(type default)
			)
			(layer "F.Fab")
		)
		(fp_line
			(start -0.67945 0.3048)
			(end -0.67945 -0.305054)
			(stroke
				(width 0.1)
				(type default)
			)
			(layer "F.Fab")
		)
		(fp_line
			(start -0.12065 -0.305054)
			(end -0.12065 -0.2794)
			(stroke
				(width 0.1)
				(type default)
			)
			(layer "F.Fab")
		)
		(fp_line
			(start -0.12065 -0.2794)
			(end 0.12065 -0.2794)
			(stroke
				(width 0.1)
				(type default)
			)
			(layer "F.Fab")
		)
		(fp_line
			(start -0.12065 0.2794)
			(end -0.12065 0.3048)
			(stroke
				(width 0.1)
				(type default)
			)
			(layer "F.Fab")
		)
		(fp_line
			(start -0.12065 0.3048)
			(end -0.67945 0.3048)
			(stroke
				(width 0.1)
				(type default)
			)
			(layer "F.Fab")
		)
		(fp_line
			(start 0.120396 0.2794)
			(end -0.12065 0.2794)
			(stroke
				(width 0.1)
				(type default)
			)
			(layer "F.Fab")
		)
		(fp_line
			(start 0.120396 0.3048)
			(end 0.120396 0.2794)
			(stroke
				(width 0.1)
				(type default)
			)
			(layer "F.Fab")
		)
		(fp_line
			(start 0.12065 -0.3048)
			(end 0.67945 -0.3048)
			(stroke
				(width 0.1)
				(type default)
			)
			(layer "F.Fab")
		)
		(fp_line
			(start 0.12065 -0.2794)
			(end 0.12065 -0.3048)
			(stroke
				(width 0.1)
				(type default)
			)
			(layer "F.Fab")
		)
		(fp_line
			(start 0.67945 -0.3048)
			(end 0.67945 0.3048)
			(stroke
				(width 0.1)
				(type default)
			)
			(layer "F.Fab")
		)
		(fp_line
			(start 0.67945 0.3048)
			(end 0.120396 0.3048)
			(stroke
				(width 0.1)
				(type default)
			)
			(layer "F.Fab")
		)
		(pad "1" smd circle
			(at -0.40005 0)
			(size 0 0)
			(layers "F.Cu" "F.Mask" "F.Paste")
			(net "P3V3_AUX")
		)
		(pad "2" smd circle
			(at 0.40005 0)
			(size 0 0)
			(layers "F.Cu" "F.Mask" "F.Paste")
			(net "PD_SMB_OCP2_HP_ADD2")
		)
	)
	(footprint ""
		(layer "F.Cu")
		(at 54.89956 -156.47797 90)
		(property "Reference" "PU50_P1_1"
			(at -0.83312 -13.79728 0)
			(unlocked yes)
			(layer "F.SilkS")
			(effects
				(font
					(size 0.7874 0.5842)
					(thickness 0.1524)
				)
				(justify left)
			)
		)
		(property "Value" ""
			(at 0 0 90)
			(layer "F.Fab")
			(effects
				(font
					(size 1.27 1.27)
				)
			)
		)
		(duplicate_pad_numbers_are_jumpers no)
		(fp_line
			(start 2.500122 -2.999994)
			(end 2.500122 -2.44348)
			(stroke
				(width 0.1524)
				(type default)
			)
			(layer "F.SilkS")
		)
		(fp_line
			(start 2.31394 -2.999994)
			(end 2.500122 -2.999994)
			(stroke
				(width 0.1524)
				(type default)
			)
			(layer "F.SilkS")
		)
		(fp_line
			(start -2.500122 -2.999994)
			(end -2.24409 -2.999994)
			(stroke
				(width 0.1524)
				(type default)
			)
			(layer "F.SilkS")
		)
		(fp_line
			(start -2.500122 -2.529078)
			(end -2.500122 -2.999994)
			(stroke
				(width 0.1524)
				(type default)
			)
			(layer "F.SilkS")
		)
		(fp_line
			(start -2.500122 0.6604)
			(end -2.500122 0.229108)
			(stroke
				(width 0.1524)
				(type default)
			)
			(layer "F.SilkS")
		)
		(fp_line
			(start 2.500122 2.339594)
			(end 2.500122 2.999994)
			(stroke
				(width 0.1524)
				(type default)
			)
			(layer "F.SilkS")
		)
		(fp_line
			(start 2.500122 2.999994)
			(end 2.2987 2.999994)
			(stroke
				(width 0.1524)
				(type default)
			)
			(layer "F.SilkS")
		)
		(fp_line
			(start -2.2987 2.999994)
			(end -2.500122 2.999994)
			(stroke
				(width 0.1524)
				(type default)
			)
			(layer "F.SilkS")
		)
		(fp_line
			(start -2.500122 2.999994)
			(end -2.500122 2.339594)
			(stroke
				(width 0.1524)
				(type default)
			)
			(layer "F.SilkS")
		)
		(fp_poly
			(pts
				(xy -5.109972 -2.793238) (xy -5.109972 -1.777238) (xy -4.093972 -2.285238)
			)
			(stroke
				(width 0)
				(type default)
			)
			(fill yes)
			(layer "F.SilkS")
		)
		(fp_line
			(start 2.500122 -2.999994)
			(end 2.500122 2.999994)
			(stroke
				(width 0.1)
				(type default)
			)
			(layer "F.Fab")
		)
		(fp_line
			(start -2.500122 -2.999994)
			(end 2.500122 -2.999994)
			(stroke
				(width 0.1)
				(type default)
			)
			(layer "F.Fab")
		)
		(fp_line
			(start 2.500122 2.999994)
			(end -2.500122 2.999994)
			(stroke
				(width 0.1)
				(type default)
			)
			(layer "F.Fab")
		)
		(fp_line
			(start -2.500122 2.999994)
			(end -2.500122 -2.999994)
			(stroke
				(width 0.1)
				(type default)
			)
			(layer "F.Fab")
		)
		(fp_poly
			(pts
				(xy -4.218432 -2.783078) (xy -4.218432 -1.767078) (xy -3.202432 -2.275078)
			)
			(stroke
				(width 0)
				(type default)
			)
			(fill yes)
			(layer "F.Fab")
		)
		(pad "1" smd rect
			(at -2.400046 -2.275078 180)
			(size 0.2286 0.6096)
			(layers "F.Cu" "F.Mask" "F.Paste")
			(net "PVCCINFAON_CPU1_VOS1")
		)
		(pad "2" smd rect
			(at -2.400046 -1.82499 180)
			(size 0.2286 0.6096)
			(layers "F.Cu" "F.Mask" "F.Paste")
			(net "GND")
		)
		(pad "3" smd rect
			(at -2.400046 -1.374902 180)
			(size 0.2286 0.6096)
			(layers "F.Cu" "F.Mask" "F.Paste")
			(net "PVCCINFAON_CPU1_VDD1")
		)
		(pad "4" smd rect
			(at -2.400046 -0.925068 180)
			(size 0.2286 0.6096)
			(layers "F.Cu" "F.Mask" "F.Paste")
			(net "PVCCFA_EHV_CPU1_PVCC")
		)
		(pad "5" smd rect
			(at -2.400046 -0.47498 180)
			(size 0.2286 0.6096)
			(layers "F.Cu" "F.Mask" "F.Paste")
			(net "GND")
		)
		(pad "6" smd rect
			(at -2.400046 -0.024892 180)
			(size 0.2286 0.6096)
			(layers "F.Cu" "F.Mask" "F.Paste")
			(net "Net_1929")
		)
		(pad "7_9-20_24" smd circle
			(at 0 1.150112 180)
			(size 0 0)
			(layers "F.Cu" "F.Mask" "F.Paste")
			(net "GND")
		)
		(pad "10_19" smd rect
			(at 0 2.899918 180)
			(size 0.6096 4.318)
			(layers "F.Cu" "F.Mask" "F.Paste")
			(net "SW_PVCCINFAON_CPU1_SW1")
		)
		(pad "25_29" smd rect
			(at 1.549908 -1.279906)
			(size 2.0574 2.3114)
			(layers "F.Cu" "F.Mask" "F.Paste")
			(net "SW_P12V_PVCCINFAON_CPU1_FLT")
		)
		(pad "30" smd rect
			(at 2.05994 -2.899918 90)
			(size 0.2286 0.6096)
			(layers "F.Cu" "F.Mask" "F.Paste")
			(net "SW_P12V_PVCCINFAON_CPU1_FLT")
		)
		(pad "31" smd rect
			(at 1.610106 -2.899918 90)
			(size 0.2286 0.6096)
			(layers "F.Cu" "F.Mask" "F.Paste")
			(net "Net_1928")
		)
		(pad "32" smd rect
			(at 1.160018 -2.899918 90)
			(size 0.2286 0.6096)
			(layers "F.Cu" "F.Mask" "F.Paste")
			(net "SW_PVCCINFAON_CPU1_BOOTR1")
		)
		(pad "33" smd rect
			(at 0.70993 -2.899918 90)
			(size 0.2286 0.6096)
			(layers "F.Cu" "F.Mask" "F.Paste")
			(net "SW_PVCCINFAON_CPU1_BOOT1")
		)
		(pad "34" smd rect
			(at 0.260096 -2.899918 90)
			(size 0.2286 0.6096)
			(layers "F.Cu" "F.Mask" "F.Paste")
			(net "PVCCINFAON_CPU1_APWM1")
		)
		(pad "35" smd rect
			(at -0.189992 -2.899918 90)
			(size 0.2286 0.6096)
			(layers "F.Cu" "F.Mask" "F.Paste")
			(net "PVCCINFAON_CPU1_VDD1")
		)
		(pad "36" smd rect
			(at -0.64008 -2.899918 90)
			(size 0.2286 0.6096)
			(layers "F.Cu" "F.Mask" "F.Paste")
			(net "PVCCINFAON_CPU1_ATSEN")
		)
		(pad "37" smd rect
			(at -1.089914 -2.899918 90)
			(size 0.2286 0.6096)
			(layers "F.Cu" "F.Mask" "F.Paste")
			(net "PVCCINFAON_CPU1_LSET1")
		)
		(pad "38" smd rect
			(at -1.540002 -2.899918 90)
			(size 0.2286 0.6096)
			(layers "F.Cu" "F.Mask" "F.Paste")
			(net "PVCCINFAON_CPU1_ACSP1")
		)
		(pad "39" smd rect
			(at -1.99009 -2.899918 90)
			(size 0.2286 0.6096)
			(layers "F.Cu" "F.Mask" "F.Paste")
			(net "PVCCINFAON_CPU1_VREF")
		)
		(pad "40" smd rect
			(at -0.87503 -1.27508 90)
			(size 1.7526 1.9558)
			(layers "F.Cu" "F.Mask" "F.Paste")
			(net "GND")
		)
		(pad "41" smd rect
			(at -1.525016 0.249936)
			(size 0.3048 0.4572)
			(layers "F.Cu" "F.Mask" "F.Paste")
			(net "Net_1930")
		)
		(zone
			(layer "F.Cu")
			(hatch none 0.5)
			(connect_pads
				(clearance 0)
			)
			(min_thickness 0.25)
			(keepout
				(tracks not_allowed)
				(vias allowed)
				(pads allowed)
				(copperpour not_allowed)
				(footprints allowed)
			)
			(placement
				(enabled no)
				(sheetname "")
			)
			(fill
				(thermal_gap 0.5)
				(thermal_bridge_width 0.5)
				(island_removal_mode 0)
			)
			(polygon
				(pts
					(xy 57.899554 -153.977848) (xy 57.391046 -153.977848) (xy 57.150254 -154.21864) (xy 57.150254 -158.767526)
					(xy 57.36082 -158.978092) (xy 57.899554 -158.978092) (xy 57.899554 -158.68777) (xy 57.443878 -158.68777)
					(xy 57.443878 -154.26817) (xy 57.899554 -154.26817)
				)
			)
		)
	)
	(footprint ""
		(layer "F.Cu")
		(at 283.413708 -411.29458 -90)
		(property "Reference" "R4557"
			(at 0 0 270)
			(layer "F.SilkS")
			(hide yes)
			(effects
				(font
					(size 1.27 1.27)
				)
			)
		)
		(property "Value" ""
			(at 0 0 270)
			(layer "F.Fab")
			(effects
				(font
					(size 1.27 1.27)
				)
			)
		)
		(duplicate_pad_numbers_are_jumpers no)
		(fp_line
			(start -0.7874 0.4064)
			(end -0.7874 -0.4064)
			(stroke
				(width 0.1524)
				(type default)
			)
			(layer "F.SilkS")
		)
		(fp_line
			(start 0.7874 0.4064)
			(end -0.7874 0.4064)
			(stroke
				(width 0.1524)
				(type default)
			)
			(layer "F.SilkS")
		)
		(fp_line
			(start -0.7874 -0.4064)
			(end 0.7874 -0.4064)
			(stroke
				(width 0.1524)
				(type default)
			)
			(layer "F.SilkS")
		)
		(fp_line
			(start 0.7874 -0.4064)
			(end 0.7874 0.4064)
			(stroke
				(width 0.1524)
				(type default)
			)
			(layer "F.SilkS")
		)
		(fp_line
			(start -0.67945 0.3048)
			(end -0.67945 -0.305054)
			(stroke
				(width 0.1)
				(type default)
			)
			(layer "F.Fab")
		)
		(fp_line
			(start -0.12065 0.3048)
			(end -0.67945 0.3048)
			(stroke
				(width 0.1)
				(type default)
			)
			(layer "F.Fab")
		)
		(fp_line
			(start 0.120396 0.3048)
			(end 0.120396 0.2794)
			(stroke
				(width 0.1)
				(type default)
			)
			(layer "F.Fab")
		)
		(fp_line
			(start 0.67945 0.3048)
			(end 0.120396 0.3048)
			(stroke
				(width 0.1)
				(type default)
			)
			(layer "F.Fab")
		)
		(fp_line
			(start -0.12065 0.2794)
			(end -0.12065 0.3048)
			(stroke
				(width 0.1)
				(type default)
			)
			(layer "F.Fab")
		)
		(fp_line
			(start 0.120396 0.2794)
			(end -0.12065 0.2794)
			(stroke
				(width 0.1)
				(type default)
			)
			(layer "F.Fab")
		)
		(fp_line
			(start -0.12065 -0.2794)
			(end 0.12065 -0.2794)
			(stroke
				(width 0.1)
				(type default)
			)
			(layer "F.Fab")
		)
		(fp_line
			(start 0.12065 -0.2794)
			(end 0.12065 -0.3048)
			(stroke
				(width 0.1)
				(type default)
			)
			(layer "F.Fab")
		)
		(fp_line
			(start 0.12065 -0.3048)
			(end 0.67945 -0.3048)
			(stroke
				(width 0.1)
				(type default)
			)
			(layer "F.Fab")
		)
		(fp_line
			(start 0.67945 -0.3048)
			(end 0.67945 0.3048)
			(stroke
				(width 0.1)
				(type default)
			)
			(layer "F.Fab")
		)
		(fp_line
			(start -0.67945 -0.305054)
			(end -0.12065 -0.305054)
			(stroke
				(width 0.1)
				(type default)
			)
			(layer "F.Fab")
		)
		(fp_line
			(start -0.12065 -0.305054)
			(end -0.12065 -0.2794)
			(stroke
				(width 0.1)
				(type default)
			)
			(layer "F.Fab")
		)
		(pad "1" smd circle
			(at -0.40005 0 270)
			(size 0 0)
			(layers "F.Cu" "F.Mask" "F.Paste")
			(net "HPDB_HSC_PWRGD_ISO")
		)
		(pad "2" smd circle
			(at 0.40005 0 270)
			(size 0 0)
			(layers "F.Cu" "F.Mask" "F.Paste")
			(net "HPDB_HSC_PWRGD_ISO_R")
		)
	)
	(footprint ""
		(layer "F.Cu")
		(at 301.136304 -426.478446 -90)
		(property "Reference" "R4126"
			(at 0 0 270)
			(layer "F.SilkS")
			(hide yes)
			(effects
				(font
					(size 1.27 1.27)
				)
			)
		)
		(property "Value" ""
			(at 0 0 270)
			(layer "F.Fab")
			(effects
				(font
					(size 1.27 1.27)
				)
			)
		)
		(duplicate_pad_numbers_are_jumpers no)
		(fp_line
			(start -0.7874 0.4064)
			(end -0.7874 -0.4064)
			(stroke
				(width 0.1524)
				(type default)
			)
			(layer "F.SilkS")
		)
		(fp_line
			(start 0.7874 0.4064)
			(end -0.7874 0.4064)
			(stroke
				(width 0.1524)
				(type default)
			)
			(layer "F.SilkS")
		)
		(fp_line
			(start -0.7874 -0.4064)
			(end 0.7874 -0.4064)
			(stroke
				(width 0.1524)
				(type default)
			)
			(layer "F.SilkS")
		)
		(fp_line
			(start 0.7874 -0.4064)
			(end 0.7874 0.4064)
			(stroke
				(width 0.1524)
				(type default)
			)
			(layer "F.SilkS")
		)
		(fp_line
			(start -0.67945 0.3048)
			(end -0.67945 -0.305054)
			(stroke
				(width 0.1)
				(type default)
			)
			(layer "F.Fab")
		)
		(fp_line
			(start -0.12065 0.3048)
			(end -0.67945 0.3048)
			(stroke
				(width 0.1)
				(type default)
			)
			(layer "F.Fab")
		)
		(fp_line
			(start 0.120396 0.3048)
			(end 0.120396 0.2794)
			(stroke
				(width 0.1)
				(type default)
			)
			(layer "F.Fab")
		)
		(fp_line
			(start 0.67945 0.3048)
			(end 0.120396 0.3048)
			(stroke
				(width 0.1)
				(type default)
			)
			(layer "F.Fab")
		)
		(fp_line
			(start -0.12065 0.2794)
			(end -0.12065 0.3048)
			(stroke
				(width 0.1)
				(type default)
			)
			(layer "F.Fab")
		)
		(fp_line
			(start 0.120396 0.2794)
			(end -0.12065 0.2794)
			(stroke
				(width 0.1)
				(type default)
			)
			(layer "F.Fab")
		)
		(fp_line
			(start -0.12065 -0.2794)
			(end 0.12065 -0.2794)
			(stroke
				(width 0.1)
				(type default)
			)
			(layer "F.Fab")
		)
		(fp_line
			(start 0.12065 -0.2794)
			(end 0.12065 -0.3048)
			(stroke
				(width 0.1)
				(type default)
			)
			(layer "F.Fab")
		)
		(fp_line
			(start 0.12065 -0.3048)
			(end 0.67945 -0.3048)
			(stroke
				(width 0.1)
				(type default)
			)
			(layer "F.Fab")
		)
		(fp_line
			(start 0.67945 -0.3048)
			(end 0.67945 0.3048)
			(stroke
				(width 0.1)
				(type default)
			)
			(layer "F.Fab")
		)
		(fp_line
			(start -0.67945 -0.305054)
			(end -0.12065 -0.305054)
			(stroke
				(width 0.1)
				(type default)
			)
			(layer "F.Fab")
		)
		(fp_line
			(start -0.12065 -0.305054)
			(end -0.12065 -0.2794)
			(stroke
				(width 0.1)
				(type default)
			)
			(layer "F.Fab")
		)
		(pad "1" smd circle
			(at -0.40005 0 270)
			(size 0 0)
			(layers "F.Cu" "F.Mask" "F.Paste")
			(net "P3V3_AUX")
		)
		(pad "2" smd circle
			(at 0.40005 0 270)
			(size 0 0)
			(layers "F.Cu" "F.Mask" "F.Paste")
			(net "PRSNT_CABLE_GPU_B3")
		)
	)
	(footprint ""
		(layer "F.Cu")
		(at 145.34388 -42.446448)
		(property "Reference" "R3295"
			(at 0 0 0)
			(layer "F.SilkS")
			(hide yes)
			(effects
				(font
					(size 1.27 1.27)
				)
			)
		)
		(property "Value" ""
			(at 0 0 0)
			(layer "F.Fab")
			(effects
				(font
					(size 1.27 1.27)
				)
			)
		)
		(duplicate_pad_numbers_are_jumpers no)
		(fp_line
			(start -0.7874 -0.4064)
			(end 0.7874 -0.4064)
			(stroke
				(width 0.1524)
				(type default)
			)
			(layer "F.SilkS")
		)
		(fp_line
			(start -0.7874 0.4064)
			(end -0.7874 -0.4064)
			(stroke
				(width 0.1524)
				(type default)
			)
			(layer "F.SilkS")
		)
		(fp_line
			(start 0.7874 -0.4064)
			(end 0.7874 0.4064)
			(stroke
				(width 0.1524)
				(type default)
			)
			(layer "F.SilkS")
		)
		(fp_line
			(start 0.7874 0.4064)
			(end -0.7874 0.4064)
			(stroke
				(width 0.1524)
				(type default)
			)
			(layer "F.SilkS")
		)
		(fp_line
			(start -0.67945 -0.305054)
			(end -0.12065 -0.305054)
			(stroke
				(width 0.1)
				(type default)
			)
			(layer "F.Fab")
		)
		(fp_line
			(start -0.67945 0.3048)
			(end -0.67945 -0.305054)
			(stroke
				(width 0.1)
				(type default)
			)
			(layer "F.Fab")
		)
		(fp_line
			(start -0.12065 -0.305054)
			(end -0.12065 -0.2794)
			(stroke
				(width 0.1)
				(type default)
			)
			(layer "F.Fab")
		)
		(fp_line
			(start -0.12065 -0.2794)
			(end 0.12065 -0.2794)
			(stroke
				(width 0.1)
				(type default)
			)
			(layer "F.Fab")
		)
		(fp_line
			(start -0.12065 0.2794)
			(end -0.12065 0.3048)
			(stroke
				(width 0.1)
				(type default)
			)
			(layer "F.Fab")
		)
		(fp_line
			(start -0.12065 0.3048)
			(end -0.67945 0.3048)
			(stroke
				(width 0.1)
				(type default)
			)
			(layer "F.Fab")
		)
		(fp_line
			(start 0.120396 0.2794)
			(end -0.12065 0.2794)
			(stroke
				(width 0.1)
				(type default)
			)
			(layer "F.Fab")
		)
		(fp_line
			(start 0.120396 0.3048)
			(end 0.120396 0.2794)
			(stroke
				(width 0.1)
				(type default)
			)
			(layer "F.Fab")
		)
		(fp_line
			(start 0.12065 -0.3048)
			(end 0.67945 -0.3048)
			(stroke
				(width 0.1)
				(type default)
			)
			(layer "F.Fab")
		)
		(fp_line
			(start 0.12065 -0.2794)
			(end 0.12065 -0.3048)
			(stroke
				(width 0.1)
				(type default)
			)
			(layer "F.Fab")
		)
		(fp_line
			(start 0.67945 -0.3048)
			(end 0.67945 0.3048)
			(stroke
				(width 0.1)
				(type default)
			)
			(layer "F.Fab")
		)
		(fp_line
			(start 0.67945 0.3048)
			(end 0.120396 0.3048)
			(stroke
				(width 0.1)
				(type default)
			)
			(layer "F.Fab")
		)
		(pad "1" smd circle
			(at -0.40005 0)
			(size 0 0)
			(layers "F.Cu" "F.Mask" "F.Paste")
			(net "P3V3_M2_0")
		)
		(pad "2" smd circle
			(at 0.40005 0)
			(size 0 0)
			(layers "F.Cu" "F.Mask" "F.Paste")
			(net "LED_HDD_ACTIVITY_N")
		)
	)
	(footprint ""
		(layer "F.Cu")
		(at 149.959314 -408.517344 -90)
		(property "Reference" "C1535"
			(at 0 0 270)
			(layer "F.SilkS")
			(hide yes)
			(effects
				(font
					(size 1.27 1.27)
				)
			)
		)
		(property "Value" ""
			(at 0 0 270)
			(layer "F.Fab")
			(effects
				(font
					(size 1.27 1.27)
				)
			)
		)
		(duplicate_pad_numbers_are_jumpers no)
		(fp_line
			(start -0.299974 0.150114)
			(end -0.299974 -0.150114)
			(stroke
				(width 0.1)
				(type default)
			)
			(layer "F.Fab")
		)
		(fp_line
			(start 0.299974 0.150114)
			(end -0.299974 0.150114)
			(stroke
				(width 0.1)
				(type default)
			)
			(layer "F.Fab")
		)
		(fp_line
			(start -0.299974 -0.150114)
			(end 0.299974 -0.150114)
			(stroke
				(width 0.1)
				(type default)
			)
			(layer "F.Fab")
		)
		(fp_line
			(start 0.299974 -0.150114)
			(end 0.299974 0.150114)
			(stroke
				(width 0.1)
				(type default)
			)
			(layer "F.Fab")
		)
		(pad "1" smd rect
			(at -0.2667 0 270)
			(size 0.3048 0.381)
			(layers "F.Cu" "F.Mask" "F.Paste")
			(net "P5E_CPU1_PE3_TX_C_DP<6>")
		)
		(pad "2" smd rect
			(at 0.2667 0 270)
			(size 0.3048 0.381)
			(layers "F.Cu" "F.Mask" "F.Paste")
			(net "P5E_CPU1_PE3_TX_DP<6>")
		)
	)
	(footprint ""
		(layer "F.Cu")
		(at 159.267144 -52.851304 180)
		(property "Reference" "R3575"
			(at 0 0 180)
			(layer "F.SilkS")
			(hide yes)
			(effects
				(font
					(size 1.27 1.27)
				)
			)
		)
		(property "Value" ""
			(at 0 0 180)
			(layer "F.Fab")
			(effects
				(font
					(size 1.27 1.27)
				)
			)
		)
		(duplicate_pad_numbers_are_jumpers no)
		(fp_line
			(start 0.7874 0.4064)
			(end -0.7874 0.4064)
			(stroke
				(width 0.1524)
				(type default)
			)
			(layer "F.SilkS")
		)
		(fp_line
			(start 0.7874 -0.4064)
			(end 0.7874 0.4064)
			(stroke
				(width 0.1524)
				(type default)
			)
			(layer "F.SilkS")
		)
		(fp_line
			(start -0.7874 0.4064)
			(end -0.7874 -0.4064)
			(stroke
				(width 0.1524)
				(type default)
			)
			(layer "F.SilkS")
		)
		(fp_line
			(start -0.7874 -0.4064)
			(end 0.7874 -0.4064)
			(stroke
				(width 0.1524)
				(type default)
			)
			(layer "F.SilkS")
		)
		(fp_line
			(start 0.67945 0.3048)
			(end 0.120396 0.3048)
			(stroke
				(width 0.1)
				(type default)
			)
			(layer "F.Fab")
		)
		(fp_line
			(start 0.67945 -0.3048)
			(end 0.67945 0.3048)
			(stroke
				(width 0.1)
				(type default)
			)
			(layer "F.Fab")
		)
		(fp_line
			(start 0.12065 -0.2794)
			(end 0.12065 -0.3048)
			(stroke
				(width 0.1)
				(type default)
			)
			(layer "F.Fab")
		)
		(fp_line
			(start 0.12065 -0.3048)
			(end 0.67945 -0.3048)
			(stroke
				(width 0.1)
				(type default)
			)
			(layer "F.Fab")
		)
		(fp_line
			(start 0.120396 0.3048)
			(end 0.120396 0.2794)
			(stroke
				(width 0.1)
				(type default)
			)
			(layer "F.Fab")
		)
		(fp_line
			(start 0.120396 0.2794)
			(end -0.12065 0.2794)
			(stroke
				(width 0.1)
				(type default)
			)
			(layer "F.Fab")
		)
		(fp_line
			(start -0.12065 0.3048)
			(end -0.67945 0.3048)
			(stroke
				(width 0.1)
				(type default)
			)
			(layer "F.Fab")
		)
		(fp_line
			(start -0.12065 0.2794)
			(end -0.12065 0.3048)
			(stroke
				(width 0.1)
				(type default)
			)
			(layer "F.Fab")
		)
		(fp_line
			(start -0.12065 -0.2794)
			(end 0.12065 -0.2794)
			(stroke
				(width 0.1)
				(type default)
			)
			(layer "F.Fab")
		)
		(fp_line
			(start -0.12065 -0.305054)
			(end -0.12065 -0.2794)
			(stroke
				(width 0.1)
				(type default)
			)
			(layer "F.Fab")
		)
		(fp_line
			(start -0.67945 0.3048)
			(end -0.67945 -0.305054)
			(stroke
				(width 0.1)
				(type default)
			)
			(layer "F.Fab")
		)
		(fp_line
			(start -0.67945 -0.305054)
			(end -0.12065 -0.305054)
			(stroke
				(width 0.1)
				(type default)
			)
			(layer "F.Fab")
		)
		(pad "1" smd circle
			(at -0.40005 0 180)
			(size 0 0)
			(layers "F.Cu" "F.Mask" "F.Paste")
			(net "P3V3_M2_0")
		)
		(pad "2" smd circle
			(at 0.40005 0 180)
			(size 0 0)
			(layers "F.Cu" "F.Mask" "F.Paste")
			(net "VSENSE_P12V_INA230_4_INN")
		)
	)
	(footprint ""
		(layer "F.Cu")
		(at 303.523904 -32.462216)
		(property "Reference" "C611"
			(at 0 0 0)
			(layer "F.SilkS")
			(hide yes)
			(effects
				(font
					(size 1.27 1.27)
				)
			)
		)
		(property "Value" ""
			(at 0 0 0)
			(layer "F.Fab")
			(effects
				(font
					(size 1.27 1.27)
				)
			)
		)
		(duplicate_pad_numbers_are_jumpers no)
		(fp_line
			(start -0.7874 -0.4064)
			(end 0.7874 -0.4064)
			(stroke
				(width 0.1524)
				(type default)
			)
			(layer "F.SilkS")
		)
		(fp_line
			(start -0.7874 0.4064)
			(end -0.7874 -0.4064)
			(stroke
				(width 0.1524)
				(type default)
			)
			(layer "F.SilkS")
		)
		(fp_line
			(start 0.7874 -0.4064)
			(end 0.7874 0.4064)
			(stroke
				(width 0.1524)
				(type default)
			)
			(layer "F.SilkS")
		)
		(fp_line
			(start 0.7874 0.4064)
			(end -0.7874 0.4064)
			(stroke
				(width 0.1524)
				(type default)
			)
			(layer "F.SilkS")
		)
		(fp_line
			(start -0.67945 -0.305054)
			(end -0.12065 -0.305054)
			(stroke
				(width 0.1)
				(type default)
			)
			(layer "F.Fab")
		)
		(fp_line
			(start -0.67945 0.3048)
			(end -0.67945 -0.305054)
			(stroke
				(width 0.1)
				(type default)
			)
			(layer "F.Fab")
		)
		(fp_line
			(start -0.12065 -0.305054)
			(end -0.12065 -0.2794)
			(stroke
				(width 0.1)
				(type default)
			)
			(layer "F.Fab")
		)
		(fp_line
			(start -0.12065 -0.2794)
			(end 0.12065 -0.2794)
			(stroke
				(width 0.1)
				(type default)
			)
			(layer "F.Fab")
		)
		(fp_line
			(start -0.12065 0.2794)
			(end -0.12065 0.3048)
			(stroke
				(width 0.1)
				(type default)
			)
			(layer "F.Fab")
		)
		(fp_line
			(start -0.12065 0.3048)
			(end -0.67945 0.3048)
			(stroke
				(width 0.1)
				(type default)
			)
			(layer "F.Fab")
		)
		(fp_line
			(start 0.120396 0.2794)
			(end -0.12065 0.2794)
			(stroke
				(width 0.1)
				(type default)
			)
			(layer "F.Fab")
		)
		(fp_line
			(start 0.120396 0.3048)
			(end 0.120396 0.2794)
			(stroke
				(width 0.1)
				(type default)
			)
			(layer "F.Fab")
		)
		(fp_line
			(start 0.12065 -0.3048)
			(end 0.67945 -0.3048)
			(stroke
				(width 0.1)
				(type default)
			)
			(layer "F.Fab")
		)
		(fp_line
			(start 0.12065 -0.2794)
			(end 0.12065 -0.3048)
			(stroke
				(width 0.1)
				(type default)
			)
			(layer "F.Fab")
		)
		(fp_line
			(start 0.67945 -0.3048)
			(end 0.67945 0.3048)
			(stroke
				(width 0.1)
				(type default)
			)
			(layer "F.Fab")
		)
		(fp_line
			(start 0.67945 0.3048)
			(end 0.120396 0.3048)
			(stroke
				(width 0.1)
				(type default)
			)
			(layer "F.Fab")
		)
		(pad "1" smd circle
			(at -0.40005 0)
			(size 0 0)
			(layers "F.Cu" "F.Mask" "F.Paste")
			(net "P3V3_RTC_AUX")
		)
		(pad "2" smd circle
			(at 0.40005 0)
			(size 0 0)
			(layers "F.Cu" "F.Mask" "F.Paste")
			(net "GND")
		)
	)
	(footprint ""
		(layer "F.Cu")
		(at 429.272192 -164.780722 180)
		(property "Reference" "PL6"
			(at -2.44094 3.725164 0)
			(unlocked yes)
			(layer "F.SilkS")
			(effects
				(font
					(size 0.7874 0.5842)
					(thickness 0.1524)
				)
				(justify left)
			)
		)
		(property "Value" ""
			(at 0 0 180)
			(layer "F.Fab")
			(effects
				(font
					(size 1.27 1.27)
				)
			)
		)
		(duplicate_pad_numbers_are_jumpers no)
		(fp_line
			(start 2.249932 2.249932)
			(end -2.249932 2.249932)
			(stroke
				(width 0.1524)
				(type default)
			)
			(layer "F.SilkS")
		)
		(fp_line
			(start 2.249932 1.3843)
			(end 2.249932 2.249932)
			(stroke
				(width 0.1524)
				(type default)
			)
			(layer "F.SilkS")
		)
		(fp_line
			(start 2.249932 -2.249932)
			(end 2.249932 -1.3843)
			(stroke
				(width 0.1524)
				(type default)
			)
			(layer "F.SilkS")
		)
		(fp_line
			(start -2.249932 2.249932)
			(end -2.249932 1.3843)
			(stroke
				(width 0.1524)
				(type default)
			)
			(layer "F.SilkS")
		)
		(fp_line
			(start -2.249932 -1.3843)
			(end -2.249932 -2.249932)
			(stroke
				(width 0.1524)
				(type default)
			)
			(layer "F.SilkS")
		)
		(fp_line
			(start -2.249932 -2.249932)
			(end 2.249932 -2.249932)
			(stroke
				(width 0.1524)
				(type default)
			)
			(layer "F.SilkS")
		)
		(fp_line
			(start 2.249932 2.249932)
			(end -2.249932 2.249932)
			(stroke
				(width 0.1)
				(type default)
			)
			(layer "F.Fab")
		)
		(fp_line
			(start 2.249932 -2.249932)
			(end 2.249932 2.249932)
			(stroke
				(width 0.1)
				(type default)
			)
			(layer "F.Fab")
		)
		(fp_line
			(start -2.249932 2.249932)
			(end -2.249932 -2.249932)
			(stroke
				(width 0.1)
				(type default)
			)
			(layer "F.Fab")
		)
		(fp_line
			(start -2.249932 -2.249932)
			(end 2.249932 -2.249932)
			(stroke
				(width 0.1)
				(type default)
			)
			(layer "F.Fab")
		)
		(pad "1" smd rect
			(at -1.82499 0 180)
			(size 1.0668 2.5146)
			(layers "F.Cu" "F.Mask" "F.Paste")
			(net "P12V_AUX")
		)
		(pad "2" smd rect
			(at 1.82499 0 180)
			(size 1.0668 2.5146)
			(layers "F.Cu" "F.Mask" "F.Paste")
			(net "SW_P12V_PVCCINFAON_CPU0_FLT")
		)
	)
	(footprint ""
		(layer "F.Cu")
		(at 179.352448 -399.207482 180)
		(property "Reference" "PR1133"
			(at 0 0 180)
			(layer "F.SilkS")
			(hide yes)
			(effects
				(font
					(size 1.27 1.27)
				)
			)
		)
		(property "Value" ""
			(at 0 0 180)
			(layer "F.Fab")
			(effects
				(font
					(size 1.27 1.27)
				)
			)
		)
		(duplicate_pad_numbers_are_jumpers no)
		(fp_line
			(start 0.7874 0.4064)
			(end -0.7874 0.4064)
			(stroke
				(width 0.1524)
				(type default)
			)
			(layer "F.SilkS")
		)
		(fp_line
			(start 0.7874 -0.4064)
			(end 0.7874 0.4064)
			(stroke
				(width 0.1524)
				(type default)
			)
			(layer "F.SilkS")
		)
		(fp_line
			(start -0.7874 0.4064)
			(end -0.7874 -0.4064)
			(stroke
				(width 0.1524)
				(type default)
			)
			(layer "F.SilkS")
		)
		(fp_line
			(start -0.7874 -0.4064)
			(end 0.7874 -0.4064)
			(stroke
				(width 0.1524)
				(type default)
			)
			(layer "F.SilkS")
		)
		(fp_line
			(start 0.67945 0.3048)
			(end 0.120396 0.3048)
			(stroke
				(width 0.1)
				(type default)
			)
			(layer "F.Fab")
		)
		(fp_line
			(start 0.67945 -0.3048)
			(end 0.67945 0.3048)
			(stroke
				(width 0.1)
				(type default)
			)
			(layer "F.Fab")
		)
		(fp_line
			(start 0.12065 -0.2794)
			(end 0.12065 -0.3048)
			(stroke
				(width 0.1)
				(type default)
			)
			(layer "F.Fab")
		)
		(fp_line
			(start 0.12065 -0.3048)
			(end 0.67945 -0.3048)
			(stroke
				(width 0.1)
				(type default)
			)
			(layer "F.Fab")
		)
		(fp_line
			(start 0.120396 0.3048)
			(end 0.120396 0.2794)
			(stroke
				(width 0.1)
				(type default)
			)
			(layer "F.Fab")
		)
		(fp_line
			(start 0.120396 0.2794)
			(end -0.12065 0.2794)
			(stroke
				(width 0.1)
				(type default)
			)
			(layer "F.Fab")
		)
		(fp_line
			(start -0.12065 0.3048)
			(end -0.67945 0.3048)
			(stroke
				(width 0.1)
				(type default)
			)
			(layer "F.Fab")
		)
		(fp_line
			(start -0.12065 0.2794)
			(end -0.12065 0.3048)
			(stroke
				(width 0.1)
				(type default)
			)
			(layer "F.Fab")
		)
		(fp_line
			(start -0.12065 -0.2794)
			(end 0.12065 -0.2794)
			(stroke
				(width 0.1)
				(type default)
			)
			(layer "F.Fab")
		)
		(fp_line
			(start -0.12065 -0.305054)
			(end -0.12065 -0.2794)
			(stroke
				(width 0.1)
				(type default)
			)
			(layer "F.Fab")
		)
		(fp_line
			(start -0.67945 0.3048)
			(end -0.67945 -0.305054)
			(stroke
				(width 0.1)
				(type default)
			)
			(layer "F.Fab")
		)
		(fp_line
			(start -0.67945 -0.305054)
			(end -0.12065 -0.305054)
			(stroke
				(width 0.1)
				(type default)
			)
			(layer "F.Fab")
		)
		(pad "1" smd circle
			(at -0.40005 0 180)
			(size 0 0)
			(layers "F.Cu" "F.Mask" "F.Paste")
			(net "HSC_IMON")
		)
		(pad "2" smd circle
			(at 0.40005 0 180)
			(size 0 0)
			(layers "F.Cu" "F.Mask" "F.Paste")
			(net "AGND_HSC")
		)
	)
	(footprint ""
		(layer "F.Cu")
		(at 424.69816 -143.675608 90)
		(property "Reference" "PR4223"
			(at 0 0 90)
			(layer "F.SilkS")
			(hide yes)
			(effects
				(font
					(size 1.27 1.27)
				)
			)
		)
		(property "Value" ""
			(at 0 0 90)
			(layer "F.Fab")
			(effects
				(font
					(size 1.27 1.27)
				)
			)
		)
		(duplicate_pad_numbers_are_jumpers no)
		(fp_line
			(start 0.7874 -0.4064)
			(end 0.7874 0.4064)
			(stroke
				(width 0.1524)
				(type default)
			)
			(layer "F.SilkS")
		)
		(fp_line
			(start -0.7874 -0.4064)
			(end 0.7874 -0.4064)
			(stroke
				(width 0.1524)
				(type default)
			)
			(layer "F.SilkS")
		)
		(fp_line
			(start 0.7874 0.4064)
			(end -0.7874 0.4064)
			(stroke
				(width 0.1524)
				(type default)
			)
			(layer "F.SilkS")
		)
		(fp_line
			(start -0.7874 0.4064)
			(end -0.7874 -0.4064)
			(stroke
				(width 0.1524)
				(type default)
			)
			(layer "F.SilkS")
		)
		(fp_line
			(start -0.12065 -0.305054)
			(end -0.12065 -0.2794)
			(stroke
				(width 0.1)
				(type default)
			)
			(layer "F.Fab")
		)
		(fp_line
			(start -0.67945 -0.305054)
			(end -0.12065 -0.305054)
			(stroke
				(width 0.1)
				(type default)
			)
			(layer "F.Fab")
		)
		(fp_line
			(start 0.67945 -0.3048)
			(end 0.67945 0.3048)
			(stroke
				(width 0.1)
				(type default)
			)
			(layer "F.Fab")
		)
		(fp_line
			(start 0.12065 -0.3048)
			(end 0.67945 -0.3048)
			(stroke
				(width 0.1)
				(type default)
			)
			(layer "F.Fab")
		)
		(fp_line
			(start 0.12065 -0.2794)
			(end 0.12065 -0.3048)
			(stroke
				(width 0.1)
				(type default)
			)
			(layer "F.Fab")
		)
		(fp_line
			(start -0.12065 -0.2794)
			(end 0.12065 -0.2794)
			(stroke
				(width 0.1)
				(type default)
			)
			(layer "F.Fab")
		)
		(fp_line
			(start 0.120396 0.2794)
			(end -0.12065 0.2794)
			(stroke
				(width 0.1)
				(type default)
			)
			(layer "F.Fab")
		)
		(fp_line
			(start -0.12065 0.2794)
			(end -0.12065 0.3048)
			(stroke
				(width 0.1)
				(type default)
			)
			(layer "F.Fab")
		)
		(fp_line
			(start 0.67945 0.3048)
			(end 0.120396 0.3048)
			(stroke
				(width 0.1)
				(type default)
			)
			(layer "F.Fab")
		)
		(fp_line
			(start 0.120396 0.3048)
			(end 0.120396 0.2794)
			(stroke
				(width 0.1)
				(type default)
			)
			(layer "F.Fab")
		)
		(fp_line
			(start -0.12065 0.3048)
			(end -0.67945 0.3048)
			(stroke
				(width 0.1)
				(type default)
			)
			(layer "F.Fab")
		)
		(fp_line
			(start -0.67945 0.3048)
			(end -0.67945 -0.305054)
			(stroke
				(width 0.1)
				(type default)
			)
			(layer "F.Fab")
		)
		(pad "1" smd circle
			(at -0.40005 0 90)
			(size 0 0)
			(layers "F.Cu" "F.Mask" "F.Paste")
			(net "NC_PVCCINFAON_CPU0_ACSP5")
		)
		(pad "2" smd circle
			(at 0.40005 0 90)
			(size 0 0)
			(layers "F.Cu" "F.Mask" "F.Paste")
			(net "GND")
		)
	)
	(footprint ""
		(layer "F.Cu")
		(at 118.09222 -294.01008 180)
		(property "Reference" "C270"
			(at 0 0 180)
			(layer "F.SilkS")
			(hide yes)
			(effects
				(font
					(size 1.27 1.27)
				)
			)
		)
		(property "Value" ""
			(at 0 0 180)
			(layer "F.Fab")
			(effects
				(font
					(size 1.27 1.27)
				)
			)
		)
		(duplicate_pad_numbers_are_jumpers no)
		(fp_line
			(start 1.524 0.762)
			(end -1.524 0.762)
			(stroke
				(width 0.1524)
				(type default)
			)
			(layer "F.SilkS")
		)
		(fp_line
			(start 1.524 -0.762)
			(end 1.524 0.762)
			(stroke
				(width 0.1524)
				(type default)
			)
			(layer "F.SilkS")
		)
		(fp_line
			(start -1.524 0.762)
			(end -1.524 -0.762)
			(stroke
				(width 0.1524)
				(type default)
			)
			(layer "F.SilkS")
		)
		(fp_line
			(start -1.524 -0.762)
			(end 1.524 -0.762)
			(stroke
				(width 0.1524)
				(type default)
			)
			(layer "F.SilkS")
		)
		(fp_line
			(start 1.1049 0.724916)
			(end 1.1049 -0.724916)
			(stroke
				(width 0.1)
				(type default)
			)
			(layer "F.Fab")
		)
		(fp_line
			(start 1.1049 -0.724916)
			(end -1.1049 -0.724916)
			(stroke
				(width 0.1)
				(type default)
			)
			(layer "F.Fab")
		)
		(fp_line
			(start -1.1049 0.724916)
			(end 1.1049 0.724916)
			(stroke
				(width 0.1)
				(type default)
			)
			(layer "F.Fab")
		)
		(fp_line
			(start -1.1049 -0.724916)
			(end -1.1049 0.724916)
			(stroke
				(width 0.1)
				(type default)
			)
			(layer "F.Fab")
		)
		(pad "1" smd rect
			(at -0.889 0)
			(size 1.016 1.27)
			(layers "F.Cu" "F.Mask" "F.Paste")
			(net "PVCCIN_CPU1")
		)
		(pad "2" smd rect
			(at 0.889 0)
			(size 1.016 1.27)
			(layers "F.Cu" "F.Mask" "F.Paste")
			(net "GND")
		)
	)
	(footprint ""
		(layer "F.Cu")
		(at 123.317 -75.021948 90)
		(property "Reference" "R1184"
			(at 0 0 90)
			(layer "F.SilkS")
			(hide yes)
			(effects
				(font
					(size 1.27 1.27)
				)
			)
		)
		(property "Value" ""
			(at 0 0 90)
			(layer "F.Fab")
			(effects
				(font
					(size 1.27 1.27)
				)
			)
		)
		(duplicate_pad_numbers_are_jumpers no)
		(fp_line
			(start 0.7874 -0.4064)
			(end 0.7874 0.4064)
			(stroke
				(width 0.1524)
				(type default)
			)
			(layer "F.SilkS")
		)
		(fp_line
			(start -0.7874 -0.4064)
			(end 0.7874 -0.4064)
			(stroke
				(width 0.1524)
				(type default)
			)
			(layer "F.SilkS")
		)
		(fp_line
			(start 0.7874 0.4064)
			(end -0.7874 0.4064)
			(stroke
				(width 0.1524)
				(type default)
			)
			(layer "F.SilkS")
		)
		(fp_line
			(start -0.7874 0.4064)
			(end -0.7874 -0.4064)
			(stroke
				(width 0.1524)
				(type default)
			)
			(layer "F.SilkS")
		)
		(fp_line
			(start -0.12065 -0.305054)
			(end -0.12065 -0.2794)
			(stroke
				(width 0.1)
				(type default)
			)
			(layer "F.Fab")
		)
		(fp_line
			(start -0.67945 -0.305054)
			(end -0.12065 -0.305054)
			(stroke
				(width 0.1)
				(type default)
			)
			(layer "F.Fab")
		)
		(fp_line
			(start 0.67945 -0.3048)
			(end 0.67945 0.3048)
			(stroke
				(width 0.1)
				(type default)
			)
			(layer "F.Fab")
		)
		(fp_line
			(start 0.12065 -0.3048)
			(end 0.67945 -0.3048)
			(stroke
				(width 0.1)
				(type default)
			)
			(layer "F.Fab")
		)
		(fp_line
			(start 0.12065 -0.2794)
			(end 0.12065 -0.3048)
			(stroke
				(width 0.1)
				(type default)
			)
			(layer "F.Fab")
		)
		(fp_line
			(start -0.12065 -0.2794)
			(end 0.12065 -0.2794)
			(stroke
				(width 0.1)
				(type default)
			)
			(layer "F.Fab")
		)
		(fp_line
			(start 0.120396 0.2794)
			(end -0.12065 0.2794)
			(stroke
				(width 0.1)
				(type default)
			)
			(layer "F.Fab")
		)
		(fp_line
			(start -0.12065 0.2794)
			(end -0.12065 0.3048)
			(stroke
				(width 0.1)
				(type default)
			)
			(layer "F.Fab")
		)
		(fp_line
			(start 0.67945 0.3048)
			(end 0.120396 0.3048)
			(stroke
				(width 0.1)
				(type default)
			)
			(layer "F.Fab")
		)
		(fp_line
			(start 0.120396 0.3048)
			(end 0.120396 0.2794)
			(stroke
				(width 0.1)
				(type default)
			)
			(layer "F.Fab")
		)
		(fp_line
			(start -0.12065 0.3048)
			(end -0.67945 0.3048)
			(stroke
				(width 0.1)
				(type default)
			)
			(layer "F.Fab")
		)
		(fp_line
			(start -0.67945 0.3048)
			(end -0.67945 -0.305054)
			(stroke
				(width 0.1)
				(type default)
			)
			(layer "F.Fab")
		)
		(pad "1" smd circle
			(at -0.40005 0 90)
			(size 0 0)
			(layers "F.Cu" "F.Mask" "F.Paste")
			(net "JTAG_BMC_DBP_TMS_R")
		)
		(pad "2" smd circle
			(at 0.40005 0 90)
			(size 0 0)
			(layers "F.Cu" "F.Mask" "F.Paste")
			(net "JTAG_BMC_DBP_TMS")
		)
	)
	(footprint ""
		(layer "F.Cu")
		(at 189.65037 -426.303948 180)
		(property "Reference" "R3907"
			(at 0 0 180)
			(layer "F.SilkS")
			(hide yes)
			(effects
				(font
					(size 1.27 1.27)
				)
			)
		)
		(property "Value" ""
			(at 0 0 180)
			(layer "F.Fab")
			(effects
				(font
					(size 1.27 1.27)
				)
			)
		)
		(duplicate_pad_numbers_are_jumpers no)
		(fp_line
			(start 0.7874 0.4064)
			(end -0.7874 0.4064)
			(stroke
				(width 0.1524)
				(type default)
			)
			(layer "F.SilkS")
		)
		(fp_line
			(start 0.7874 -0.4064)
			(end 0.7874 0.4064)
			(stroke
				(width 0.1524)
				(type default)
			)
			(layer "F.SilkS")
		)
		(fp_line
			(start -0.7874 0.4064)
			(end -0.7874 -0.4064)
			(stroke
				(width 0.1524)
				(type default)
			)
			(layer "F.SilkS")
		)
		(fp_line
			(start -0.7874 -0.4064)
			(end 0.7874 -0.4064)
			(stroke
				(width 0.1524)
				(type default)
			)
			(layer "F.SilkS")
		)
		(fp_line
			(start 0.67945 0.3048)
			(end 0.120396 0.3048)
			(stroke
				(width 0.1)
				(type default)
			)
			(layer "F.Fab")
		)
		(fp_line
			(start 0.67945 -0.3048)
			(end 0.67945 0.3048)
			(stroke
				(width 0.1)
				(type default)
			)
			(layer "F.Fab")
		)
		(fp_line
			(start 0.12065 -0.2794)
			(end 0.12065 -0.3048)
			(stroke
				(width 0.1)
				(type default)
			)
			(layer "F.Fab")
		)
		(fp_line
			(start 0.12065 -0.3048)
			(end 0.67945 -0.3048)
			(stroke
				(width 0.1)
				(type default)
			)
			(layer "F.Fab")
		)
		(fp_line
			(start 0.120396 0.3048)
			(end 0.120396 0.2794)
			(stroke
				(width 0.1)
				(type default)
			)
			(layer "F.Fab")
		)
		(fp_line
			(start 0.120396 0.2794)
			(end -0.12065 0.2794)
			(stroke
				(width 0.1)
				(type default)
			)
			(layer "F.Fab")
		)
		(fp_line
			(start -0.12065 0.3048)
			(end -0.67945 0.3048)
			(stroke
				(width 0.1)
				(type default)
			)
			(layer "F.Fab")
		)
		(fp_line
			(start -0.12065 0.2794)
			(end -0.12065 0.3048)
			(stroke
				(width 0.1)
				(type default)
			)
			(layer "F.Fab")
		)
		(fp_line
			(start -0.12065 -0.2794)
			(end 0.12065 -0.2794)
			(stroke
				(width 0.1)
				(type default)
			)
			(layer "F.Fab")
		)
		(fp_line
			(start -0.12065 -0.305054)
			(end -0.12065 -0.2794)
			(stroke
				(width 0.1)
				(type default)
			)
			(layer "F.Fab")
		)
		(fp_line
			(start -0.67945 0.3048)
			(end -0.67945 -0.305054)
			(stroke
				(width 0.1)
				(type default)
			)
			(layer "F.Fab")
		)
		(fp_line
			(start -0.67945 -0.305054)
			(end -0.12065 -0.305054)
			(stroke
				(width 0.1)
				(type default)
			)
			(layer "F.Fab")
		)
		(pad "1" smd circle
			(at -0.40005 0 180)
			(size 0 0)
			(layers "F.Cu" "F.Mask" "F.Paste")
			(net "PDB_PRSNT_N")
		)
		(pad "2" smd circle
			(at 0.40005 0 180)
			(size 0 0)
			(layers "F.Cu" "F.Mask" "F.Paste")
			(net "GND")
		)
	)
	(footprint ""
		(layer "F.Cu")
		(at 365.46663 -241.976656 -90)
		(property "Reference" "C1029"
			(at 0 0 270)
			(layer "F.SilkS")
			(hide yes)
			(effects
				(font
					(size 1.27 1.27)
				)
			)
		)
		(property "Value" ""
			(at 0 0 270)
			(layer "F.Fab")
			(effects
				(font
					(size 1.27 1.27)
				)
			)
		)
		(duplicate_pad_numbers_are_jumpers no)
		(fp_line
			(start -0.7874 0.4064)
			(end -0.7874 -0.4064)
			(stroke
				(width 0.1524)
				(type default)
			)
			(layer "F.SilkS")
		)
		(fp_line
			(start 0.7874 0.4064)
			(end -0.7874 0.4064)
			(stroke
				(width 0.1524)
				(type default)
			)
			(layer "F.SilkS")
		)
		(fp_line
			(start -0.7874 -0.4064)
			(end 0.7874 -0.4064)
			(stroke
				(width 0.1524)
				(type default)
			)
			(layer "F.SilkS")
		)
		(fp_line
			(start 0.7874 -0.4064)
			(end 0.7874 0.4064)
			(stroke
				(width 0.1524)
				(type default)
			)
			(layer "F.SilkS")
		)
		(fp_line
			(start -0.67945 0.3048)
			(end -0.67945 -0.305054)
			(stroke
				(width 0.1)
				(type default)
			)
			(layer "F.Fab")
		)
		(fp_line
			(start -0.12065 0.3048)
			(end -0.67945 0.3048)
			(stroke
				(width 0.1)
				(type default)
			)
			(layer "F.Fab")
		)
		(fp_line
			(start 0.120396 0.3048)
			(end 0.120396 0.2794)
			(stroke
				(width 0.1)
				(type default)
			)
			(layer "F.Fab")
		)
		(fp_line
			(start 0.67945 0.3048)
			(end 0.120396 0.3048)
			(stroke
				(width 0.1)
				(type default)
			)
			(layer "F.Fab")
		)
		(fp_line
			(start -0.12065 0.2794)
			(end -0.12065 0.3048)
			(stroke
				(width 0.1)
				(type default)
			)
			(layer "F.Fab")
		)
		(fp_line
			(start 0.120396 0.2794)
			(end -0.12065 0.2794)
			(stroke
				(width 0.1)
				(type default)
			)
			(layer "F.Fab")
		)
		(fp_line
			(start -0.12065 -0.2794)
			(end 0.12065 -0.2794)
			(stroke
				(width 0.1)
				(type default)
			)
			(layer "F.Fab")
		)
		(fp_line
			(start 0.12065 -0.2794)
			(end 0.12065 -0.3048)
			(stroke
				(width 0.1)
				(type default)
			)
			(layer "F.Fab")
		)
		(fp_line
			(start 0.12065 -0.3048)
			(end 0.67945 -0.3048)
			(stroke
				(width 0.1)
				(type default)
			)
			(layer "F.Fab")
		)
		(fp_line
			(start 0.67945 -0.3048)
			(end 0.67945 0.3048)
			(stroke
				(width 0.1)
				(type default)
			)
			(layer "F.Fab")
		)
		(fp_line
			(start -0.67945 -0.305054)
			(end -0.12065 -0.305054)
			(stroke
				(width 0.1)
				(type default)
			)
			(layer "F.Fab")
		)
		(fp_line
			(start -0.12065 -0.305054)
			(end -0.12065 -0.2794)
			(stroke
				(width 0.1)
				(type default)
			)
			(layer "F.Fab")
		)
		(pad "1" smd circle
			(at -0.40005 0 270)
			(size 0 0)
			(layers "F.Cu" "F.Mask" "F.Paste")
			(net "PVCCIN_CPU0")
		)
		(pad "2" smd circle
			(at 0.40005 0 270)
			(size 0 0)
			(layers "F.Cu" "F.Mask" "F.Paste")
			(net "GND")
		)
	)
	(footprint ""
		(layer "F.Cu")
		(at 181.15788 -99.659948 -90)
		(property "Reference" "R208"
			(at 0 0 270)
			(layer "F.SilkS")
			(hide yes)
			(effects
				(font
					(size 1.27 1.27)
				)
			)
		)
		(property "Value" ""
			(at 0 0 270)
			(layer "F.Fab")
			(effects
				(font
					(size 1.27 1.27)
				)
			)
		)
		(duplicate_pad_numbers_are_jumpers no)
		(fp_line
			(start -0.7874 0.4064)
			(end -0.7874 -0.4064)
			(stroke
				(width 0.1524)
				(type default)
			)
			(layer "F.SilkS")
		)
		(fp_line
			(start 0.7874 0.4064)
			(end -0.7874 0.4064)
			(stroke
				(width 0.1524)
				(type default)
			)
			(layer "F.SilkS")
		)
		(fp_line
			(start -0.7874 -0.4064)
			(end 0.7874 -0.4064)
			(stroke
				(width 0.1524)
				(type default)
			)
			(layer "F.SilkS")
		)
		(fp_line
			(start 0.7874 -0.4064)
			(end 0.7874 0.4064)
			(stroke
				(width 0.1524)
				(type default)
			)
			(layer "F.SilkS")
		)
		(fp_line
			(start -0.67945 0.3048)
			(end -0.67945 -0.305054)
			(stroke
				(width 0.1)
				(type default)
			)
			(layer "F.Fab")
		)
		(fp_line
			(start -0.12065 0.3048)
			(end -0.67945 0.3048)
			(stroke
				(width 0.1)
				(type default)
			)
			(layer "F.Fab")
		)
		(fp_line
			(start 0.120396 0.3048)
			(end 0.120396 0.2794)
			(stroke
				(width 0.1)
				(type default)
			)
			(layer "F.Fab")
		)
		(fp_line
			(start 0.67945 0.3048)
			(end 0.120396 0.3048)
			(stroke
				(width 0.1)
				(type default)
			)
			(layer "F.Fab")
		)
		(fp_line
			(start -0.12065 0.2794)
			(end -0.12065 0.3048)
			(stroke
				(width 0.1)
				(type default)
			)
			(layer "F.Fab")
		)
		(fp_line
			(start 0.120396 0.2794)
			(end -0.12065 0.2794)
			(stroke
				(width 0.1)
				(type default)
			)
			(layer "F.Fab")
		)
		(fp_line
			(start -0.12065 -0.2794)
			(end 0.12065 -0.2794)
			(stroke
				(width 0.1)
				(type default)
			)
			(layer "F.Fab")
		)
		(fp_line
			(start 0.12065 -0.2794)
			(end 0.12065 -0.3048)
			(stroke
				(width 0.1)
				(type default)
			)
			(layer "F.Fab")
		)
		(fp_line
			(start 0.12065 -0.3048)
			(end 0.67945 -0.3048)
			(stroke
				(width 0.1)
				(type default)
			)
			(layer "F.Fab")
		)
		(fp_line
			(start 0.67945 -0.3048)
			(end 0.67945 0.3048)
			(stroke
				(width 0.1)
				(type default)
			)
			(layer "F.Fab")
		)
		(fp_line
			(start -0.67945 -0.305054)
			(end -0.12065 -0.305054)
			(stroke
				(width 0.1)
				(type default)
			)
			(layer "F.Fab")
		)
		(fp_line
			(start -0.12065 -0.305054)
			(end -0.12065 -0.2794)
			(stroke
				(width 0.1)
				(type default)
			)
			(layer "F.Fab")
		)
		(pad "1" smd circle
			(at -0.40005 0 270)
			(size 0 0)
			(layers "F.Cu" "F.Mask" "F.Paste")
			(net "H_CPU0_MEMHOT_IN_LVC1_R_N")
		)
		(pad "2" smd circle
			(at 0.40005 0 270)
			(size 0 0)
			(layers "F.Cu" "F.Mask" "F.Paste")
			(net "H_CPU0_MEMHOT_IN_LVC1_R1_N")
		)
	)
	(footprint ""
		(layer "F.Cu")
		(at 322.095622 -59.299348)
		(property "Reference" "R456"
			(at 0 0 0)
			(layer "F.SilkS")
			(hide yes)
			(effects
				(font
					(size 1.27 1.27)
				)
			)
		)
		(property "Value" ""
			(at 0 0 0)
			(layer "F.Fab")
			(effects
				(font
					(size 1.27 1.27)
				)
			)
		)
		(duplicate_pad_numbers_are_jumpers no)
		(fp_line
			(start -0.7874 -0.4064)
			(end 0.7874 -0.4064)
			(stroke
				(width 0.1524)
				(type default)
			)
			(layer "F.SilkS")
		)
		(fp_line
			(start -0.7874 0.4064)
			(end -0.7874 -0.4064)
			(stroke
				(width 0.1524)
				(type default)
			)
			(layer "F.SilkS")
		)
		(fp_line
			(start 0.7874 -0.4064)
			(end 0.7874 0.4064)
			(stroke
				(width 0.1524)
				(type default)
			)
			(layer "F.SilkS")
		)
		(fp_line
			(start 0.7874 0.4064)
			(end -0.7874 0.4064)
			(stroke
				(width 0.1524)
				(type default)
			)
			(layer "F.SilkS")
		)
		(fp_line
			(start -0.67945 -0.305054)
			(end -0.12065 -0.305054)
			(stroke
				(width 0.1)
				(type default)
			)
			(layer "F.Fab")
		)
		(fp_line
			(start -0.67945 0.3048)
			(end -0.67945 -0.305054)
			(stroke
				(width 0.1)
				(type default)
			)
			(layer "F.Fab")
		)
		(fp_line
			(start -0.12065 -0.305054)
			(end -0.12065 -0.2794)
			(stroke
				(width 0.1)
				(type default)
			)
			(layer "F.Fab")
		)
		(fp_line
			(start -0.12065 -0.2794)
			(end 0.12065 -0.2794)
			(stroke
				(width 0.1)
				(type default)
			)
			(layer "F.Fab")
		)
		(fp_line
			(start -0.12065 0.2794)
			(end -0.12065 0.3048)
			(stroke
				(width 0.1)
				(type default)
			)
			(layer "F.Fab")
		)
		(fp_line
			(start -0.12065 0.3048)
			(end -0.67945 0.3048)
			(stroke
				(width 0.1)
				(type default)
			)
			(layer "F.Fab")
		)
		(fp_line
			(start 0.120396 0.2794)
			(end -0.12065 0.2794)
			(stroke
				(width 0.1)
				(type default)
			)
			(layer "F.Fab")
		)
		(fp_line
			(start 0.120396 0.3048)
			(end 0.120396 0.2794)
			(stroke
				(width 0.1)
				(type default)
			)
			(layer "F.Fab")
		)
		(fp_line
			(start 0.12065 -0.3048)
			(end 0.67945 -0.3048)
			(stroke
				(width 0.1)
				(type default)
			)
			(layer "F.Fab")
		)
		(fp_line
			(start 0.12065 -0.2794)
			(end 0.12065 -0.3048)
			(stroke
				(width 0.1)
				(type default)
			)
			(layer "F.Fab")
		)
		(fp_line
			(start 0.67945 -0.3048)
			(end 0.67945 0.3048)
			(stroke
				(width 0.1)
				(type default)
			)
			(layer "F.Fab")
		)
		(fp_line
			(start 0.67945 0.3048)
			(end 0.120396 0.3048)
			(stroke
				(width 0.1)
				(type default)
			)
			(layer "F.Fab")
		)
		(pad "1" smd circle
			(at -0.40005 0)
			(size 0 0)
			(layers "F.Cu" "F.Mask" "F.Paste")
			(net "P3V3_AUX")
		)
		(pad "2" smd circle
			(at 0.40005 0)
			(size 0 0)
			(layers "F.Cu" "F.Mask" "F.Paste")
			(net "PU_PCH_PMCALERT_N")
		)
	)
	(footprint ""
		(layer "F.Cu")
		(at 239.203738 -119.183658 -90)
		(property "Reference" "R3198"
			(at 0 0 270)
			(layer "F.SilkS")
			(hide yes)
			(effects
				(font
					(size 1.27 1.27)
				)
			)
		)
		(property "Value" ""
			(at 0 0 270)
			(layer "F.Fab")
			(effects
				(font
					(size 1.27 1.27)
				)
			)
		)
		(duplicate_pad_numbers_are_jumpers no)
		(fp_line
			(start -0.7874 0.4064)
			(end -0.7874 0.070358)
			(stroke
				(width 0.1524)
				(type default)
			)
			(layer "F.SilkS")
		)
		(fp_line
			(start 0.7874 0.4064)
			(end -0.7874 0.4064)
			(stroke
				(width 0.1524)
				(type default)
			)
			(layer "F.SilkS")
		)
		(fp_line
			(start 0.7874 0.022098)
			(end 0.7874 0.4064)
			(stroke
				(width 0.1524)
				(type default)
			)
			(layer "F.SilkS")
		)
		(fp_line
			(start -0.254762 -0.4064)
			(end 0.385318 -0.4064)
			(stroke
				(width 0.1524)
				(type default)
			)
			(layer "F.SilkS")
		)
		(fp_line
			(start -0.67945 0.3048)
			(end -0.67945 -0.305054)
			(stroke
				(width 0.1)
				(type default)
			)
			(layer "F.Fab")
		)
		(fp_line
			(start -0.12065 0.3048)
			(end -0.67945 0.3048)
			(stroke
				(width 0.1)
				(type default)
			)
			(layer "F.Fab")
		)
		(fp_line
			(start 0.120396 0.3048)
			(end 0.120396 0.2794)
			(stroke
				(width 0.1)
				(type default)
			)
			(layer "F.Fab")
		)
		(fp_line
			(start 0.67945 0.3048)
			(end 0.120396 0.3048)
			(stroke
				(width 0.1)
				(type default)
			)
			(layer "F.Fab")
		)
		(fp_line
			(start -0.12065 0.2794)
			(end -0.12065 0.3048)
			(stroke
				(width 0.1)
				(type default)
			)
			(layer "F.Fab")
		)
		(fp_line
			(start 0.120396 0.2794)
			(end -0.12065 0.2794)
			(stroke
				(width 0.1)
				(type default)
			)
			(layer "F.Fab")
		)
		(fp_line
			(start -0.12065 -0.2794)
			(end 0.12065 -0.2794)
			(stroke
				(width 0.1)
				(type default)
			)
			(layer "F.Fab")
		)
		(fp_line
			(start 0.12065 -0.2794)
			(end 0.12065 -0.3048)
			(stroke
				(width 0.1)
				(type default)
			)
			(layer "F.Fab")
		)
		(fp_line
			(start 0.12065 -0.3048)
			(end 0.67945 -0.3048)
			(stroke
				(width 0.1)
				(type default)
			)
			(layer "F.Fab")
		)
		(fp_line
			(start 0.67945 -0.3048)
			(end 0.67945 0.3048)
			(stroke
				(width 0.1)
				(type default)
			)
			(layer "F.Fab")
		)
		(fp_line
			(start -0.67945 -0.305054)
			(end -0.12065 -0.305054)
			(stroke
				(width 0.1)
				(type default)
			)
			(layer "F.Fab")
		)
		(fp_line
			(start -0.12065 -0.305054)
			(end -0.12065 -0.2794)
			(stroke
				(width 0.1)
				(type default)
			)
			(layer "F.Fab")
		)
		(pad "1" smd circle
			(at -0.40005 0 270)
			(size 0 0)
			(layers "F.Cu" "F.Mask" "F.Paste")
			(net "CLK_100M_OCP_V3_2_C_R_DP")
		)
		(pad "2" smd circle
			(at 0.40005 0 270)
			(size 0 0)
			(layers "F.Cu" "F.Mask" "F.Paste")
			(net "CLK_100M_OCP_V3_2_C_DP")
		)
	)
	(footprint ""
		(layer "F.Cu")
		(at 367.44783 -241.976656 -90)
		(property "Reference" "C1037"
			(at 0 0 270)
			(layer "F.SilkS")
			(hide yes)
			(effects
				(font
					(size 1.27 1.27)
				)
			)
		)
		(property "Value" ""
			(at 0 0 270)
			(layer "F.Fab")
			(effects
				(font
					(size 1.27 1.27)
				)
			)
		)
		(duplicate_pad_numbers_are_jumpers no)
		(fp_line
			(start -0.7874 0.4064)
			(end -0.7874 -0.4064)
			(stroke
				(width 0.1524)
				(type default)
			)
			(layer "F.SilkS")
		)
		(fp_line
			(start 0.7874 0.4064)
			(end -0.7874 0.4064)
			(stroke
				(width 0.1524)
				(type default)
			)
			(layer "F.SilkS")
		)
		(fp_line
			(start -0.7874 -0.4064)
			(end 0.7874 -0.4064)
			(stroke
				(width 0.1524)
				(type default)
			)
			(layer "F.SilkS")
		)
		(fp_line
			(start 0.7874 -0.4064)
			(end 0.7874 0.4064)
			(stroke
				(width 0.1524)
				(type default)
			)
			(layer "F.SilkS")
		)
		(fp_line
			(start -0.67945 0.3048)
			(end -0.67945 -0.305054)
			(stroke
				(width 0.1)
				(type default)
			)
			(layer "F.Fab")
		)
		(fp_line
			(start -0.12065 0.3048)
			(end -0.67945 0.3048)
			(stroke
				(width 0.1)
				(type default)
			)
			(layer "F.Fab")
		)
		(fp_line
			(start 0.120396 0.3048)
			(end 0.120396 0.2794)
			(stroke
				(width 0.1)
				(type default)
			)
			(layer "F.Fab")
		)
		(fp_line
			(start 0.67945 0.3048)
			(end 0.120396 0.3048)
			(stroke
				(width 0.1)
				(type default)
			)
			(layer "F.Fab")
		)
		(fp_line
			(start -0.12065 0.2794)
			(end -0.12065 0.3048)
			(stroke
				(width 0.1)
				(type default)
			)
			(layer "F.Fab")
		)
		(fp_line
			(start 0.120396 0.2794)
			(end -0.12065 0.2794)
			(stroke
				(width 0.1)
				(type default)
			)
			(layer "F.Fab")
		)
		(fp_line
			(start -0.12065 -0.2794)
			(end 0.12065 -0.2794)
			(stroke
				(width 0.1)
				(type default)
			)
			(layer "F.Fab")
		)
		(fp_line
			(start 0.12065 -0.2794)
			(end 0.12065 -0.3048)
			(stroke
				(width 0.1)
				(type default)
			)
			(layer "F.Fab")
		)
		(fp_line
			(start 0.12065 -0.3048)
			(end 0.67945 -0.3048)
			(stroke
				(width 0.1)
				(type default)
			)
			(layer "F.Fab")
		)
		(fp_line
			(start 0.67945 -0.3048)
			(end 0.67945 0.3048)
			(stroke
				(width 0.1)
				(type default)
			)
			(layer "F.Fab")
		)
		(fp_line
			(start -0.67945 -0.305054)
			(end -0.12065 -0.305054)
			(stroke
				(width 0.1)
				(type default)
			)
			(layer "F.Fab")
		)
		(fp_line
			(start -0.12065 -0.305054)
			(end -0.12065 -0.2794)
			(stroke
				(width 0.1)
				(type default)
			)
			(layer "F.Fab")
		)
		(pad "1" smd circle
			(at -0.40005 0 270)
			(size 0 0)
			(layers "F.Cu" "F.Mask" "F.Paste")
			(net "PVCCIN_CPU0")
		)
		(pad "2" smd circle
			(at 0.40005 0 270)
			(size 0 0)
			(layers "F.Cu" "F.Mask" "F.Paste")
			(net "GND")
		)
	)
	(footprint ""
		(layer "F.Cu")
		(at 256.889504 -42.488612 180)
		(property "Reference" "PR3966"
			(at 0 0 180)
			(layer "F.SilkS")
			(hide yes)
			(effects
				(font
					(size 1.27 1.27)
				)
			)
		)
		(property "Value" ""
			(at 0 0 180)
			(layer "F.Fab")
			(effects
				(font
					(size 1.27 1.27)
				)
			)
		)
		(duplicate_pad_numbers_are_jumpers no)
		(fp_line
			(start 0.7874 0.4064)
			(end -0.7874 0.4064)
			(stroke
				(width 0.1524)
				(type default)
			)
			(layer "F.SilkS")
		)
		(fp_line
			(start 0.7874 -0.4064)
			(end 0.7874 0.4064)
			(stroke
				(width 0.1524)
				(type default)
			)
			(layer "F.SilkS")
		)
		(fp_line
			(start -0.7874 0.4064)
			(end -0.7874 -0.4064)
			(stroke
				(width 0.1524)
				(type default)
			)
			(layer "F.SilkS")
		)
		(fp_line
			(start -0.7874 -0.4064)
			(end 0.7874 -0.4064)
			(stroke
				(width 0.1524)
				(type default)
			)
			(layer "F.SilkS")
		)
		(fp_line
			(start 0.67945 0.3048)
			(end 0.120396 0.3048)
			(stroke
				(width 0.1)
				(type default)
			)
			(layer "F.Fab")
		)
		(fp_line
			(start 0.67945 -0.3048)
			(end 0.67945 0.3048)
			(stroke
				(width 0.1)
				(type default)
			)
			(layer "F.Fab")
		)
		(fp_line
			(start 0.12065 -0.2794)
			(end 0.12065 -0.3048)
			(stroke
				(width 0.1)
				(type default)
			)
			(layer "F.Fab")
		)
		(fp_line
			(start 0.12065 -0.3048)
			(end 0.67945 -0.3048)
			(stroke
				(width 0.1)
				(type default)
			)
			(layer "F.Fab")
		)
		(fp_line
			(start 0.120396 0.3048)
			(end 0.120396 0.2794)
			(stroke
				(width 0.1)
				(type default)
			)
			(layer "F.Fab")
		)
		(fp_line
			(start 0.120396 0.2794)
			(end -0.12065 0.2794)
			(stroke
				(width 0.1)
				(type default)
			)
			(layer "F.Fab")
		)
		(fp_line
			(start -0.12065 0.3048)
			(end -0.67945 0.3048)
			(stroke
				(width 0.1)
				(type default)
			)
			(layer "F.Fab")
		)
		(fp_line
			(start -0.12065 0.2794)
			(end -0.12065 0.3048)
			(stroke
				(width 0.1)
				(type default)
			)
			(layer "F.Fab")
		)
		(fp_line
			(start -0.12065 -0.2794)
			(end 0.12065 -0.2794)
			(stroke
				(width 0.1)
				(type default)
			)
			(layer "F.Fab")
		)
		(fp_line
			(start -0.12065 -0.305054)
			(end -0.12065 -0.2794)
			(stroke
				(width 0.1)
				(type default)
			)
			(layer "F.Fab")
		)
		(fp_line
			(start -0.67945 0.3048)
			(end -0.67945 -0.305054)
			(stroke
				(width 0.1)
				(type default)
			)
			(layer "F.Fab")
		)
		(fp_line
			(start -0.67945 -0.305054)
			(end -0.12065 -0.305054)
			(stroke
				(width 0.1)
				(type default)
			)
			(layer "F.Fab")
		)
		(pad "1" smd circle
			(at -0.40005 0 180)
			(size 0 0)
			(layers "F.Cu" "F.Mask" "F.Paste")
			(net "P12V_AUX")
		)
		(pad "2" smd circle
			(at 0.40005 0 180)
			(size 0 0)
			(layers "F.Cu" "F.Mask" "F.Paste")
			(net "P12V_E1S_VCC_0")
		)
	)
	(footprint ""
		(layer "F.Cu")
		(at 180.77688 -56.352948 180)
		(property "Reference" "R478"
			(at 0 0 180)
			(layer "F.SilkS")
			(hide yes)
			(effects
				(font
					(size 1.27 1.27)
				)
			)
		)
		(property "Value" ""
			(at 0 0 180)
			(layer "F.Fab")
			(effects
				(font
					(size 1.27 1.27)
				)
			)
		)
		(duplicate_pad_numbers_are_jumpers no)
		(fp_line
			(start 0.7874 0.4064)
			(end -0.7874 0.4064)
			(stroke
				(width 0.1524)
				(type default)
			)
			(layer "F.SilkS")
		)
		(fp_line
			(start 0.7874 -0.4064)
			(end 0.7874 0.4064)
			(stroke
				(width 0.1524)
				(type default)
			)
			(layer "F.SilkS")
		)
		(fp_line
			(start -0.7874 0.4064)
			(end -0.7874 -0.4064)
			(stroke
				(width 0.1524)
				(type default)
			)
			(layer "F.SilkS")
		)
		(fp_line
			(start -0.7874 -0.4064)
			(end 0.7874 -0.4064)
			(stroke
				(width 0.1524)
				(type default)
			)
			(layer "F.SilkS")
		)
		(fp_line
			(start 0.67945 0.3048)
			(end 0.120396 0.3048)
			(stroke
				(width 0.1)
				(type default)
			)
			(layer "F.Fab")
		)
		(fp_line
			(start 0.67945 -0.3048)
			(end 0.67945 0.3048)
			(stroke
				(width 0.1)
				(type default)
			)
			(layer "F.Fab")
		)
		(fp_line
			(start 0.12065 -0.2794)
			(end 0.12065 -0.3048)
			(stroke
				(width 0.1)
				(type default)
			)
			(layer "F.Fab")
		)
		(fp_line
			(start 0.12065 -0.3048)
			(end 0.67945 -0.3048)
			(stroke
				(width 0.1)
				(type default)
			)
			(layer "F.Fab")
		)
		(fp_line
			(start 0.120396 0.3048)
			(end 0.120396 0.2794)
			(stroke
				(width 0.1)
				(type default)
			)
			(layer "F.Fab")
		)
		(fp_line
			(start 0.120396 0.2794)
			(end -0.12065 0.2794)
			(stroke
				(width 0.1)
				(type default)
			)
			(layer "F.Fab")
		)
		(fp_line
			(start -0.12065 0.3048)
			(end -0.67945 0.3048)
			(stroke
				(width 0.1)
				(type default)
			)
			(layer "F.Fab")
		)
		(fp_line
			(start -0.12065 0.2794)
			(end -0.12065 0.3048)
			(stroke
				(width 0.1)
				(type default)
			)
			(layer "F.Fab")
		)
		(fp_line
			(start -0.12065 -0.2794)
			(end 0.12065 -0.2794)
			(stroke
				(width 0.1)
				(type default)
			)
			(layer "F.Fab")
		)
		(fp_line
			(start -0.12065 -0.305054)
			(end -0.12065 -0.2794)
			(stroke
				(width 0.1)
				(type default)
			)
			(layer "F.Fab")
		)
		(fp_line
			(start -0.67945 0.3048)
			(end -0.67945 -0.305054)
			(stroke
				(width 0.1)
				(type default)
			)
			(layer "F.Fab")
		)
		(fp_line
			(start -0.67945 -0.305054)
			(end -0.12065 -0.305054)
			(stroke
				(width 0.1)
				(type default)
			)
			(layer "F.Fab")
		)
		(pad "1" smd circle
			(at -0.40005 0 180)
			(size 0 0)
			(layers "F.Cu" "F.Mask" "F.Paste")
			(net "P3V3_AUX")
		)
		(pad "2" smd circle
			(at 0.40005 0 180)
			(size 0 0)
			(layers "F.Cu" "F.Mask" "F.Paste")
			(net "PCIE_M2_SSD0_PRSNT_N")
		)
	)
	(footprint ""
		(layer "F.Cu")
		(at 97.821242 -417.766246 90)
		(property "Reference" "R4194"
			(at 0 0 90)
			(layer "F.SilkS")
			(hide yes)
			(effects
				(font
					(size 1.27 1.27)
				)
			)
		)
		(property "Value" ""
			(at 0 0 90)
			(layer "F.Fab")
			(effects
				(font
					(size 1.27 1.27)
				)
			)
		)
		(duplicate_pad_numbers_are_jumpers no)
		(fp_line
			(start 0.7874 -0.4064)
			(end 0.7874 0.4064)
			(stroke
				(width 0.1524)
				(type default)
			)
			(layer "F.SilkS")
		)
		(fp_line
			(start -0.7874 -0.4064)
			(end 0.7874 -0.4064)
			(stroke
				(width 0.1524)
				(type default)
			)
			(layer "F.SilkS")
		)
		(fp_line
			(start 0.7874 0.4064)
			(end -0.7874 0.4064)
			(stroke
				(width 0.1524)
				(type default)
			)
			(layer "F.SilkS")
		)
		(fp_line
			(start -0.7874 0.4064)
			(end -0.7874 -0.4064)
			(stroke
				(width 0.1524)
				(type default)
			)
			(layer "F.SilkS")
		)
		(fp_line
			(start -0.12065 -0.305054)
			(end -0.12065 -0.2794)
			(stroke
				(width 0.1)
				(type default)
			)
			(layer "F.Fab")
		)
		(fp_line
			(start -0.67945 -0.305054)
			(end -0.12065 -0.305054)
			(stroke
				(width 0.1)
				(type default)
			)
			(layer "F.Fab")
		)
		(fp_line
			(start 0.67945 -0.3048)
			(end 0.67945 0.3048)
			(stroke
				(width 0.1)
				(type default)
			)
			(layer "F.Fab")
		)
		(fp_line
			(start 0.12065 -0.3048)
			(end 0.67945 -0.3048)
			(stroke
				(width 0.1)
				(type default)
			)
			(layer "F.Fab")
		)
		(fp_line
			(start 0.12065 -0.2794)
			(end 0.12065 -0.3048)
			(stroke
				(width 0.1)
				(type default)
			)
			(layer "F.Fab")
		)
		(fp_line
			(start -0.12065 -0.2794)
			(end 0.12065 -0.2794)
			(stroke
				(width 0.1)
				(type default)
			)
			(layer "F.Fab")
		)
		(fp_line
			(start 0.120396 0.2794)
			(end -0.12065 0.2794)
			(stroke
				(width 0.1)
				(type default)
			)
			(layer "F.Fab")
		)
		(fp_line
			(start -0.12065 0.2794)
			(end -0.12065 0.3048)
			(stroke
				(width 0.1)
				(type default)
			)
			(layer "F.Fab")
		)
		(fp_line
			(start 0.67945 0.3048)
			(end 0.120396 0.3048)
			(stroke
				(width 0.1)
				(type default)
			)
			(layer "F.Fab")
		)
		(fp_line
			(start 0.120396 0.3048)
			(end 0.120396 0.2794)
			(stroke
				(width 0.1)
				(type default)
			)
			(layer "F.Fab")
		)
		(fp_line
			(start -0.12065 0.3048)
			(end -0.67945 0.3048)
			(stroke
				(width 0.1)
				(type default)
			)
			(layer "F.Fab")
		)
		(fp_line
			(start -0.67945 0.3048)
			(end -0.67945 -0.305054)
			(stroke
				(width 0.1)
				(type default)
			)
			(layer "F.Fab")
		)
		(pad "1" smd circle
			(at -0.40005 0 90)
			(size 0 0)
			(layers "F.Cu" "F.Mask" "F.Paste")
			(net "P3V3_AUX")
		)
		(pad "2" smd circle
			(at 0.40005 0 90)
			(size 0 0)
			(layers "F.Cu" "F.Mask" "F.Paste")
			(net "U272_2_ADD1")
		)
	)
	(footprint ""
		(layer "F.Cu")
		(at 303.9872 -24.7396 180)
		(property "Reference" "C2386"
			(at 0 0 180)
			(layer "F.SilkS")
			(hide yes)
			(effects
				(font
					(size 1.27 1.27)
				)
			)
		)
		(property "Value" ""
			(at 0 0 180)
			(layer "F.Fab")
			(effects
				(font
					(size 1.27 1.27)
				)
			)
		)
		(duplicate_pad_numbers_are_jumpers no)
		(fp_line
			(start 0.7874 0.4064)
			(end -0.7874 0.4064)
			(stroke
				(width 0.1524)
				(type default)
			)
			(layer "F.SilkS")
		)
		(fp_line
			(start 0.7874 -0.4064)
			(end 0.7874 0.4064)
			(stroke
				(width 0.1524)
				(type default)
			)
			(layer "F.SilkS")
		)
		(fp_line
			(start -0.7874 0.4064)
			(end -0.7874 -0.4064)
			(stroke
				(width 0.1524)
				(type default)
			)
			(layer "F.SilkS")
		)
		(fp_line
			(start -0.7874 -0.4064)
			(end 0.7874 -0.4064)
			(stroke
				(width 0.1524)
				(type default)
			)
			(layer "F.SilkS")
		)
		(fp_line
			(start 0.67945 0.3048)
			(end 0.120396 0.3048)
			(stroke
				(width 0.1)
				(type default)
			)
			(layer "F.Fab")
		)
		(fp_line
			(start 0.67945 -0.3048)
			(end 0.67945 0.3048)
			(stroke
				(width 0.1)
				(type default)
			)
			(layer "F.Fab")
		)
		(fp_line
			(start 0.12065 -0.2794)
			(end 0.12065 -0.3048)
			(stroke
				(width 0.1)
				(type default)
			)
			(layer "F.Fab")
		)
		(fp_line
			(start 0.12065 -0.3048)
			(end 0.67945 -0.3048)
			(stroke
				(width 0.1)
				(type default)
			)
			(layer "F.Fab")
		)
		(fp_line
			(start 0.120396 0.3048)
			(end 0.120396 0.2794)
			(stroke
				(width 0.1)
				(type default)
			)
			(layer "F.Fab")
		)
		(fp_line
			(start 0.120396 0.2794)
			(end -0.12065 0.2794)
			(stroke
				(width 0.1)
				(type default)
			)
			(layer "F.Fab")
		)
		(fp_line
			(start -0.12065 0.3048)
			(end -0.67945 0.3048)
			(stroke
				(width 0.1)
				(type default)
			)
			(layer "F.Fab")
		)
		(fp_line
			(start -0.12065 0.2794)
			(end -0.12065 0.3048)
			(stroke
				(width 0.1)
				(type default)
			)
			(layer "F.Fab")
		)
		(fp_line
			(start -0.12065 -0.2794)
			(end 0.12065 -0.2794)
			(stroke
				(width 0.1)
				(type default)
			)
			(layer "F.Fab")
		)
		(fp_line
			(start -0.12065 -0.305054)
			(end -0.12065 -0.2794)
			(stroke
				(width 0.1)
				(type default)
			)
			(layer "F.Fab")
		)
		(fp_line
			(start -0.67945 0.3048)
			(end -0.67945 -0.305054)
			(stroke
				(width 0.1)
				(type default)
			)
			(layer "F.Fab")
		)
		(fp_line
			(start -0.67945 -0.305054)
			(end -0.12065 -0.305054)
			(stroke
				(width 0.1)
				(type default)
			)
			(layer "F.Fab")
		)
		(pad "1" smd circle
			(at -0.40005 0 180)
			(size 0 0)
			(layers "F.Cu" "F.Mask" "F.Paste")
			(net "PWRGD_DSW_PWROK_TRIGGER")
		)
		(pad "2" smd circle
			(at 0.40005 0 180)
			(size 0 0)
			(layers "F.Cu" "F.Mask" "F.Paste")
			(net "GND")
		)
	)
	(footprint ""
		(layer "F.Cu")
		(at 509.384808 -148.08708 90)
		(property "Reference" "X14"
			(at -3.417316 3.094482 90)
			(unlocked yes)
			(layer "F.SilkS")
			(effects
				(font
					(size 0.7874 0.5842)
					(thickness 0.1524)
				)
				(justify left)
			)
		)
		(property "Value" ""
			(at 0 0 90)
			(layer "F.Fab")
			(effects
				(font
					(size 1.27 1.27)
				)
			)
		)
		(property "Device Type" "TP_TDR_4P_FTS_MPKT4_H025P0200_I"
			(at 1.30175 1.27 180)
			(unlocked yes)
			(layer "F.Fab")
			(hide yes)
			(effects
				(font
					(size 0.635 0.4064)
					(thickness 0.1524)
				)
			)
		)
		(property "User Part Number" "TP15"
			(at 1.30175 1.27 180)
			(unlocked yes)
			(layer "Cmts.User")
			(hide yes)
			(effects
				(font
					(size 0.635 0.4064)
					(thickness 0.1524)
				)
			)
		)
		(duplicate_pad_numbers_are_jumpers no)
		(fp_line
			(start 2.54 -1.27)
			(end 0 -1.27)
			(stroke
				(width 0.1524)
				(type default)
			)
			(layer "F.SilkS")
		)
		(fp_line
			(start 0 -1.27)
			(end 0 -0.635)
			(stroke
				(width 0.1524)
				(type default)
			)
			(layer "F.SilkS")
		)
		(fp_line
			(start 2.54 -1.1303)
			(end 2.54 -1.27)
			(stroke
				(width 0.1524)
				(type default)
			)
			(layer "F.SilkS")
		)
		(fp_line
			(start 0 0.635)
			(end 0 1.905)
			(stroke
				(width 0.1524)
				(type default)
			)
			(layer "F.SilkS")
		)
		(fp_line
			(start 2.54 1.4097)
			(end 2.54 1.1303)
			(stroke
				(width 0.1524)
				(type default)
			)
			(layer "F.SilkS")
		)
		(fp_line
			(start 0 3.175)
			(end 0 3.81)
			(stroke
				(width 0.1524)
				(type default)
			)
			(layer "F.SilkS")
		)
		(fp_line
			(start 2.54 3.81)
			(end 2.54 3.6703)
			(stroke
				(width 0.1524)
				(type default)
			)
			(layer "F.SilkS")
		)
		(fp_line
			(start 0 3.81)
			(end 2.54 3.81)
			(stroke
				(width 0.1524)
				(type default)
			)
			(layer "F.SilkS")
		)
		(fp_poly
			(pts
				(xy -1.267206 -0.04064) (xy -2.791206 0.72136) (xy -2.791206 -0.80264)
			)
			(stroke
				(width 0)
				(type default)
			)
			(fill yes)
			(layer "F.SilkS")
		)
		(fp_line
			(start 2.54 -1.27)
			(end 0 -1.27)
			(stroke
				(width 0.1)
				(type default)
			)
			(layer "F.Fab")
		)
		(fp_line
			(start 0 -1.27)
			(end 0 3.81)
			(stroke
				(width 0.1)
				(type default)
			)
			(layer "F.Fab")
		)
		(fp_line
			(start 2.54 3.81)
			(end 2.54 -1.27)
			(stroke
				(width 0.1)
				(type default)
			)
			(layer "F.Fab")
		)
		(fp_line
			(start 0 3.81)
			(end 2.54 3.81)
			(stroke
				(width 0.1)
				(type default)
			)
			(layer "F.Fab")
		)
		(fp_poly
			(pts
				(xy -0.761746 0) (xy -2.285746 -0.762) (xy -2.285746 0.762)
			)
			(stroke
				(width 0)
				(type default)
			)
			(fill yes)
			(layer "F.Fab")
		)
		(pad "1" thru_hole circle
			(at 0 0 90)
			(size 1.0033 1.0033)
			(drill 0.249936)
			(layers "*.Cu" "*.Mask")
			(remove_unused_layers no)
			(net "TDR_DIFF_100_IN1_DP")
			(clearance 0.10795)
			(thermal_gap 0.10795)
			(padstack
				(mode front_inner_back)
				(layer "Inner"
					(shape circle)
					(size 0.8001 0.8001)
					(clearance 0.1524)
				)
				(layer "B.Cu"
					(shape circle)
					(size 1.0033 1.0033)
					(clearance 0.10795)
				)
			)
		)
		(pad "2" thru_hole circle
			(at 2.54 0 90)
			(size 1.9939 1.9939)
			(drill 0.249936)
			(layers "*.Cu" "*.Mask")
			(remove_unused_layers no)
			(net "T1_GND")
			(clearance 0.10795)
			(thermal_gap 0.10795)
			(padstack
				(mode front_inner_back)
				(layer "Inner"
					(shape circle)
					(size 0.8001 0.8001)
					(clearance 0.1524)
				)
				(layer "B.Cu"
					(shape circle)
					(size 1.9939 1.9939)
					(clearance 0.10795)
				)
			)
		)
		(pad "3" thru_hole circle
			(at 2.54 2.54 90)
			(size 1.9939 1.9939)
			(drill 0.249936)
			(layers "*.Cu" "*.Mask")
			(remove_unused_layers no)
			(net "T1_GND")
			(clearance 0.10795)
			(thermal_gap 0.10795)
			(padstack
				(mode front_inner_back)
				(layer "Inner"
					(shape circle)
					(size 0.8001 0.8001)
					(clearance 0.1524)
				)
				(layer "B.Cu"
					(shape circle)
					(size 1.9939 1.9939)
					(clearance 0.10795)
				)
			)
		)
		(pad "4" thru_hole circle
			(at 0 2.54 90)
			(size 1.0033 1.0033)
			(drill 0.249936)
			(layers "*.Cu" "*.Mask")
			(remove_unused_layers no)
			(net "TDR_DIFF_100_IN1_DN")
			(clearance 0.10795)
			(thermal_gap 0.10795)
			(padstack
				(mode front_inner_back)
				(layer "Inner"
					(shape circle)
					(size 0.8001 0.8001)
					(clearance 0.1524)
				)
				(layer "B.Cu"
					(shape circle)
					(size 1.0033 1.0033)
					(clearance 0.10795)
				)
			)
		)
	)
	(footprint ""
		(layer "F.Cu")
		(at 115.951 -54.193948 180)
		(property "Reference" "R4632"
			(at 0 0 180)
			(layer "F.SilkS")
			(hide yes)
			(effects
				(font
					(size 1.27 1.27)
				)
			)
		)
		(property "Value" ""
			(at 0 0 180)
			(layer "F.Fab")
			(effects
				(font
					(size 1.27 1.27)
				)
			)
		)
		(duplicate_pad_numbers_are_jumpers no)
		(fp_line
			(start 0.7874 0.4064)
			(end -0.7874 0.4064)
			(stroke
				(width 0.1524)
				(type default)
			)
			(layer "F.SilkS")
		)
		(fp_line
			(start 0.7874 -0.4064)
			(end 0.7874 0.4064)
			(stroke
				(width 0.1524)
				(type default)
			)
			(layer "F.SilkS")
		)
		(fp_line
			(start -0.7874 0.4064)
			(end -0.7874 -0.4064)
			(stroke
				(width 0.1524)
				(type default)
			)
			(layer "F.SilkS")
		)
		(fp_line
			(start -0.7874 -0.4064)
			(end 0.7874 -0.4064)
			(stroke
				(width 0.1524)
				(type default)
			)
			(layer "F.SilkS")
		)
		(fp_line
			(start 0.67945 0.3048)
			(end 0.120396 0.3048)
			(stroke
				(width 0.1)
				(type default)
			)
			(layer "F.Fab")
		)
		(fp_line
			(start 0.67945 -0.3048)
			(end 0.67945 0.3048)
			(stroke
				(width 0.1)
				(type default)
			)
			(layer "F.Fab")
		)
		(fp_line
			(start 0.12065 -0.2794)
			(end 0.12065 -0.3048)
			(stroke
				(width 0.1)
				(type default)
			)
			(layer "F.Fab")
		)
		(fp_line
			(start 0.12065 -0.3048)
			(end 0.67945 -0.3048)
			(stroke
				(width 0.1)
				(type default)
			)
			(layer "F.Fab")
		)
		(fp_line
			(start 0.120396 0.3048)
			(end 0.120396 0.2794)
			(stroke
				(width 0.1)
				(type default)
			)
			(layer "F.Fab")
		)
		(fp_line
			(start 0.120396 0.2794)
			(end -0.12065 0.2794)
			(stroke
				(width 0.1)
				(type default)
			)
			(layer "F.Fab")
		)
		(fp_line
			(start -0.12065 0.3048)
			(end -0.67945 0.3048)
			(stroke
				(width 0.1)
				(type default)
			)
			(layer "F.Fab")
		)
		(fp_line
			(start -0.12065 0.2794)
			(end -0.12065 0.3048)
			(stroke
				(width 0.1)
				(type default)
			)
			(layer "F.Fab")
		)
		(fp_line
			(start -0.12065 -0.2794)
			(end 0.12065 -0.2794)
			(stroke
				(width 0.1)
				(type default)
			)
			(layer "F.Fab")
		)
		(fp_line
			(start -0.12065 -0.305054)
			(end -0.12065 -0.2794)
			(stroke
				(width 0.1)
				(type default)
			)
			(layer "F.Fab")
		)
		(fp_line
			(start -0.67945 0.3048)
			(end -0.67945 -0.305054)
			(stroke
				(width 0.1)
				(type default)
			)
			(layer "F.Fab")
		)
		(fp_line
			(start -0.67945 -0.305054)
			(end -0.12065 -0.305054)
			(stroke
				(width 0.1)
				(type default)
			)
			(layer "F.Fab")
		)
		(pad "1" smd circle
			(at -0.40005 0 180)
			(size 0 0)
			(layers "F.Cu" "F.Mask" "F.Paste")
			(net "JTAG_BMC_SW_TMS_R")
		)
		(pad "2" smd circle
			(at 0.40005 0 180)
			(size 0 0)
			(layers "F.Cu" "F.Mask" "F.Paste")
			(net "JTAG_BMC_SW_TMS")
		)
	)
	(footprint ""
		(layer "F.Cu")
		(at 96.138238 -414.75533 -90)
		(property "Reference" "R4187"
			(at 0 0 270)
			(layer "F.SilkS")
			(hide yes)
			(effects
				(font
					(size 1.27 1.27)
				)
			)
		)
		(property "Value" ""
			(at 0 0 270)
			(layer "F.Fab")
			(effects
				(font
					(size 1.27 1.27)
				)
			)
		)
		(duplicate_pad_numbers_are_jumpers no)
		(fp_line
			(start -0.7874 0.4064)
			(end -0.7874 -0.4064)
			(stroke
				(width 0.1524)
				(type default)
			)
			(layer "F.SilkS")
		)
		(fp_line
			(start 0.7874 0.4064)
			(end -0.7874 0.4064)
			(stroke
				(width 0.1524)
				(type default)
			)
			(layer "F.SilkS")
		)
		(fp_line
			(start -0.7874 -0.4064)
			(end 0.7874 -0.4064)
			(stroke
				(width 0.1524)
				(type default)
			)
			(layer "F.SilkS")
		)
		(fp_line
			(start 0.7874 -0.4064)
			(end 0.7874 0.4064)
			(stroke
				(width 0.1524)
				(type default)
			)
			(layer "F.SilkS")
		)
		(fp_line
			(start -0.67945 0.3048)
			(end -0.67945 -0.305054)
			(stroke
				(width 0.1)
				(type default)
			)
			(layer "F.Fab")
		)
		(fp_line
			(start -0.12065 0.3048)
			(end -0.67945 0.3048)
			(stroke
				(width 0.1)
				(type default)
			)
			(layer "F.Fab")
		)
		(fp_line
			(start 0.120396 0.3048)
			(end 0.120396 0.2794)
			(stroke
				(width 0.1)
				(type default)
			)
			(layer "F.Fab")
		)
		(fp_line
			(start 0.67945 0.3048)
			(end 0.120396 0.3048)
			(stroke
				(width 0.1)
				(type default)
			)
			(layer "F.Fab")
		)
		(fp_line
			(start -0.12065 0.2794)
			(end -0.12065 0.3048)
			(stroke
				(width 0.1)
				(type default)
			)
			(layer "F.Fab")
		)
		(fp_line
			(start 0.120396 0.2794)
			(end -0.12065 0.2794)
			(stroke
				(width 0.1)
				(type default)
			)
			(layer "F.Fab")
		)
		(fp_line
			(start -0.12065 -0.2794)
			(end 0.12065 -0.2794)
			(stroke
				(width 0.1)
				(type default)
			)
			(layer "F.Fab")
		)
		(fp_line
			(start 0.12065 -0.2794)
			(end 0.12065 -0.3048)
			(stroke
				(width 0.1)
				(type default)
			)
			(layer "F.Fab")
		)
		(fp_line
			(start 0.12065 -0.3048)
			(end 0.67945 -0.3048)
			(stroke
				(width 0.1)
				(type default)
			)
			(layer "F.Fab")
		)
		(fp_line
			(start 0.67945 -0.3048)
			(end 0.67945 0.3048)
			(stroke
				(width 0.1)
				(type default)
			)
			(layer "F.Fab")
		)
		(fp_line
			(start -0.67945 -0.305054)
			(end -0.12065 -0.305054)
			(stroke
				(width 0.1)
				(type default)
			)
			(layer "F.Fab")
		)
		(fp_line
			(start -0.12065 -0.305054)
			(end -0.12065 -0.2794)
			(stroke
				(width 0.1)
				(type default)
			)
			(layer "F.Fab")
		)
		(pad "1" smd circle
			(at -0.40005 0 270)
			(size 0 0)
			(layers "F.Cu" "F.Mask" "F.Paste")
			(net "U272_2_ADD2")
		)
		(pad "2" smd circle
			(at 0.40005 0 270)
			(size 0 0)
			(layers "F.Cu" "F.Mask" "F.Paste")
			(net "GND")
		)
	)
	(footprint ""
		(layer "F.Cu")
		(at 277.230078 -417.2839 90)
		(property "Reference" "R4672"
			(at 0 0 90)
			(layer "F.SilkS")
			(hide yes)
			(effects
				(font
					(size 1.27 1.27)
				)
			)
		)
		(property "Value" ""
			(at 0 0 90)
			(layer "F.Fab")
			(effects
				(font
					(size 1.27 1.27)
				)
			)
		)
		(duplicate_pad_numbers_are_jumpers no)
		(fp_line
			(start 0.7874 -0.4064)
			(end 0.7874 0.4064)
			(stroke
				(width 0.1524)
				(type default)
			)
			(layer "F.SilkS")
		)
		(fp_line
			(start -0.7874 -0.4064)
			(end 0.7874 -0.4064)
			(stroke
				(width 0.1524)
				(type default)
			)
			(layer "F.SilkS")
		)
		(fp_line
			(start 0.7874 0.4064)
			(end -0.7874 0.4064)
			(stroke
				(width 0.1524)
				(type default)
			)
			(layer "F.SilkS")
		)
		(fp_line
			(start -0.7874 0.4064)
			(end -0.7874 -0.4064)
			(stroke
				(width 0.1524)
				(type default)
			)
			(layer "F.SilkS")
		)
		(fp_line
			(start -0.12065 -0.305054)
			(end -0.12065 -0.2794)
			(stroke
				(width 0.1)
				(type default)
			)
			(layer "F.Fab")
		)
		(fp_line
			(start -0.67945 -0.305054)
			(end -0.12065 -0.305054)
			(stroke
				(width 0.1)
				(type default)
			)
			(layer "F.Fab")
		)
		(fp_line
			(start 0.67945 -0.3048)
			(end 0.67945 0.3048)
			(stroke
				(width 0.1)
				(type default)
			)
			(layer "F.Fab")
		)
		(fp_line
			(start 0.12065 -0.3048)
			(end 0.67945 -0.3048)
			(stroke
				(width 0.1)
				(type default)
			)
			(layer "F.Fab")
		)
		(fp_line
			(start 0.12065 -0.2794)
			(end 0.12065 -0.3048)
			(stroke
				(width 0.1)
				(type default)
			)
			(layer "F.Fab")
		)
		(fp_line
			(start -0.12065 -0.2794)
			(end 0.12065 -0.2794)
			(stroke
				(width 0.1)
				(type default)
			)
			(layer "F.Fab")
		)
		(fp_line
			(start 0.120396 0.2794)
			(end -0.12065 0.2794)
			(stroke
				(width 0.1)
				(type default)
			)
			(layer "F.Fab")
		)
		(fp_line
			(start -0.12065 0.2794)
			(end -0.12065 0.3048)
			(stroke
				(width 0.1)
				(type default)
			)
			(layer "F.Fab")
		)
		(fp_line
			(start 0.67945 0.3048)
			(end 0.120396 0.3048)
			(stroke
				(width 0.1)
				(type default)
			)
			(layer "F.Fab")
		)
		(fp_line
			(start 0.120396 0.3048)
			(end 0.120396 0.2794)
			(stroke
				(width 0.1)
				(type default)
			)
			(layer "F.Fab")
		)
		(fp_line
			(start -0.12065 0.3048)
			(end -0.67945 0.3048)
			(stroke
				(width 0.1)
				(type default)
			)
			(layer "F.Fab")
		)
		(fp_line
			(start -0.67945 0.3048)
			(end -0.67945 -0.305054)
			(stroke
				(width 0.1)
				(type default)
			)
			(layer "F.Fab")
		)
		(pad "1" smd circle
			(at -0.40005 0 90)
			(size 0 0)
			(layers "F.Cu" "F.Mask" "F.Paste")
			(net "P3V3_AUX")
		)
		(pad "2" smd circle
			(at 0.40005 0 90)
			(size 0 0)
			(layers "F.Cu" "F.Mask" "F.Paste")
			(net "A_HSC_LOW_GATE")
		)
	)
	(footprint ""
		(layer "F.Cu")
		(at 288.794952 -354.000816 -90)
		(property "Reference" "PL210"
			(at -2.553462 8.124952 0)
			(unlocked yes)
			(layer "F.SilkS")
			(effects
				(font
					(size 0.7874 0.5842)
					(thickness 0.1524)
				)
				(justify left)
			)
		)
		(property "Value" ""
			(at 0 0 270)
			(layer "F.Fab")
			(effects
				(font
					(size 1.27 1.27)
				)
			)
		)
		(duplicate_pad_numbers_are_jumpers no)
		(fp_line
			(start -4.99999 3.750056)
			(end -4.99999 2.2479)
			(stroke
				(width 0.1524)
				(type default)
			)
			(layer "F.SilkS")
		)
		(fp_line
			(start 0 3.750056)
			(end -4.99999 3.750056)
			(stroke
				(width 0.1524)
				(type default)
			)
			(layer "F.SilkS")
		)
		(fp_line
			(start 4.99999 3.750056)
			(end 0 3.750056)
			(stroke
				(width 0.1524)
				(type default)
			)
			(layer "F.SilkS")
		)
		(fp_line
			(start 4.99999 2.2352)
			(end 4.99999 3.750056)
			(stroke
				(width 0.1524)
				(type default)
			)
			(layer "F.SilkS")
		)
		(fp_line
			(start -4.99999 -2.2479)
			(end -4.99999 -3.750056)
			(stroke
				(width 0.1524)
				(type default)
			)
			(layer "F.SilkS")
		)
		(fp_line
			(start -4.99999 -3.750056)
			(end 4.99999 -3.750056)
			(stroke
				(width 0.1524)
				(type default)
			)
			(layer "F.SilkS")
		)
		(fp_line
			(start 4.99999 -3.750056)
			(end 4.99999 -2.2479)
			(stroke
				(width 0.1524)
				(type default)
			)
			(layer "F.SilkS")
		)
		(fp_line
			(start -4.99999 3.750056)
			(end -4.99999 -3.750056)
			(stroke
				(width 0.1)
				(type default)
			)
			(layer "F.Fab")
		)
		(fp_line
			(start 0 3.750056)
			(end -4.99999 3.750056)
			(stroke
				(width 0.1)
				(type default)
			)
			(layer "F.Fab")
		)
		(fp_line
			(start 4.99999 3.750056)
			(end 0 3.750056)
			(stroke
				(width 0.1)
				(type default)
			)
			(layer "F.Fab")
		)
		(fp_line
			(start -4.99999 -3.750056)
			(end 4.99999 -3.750056)
			(stroke
				(width 0.1)
				(type default)
			)
			(layer "F.Fab")
		)
		(fp_line
			(start 4.99999 -3.750056)
			(end 4.99999 3.750056)
			(stroke
				(width 0.1)
				(type default)
			)
			(layer "F.Fab")
		)
		(pad "1" smd rect
			(at -3.299968 0 270)
			(size 3.302 4.2164)
			(layers "F.Cu" "F.Mask" "F.Paste")
			(net "SW_PVCCFA_EHV_FIVRA_CPU0_SW4")
		)
		(pad "2" smd rect
			(at 3.299968 0 270)
			(size 3.302 4.2164)
			(layers "F.Cu" "F.Mask" "F.Paste")
			(net "PVCCFA_EHV_FIVRA_CPU0")
		)
	)
	(footprint ""
		(layer "F.Cu")
		(at 298.04995 -417.2204)
		(property "Reference" "R4576"
			(at 0 0 0)
			(layer "F.SilkS")
			(hide yes)
			(effects
				(font
					(size 1.27 1.27)
				)
			)
		)
		(property "Value" ""
			(at 0 0 0)
			(layer "F.Fab")
			(effects
				(font
					(size 1.27 1.27)
				)
			)
		)
		(duplicate_pad_numbers_are_jumpers no)
		(fp_line
			(start -0.7874 -0.4064)
			(end 0.7874 -0.4064)
			(stroke
				(width 0.1524)
				(type default)
			)
			(layer "F.SilkS")
		)
		(fp_line
			(start -0.7874 0.4064)
			(end -0.7874 -0.4064)
			(stroke
				(width 0.1524)
				(type default)
			)
			(layer "F.SilkS")
		)
		(fp_line
			(start 0.7874 -0.4064)
			(end 0.7874 0.4064)
			(stroke
				(width 0.1524)
				(type default)
			)
			(layer "F.SilkS")
		)
		(fp_line
			(start 0.7874 0.4064)
			(end -0.7874 0.4064)
			(stroke
				(width 0.1524)
				(type default)
			)
			(layer "F.SilkS")
		)
		(fp_line
			(start -0.67945 -0.305054)
			(end -0.12065 -0.305054)
			(stroke
				(width 0.1)
				(type default)
			)
			(layer "F.Fab")
		)
		(fp_line
			(start -0.67945 0.3048)
			(end -0.67945 -0.305054)
			(stroke
				(width 0.1)
				(type default)
			)
			(layer "F.Fab")
		)
		(fp_line
			(start -0.12065 -0.305054)
			(end -0.12065 -0.2794)
			(stroke
				(width 0.1)
				(type default)
			)
			(layer "F.Fab")
		)
		(fp_line
			(start -0.12065 -0.2794)
			(end 0.12065 -0.2794)
			(stroke
				(width 0.1)
				(type default)
			)
			(layer "F.Fab")
		)
		(fp_line
			(start -0.12065 0.2794)
			(end -0.12065 0.3048)
			(stroke
				(width 0.1)
				(type default)
			)
			(layer "F.Fab")
		)
		(fp_line
			(start -0.12065 0.3048)
			(end -0.67945 0.3048)
			(stroke
				(width 0.1)
				(type default)
			)
			(layer "F.Fab")
		)
		(fp_line
			(start 0.120396 0.2794)
			(end -0.12065 0.2794)
			(stroke
				(width 0.1)
				(type default)
			)
			(layer "F.Fab")
		)
		(fp_line
			(start 0.120396 0.3048)
			(end 0.120396 0.2794)
			(stroke
				(width 0.1)
				(type default)
			)
			(layer "F.Fab")
		)
		(fp_line
			(start 0.12065 -0.3048)
			(end 0.67945 -0.3048)
			(stroke
				(width 0.1)
				(type default)
			)
			(layer "F.Fab")
		)
		(fp_line
			(start 0.12065 -0.2794)
			(end 0.12065 -0.3048)
			(stroke
				(width 0.1)
				(type default)
			)
			(layer "F.Fab")
		)
		(fp_line
			(start 0.67945 -0.3048)
			(end 0.67945 0.3048)
			(stroke
				(width 0.1)
				(type default)
			)
			(layer "F.Fab")
		)
		(fp_line
			(start 0.67945 0.3048)
			(end 0.120396 0.3048)
			(stroke
				(width 0.1)
				(type default)
			)
			(layer "F.Fab")
		)
		(pad "1" smd circle
			(at -0.40005 0)
			(size 0 0)
			(layers "F.Cu" "F.Mask" "F.Paste")
			(net "GPU_3V3IO_RSVD5_FFU")
		)
		(pad "2" smd circle
			(at 0.40005 0)
			(size 0 0)
			(layers "F.Cu" "F.Mask" "F.Paste")
			(net "GPU_3V3IO_RSVD5_FFU_ISO")
		)
	)
	(footprint ""
		(layer "F.Cu")
		(at 328.620882 -333.61884)
		(property "Reference" "PL8"
			(at -6.299962 4.735322 0)
			(unlocked yes)
			(layer "F.SilkS")
			(effects
				(font
					(size 0.7874 0.5842)
					(thickness 0.1524)
				)
				(justify left)
			)
		)
		(property "Value" ""
			(at 0 0 0)
			(layer "F.Fab")
			(effects
				(font
					(size 1.27 1.27)
				)
			)
		)
		(duplicate_pad_numbers_are_jumpers no)
		(fp_line
			(start -3.750056 -5.500116)
			(end -2.393442 -5.500116)
			(stroke
				(width 0.1524)
				(type default)
			)
			(layer "F.SilkS")
		)
		(fp_line
			(start -3.750056 5.500116)
			(end -3.750056 -5.500116)
			(stroke
				(width 0.1524)
				(type default)
			)
			(layer "F.SilkS")
		)
		(fp_line
			(start -2.393442 5.500116)
			(end -3.750056 5.500116)
			(stroke
				(width 0.1524)
				(type default)
			)
			(layer "F.SilkS")
		)
		(fp_line
			(start 2.393442 5.500116)
			(end 3.750056 5.500116)
			(stroke
				(width 0.1524)
				(type default)
			)
			(layer "F.SilkS")
		)
		(fp_line
			(start 3.750056 -5.500116)
			(end 2.393442 -5.500116)
			(stroke
				(width 0.1524)
				(type default)
			)
			(layer "F.SilkS")
		)
		(fp_line
			(start 3.750056 0.786892)
			(end 3.750056 -5.500116)
			(stroke
				(width 0.1524)
				(type default)
			)
			(layer "F.SilkS")
		)
		(fp_line
			(start 3.750056 5.500116)
			(end 3.750056 2.056892)
			(stroke
				(width 0.1524)
				(type default)
			)
			(layer "F.SilkS")
		)
		(fp_poly
			(pts
				(xy -3.060192 -6.962394) (xy -2.701036 -5.884672) (xy -3.778504 -6.244082)
			)
			(stroke
				(width 0)
				(type default)
			)
			(fill yes)
			(layer "F.SilkS")
		)
		(fp_line
			(start -3.750056 -5.500116)
			(end -3.750056 5.500116)
			(stroke
				(width 0.1)
				(type default)
			)
			(layer "F.Fab")
		)
		(fp_line
			(start -3.750056 5.500116)
			(end 3.750056 5.500116)
			(stroke
				(width 0.1)
				(type default)
			)
			(layer "F.Fab")
		)
		(fp_line
			(start 3.750056 -5.500116)
			(end -3.750056 -5.500116)
			(stroke
				(width 0.1)
				(type default)
			)
			(layer "F.Fab")
		)
		(fp_line
			(start 3.750056 5.500116)
			(end 3.750056 -5.500116)
			(stroke
				(width 0.1)
				(type default)
			)
			(layer "F.Fab")
		)
		(fp_poly
			(pts
				(xy -4.9276 -4.757928) (xy -4.9276 -3.741928) (xy -3.9116 -4.249928)
			)
			(stroke
				(width 0)
				(type default)
			)
			(fill yes)
			(layer "F.Fab")
		)
		(pad "1" smd rect
			(at 0 -4.249928 270)
			(size 2.413 4.5212)
			(layers "F.Cu" "F.Mask" "F.Paste")
			(net "SW_PVCCIN_CPU0_SW7")
		)
		(pad "2" smd rect
			(at 0 -1.175004 270)
			(size 1.3716 4.5212)
			(layers "F.Cu" "F.Mask" "F.Paste")
			(net "IND_P0_CPL7")
		)
		(pad "3" smd rect
			(at 0 1.175004 270)
			(size 1.3716 4.5212)
			(layers "F.Cu" "F.Mask" "F.Paste")
			(net "IND_P0_CPL6")
		)
		(pad "4" smd rect
			(at 0 4.249928 270)
			(size 2.413 4.5212)
			(layers "F.Cu" "F.Mask" "F.Paste")
			(net "PVCCIN_CPU0")
		)
	)
	(footprint ""
		(layer "F.Cu")
		(at 326.647302 -20.548346 90)
		(property "Reference" "R1271"
			(at 0 0 90)
			(layer "F.SilkS")
			(hide yes)
			(effects
				(font
					(size 1.27 1.27)
				)
			)
		)
		(property "Value" ""
			(at 0 0 90)
			(layer "F.Fab")
			(effects
				(font
					(size 1.27 1.27)
				)
			)
		)
		(duplicate_pad_numbers_are_jumpers no)
		(fp_line
			(start 0.7874 -0.4064)
			(end 0.7874 0.4064)
			(stroke
				(width 0.1524)
				(type default)
			)
			(layer "F.SilkS")
		)
		(fp_line
			(start -0.7874 -0.4064)
			(end 0.7874 -0.4064)
			(stroke
				(width 0.1524)
				(type default)
			)
			(layer "F.SilkS")
		)
		(fp_line
			(start 0.7874 0.4064)
			(end -0.7874 0.4064)
			(stroke
				(width 0.1524)
				(type default)
			)
			(layer "F.SilkS")
		)
		(fp_line
			(start -0.7874 0.4064)
			(end -0.7874 -0.4064)
			(stroke
				(width 0.1524)
				(type default)
			)
			(layer "F.SilkS")
		)
		(fp_line
			(start -0.12065 -0.305054)
			(end -0.12065 -0.2794)
			(stroke
				(width 0.1)
				(type default)
			)
			(layer "F.Fab")
		)
		(fp_line
			(start -0.67945 -0.305054)
			(end -0.12065 -0.305054)
			(stroke
				(width 0.1)
				(type default)
			)
			(layer "F.Fab")
		)
		(fp_line
			(start 0.67945 -0.3048)
			(end 0.67945 0.3048)
			(stroke
				(width 0.1)
				(type default)
			)
			(layer "F.Fab")
		)
		(fp_line
			(start 0.12065 -0.3048)
			(end 0.67945 -0.3048)
			(stroke
				(width 0.1)
				(type default)
			)
			(layer "F.Fab")
		)
		(fp_line
			(start 0.12065 -0.2794)
			(end 0.12065 -0.3048)
			(stroke
				(width 0.1)
				(type default)
			)
			(layer "F.Fab")
		)
		(fp_line
			(start -0.12065 -0.2794)
			(end 0.12065 -0.2794)
			(stroke
				(width 0.1)
				(type default)
			)
			(layer "F.Fab")
		)
		(fp_line
			(start 0.120396 0.2794)
			(end -0.12065 0.2794)
			(stroke
				(width 0.1)
				(type default)
			)
			(layer "F.Fab")
		)
		(fp_line
			(start -0.12065 0.2794)
			(end -0.12065 0.3048)
			(stroke
				(width 0.1)
				(type default)
			)
			(layer "F.Fab")
		)
		(fp_line
			(start 0.67945 0.3048)
			(end 0.120396 0.3048)
			(stroke
				(width 0.1)
				(type default)
			)
			(layer "F.Fab")
		)
		(fp_line
			(start 0.120396 0.3048)
			(end 0.120396 0.2794)
			(stroke
				(width 0.1)
				(type default)
			)
			(layer "F.Fab")
		)
		(fp_line
			(start -0.12065 0.3048)
			(end -0.67945 0.3048)
			(stroke
				(width 0.1)
				(type default)
			)
			(layer "F.Fab")
		)
		(fp_line
			(start -0.67945 0.3048)
			(end -0.67945 -0.305054)
			(stroke
				(width 0.1)
				(type default)
			)
			(layer "F.Fab")
		)
		(pad "1" smd circle
			(at -0.40005 0 90)
			(size 0 0)
			(layers "F.Cu" "F.Mask" "F.Paste")
			(net "P3V3_AUX")
		)
		(pad "2" smd circle
			(at 0.40005 0 90)
			(size 0 0)
			(layers "F.Cu" "F.Mask" "F.Paste")
			(net "FM_PCH_SATA_RAID_KEY")
		)
	)
	(footprint ""
		(layer "F.Cu")
		(at 162.34283 -74.759058 180)
		(property "Reference" "R2315"
			(at 0 0 180)
			(layer "F.SilkS")
			(hide yes)
			(effects
				(font
					(size 1.27 1.27)
				)
			)
		)
		(property "Value" ""
			(at 0 0 180)
			(layer "F.Fab")
			(effects
				(font
					(size 1.27 1.27)
				)
			)
		)
		(duplicate_pad_numbers_are_jumpers no)
		(fp_line
			(start 0.7874 0.4064)
			(end -0.7874 0.4064)
			(stroke
				(width 0.1524)
				(type default)
			)
			(layer "F.SilkS")
		)
		(fp_line
			(start 0.7874 -0.4064)
			(end 0.7874 0.4064)
			(stroke
				(width 0.1524)
				(type default)
			)
			(layer "F.SilkS")
		)
		(fp_line
			(start -0.7874 0.4064)
			(end -0.7874 -0.4064)
			(stroke
				(width 0.1524)
				(type default)
			)
			(layer "F.SilkS")
		)
		(fp_line
			(start -0.7874 -0.4064)
			(end 0.7874 -0.4064)
			(stroke
				(width 0.1524)
				(type default)
			)
			(layer "F.SilkS")
		)
		(fp_line
			(start 0.67945 0.3048)
			(end 0.120396 0.3048)
			(stroke
				(width 0.1)
				(type default)
			)
			(layer "F.Fab")
		)
		(fp_line
			(start 0.67945 -0.3048)
			(end 0.67945 0.3048)
			(stroke
				(width 0.1)
				(type default)
			)
			(layer "F.Fab")
		)
		(fp_line
			(start 0.12065 -0.2794)
			(end 0.12065 -0.3048)
			(stroke
				(width 0.1)
				(type default)
			)
			(layer "F.Fab")
		)
		(fp_line
			(start 0.12065 -0.3048)
			(end 0.67945 -0.3048)
			(stroke
				(width 0.1)
				(type default)
			)
			(layer "F.Fab")
		)
		(fp_line
			(start 0.120396 0.3048)
			(end 0.120396 0.2794)
			(stroke
				(width 0.1)
				(type default)
			)
			(layer "F.Fab")
		)
		(fp_line
			(start 0.120396 0.2794)
			(end -0.12065 0.2794)
			(stroke
				(width 0.1)
				(type default)
			)
			(layer "F.Fab")
		)
		(fp_line
			(start -0.12065 0.3048)
			(end -0.67945 0.3048)
			(stroke
				(width 0.1)
				(type default)
			)
			(layer "F.Fab")
		)
		(fp_line
			(start -0.12065 0.2794)
			(end -0.12065 0.3048)
			(stroke
				(width 0.1)
				(type default)
			)
			(layer "F.Fab")
		)
		(fp_line
			(start -0.12065 -0.2794)
			(end 0.12065 -0.2794)
			(stroke
				(width 0.1)
				(type default)
			)
			(layer "F.Fab")
		)
		(fp_line
			(start -0.12065 -0.305054)
			(end -0.12065 -0.2794)
			(stroke
				(width 0.1)
				(type default)
			)
			(layer "F.Fab")
		)
		(fp_line
			(start -0.67945 0.3048)
			(end -0.67945 -0.305054)
			(stroke
				(width 0.1)
				(type default)
			)
			(layer "F.Fab")
		)
		(fp_line
			(start -0.67945 -0.305054)
			(end -0.12065 -0.305054)
			(stroke
				(width 0.1)
				(type default)
			)
			(layer "F.Fab")
		)
		(pad "1" smd circle
			(at -0.40005 0 180)
			(size 0 0)
			(layers "F.Cu" "F.Mask" "F.Paste")
			(net "P3V3_AUX")
		)
		(pad "2" smd circle
			(at 0.40005 0 180)
			(size 0 0)
			(layers "F.Cu" "F.Mask" "F.Paste")
			(net "PCA9543_S3M_INT0_N")
		)
	)
	(footprint ""
		(layer "F.Cu")
		(at 46.626018 -437.792368)
		(property "Reference" "R2990"
			(at 0 0 0)
			(layer "F.SilkS")
			(hide yes)
			(effects
				(font
					(size 1.27 1.27)
				)
			)
		)
		(property "Value" ""
			(at 0 0 0)
			(layer "F.Fab")
			(effects
				(font
					(size 1.27 1.27)
				)
			)
		)
		(duplicate_pad_numbers_are_jumpers no)
		(fp_line
			(start -0.7874 -0.4064)
			(end 0.7874 -0.4064)
			(stroke
				(width 0.1524)
				(type default)
			)
			(layer "F.SilkS")
		)
		(fp_line
			(start -0.7874 0.4064)
			(end -0.7874 -0.4064)
			(stroke
				(width 0.1524)
				(type default)
			)
			(layer "F.SilkS")
		)
		(fp_line
			(start 0.7874 -0.4064)
			(end 0.7874 0.4064)
			(stroke
				(width 0.1524)
				(type default)
			)
			(layer "F.SilkS")
		)
		(fp_line
			(start 0.7874 0.4064)
			(end -0.7874 0.4064)
			(stroke
				(width 0.1524)
				(type default)
			)
			(layer "F.SilkS")
		)
		(fp_line
			(start -0.67945 -0.305054)
			(end -0.12065 -0.305054)
			(stroke
				(width 0.1)
				(type default)
			)
			(layer "F.Fab")
		)
		(fp_line
			(start -0.67945 0.3048)
			(end -0.67945 -0.305054)
			(stroke
				(width 0.1)
				(type default)
			)
			(layer "F.Fab")
		)
		(fp_line
			(start -0.12065 -0.305054)
			(end -0.12065 -0.2794)
			(stroke
				(width 0.1)
				(type default)
			)
			(layer "F.Fab")
		)
		(fp_line
			(start -0.12065 -0.2794)
			(end 0.12065 -0.2794)
			(stroke
				(width 0.1)
				(type default)
			)
			(layer "F.Fab")
		)
		(fp_line
			(start -0.12065 0.2794)
			(end -0.12065 0.3048)
			(stroke
				(width 0.1)
				(type default)
			)
			(layer "F.Fab")
		)
		(fp_line
			(start -0.12065 0.3048)
			(end -0.67945 0.3048)
			(stroke
				(width 0.1)
				(type default)
			)
			(layer "F.Fab")
		)
		(fp_line
			(start 0.120396 0.2794)
			(end -0.12065 0.2794)
			(stroke
				(width 0.1)
				(type default)
			)
			(layer "F.Fab")
		)
		(fp_line
			(start 0.120396 0.3048)
			(end 0.120396 0.2794)
			(stroke
				(width 0.1)
				(type default)
			)
			(layer "F.Fab")
		)
		(fp_line
			(start 0.12065 -0.3048)
			(end 0.67945 -0.3048)
			(stroke
				(width 0.1)
				(type default)
			)
			(layer "F.Fab")
		)
		(fp_line
			(start 0.12065 -0.2794)
			(end 0.12065 -0.3048)
			(stroke
				(width 0.1)
				(type default)
			)
			(layer "F.Fab")
		)
		(fp_line
			(start 0.67945 -0.3048)
			(end 0.67945 0.3048)
			(stroke
				(width 0.1)
				(type default)
			)
			(layer "F.Fab")
		)
		(fp_line
			(start 0.67945 0.3048)
			(end 0.120396 0.3048)
			(stroke
				(width 0.1)
				(type default)
			)
			(layer "F.Fab")
		)
		(pad "1" smd circle
			(at -0.40005 0)
			(size 0 0)
			(layers "F.Cu" "F.Mask" "F.Paste")
			(net "SMB_2_BMC_GPU_BUF_R_SCL")
		)
		(pad "2" smd circle
			(at 0.40005 0)
			(size 0 0)
			(layers "F.Cu" "F.Mask" "F.Paste")
			(net "SMB_2_BMC_GPU_BUF_SCL")
		)
	)
	(footprint ""
		(layer "F.Cu")
		(at 113.494312 -129.408682 180)
		(property "Reference" "R3527"
			(at 0 0 180)
			(layer "F.SilkS")
			(hide yes)
			(effects
				(font
					(size 1.27 1.27)
				)
			)
		)
		(property "Value" ""
			(at 0 0 180)
			(layer "F.Fab")
			(effects
				(font
					(size 1.27 1.27)
				)
			)
		)
		(duplicate_pad_numbers_are_jumpers no)
		(fp_line
			(start 0.7874 0.4064)
			(end -0.7874 0.4064)
			(stroke
				(width 0.1524)
				(type default)
			)
			(layer "F.SilkS")
		)
		(fp_line
			(start 0.7874 -0.4064)
			(end 0.7874 0.4064)
			(stroke
				(width 0.1524)
				(type default)
			)
			(layer "F.SilkS")
		)
		(fp_line
			(start -0.7874 0.4064)
			(end -0.7874 -0.4064)
			(stroke
				(width 0.1524)
				(type default)
			)
			(layer "F.SilkS")
		)
		(fp_line
			(start -0.7874 -0.4064)
			(end 0.7874 -0.4064)
			(stroke
				(width 0.1524)
				(type default)
			)
			(layer "F.SilkS")
		)
		(fp_line
			(start 0.67945 0.3048)
			(end 0.120396 0.3048)
			(stroke
				(width 0.1)
				(type default)
			)
			(layer "F.Fab")
		)
		(fp_line
			(start 0.67945 -0.3048)
			(end 0.67945 0.3048)
			(stroke
				(width 0.1)
				(type default)
			)
			(layer "F.Fab")
		)
		(fp_line
			(start 0.12065 -0.2794)
			(end 0.12065 -0.3048)
			(stroke
				(width 0.1)
				(type default)
			)
			(layer "F.Fab")
		)
		(fp_line
			(start 0.12065 -0.3048)
			(end 0.67945 -0.3048)
			(stroke
				(width 0.1)
				(type default)
			)
			(layer "F.Fab")
		)
		(fp_line
			(start 0.120396 0.3048)
			(end 0.120396 0.2794)
			(stroke
				(width 0.1)
				(type default)
			)
			(layer "F.Fab")
		)
		(fp_line
			(start 0.120396 0.2794)
			(end -0.12065 0.2794)
			(stroke
				(width 0.1)
				(type default)
			)
			(layer "F.Fab")
		)
		(fp_line
			(start -0.12065 0.3048)
			(end -0.67945 0.3048)
			(stroke
				(width 0.1)
				(type default)
			)
			(layer "F.Fab")
		)
		(fp_line
			(start -0.12065 0.2794)
			(end -0.12065 0.3048)
			(stroke
				(width 0.1)
				(type default)
			)
			(layer "F.Fab")
		)
		(fp_line
			(start -0.12065 -0.2794)
			(end 0.12065 -0.2794)
			(stroke
				(width 0.1)
				(type default)
			)
			(layer "F.Fab")
		)
		(fp_line
			(start -0.12065 -0.305054)
			(end -0.12065 -0.2794)
			(stroke
				(width 0.1)
				(type default)
			)
			(layer "F.Fab")
		)
		(fp_line
			(start -0.67945 0.3048)
			(end -0.67945 -0.305054)
			(stroke
				(width 0.1)
				(type default)
			)
			(layer "F.Fab")
		)
		(fp_line
			(start -0.67945 -0.305054)
			(end -0.12065 -0.305054)
			(stroke
				(width 0.1)
				(type default)
			)
			(layer "F.Fab")
		)
		(pad "1" smd circle
			(at -0.40005 0 180)
			(size 0 0)
			(layers "F.Cu" "F.Mask" "F.Paste")
			(net "SMB_PCIE0_3V3AUX_SDA_R5")
		)
		(pad "2" smd circle
			(at 0.40005 0 180)
			(size 0 0)
			(layers "F.Cu" "F.Mask" "F.Paste")
			(net "SMB_SENSOR_E1S_3V3AUX_SDA")
		)
	)
	(footprint ""
		(layer "F.Cu")
		(at 367.411 -53.812948)
		(property "Reference" "R749"
			(at 0 0 0)
			(layer "F.SilkS")
			(hide yes)
			(effects
				(font
					(size 1.27 1.27)
				)
			)
		)
		(property "Value" ""
			(at 0 0 0)
			(layer "F.Fab")
			(effects
				(font
					(size 1.27 1.27)
				)
			)
		)
		(duplicate_pad_numbers_are_jumpers no)
		(fp_line
			(start -0.7874 -0.4064)
			(end 0.7874 -0.4064)
			(stroke
				(width 0.1524)
				(type default)
			)
			(layer "F.SilkS")
		)
		(fp_line
			(start -0.7874 0.4064)
			(end -0.7874 -0.4064)
			(stroke
				(width 0.1524)
				(type default)
			)
			(layer "F.SilkS")
		)
		(fp_line
			(start 0.7874 -0.4064)
			(end 0.7874 0.4064)
			(stroke
				(width 0.1524)
				(type default)
			)
			(layer "F.SilkS")
		)
		(fp_line
			(start 0.7874 0.4064)
			(end -0.7874 0.4064)
			(stroke
				(width 0.1524)
				(type default)
			)
			(layer "F.SilkS")
		)
		(fp_line
			(start -0.67945 -0.305054)
			(end -0.12065 -0.305054)
			(stroke
				(width 0.1)
				(type default)
			)
			(layer "F.Fab")
		)
		(fp_line
			(start -0.67945 0.3048)
			(end -0.67945 -0.305054)
			(stroke
				(width 0.1)
				(type default)
			)
			(layer "F.Fab")
		)
		(fp_line
			(start -0.12065 -0.305054)
			(end -0.12065 -0.2794)
			(stroke
				(width 0.1)
				(type default)
			)
			(layer "F.Fab")
		)
		(fp_line
			(start -0.12065 -0.2794)
			(end 0.12065 -0.2794)
			(stroke
				(width 0.1)
				(type default)
			)
			(layer "F.Fab")
		)
		(fp_line
			(start -0.12065 0.2794)
			(end -0.12065 0.3048)
			(stroke
				(width 0.1)
				(type default)
			)
			(layer "F.Fab")
		)
		(fp_line
			(start -0.12065 0.3048)
			(end -0.67945 0.3048)
			(stroke
				(width 0.1)
				(type default)
			)
			(layer "F.Fab")
		)
		(fp_line
			(start 0.120396 0.2794)
			(end -0.12065 0.2794)
			(stroke
				(width 0.1)
				(type default)
			)
			(layer "F.Fab")
		)
		(fp_line
			(start 0.120396 0.3048)
			(end 0.120396 0.2794)
			(stroke
				(width 0.1)
				(type default)
			)
			(layer "F.Fab")
		)
		(fp_line
			(start 0.12065 -0.3048)
			(end 0.67945 -0.3048)
			(stroke
				(width 0.1)
				(type default)
			)
			(layer "F.Fab")
		)
		(fp_line
			(start 0.12065 -0.2794)
			(end 0.12065 -0.3048)
			(stroke
				(width 0.1)
				(type default)
			)
			(layer "F.Fab")
		)
		(fp_line
			(start 0.67945 -0.3048)
			(end 0.67945 0.3048)
			(stroke
				(width 0.1)
				(type default)
			)
			(layer "F.Fab")
		)
		(fp_line
			(start 0.67945 0.3048)
			(end 0.120396 0.3048)
			(stroke
				(width 0.1)
				(type default)
			)
			(layer "F.Fab")
		)
		(pad "1" smd circle
			(at -0.40005 0)
			(size 0 0)
			(layers "F.Cu" "F.Mask" "F.Paste")
			(net "P1V05_PCH_AUX")
		)
		(pad "2" smd circle
			(at 0.40005 0)
			(size 0 0)
			(layers "F.Cu" "F.Mask" "F.Paste")
			(net "JTAG_DBP_TMS_PCH")
		)
	)
	(footprint ""
		(layer "F.Cu")
		(at 99.998276 -79.078836)
		(property "Reference" "D94"
			(at -50.01641 38.649402 90)
			(unlocked yes)
			(layer "F.SilkS")
			(effects
				(font
					(size 0.635 0.4064)
					(thickness 0.1524)
				)
				(justify left)
			)
		)
		(property "Value" ""
			(at 0 0 0)
			(layer "F.Fab")
			(effects
				(font
					(size 1.27 1.27)
				)
			)
		)
		(duplicate_pad_numbers_are_jumpers no)
		(fp_line
			(start -0.90678 0.4826)
			(end -0.90678 -0.4699)
			(stroke
				(width 0.1524)
				(type default)
			)
			(layer "F.SilkS")
		)
		(fp_line
			(start -0.89408 -0.4826)
			(end 0.90678 -0.4826)
			(stroke
				(width 0.1524)
				(type default)
			)
			(layer "F.SilkS")
		)
		(fp_line
			(start -0.79248 -0.4826)
			(end 1.03378 -0.4826)
			(stroke
				(width 0.1524)
				(type default)
			)
			(layer "F.SilkS")
		)
		(fp_line
			(start -0.64008 -0.4826)
			(end 1.16078 -0.4826)
			(stroke
				(width 0.1524)
				(type default)
			)
			(layer "F.SilkS")
		)
		(fp_line
			(start 0.90678 -0.4826)
			(end 0.90678 0.4826)
			(stroke
				(width 0.1524)
				(type default)
			)
			(layer "F.SilkS")
		)
		(fp_line
			(start 0.90678 0.4826)
			(end -0.90678 0.4826)
			(stroke
				(width 0.1524)
				(type default)
			)
			(layer "F.SilkS")
		)
		(fp_line
			(start 1.03378 -0.4826)
			(end 1.03378 0.4826)
			(stroke
				(width 0.1524)
				(type default)
			)
			(layer "F.SilkS")
		)
		(fp_line
			(start 1.03378 0.4826)
			(end -0.79248 0.4826)
			(stroke
				(width 0.1524)
				(type default)
			)
			(layer "F.SilkS")
		)
		(fp_line
			(start 1.16078 -0.4826)
			(end 1.16078 0.4826)
			(stroke
				(width 0.1524)
				(type default)
			)
			(layer "F.SilkS")
		)
		(fp_line
			(start 1.16078 0.4826)
			(end -0.64008 0.4826)
			(stroke
				(width 0.1524)
				(type default)
			)
			(layer "F.SilkS")
		)
		(fp_line
			(start -0.499872 -0.249936)
			(end 0.499872 -0.249936)
			(stroke
				(width 0.1)
				(type default)
			)
			(layer "F.Fab")
		)
		(fp_line
			(start -0.499872 0.249936)
			(end -0.499872 -0.249936)
			(stroke
				(width 0.1)
				(type default)
			)
			(layer "F.Fab")
		)
		(fp_line
			(start 0.499872 -0.249936)
			(end 0.499872 0.249936)
			(stroke
				(width 0.1)
				(type default)
			)
			(layer "F.Fab")
		)
		(fp_line
			(start 0.499872 0.249936)
			(end -0.499872 0.249936)
			(stroke
				(width 0.1)
				(type default)
			)
			(layer "F.Fab")
		)
		(pad "A" smd rect
			(at -0.47498 0)
			(size 0.6096 0.7112)
			(layers "F.Cu" "F.Mask" "F.Paste")
			(net "LED_FM_PCH_SLP_S4_N")
		)
		(pad "C" smd rect
			(at 0.47498 0)
			(size 0.6096 0.7112)
			(layers "F.Cu" "F.Mask" "F.Paste")
			(net "LED_FM_PCH_SLP_S4_N_D")
		)
	)
	(footprint ""
		(layer "F.Cu")
		(at 31.540196 -169.04081)
		(property "Reference" "PC394"
			(at 0 0 0)
			(layer "F.SilkS")
			(hide yes)
			(effects
				(font
					(size 1.27 1.27)
				)
			)
		)
		(property "Value" ""
			(at 0 0 0)
			(layer "F.Fab")
			(effects
				(font
					(size 1.27 1.27)
				)
			)
		)
		(duplicate_pad_numbers_are_jumpers no)
		(fp_line
			(start -0.7874 -0.4064)
			(end 0.7874 -0.4064)
			(stroke
				(width 0.1524)
				(type default)
			)
			(layer "F.SilkS")
		)
		(fp_line
			(start -0.7874 0.4064)
			(end -0.7874 -0.4064)
			(stroke
				(width 0.1524)
				(type default)
			)
			(layer "F.SilkS")
		)
		(fp_line
			(start 0.7874 -0.4064)
			(end 0.7874 0.4064)
			(stroke
				(width 0.1524)
				(type default)
			)
			(layer "F.SilkS")
		)
		(fp_line
			(start 0.7874 0.4064)
			(end -0.7874 0.4064)
			(stroke
				(width 0.1524)
				(type default)
			)
			(layer "F.SilkS")
		)
		(fp_line
			(start -0.67945 -0.305054)
			(end -0.12065 -0.305054)
			(stroke
				(width 0.1)
				(type default)
			)
			(layer "F.Fab")
		)
		(fp_line
			(start -0.67945 0.3048)
			(end -0.67945 -0.305054)
			(stroke
				(width 0.1)
				(type default)
			)
			(layer "F.Fab")
		)
		(fp_line
			(start -0.12065 -0.305054)
			(end -0.12065 -0.2794)
			(stroke
				(width 0.1)
				(type default)
			)
			(layer "F.Fab")
		)
		(fp_line
			(start -0.12065 -0.2794)
			(end 0.12065 -0.2794)
			(stroke
				(width 0.1)
				(type default)
			)
			(layer "F.Fab")
		)
		(fp_line
			(start -0.12065 0.2794)
			(end -0.12065 0.3048)
			(stroke
				(width 0.1)
				(type default)
			)
			(layer "F.Fab")
		)
		(fp_line
			(start -0.12065 0.3048)
			(end -0.67945 0.3048)
			(stroke
				(width 0.1)
				(type default)
			)
			(layer "F.Fab")
		)
		(fp_line
			(start 0.120396 0.2794)
			(end -0.12065 0.2794)
			(stroke
				(width 0.1)
				(type default)
			)
			(layer "F.Fab")
		)
		(fp_line
			(start 0.120396 0.3048)
			(end 0.120396 0.2794)
			(stroke
				(width 0.1)
				(type default)
			)
			(layer "F.Fab")
		)
		(fp_line
			(start 0.12065 -0.3048)
			(end 0.67945 -0.3048)
			(stroke
				(width 0.1)
				(type default)
			)
			(layer "F.Fab")
		)
		(fp_line
			(start 0.12065 -0.2794)
			(end 0.12065 -0.3048)
			(stroke
				(width 0.1)
				(type default)
			)
			(layer "F.Fab")
		)
		(fp_line
			(start 0.67945 -0.3048)
			(end 0.67945 0.3048)
			(stroke
				(width 0.1)
				(type default)
			)
			(layer "F.Fab")
		)
		(fp_line
			(start 0.67945 0.3048)
			(end 0.120396 0.3048)
			(stroke
				(width 0.1)
				(type default)
			)
			(layer "F.Fab")
		)
		(pad "1" smd circle
			(at -0.40005 0)
			(size 0 0)
			(layers "F.Cu" "F.Mask" "F.Paste")
			(net "PVCCD_HV_CPU1_VCC")
		)
		(pad "2" smd circle
			(at 0.40005 0)
			(size 0 0)
			(layers "F.Cu" "F.Mask" "F.Paste")
			(net "GND")
		)
	)
	(footprint ""
		(layer "F.Cu")
		(at 317.396622 -52.161948)
		(property "Reference" "R1820"
			(at 0 0 0)
			(layer "F.SilkS")
			(hide yes)
			(effects
				(font
					(size 1.27 1.27)
				)
			)
		)
		(property "Value" ""
			(at 0 0 0)
			(layer "F.Fab")
			(effects
				(font
					(size 1.27 1.27)
				)
			)
		)
		(duplicate_pad_numbers_are_jumpers no)
		(fp_line
			(start -0.7874 -0.4064)
			(end 0.7874 -0.4064)
			(stroke
				(width 0.1524)
				(type default)
			)
			(layer "F.SilkS")
		)
		(fp_line
			(start -0.7874 0.4064)
			(end -0.7874 -0.4064)
			(stroke
				(width 0.1524)
				(type default)
			)
			(layer "F.SilkS")
		)
		(fp_line
			(start 0.7874 -0.4064)
			(end 0.7874 0.4064)
			(stroke
				(width 0.1524)
				(type default)
			)
			(layer "F.SilkS")
		)
		(fp_line
			(start 0.7874 0.4064)
			(end -0.7874 0.4064)
			(stroke
				(width 0.1524)
				(type default)
			)
			(layer "F.SilkS")
		)
		(fp_line
			(start -0.67945 -0.305054)
			(end -0.12065 -0.305054)
			(stroke
				(width 0.1)
				(type default)
			)
			(layer "F.Fab")
		)
		(fp_line
			(start -0.67945 0.3048)
			(end -0.67945 -0.305054)
			(stroke
				(width 0.1)
				(type default)
			)
			(layer "F.Fab")
		)
		(fp_line
			(start -0.12065 -0.305054)
			(end -0.12065 -0.2794)
			(stroke
				(width 0.1)
				(type default)
			)
			(layer "F.Fab")
		)
		(fp_line
			(start -0.12065 -0.2794)
			(end 0.12065 -0.2794)
			(stroke
				(width 0.1)
				(type default)
			)
			(layer "F.Fab")
		)
		(fp_line
			(start -0.12065 0.2794)
			(end -0.12065 0.3048)
			(stroke
				(width 0.1)
				(type default)
			)
			(layer "F.Fab")
		)
		(fp_line
			(start -0.12065 0.3048)
			(end -0.67945 0.3048)
			(stroke
				(width 0.1)
				(type default)
			)
			(layer "F.Fab")
		)
		(fp_line
			(start 0.120396 0.2794)
			(end -0.12065 0.2794)
			(stroke
				(width 0.1)
				(type default)
			)
			(layer "F.Fab")
		)
		(fp_line
			(start 0.120396 0.3048)
			(end 0.120396 0.2794)
			(stroke
				(width 0.1)
				(type default)
			)
			(layer "F.Fab")
		)
		(fp_line
			(start 0.12065 -0.3048)
			(end 0.67945 -0.3048)
			(stroke
				(width 0.1)
				(type default)
			)
			(layer "F.Fab")
		)
		(fp_line
			(start 0.12065 -0.2794)
			(end 0.12065 -0.3048)
			(stroke
				(width 0.1)
				(type default)
			)
			(layer "F.Fab")
		)
		(fp_line
			(start 0.67945 -0.3048)
			(end 0.67945 0.3048)
			(stroke
				(width 0.1)
				(type default)
			)
			(layer "F.Fab")
		)
		(fp_line
			(start 0.67945 0.3048)
			(end 0.120396 0.3048)
			(stroke
				(width 0.1)
				(type default)
			)
			(layer "F.Fab")
		)
		(pad "1" smd circle
			(at -0.40005 0)
			(size 0 0)
			(layers "F.Cu" "F.Mask" "F.Paste")
			(net "P3V3_AUX")
		)
		(pad "2" smd circle
			(at 0.40005 0)
			(size 0 0)
			(layers "F.Cu" "F.Mask" "F.Paste")
			(net "FM_PLT_BMC_THERMTRIP_R_N")
		)
	)
	(footprint ""
		(layer "F.Cu")
		(at 355.8286 -402.9456)
		(property "Reference" "R4733"
			(at 0 0 0)
			(layer "F.SilkS")
			(hide yes)
			(effects
				(font
					(size 1.27 1.27)
				)
			)
		)
		(property "Value" ""
			(at 0 0 0)
			(layer "F.Fab")
			(effects
				(font
					(size 1.27 1.27)
				)
			)
		)
		(duplicate_pad_numbers_are_jumpers no)
		(fp_line
			(start -0.7874 -0.4064)
			(end 0.7874 -0.4064)
			(stroke
				(width 0.1524)
				(type default)
			)
			(layer "F.SilkS")
		)
		(fp_line
			(start -0.7874 0.4064)
			(end -0.7874 -0.4064)
			(stroke
				(width 0.1524)
				(type default)
			)
			(layer "F.SilkS")
		)
		(fp_line
			(start 0.7874 -0.4064)
			(end 0.7874 0.4064)
			(stroke
				(width 0.1524)
				(type default)
			)
			(layer "F.SilkS")
		)
		(fp_line
			(start 0.7874 0.4064)
			(end -0.7874 0.4064)
			(stroke
				(width 0.1524)
				(type default)
			)
			(layer "F.SilkS")
		)
		(fp_line
			(start -0.67945 -0.305054)
			(end -0.12065 -0.305054)
			(stroke
				(width 0.1)
				(type default)
			)
			(layer "F.Fab")
		)
		(fp_line
			(start -0.67945 0.3048)
			(end -0.67945 -0.305054)
			(stroke
				(width 0.1)
				(type default)
			)
			(layer "F.Fab")
		)
		(fp_line
			(start -0.12065 -0.305054)
			(end -0.12065 -0.2794)
			(stroke
				(width 0.1)
				(type default)
			)
			(layer "F.Fab")
		)
		(fp_line
			(start -0.12065 -0.2794)
			(end 0.12065 -0.2794)
			(stroke
				(width 0.1)
				(type default)
			)
			(layer "F.Fab")
		)
		(fp_line
			(start -0.12065 0.2794)
			(end -0.12065 0.3048)
			(stroke
				(width 0.1)
				(type default)
			)
			(layer "F.Fab")
		)
		(fp_line
			(start -0.12065 0.3048)
			(end -0.67945 0.3048)
			(stroke
				(width 0.1)
				(type default)
			)
			(layer "F.Fab")
		)
		(fp_line
			(start 0.120396 0.2794)
			(end -0.12065 0.2794)
			(stroke
				(width 0.1)
				(type default)
			)
			(layer "F.Fab")
		)
		(fp_line
			(start 0.120396 0.3048)
			(end 0.120396 0.2794)
			(stroke
				(width 0.1)
				(type default)
			)
			(layer "F.Fab")
		)
		(fp_line
			(start 0.12065 -0.3048)
			(end 0.67945 -0.3048)
			(stroke
				(width 0.1)
				(type default)
			)
			(layer "F.Fab")
		)
		(fp_line
			(start 0.12065 -0.2794)
			(end 0.12065 -0.3048)
			(stroke
				(width 0.1)
				(type default)
			)
			(layer "F.Fab")
		)
		(fp_line
			(start 0.67945 -0.3048)
			(end 0.67945 0.3048)
			(stroke
				(width 0.1)
				(type default)
			)
			(layer "F.Fab")
		)
		(fp_line
			(start 0.67945 0.3048)
			(end 0.120396 0.3048)
			(stroke
				(width 0.1)
				(type default)
			)
			(layer "F.Fab")
		)
		(pad "1" smd circle
			(at -0.40005 0)
			(size 0 0)
			(layers "F.Cu" "F.Mask" "F.Paste")
			(net "P3V3_AUX")
		)
		(pad "2" smd circle
			(at 0.40005 0)
			(size 0 0)
			(layers "F.Cu" "F.Mask" "F.Paste")
			(net "PRSNT_CABLE_SWB_B2_ISO_N")
		)
	)
	(footprint ""
		(layer "F.Cu")
		(at 432.243992 -402.290534 180)
		(property "Reference" "R3472"
			(at 0 0 180)
			(layer "F.SilkS")
			(hide yes)
			(effects
				(font
					(size 1.27 1.27)
				)
			)
		)
		(property "Value" ""
			(at 0 0 180)
			(layer "F.Fab")
			(effects
				(font
					(size 1.27 1.27)
				)
			)
		)
		(duplicate_pad_numbers_are_jumpers no)
		(fp_line
			(start 0.7874 0.4064)
			(end -0.7874 0.4064)
			(stroke
				(width 0.1524)
				(type default)
			)
			(layer "F.SilkS")
		)
		(fp_line
			(start 0.7874 -0.4064)
			(end 0.7874 0.4064)
			(stroke
				(width 0.1524)
				(type default)
			)
			(layer "F.SilkS")
		)
		(fp_line
			(start -0.7874 0.4064)
			(end -0.7874 -0.4064)
			(stroke
				(width 0.1524)
				(type default)
			)
			(layer "F.SilkS")
		)
		(fp_line
			(start -0.7874 -0.4064)
			(end 0.7874 -0.4064)
			(stroke
				(width 0.1524)
				(type default)
			)
			(layer "F.SilkS")
		)
		(fp_line
			(start 0.67945 0.3048)
			(end 0.120396 0.3048)
			(stroke
				(width 0.1)
				(type default)
			)
			(layer "F.Fab")
		)
		(fp_line
			(start 0.67945 -0.3048)
			(end 0.67945 0.3048)
			(stroke
				(width 0.1)
				(type default)
			)
			(layer "F.Fab")
		)
		(fp_line
			(start 0.12065 -0.2794)
			(end 0.12065 -0.3048)
			(stroke
				(width 0.1)
				(type default)
			)
			(layer "F.Fab")
		)
		(fp_line
			(start 0.12065 -0.3048)
			(end 0.67945 -0.3048)
			(stroke
				(width 0.1)
				(type default)
			)
			(layer "F.Fab")
		)
		(fp_line
			(start 0.120396 0.3048)
			(end 0.120396 0.2794)
			(stroke
				(width 0.1)
				(type default)
			)
			(layer "F.Fab")
		)
		(fp_line
			(start 0.120396 0.2794)
			(end -0.12065 0.2794)
			(stroke
				(width 0.1)
				(type default)
			)
			(layer "F.Fab")
		)
		(fp_line
			(start -0.12065 0.3048)
			(end -0.67945 0.3048)
			(stroke
				(width 0.1)
				(type default)
			)
			(layer "F.Fab")
		)
		(fp_line
			(start -0.12065 0.2794)
			(end -0.12065 0.3048)
			(stroke
				(width 0.1)
				(type default)
			)
			(layer "F.Fab")
		)
		(fp_line
			(start -0.12065 -0.2794)
			(end 0.12065 -0.2794)
			(stroke
				(width 0.1)
				(type default)
			)
			(layer "F.Fab")
		)
		(fp_line
			(start -0.12065 -0.305054)
			(end -0.12065 -0.2794)
			(stroke
				(width 0.1)
				(type default)
			)
			(layer "F.Fab")
		)
		(fp_line
			(start -0.67945 0.3048)
			(end -0.67945 -0.305054)
			(stroke
				(width 0.1)
				(type default)
			)
			(layer "F.Fab")
		)
		(fp_line
			(start -0.67945 -0.305054)
			(end -0.12065 -0.305054)
			(stroke
				(width 0.1)
				(type default)
			)
			(layer "F.Fab")
		)
		(pad "1" smd circle
			(at -0.40005 0 180)
			(size 0 0)
			(layers "F.Cu" "F.Mask" "F.Paste")
			(net "GND")
		)
		(pad "2" smd circle
			(at 0.40005 0 180)
			(size 0 0)
			(layers "F.Cu" "F.Mask" "F.Paste")
			(net "GPU_WP_HW_CTRL_ISO")
		)
	)
	(footprint ""
		(layer "F.Cu")
		(at 420.93388 -156.632148 90)
		(property "Reference" "PR4228"
			(at 0 0 90)
			(layer "F.SilkS")
			(hide yes)
			(effects
				(font
					(size 1.27 1.27)
				)
			)
		)
		(property "Value" ""
			(at 0 0 90)
			(layer "F.Fab")
			(effects
				(font
					(size 1.27 1.27)
				)
			)
		)
		(duplicate_pad_numbers_are_jumpers no)
		(fp_line
			(start 0.7874 -0.4064)
			(end 0.7874 0.4064)
			(stroke
				(width 0.1524)
				(type default)
			)
			(layer "F.SilkS")
		)
		(fp_line
			(start -0.7874 -0.4064)
			(end 0.7874 -0.4064)
			(stroke
				(width 0.1524)
				(type default)
			)
			(layer "F.SilkS")
		)
		(fp_line
			(start 0.7874 0.4064)
			(end -0.7874 0.4064)
			(stroke
				(width 0.1524)
				(type default)
			)
			(layer "F.SilkS")
		)
		(fp_line
			(start -0.7874 0.4064)
			(end -0.7874 -0.4064)
			(stroke
				(width 0.1524)
				(type default)
			)
			(layer "F.SilkS")
		)
		(fp_line
			(start -0.12065 -0.305054)
			(end -0.12065 -0.2794)
			(stroke
				(width 0.1)
				(type default)
			)
			(layer "F.Fab")
		)
		(fp_line
			(start -0.67945 -0.305054)
			(end -0.12065 -0.305054)
			(stroke
				(width 0.1)
				(type default)
			)
			(layer "F.Fab")
		)
		(fp_line
			(start 0.67945 -0.3048)
			(end 0.67945 0.3048)
			(stroke
				(width 0.1)
				(type default)
			)
			(layer "F.Fab")
		)
		(fp_line
			(start 0.12065 -0.3048)
			(end 0.67945 -0.3048)
			(stroke
				(width 0.1)
				(type default)
			)
			(layer "F.Fab")
		)
		(fp_line
			(start 0.12065 -0.2794)
			(end 0.12065 -0.3048)
			(stroke
				(width 0.1)
				(type default)
			)
			(layer "F.Fab")
		)
		(fp_line
			(start -0.12065 -0.2794)
			(end 0.12065 -0.2794)
			(stroke
				(width 0.1)
				(type default)
			)
			(layer "F.Fab")
		)
		(fp_line
			(start 0.120396 0.2794)
			(end -0.12065 0.2794)
			(stroke
				(width 0.1)
				(type default)
			)
			(layer "F.Fab")
		)
		(fp_line
			(start -0.12065 0.2794)
			(end -0.12065 0.3048)
			(stroke
				(width 0.1)
				(type default)
			)
			(layer "F.Fab")
		)
		(fp_line
			(start 0.67945 0.3048)
			(end 0.120396 0.3048)
			(stroke
				(width 0.1)
				(type default)
			)
			(layer "F.Fab")
		)
		(fp_line
			(start 0.120396 0.3048)
			(end 0.120396 0.2794)
			(stroke
				(width 0.1)
				(type default)
			)
			(layer "F.Fab")
		)
		(fp_line
			(start -0.12065 0.3048)
			(end -0.67945 0.3048)
			(stroke
				(width 0.1)
				(type default)
			)
			(layer "F.Fab")
		)
		(fp_line
			(start -0.67945 0.3048)
			(end -0.67945 -0.305054)
			(stroke
				(width 0.1)
				(type default)
			)
			(layer "F.Fab")
		)
		(pad "1" smd circle
			(at -0.40005 0 90)
			(size 0 0)
			(layers "F.Cu" "F.Mask" "F.Paste")
			(net "PVCCFA_EHV_CPU0_FAULT")
		)
		(pad "2" smd circle
			(at 0.40005 0 90)
			(size 0 0)
			(layers "F.Cu" "F.Mask" "F.Paste")
			(net "GND")
		)
	)
	(footprint ""
		(layer "F.Cu")
		(at 127.288544 -77.571092 180)
		(property "Reference" "U96"
			(at -0.257556 3.718306 0)
			(unlocked yes)
			(layer "F.SilkS")
			(effects
				(font
					(size 0.7874 0.5842)
					(thickness 0.1524)
				)
				(justify left)
			)
		)
		(property "Value" ""
			(at 0 0 180)
			(layer "F.Fab")
			(effects
				(font
					(size 1.27 1.27)
				)
			)
		)
		(duplicate_pad_numbers_are_jumpers no)
		(fp_line
			(start 0.824992 1.050036)
			(end 0.254 1.050036)
			(stroke
				(width 0.1524)
				(type default)
			)
			(layer "F.SilkS")
		)
		(fp_line
			(start 0.824992 1.00584)
			(end 0.824992 1.050036)
			(stroke
				(width 0.1524)
				(type default)
			)
			(layer "F.SilkS")
		)
		(fp_line
			(start 0.824992 -1.050036)
			(end 0.824992 -1.00584)
			(stroke
				(width 0.1524)
				(type default)
			)
			(layer "F.SilkS")
		)
		(fp_line
			(start 0.254 -1.050036)
			(end 0.824992 -1.050036)
			(stroke
				(width 0.1524)
				(type default)
			)
			(layer "F.SilkS")
		)
		(fp_line
			(start -0.254 1.050036)
			(end -0.824992 1.050036)
			(stroke
				(width 0.1524)
				(type default)
			)
			(layer "F.SilkS")
		)
		(fp_line
			(start -0.824992 1.050036)
			(end -0.824992 1.00584)
			(stroke
				(width 0.1524)
				(type default)
			)
			(layer "F.SilkS")
		)
		(fp_line
			(start -0.824992 -1.01854)
			(end -0.824992 -1.050036)
			(stroke
				(width 0.1524)
				(type default)
			)
			(layer "F.SilkS")
		)
		(fp_line
			(start -0.824992 -1.050036)
			(end -0.254 -1.050036)
			(stroke
				(width 0.1524)
				(type default)
			)
			(layer "F.SilkS")
		)
		(fp_poly
			(pts
				(xy -1.969008 -0.411734) (xy -1.969008 -1.11379) (xy -1.266952 -0.762762)
			)
			(stroke
				(width 0)
				(type default)
			)
			(fill yes)
			(layer "F.SilkS")
		)
		(fp_line
			(start 0.824992 1.050036)
			(end -0.824992 1.050036)
			(stroke
				(width 0.1)
				(type default)
			)
			(layer "F.Fab")
		)
		(fp_line
			(start 0.824992 -1.050036)
			(end 0.824992 1.050036)
			(stroke
				(width 0.1)
				(type default)
			)
			(layer "F.Fab")
		)
		(fp_line
			(start -0.824992 1.050036)
			(end -0.824992 -1.050036)
			(stroke
				(width 0.1)
				(type default)
			)
			(layer "F.Fab")
		)
		(fp_line
			(start -0.824992 -1.050036)
			(end 0.824992 -1.050036)
			(stroke
				(width 0.1)
				(type default)
			)
			(layer "F.Fab")
		)
		(fp_poly
			(pts
				(xy -1.325372 -0.750062) (xy -2.027428 -0.399034) (xy -2.027428 -1.10109)
			)
			(stroke
				(width 0)
				(type default)
			)
			(fill yes)
			(layer "F.Fab")
		)
		(pad "1" smd rect
			(at -0.741172 -0.750062 270)
			(size 0.2794 0.8128)
			(layers "F.Cu" "F.Mask" "F.Paste")
			(net "JTAG_BMC_PLD_TDI")
		)
		(pad "2" smd rect
			(at -0.741172 -0.249936 270)
			(size 0.254 0.8128)
			(layers "F.Cu" "F.Mask" "F.Paste")
			(net "JTAG_BMC_DBP_TDI")
		)
		(pad "3" smd rect
			(at -0.741172 0.249936 270)
			(size 0.254 0.8128)
			(layers "F.Cu" "F.Mask" "F.Paste")
			(net "JTAG_BMC_PLD_TDO")
		)
		(pad "4" smd rect
			(at -0.741172 0.750062 270)
			(size 0.254 0.8128)
			(layers "F.Cu" "F.Mask" "F.Paste")
			(net "JTAG_BMC_DBP_TDO")
		)
		(pad "5" smd rect
			(at 0 0.94996 180)
			(size 0.254 0.8128)
			(layers "F.Cu" "F.Mask" "F.Paste")
			(net "GND")
		)
		(pad "6" smd rect
			(at 0.741172 0.750062 270)
			(size 0.254 0.8128)
			(layers "F.Cu" "F.Mask" "F.Paste")
			(net "JTAG_BMC_SW_TDO")
		)
		(pad "7" smd rect
			(at 0.741172 0.249936 270)
			(size 0.254 0.8128)
			(layers "F.Cu" "F.Mask" "F.Paste")
			(net "FM_JTAG_BMC_MUX_SEL")
		)
		(pad "8" smd rect
			(at 0.741172 -0.249936 270)
			(size 0.254 0.8128)
			(layers "F.Cu" "F.Mask" "F.Paste")
			(net "FM_JTAG_BMC_MUX_SEL")
		)
		(pad "9" smd rect
			(at 0.741172 -0.750062 270)
			(size 0.254 0.8128)
			(layers "F.Cu" "F.Mask" "F.Paste")
			(net "JTAG_BMC_SW_TDI")
		)
		(pad "10" smd rect
			(at 0 -0.94996 180)
			(size 0.254 0.8128)
			(layers "F.Cu" "F.Mask" "F.Paste")
			(net "P3V3_AUX")
		)
		(zone
			(layer "F.Cu")
			(hatch none 0.5)
			(connect_pads
				(clearance 0)
			)
			(min_thickness 0.25)
			(keepout
				(tracks not_allowed)
				(vias allowed)
				(pads allowed)
				(copperpour not_allowed)
				(footprints allowed)
			)
			(placement
				(enabled no)
				(sheetname "")
			)
			(fill
				(thermal_gap 0.5)
				(thermal_bridge_width 0.5)
				(island_removal_mode 0)
			)
			(polygon
				(pts
					(xy 128.114044 -76.631292) (xy 128.114044 -76.516992) (xy 127.567944 -76.516992) (xy 127.567944 -76.631292)
				)
			)
		)
	)
	(footprint ""
		(layer "F.Cu")
		(at 127.04064 -156.365448 180)
		(property "Reference" "R1493"
			(at 0 0 180)
			(layer "F.SilkS")
			(hide yes)
			(effects
				(font
					(size 1.27 1.27)
				)
			)
		)
		(property "Value" ""
			(at 0 0 180)
			(layer "F.Fab")
			(effects
				(font
					(size 1.27 1.27)
				)
			)
		)
		(duplicate_pad_numbers_are_jumpers no)
		(fp_line
			(start 0.7874 0.4064)
			(end -0.7874 0.4064)
			(stroke
				(width 0.1524)
				(type default)
			)
			(layer "F.SilkS")
		)
		(fp_line
			(start 0.7874 -0.4064)
			(end 0.7874 0.4064)
			(stroke
				(width 0.1524)
				(type default)
			)
			(layer "F.SilkS")
		)
		(fp_line
			(start -0.7874 0.4064)
			(end -0.7874 -0.4064)
			(stroke
				(width 0.1524)
				(type default)
			)
			(layer "F.SilkS")
		)
		(fp_line
			(start -0.7874 -0.4064)
			(end 0.7874 -0.4064)
			(stroke
				(width 0.1524)
				(type default)
			)
			(layer "F.SilkS")
		)
		(fp_line
			(start 0.67945 0.3048)
			(end 0.120396 0.3048)
			(stroke
				(width 0.1)
				(type default)
			)
			(layer "F.Fab")
		)
		(fp_line
			(start 0.67945 -0.3048)
			(end 0.67945 0.3048)
			(stroke
				(width 0.1)
				(type default)
			)
			(layer "F.Fab")
		)
		(fp_line
			(start 0.12065 -0.2794)
			(end 0.12065 -0.3048)
			(stroke
				(width 0.1)
				(type default)
			)
			(layer "F.Fab")
		)
		(fp_line
			(start 0.12065 -0.3048)
			(end 0.67945 -0.3048)
			(stroke
				(width 0.1)
				(type default)
			)
			(layer "F.Fab")
		)
		(fp_line
			(start 0.120396 0.3048)
			(end 0.120396 0.2794)
			(stroke
				(width 0.1)
				(type default)
			)
			(layer "F.Fab")
		)
		(fp_line
			(start 0.120396 0.2794)
			(end -0.12065 0.2794)
			(stroke
				(width 0.1)
				(type default)
			)
			(layer "F.Fab")
		)
		(fp_line
			(start -0.12065 0.3048)
			(end -0.67945 0.3048)
			(stroke
				(width 0.1)
				(type default)
			)
			(layer "F.Fab")
		)
		(fp_line
			(start -0.12065 0.2794)
			(end -0.12065 0.3048)
			(stroke
				(width 0.1)
				(type default)
			)
			(layer "F.Fab")
		)
		(fp_line
			(start -0.12065 -0.2794)
			(end 0.12065 -0.2794)
			(stroke
				(width 0.1)
				(type default)
			)
			(layer "F.Fab")
		)
		(fp_line
			(start -0.12065 -0.305054)
			(end -0.12065 -0.2794)
			(stroke
				(width 0.1)
				(type default)
			)
			(layer "F.Fab")
		)
		(fp_line
			(start -0.67945 0.3048)
			(end -0.67945 -0.305054)
			(stroke
				(width 0.1)
				(type default)
			)
			(layer "F.Fab")
		)
		(fp_line
			(start -0.67945 -0.305054)
			(end -0.12065 -0.305054)
			(stroke
				(width 0.1)
				(type default)
			)
			(layer "F.Fab")
		)
		(pad "1" smd circle
			(at -0.40005 0 180)
			(size 0 0)
			(layers "F.Cu" "F.Mask" "F.Paste")
			(net "P3V3_AUX")
		)
		(pad "2" smd circle
			(at 0.40005 0 180)
			(size 0 0)
			(layers "F.Cu" "F.Mask" "F.Paste")
			(net "PU_FORCE_PWRON")
		)
	)
	(footprint ""
		(layer "F.Cu")
		(at 117.526816 -247.715278 90)
		(property "Reference" "C273"
			(at 0 0 90)
			(layer "F.SilkS")
			(hide yes)
			(effects
				(font
					(size 1.27 1.27)
				)
			)
		)
		(property "Value" ""
			(at 0 0 90)
			(layer "F.Fab")
			(effects
				(font
					(size 1.27 1.27)
				)
			)
		)
		(duplicate_pad_numbers_are_jumpers no)
		(fp_line
			(start 0.7874 -0.4064)
			(end 0.7874 0.4064)
			(stroke
				(width 0.1524)
				(type default)
			)
			(layer "F.SilkS")
		)
		(fp_line
			(start -0.7874 -0.4064)
			(end 0.7874 -0.4064)
			(stroke
				(width 0.1524)
				(type default)
			)
			(layer "F.SilkS")
		)
		(fp_line
			(start 0.7874 0.4064)
			(end -0.7874 0.4064)
			(stroke
				(width 0.1524)
				(type default)
			)
			(layer "F.SilkS")
		)
		(fp_line
			(start -0.7874 0.4064)
			(end -0.7874 -0.4064)
			(stroke
				(width 0.1524)
				(type default)
			)
			(layer "F.SilkS")
		)
		(fp_line
			(start -0.12065 -0.305054)
			(end -0.12065 -0.2794)
			(stroke
				(width 0.1)
				(type default)
			)
			(layer "F.Fab")
		)
		(fp_line
			(start -0.67945 -0.305054)
			(end -0.12065 -0.305054)
			(stroke
				(width 0.1)
				(type default)
			)
			(layer "F.Fab")
		)
		(fp_line
			(start 0.67945 -0.3048)
			(end 0.67945 0.3048)
			(stroke
				(width 0.1)
				(type default)
			)
			(layer "F.Fab")
		)
		(fp_line
			(start 0.12065 -0.3048)
			(end 0.67945 -0.3048)
			(stroke
				(width 0.1)
				(type default)
			)
			(layer "F.Fab")
		)
		(fp_line
			(start 0.12065 -0.2794)
			(end 0.12065 -0.3048)
			(stroke
				(width 0.1)
				(type default)
			)
			(layer "F.Fab")
		)
		(fp_line
			(start -0.12065 -0.2794)
			(end 0.12065 -0.2794)
			(stroke
				(width 0.1)
				(type default)
			)
			(layer "F.Fab")
		)
		(fp_line
			(start 0.120396 0.2794)
			(end -0.12065 0.2794)
			(stroke
				(width 0.1)
				(type default)
			)
			(layer "F.Fab")
		)
		(fp_line
			(start -0.12065 0.2794)
			(end -0.12065 0.3048)
			(stroke
				(width 0.1)
				(type default)
			)
			(layer "F.Fab")
		)
		(fp_line
			(start 0.67945 0.3048)
			(end 0.120396 0.3048)
			(stroke
				(width 0.1)
				(type default)
			)
			(layer "F.Fab")
		)
		(fp_line
			(start 0.120396 0.3048)
			(end 0.120396 0.2794)
			(stroke
				(width 0.1)
				(type default)
			)
			(layer "F.Fab")
		)
		(fp_line
			(start -0.12065 0.3048)
			(end -0.67945 0.3048)
			(stroke
				(width 0.1)
				(type default)
			)
			(layer "F.Fab")
		)
		(fp_line
			(start -0.67945 0.3048)
			(end -0.67945 -0.305054)
			(stroke
				(width 0.1)
				(type default)
			)
			(layer "F.Fab")
		)
		(pad "1" smd circle
			(at -0.40005 0 90)
			(size 0 0)
			(layers "F.Cu" "F.Mask" "F.Paste")
			(net "PVCCIN_CPU1")
		)
		(pad "2" smd circle
			(at 0.40005 0 90)
			(size 0 0)
			(layers "F.Cu" "F.Mask" "F.Paste")
			(net "GND")
		)
	)
	(footprint ""
		(layer "F.Cu")
		(at 85.626194 -102.509574 180)
		(property "Reference" "Q100"
			(at 3.226308 0.425196 0)
			(unlocked yes)
			(layer "F.SilkS")
			(effects
				(font
					(size 0.7874 0.5842)
					(thickness 0.1524)
				)
			)
		)
		(property "Value" ""
			(at 0 0 180)
			(layer "F.Fab")
			(effects
				(font
					(size 1.27 1.27)
				)
			)
		)
		(duplicate_pad_numbers_are_jumpers no)
		(fp_line
			(start 1.376172 1.199896)
			(end -1.376172 1.199896)
			(stroke
				(width 0.1524)
				(type default)
			)
			(layer "F.SilkS")
		)
		(fp_line
			(start 1.376172 -1.199896)
			(end 1.376172 1.199896)
			(stroke
				(width 0.1524)
				(type default)
			)
			(layer "F.SilkS")
		)
		(fp_line
			(start 0.508 -1.199896)
			(end 1.376172 -1.199896)
			(stroke
				(width 0.1524)
				(type default)
			)
			(layer "F.SilkS")
		)
		(fp_line
			(start 0 -0.762)
			(end 0.508 -1.199896)
			(stroke
				(width 0.1524)
				(type default)
			)
			(layer "F.SilkS")
		)
		(fp_line
			(start -0.508 -1.199896)
			(end 0 -0.762)
			(stroke
				(width 0.1524)
				(type default)
			)
			(layer "F.SilkS")
		)
		(fp_line
			(start -1.376172 1.199896)
			(end -1.376172 -1.199896)
			(stroke
				(width 0.1524)
				(type default)
			)
			(layer "F.SilkS")
		)
		(fp_line
			(start -1.376172 -1.199896)
			(end -0.508 -1.199896)
			(stroke
				(width 0.1524)
				(type default)
			)
			(layer "F.SilkS")
		)
		(fp_poly
			(pts
				(xy -2.04724 -0.7747) (xy -2.80924 -0.3937) (xy -2.80924 -1.1557)
			)
			(stroke
				(width 0)
				(type default)
			)
			(fill yes)
			(layer "F.SilkS")
		)
		(fp_line
			(start 0.674878 1.100074)
			(end -0.674878 1.100074)
			(stroke
				(width 0.1)
				(type default)
			)
			(layer "F.Fab")
		)
		(fp_line
			(start 0.674878 -1.100074)
			(end 0.674878 1.100074)
			(stroke
				(width 0.1)
				(type default)
			)
			(layer "F.Fab")
		)
		(fp_line
			(start -0.674878 1.100074)
			(end -0.674878 -1.100074)
			(stroke
				(width 0.1)
				(type default)
			)
			(layer "F.Fab")
		)
		(fp_line
			(start -0.674878 -1.100074)
			(end 0.674878 -1.100074)
			(stroke
				(width 0.1)
				(type default)
			)
			(layer "F.Fab")
		)
		(fp_poly
			(pts
				(xy -1.4605 -0.7493) (xy -2.2225 -1.1303) (xy -2.2225 -0.3683)
			)
			(stroke
				(width 0)
				(type default)
			)
			(fill yes)
			(layer "F.Fab")
		)
		(pad "1" smd rect
			(at -0.899922 -0.750062 90)
			(size 0.6096 0.6096)
			(layers "F.Cu" "F.Mask" "F.Paste")
			(net "GND")
		)
		(pad "2" smd rect
			(at -0.899922 0 90)
			(size 0.4064 0.6096)
			(layers "F.Cu" "F.Mask" "F.Paste")
			(net "RST_PLD_CPU1_DRAM_EF_N")
		)
		(pad "3" smd rect
			(at -0.899922 0.750062 90)
			(size 0.6096 0.6096)
			(layers "F.Cu" "F.Mask" "F.Paste")
			(net "LED_RST_PLD_CPU1_DRAM_GH_N_D")
		)
		(pad "4" smd rect
			(at 0.899922 0.750062 90)
			(size 0.6096 0.6096)
			(layers "F.Cu" "F.Mask" "F.Paste")
			(net "GND")
		)
		(pad "5" smd rect
			(at 0.899922 0 90)
			(size 0.4064 0.6096)
			(layers "F.Cu" "F.Mask" "F.Paste")
			(net "RST_PLD_CPU1_DRAM_GH_N")
		)
		(pad "6" smd rect
			(at 0.899922 -0.750062 90)
			(size 0.6096 0.6096)
			(layers "F.Cu" "F.Mask" "F.Paste")
			(net "LED_RST_PLD_CPU1_DRAM_EF_N_D")
		)
	)
	(footprint ""
		(layer "F.Cu")
		(at 77.595476 -79.078836)
		(property "Reference" "D74"
			(at -40.11041 34.331402 90)
			(unlocked yes)
			(layer "F.SilkS")
			(effects
				(font
					(size 0.635 0.4064)
					(thickness 0.1524)
				)
				(justify left)
			)
		)
		(property "Value" ""
			(at 0 0 0)
			(layer "F.Fab")
			(effects
				(font
					(size 1.27 1.27)
				)
			)
		)
		(duplicate_pad_numbers_are_jumpers no)
		(fp_line
			(start -0.90678 0.4826)
			(end -0.90678 -0.4699)
			(stroke
				(width 0.1524)
				(type default)
			)
			(layer "F.SilkS")
		)
		(fp_line
			(start -0.89408 -0.4826)
			(end 0.90678 -0.4826)
			(stroke
				(width 0.1524)
				(type default)
			)
			(layer "F.SilkS")
		)
		(fp_line
			(start -0.79248 -0.4826)
			(end 1.03378 -0.4826)
			(stroke
				(width 0.1524)
				(type default)
			)
			(layer "F.SilkS")
		)
		(fp_line
			(start -0.64008 -0.4826)
			(end 1.16078 -0.4826)
			(stroke
				(width 0.1524)
				(type default)
			)
			(layer "F.SilkS")
		)
		(fp_line
			(start 0.90678 -0.4826)
			(end 0.90678 0.4826)
			(stroke
				(width 0.1524)
				(type default)
			)
			(layer "F.SilkS")
		)
		(fp_line
			(start 0.90678 0.4826)
			(end -0.90678 0.4826)
			(stroke
				(width 0.1524)
				(type default)
			)
			(layer "F.SilkS")
		)
		(fp_line
			(start 1.03378 -0.4826)
			(end 1.03378 0.4826)
			(stroke
				(width 0.1524)
				(type default)
			)
			(layer "F.SilkS")
		)
		(fp_line
			(start 1.03378 0.4826)
			(end -0.79248 0.4826)
			(stroke
				(width 0.1524)
				(type default)
			)
			(layer "F.SilkS")
		)
		(fp_line
			(start 1.16078 -0.4826)
			(end 1.16078 0.4826)
			(stroke
				(width 0.1524)
				(type default)
			)
			(layer "F.SilkS")
		)
		(fp_line
			(start 1.16078 0.4826)
			(end -0.64008 0.4826)
			(stroke
				(width 0.1524)
				(type default)
			)
			(layer "F.SilkS")
		)
		(fp_line
			(start -0.499872 -0.249936)
			(end 0.499872 -0.249936)
			(stroke
				(width 0.1)
				(type default)
			)
			(layer "F.Fab")
		)
		(fp_line
			(start -0.499872 0.249936)
			(end -0.499872 -0.249936)
			(stroke
				(width 0.1)
				(type default)
			)
			(layer "F.Fab")
		)
		(fp_line
			(start 0.499872 -0.249936)
			(end 0.499872 0.249936)
			(stroke
				(width 0.1)
				(type default)
			)
			(layer "F.Fab")
		)
		(fp_line
			(start 0.499872 0.249936)
			(end -0.499872 0.249936)
			(stroke
				(width 0.1)
				(type default)
			)
			(layer "F.Fab")
		)
		(pad "A" smd rect
			(at -0.47498 0)
			(size 0.6096 0.7112)
			(layers "F.Cu" "F.Mask" "F.Paste")
			(net "LED_PWRGD_PVPP_HBM_CPU0")
		)
		(pad "C" smd rect
			(at 0.47498 0)
			(size 0.6096 0.7112)
			(layers "F.Cu" "F.Mask" "F.Paste")
			(net "LED_PWRGD_PVPP_HBM_CPU0_D")
		)
	)
	(footprint ""
		(layer "F.Cu")
		(at 38.02888 -433.923948)
		(property "Reference" "R3109"
			(at 0 0 0)
			(layer "F.SilkS")
			(hide yes)
			(effects
				(font
					(size 1.27 1.27)
				)
			)
		)
		(property "Value" ""
			(at 0 0 0)
			(layer "F.Fab")
			(effects
				(font
					(size 1.27 1.27)
				)
			)
		)
		(duplicate_pad_numbers_are_jumpers no)
		(fp_line
			(start -0.7874 -0.4064)
			(end 0.7874 -0.4064)
			(stroke
				(width 0.1524)
				(type default)
			)
			(layer "F.SilkS")
		)
		(fp_line
			(start -0.7874 0.4064)
			(end -0.7874 -0.4064)
			(stroke
				(width 0.1524)
				(type default)
			)
			(layer "F.SilkS")
		)
		(fp_line
			(start 0.7874 -0.4064)
			(end 0.7874 0.4064)
			(stroke
				(width 0.1524)
				(type default)
			)
			(layer "F.SilkS")
		)
		(fp_line
			(start 0.7874 0.4064)
			(end -0.7874 0.4064)
			(stroke
				(width 0.1524)
				(type default)
			)
			(layer "F.SilkS")
		)
		(fp_line
			(start -0.67945 -0.305054)
			(end -0.12065 -0.305054)
			(stroke
				(width 0.1)
				(type default)
			)
			(layer "F.Fab")
		)
		(fp_line
			(start -0.67945 0.3048)
			(end -0.67945 -0.305054)
			(stroke
				(width 0.1)
				(type default)
			)
			(layer "F.Fab")
		)
		(fp_line
			(start -0.12065 -0.305054)
			(end -0.12065 -0.2794)
			(stroke
				(width 0.1)
				(type default)
			)
			(layer "F.Fab")
		)
		(fp_line
			(start -0.12065 -0.2794)
			(end 0.12065 -0.2794)
			(stroke
				(width 0.1)
				(type default)
			)
			(layer "F.Fab")
		)
		(fp_line
			(start -0.12065 0.2794)
			(end -0.12065 0.3048)
			(stroke
				(width 0.1)
				(type default)
			)
			(layer "F.Fab")
		)
		(fp_line
			(start -0.12065 0.3048)
			(end -0.67945 0.3048)
			(stroke
				(width 0.1)
				(type default)
			)
			(layer "F.Fab")
		)
		(fp_line
			(start 0.120396 0.2794)
			(end -0.12065 0.2794)
			(stroke
				(width 0.1)
				(type default)
			)
			(layer "F.Fab")
		)
		(fp_line
			(start 0.120396 0.3048)
			(end 0.120396 0.2794)
			(stroke
				(width 0.1)
				(type default)
			)
			(layer "F.Fab")
		)
		(fp_line
			(start 0.12065 -0.3048)
			(end 0.67945 -0.3048)
			(stroke
				(width 0.1)
				(type default)
			)
			(layer "F.Fab")
		)
		(fp_line
			(start 0.12065 -0.2794)
			(end 0.12065 -0.3048)
			(stroke
				(width 0.1)
				(type default)
			)
			(layer "F.Fab")
		)
		(fp_line
			(start 0.67945 -0.3048)
			(end 0.67945 0.3048)
			(stroke
				(width 0.1)
				(type default)
			)
			(layer "F.Fab")
		)
		(fp_line
			(start 0.67945 0.3048)
			(end 0.120396 0.3048)
			(stroke
				(width 0.1)
				(type default)
			)
			(layer "F.Fab")
		)
		(pad "1" smd circle
			(at -0.40005 0)
			(size 0 0)
			(layers "F.Cu" "F.Mask" "F.Paste")
			(net "SMB_1_BMC_GPU_SCL")
		)
		(pad "2" smd circle
			(at 0.40005 0)
			(size 0 0)
			(layers "F.Cu" "F.Mask" "F.Paste")
			(net "SMB_1_BMC_GPU_R_SCL")
		)
	)
	(footprint ""
		(layer "F.Cu")
		(at 124.672344 -78.587092 180)
		(property "Reference" "R1814"
			(at 0 0 180)
			(layer "F.SilkS")
			(hide yes)
			(effects
				(font
					(size 1.27 1.27)
				)
			)
		)
		(property "Value" ""
			(at 0 0 180)
			(layer "F.Fab")
			(effects
				(font
					(size 1.27 1.27)
				)
			)
		)
		(duplicate_pad_numbers_are_jumpers no)
		(fp_line
			(start 0.7874 0.4064)
			(end -0.7874 0.4064)
			(stroke
				(width 0.1524)
				(type default)
			)
			(layer "F.SilkS")
		)
		(fp_line
			(start 0.7874 -0.4064)
			(end 0.7874 0.4064)
			(stroke
				(width 0.1524)
				(type default)
			)
			(layer "F.SilkS")
		)
		(fp_line
			(start -0.7874 0.4064)
			(end -0.7874 -0.4064)
			(stroke
				(width 0.1524)
				(type default)
			)
			(layer "F.SilkS")
		)
		(fp_line
			(start -0.7874 -0.4064)
			(end 0.7874 -0.4064)
			(stroke
				(width 0.1524)
				(type default)
			)
			(layer "F.SilkS")
		)
		(fp_line
			(start 0.67945 0.3048)
			(end 0.120396 0.3048)
			(stroke
				(width 0.1)
				(type default)
			)
			(layer "F.Fab")
		)
		(fp_line
			(start 0.67945 -0.3048)
			(end 0.67945 0.3048)
			(stroke
				(width 0.1)
				(type default)
			)
			(layer "F.Fab")
		)
		(fp_line
			(start 0.12065 -0.2794)
			(end 0.12065 -0.3048)
			(stroke
				(width 0.1)
				(type default)
			)
			(layer "F.Fab")
		)
		(fp_line
			(start 0.12065 -0.3048)
			(end 0.67945 -0.3048)
			(stroke
				(width 0.1)
				(type default)
			)
			(layer "F.Fab")
		)
		(fp_line
			(start 0.120396 0.3048)
			(end 0.120396 0.2794)
			(stroke
				(width 0.1)
				(type default)
			)
			(layer "F.Fab")
		)
		(fp_line
			(start 0.120396 0.2794)
			(end -0.12065 0.2794)
			(stroke
				(width 0.1)
				(type default)
			)
			(layer "F.Fab")
		)
		(fp_line
			(start -0.12065 0.3048)
			(end -0.67945 0.3048)
			(stroke
				(width 0.1)
				(type default)
			)
			(layer "F.Fab")
		)
		(fp_line
			(start -0.12065 0.2794)
			(end -0.12065 0.3048)
			(stroke
				(width 0.1)
				(type default)
			)
			(layer "F.Fab")
		)
		(fp_line
			(start -0.12065 -0.2794)
			(end 0.12065 -0.2794)
			(stroke
				(width 0.1)
				(type default)
			)
			(layer "F.Fab")
		)
		(fp_line
			(start -0.12065 -0.305054)
			(end -0.12065 -0.2794)
			(stroke
				(width 0.1)
				(type default)
			)
			(layer "F.Fab")
		)
		(fp_line
			(start -0.67945 0.3048)
			(end -0.67945 -0.305054)
			(stroke
				(width 0.1)
				(type default)
			)
			(layer "F.Fab")
		)
		(fp_line
			(start -0.67945 -0.305054)
			(end -0.12065 -0.305054)
			(stroke
				(width 0.1)
				(type default)
			)
			(layer "F.Fab")
		)
		(pad "1" smd circle
			(at -0.40005 0 180)
			(size 0 0)
			(layers "F.Cu" "F.Mask" "F.Paste")
			(net "FM_JTAG_BMC_MUX_SEL")
		)
		(pad "2" smd circle
			(at 0.40005 0 180)
			(size 0 0)
			(layers "F.Cu" "F.Mask" "F.Paste")
			(net "GND")
		)
	)
	(footprint ""
		(layer "F.Cu")
		(at 272.07337 -98.227642 180)
		(property "Reference" "R111"
			(at 0 0 180)
			(layer "F.SilkS")
			(hide yes)
			(effects
				(font
					(size 1.27 1.27)
				)
			)
		)
		(property "Value" ""
			(at 0 0 180)
			(layer "F.Fab")
			(effects
				(font
					(size 1.27 1.27)
				)
			)
		)
		(duplicate_pad_numbers_are_jumpers no)
		(fp_line
			(start 0.7874 0.4064)
			(end -0.7874 0.4064)
			(stroke
				(width 0.1524)
				(type default)
			)
			(layer "F.SilkS")
		)
		(fp_line
			(start 0.7874 -0.4064)
			(end 0.7874 0.4064)
			(stroke
				(width 0.1524)
				(type default)
			)
			(layer "F.SilkS")
		)
		(fp_line
			(start -0.7874 0.4064)
			(end -0.7874 -0.4064)
			(stroke
				(width 0.1524)
				(type default)
			)
			(layer "F.SilkS")
		)
		(fp_line
			(start -0.7874 -0.4064)
			(end 0.7874 -0.4064)
			(stroke
				(width 0.1524)
				(type default)
			)
			(layer "F.SilkS")
		)
		(fp_line
			(start 0.67945 0.3048)
			(end 0.120396 0.3048)
			(stroke
				(width 0.1)
				(type default)
			)
			(layer "F.Fab")
		)
		(fp_line
			(start 0.67945 -0.3048)
			(end 0.67945 0.3048)
			(stroke
				(width 0.1)
				(type default)
			)
			(layer "F.Fab")
		)
		(fp_line
			(start 0.12065 -0.2794)
			(end 0.12065 -0.3048)
			(stroke
				(width 0.1)
				(type default)
			)
			(layer "F.Fab")
		)
		(fp_line
			(start 0.12065 -0.3048)
			(end 0.67945 -0.3048)
			(stroke
				(width 0.1)
				(type default)
			)
			(layer "F.Fab")
		)
		(fp_line
			(start 0.120396 0.3048)
			(end 0.120396 0.2794)
			(stroke
				(width 0.1)
				(type default)
			)
			(layer "F.Fab")
		)
		(fp_line
			(start 0.120396 0.2794)
			(end -0.12065 0.2794)
			(stroke
				(width 0.1)
				(type default)
			)
			(layer "F.Fab")
		)
		(fp_line
			(start -0.12065 0.3048)
			(end -0.67945 0.3048)
			(stroke
				(width 0.1)
				(type default)
			)
			(layer "F.Fab")
		)
		(fp_line
			(start -0.12065 0.2794)
			(end -0.12065 0.3048)
			(stroke
				(width 0.1)
				(type default)
			)
			(layer "F.Fab")
		)
		(fp_line
			(start -0.12065 -0.2794)
			(end 0.12065 -0.2794)
			(stroke
				(width 0.1)
				(type default)
			)
			(layer "F.Fab")
		)
		(fp_line
			(start -0.12065 -0.305054)
			(end -0.12065 -0.2794)
			(stroke
				(width 0.1)
				(type default)
			)
			(layer "F.Fab")
		)
		(fp_line
			(start -0.67945 0.3048)
			(end -0.67945 -0.305054)
			(stroke
				(width 0.1)
				(type default)
			)
			(layer "F.Fab")
		)
		(fp_line
			(start -0.67945 -0.305054)
			(end -0.12065 -0.305054)
			(stroke
				(width 0.1)
				(type default)
			)
			(layer "F.Fab")
		)
		(pad "1" smd circle
			(at -0.40005 0 180)
			(size 0 0)
			(layers "F.Cu" "F.Mask" "F.Paste")
			(net "P3V3")
		)
		(pad "2" smd circle
			(at 0.40005 0 180)
			(size 0 0)
			(layers "F.Cu" "F.Mask" "F.Paste")
			(net "FM_PLD_CLKS_OE_R_N")
		)
	)
	(footprint ""
		(layer "F.Cu")
		(at 22.225 -397.025876 -90)
		(property "Reference" "R3277"
			(at 0 0 270)
			(layer "F.SilkS")
			(hide yes)
			(effects
				(font
					(size 1.27 1.27)
				)
			)
		)
		(property "Value" ""
			(at 0 0 270)
			(layer "F.Fab")
			(effects
				(font
					(size 1.27 1.27)
				)
			)
		)
		(duplicate_pad_numbers_are_jumpers no)
		(fp_line
			(start -0.7874 0.4064)
			(end -0.7874 -0.4064)
			(stroke
				(width 0.1524)
				(type default)
			)
			(layer "F.SilkS")
		)
		(fp_line
			(start 0.7874 0.4064)
			(end -0.7874 0.4064)
			(stroke
				(width 0.1524)
				(type default)
			)
			(layer "F.SilkS")
		)
		(fp_line
			(start -0.7874 -0.4064)
			(end 0.7874 -0.4064)
			(stroke
				(width 0.1524)
				(type default)
			)
			(layer "F.SilkS")
		)
		(fp_line
			(start 0.7874 -0.4064)
			(end 0.7874 0.4064)
			(stroke
				(width 0.1524)
				(type default)
			)
			(layer "F.SilkS")
		)
		(fp_line
			(start -0.67945 0.3048)
			(end -0.67945 -0.305054)
			(stroke
				(width 0.1)
				(type default)
			)
			(layer "F.Fab")
		)
		(fp_line
			(start -0.12065 0.3048)
			(end -0.67945 0.3048)
			(stroke
				(width 0.1)
				(type default)
			)
			(layer "F.Fab")
		)
		(fp_line
			(start 0.120396 0.3048)
			(end 0.120396 0.2794)
			(stroke
				(width 0.1)
				(type default)
			)
			(layer "F.Fab")
		)
		(fp_line
			(start 0.67945 0.3048)
			(end 0.120396 0.3048)
			(stroke
				(width 0.1)
				(type default)
			)
			(layer "F.Fab")
		)
		(fp_line
			(start -0.12065 0.2794)
			(end -0.12065 0.3048)
			(stroke
				(width 0.1)
				(type default)
			)
			(layer "F.Fab")
		)
		(fp_line
			(start 0.120396 0.2794)
			(end -0.12065 0.2794)
			(stroke
				(width 0.1)
				(type default)
			)
			(layer "F.Fab")
		)
		(fp_line
			(start -0.12065 -0.2794)
			(end 0.12065 -0.2794)
			(stroke
				(width 0.1)
				(type default)
			)
			(layer "F.Fab")
		)
		(fp_line
			(start 0.12065 -0.2794)
			(end 0.12065 -0.3048)
			(stroke
				(width 0.1)
				(type default)
			)
			(layer "F.Fab")
		)
		(fp_line
			(start 0.12065 -0.3048)
			(end 0.67945 -0.3048)
			(stroke
				(width 0.1)
				(type default)
			)
			(layer "F.Fab")
		)
		(fp_line
			(start 0.67945 -0.3048)
			(end 0.67945 0.3048)
			(stroke
				(width 0.1)
				(type default)
			)
			(layer "F.Fab")
		)
		(fp_line
			(start -0.67945 -0.305054)
			(end -0.12065 -0.305054)
			(stroke
				(width 0.1)
				(type default)
			)
			(layer "F.Fab")
		)
		(fp_line
			(start -0.12065 -0.305054)
			(end -0.12065 -0.2794)
			(stroke
				(width 0.1)
				(type default)
			)
			(layer "F.Fab")
		)
		(pad "1" smd circle
			(at -0.40005 0 270)
			(size 0 0)
			(layers "F.Cu" "F.Mask" "F.Paste")
			(net "P3V3_AUX")
		)
		(pad "2" smd circle
			(at 0.40005 0 270)
			(size 0 0)
			(layers "F.Cu" "F.Mask" "F.Paste")
			(net "FM_P2E_EQA0")
		)
	)
	(footprint ""
		(layer "F.Cu")
		(at 88.8111 -327.768204)
		(property "Reference" "PL26"
			(at -3.844036 6.909054 0)
			(unlocked yes)
			(layer "F.SilkS")
			(effects
				(font
					(size 0.7874 0.5842)
					(thickness 0.1524)
				)
				(justify left)
			)
		)
		(property "Value" ""
			(at 0 0 0)
			(layer "F.Fab")
			(effects
				(font
					(size 1.27 1.27)
				)
			)
		)
		(duplicate_pad_numbers_are_jumpers no)
		(fp_line
			(start -3.750056 -5.500116)
			(end -2.393442 -5.500116)
			(stroke
				(width 0.1524)
				(type default)
			)
			(layer "F.SilkS")
		)
		(fp_line
			(start -3.750056 5.500116)
			(end -3.750056 -5.500116)
			(stroke
				(width 0.1524)
				(type default)
			)
			(layer "F.SilkS")
		)
		(fp_line
			(start -2.393442 5.500116)
			(end -3.750056 5.500116)
			(stroke
				(width 0.1524)
				(type default)
			)
			(layer "F.SilkS")
		)
		(fp_line
			(start 2.393442 5.500116)
			(end 3.750056 5.500116)
			(stroke
				(width 0.1524)
				(type default)
			)
			(layer "F.SilkS")
		)
		(fp_line
			(start 3.750056 -5.500116)
			(end 2.393442 -5.500116)
			(stroke
				(width 0.1524)
				(type default)
			)
			(layer "F.SilkS")
		)
		(fp_line
			(start 3.750056 5.500116)
			(end 3.750056 -5.500116)
			(stroke
				(width 0.1524)
				(type default)
			)
			(layer "F.SilkS")
		)
		(fp_poly
			(pts
				(xy -3.255772 -6.952996) (xy -2.896616 -5.875274) (xy -3.974338 -6.23443)
			)
			(stroke
				(width 0)
				(type default)
			)
			(fill yes)
			(layer "F.SilkS")
		)
		(fp_line
			(start -3.750056 -5.500116)
			(end -3.750056 5.500116)
			(stroke
				(width 0.1)
				(type default)
			)
			(layer "F.Fab")
		)
		(fp_line
			(start -3.750056 5.500116)
			(end 3.750056 5.500116)
			(stroke
				(width 0.1)
				(type default)
			)
			(layer "F.Fab")
		)
		(fp_line
			(start 3.750056 -5.500116)
			(end -3.750056 -5.500116)
			(stroke
				(width 0.1)
				(type default)
			)
			(layer "F.Fab")
		)
		(fp_line
			(start 3.750056 5.500116)
			(end 3.750056 -5.500116)
			(stroke
				(width 0.1)
				(type default)
			)
			(layer "F.Fab")
		)
		(fp_poly
			(pts
				(xy -4.9276 -4.757928) (xy -4.9276 -3.741928) (xy -3.9116 -4.249928)
			)
			(stroke
				(width 0)
				(type default)
			)
			(fill yes)
			(layer "F.Fab")
		)
		(pad "1" smd rect
			(at 0 -4.249928 270)
			(size 2.413 4.5212)
			(layers "F.Cu" "F.Mask" "F.Paste")
			(net "SW_PVCCIN_CPU1_SW6")
		)
		(pad "2" smd rect
			(at 0 -1.175004 270)
			(size 1.3716 4.5212)
			(layers "F.Cu" "F.Mask" "F.Paste")
			(net "IND_P1_CPL6")
		)
		(pad "3" smd rect
			(at 0 1.175004 270)
			(size 1.3716 4.5212)
			(layers "F.Cu" "F.Mask" "F.Paste")
			(net "IND_P1_CPL7")
		)
		(pad "4" smd rect
			(at 0 4.249928 270)
			(size 2.413 4.5212)
			(layers "F.Cu" "F.Mask" "F.Paste")
			(net "PVCCIN_CPU1")
		)
	)
	(footprint ""
		(layer "F.Cu")
		(at 36.956238 -130.76174 180)
		(property "Reference" "R2560"
			(at 0 0 180)
			(layer "F.SilkS")
			(hide yes)
			(effects
				(font
					(size 1.27 1.27)
				)
			)
		)
		(property "Value" ""
			(at 0 0 180)
			(layer "F.Fab")
			(effects
				(font
					(size 1.27 1.27)
				)
			)
		)
		(duplicate_pad_numbers_are_jumpers no)
		(fp_line
			(start 0.7874 0.4064)
			(end -0.7874 0.4064)
			(stroke
				(width 0.1524)
				(type default)
			)
			(layer "F.SilkS")
		)
		(fp_line
			(start 0.7874 -0.4064)
			(end 0.7874 0.4064)
			(stroke
				(width 0.1524)
				(type default)
			)
			(layer "F.SilkS")
		)
		(fp_line
			(start -0.7874 0.4064)
			(end -0.7874 -0.4064)
			(stroke
				(width 0.1524)
				(type default)
			)
			(layer "F.SilkS")
		)
		(fp_line
			(start -0.7874 -0.4064)
			(end 0.7874 -0.4064)
			(stroke
				(width 0.1524)
				(type default)
			)
			(layer "F.SilkS")
		)
		(fp_line
			(start 0.67945 0.3048)
			(end 0.120396 0.3048)
			(stroke
				(width 0.1)
				(type default)
			)
			(layer "F.Fab")
		)
		(fp_line
			(start 0.67945 -0.3048)
			(end 0.67945 0.3048)
			(stroke
				(width 0.1)
				(type default)
			)
			(layer "F.Fab")
		)
		(fp_line
			(start 0.12065 -0.2794)
			(end 0.12065 -0.3048)
			(stroke
				(width 0.1)
				(type default)
			)
			(layer "F.Fab")
		)
		(fp_line
			(start 0.12065 -0.3048)
			(end 0.67945 -0.3048)
			(stroke
				(width 0.1)
				(type default)
			)
			(layer "F.Fab")
		)
		(fp_line
			(start 0.120396 0.3048)
			(end 0.120396 0.2794)
			(stroke
				(width 0.1)
				(type default)
			)
			(layer "F.Fab")
		)
		(fp_line
			(start 0.120396 0.2794)
			(end -0.12065 0.2794)
			(stroke
				(width 0.1)
				(type default)
			)
			(layer "F.Fab")
		)
		(fp_line
			(start -0.12065 0.3048)
			(end -0.67945 0.3048)
			(stroke
				(width 0.1)
				(type default)
			)
			(layer "F.Fab")
		)
		(fp_line
			(start -0.12065 0.2794)
			(end -0.12065 0.3048)
			(stroke
				(width 0.1)
				(type default)
			)
			(layer "F.Fab")
		)
		(fp_line
			(start -0.12065 -0.2794)
			(end 0.12065 -0.2794)
			(stroke
				(width 0.1)
				(type default)
			)
			(layer "F.Fab")
		)
		(fp_line
			(start -0.12065 -0.305054)
			(end -0.12065 -0.2794)
			(stroke
				(width 0.1)
				(type default)
			)
			(layer "F.Fab")
		)
		(fp_line
			(start -0.67945 0.3048)
			(end -0.67945 -0.305054)
			(stroke
				(width 0.1)
				(type default)
			)
			(layer "F.Fab")
		)
		(fp_line
			(start -0.67945 -0.305054)
			(end -0.12065 -0.305054)
			(stroke
				(width 0.1)
				(type default)
			)
			(layer "F.Fab")
		)
		(pad "1" smd circle
			(at -0.40005 0 180)
			(size 0 0)
			(layers "F.Cu" "F.Mask" "F.Paste")
			(net "SVID_DIO0_CPU1_R")
		)
		(pad "2" smd circle
			(at 0.40005 0 180)
			(size 0 0)
			(layers "F.Cu" "F.Mask" "F.Paste")
			(net "SVID_DIO_PVCCINFAON_CPU1_R")
		)
	)
	(footprint ""
		(layer "F.Cu")
		(at 40.300402 -180.55336 180)
		(property "Reference" "C1403"
			(at 0 0 180)
			(layer "F.SilkS")
			(hide yes)
			(effects
				(font
					(size 1.27 1.27)
				)
			)
		)
		(property "Value" ""
			(at 0 0 180)
			(layer "F.Fab")
			(effects
				(font
					(size 1.27 1.27)
				)
			)
		)
		(duplicate_pad_numbers_are_jumpers no)
		(fp_line
			(start 1.524 0.762)
			(end -1.524 0.762)
			(stroke
				(width 0.1524)
				(type default)
			)
			(layer "F.SilkS")
		)
		(fp_line
			(start 1.524 -0.762)
			(end 1.524 0.762)
			(stroke
				(width 0.1524)
				(type default)
			)
			(layer "F.SilkS")
		)
		(fp_line
			(start -1.524 0.762)
			(end -1.524 -0.762)
			(stroke
				(width 0.1524)
				(type default)
			)
			(layer "F.SilkS")
		)
		(fp_line
			(start -1.524 -0.762)
			(end 1.524 -0.762)
			(stroke
				(width 0.1524)
				(type default)
			)
			(layer "F.SilkS")
		)
		(fp_line
			(start 1.1049 0.724916)
			(end 1.1049 -0.724916)
			(stroke
				(width 0.1)
				(type default)
			)
			(layer "F.Fab")
		)
		(fp_line
			(start 1.1049 -0.724916)
			(end -1.1049 -0.724916)
			(stroke
				(width 0.1)
				(type default)
			)
			(layer "F.Fab")
		)
		(fp_line
			(start -1.1049 0.724916)
			(end 1.1049 0.724916)
			(stroke
				(width 0.1)
				(type default)
			)
			(layer "F.Fab")
		)
		(fp_line
			(start -1.1049 -0.724916)
			(end -1.1049 0.724916)
			(stroke
				(width 0.1)
				(type default)
			)
			(layer "F.Fab")
		)
		(pad "1" smd rect
			(at -0.889 0)
			(size 1.016 1.27)
			(layers "F.Cu" "F.Mask" "F.Paste")
			(net "PVNN_MAIN_CPU1")
		)
		(pad "2" smd rect
			(at 0.889 0)
			(size 1.016 1.27)
			(layers "F.Cu" "F.Mask" "F.Paste")
			(net "GND")
		)
	)
	(footprint ""
		(layer "F.Cu")
		(at 332.433168 -23.571454 -90)
		(property "Reference" "R2363"
			(at 0 0 270)
			(layer "F.SilkS")
			(hide yes)
			(effects
				(font
					(size 1.27 1.27)
				)
			)
		)
		(property "Value" ""
			(at 0 0 270)
			(layer "F.Fab")
			(effects
				(font
					(size 1.27 1.27)
				)
			)
		)
		(duplicate_pad_numbers_are_jumpers no)
		(fp_line
			(start -0.7874 0.4064)
			(end -0.7874 -0.4064)
			(stroke
				(width 0.1524)
				(type default)
			)
			(layer "F.SilkS")
		)
		(fp_line
			(start 0.7874 0.4064)
			(end -0.7874 0.4064)
			(stroke
				(width 0.1524)
				(type default)
			)
			(layer "F.SilkS")
		)
		(fp_line
			(start -0.7874 -0.4064)
			(end 0.7874 -0.4064)
			(stroke
				(width 0.1524)
				(type default)
			)
			(layer "F.SilkS")
		)
		(fp_line
			(start 0.7874 -0.4064)
			(end 0.7874 0.4064)
			(stroke
				(width 0.1524)
				(type default)
			)
			(layer "F.SilkS")
		)
		(fp_line
			(start -0.67945 0.3048)
			(end -0.67945 -0.305054)
			(stroke
				(width 0.1)
				(type default)
			)
			(layer "F.Fab")
		)
		(fp_line
			(start -0.12065 0.3048)
			(end -0.67945 0.3048)
			(stroke
				(width 0.1)
				(type default)
			)
			(layer "F.Fab")
		)
		(fp_line
			(start 0.120396 0.3048)
			(end 0.120396 0.2794)
			(stroke
				(width 0.1)
				(type default)
			)
			(layer "F.Fab")
		)
		(fp_line
			(start 0.67945 0.3048)
			(end 0.120396 0.3048)
			(stroke
				(width 0.1)
				(type default)
			)
			(layer "F.Fab")
		)
		(fp_line
			(start -0.12065 0.2794)
			(end -0.12065 0.3048)
			(stroke
				(width 0.1)
				(type default)
			)
			(layer "F.Fab")
		)
		(fp_line
			(start 0.120396 0.2794)
			(end -0.12065 0.2794)
			(stroke
				(width 0.1)
				(type default)
			)
			(layer "F.Fab")
		)
		(fp_line
			(start -0.12065 -0.2794)
			(end 0.12065 -0.2794)
			(stroke
				(width 0.1)
				(type default)
			)
			(layer "F.Fab")
		)
		(fp_line
			(start 0.12065 -0.2794)
			(end 0.12065 -0.3048)
			(stroke
				(width 0.1)
				(type default)
			)
			(layer "F.Fab")
		)
		(fp_line
			(start 0.12065 -0.3048)
			(end 0.67945 -0.3048)
			(stroke
				(width 0.1)
				(type default)
			)
			(layer "F.Fab")
		)
		(fp_line
			(start 0.67945 -0.3048)
			(end 0.67945 0.3048)
			(stroke
				(width 0.1)
				(type default)
			)
			(layer "F.Fab")
		)
		(fp_line
			(start -0.67945 -0.305054)
			(end -0.12065 -0.305054)
			(stroke
				(width 0.1)
				(type default)
			)
			(layer "F.Fab")
		)
		(fp_line
			(start -0.12065 -0.305054)
			(end -0.12065 -0.2794)
			(stroke
				(width 0.1)
				(type default)
			)
			(layer "F.Fab")
		)
		(pad "1" smd circle
			(at -0.40005 0 270)
			(size 0 0)
			(layers "F.Cu" "F.Mask" "F.Paste")
			(net "RST_ESPI_RESET_N")
		)
		(pad "2" smd circle
			(at 0.40005 0 270)
			(size 0 0)
			(layers "F.Cu" "F.Mask" "F.Paste")
			(net "RST_ESPI_RESET_N_R")
		)
	)
	(footprint ""
		(layer "F.Cu")
		(at 237.401608 -403.705822)
		(property "Reference" "PR3995"
			(at 0 0 0)
			(layer "F.SilkS")
			(hide yes)
			(effects
				(font
					(size 1.27 1.27)
				)
			)
		)
		(property "Value" ""
			(at 0 0 0)
			(layer "F.Fab")
			(effects
				(font
					(size 1.27 1.27)
				)
			)
		)
		(duplicate_pad_numbers_are_jumpers no)
		(fp_line
			(start -0.7874 -0.4064)
			(end 0.7874 -0.4064)
			(stroke
				(width 0.1524)
				(type default)
			)
			(layer "F.SilkS")
		)
		(fp_line
			(start -0.7874 0.4064)
			(end -0.7874 -0.4064)
			(stroke
				(width 0.1524)
				(type default)
			)
			(layer "F.SilkS")
		)
		(fp_line
			(start 0.7874 -0.4064)
			(end 0.7874 0.4064)
			(stroke
				(width 0.1524)
				(type default)
			)
			(layer "F.SilkS")
		)
		(fp_line
			(start 0.7874 0.4064)
			(end -0.7874 0.4064)
			(stroke
				(width 0.1524)
				(type default)
			)
			(layer "F.SilkS")
		)
		(fp_line
			(start -0.67945 -0.305054)
			(end -0.12065 -0.305054)
			(stroke
				(width 0.1)
				(type default)
			)
			(layer "F.Fab")
		)
		(fp_line
			(start -0.67945 0.3048)
			(end -0.67945 -0.305054)
			(stroke
				(width 0.1)
				(type default)
			)
			(layer "F.Fab")
		)
		(fp_line
			(start -0.12065 -0.305054)
			(end -0.12065 -0.2794)
			(stroke
				(width 0.1)
				(type default)
			)
			(layer "F.Fab")
		)
		(fp_line
			(start -0.12065 -0.2794)
			(end 0.12065 -0.2794)
			(stroke
				(width 0.1)
				(type default)
			)
			(layer "F.Fab")
		)
		(fp_line
			(start -0.12065 0.2794)
			(end -0.12065 0.3048)
			(stroke
				(width 0.1)
				(type default)
			)
			(layer "F.Fab")
		)
		(fp_line
			(start -0.12065 0.3048)
			(end -0.67945 0.3048)
			(stroke
				(width 0.1)
				(type default)
			)
			(layer "F.Fab")
		)
		(fp_line
			(start 0.120396 0.2794)
			(end -0.12065 0.2794)
			(stroke
				(width 0.1)
				(type default)
			)
			(layer "F.Fab")
		)
		(fp_line
			(start 0.120396 0.3048)
			(end 0.120396 0.2794)
			(stroke
				(width 0.1)
				(type default)
			)
			(layer "F.Fab")
		)
		(fp_line
			(start 0.12065 -0.3048)
			(end 0.67945 -0.3048)
			(stroke
				(width 0.1)
				(type default)
			)
			(layer "F.Fab")
		)
		(fp_line
			(start 0.12065 -0.2794)
			(end 0.12065 -0.3048)
			(stroke
				(width 0.1)
				(type default)
			)
			(layer "F.Fab")
		)
		(fp_line
			(start 0.67945 -0.3048)
			(end 0.67945 0.3048)
			(stroke
				(width 0.1)
				(type default)
			)
			(layer "F.Fab")
		)
		(fp_line
			(start 0.67945 0.3048)
			(end 0.120396 0.3048)
			(stroke
				(width 0.1)
				(type default)
			)
			(layer "F.Fab")
		)
		(pad "1" smd circle
			(at -0.40005 0)
			(size 0 0)
			(layers "F.Cu" "F.Mask" "F.Paste")
			(net "HSC_FLT_TYPE_4")
		)
		(pad "2" smd circle
			(at 0.40005 0)
			(size 0 0)
			(layers "F.Cu" "F.Mask" "F.Paste")
			(net "HSC_FLT_TYPE")
		)
	)
	(footprint ""
		(layer "F.Cu")
		(at 434.805328 -16.188182 -90)
		(property "Reference" "R1671"
			(at 0 0 270)
			(layer "F.SilkS")
			(hide yes)
			(effects
				(font
					(size 1.27 1.27)
				)
			)
		)
		(property "Value" ""
			(at 0 0 270)
			(layer "F.Fab")
			(effects
				(font
					(size 1.27 1.27)
				)
			)
		)
		(duplicate_pad_numbers_are_jumpers no)
		(fp_line
			(start -0.7874 0.4064)
			(end -0.7874 -0.4064)
			(stroke
				(width 0.1524)
				(type default)
			)
			(layer "F.SilkS")
		)
		(fp_line
			(start 0.7874 0.4064)
			(end -0.7874 0.4064)
			(stroke
				(width 0.1524)
				(type default)
			)
			(layer "F.SilkS")
		)
		(fp_line
			(start -0.7874 -0.4064)
			(end 0.7874 -0.4064)
			(stroke
				(width 0.1524)
				(type default)
			)
			(layer "F.SilkS")
		)
		(fp_line
			(start 0.7874 -0.4064)
			(end 0.7874 0.4064)
			(stroke
				(width 0.1524)
				(type default)
			)
			(layer "F.SilkS")
		)
		(fp_line
			(start -0.67945 0.3048)
			(end -0.67945 -0.305054)
			(stroke
				(width 0.1)
				(type default)
			)
			(layer "F.Fab")
		)
		(fp_line
			(start -0.12065 0.3048)
			(end -0.67945 0.3048)
			(stroke
				(width 0.1)
				(type default)
			)
			(layer "F.Fab")
		)
		(fp_line
			(start 0.120396 0.3048)
			(end 0.120396 0.2794)
			(stroke
				(width 0.1)
				(type default)
			)
			(layer "F.Fab")
		)
		(fp_line
			(start 0.67945 0.3048)
			(end 0.120396 0.3048)
			(stroke
				(width 0.1)
				(type default)
			)
			(layer "F.Fab")
		)
		(fp_line
			(start -0.12065 0.2794)
			(end -0.12065 0.3048)
			(stroke
				(width 0.1)
				(type default)
			)
			(layer "F.Fab")
		)
		(fp_line
			(start 0.120396 0.2794)
			(end -0.12065 0.2794)
			(stroke
				(width 0.1)
				(type default)
			)
			(layer "F.Fab")
		)
		(fp_line
			(start -0.12065 -0.2794)
			(end 0.12065 -0.2794)
			(stroke
				(width 0.1)
				(type default)
			)
			(layer "F.Fab")
		)
		(fp_line
			(start 0.12065 -0.2794)
			(end 0.12065 -0.3048)
			(stroke
				(width 0.1)
				(type default)
			)
			(layer "F.Fab")
		)
		(fp_line
			(start 0.12065 -0.3048)
			(end 0.67945 -0.3048)
			(stroke
				(width 0.1)
				(type default)
			)
			(layer "F.Fab")
		)
		(fp_line
			(start 0.67945 -0.3048)
			(end 0.67945 0.3048)
			(stroke
				(width 0.1)
				(type default)
			)
			(layer "F.Fab")
		)
		(fp_line
			(start -0.67945 -0.305054)
			(end -0.12065 -0.305054)
			(stroke
				(width 0.1)
				(type default)
			)
			(layer "F.Fab")
		)
		(fp_line
			(start -0.12065 -0.305054)
			(end -0.12065 -0.2794)
			(stroke
				(width 0.1)
				(type default)
			)
			(layer "F.Fab")
		)
		(pad "1" smd circle
			(at -0.40005 0 270)
			(size 0 0)
			(layers "F.Cu" "F.Mask" "F.Paste")
			(net "OCP_SFF_AUX_PWR_EN")
		)
		(pad "2" smd circle
			(at 0.40005 0 270)
			(size 0 0)
			(layers "F.Cu" "F.Mask" "F.Paste")
			(net "OCP_SFF_AUX_PWR_EN_R")
		)
	)
	(footprint ""
		(layer "F.Cu")
		(at 435.208172 -32.173418 -90)
		(property "Reference" "R3869"
			(at 0 0 270)
			(layer "F.SilkS")
			(hide yes)
			(effects
				(font
					(size 1.27 1.27)
				)
			)
		)
		(property "Value" ""
			(at 0 0 270)
			(layer "F.Fab")
			(effects
				(font
					(size 1.27 1.27)
				)
			)
		)
		(duplicate_pad_numbers_are_jumpers no)
		(fp_line
			(start -0.7874 0.4064)
			(end -0.7874 -0.4064)
			(stroke
				(width 0.1524)
				(type default)
			)
			(layer "F.SilkS")
		)
		(fp_line
			(start 0.7874 0.4064)
			(end -0.7874 0.4064)
			(stroke
				(width 0.1524)
				(type default)
			)
			(layer "F.SilkS")
		)
		(fp_line
			(start -0.7874 -0.4064)
			(end 0.7874 -0.4064)
			(stroke
				(width 0.1524)
				(type default)
			)
			(layer "F.SilkS")
		)
		(fp_line
			(start 0.7874 -0.4064)
			(end 0.7874 0.4064)
			(stroke
				(width 0.1524)
				(type default)
			)
			(layer "F.SilkS")
		)
		(fp_line
			(start -0.67945 0.3048)
			(end -0.67945 -0.305054)
			(stroke
				(width 0.1)
				(type default)
			)
			(layer "F.Fab")
		)
		(fp_line
			(start -0.12065 0.3048)
			(end -0.67945 0.3048)
			(stroke
				(width 0.1)
				(type default)
			)
			(layer "F.Fab")
		)
		(fp_line
			(start 0.120396 0.3048)
			(end 0.120396 0.2794)
			(stroke
				(width 0.1)
				(type default)
			)
			(layer "F.Fab")
		)
		(fp_line
			(start 0.67945 0.3048)
			(end 0.120396 0.3048)
			(stroke
				(width 0.1)
				(type default)
			)
			(layer "F.Fab")
		)
		(fp_line
			(start -0.12065 0.2794)
			(end -0.12065 0.3048)
			(stroke
				(width 0.1)
				(type default)
			)
			(layer "F.Fab")
		)
		(fp_line
			(start 0.120396 0.2794)
			(end -0.12065 0.2794)
			(stroke
				(width 0.1)
				(type default)
			)
			(layer "F.Fab")
		)
		(fp_line
			(start -0.12065 -0.2794)
			(end 0.12065 -0.2794)
			(stroke
				(width 0.1)
				(type default)
			)
			(layer "F.Fab")
		)
		(fp_line
			(start 0.12065 -0.2794)
			(end 0.12065 -0.3048)
			(stroke
				(width 0.1)
				(type default)
			)
			(layer "F.Fab")
		)
		(fp_line
			(start 0.12065 -0.3048)
			(end 0.67945 -0.3048)
			(stroke
				(width 0.1)
				(type default)
			)
			(layer "F.Fab")
		)
		(fp_line
			(start 0.67945 -0.3048)
			(end 0.67945 0.3048)
			(stroke
				(width 0.1)
				(type default)
			)
			(layer "F.Fab")
		)
		(fp_line
			(start -0.67945 -0.305054)
			(end -0.12065 -0.305054)
			(stroke
				(width 0.1)
				(type default)
			)
			(layer "F.Fab")
		)
		(fp_line
			(start -0.12065 -0.305054)
			(end -0.12065 -0.2794)
			(stroke
				(width 0.1)
				(type default)
			)
			(layer "F.Fab")
		)
		(pad "1" smd rect
			(at -0.40005 0 90)
			(size 0.4572 0.508)
			(layers "F.Cu" "F.Mask" "F.Paste")
			(net "P12V_OCP_SENSE_1")
		)
		(pad "2" smd rect
			(at 0.40005 0 90)
			(size 0.4572 0.508)
			(layers "F.Cu" "F.Mask" "F.Paste")
			(net "P12V_OCP_SFF_ISENSE_MAM_MAM")
		)
	)
	(footprint ""
		(layer "F.Cu")
		(at 106.32313 -240.277142 90)
		(property "Reference" "C292"
			(at 0 0 90)
			(layer "F.SilkS")
			(hide yes)
			(effects
				(font
					(size 1.27 1.27)
				)
			)
		)
		(property "Value" ""
			(at 0 0 90)
			(layer "F.Fab")
			(effects
				(font
					(size 1.27 1.27)
				)
			)
		)
		(duplicate_pad_numbers_are_jumpers no)
		(fp_line
			(start 0.7874 -0.4064)
			(end 0.7874 0.4064)
			(stroke
				(width 0.1524)
				(type default)
			)
			(layer "F.SilkS")
		)
		(fp_line
			(start -0.7874 -0.4064)
			(end 0.7874 -0.4064)
			(stroke
				(width 0.1524)
				(type default)
			)
			(layer "F.SilkS")
		)
		(fp_line
			(start 0.7874 0.4064)
			(end -0.7874 0.4064)
			(stroke
				(width 0.1524)
				(type default)
			)
			(layer "F.SilkS")
		)
		(fp_line
			(start -0.7874 0.4064)
			(end -0.7874 -0.4064)
			(stroke
				(width 0.1524)
				(type default)
			)
			(layer "F.SilkS")
		)
		(fp_line
			(start -0.12065 -0.305054)
			(end -0.12065 -0.2794)
			(stroke
				(width 0.1)
				(type default)
			)
			(layer "F.Fab")
		)
		(fp_line
			(start -0.67945 -0.305054)
			(end -0.12065 -0.305054)
			(stroke
				(width 0.1)
				(type default)
			)
			(layer "F.Fab")
		)
		(fp_line
			(start 0.67945 -0.3048)
			(end 0.67945 0.3048)
			(stroke
				(width 0.1)
				(type default)
			)
			(layer "F.Fab")
		)
		(fp_line
			(start 0.12065 -0.3048)
			(end 0.67945 -0.3048)
			(stroke
				(width 0.1)
				(type default)
			)
			(layer "F.Fab")
		)
		(fp_line
			(start 0.12065 -0.2794)
			(end 0.12065 -0.3048)
			(stroke
				(width 0.1)
				(type default)
			)
			(layer "F.Fab")
		)
		(fp_line
			(start -0.12065 -0.2794)
			(end 0.12065 -0.2794)
			(stroke
				(width 0.1)
				(type default)
			)
			(layer "F.Fab")
		)
		(fp_line
			(start 0.120396 0.2794)
			(end -0.12065 0.2794)
			(stroke
				(width 0.1)
				(type default)
			)
			(layer "F.Fab")
		)
		(fp_line
			(start -0.12065 0.2794)
			(end -0.12065 0.3048)
			(stroke
				(width 0.1)
				(type default)
			)
			(layer "F.Fab")
		)
		(fp_line
			(start 0.67945 0.3048)
			(end 0.120396 0.3048)
			(stroke
				(width 0.1)
				(type default)
			)
			(layer "F.Fab")
		)
		(fp_line
			(start 0.120396 0.3048)
			(end 0.120396 0.2794)
			(stroke
				(width 0.1)
				(type default)
			)
			(layer "F.Fab")
		)
		(fp_line
			(start -0.12065 0.3048)
			(end -0.67945 0.3048)
			(stroke
				(width 0.1)
				(type default)
			)
			(layer "F.Fab")
		)
		(fp_line
			(start -0.67945 0.3048)
			(end -0.67945 -0.305054)
			(stroke
				(width 0.1)
				(type default)
			)
			(layer "F.Fab")
		)
		(pad "1" smd circle
			(at -0.40005 0 90)
			(size 0 0)
			(layers "F.Cu" "F.Mask" "F.Paste")
			(net "PVCCIN_CPU1")
		)
		(pad "2" smd circle
			(at 0.40005 0 90)
			(size 0 0)
			(layers "F.Cu" "F.Mask" "F.Paste")
			(net "GND")
		)
	)
	(footprint ""
		(layer "F.Cu")
		(at 7.42188 -56.987948)
		(property "Reference" "R2995"
			(at 0 0 0)
			(layer "F.SilkS")
			(hide yes)
			(effects
				(font
					(size 1.27 1.27)
				)
			)
		)
		(property "Value" ""
			(at 0 0 0)
			(layer "F.Fab")
			(effects
				(font
					(size 1.27 1.27)
				)
			)
		)
		(duplicate_pad_numbers_are_jumpers no)
		(fp_line
			(start -0.7874 -0.4064)
			(end 0.7874 -0.4064)
			(stroke
				(width 0.1524)
				(type default)
			)
			(layer "F.SilkS")
		)
		(fp_line
			(start -0.7874 0.4064)
			(end -0.7874 -0.4064)
			(stroke
				(width 0.1524)
				(type default)
			)
			(layer "F.SilkS")
		)
		(fp_line
			(start 0.7874 -0.4064)
			(end 0.7874 0.4064)
			(stroke
				(width 0.1524)
				(type default)
			)
			(layer "F.SilkS")
		)
		(fp_line
			(start 0.7874 0.4064)
			(end -0.7874 0.4064)
			(stroke
				(width 0.1524)
				(type default)
			)
			(layer "F.SilkS")
		)
		(fp_line
			(start -0.67945 -0.305054)
			(end -0.12065 -0.305054)
			(stroke
				(width 0.1)
				(type default)
			)
			(layer "F.Fab")
		)
		(fp_line
			(start -0.67945 0.3048)
			(end -0.67945 -0.305054)
			(stroke
				(width 0.1)
				(type default)
			)
			(layer "F.Fab")
		)
		(fp_line
			(start -0.12065 -0.305054)
			(end -0.12065 -0.2794)
			(stroke
				(width 0.1)
				(type default)
			)
			(layer "F.Fab")
		)
		(fp_line
			(start -0.12065 -0.2794)
			(end 0.12065 -0.2794)
			(stroke
				(width 0.1)
				(type default)
			)
			(layer "F.Fab")
		)
		(fp_line
			(start -0.12065 0.2794)
			(end -0.12065 0.3048)
			(stroke
				(width 0.1)
				(type default)
			)
			(layer "F.Fab")
		)
		(fp_line
			(start -0.12065 0.3048)
			(end -0.67945 0.3048)
			(stroke
				(width 0.1)
				(type default)
			)
			(layer "F.Fab")
		)
		(fp_line
			(start 0.120396 0.2794)
			(end -0.12065 0.2794)
			(stroke
				(width 0.1)
				(type default)
			)
			(layer "F.Fab")
		)
		(fp_line
			(start 0.120396 0.3048)
			(end 0.120396 0.2794)
			(stroke
				(width 0.1)
				(type default)
			)
			(layer "F.Fab")
		)
		(fp_line
			(start 0.12065 -0.3048)
			(end 0.67945 -0.3048)
			(stroke
				(width 0.1)
				(type default)
			)
			(layer "F.Fab")
		)
		(fp_line
			(start 0.12065 -0.2794)
			(end 0.12065 -0.3048)
			(stroke
				(width 0.1)
				(type default)
			)
			(layer "F.Fab")
		)
		(fp_line
			(start 0.67945 -0.3048)
			(end 0.67945 0.3048)
			(stroke
				(width 0.1)
				(type default)
			)
			(layer "F.Fab")
		)
		(fp_line
			(start 0.67945 0.3048)
			(end 0.120396 0.3048)
			(stroke
				(width 0.1)
				(type default)
			)
			(layer "F.Fab")
		)
		(pad "1" smd circle
			(at -0.40005 0)
			(size 0 0)
			(layers "F.Cu" "F.Mask" "F.Paste")
			(net "SMB_SML1_PMBUS_3V3AUX_PCH_SCL")
		)
		(pad "2" smd circle
			(at 0.40005 0)
			(size 0 0)
			(layers "F.Cu" "F.Mask" "F.Paste")
			(net "SMB_SML1_PMBUS_HSC_SCL_R3")
		)
	)
	(footprint ""
		(layer "F.Cu")
		(at 397.403066 -166.475664)
		(property "Reference" "PR592"
			(at 0 0 0)
			(layer "F.SilkS")
			(hide yes)
			(effects
				(font
					(size 1.27 1.27)
				)
			)
		)
		(property "Value" ""
			(at 0 0 0)
			(layer "F.Fab")
			(effects
				(font
					(size 1.27 1.27)
				)
			)
		)
		(duplicate_pad_numbers_are_jumpers no)
		(fp_line
			(start -0.7874 -0.4064)
			(end 0.7874 -0.4064)
			(stroke
				(width 0.1524)
				(type default)
			)
			(layer "F.SilkS")
		)
		(fp_line
			(start -0.7874 0.4064)
			(end -0.7874 -0.4064)
			(stroke
				(width 0.1524)
				(type default)
			)
			(layer "F.SilkS")
		)
		(fp_line
			(start 0.7874 -0.4064)
			(end 0.7874 0.4064)
			(stroke
				(width 0.1524)
				(type default)
			)
			(layer "F.SilkS")
		)
		(fp_line
			(start 0.7874 0.4064)
			(end -0.7874 0.4064)
			(stroke
				(width 0.1524)
				(type default)
			)
			(layer "F.SilkS")
		)
		(fp_line
			(start -0.67945 -0.305054)
			(end -0.12065 -0.305054)
			(stroke
				(width 0.1)
				(type default)
			)
			(layer "F.Fab")
		)
		(fp_line
			(start -0.67945 0.3048)
			(end -0.67945 -0.305054)
			(stroke
				(width 0.1)
				(type default)
			)
			(layer "F.Fab")
		)
		(fp_line
			(start -0.12065 -0.305054)
			(end -0.12065 -0.2794)
			(stroke
				(width 0.1)
				(type default)
			)
			(layer "F.Fab")
		)
		(fp_line
			(start -0.12065 -0.2794)
			(end 0.12065 -0.2794)
			(stroke
				(width 0.1)
				(type default)
			)
			(layer "F.Fab")
		)
		(fp_line
			(start -0.12065 0.2794)
			(end -0.12065 0.3048)
			(stroke
				(width 0.1)
				(type default)
			)
			(layer "F.Fab")
		)
		(fp_line
			(start -0.12065 0.3048)
			(end -0.67945 0.3048)
			(stroke
				(width 0.1)
				(type default)
			)
			(layer "F.Fab")
		)
		(fp_line
			(start 0.120396 0.2794)
			(end -0.12065 0.2794)
			(stroke
				(width 0.1)
				(type default)
			)
			(layer "F.Fab")
		)
		(fp_line
			(start 0.120396 0.3048)
			(end 0.120396 0.2794)
			(stroke
				(width 0.1)
				(type default)
			)
			(layer "F.Fab")
		)
		(fp_line
			(start 0.12065 -0.3048)
			(end 0.67945 -0.3048)
			(stroke
				(width 0.1)
				(type default)
			)
			(layer "F.Fab")
		)
		(fp_line
			(start 0.12065 -0.2794)
			(end 0.12065 -0.3048)
			(stroke
				(width 0.1)
				(type default)
			)
			(layer "F.Fab")
		)
		(fp_line
			(start 0.67945 -0.3048)
			(end 0.67945 0.3048)
			(stroke
				(width 0.1)
				(type default)
			)
			(layer "F.Fab")
		)
		(fp_line
			(start 0.67945 0.3048)
			(end 0.120396 0.3048)
			(stroke
				(width 0.1)
				(type default)
			)
			(layer "F.Fab")
		)
		(pad "1" smd circle
			(at -0.40005 0)
			(size 0 0)
			(layers "F.Cu" "F.Mask" "F.Paste")
			(net "VSENSE_PVCCD_HV_CPU0_DP")
		)
		(pad "2" smd circle
			(at 0.40005 0)
			(size 0 0)
			(layers "F.Cu" "F.Mask" "F.Paste")
			(net "PVCCD_HV_CPU0")
		)
	)
	(footprint ""
		(layer "F.Cu")
		(at 180.776626 -416.903154 -90)
		(property "Reference" "C1751"
			(at 0 0 270)
			(layer "F.SilkS")
			(hide yes)
			(effects
				(font
					(size 1.27 1.27)
				)
			)
		)
		(property "Value" ""
			(at 0 0 270)
			(layer "F.Fab")
			(effects
				(font
					(size 1.27 1.27)
				)
			)
		)
		(duplicate_pad_numbers_are_jumpers no)
		(fp_line
			(start -0.7874 0.4064)
			(end -0.7874 -0.4064)
			(stroke
				(width 0.1524)
				(type default)
			)
			(layer "F.SilkS")
		)
		(fp_line
			(start 0.7874 0.4064)
			(end -0.7874 0.4064)
			(stroke
				(width 0.1524)
				(type default)
			)
			(layer "F.SilkS")
		)
		(fp_line
			(start -0.7874 -0.4064)
			(end 0.7874 -0.4064)
			(stroke
				(width 0.1524)
				(type default)
			)
			(layer "F.SilkS")
		)
		(fp_line
			(start 0.7874 -0.4064)
			(end 0.7874 0.4064)
			(stroke
				(width 0.1524)
				(type default)
			)
			(layer "F.SilkS")
		)
		(fp_line
			(start -0.67945 0.3048)
			(end -0.67945 -0.305054)
			(stroke
				(width 0.1)
				(type default)
			)
			(layer "F.Fab")
		)
		(fp_line
			(start -0.12065 0.3048)
			(end -0.67945 0.3048)
			(stroke
				(width 0.1)
				(type default)
			)
			(layer "F.Fab")
		)
		(fp_line
			(start 0.120396 0.3048)
			(end 0.120396 0.2794)
			(stroke
				(width 0.1)
				(type default)
			)
			(layer "F.Fab")
		)
		(fp_line
			(start 0.67945 0.3048)
			(end 0.120396 0.3048)
			(stroke
				(width 0.1)
				(type default)
			)
			(layer "F.Fab")
		)
		(fp_line
			(start -0.12065 0.2794)
			(end -0.12065 0.3048)
			(stroke
				(width 0.1)
				(type default)
			)
			(layer "F.Fab")
		)
		(fp_line
			(start 0.120396 0.2794)
			(end -0.12065 0.2794)
			(stroke
				(width 0.1)
				(type default)
			)
			(layer "F.Fab")
		)
		(fp_line
			(start -0.12065 -0.2794)
			(end 0.12065 -0.2794)
			(stroke
				(width 0.1)
				(type default)
			)
			(layer "F.Fab")
		)
		(fp_line
			(start 0.12065 -0.2794)
			(end 0.12065 -0.3048)
			(stroke
				(width 0.1)
				(type default)
			)
			(layer "F.Fab")
		)
		(fp_line
			(start 0.12065 -0.3048)
			(end 0.67945 -0.3048)
			(stroke
				(width 0.1)
				(type default)
			)
			(layer "F.Fab")
		)
		(fp_line
			(start 0.67945 -0.3048)
			(end 0.67945 0.3048)
			(stroke
				(width 0.1)
				(type default)
			)
			(layer "F.Fab")
		)
		(fp_line
			(start -0.67945 -0.305054)
			(end -0.12065 -0.305054)
			(stroke
				(width 0.1)
				(type default)
			)
			(layer "F.Fab")
		)
		(fp_line
			(start -0.12065 -0.305054)
			(end -0.12065 -0.2794)
			(stroke
				(width 0.1)
				(type default)
			)
			(layer "F.Fab")
		)
		(pad "1" smd circle
			(at -0.40005 0 270)
			(size 0 0)
			(layers "F.Cu" "F.Mask" "F.Paste")
			(net "P3V3_AUX")
		)
		(pad "2" smd circle
			(at 0.40005 0 270)
			(size 0 0)
			(layers "F.Cu" "F.Mask" "F.Paste")
			(net "GND")
		)
	)
	(footprint ""
		(layer "F.Cu")
		(at 169.44848 -424.906948)
		(property "Reference" "R2815"
			(at 0 0 0)
			(layer "F.SilkS")
			(hide yes)
			(effects
				(font
					(size 1.27 1.27)
				)
			)
		)
		(property "Value" ""
			(at 0 0 0)
			(layer "F.Fab")
			(effects
				(font
					(size 1.27 1.27)
				)
			)
		)
		(duplicate_pad_numbers_are_jumpers no)
		(fp_line
			(start -0.7874 -0.4064)
			(end 0.7874 -0.4064)
			(stroke
				(width 0.1524)
				(type default)
			)
			(layer "F.SilkS")
		)
		(fp_line
			(start -0.7874 0.4064)
			(end -0.7874 -0.4064)
			(stroke
				(width 0.1524)
				(type default)
			)
			(layer "F.SilkS")
		)
		(fp_line
			(start 0.7874 -0.4064)
			(end 0.7874 0.4064)
			(stroke
				(width 0.1524)
				(type default)
			)
			(layer "F.SilkS")
		)
		(fp_line
			(start 0.7874 0.4064)
			(end -0.7874 0.4064)
			(stroke
				(width 0.1524)
				(type default)
			)
			(layer "F.SilkS")
		)
		(fp_line
			(start -0.67945 -0.305054)
			(end -0.12065 -0.305054)
			(stroke
				(width 0.1)
				(type default)
			)
			(layer "F.Fab")
		)
		(fp_line
			(start -0.67945 0.3048)
			(end -0.67945 -0.305054)
			(stroke
				(width 0.1)
				(type default)
			)
			(layer "F.Fab")
		)
		(fp_line
			(start -0.12065 -0.305054)
			(end -0.12065 -0.2794)
			(stroke
				(width 0.1)
				(type default)
			)
			(layer "F.Fab")
		)
		(fp_line
			(start -0.12065 -0.2794)
			(end 0.12065 -0.2794)
			(stroke
				(width 0.1)
				(type default)
			)
			(layer "F.Fab")
		)
		(fp_line
			(start -0.12065 0.2794)
			(end -0.12065 0.3048)
			(stroke
				(width 0.1)
				(type default)
			)
			(layer "F.Fab")
		)
		(fp_line
			(start -0.12065 0.3048)
			(end -0.67945 0.3048)
			(stroke
				(width 0.1)
				(type default)
			)
			(layer "F.Fab")
		)
		(fp_line
			(start 0.120396 0.2794)
			(end -0.12065 0.2794)
			(stroke
				(width 0.1)
				(type default)
			)
			(layer "F.Fab")
		)
		(fp_line
			(start 0.120396 0.3048)
			(end 0.120396 0.2794)
			(stroke
				(width 0.1)
				(type default)
			)
			(layer "F.Fab")
		)
		(fp_line
			(start 0.12065 -0.3048)
			(end 0.67945 -0.3048)
			(stroke
				(width 0.1)
				(type default)
			)
			(layer "F.Fab")
		)
		(fp_line
			(start 0.12065 -0.2794)
			(end 0.12065 -0.3048)
			(stroke
				(width 0.1)
				(type default)
			)
			(layer "F.Fab")
		)
		(fp_line
			(start 0.67945 -0.3048)
			(end 0.67945 0.3048)
			(stroke
				(width 0.1)
				(type default)
			)
			(layer "F.Fab")
		)
		(fp_line
			(start 0.67945 0.3048)
			(end 0.120396 0.3048)
			(stroke
				(width 0.1)
				(type default)
			)
			(layer "F.Fab")
		)
		(pad "1" smd circle
			(at -0.40005 0)
			(size 0 0)
			(layers "F.Cu" "F.Mask" "F.Paste")
			(net "P3V3_AUX")
		)
		(pad "2" smd circle
			(at 0.40005 0)
			(size 0 0)
			(layers "F.Cu" "F.Mask" "F.Paste")
			(net "BMC_MONITER_R")
		)
	)
	(footprint ""
		(layer "F.Cu")
		(at 49.161954 -173.047914)
		(property "Reference" "PC1366"
			(at 0 0 0)
			(layer "F.SilkS")
			(hide yes)
			(effects
				(font
					(size 1.27 1.27)
				)
			)
		)
		(property "Value" ""
			(at 0 0 0)
			(layer "F.Fab")
			(effects
				(font
					(size 1.27 1.27)
				)
			)
		)
		(duplicate_pad_numbers_are_jumpers no)
		(fp_line
			(start -0.7874 -0.4064)
			(end 0.7874 -0.4064)
			(stroke
				(width 0.1524)
				(type default)
			)
			(layer "F.SilkS")
		)
		(fp_line
			(start -0.7874 0.4064)
			(end -0.7874 -0.4064)
			(stroke
				(width 0.1524)
				(type default)
			)
			(layer "F.SilkS")
		)
		(fp_line
			(start 0.7874 -0.4064)
			(end 0.7874 0.4064)
			(stroke
				(width 0.1524)
				(type default)
			)
			(layer "F.SilkS")
		)
		(fp_line
			(start 0.7874 0.4064)
			(end -0.7874 0.4064)
			(stroke
				(width 0.1524)
				(type default)
			)
			(layer "F.SilkS")
		)
		(fp_line
			(start -0.67945 -0.305054)
			(end -0.12065 -0.305054)
			(stroke
				(width 0.1)
				(type default)
			)
			(layer "F.Fab")
		)
		(fp_line
			(start -0.67945 0.3048)
			(end -0.67945 -0.305054)
			(stroke
				(width 0.1)
				(type default)
			)
			(layer "F.Fab")
		)
		(fp_line
			(start -0.12065 -0.305054)
			(end -0.12065 -0.2794)
			(stroke
				(width 0.1)
				(type default)
			)
			(layer "F.Fab")
		)
		(fp_line
			(start -0.12065 -0.2794)
			(end 0.12065 -0.2794)
			(stroke
				(width 0.1)
				(type default)
			)
			(layer "F.Fab")
		)
		(fp_line
			(start -0.12065 0.2794)
			(end -0.12065 0.3048)
			(stroke
				(width 0.1)
				(type default)
			)
			(layer "F.Fab")
		)
		(fp_line
			(start -0.12065 0.3048)
			(end -0.67945 0.3048)
			(stroke
				(width 0.1)
				(type default)
			)
			(layer "F.Fab")
		)
		(fp_line
			(start 0.120396 0.2794)
			(end -0.12065 0.2794)
			(stroke
				(width 0.1)
				(type default)
			)
			(layer "F.Fab")
		)
		(fp_line
			(start 0.120396 0.3048)
			(end 0.120396 0.2794)
			(stroke
				(width 0.1)
				(type default)
			)
			(layer "F.Fab")
		)
		(fp_line
			(start 0.12065 -0.3048)
			(end 0.67945 -0.3048)
			(stroke
				(width 0.1)
				(type default)
			)
			(layer "F.Fab")
		)
		(fp_line
			(start 0.12065 -0.2794)
			(end 0.12065 -0.3048)
			(stroke
				(width 0.1)
				(type default)
			)
			(layer "F.Fab")
		)
		(fp_line
			(start 0.67945 -0.3048)
			(end 0.67945 0.3048)
			(stroke
				(width 0.1)
				(type default)
			)
			(layer "F.Fab")
		)
		(fp_line
			(start 0.67945 0.3048)
			(end 0.120396 0.3048)
			(stroke
				(width 0.1)
				(type default)
			)
			(layer "F.Fab")
		)
		(pad "1" smd circle
			(at -0.40005 0)
			(size 0 0)
			(layers "F.Cu" "F.Mask" "F.Paste")
			(net "GND")
		)
		(pad "2" smd circle
			(at 0.40005 0)
			(size 0 0)
			(layers "F.Cu" "F.Mask" "F.Paste")
			(net "PVCCINFAON_CPU1_VREF")
		)
	)
	(footprint ""
		(layer "F.Cu")
		(at 184.658 -93.91015 90)
		(property "Reference" "R4760"
			(at 0 0 90)
			(layer "F.SilkS")
			(hide yes)
			(effects
				(font
					(size 1.27 1.27)
				)
			)
		)
		(property "Value" ""
			(at 0 0 90)
			(layer "F.Fab")
			(effects
				(font
					(size 1.27 1.27)
				)
			)
		)
		(duplicate_pad_numbers_are_jumpers no)
		(fp_line
			(start 0.7874 -0.4064)
			(end 0.7874 0.4064)
			(stroke
				(width 0.1524)
				(type default)
			)
			(layer "F.SilkS")
		)
		(fp_line
			(start -0.7874 -0.4064)
			(end 0.7874 -0.4064)
			(stroke
				(width 0.1524)
				(type default)
			)
			(layer "F.SilkS")
		)
		(fp_line
			(start 0.7874 0.4064)
			(end -0.7874 0.4064)
			(stroke
				(width 0.1524)
				(type default)
			)
			(layer "F.SilkS")
		)
		(fp_line
			(start -0.7874 0.4064)
			(end -0.7874 -0.4064)
			(stroke
				(width 0.1524)
				(type default)
			)
			(layer "F.SilkS")
		)
		(fp_line
			(start -0.12065 -0.305054)
			(end -0.12065 -0.2794)
			(stroke
				(width 0.1)
				(type default)
			)
			(layer "F.Fab")
		)
		(fp_line
			(start -0.67945 -0.305054)
			(end -0.12065 -0.305054)
			(stroke
				(width 0.1)
				(type default)
			)
			(layer "F.Fab")
		)
		(fp_line
			(start 0.67945 -0.3048)
			(end 0.67945 0.3048)
			(stroke
				(width 0.1)
				(type default)
			)
			(layer "F.Fab")
		)
		(fp_line
			(start 0.12065 -0.3048)
			(end 0.67945 -0.3048)
			(stroke
				(width 0.1)
				(type default)
			)
			(layer "F.Fab")
		)
		(fp_line
			(start 0.12065 -0.2794)
			(end 0.12065 -0.3048)
			(stroke
				(width 0.1)
				(type default)
			)
			(layer "F.Fab")
		)
		(fp_line
			(start -0.12065 -0.2794)
			(end 0.12065 -0.2794)
			(stroke
				(width 0.1)
				(type default)
			)
			(layer "F.Fab")
		)
		(fp_line
			(start 0.120396 0.2794)
			(end -0.12065 0.2794)
			(stroke
				(width 0.1)
				(type default)
			)
			(layer "F.Fab")
		)
		(fp_line
			(start -0.12065 0.2794)
			(end -0.12065 0.3048)
			(stroke
				(width 0.1)
				(type default)
			)
			(layer "F.Fab")
		)
		(fp_line
			(start 0.67945 0.3048)
			(end 0.120396 0.3048)
			(stroke
				(width 0.1)
				(type default)
			)
			(layer "F.Fab")
		)
		(fp_line
			(start 0.120396 0.3048)
			(end 0.120396 0.2794)
			(stroke
				(width 0.1)
				(type default)
			)
			(layer "F.Fab")
		)
		(fp_line
			(start -0.12065 0.3048)
			(end -0.67945 0.3048)
			(stroke
				(width 0.1)
				(type default)
			)
			(layer "F.Fab")
		)
		(fp_line
			(start -0.67945 0.3048)
			(end -0.67945 -0.305054)
			(stroke
				(width 0.1)
				(type default)
			)
			(layer "F.Fab")
		)
		(pad "1" smd circle
			(at -0.40005 0 90)
			(size 0 0)
			(layers "F.Cu" "F.Mask" "F.Paste")
			(net "HP_LVC3_OCP_V3_2_PWRGD_R")
		)
		(pad "2" smd circle
			(at 0.40005 0 90)
			(size 0 0)
			(layers "F.Cu" "F.Mask" "F.Paste")
			(net "HP_LVC3_OCP_V3_2_FUSE_PWRGD")
		)
	)
	(footprint ""
		(layer "F.Cu")
		(at 355.2444 -386.425948 180)
		(property "Reference" "R4569"
			(at 0 0 180)
			(layer "F.SilkS")
			(hide yes)
			(effects
				(font
					(size 1.27 1.27)
				)
			)
		)
		(property "Value" ""
			(at 0 0 180)
			(layer "F.Fab")
			(effects
				(font
					(size 1.27 1.27)
				)
			)
		)
		(duplicate_pad_numbers_are_jumpers no)
		(fp_line
			(start 0.7874 0.4064)
			(end -0.7874 0.4064)
			(stroke
				(width 0.1524)
				(type default)
			)
			(layer "F.SilkS")
		)
		(fp_line
			(start 0.7874 -0.4064)
			(end 0.7874 0.4064)
			(stroke
				(width 0.1524)
				(type default)
			)
			(layer "F.SilkS")
		)
		(fp_line
			(start -0.7874 0.4064)
			(end -0.7874 -0.4064)
			(stroke
				(width 0.1524)
				(type default)
			)
			(layer "F.SilkS")
		)
		(fp_line
			(start -0.7874 -0.4064)
			(end 0.7874 -0.4064)
			(stroke
				(width 0.1524)
				(type default)
			)
			(layer "F.SilkS")
		)
		(fp_line
			(start 0.67945 0.3048)
			(end 0.120396 0.3048)
			(stroke
				(width 0.1)
				(type default)
			)
			(layer "F.Fab")
		)
		(fp_line
			(start 0.67945 -0.3048)
			(end 0.67945 0.3048)
			(stroke
				(width 0.1)
				(type default)
			)
			(layer "F.Fab")
		)
		(fp_line
			(start 0.12065 -0.2794)
			(end 0.12065 -0.3048)
			(stroke
				(width 0.1)
				(type default)
			)
			(layer "F.Fab")
		)
		(fp_line
			(start 0.12065 -0.3048)
			(end 0.67945 -0.3048)
			(stroke
				(width 0.1)
				(type default)
			)
			(layer "F.Fab")
		)
		(fp_line
			(start 0.120396 0.3048)
			(end 0.120396 0.2794)
			(stroke
				(width 0.1)
				(type default)
			)
			(layer "F.Fab")
		)
		(fp_line
			(start 0.120396 0.2794)
			(end -0.12065 0.2794)
			(stroke
				(width 0.1)
				(type default)
			)
			(layer "F.Fab")
		)
		(fp_line
			(start -0.12065 0.3048)
			(end -0.67945 0.3048)
			(stroke
				(width 0.1)
				(type default)
			)
			(layer "F.Fab")
		)
		(fp_line
			(start -0.12065 0.2794)
			(end -0.12065 0.3048)
			(stroke
				(width 0.1)
				(type default)
			)
			(layer "F.Fab")
		)
		(fp_line
			(start -0.12065 -0.2794)
			(end 0.12065 -0.2794)
			(stroke
				(width 0.1)
				(type default)
			)
			(layer "F.Fab")
		)
		(fp_line
			(start -0.12065 -0.305054)
			(end -0.12065 -0.2794)
			(stroke
				(width 0.1)
				(type default)
			)
			(layer "F.Fab")
		)
		(fp_line
			(start -0.67945 0.3048)
			(end -0.67945 -0.305054)
			(stroke
				(width 0.1)
				(type default)
			)
			(layer "F.Fab")
		)
		(fp_line
			(start -0.67945 -0.305054)
			(end -0.12065 -0.305054)
			(stroke
				(width 0.1)
				(type default)
			)
			(layer "F.Fab")
		)
		(pad "1" smd circle
			(at -0.40005 0 180)
			(size 0 0)
			(layers "F.Cu" "F.Mask" "F.Paste")
			(net "GPU_3V3IO_RSVD1")
		)
		(pad "2" smd circle
			(at 0.40005 0 180)
			(size 0 0)
			(layers "F.Cu" "F.Mask" "F.Paste")
			(net "GPU_3V3IO_RSVD1_ISO")
		)
	)
	(footprint ""
		(layer "F.Cu")
		(at 418.485828 -174.396654)
		(property "Reference" "PC187"
			(at 0 0 0)
			(layer "F.SilkS")
			(hide yes)
			(effects
				(font
					(size 1.27 1.27)
				)
			)
		)
		(property "Value" ""
			(at 0 0 0)
			(layer "F.Fab")
			(effects
				(font
					(size 1.27 1.27)
				)
			)
		)
		(duplicate_pad_numbers_are_jumpers no)
		(fp_line
			(start -0.7874 -0.4064)
			(end 0.7874 -0.4064)
			(stroke
				(width 0.1524)
				(type default)
			)
			(layer "F.SilkS")
		)
		(fp_line
			(start -0.7874 0.4064)
			(end -0.7874 -0.4064)
			(stroke
				(width 0.1524)
				(type default)
			)
			(layer "F.SilkS")
		)
		(fp_line
			(start 0.7874 -0.4064)
			(end 0.7874 0.4064)
			(stroke
				(width 0.1524)
				(type default)
			)
			(layer "F.SilkS")
		)
		(fp_line
			(start 0.7874 0.4064)
			(end -0.7874 0.4064)
			(stroke
				(width 0.1524)
				(type default)
			)
			(layer "F.SilkS")
		)
		(fp_line
			(start -0.67945 -0.305054)
			(end -0.12065 -0.305054)
			(stroke
				(width 0.1)
				(type default)
			)
			(layer "F.Fab")
		)
		(fp_line
			(start -0.67945 0.3048)
			(end -0.67945 -0.305054)
			(stroke
				(width 0.1)
				(type default)
			)
			(layer "F.Fab")
		)
		(fp_line
			(start -0.12065 -0.305054)
			(end -0.12065 -0.2794)
			(stroke
				(width 0.1)
				(type default)
			)
			(layer "F.Fab")
		)
		(fp_line
			(start -0.12065 -0.2794)
			(end 0.12065 -0.2794)
			(stroke
				(width 0.1)
				(type default)
			)
			(layer "F.Fab")
		)
		(fp_line
			(start -0.12065 0.2794)
			(end -0.12065 0.3048)
			(stroke
				(width 0.1)
				(type default)
			)
			(layer "F.Fab")
		)
		(fp_line
			(start -0.12065 0.3048)
			(end -0.67945 0.3048)
			(stroke
				(width 0.1)
				(type default)
			)
			(layer "F.Fab")
		)
		(fp_line
			(start 0.120396 0.2794)
			(end -0.12065 0.2794)
			(stroke
				(width 0.1)
				(type default)
			)
			(layer "F.Fab")
		)
		(fp_line
			(start 0.120396 0.3048)
			(end 0.120396 0.2794)
			(stroke
				(width 0.1)
				(type default)
			)
			(layer "F.Fab")
		)
		(fp_line
			(start 0.12065 -0.3048)
			(end 0.67945 -0.3048)
			(stroke
				(width 0.1)
				(type default)
			)
			(layer "F.Fab")
		)
		(fp_line
			(start 0.12065 -0.2794)
			(end 0.12065 -0.3048)
			(stroke
				(width 0.1)
				(type default)
			)
			(layer "F.Fab")
		)
		(fp_line
			(start 0.67945 -0.3048)
			(end 0.67945 0.3048)
			(stroke
				(width 0.1)
				(type default)
			)
			(layer "F.Fab")
		)
		(fp_line
			(start 0.67945 0.3048)
			(end 0.120396 0.3048)
			(stroke
				(width 0.1)
				(type default)
			)
			(layer "F.Fab")
		)
		(pad "1" smd circle
			(at -0.40005 0)
			(size 0 0)
			(layers "F.Cu" "F.Mask" "F.Paste")
			(net "PVCCINFAON_CPU0_VDD1")
		)
		(pad "2" smd circle
			(at 0.40005 0)
			(size 0 0)
			(layers "F.Cu" "F.Mask" "F.Paste")
			(net "GND")
		)
	)
	(footprint ""
		(layer "F.Cu")
		(at 254.35433 -54.844442 -90)
		(property "Reference" "R3948"
			(at 0 0 270)
			(layer "F.SilkS")
			(hide yes)
			(effects
				(font
					(size 1.27 1.27)
				)
			)
		)
		(property "Value" ""
			(at 0 0 270)
			(layer "F.Fab")
			(effects
				(font
					(size 1.27 1.27)
				)
			)
		)
		(duplicate_pad_numbers_are_jumpers no)
		(fp_line
			(start -0.7874 0.4064)
			(end -0.7874 -0.4064)
			(stroke
				(width 0.1524)
				(type default)
			)
			(layer "F.SilkS")
		)
		(fp_line
			(start 0.7874 0.4064)
			(end -0.7874 0.4064)
			(stroke
				(width 0.1524)
				(type default)
			)
			(layer "F.SilkS")
		)
		(fp_line
			(start -0.7874 -0.4064)
			(end 0.7874 -0.4064)
			(stroke
				(width 0.1524)
				(type default)
			)
			(layer "F.SilkS")
		)
		(fp_line
			(start 0.7874 -0.4064)
			(end 0.7874 0.4064)
			(stroke
				(width 0.1524)
				(type default)
			)
			(layer "F.SilkS")
		)
		(fp_line
			(start -0.67945 0.3048)
			(end -0.67945 -0.305054)
			(stroke
				(width 0.1)
				(type default)
			)
			(layer "F.Fab")
		)
		(fp_line
			(start -0.12065 0.3048)
			(end -0.67945 0.3048)
			(stroke
				(width 0.1)
				(type default)
			)
			(layer "F.Fab")
		)
		(fp_line
			(start 0.120396 0.3048)
			(end 0.120396 0.2794)
			(stroke
				(width 0.1)
				(type default)
			)
			(layer "F.Fab")
		)
		(fp_line
			(start 0.67945 0.3048)
			(end 0.120396 0.3048)
			(stroke
				(width 0.1)
				(type default)
			)
			(layer "F.Fab")
		)
		(fp_line
			(start -0.12065 0.2794)
			(end -0.12065 0.3048)
			(stroke
				(width 0.1)
				(type default)
			)
			(layer "F.Fab")
		)
		(fp_line
			(start 0.120396 0.2794)
			(end -0.12065 0.2794)
			(stroke
				(width 0.1)
				(type default)
			)
			(layer "F.Fab")
		)
		(fp_line
			(start -0.12065 -0.2794)
			(end 0.12065 -0.2794)
			(stroke
				(width 0.1)
				(type default)
			)
			(layer "F.Fab")
		)
		(fp_line
			(start 0.12065 -0.2794)
			(end 0.12065 -0.3048)
			(stroke
				(width 0.1)
				(type default)
			)
			(layer "F.Fab")
		)
		(fp_line
			(start 0.12065 -0.3048)
			(end 0.67945 -0.3048)
			(stroke
				(width 0.1)
				(type default)
			)
			(layer "F.Fab")
		)
		(fp_line
			(start 0.67945 -0.3048)
			(end 0.67945 0.3048)
			(stroke
				(width 0.1)
				(type default)
			)
			(layer "F.Fab")
		)
		(fp_line
			(start -0.67945 -0.305054)
			(end -0.12065 -0.305054)
			(stroke
				(width 0.1)
				(type default)
			)
			(layer "F.Fab")
		)
		(fp_line
			(start -0.12065 -0.305054)
			(end -0.12065 -0.2794)
			(stroke
				(width 0.1)
				(type default)
			)
			(layer "F.Fab")
		)
		(pad "1" smd circle
			(at -0.40005 0 270)
			(size 0 0)
			(layers "F.Cu" "F.Mask" "F.Paste")
			(net "P3V3_AUX")
		)
		(pad "2" smd circle
			(at 0.40005 0 270)
			(size 0 0)
			(layers "F.Cu" "F.Mask" "F.Paste")
			(net "HP_LVC3_E1S_0_HSC_PWRGD")
		)
	)
	(footprint ""
		(layer "F.Cu")
		(at 171.867322 -28.03779 90)
		(property "Reference" "PR4009"
			(at 0 0 90)
			(layer "F.SilkS")
			(hide yes)
			(effects
				(font
					(size 1.27 1.27)
				)
			)
		)
		(property "Value" ""
			(at 0 0 90)
			(layer "F.Fab")
			(effects
				(font
					(size 1.27 1.27)
				)
			)
		)
		(duplicate_pad_numbers_are_jumpers no)
		(fp_line
			(start 0.7874 -0.4064)
			(end 0.7874 0.4064)
			(stroke
				(width 0.1524)
				(type default)
			)
			(layer "F.SilkS")
		)
		(fp_line
			(start -0.7874 -0.4064)
			(end 0.7874 -0.4064)
			(stroke
				(width 0.1524)
				(type default)
			)
			(layer "F.SilkS")
		)
		(fp_line
			(start 0.7874 0.4064)
			(end -0.7874 0.4064)
			(stroke
				(width 0.1524)
				(type default)
			)
			(layer "F.SilkS")
		)
		(fp_line
			(start -0.7874 0.4064)
			(end -0.7874 -0.4064)
			(stroke
				(width 0.1524)
				(type default)
			)
			(layer "F.SilkS")
		)
		(fp_line
			(start -0.12065 -0.305054)
			(end -0.12065 -0.2794)
			(stroke
				(width 0.1)
				(type default)
			)
			(layer "F.Fab")
		)
		(fp_line
			(start -0.67945 -0.305054)
			(end -0.12065 -0.305054)
			(stroke
				(width 0.1)
				(type default)
			)
			(layer "F.Fab")
		)
		(fp_line
			(start 0.67945 -0.3048)
			(end 0.67945 0.3048)
			(stroke
				(width 0.1)
				(type default)
			)
			(layer "F.Fab")
		)
		(fp_line
			(start 0.12065 -0.3048)
			(end 0.67945 -0.3048)
			(stroke
				(width 0.1)
				(type default)
			)
			(layer "F.Fab")
		)
		(fp_line
			(start 0.12065 -0.2794)
			(end 0.12065 -0.3048)
			(stroke
				(width 0.1)
				(type default)
			)
			(layer "F.Fab")
		)
		(fp_line
			(start -0.12065 -0.2794)
			(end 0.12065 -0.2794)
			(stroke
				(width 0.1)
				(type default)
			)
			(layer "F.Fab")
		)
		(fp_line
			(start 0.120396 0.2794)
			(end -0.12065 0.2794)
			(stroke
				(width 0.1)
				(type default)
			)
			(layer "F.Fab")
		)
		(fp_line
			(start -0.12065 0.2794)
			(end -0.12065 0.3048)
			(stroke
				(width 0.1)
				(type default)
			)
			(layer "F.Fab")
		)
		(fp_line
			(start 0.67945 0.3048)
			(end 0.120396 0.3048)
			(stroke
				(width 0.1)
				(type default)
			)
			(layer "F.Fab")
		)
		(fp_line
			(start 0.120396 0.3048)
			(end 0.120396 0.2794)
			(stroke
				(width 0.1)
				(type default)
			)
			(layer "F.Fab")
		)
		(fp_line
			(start -0.12065 0.3048)
			(end -0.67945 0.3048)
			(stroke
				(width 0.1)
				(type default)
			)
			(layer "F.Fab")
		)
		(fp_line
			(start -0.67945 0.3048)
			(end -0.67945 -0.305054)
			(stroke
				(width 0.1)
				(type default)
			)
			(layer "F.Fab")
		)
		(pad "1" smd circle
			(at -0.40005 0 90)
			(size 0 0)
			(layers "F.Cu" "F.Mask" "F.Paste")
			(net "P12V_SCM_R")
		)
		(pad "2" smd circle
			(at 0.40005 0 90)
			(size 0 0)
			(layers "F.Cu" "F.Mask" "F.Paste")
			(net "P12V_SCM_OV_FB")
		)
	)
	(footprint ""
		(layer "F.Cu")
		(at 62.28588 -16.220948 -90)
		(property "Reference" "R3170"
			(at 0 0 270)
			(layer "F.SilkS")
			(hide yes)
			(effects
				(font
					(size 1.27 1.27)
				)
			)
		)
		(property "Value" ""
			(at 0 0 270)
			(layer "F.Fab")
			(effects
				(font
					(size 1.27 1.27)
				)
			)
		)
		(duplicate_pad_numbers_are_jumpers no)
		(fp_line
			(start -0.7874 0.4064)
			(end -0.7874 -0.4064)
			(stroke
				(width 0.1524)
				(type default)
			)
			(layer "F.SilkS")
		)
		(fp_line
			(start 0.7874 0.4064)
			(end -0.7874 0.4064)
			(stroke
				(width 0.1524)
				(type default)
			)
			(layer "F.SilkS")
		)
		(fp_line
			(start -0.7874 -0.4064)
			(end 0.7874 -0.4064)
			(stroke
				(width 0.1524)
				(type default)
			)
			(layer "F.SilkS")
		)
		(fp_line
			(start 0.7874 -0.4064)
			(end 0.7874 0.4064)
			(stroke
				(width 0.1524)
				(type default)
			)
			(layer "F.SilkS")
		)
		(fp_line
			(start -0.67945 0.3048)
			(end -0.67945 -0.305054)
			(stroke
				(width 0.1)
				(type default)
			)
			(layer "F.Fab")
		)
		(fp_line
			(start -0.12065 0.3048)
			(end -0.67945 0.3048)
			(stroke
				(width 0.1)
				(type default)
			)
			(layer "F.Fab")
		)
		(fp_line
			(start 0.120396 0.3048)
			(end 0.120396 0.2794)
			(stroke
				(width 0.1)
				(type default)
			)
			(layer "F.Fab")
		)
		(fp_line
			(start 0.67945 0.3048)
			(end 0.120396 0.3048)
			(stroke
				(width 0.1)
				(type default)
			)
			(layer "F.Fab")
		)
		(fp_line
			(start -0.12065 0.2794)
			(end -0.12065 0.3048)
			(stroke
				(width 0.1)
				(type default)
			)
			(layer "F.Fab")
		)
		(fp_line
			(start 0.120396 0.2794)
			(end -0.12065 0.2794)
			(stroke
				(width 0.1)
				(type default)
			)
			(layer "F.Fab")
		)
		(fp_line
			(start -0.12065 -0.2794)
			(end 0.12065 -0.2794)
			(stroke
				(width 0.1)
				(type default)
			)
			(layer "F.Fab")
		)
		(fp_line
			(start 0.12065 -0.2794)
			(end 0.12065 -0.3048)
			(stroke
				(width 0.1)
				(type default)
			)
			(layer "F.Fab")
		)
		(fp_line
			(start 0.12065 -0.3048)
			(end 0.67945 -0.3048)
			(stroke
				(width 0.1)
				(type default)
			)
			(layer "F.Fab")
		)
		(fp_line
			(start 0.67945 -0.3048)
			(end 0.67945 0.3048)
			(stroke
				(width 0.1)
				(type default)
			)
			(layer "F.Fab")
		)
		(fp_line
			(start -0.67945 -0.305054)
			(end -0.12065 -0.305054)
			(stroke
				(width 0.1)
				(type default)
			)
			(layer "F.Fab")
		)
		(fp_line
			(start -0.12065 -0.305054)
			(end -0.12065 -0.2794)
			(stroke
				(width 0.1)
				(type default)
			)
			(layer "F.Fab")
		)
		(pad "1" smd circle
			(at -0.40005 0 270)
			(size 0 0)
			(layers "F.Cu" "F.Mask" "F.Paste")
			(net "OCP_V3_2_ISO_BIF1_EN")
		)
		(pad "2" smd circle
			(at 0.40005 0 270)
			(size 0 0)
			(layers "F.Cu" "F.Mask" "F.Paste")
			(net "OCP_V3_2_BIF1_R_N")
		)
	)
	(footprint ""
		(layer "F.Cu")
		(at 214.75827 -72.641714 90)
		(property "Reference" "R1294"
			(at 0 0 90)
			(layer "F.SilkS")
			(hide yes)
			(effects
				(font
					(size 1.27 1.27)
				)
			)
		)
		(property "Value" ""
			(at 0 0 90)
			(layer "F.Fab")
			(effects
				(font
					(size 1.27 1.27)
				)
			)
		)
		(duplicate_pad_numbers_are_jumpers no)
		(fp_line
			(start 0.7874 -0.4064)
			(end 0.7874 0.4064)
			(stroke
				(width 0.1524)
				(type default)
			)
			(layer "F.SilkS")
		)
		(fp_line
			(start -0.7874 -0.4064)
			(end 0.7874 -0.4064)
			(stroke
				(width 0.1524)
				(type default)
			)
			(layer "F.SilkS")
		)
		(fp_line
			(start 0.7874 0.4064)
			(end -0.7874 0.4064)
			(stroke
				(width 0.1524)
				(type default)
			)
			(layer "F.SilkS")
		)
		(fp_line
			(start -0.7874 0.4064)
			(end -0.7874 -0.4064)
			(stroke
				(width 0.1524)
				(type default)
			)
			(layer "F.SilkS")
		)
		(fp_line
			(start -0.12065 -0.305054)
			(end -0.12065 -0.2794)
			(stroke
				(width 0.1)
				(type default)
			)
			(layer "F.Fab")
		)
		(fp_line
			(start -0.67945 -0.305054)
			(end -0.12065 -0.305054)
			(stroke
				(width 0.1)
				(type default)
			)
			(layer "F.Fab")
		)
		(fp_line
			(start 0.67945 -0.3048)
			(end 0.67945 0.3048)
			(stroke
				(width 0.1)
				(type default)
			)
			(layer "F.Fab")
		)
		(fp_line
			(start 0.12065 -0.3048)
			(end 0.67945 -0.3048)
			(stroke
				(width 0.1)
				(type default)
			)
			(layer "F.Fab")
		)
		(fp_line
			(start 0.12065 -0.2794)
			(end 0.12065 -0.3048)
			(stroke
				(width 0.1)
				(type default)
			)
			(layer "F.Fab")
		)
		(fp_line
			(start -0.12065 -0.2794)
			(end 0.12065 -0.2794)
			(stroke
				(width 0.1)
				(type default)
			)
			(layer "F.Fab")
		)
		(fp_line
			(start 0.120396 0.2794)
			(end -0.12065 0.2794)
			(stroke
				(width 0.1)
				(type default)
			)
			(layer "F.Fab")
		)
		(fp_line
			(start -0.12065 0.2794)
			(end -0.12065 0.3048)
			(stroke
				(width 0.1)
				(type default)
			)
			(layer "F.Fab")
		)
		(fp_line
			(start 0.67945 0.3048)
			(end 0.120396 0.3048)
			(stroke
				(width 0.1)
				(type default)
			)
			(layer "F.Fab")
		)
		(fp_line
			(start 0.120396 0.3048)
			(end 0.120396 0.2794)
			(stroke
				(width 0.1)
				(type default)
			)
			(layer "F.Fab")
		)
		(fp_line
			(start -0.12065 0.3048)
			(end -0.67945 0.3048)
			(stroke
				(width 0.1)
				(type default)
			)
			(layer "F.Fab")
		)
		(fp_line
			(start -0.67945 0.3048)
			(end -0.67945 -0.305054)
			(stroke
				(width 0.1)
				(type default)
			)
			(layer "F.Fab")
		)
		(pad "1" smd circle
			(at -0.40005 0 90)
			(size 0 0)
			(layers "F.Cu" "F.Mask" "F.Paste")
			(net "NCSI_BMC_TX_EN_R")
		)
		(pad "2" smd circle
			(at 0.40005 0 90)
			(size 0 0)
			(layers "F.Cu" "F.Mask" "F.Paste")
			(net "RMII_BMC_OCP_TX_EN")
		)
	)
	(footprint ""
		(layer "F.Cu")
		(at 340.713568 -402.371052 -90)
		(property "Reference" "C1554"
			(at 0 0 270)
			(layer "F.SilkS")
			(hide yes)
			(effects
				(font
					(size 1.27 1.27)
				)
			)
		)
		(property "Value" ""
			(at 0 0 270)
			(layer "F.Fab")
			(effects
				(font
					(size 1.27 1.27)
				)
			)
		)
		(duplicate_pad_numbers_are_jumpers no)
		(fp_line
			(start -0.299974 0.150114)
			(end -0.299974 -0.150114)
			(stroke
				(width 0.1)
				(type default)
			)
			(layer "F.Fab")
		)
		(fp_line
			(start 0.299974 0.150114)
			(end -0.299974 0.150114)
			(stroke
				(width 0.1)
				(type default)
			)
			(layer "F.Fab")
		)
		(fp_line
			(start -0.299974 -0.150114)
			(end 0.299974 -0.150114)
			(stroke
				(width 0.1)
				(type default)
			)
			(layer "F.Fab")
		)
		(fp_line
			(start 0.299974 -0.150114)
			(end 0.299974 0.150114)
			(stroke
				(width 0.1)
				(type default)
			)
			(layer "F.Fab")
		)
		(pad "1" smd rect
			(at -0.2667 0 270)
			(size 0.3048 0.381)
			(layers "F.Cu" "F.Mask" "F.Paste")
			(net "P5E_CPU0_PE4_TX_C_DN<12>")
		)
		(pad "2" smd rect
			(at 0.2667 0 270)
			(size 0.3048 0.381)
			(layers "F.Cu" "F.Mask" "F.Paste")
			(net "P5E_CPU0_PE4_TX_DN<12>")
		)
	)
	(footprint ""
		(layer "F.Cu")
		(at 447.557652 -17.433798 180)
		(property "Reference" "PR3788"
			(at 0 0 180)
			(layer "F.SilkS")
			(hide yes)
			(effects
				(font
					(size 1.27 1.27)
				)
			)
		)
		(property "Value" ""
			(at 0 0 180)
			(layer "F.Fab")
			(effects
				(font
					(size 1.27 1.27)
				)
			)
		)
		(duplicate_pad_numbers_are_jumpers no)
		(fp_line
			(start 0.7874 0.4064)
			(end -0.7874 0.4064)
			(stroke
				(width 0.1524)
				(type default)
			)
			(layer "F.SilkS")
		)
		(fp_line
			(start 0.7874 -0.4064)
			(end 0.7874 0.4064)
			(stroke
				(width 0.1524)
				(type default)
			)
			(layer "F.SilkS")
		)
		(fp_line
			(start -0.7874 0.4064)
			(end -0.7874 -0.4064)
			(stroke
				(width 0.1524)
				(type default)
			)
			(layer "F.SilkS")
		)
		(fp_line
			(start -0.7874 -0.4064)
			(end 0.7874 -0.4064)
			(stroke
				(width 0.1524)
				(type default)
			)
			(layer "F.SilkS")
		)
		(fp_line
			(start 0.67945 0.3048)
			(end 0.120396 0.3048)
			(stroke
				(width 0.1)
				(type default)
			)
			(layer "F.Fab")
		)
		(fp_line
			(start 0.67945 -0.3048)
			(end 0.67945 0.3048)
			(stroke
				(width 0.1)
				(type default)
			)
			(layer "F.Fab")
		)
		(fp_line
			(start 0.12065 -0.2794)
			(end 0.12065 -0.3048)
			(stroke
				(width 0.1)
				(type default)
			)
			(layer "F.Fab")
		)
		(fp_line
			(start 0.12065 -0.3048)
			(end 0.67945 -0.3048)
			(stroke
				(width 0.1)
				(type default)
			)
			(layer "F.Fab")
		)
		(fp_line
			(start 0.120396 0.3048)
			(end 0.120396 0.2794)
			(stroke
				(width 0.1)
				(type default)
			)
			(layer "F.Fab")
		)
		(fp_line
			(start 0.120396 0.2794)
			(end -0.12065 0.2794)
			(stroke
				(width 0.1)
				(type default)
			)
			(layer "F.Fab")
		)
		(fp_line
			(start -0.12065 0.3048)
			(end -0.67945 0.3048)
			(stroke
				(width 0.1)
				(type default)
			)
			(layer "F.Fab")
		)
		(fp_line
			(start -0.12065 0.2794)
			(end -0.12065 0.3048)
			(stroke
				(width 0.1)
				(type default)
			)
			(layer "F.Fab")
		)
		(fp_line
			(start -0.12065 -0.2794)
			(end 0.12065 -0.2794)
			(stroke
				(width 0.1)
				(type default)
			)
			(layer "F.Fab")
		)
		(fp_line
			(start -0.12065 -0.305054)
			(end -0.12065 -0.2794)
			(stroke
				(width 0.1)
				(type default)
			)
			(layer "F.Fab")
		)
		(fp_line
			(start -0.67945 0.3048)
			(end -0.67945 -0.305054)
			(stroke
				(width 0.1)
				(type default)
			)
			(layer "F.Fab")
		)
		(fp_line
			(start -0.67945 -0.305054)
			(end -0.12065 -0.305054)
			(stroke
				(width 0.1)
				(type default)
			)
			(layer "F.Fab")
		)
		(pad "1" smd circle
			(at -0.40005 0 180)
			(size 0 0)
			(layers "F.Cu" "F.Mask" "F.Paste")
			(net "P12V_OCP_OV_1")
		)
		(pad "2" smd circle
			(at 0.40005 0 180)
			(size 0 0)
			(layers "F.Cu" "F.Mask" "F.Paste")
			(net "GND")
		)
	)
	(footprint ""
		(layer "F.Cu")
		(at 376.888248 -361.313476 180)
		(property "Reference" "PR1335"
			(at 0 0 180)
			(layer "F.SilkS")
			(hide yes)
			(effects
				(font
					(size 1.27 1.27)
				)
			)
		)
		(property "Value" ""
			(at 0 0 180)
			(layer "F.Fab")
			(effects
				(font
					(size 1.27 1.27)
				)
			)
		)
		(duplicate_pad_numbers_are_jumpers no)
		(fp_line
			(start 0.7874 0.4064)
			(end -0.7874 0.4064)
			(stroke
				(width 0.1524)
				(type default)
			)
			(layer "F.SilkS")
		)
		(fp_line
			(start 0.7874 -0.4064)
			(end 0.7874 0.4064)
			(stroke
				(width 0.1524)
				(type default)
			)
			(layer "F.SilkS")
		)
		(fp_line
			(start -0.7874 0.4064)
			(end -0.7874 -0.4064)
			(stroke
				(width 0.1524)
				(type default)
			)
			(layer "F.SilkS")
		)
		(fp_line
			(start -0.7874 -0.4064)
			(end 0.7874 -0.4064)
			(stroke
				(width 0.1524)
				(type default)
			)
			(layer "F.SilkS")
		)
		(fp_line
			(start 0.67945 0.3048)
			(end 0.120396 0.3048)
			(stroke
				(width 0.1)
				(type default)
			)
			(layer "F.Fab")
		)
		(fp_line
			(start 0.67945 -0.3048)
			(end 0.67945 0.3048)
			(stroke
				(width 0.1)
				(type default)
			)
			(layer "F.Fab")
		)
		(fp_line
			(start 0.12065 -0.2794)
			(end 0.12065 -0.3048)
			(stroke
				(width 0.1)
				(type default)
			)
			(layer "F.Fab")
		)
		(fp_line
			(start 0.12065 -0.3048)
			(end 0.67945 -0.3048)
			(stroke
				(width 0.1)
				(type default)
			)
			(layer "F.Fab")
		)
		(fp_line
			(start 0.120396 0.3048)
			(end 0.120396 0.2794)
			(stroke
				(width 0.1)
				(type default)
			)
			(layer "F.Fab")
		)
		(fp_line
			(start 0.120396 0.2794)
			(end -0.12065 0.2794)
			(stroke
				(width 0.1)
				(type default)
			)
			(layer "F.Fab")
		)
		(fp_line
			(start -0.12065 0.3048)
			(end -0.67945 0.3048)
			(stroke
				(width 0.1)
				(type default)
			)
			(layer "F.Fab")
		)
		(fp_line
			(start -0.12065 0.2794)
			(end -0.12065 0.3048)
			(stroke
				(width 0.1)
				(type default)
			)
			(layer "F.Fab")
		)
		(fp_line
			(start -0.12065 -0.2794)
			(end 0.12065 -0.2794)
			(stroke
				(width 0.1)
				(type default)
			)
			(layer "F.Fab")
		)
		(fp_line
			(start -0.12065 -0.305054)
			(end -0.12065 -0.2794)
			(stroke
				(width 0.1)
				(type default)
			)
			(layer "F.Fab")
		)
		(fp_line
			(start -0.67945 0.3048)
			(end -0.67945 -0.305054)
			(stroke
				(width 0.1)
				(type default)
			)
			(layer "F.Fab")
		)
		(fp_line
			(start -0.67945 -0.305054)
			(end -0.12065 -0.305054)
			(stroke
				(width 0.1)
				(type default)
			)
			(layer "F.Fab")
		)
		(pad "1" smd circle
			(at -0.40005 0 180)
			(size 0 0)
			(layers "F.Cu" "F.Mask" "F.Paste")
			(net "P3V3_AUX")
		)
		(pad "2" smd circle
			(at 0.40005 0 180)
			(size 0 0)
			(layers "F.Cu" "F.Mask" "F.Paste")
			(net "PVPP_HBM_CPU0_VCC")
		)
	)
	(footprint ""
		(layer "F.Cu")
		(at 38.02888 -435.955948 180)
		(property "Reference" "R2897"
			(at 0 0 180)
			(layer "F.SilkS")
			(hide yes)
			(effects
				(font
					(size 1.27 1.27)
				)
			)
		)
		(property "Value" ""
			(at 0 0 180)
			(layer "F.Fab")
			(effects
				(font
					(size 1.27 1.27)
				)
			)
		)
		(duplicate_pad_numbers_are_jumpers no)
		(fp_line
			(start 0.7874 0.4064)
			(end -0.7874 0.4064)
			(stroke
				(width 0.1524)
				(type default)
			)
			(layer "F.SilkS")
		)
		(fp_line
			(start 0.7874 -0.4064)
			(end 0.7874 0.4064)
			(stroke
				(width 0.1524)
				(type default)
			)
			(layer "F.SilkS")
		)
		(fp_line
			(start -0.7874 0.4064)
			(end -0.7874 -0.4064)
			(stroke
				(width 0.1524)
				(type default)
			)
			(layer "F.SilkS")
		)
		(fp_line
			(start -0.7874 -0.4064)
			(end 0.7874 -0.4064)
			(stroke
				(width 0.1524)
				(type default)
			)
			(layer "F.SilkS")
		)
		(fp_line
			(start 0.67945 0.3048)
			(end 0.120396 0.3048)
			(stroke
				(width 0.1)
				(type default)
			)
			(layer "F.Fab")
		)
		(fp_line
			(start 0.67945 -0.3048)
			(end 0.67945 0.3048)
			(stroke
				(width 0.1)
				(type default)
			)
			(layer "F.Fab")
		)
		(fp_line
			(start 0.12065 -0.2794)
			(end 0.12065 -0.3048)
			(stroke
				(width 0.1)
				(type default)
			)
			(layer "F.Fab")
		)
		(fp_line
			(start 0.12065 -0.3048)
			(end 0.67945 -0.3048)
			(stroke
				(width 0.1)
				(type default)
			)
			(layer "F.Fab")
		)
		(fp_line
			(start 0.120396 0.3048)
			(end 0.120396 0.2794)
			(stroke
				(width 0.1)
				(type default)
			)
			(layer "F.Fab")
		)
		(fp_line
			(start 0.120396 0.2794)
			(end -0.12065 0.2794)
			(stroke
				(width 0.1)
				(type default)
			)
			(layer "F.Fab")
		)
		(fp_line
			(start -0.12065 0.3048)
			(end -0.67945 0.3048)
			(stroke
				(width 0.1)
				(type default)
			)
			(layer "F.Fab")
		)
		(fp_line
			(start -0.12065 0.2794)
			(end -0.12065 0.3048)
			(stroke
				(width 0.1)
				(type default)
			)
			(layer "F.Fab")
		)
		(fp_line
			(start -0.12065 -0.2794)
			(end 0.12065 -0.2794)
			(stroke
				(width 0.1)
				(type default)
			)
			(layer "F.Fab")
		)
		(fp_line
			(start -0.12065 -0.305054)
			(end -0.12065 -0.2794)
			(stroke
				(width 0.1)
				(type default)
			)
			(layer "F.Fab")
		)
		(fp_line
			(start -0.67945 0.3048)
			(end -0.67945 -0.305054)
			(stroke
				(width 0.1)
				(type default)
			)
			(layer "F.Fab")
		)
		(fp_line
			(start -0.67945 -0.305054)
			(end -0.12065 -0.305054)
			(stroke
				(width 0.1)
				(type default)
			)
			(layer "F.Fab")
		)
		(pad "1" smd circle
			(at -0.40005 0 180)
			(size 0 0)
			(layers "F.Cu" "F.Mask" "F.Paste")
			(net "SMB_1_BMC_GPU_BUF_R_SCL")
		)
		(pad "2" smd circle
			(at 0.40005 0 180)
			(size 0 0)
			(layers "F.Cu" "F.Mask" "F.Paste")
			(net "SMB_1_BMC_GPU_BUF_SCL")
		)
	)
	(footprint ""
		(layer "F.Cu")
		(at 164.52215 -418.514276 90)
		(property "Reference" "R2669"
			(at 0 0 90)
			(layer "F.SilkS")
			(hide yes)
			(effects
				(font
					(size 1.27 1.27)
				)
			)
		)
		(property "Value" ""
			(at 0 0 90)
			(layer "F.Fab")
			(effects
				(font
					(size 1.27 1.27)
				)
			)
		)
		(duplicate_pad_numbers_are_jumpers no)
		(fp_line
			(start 0.7874 -0.4064)
			(end 0.7874 0.4064)
			(stroke
				(width 0.1524)
				(type default)
			)
			(layer "F.SilkS")
		)
		(fp_line
			(start -0.7874 -0.4064)
			(end 0.7874 -0.4064)
			(stroke
				(width 0.1524)
				(type default)
			)
			(layer "F.SilkS")
		)
		(fp_line
			(start 0.7874 0.4064)
			(end -0.7874 0.4064)
			(stroke
				(width 0.1524)
				(type default)
			)
			(layer "F.SilkS")
		)
		(fp_line
			(start -0.7874 0.4064)
			(end -0.7874 -0.4064)
			(stroke
				(width 0.1524)
				(type default)
			)
			(layer "F.SilkS")
		)
		(fp_line
			(start -0.12065 -0.305054)
			(end -0.12065 -0.2794)
			(stroke
				(width 0.1)
				(type default)
			)
			(layer "F.Fab")
		)
		(fp_line
			(start -0.67945 -0.305054)
			(end -0.12065 -0.305054)
			(stroke
				(width 0.1)
				(type default)
			)
			(layer "F.Fab")
		)
		(fp_line
			(start 0.67945 -0.3048)
			(end 0.67945 0.3048)
			(stroke
				(width 0.1)
				(type default)
			)
			(layer "F.Fab")
		)
		(fp_line
			(start 0.12065 -0.3048)
			(end 0.67945 -0.3048)
			(stroke
				(width 0.1)
				(type default)
			)
			(layer "F.Fab")
		)
		(fp_line
			(start 0.12065 -0.2794)
			(end 0.12065 -0.3048)
			(stroke
				(width 0.1)
				(type default)
			)
			(layer "F.Fab")
		)
		(fp_line
			(start -0.12065 -0.2794)
			(end 0.12065 -0.2794)
			(stroke
				(width 0.1)
				(type default)
			)
			(layer "F.Fab")
		)
		(fp_line
			(start 0.120396 0.2794)
			(end -0.12065 0.2794)
			(stroke
				(width 0.1)
				(type default)
			)
			(layer "F.Fab")
		)
		(fp_line
			(start -0.12065 0.2794)
			(end -0.12065 0.3048)
			(stroke
				(width 0.1)
				(type default)
			)
			(layer "F.Fab")
		)
		(fp_line
			(start 0.67945 0.3048)
			(end 0.120396 0.3048)
			(stroke
				(width 0.1)
				(type default)
			)
			(layer "F.Fab")
		)
		(fp_line
			(start 0.120396 0.3048)
			(end 0.120396 0.2794)
			(stroke
				(width 0.1)
				(type default)
			)
			(layer "F.Fab")
		)
		(fp_line
			(start -0.12065 0.3048)
			(end -0.67945 0.3048)
			(stroke
				(width 0.1)
				(type default)
			)
			(layer "F.Fab")
		)
		(fp_line
			(start -0.67945 0.3048)
			(end -0.67945 -0.305054)
			(stroke
				(width 0.1)
				(type default)
			)
			(layer "F.Fab")
		)
		(pad "1" smd circle
			(at -0.40005 0 90)
			(size 0 0)
			(layers "F.Cu" "F.Mask" "F.Paste")
			(net "P3V3_AUX")
		)
		(pad "2" smd circle
			(at 0.40005 0 90)
			(size 0 0)
			(layers "F.Cu" "F.Mask" "F.Paste")
			(net "SMB_BMC_SWB_BUF_R_SDA")
		)
	)
	(footprint ""
		(layer "F.Cu")
		(at 424.204892 -379.313948)
		(property "Reference" "R2919"
			(at 0 0 0)
			(layer "F.SilkS")
			(hide yes)
			(effects
				(font
					(size 1.27 1.27)
				)
			)
		)
		(property "Value" ""
			(at 0 0 0)
			(layer "F.Fab")
			(effects
				(font
					(size 1.27 1.27)
				)
			)
		)
		(duplicate_pad_numbers_are_jumpers no)
		(fp_line
			(start -0.7874 -0.4064)
			(end 0.7874 -0.4064)
			(stroke
				(width 0.1524)
				(type default)
			)
			(layer "F.SilkS")
		)
		(fp_line
			(start -0.7874 0.4064)
			(end -0.7874 -0.4064)
			(stroke
				(width 0.1524)
				(type default)
			)
			(layer "F.SilkS")
		)
		(fp_line
			(start 0.7874 -0.4064)
			(end 0.7874 0.4064)
			(stroke
				(width 0.1524)
				(type default)
			)
			(layer "F.SilkS")
		)
		(fp_line
			(start 0.7874 0.4064)
			(end -0.7874 0.4064)
			(stroke
				(width 0.1524)
				(type default)
			)
			(layer "F.SilkS")
		)
		(fp_line
			(start -0.67945 -0.305054)
			(end -0.12065 -0.305054)
			(stroke
				(width 0.1)
				(type default)
			)
			(layer "F.Fab")
		)
		(fp_line
			(start -0.67945 0.3048)
			(end -0.67945 -0.305054)
			(stroke
				(width 0.1)
				(type default)
			)
			(layer "F.Fab")
		)
		(fp_line
			(start -0.12065 -0.305054)
			(end -0.12065 -0.2794)
			(stroke
				(width 0.1)
				(type default)
			)
			(layer "F.Fab")
		)
		(fp_line
			(start -0.12065 -0.2794)
			(end 0.12065 -0.2794)
			(stroke
				(width 0.1)
				(type default)
			)
			(layer "F.Fab")
		)
		(fp_line
			(start -0.12065 0.2794)
			(end -0.12065 0.3048)
			(stroke
				(width 0.1)
				(type default)
			)
			(layer "F.Fab")
		)
		(fp_line
			(start -0.12065 0.3048)
			(end -0.67945 0.3048)
			(stroke
				(width 0.1)
				(type default)
			)
			(layer "F.Fab")
		)
		(fp_line
			(start 0.120396 0.2794)
			(end -0.12065 0.2794)
			(stroke
				(width 0.1)
				(type default)
			)
			(layer "F.Fab")
		)
		(fp_line
			(start 0.120396 0.3048)
			(end 0.120396 0.2794)
			(stroke
				(width 0.1)
				(type default)
			)
			(layer "F.Fab")
		)
		(fp_line
			(start 0.12065 -0.3048)
			(end 0.67945 -0.3048)
			(stroke
				(width 0.1)
				(type default)
			)
			(layer "F.Fab")
		)
		(fp_line
			(start 0.12065 -0.2794)
			(end 0.12065 -0.3048)
			(stroke
				(width 0.1)
				(type default)
			)
			(layer "F.Fab")
		)
		(fp_line
			(start 0.67945 -0.3048)
			(end 0.67945 0.3048)
			(stroke
				(width 0.1)
				(type default)
			)
			(layer "F.Fab")
		)
		(fp_line
			(start 0.67945 0.3048)
			(end 0.120396 0.3048)
			(stroke
				(width 0.1)
				(type default)
			)
			(layer "F.Fab")
		)
		(pad "1" smd circle
			(at -0.40005 0)
			(size 0 0)
			(layers "F.Cu" "F.Mask" "F.Paste")
			(net "P3V3_AUX")
		)
		(pad "2" smd circle
			(at 0.40005 0)
			(size 0 0)
			(layers "F.Cu" "F.Mask" "F.Paste")
			(net "RST_BMC_FROM_SWB_ISO_N")
		)
	)
	(footprint ""
		(layer "F.Cu")
		(at 165.301676 -131.980178 -90)
		(property "Reference" "R1654"
			(at 0 0 270)
			(layer "F.SilkS")
			(hide yes)
			(effects
				(font
					(size 1.27 1.27)
				)
			)
		)
		(property "Value" ""
			(at 0 0 270)
			(layer "F.Fab")
			(effects
				(font
					(size 1.27 1.27)
				)
			)
		)
		(duplicate_pad_numbers_are_jumpers no)
		(fp_line
			(start -0.7874 0.4064)
			(end -0.7874 -0.4064)
			(stroke
				(width 0.1524)
				(type default)
			)
			(layer "F.SilkS")
		)
		(fp_line
			(start 0.7874 0.4064)
			(end -0.7874 0.4064)
			(stroke
				(width 0.1524)
				(type default)
			)
			(layer "F.SilkS")
		)
		(fp_line
			(start -0.7874 -0.4064)
			(end 0.7874 -0.4064)
			(stroke
				(width 0.1524)
				(type default)
			)
			(layer "F.SilkS")
		)
		(fp_line
			(start 0.7874 -0.4064)
			(end 0.7874 0.4064)
			(stroke
				(width 0.1524)
				(type default)
			)
			(layer "F.SilkS")
		)
		(fp_line
			(start -0.67945 0.3048)
			(end -0.67945 -0.305054)
			(stroke
				(width 0.1)
				(type default)
			)
			(layer "F.Fab")
		)
		(fp_line
			(start -0.12065 0.3048)
			(end -0.67945 0.3048)
			(stroke
				(width 0.1)
				(type default)
			)
			(layer "F.Fab")
		)
		(fp_line
			(start 0.120396 0.3048)
			(end 0.120396 0.2794)
			(stroke
				(width 0.1)
				(type default)
			)
			(layer "F.Fab")
		)
		(fp_line
			(start 0.67945 0.3048)
			(end 0.120396 0.3048)
			(stroke
				(width 0.1)
				(type default)
			)
			(layer "F.Fab")
		)
		(fp_line
			(start -0.12065 0.2794)
			(end -0.12065 0.3048)
			(stroke
				(width 0.1)
				(type default)
			)
			(layer "F.Fab")
		)
		(fp_line
			(start 0.120396 0.2794)
			(end -0.12065 0.2794)
			(stroke
				(width 0.1)
				(type default)
			)
			(layer "F.Fab")
		)
		(fp_line
			(start -0.12065 -0.2794)
			(end 0.12065 -0.2794)
			(stroke
				(width 0.1)
				(type default)
			)
			(layer "F.Fab")
		)
		(fp_line
			(start 0.12065 -0.2794)
			(end 0.12065 -0.3048)
			(stroke
				(width 0.1)
				(type default)
			)
			(layer "F.Fab")
		)
		(fp_line
			(start 0.12065 -0.3048)
			(end 0.67945 -0.3048)
			(stroke
				(width 0.1)
				(type default)
			)
			(layer "F.Fab")
		)
		(fp_line
			(start 0.67945 -0.3048)
			(end 0.67945 0.3048)
			(stroke
				(width 0.1)
				(type default)
			)
			(layer "F.Fab")
		)
		(fp_line
			(start -0.67945 -0.305054)
			(end -0.12065 -0.305054)
			(stroke
				(width 0.1)
				(type default)
			)
			(layer "F.Fab")
		)
		(fp_line
			(start -0.12065 -0.305054)
			(end -0.12065 -0.2794)
			(stroke
				(width 0.1)
				(type default)
			)
			(layer "F.Fab")
		)
		(pad "1" smd circle
			(at -0.40005 0 270)
			(size 0 0)
			(layers "F.Cu" "F.Mask" "F.Paste")
			(net "VR_P5V_EN_D_R")
		)
		(pad "2" smd circle
			(at 0.40005 0 270)
			(size 0 0)
			(layers "F.Cu" "F.Mask" "F.Paste")
			(net "VR_P5V_EN_D_R1")
		)
	)
	(footprint ""
		(layer "F.Cu")
		(at 205.397608 -400.759422)
		(property "Reference" "PR3919"
			(at 0 0 0)
			(layer "F.SilkS")
			(hide yes)
			(effects
				(font
					(size 1.27 1.27)
				)
			)
		)
		(property "Value" ""
			(at 0 0 0)
			(layer "F.Fab")
			(effects
				(font
					(size 1.27 1.27)
				)
			)
		)
		(duplicate_pad_numbers_are_jumpers no)
		(fp_line
			(start -0.7874 -0.4064)
			(end 0.7874 -0.4064)
			(stroke
				(width 0.1524)
				(type default)
			)
			(layer "F.SilkS")
		)
		(fp_line
			(start -0.7874 0.4064)
			(end -0.7874 -0.4064)
			(stroke
				(width 0.1524)
				(type default)
			)
			(layer "F.SilkS")
		)
		(fp_line
			(start 0.7874 -0.4064)
			(end 0.7874 0.4064)
			(stroke
				(width 0.1524)
				(type default)
			)
			(layer "F.SilkS")
		)
		(fp_line
			(start 0.7874 0.4064)
			(end -0.7874 0.4064)
			(stroke
				(width 0.1524)
				(type default)
			)
			(layer "F.SilkS")
		)
		(fp_line
			(start -0.67945 -0.305054)
			(end -0.12065 -0.305054)
			(stroke
				(width 0.1)
				(type default)
			)
			(layer "F.Fab")
		)
		(fp_line
			(start -0.67945 0.3048)
			(end -0.67945 -0.305054)
			(stroke
				(width 0.1)
				(type default)
			)
			(layer "F.Fab")
		)
		(fp_line
			(start -0.12065 -0.305054)
			(end -0.12065 -0.2794)
			(stroke
				(width 0.1)
				(type default)
			)
			(layer "F.Fab")
		)
		(fp_line
			(start -0.12065 -0.2794)
			(end 0.12065 -0.2794)
			(stroke
				(width 0.1)
				(type default)
			)
			(layer "F.Fab")
		)
		(fp_line
			(start -0.12065 0.2794)
			(end -0.12065 0.3048)
			(stroke
				(width 0.1)
				(type default)
			)
			(layer "F.Fab")
		)
		(fp_line
			(start -0.12065 0.3048)
			(end -0.67945 0.3048)
			(stroke
				(width 0.1)
				(type default)
			)
			(layer "F.Fab")
		)
		(fp_line
			(start 0.120396 0.2794)
			(end -0.12065 0.2794)
			(stroke
				(width 0.1)
				(type default)
			)
			(layer "F.Fab")
		)
		(fp_line
			(start 0.120396 0.3048)
			(end 0.120396 0.2794)
			(stroke
				(width 0.1)
				(type default)
			)
			(layer "F.Fab")
		)
		(fp_line
			(start 0.12065 -0.3048)
			(end 0.67945 -0.3048)
			(stroke
				(width 0.1)
				(type default)
			)
			(layer "F.Fab")
		)
		(fp_line
			(start 0.12065 -0.2794)
			(end 0.12065 -0.3048)
			(stroke
				(width 0.1)
				(type default)
			)
			(layer "F.Fab")
		)
		(fp_line
			(start 0.67945 -0.3048)
			(end 0.67945 0.3048)
			(stroke
				(width 0.1)
				(type default)
			)
			(layer "F.Fab")
		)
		(fp_line
			(start 0.67945 0.3048)
			(end 0.120396 0.3048)
			(stroke
				(width 0.1)
				(type default)
			)
			(layer "F.Fab")
		)
		(pad "1" smd circle
			(at -0.40005 0)
			(size 0 0)
			(layers "F.Cu" "F.Mask" "F.Paste")
			(net "HSC_D_OC_1")
		)
		(pad "2" smd circle
			(at 0.40005 0)
			(size 0 0)
			(layers "F.Cu" "F.Mask" "F.Paste")
			(net "HSC_D_OC_R")
		)
	)
	(footprint ""
		(layer "F.Cu")
		(at 261.88035 -75.61834 90)
		(property "Reference" "PC1221"
			(at 0 0 90)
			(layer "F.SilkS")
			(hide yes)
			(effects
				(font
					(size 1.27 1.27)
				)
			)
		)
		(property "Value" ""
			(at 0 0 90)
			(layer "F.Fab")
			(effects
				(font
					(size 1.27 1.27)
				)
			)
		)
		(duplicate_pad_numbers_are_jumpers no)
		(fp_line
			(start 0.7874 -0.4064)
			(end 0.7874 0.4064)
			(stroke
				(width 0.1524)
				(type default)
			)
			(layer "F.SilkS")
		)
		(fp_line
			(start -0.7874 -0.4064)
			(end 0.7874 -0.4064)
			(stroke
				(width 0.1524)
				(type default)
			)
			(layer "F.SilkS")
		)
		(fp_line
			(start 0.7874 0.4064)
			(end -0.7874 0.4064)
			(stroke
				(width 0.1524)
				(type default)
			)
			(layer "F.SilkS")
		)
		(fp_line
			(start -0.7874 0.4064)
			(end -0.7874 -0.4064)
			(stroke
				(width 0.1524)
				(type default)
			)
			(layer "F.SilkS")
		)
		(fp_line
			(start -0.12065 -0.305054)
			(end -0.12065 -0.2794)
			(stroke
				(width 0.1)
				(type default)
			)
			(layer "F.Fab")
		)
		(fp_line
			(start -0.67945 -0.305054)
			(end -0.12065 -0.305054)
			(stroke
				(width 0.1)
				(type default)
			)
			(layer "F.Fab")
		)
		(fp_line
			(start 0.67945 -0.3048)
			(end 0.67945 0.3048)
			(stroke
				(width 0.1)
				(type default)
			)
			(layer "F.Fab")
		)
		(fp_line
			(start 0.12065 -0.3048)
			(end 0.67945 -0.3048)
			(stroke
				(width 0.1)
				(type default)
			)
			(layer "F.Fab")
		)
		(fp_line
			(start 0.12065 -0.2794)
			(end 0.12065 -0.3048)
			(stroke
				(width 0.1)
				(type default)
			)
			(layer "F.Fab")
		)
		(fp_line
			(start -0.12065 -0.2794)
			(end 0.12065 -0.2794)
			(stroke
				(width 0.1)
				(type default)
			)
			(layer "F.Fab")
		)
		(fp_line
			(start 0.120396 0.2794)
			(end -0.12065 0.2794)
			(stroke
				(width 0.1)
				(type default)
			)
			(layer "F.Fab")
		)
		(fp_line
			(start -0.12065 0.2794)
			(end -0.12065 0.3048)
			(stroke
				(width 0.1)
				(type default)
			)
			(layer "F.Fab")
		)
		(fp_line
			(start 0.67945 0.3048)
			(end 0.120396 0.3048)
			(stroke
				(width 0.1)
				(type default)
			)
			(layer "F.Fab")
		)
		(fp_line
			(start 0.120396 0.3048)
			(end 0.120396 0.2794)
			(stroke
				(width 0.1)
				(type default)
			)
			(layer "F.Fab")
		)
		(fp_line
			(start -0.12065 0.3048)
			(end -0.67945 0.3048)
			(stroke
				(width 0.1)
				(type default)
			)
			(layer "F.Fab")
		)
		(fp_line
			(start -0.67945 0.3048)
			(end -0.67945 -0.305054)
			(stroke
				(width 0.1)
				(type default)
			)
			(layer "F.Fab")
		)
		(pad "1" smd circle
			(at -0.40005 0 90)
			(size 0 0)
			(layers "F.Cu" "F.Mask" "F.Paste")
			(net "P1V05_PCH_AUX_REF")
		)
		(pad "2" smd circle
			(at 0.40005 0 90)
			(size 0 0)
			(layers "F.Cu" "F.Mask" "F.Paste")
			(net "SH_P1V05_PCH_AUX_N")
		)
	)
	(footprint ""
		(layer "F.Cu")
		(at 105.312464 -238.162592 90)
		(property "Reference" "C310"
			(at 0 0 90)
			(layer "F.SilkS")
			(hide yes)
			(effects
				(font
					(size 1.27 1.27)
				)
			)
		)
		(property "Value" ""
			(at 0 0 90)
			(layer "F.Fab")
			(effects
				(font
					(size 1.27 1.27)
				)
			)
		)
		(duplicate_pad_numbers_are_jumpers no)
		(fp_line
			(start 0.7874 -0.4064)
			(end 0.7874 0.4064)
			(stroke
				(width 0.1524)
				(type default)
			)
			(layer "F.SilkS")
		)
		(fp_line
			(start -0.7874 -0.4064)
			(end 0.7874 -0.4064)
			(stroke
				(width 0.1524)
				(type default)
			)
			(layer "F.SilkS")
		)
		(fp_line
			(start 0.7874 0.4064)
			(end -0.7874 0.4064)
			(stroke
				(width 0.1524)
				(type default)
			)
			(layer "F.SilkS")
		)
		(fp_line
			(start -0.7874 0.4064)
			(end -0.7874 -0.4064)
			(stroke
				(width 0.1524)
				(type default)
			)
			(layer "F.SilkS")
		)
		(fp_line
			(start -0.12065 -0.305054)
			(end -0.12065 -0.2794)
			(stroke
				(width 0.1)
				(type default)
			)
			(layer "F.Fab")
		)
		(fp_line
			(start -0.67945 -0.305054)
			(end -0.12065 -0.305054)
			(stroke
				(width 0.1)
				(type default)
			)
			(layer "F.Fab")
		)
		(fp_line
			(start 0.67945 -0.3048)
			(end 0.67945 0.3048)
			(stroke
				(width 0.1)
				(type default)
			)
			(layer "F.Fab")
		)
		(fp_line
			(start 0.12065 -0.3048)
			(end 0.67945 -0.3048)
			(stroke
				(width 0.1)
				(type default)
			)
			(layer "F.Fab")
		)
		(fp_line
			(start 0.12065 -0.2794)
			(end 0.12065 -0.3048)
			(stroke
				(width 0.1)
				(type default)
			)
			(layer "F.Fab")
		)
		(fp_line
			(start -0.12065 -0.2794)
			(end 0.12065 -0.2794)
			(stroke
				(width 0.1)
				(type default)
			)
			(layer "F.Fab")
		)
		(fp_line
			(start 0.120396 0.2794)
			(end -0.12065 0.2794)
			(stroke
				(width 0.1)
				(type default)
			)
			(layer "F.Fab")
		)
		(fp_line
			(start -0.12065 0.2794)
			(end -0.12065 0.3048)
			(stroke
				(width 0.1)
				(type default)
			)
			(layer "F.Fab")
		)
		(fp_line
			(start 0.67945 0.3048)
			(end 0.120396 0.3048)
			(stroke
				(width 0.1)
				(type default)
			)
			(layer "F.Fab")
		)
		(fp_line
			(start 0.120396 0.3048)
			(end 0.120396 0.2794)
			(stroke
				(width 0.1)
				(type default)
			)
			(layer "F.Fab")
		)
		(fp_line
			(start -0.12065 0.3048)
			(end -0.67945 0.3048)
			(stroke
				(width 0.1)
				(type default)
			)
			(layer "F.Fab")
		)
		(fp_line
			(start -0.67945 0.3048)
			(end -0.67945 -0.305054)
			(stroke
				(width 0.1)
				(type default)
			)
			(layer "F.Fab")
		)
		(pad "1" smd circle
			(at -0.40005 0 90)
			(size 0 0)
			(layers "F.Cu" "F.Mask" "F.Paste")
			(net "PVNN_MAIN_CPU1")
		)
		(pad "2" smd circle
			(at 0.40005 0 90)
			(size 0 0)
			(layers "F.Cu" "F.Mask" "F.Paste")
			(net "GND")
		)
	)
	(footprint ""
		(layer "F.Cu")
		(at 250.65482 2.921 180)
		(property "Reference" "J85"
			(at -4.26085 -1.143 90)
			(unlocked yes)
			(layer "F.SilkS")
			(effects
				(font
					(size 0.7874 0.5842)
					(thickness 0.1524)
				)
				(justify left)
			)
		)
		(property "Value" ""
			(at 0 0 180)
			(layer "F.Fab")
			(effects
				(font
					(size 1.27 1.27)
				)
			)
		)
		(duplicate_pad_numbers_are_jumpers no)
		(fp_line
			(start 1.2192 2.1082)
			(end -1.2192 2.1082)
			(stroke
				(width 0.1524)
				(type default)
			)
			(layer "F.SilkS")
		)
		(fp_line
			(start 1.2192 -2.1082)
			(end 1.2192 2.1082)
			(stroke
				(width 0.1524)
				(type default)
			)
			(layer "F.SilkS")
		)
		(fp_line
			(start -1.2192 2.1082)
			(end -1.2192 -2.1082)
			(stroke
				(width 0.1524)
				(type default)
			)
			(layer "F.SilkS")
		)
		(fp_line
			(start -1.2192 -2.1082)
			(end 1.2192 -2.1082)
			(stroke
				(width 0.1524)
				(type default)
			)
			(layer "F.SilkS")
		)
		(pad "" np_thru_hole circle
			(at -2.8829 -1.27 90)
			(size 1.0414 1.0414)
			(drill 1.0414)
			(layers "*.Cu" "*.Mask")
			(clearance 0.381)
			(thermal_gap 0.381)
		)
		(pad "" np_thru_hole circle
			(at -2.8829 1.27 90)
			(size 1.0414 1.0414)
			(drill 1.0414)
			(layers "*.Cu" "*.Mask")
			(clearance 0.381)
			(thermal_gap 0.381)
		)
		(pad "" np_thru_hole circle
			(at 3.4671 -1.27 90)
			(size 1.0414 1.0414)
			(drill 1.0414)
			(layers "*.Cu" "*.Mask")
			(clearance 0.381)
			(thermal_gap 0.381)
		)
		(pad "" np_thru_hole circle
			(at 3.4671 1.27 90)
			(size 1.0414 1.0414)
			(drill 1.0414)
			(layers "*.Cu" "*.Mask")
			(clearance 0.381)
			(thermal_gap 0.381)
		)
		(pad "1" smd rect
			(at 0.8255 -0.249936 90)
			(size 0.3048 0.508)
			(layers "F.Cu" "F.Mask" "F.Paste")
			(net "DELTA_L_85_10INCH_IN3_DN")
		)
		(pad "2" smd rect
			(at 0.8255 0.249936 90)
			(size 0.3048 0.508)
			(layers "F.Cu" "F.Mask" "F.Paste")
			(net "DELTA_L_85_10INCH_IN3_DP")
		)
		(pad "3" smd circle
			(at 0 0 180)
			(size 0 0)
			(layers "F.Cu" "F.Mask" "F.Paste")
			(net "DELTA_L_GND_1")
		)
		(zone
			(layer "F.Cu")
			(hatch none 0.5)
			(connect_pads
				(clearance 0)
			)
			(min_thickness 0.25)
			(keepout
				(tracks not_allowed)
				(vias allowed)
				(pads allowed)
				(copperpour not_allowed)
				(footprints allowed)
			)
			(placement
				(enabled no)
				(sheetname "")
			)
			(fill
				(thermal_gap 0.5)
				(thermal_bridge_width 0.5)
				(island_removal_mode 0)
			)
			(polygon
				(pts
					(xy 249.53722 3.46964) (xy 249.53722 3.374136) (xy 250.13412 3.374136) (xy 250.13412 2.967736)
					(xy 249.53722 2.967736) (xy 249.53722 2.874264) (xy 250.13412 2.874264) (xy 250.13412 2.467864)
					(xy 249.53722 2.467864) (xy 249.53722 2.37236) (xy 250.23572 2.37236) (xy 250.23572 3.46964)
				)
			)
		)
		(zone
			(layers "F.Cu" "B.Cu" "In1.Cu" "In2.Cu" "In3.Cu" "In4.Cu" "In5.Cu" "In6.Cu"
				"In7.Cu" "In8.Cu" "In9.Cu" "In10.Cu" "In11.Cu" "In12.Cu" "In13.Cu" "In14.Cu"
				"In15.Cu" "In16.Cu"
			)
			(hatch none 0.5)
			(connect_pads
				(clearance 0)
			)
			(min_thickness 0.25)
			(keepout
				(tracks not_allowed)
				(vias allowed)
				(pads allowed)
				(copperpour not_allowed)
				(footprints allowed)
			)
			(placement
				(enabled no)
				(sheetname "")
			)
			(fill
				(thermal_gap 0.5)
				(thermal_bridge_width 0.5)
				(island_removal_mode 0)
			)
			(polygon
				(pts
					(arc
						(start 248.11482 1.651)
						(mid 246.26062 1.651)
						(end 248.11482 1.651)
					)
				)
			)
		)
		(zone
			(layers "F.Cu" "B.Cu" "In1.Cu" "In2.Cu" "In3.Cu" "In4.Cu" "In5.Cu" "In6.Cu"
				"In7.Cu" "In8.Cu" "In9.Cu" "In10.Cu" "In11.Cu" "In12.Cu" "In13.Cu" "In14.Cu"
				"In15.Cu" "In16.Cu"
			)
			(hatch none 0.5)
			(connect_pads
				(clearance 0)
			)
			(min_thickness 0.25)
			(keepout
				(tracks not_allowed)
				(vias allowed)
				(pads allowed)
				(copperpour not_allowed)
				(footprints allowed)
			)
			(placement
				(enabled no)
				(sheetname "")
			)
			(fill
				(thermal_gap 0.5)
				(thermal_bridge_width 0.5)
				(island_removal_mode 0)
			)
			(polygon
				(pts
					(arc
						(start 248.11482 4.191)
						(mid 246.26062 4.191)
						(end 248.11482 4.191)
					)
				)
			)
		)
		(zone
			(layers "F.Cu" "B.Cu" "In1.Cu" "In2.Cu" "In3.Cu" "In4.Cu" "In5.Cu" "In6.Cu"
				"In7.Cu" "In8.Cu" "In9.Cu" "In10.Cu" "In11.Cu" "In12.Cu" "In13.Cu" "In14.Cu"
				"In15.Cu" "In16.Cu"
			)
			(hatch none 0.5)
			(connect_pads
				(clearance 0)
			)
			(min_thickness 0.25)
			(keepout
				(tracks not_allowed)
				(vias allowed)
				(pads allowed)
				(copperpour not_allowed)
				(footprints allowed)
			)
			(placement
				(enabled no)
				(sheetname "")
			)
			(fill
				(thermal_gap 0.5)
				(thermal_bridge_width 0.5)
				(island_removal_mode 0)
			)
			(polygon
				(pts
					(arc
						(start 254.46482 1.651)
						(mid 252.61062 1.651)
						(end 254.46482 1.651)
					)
				)
			)
		)
		(zone
			(layers "F.Cu" "B.Cu" "In1.Cu" "In2.Cu" "In3.Cu" "In4.Cu" "In5.Cu" "In6.Cu"
				"In7.Cu" "In8.Cu" "In9.Cu" "In10.Cu" "In11.Cu" "In12.Cu" "In13.Cu" "In14.Cu"
				"In15.Cu" "In16.Cu"
			)
			(hatch none 0.5)
			(connect_pads
				(clearance 0)
			)
			(min_thickness 0.25)
			(keepout
				(tracks not_allowed)
				(vias allowed)
				(pads allowed)
				(copperpour not_allowed)
				(footprints allowed)
			)
			(placement
				(enabled no)
				(sheetname "")
			)
			(fill
				(thermal_gap 0.5)
				(thermal_bridge_width 0.5)
				(island_removal_mode 0)
			)
			(polygon
				(pts
					(arc
						(start 254.46482 4.191)
						(mid 252.61062 4.191)
						(end 254.46482 4.191)
					)
				)
			)
		)
	)
	(footprint ""
		(layer "F.Cu")
		(at 449.38442 -77.829918 90)
		(property "Reference" "PC569"
			(at 0 0 90)
			(layer "F.SilkS")
			(hide yes)
			(effects
				(font
					(size 1.27 1.27)
				)
			)
		)
		(property "Value" ""
			(at 0 0 90)
			(layer "F.Fab")
			(effects
				(font
					(size 1.27 1.27)
				)
			)
		)
		(duplicate_pad_numbers_are_jumpers no)
		(fp_line
			(start 0.7874 -0.4064)
			(end 0.7874 0.4064)
			(stroke
				(width 0.1524)
				(type default)
			)
			(layer "F.SilkS")
		)
		(fp_line
			(start -0.7874 -0.4064)
			(end 0.7874 -0.4064)
			(stroke
				(width 0.1524)
				(type default)
			)
			(layer "F.SilkS")
		)
		(fp_line
			(start 0.7874 0.4064)
			(end -0.7874 0.4064)
			(stroke
				(width 0.1524)
				(type default)
			)
			(layer "F.SilkS")
		)
		(fp_line
			(start -0.7874 0.4064)
			(end -0.7874 -0.4064)
			(stroke
				(width 0.1524)
				(type default)
			)
			(layer "F.SilkS")
		)
		(fp_line
			(start -0.12065 -0.305054)
			(end -0.12065 -0.2794)
			(stroke
				(width 0.1)
				(type default)
			)
			(layer "F.Fab")
		)
		(fp_line
			(start -0.67945 -0.305054)
			(end -0.12065 -0.305054)
			(stroke
				(width 0.1)
				(type default)
			)
			(layer "F.Fab")
		)
		(fp_line
			(start 0.67945 -0.3048)
			(end 0.67945 0.3048)
			(stroke
				(width 0.1)
				(type default)
			)
			(layer "F.Fab")
		)
		(fp_line
			(start 0.12065 -0.3048)
			(end 0.67945 -0.3048)
			(stroke
				(width 0.1)
				(type default)
			)
			(layer "F.Fab")
		)
		(fp_line
			(start 0.12065 -0.2794)
			(end 0.12065 -0.3048)
			(stroke
				(width 0.1)
				(type default)
			)
			(layer "F.Fab")
		)
		(fp_line
			(start -0.12065 -0.2794)
			(end 0.12065 -0.2794)
			(stroke
				(width 0.1)
				(type default)
			)
			(layer "F.Fab")
		)
		(fp_line
			(start 0.120396 0.2794)
			(end -0.12065 0.2794)
			(stroke
				(width 0.1)
				(type default)
			)
			(layer "F.Fab")
		)
		(fp_line
			(start -0.12065 0.2794)
			(end -0.12065 0.3048)
			(stroke
				(width 0.1)
				(type default)
			)
			(layer "F.Fab")
		)
		(fp_line
			(start 0.67945 0.3048)
			(end 0.120396 0.3048)
			(stroke
				(width 0.1)
				(type default)
			)
			(layer "F.Fab")
		)
		(fp_line
			(start 0.120396 0.3048)
			(end 0.120396 0.2794)
			(stroke
				(width 0.1)
				(type default)
			)
			(layer "F.Fab")
		)
		(fp_line
			(start -0.12065 0.3048)
			(end -0.67945 0.3048)
			(stroke
				(width 0.1)
				(type default)
			)
			(layer "F.Fab")
		)
		(fp_line
			(start -0.67945 0.3048)
			(end -0.67945 -0.305054)
			(stroke
				(width 0.1)
				(type default)
			)
			(layer "F.Fab")
		)
		(pad "1" smd circle
			(at -0.40005 0 90)
			(size 0 0)
			(layers "F.Cu" "F.Mask" "F.Paste")
			(net "P3V3_AUX_FB")
		)
		(pad "2" smd circle
			(at 0.40005 0 90)
			(size 0 0)
			(layers "F.Cu" "F.Mask" "F.Paste")
			(net "P3V3_AUX")
		)
	)
	(footprint ""
		(layer "F.Cu")
		(at 113.873534 -38.065456)
		(property "Reference" "R3327"
			(at 0 0 0)
			(layer "F.SilkS")
			(hide yes)
			(effects
				(font
					(size 1.27 1.27)
				)
			)
		)
		(property "Value" ""
			(at 0 0 0)
			(layer "F.Fab")
			(effects
				(font
					(size 1.27 1.27)
				)
			)
		)
		(duplicate_pad_numbers_are_jumpers no)
		(fp_line
			(start -0.7874 -0.4064)
			(end 0.7874 -0.4064)
			(stroke
				(width 0.1524)
				(type default)
			)
			(layer "F.SilkS")
		)
		(fp_line
			(start -0.7874 0.4064)
			(end -0.7874 -0.4064)
			(stroke
				(width 0.1524)
				(type default)
			)
			(layer "F.SilkS")
		)
		(fp_line
			(start 0.7874 -0.4064)
			(end 0.7874 0.4064)
			(stroke
				(width 0.1524)
				(type default)
			)
			(layer "F.SilkS")
		)
		(fp_line
			(start 0.7874 0.4064)
			(end -0.7874 0.4064)
			(stroke
				(width 0.1524)
				(type default)
			)
			(layer "F.SilkS")
		)
		(fp_line
			(start -0.67945 -0.305054)
			(end -0.12065 -0.305054)
			(stroke
				(width 0.1)
				(type default)
			)
			(layer "F.Fab")
		)
		(fp_line
			(start -0.67945 0.3048)
			(end -0.67945 -0.305054)
			(stroke
				(width 0.1)
				(type default)
			)
			(layer "F.Fab")
		)
		(fp_line
			(start -0.12065 -0.305054)
			(end -0.12065 -0.2794)
			(stroke
				(width 0.1)
				(type default)
			)
			(layer "F.Fab")
		)
		(fp_line
			(start -0.12065 -0.2794)
			(end 0.12065 -0.2794)
			(stroke
				(width 0.1)
				(type default)
			)
			(layer "F.Fab")
		)
		(fp_line
			(start -0.12065 0.2794)
			(end -0.12065 0.3048)
			(stroke
				(width 0.1)
				(type default)
			)
			(layer "F.Fab")
		)
		(fp_line
			(start -0.12065 0.3048)
			(end -0.67945 0.3048)
			(stroke
				(width 0.1)
				(type default)
			)
			(layer "F.Fab")
		)
		(fp_line
			(start 0.120396 0.2794)
			(end -0.12065 0.2794)
			(stroke
				(width 0.1)
				(type default)
			)
			(layer "F.Fab")
		)
		(fp_line
			(start 0.120396 0.3048)
			(end 0.120396 0.2794)
			(stroke
				(width 0.1)
				(type default)
			)
			(layer "F.Fab")
		)
		(fp_line
			(start 0.12065 -0.3048)
			(end 0.67945 -0.3048)
			(stroke
				(width 0.1)
				(type default)
			)
			(layer "F.Fab")
		)
		(fp_line
			(start 0.12065 -0.2794)
			(end 0.12065 -0.3048)
			(stroke
				(width 0.1)
				(type default)
			)
			(layer "F.Fab")
		)
		(fp_line
			(start 0.67945 -0.3048)
			(end 0.67945 0.3048)
			(stroke
				(width 0.1)
				(type default)
			)
			(layer "F.Fab")
		)
		(fp_line
			(start 0.67945 0.3048)
			(end 0.120396 0.3048)
			(stroke
				(width 0.1)
				(type default)
			)
			(layer "F.Fab")
		)
		(pad "1" smd circle
			(at -0.40005 0)
			(size 0 0)
			(layers "F.Cu" "F.Mask" "F.Paste")
			(net "CLK_GEN2_GPU_FPGA_OE_N")
		)
		(pad "2" smd circle
			(at 0.40005 0)
			(size 0 0)
			(layers "F.Cu" "F.Mask" "F.Paste")
			(net "CLK_GEN2_GPU_FPGA_OE_R2_N")
		)
	)
	(footprint ""
		(layer "F.Cu")
		(at 175.95088 -258.091686)
		(property "Reference" "J28"
			(at -0.26924 -81.680812 0)
			(unlocked yes)
			(layer "F.SilkS")
			(effects
				(font
					(size 0.7874 0.5842)
					(thickness 0.1524)
				)
				(justify left)
			)
		)
		(property "Value" ""
			(at 0 0 0)
			(layer "F.Fab")
			(effects
				(font
					(size 1.27 1.27)
				)
			)
		)
		(duplicate_pad_numbers_are_jumpers no)
		(fp_line
			(start -3.24993 -81.000092)
			(end -3.24993 -80.736694)
			(stroke
				(width 0.1524)
				(type default)
			)
			(layer "F.SilkS")
		)
		(fp_line
			(start -3.24993 -75.262994)
			(end -3.24993 81.000092)
			(stroke
				(width 0.1524)
				(type default)
			)
			(layer "F.SilkS")
		)
		(fp_line
			(start -3.24993 81.000092)
			(end 3.24993 81.000092)
			(stroke
				(width 0.1524)
				(type default)
			)
			(layer "F.SilkS")
		)
		(fp_line
			(start -0.67056 -81.000092)
			(end -3.24993 -81.000092)
			(stroke
				(width 0.1524)
				(type default)
			)
			(layer "F.SilkS")
		)
		(fp_line
			(start 3.24993 -81.000092)
			(end 2.76098 -81.000092)
			(stroke
				(width 0.1524)
				(type default)
			)
			(layer "F.SilkS")
		)
		(fp_line
			(start 3.24993 -80.673194)
			(end 3.24993 -81.000092)
			(stroke
				(width 0.1524)
				(type default)
			)
			(layer "F.SilkS")
		)
		(fp_line
			(start 3.24993 -72.00011)
			(end -3.24993 -72.00011)
			(stroke
				(width 0.1524)
				(type default)
			)
			(layer "F.SilkS")
		)
		(fp_line
			(start 3.24993 72.00011)
			(end -3.24993 72.00011)
			(stroke
				(width 0.1524)
				(type default)
			)
			(layer "F.SilkS")
		)
		(fp_line
			(start 3.24993 81.000092)
			(end 3.24993 -75.346814)
			(stroke
				(width 0.1524)
				(type default)
			)
			(layer "F.SilkS")
		)
		(fp_poly
			(pts
				(xy -4.115054 -63.758826) (xy -3.251708 -63.327026) (xy -4.115054 -62.895226)
			)
			(stroke
				(width 0)
				(type default)
			)
			(fill yes)
			(layer "F.SilkS")
		)
		(fp_line
			(start -3.24993 -81.000092)
			(end -3.24993 81.000092)
			(stroke
				(width 0.1)
				(type default)
			)
			(layer "F.Fab")
		)
		(fp_line
			(start -3.24993 81.000092)
			(end 3.24993 81.000092)
			(stroke
				(width 0.1)
				(type default)
			)
			(layer "F.Fab")
		)
		(fp_line
			(start 3.24993 -81.000092)
			(end -3.24993 -81.000092)
			(stroke
				(width 0.1)
				(type default)
			)
			(layer "F.Fab")
		)
		(fp_line
			(start 3.24993 -72.00011)
			(end -3.24993 -72.00011)
			(stroke
				(width 0.1)
				(type default)
			)
			(layer "F.Fab")
		)
		(fp_line
			(start 3.24993 -71.000112)
			(end -3.24993 -71.000112)
			(stroke
				(width 0.1)
				(type default)
			)
			(layer "F.Fab")
		)
		(fp_line
			(start 3.24993 71.000112)
			(end -3.24993 71.000112)
			(stroke
				(width 0.1)
				(type default)
			)
			(layer "F.Fab")
		)
		(fp_line
			(start 3.24993 72.00011)
			(end -3.24993 72.00011)
			(stroke
				(width 0.1)
				(type default)
			)
			(layer "F.Fab")
		)
		(fp_line
			(start 3.24993 81.000092)
			(end 3.24993 -81.000092)
			(stroke
				(width 0.1)
				(type default)
			)
			(layer "F.Fab")
		)
		(fp_poly
			(pts
				(xy -4.445 -63.832994) (xy -4.445 -62.816994) (xy -3.429 -63.324994)
			)
			(stroke
				(width 0)
				(type default)
			)
			(fill yes)
			(layer "F.Fab")
		)
		(pad "1" smd rect
			(at -2.050034 -63.324994 270)
			(size 0.519938 1.4986)
			(layers "F.Cu" "F.Mask" "F.Paste")
			(net "P12V_S3_AUX_CPU1_NVDIMM")
		)
		(pad "2" smd rect
			(at -2.050034 -62.47511 270)
			(size 0.519938 1.4986)
			(layers "F.Cu" "F.Mask" "F.Paste")
			(net "TP_CHF_CPU1_DIMM2_FRU_0")
		)
		(pad "3" smd rect
			(at -2.050034 -61.624972 270)
			(size 0.519938 1.4986)
			(layers "F.Cu" "F.Mask" "F.Paste")
			(net "P3V3_AUX")
		)
		(pad "4" smd rect
			(at -2.050034 -60.775088 270)
			(size 0.519938 1.4986)
			(layers "F.Cu" "F.Mask" "F.Paste")
			(net "I3C_SPD_DDREFGH_CPU1_LVC1_SCL_3")
		)
		(pad "5" smd rect
			(at -2.050034 -59.92495 270)
			(size 0.519938 1.4986)
			(layers "F.Cu" "F.Mask" "F.Paste")
			(net "I3C_SPD_DDREFGH_CPU1_LVC1_SDA")
		)
		(pad "6" smd rect
			(at -2.050034 -59.075066 270)
			(size 0.519938 1.4986)
			(layers "F.Cu" "F.Mask" "F.Paste")
			(net "GND")
		)
		(pad "7" smd rect
			(at -2.050034 -58.224928 270)
			(size 0.519938 1.4986)
			(layers "F.Cu" "F.Mask" "F.Paste")
			(net "M_F_CPU1_SA_DQ<0>")
		)
		(pad "8" smd rect
			(at -2.050034 -57.375044 270)
			(size 0.519938 1.4986)
			(layers "F.Cu" "F.Mask" "F.Paste")
			(net "GND")
		)
		(pad "9" smd rect
			(at -2.050034 -56.524906 270)
			(size 0.519938 1.4986)
			(layers "F.Cu" "F.Mask" "F.Paste")
			(net "M_F_CPU1_SA_DQ<1>")
		)
		(pad "10" smd rect
			(at -2.050034 -55.675022 270)
			(size 0.519938 1.4986)
			(layers "F.Cu" "F.Mask" "F.Paste")
			(net "GND")
		)
		(pad "11" smd rect
			(at -2.050034 -54.824884 270)
			(size 0.519938 1.4986)
			(layers "F.Cu" "F.Mask" "F.Paste")
			(net "M_F_CPU1_SA_DQS_DP<0>")
		)
		(pad "12" smd rect
			(at -2.050034 -53.975 270)
			(size 0.519938 1.4986)
			(layers "F.Cu" "F.Mask" "F.Paste")
			(net "M_F_CPU1_SA_DQS_DN<0>")
		)
		(pad "13" smd rect
			(at -2.050034 -53.125116 270)
			(size 0.519938 1.4986)
			(layers "F.Cu" "F.Mask" "F.Paste")
			(net "GND")
		)
		(pad "14" smd rect
			(at -2.050034 -52.274978 270)
			(size 0.519938 1.4986)
			(layers "F.Cu" "F.Mask" "F.Paste")
			(net "M_F_CPU1_SA_DQ<4>")
		)
		(pad "15" smd rect
			(at -2.050034 -51.425094 270)
			(size 0.519938 1.4986)
			(layers "F.Cu" "F.Mask" "F.Paste")
			(net "GND")
		)
		(pad "16" smd rect
			(at -2.050034 -50.574956 270)
			(size 0.519938 1.4986)
			(layers "F.Cu" "F.Mask" "F.Paste")
			(net "M_F_CPU1_SA_DQ<5>")
		)
		(pad "17" smd rect
			(at -2.050034 -49.725072 270)
			(size 0.519938 1.4986)
			(layers "F.Cu" "F.Mask" "F.Paste")
			(net "GND")
		)
		(pad "18" smd rect
			(at -2.050034 -48.874934 270)
			(size 0.519938 1.4986)
			(layers "F.Cu" "F.Mask" "F.Paste")
			(net "M_F_CPU1_SA_DQ<8>")
		)
		(pad "19" smd rect
			(at -2.050034 -48.02505 270)
			(size 0.519938 1.4986)
			(layers "F.Cu" "F.Mask" "F.Paste")
			(net "GND")
		)
		(pad "20" smd rect
			(at -2.050034 -47.174912 270)
			(size 0.519938 1.4986)
			(layers "F.Cu" "F.Mask" "F.Paste")
			(net "M_F_CPU1_SA_DQ<9>")
		)
		(pad "21" smd rect
			(at -2.050034 -46.325028 270)
			(size 0.519938 1.4986)
			(layers "F.Cu" "F.Mask" "F.Paste")
			(net "GND")
		)
		(pad "22" smd rect
			(at -2.050034 -45.47489 270)
			(size 0.519938 1.4986)
			(layers "F.Cu" "F.Mask" "F.Paste")
			(net "M_F_CPU1_SA_DQS_DP<1>")
		)
		(pad "23" smd rect
			(at -2.050034 -44.625006 270)
			(size 0.519938 1.4986)
			(layers "F.Cu" "F.Mask" "F.Paste")
			(net "M_F_CPU1_SA_DQS_DN<1>")
		)
		(pad "24" smd rect
			(at -2.050034 -43.775122 270)
			(size 0.519938 1.4986)
			(layers "F.Cu" "F.Mask" "F.Paste")
			(net "GND")
		)
		(pad "25" smd rect
			(at -2.050034 -42.924984 270)
			(size 0.519938 1.4986)
			(layers "F.Cu" "F.Mask" "F.Paste")
			(net "M_F_CPU1_SA_DQ<12>")
		)
		(pad "26" smd rect
			(at -2.050034 -42.0751 270)
			(size 0.519938 1.4986)
			(layers "F.Cu" "F.Mask" "F.Paste")
			(net "GND")
		)
		(pad "27" smd rect
			(at -2.050034 -41.224962 270)
			(size 0.519938 1.4986)
			(layers "F.Cu" "F.Mask" "F.Paste")
			(net "M_F_CPU1_SA_DQ<13>")
		)
		(pad "28" smd rect
			(at -2.050034 -40.375078 270)
			(size 0.519938 1.4986)
			(layers "F.Cu" "F.Mask" "F.Paste")
			(net "GND")
		)
		(pad "29" smd rect
			(at -2.050034 -39.52494 270)
			(size 0.519938 1.4986)
			(layers "F.Cu" "F.Mask" "F.Paste")
			(net "M_F_CPU1_SA_DQ<16>")
		)
		(pad "30" smd rect
			(at -2.050034 -38.675056 270)
			(size 0.519938 1.4986)
			(layers "F.Cu" "F.Mask" "F.Paste")
			(net "GND")
		)
		(pad "31" smd rect
			(at -2.050034 -37.824918 270)
			(size 0.519938 1.4986)
			(layers "F.Cu" "F.Mask" "F.Paste")
			(net "M_F_CPU1_SA_DQ<17>")
		)
		(pad "32" smd rect
			(at -2.050034 -36.975034 270)
			(size 0.519938 1.4986)
			(layers "F.Cu" "F.Mask" "F.Paste")
			(net "GND")
		)
		(pad "33" smd rect
			(at -2.050034 -36.124896 270)
			(size 0.519938 1.4986)
			(layers "F.Cu" "F.Mask" "F.Paste")
			(net "M_F_CPU1_SA_DQS_DP<2>")
		)
		(pad "34" smd rect
			(at -2.050034 -35.275012 270)
			(size 0.519938 1.4986)
			(layers "F.Cu" "F.Mask" "F.Paste")
			(net "M_F_CPU1_SA_DQS_DN<2>")
		)
		(pad "35" smd rect
			(at -2.050034 -34.425128 270)
			(size 0.519938 1.4986)
			(layers "F.Cu" "F.Mask" "F.Paste")
			(net "GND")
		)
		(pad "36" smd rect
			(at -2.050034 -33.57499 270)
			(size 0.519938 1.4986)
			(layers "F.Cu" "F.Mask" "F.Paste")
			(net "M_F_CPU1_SA_DQ<20>")
		)
		(pad "37" smd rect
			(at -2.050034 -32.725106 270)
			(size 0.519938 1.4986)
			(layers "F.Cu" "F.Mask" "F.Paste")
			(net "GND")
		)
		(pad "38" smd rect
			(at -2.050034 -31.874968 270)
			(size 0.519938 1.4986)
			(layers "F.Cu" "F.Mask" "F.Paste")
			(net "M_F_CPU1_SA_DQ<21>")
		)
		(pad "39" smd rect
			(at -2.050034 -31.025084 270)
			(size 0.519938 1.4986)
			(layers "F.Cu" "F.Mask" "F.Paste")
			(net "GND")
		)
		(pad "40" smd rect
			(at -2.050034 -30.174946 270)
			(size 0.519938 1.4986)
			(layers "F.Cu" "F.Mask" "F.Paste")
			(net "M_F_CPU1_SA_DQ<24>")
		)
		(pad "41" smd rect
			(at -2.050034 -29.325062 270)
			(size 0.519938 1.4986)
			(layers "F.Cu" "F.Mask" "F.Paste")
			(net "GND")
		)
		(pad "42" smd rect
			(at -2.050034 -28.474924 270)
			(size 0.519938 1.4986)
			(layers "F.Cu" "F.Mask" "F.Paste")
			(net "M_F_CPU1_SA_DQ<25>")
		)
		(pad "43" smd rect
			(at -2.050034 -27.62504 270)
			(size 0.519938 1.4986)
			(layers "F.Cu" "F.Mask" "F.Paste")
			(net "GND")
		)
		(pad "44" smd rect
			(at -2.050034 -26.774902 270)
			(size 0.519938 1.4986)
			(layers "F.Cu" "F.Mask" "F.Paste")
			(net "M_F_CPU1_SA_DQS_DP<3>")
		)
		(pad "45" smd rect
			(at -2.050034 -25.925018 270)
			(size 0.519938 1.4986)
			(layers "F.Cu" "F.Mask" "F.Paste")
			(net "M_F_CPU1_SA_DQS_DN<3>")
		)
		(pad "46" smd rect
			(at -2.050034 -25.07488 270)
			(size 0.519938 1.4986)
			(layers "F.Cu" "F.Mask" "F.Paste")
			(net "GND")
		)
		(pad "47" smd rect
			(at -2.050034 -24.224996 270)
			(size 0.519938 1.4986)
			(layers "F.Cu" "F.Mask" "F.Paste")
			(net "M_F_CPU1_SA_DQ<28>")
		)
		(pad "48" smd rect
			(at -2.050034 -23.375112 270)
			(size 0.519938 1.4986)
			(layers "F.Cu" "F.Mask" "F.Paste")
			(net "GND")
		)
		(pad "49" smd rect
			(at -2.050034 -22.524974 270)
			(size 0.519938 1.4986)
			(layers "F.Cu" "F.Mask" "F.Paste")
			(net "M_F_CPU1_SA_DQ<29>")
		)
		(pad "50" smd rect
			(at -2.050034 -21.67509 270)
			(size 0.519938 1.4986)
			(layers "F.Cu" "F.Mask" "F.Paste")
			(net "GND")
		)
		(pad "51" smd rect
			(at -2.050034 -20.824952 270)
			(size 0.519938 1.4986)
			(layers "F.Cu" "F.Mask" "F.Paste")
			(net "M_F_CPU1_SA_CB<0>")
		)
		(pad "52" smd rect
			(at -2.050034 -19.975068 270)
			(size 0.519938 1.4986)
			(layers "F.Cu" "F.Mask" "F.Paste")
			(net "GND")
		)
		(pad "53" smd rect
			(at -2.050034 -19.12493 270)
			(size 0.519938 1.4986)
			(layers "F.Cu" "F.Mask" "F.Paste")
			(net "M_F_CPU1_SA_CB<1>")
		)
		(pad "54" smd rect
			(at -2.050034 -18.275046 270)
			(size 0.519938 1.4986)
			(layers "F.Cu" "F.Mask" "F.Paste")
			(net "GND")
		)
		(pad "55" smd rect
			(at -2.050034 -17.424908 270)
			(size 0.519938 1.4986)
			(layers "F.Cu" "F.Mask" "F.Paste")
			(net "M_F_CPU1_SA_DQS_DP<4>")
		)
		(pad "56" smd rect
			(at -2.050034 -16.575024 270)
			(size 0.519938 1.4986)
			(layers "F.Cu" "F.Mask" "F.Paste")
			(net "M_F_CPU1_SA_DQS_DN<4>")
		)
		(pad "57" smd rect
			(at -2.050034 -15.724886 270)
			(size 0.519938 1.4986)
			(layers "F.Cu" "F.Mask" "F.Paste")
			(net "GND")
		)
		(pad "58" smd rect
			(at -2.050034 -14.875002 270)
			(size 0.519938 1.4986)
			(layers "F.Cu" "F.Mask" "F.Paste")
			(net "M_F_CPU1_SA_CB<4>")
		)
		(pad "59" smd rect
			(at -2.050034 -14.025118 270)
			(size 0.519938 1.4986)
			(layers "F.Cu" "F.Mask" "F.Paste")
			(net "GND")
		)
		(pad "60" smd rect
			(at -2.050034 -13.17498 270)
			(size 0.519938 1.4986)
			(layers "F.Cu" "F.Mask" "F.Paste")
			(net "M_F_CPU1_SA_CB<5>")
		)
		(pad "61" smd rect
			(at -2.050034 -12.325096 270)
			(size 0.519938 1.4986)
			(layers "F.Cu" "F.Mask" "F.Paste")
			(net "GND")
		)
		(pad "62" smd rect
			(at -2.050034 -11.474958 270)
			(size 0.519938 1.4986)
			(layers "F.Cu" "F.Mask" "F.Paste")
			(net "M_F_CPU1_ALERT_N")
		)
		(pad "63" smd rect
			(at -2.050034 -10.625074 270)
			(size 0.519938 1.4986)
			(layers "F.Cu" "F.Mask" "F.Paste")
			(net "GND")
		)
		(pad "64" smd rect
			(at -2.050034 -9.774936 270)
			(size 0.519938 1.4986)
			(layers "F.Cu" "F.Mask" "F.Paste")
			(net "M_F_CPU1_SA_CS_N<2>")
		)
		(pad "65" smd rect
			(at -2.050034 -8.925052 270)
			(size 0.519938 1.4986)
			(layers "F.Cu" "F.Mask" "F.Paste")
			(net "GND")
		)
		(pad "66" smd rect
			(at -2.050034 -8.074914 270)
			(size 0.519938 1.4986)
			(layers "F.Cu" "F.Mask" "F.Paste")
			(net "M_F_CPU1_SA_CA<0>")
		)
		(pad "67" smd rect
			(at -2.050034 -7.22503 270)
			(size 0.519938 1.4986)
			(layers "F.Cu" "F.Mask" "F.Paste")
			(net "GND")
		)
		(pad "68" smd rect
			(at -2.050034 -6.374892 270)
			(size 0.519938 1.4986)
			(layers "F.Cu" "F.Mask" "F.Paste")
			(net "M_F_CPU1_SA_CA<2>")
		)
		(pad "69" smd rect
			(at -2.050034 -5.525008 270)
			(size 0.519938 1.4986)
			(layers "F.Cu" "F.Mask" "F.Paste")
			(net "GND")
		)
		(pad "70" smd rect
			(at -2.050034 -4.675124 270)
			(size 0.519938 1.4986)
			(layers "F.Cu" "F.Mask" "F.Paste")
			(net "M_F_CPU1_SA_CA<4>")
		)
		(pad "71" smd rect
			(at -2.050034 -3.824986 270)
			(size 0.519938 1.4986)
			(layers "F.Cu" "F.Mask" "F.Paste")
			(net "GND")
		)
		(pad "72" smd rect
			(at -2.050034 -2.975102 270)
			(size 0.519938 1.4986)
			(layers "F.Cu" "F.Mask" "F.Paste")
			(net "M_F_CPU1_SA_CA<6>")
		)
		(pad "73" smd rect
			(at -2.050034 -2.124964 270)
			(size 0.519938 1.4986)
			(layers "F.Cu" "F.Mask" "F.Paste")
			(net "GND")
		)
		(pad "74" smd rect
			(at -2.050034 -1.27508 270)
			(size 0.519938 1.4986)
			(layers "F.Cu" "F.Mask" "F.Paste")
			(net "M_F_CPU1_SA_PAR")
		)
		(pad "75" smd rect
			(at -2.050034 -0.424942 270)
			(size 0.519938 1.4986)
			(layers "F.Cu" "F.Mask" "F.Paste")
			(net "GND")
		)
		(pad "76" smd rect
			(at -2.050034 5.525008 270)
			(size 0.519938 1.4986)
			(layers "F.Cu" "F.Mask" "F.Paste")
			(net "M_F_CPU1_SB_CA<0>")
		)
		(pad "77" smd rect
			(at -2.050034 6.374892 270)
			(size 0.519938 1.4986)
			(layers "F.Cu" "F.Mask" "F.Paste")
			(net "GND")
		)
		(pad "78" smd rect
			(at -2.050034 7.22503 270)
			(size 0.519938 1.4986)
			(layers "F.Cu" "F.Mask" "F.Paste")
			(net "M_F_CPU1_SB_CA<2>")
		)
		(pad "79" smd rect
			(at -2.050034 8.074914 270)
			(size 0.519938 1.4986)
			(layers "F.Cu" "F.Mask" "F.Paste")
			(net "GND")
		)
		(pad "80" smd rect
			(at -2.050034 8.925052 270)
			(size 0.519938 1.4986)
			(layers "F.Cu" "F.Mask" "F.Paste")
			(net "M_F_CPU1_SB_CA<4>")
		)
		(pad "81" smd rect
			(at -2.050034 9.774936 270)
			(size 0.519938 1.4986)
			(layers "F.Cu" "F.Mask" "F.Paste")
			(net "GND")
		)
		(pad "82" smd rect
			(at -2.050034 10.625074 270)
			(size 0.519938 1.4986)
			(layers "F.Cu" "F.Mask" "F.Paste")
			(net "M_F_CPU1_SB_CA<6>")
		)
		(pad "83" smd rect
			(at -2.050034 11.474958 270)
			(size 0.519938 1.4986)
			(layers "F.Cu" "F.Mask" "F.Paste")
			(net "GND")
		)
		(pad "84" smd rect
			(at -2.050034 12.325096 270)
			(size 0.519938 1.4986)
			(layers "F.Cu" "F.Mask" "F.Paste")
			(net "M_F_CPU1_SB_CS_N<2>")
		)
		(pad "85" smd rect
			(at -2.050034 13.17498 270)
			(size 0.519938 1.4986)
			(layers "F.Cu" "F.Mask" "F.Paste")
			(net "GND")
		)
		(pad "86" smd rect
			(at -2.050034 14.025118 270)
			(size 0.519938 1.4986)
			(layers "F.Cu" "F.Mask" "F.Paste")
			(net "M_F_CPU1_SA_RSP<1>")
		)
		(pad "87" smd rect
			(at -2.050034 14.875002 270)
			(size 0.519938 1.4986)
			(layers "F.Cu" "F.Mask" "F.Paste")
			(net "M_F_CPU1_SB_RSP<1>")
		)
		(pad "88" smd rect
			(at -2.050034 15.724886 270)
			(size 0.519938 1.4986)
			(layers "F.Cu" "F.Mask" "F.Paste")
			(net "GND")
		)
		(pad "89" smd rect
			(at -2.050034 16.575024 270)
			(size 0.519938 1.4986)
			(layers "F.Cu" "F.Mask" "F.Paste")
			(net "M_F_CPU1_SB_CB<4>")
		)
		(pad "90" smd rect
			(at -2.050034 17.424908 270)
			(size 0.519938 1.4986)
			(layers "F.Cu" "F.Mask" "F.Paste")
			(net "GND")
		)
		(pad "91" smd rect
			(at -2.050034 18.275046 270)
			(size 0.519938 1.4986)
			(layers "F.Cu" "F.Mask" "F.Paste")
			(net "M_F_CPU1_SB_CB<5>")
		)
		(pad "92" smd rect
			(at -2.050034 19.12493 270)
			(size 0.519938 1.4986)
			(layers "F.Cu" "F.Mask" "F.Paste")
			(net "GND")
		)
		(pad "93" smd rect
			(at -2.050034 19.975068 270)
			(size 0.519938 1.4986)
			(layers "F.Cu" "F.Mask" "F.Paste")
			(net "M_F_CPU1_SB_DQS_DP<9>")
		)
		(pad "94" smd rect
			(at -2.050034 20.824952 270)
			(size 0.519938 1.4986)
			(layers "F.Cu" "F.Mask" "F.Paste")
			(net "M_F_CPU1_SB_DQS_DN<9>")
		)
		(pad "95" smd rect
			(at -2.050034 21.67509 270)
			(size 0.519938 1.4986)
			(layers "F.Cu" "F.Mask" "F.Paste")
			(net "GND")
		)
		(pad "96" smd rect
			(at -2.050034 22.524974 270)
			(size 0.519938 1.4986)
			(layers "F.Cu" "F.Mask" "F.Paste")
			(net "M_F_CPU1_SB_CB<0>")
		)
		(pad "97" smd rect
			(at -2.050034 23.375112 270)
			(size 0.519938 1.4986)
			(layers "F.Cu" "F.Mask" "F.Paste")
			(net "GND")
		)
		(pad "98" smd rect
			(at -2.050034 24.224996 270)
			(size 0.519938 1.4986)
			(layers "F.Cu" "F.Mask" "F.Paste")
			(net "M_F_CPU1_SB_CB<1>")
		)
		(pad "99" smd rect
			(at -2.050034 25.07488 270)
			(size 0.519938 1.4986)
			(layers "F.Cu" "F.Mask" "F.Paste")
			(net "GND")
		)
		(pad "100" smd rect
			(at -2.050034 25.925018 270)
			(size 0.519938 1.4986)
			(layers "F.Cu" "F.Mask" "F.Paste")
			(net "M_F_CPU1_SB_DQ<0>")
		)
		(pad "101" smd rect
			(at -2.050034 26.774902 270)
			(size 0.519938 1.4986)
			(layers "F.Cu" "F.Mask" "F.Paste")
			(net "GND")
		)
		(pad "102" smd rect
			(at -2.050034 27.62504 270)
			(size 0.519938 1.4986)
			(layers "F.Cu" "F.Mask" "F.Paste")
			(net "M_F_CPU1_SB_DQ<1>")
		)
		(pad "103" smd rect
			(at -2.050034 28.474924 270)
			(size 0.519938 1.4986)
			(layers "F.Cu" "F.Mask" "F.Paste")
			(net "GND")
		)
		(pad "104" smd rect
			(at -2.050034 29.325062 270)
			(size 0.519938 1.4986)
			(layers "F.Cu" "F.Mask" "F.Paste")
			(net "M_F_CPU1_SB_DQS_DP<0>")
		)
		(pad "105" smd rect
			(at -2.050034 30.174946 270)
			(size 0.519938 1.4986)
			(layers "F.Cu" "F.Mask" "F.Paste")
			(net "M_F_CPU1_SB_DQS_DN<0>")
		)
		(pad "106" smd rect
			(at -2.050034 31.025084 270)
			(size 0.519938 1.4986)
			(layers "F.Cu" "F.Mask" "F.Paste")
			(net "GND")
		)
		(pad "107" smd rect
			(at -2.050034 31.874968 270)
			(size 0.519938 1.4986)
			(layers "F.Cu" "F.Mask" "F.Paste")
			(net "M_F_CPU1_SB_DQ<4>")
		)
		(pad "108" smd rect
			(at -2.050034 32.725106 270)
			(size 0.519938 1.4986)
			(layers "F.Cu" "F.Mask" "F.Paste")
			(net "GND")
		)
		(pad "109" smd rect
			(at -2.050034 33.57499 270)
			(size 0.519938 1.4986)
			(layers "F.Cu" "F.Mask" "F.Paste")
			(net "M_F_CPU1_SB_DQ<5>")
		)
		(pad "110" smd rect
			(at -2.050034 34.425128 270)
			(size 0.519938 1.4986)
			(layers "F.Cu" "F.Mask" "F.Paste")
			(net "GND")
		)
		(pad "111" smd rect
			(at -2.050034 35.275012 270)
			(size 0.519938 1.4986)
			(layers "F.Cu" "F.Mask" "F.Paste")
			(net "M_F_CPU1_SB_DQ<8>")
		)
		(pad "112" smd rect
			(at -2.050034 36.124896 270)
			(size 0.519938 1.4986)
			(layers "F.Cu" "F.Mask" "F.Paste")
			(net "GND")
		)
		(pad "113" smd rect
			(at -2.050034 36.975034 270)
			(size 0.519938 1.4986)
			(layers "F.Cu" "F.Mask" "F.Paste")
			(net "M_F_CPU1_SB_DQ<9>")
		)
		(pad "114" smd rect
			(at -2.050034 37.824918 270)
			(size 0.519938 1.4986)
			(layers "F.Cu" "F.Mask" "F.Paste")
			(net "GND")
		)
		(pad "115" smd rect
			(at -2.050034 38.675056 270)
			(size 0.519938 1.4986)
			(layers "F.Cu" "F.Mask" "F.Paste")
			(net "M_F_CPU1_SB_DQS_DP<1>")
		)
		(pad "116" smd rect
			(at -2.050034 39.52494 270)
			(size 0.519938 1.4986)
			(layers "F.Cu" "F.Mask" "F.Paste")
			(net "M_F_CPU1_SB_DQS_DN<1>")
		)
		(pad "117" smd rect
			(at -2.050034 40.375078 270)
			(size 0.519938 1.4986)
			(layers "F.Cu" "F.Mask" "F.Paste")
			(net "GND")
		)
		(pad "118" smd rect
			(at -2.050034 41.224962 270)
			(size 0.519938 1.4986)
			(layers "F.Cu" "F.Mask" "F.Paste")
			(net "M_F_CPU1_SB_DQ<12>")
		)
		(pad "119" smd rect
			(at -2.050034 42.0751 270)
			(size 0.519938 1.4986)
			(layers "F.Cu" "F.Mask" "F.Paste")
			(net "GND")
		)
		(pad "120" smd rect
			(at -2.050034 42.924984 270)
			(size 0.519938 1.4986)
			(layers "F.Cu" "F.Mask" "F.Paste")
			(net "M_F_CPU1_SB_DQ<13>")
		)
		(pad "121" smd rect
			(at -2.050034 43.775122 270)
			(size 0.519938 1.4986)
			(layers "F.Cu" "F.Mask" "F.Paste")
			(net "GND")
		)
		(pad "122" smd rect
			(at -2.050034 44.625006 270)
			(size 0.519938 1.4986)
			(layers "F.Cu" "F.Mask" "F.Paste")
			(net "M_F_CPU1_SB_DQ<16>")
		)
		(pad "123" smd rect
			(at -2.050034 45.47489 270)
			(size 0.519938 1.4986)
			(layers "F.Cu" "F.Mask" "F.Paste")
			(net "GND")
		)
		(pad "124" smd rect
			(at -2.050034 46.325028 270)
			(size 0.519938 1.4986)
			(layers "F.Cu" "F.Mask" "F.Paste")
			(net "M_F_CPU1_SB_DQ<17>")
		)
		(pad "125" smd rect
			(at -2.050034 47.174912 270)
			(size 0.519938 1.4986)
			(layers "F.Cu" "F.Mask" "F.Paste")
			(net "GND")
		)
		(pad "126" smd rect
			(at -2.050034 48.02505 270)
			(size 0.519938 1.4986)
			(layers "F.Cu" "F.Mask" "F.Paste")
			(net "M_F_CPU1_SB_DQS_DP<2>")
		)
		(pad "127" smd rect
			(at -2.050034 48.874934 270)
			(size 0.519938 1.4986)
			(layers "F.Cu" "F.Mask" "F.Paste")
			(net "M_F_CPU1_SB_DQS_DN<2>")
		)
		(pad "128" smd rect
			(at -2.050034 49.725072 270)
			(size 0.519938 1.4986)
			(layers "F.Cu" "F.Mask" "F.Paste")
			(net "GND")
		)
		(pad "129" smd rect
			(at -2.050034 50.574956 270)
			(size 0.519938 1.4986)
			(layers "F.Cu" "F.Mask" "F.Paste")
			(net "M_F_CPU1_SB_DQ<20>")
		)
		(pad "130" smd rect
			(at -2.050034 51.425094 270)
			(size 0.519938 1.4986)
			(layers "F.Cu" "F.Mask" "F.Paste")
			(net "GND")
		)
		(pad "131" smd rect
			(at -2.050034 52.274978 270)
			(size 0.519938 1.4986)
			(layers "F.Cu" "F.Mask" "F.Paste")
			(net "M_F_CPU1_SB_DQ<21>")
		)
		(pad "132" smd rect
			(at -2.050034 53.125116 270)
			(size 0.519938 1.4986)
			(layers "F.Cu" "F.Mask" "F.Paste")
			(net "GND")
		)
		(pad "133" smd rect
			(at -2.050034 53.975 270)
			(size 0.519938 1.4986)
			(layers "F.Cu" "F.Mask" "F.Paste")
			(net "M_F_CPU1_SB_DQ<24>")
		)
		(pad "134" smd rect
			(at -2.050034 54.824884 270)
			(size 0.519938 1.4986)
			(layers "F.Cu" "F.Mask" "F.Paste")
			(net "GND")
		)
		(pad "135" smd rect
			(at -2.050034 55.675022 270)
			(size 0.519938 1.4986)
			(layers "F.Cu" "F.Mask" "F.Paste")
			(net "M_F_CPU1_SB_DQ<25>")
		)
		(pad "136" smd rect
			(at -2.050034 56.524906 270)
			(size 0.519938 1.4986)
			(layers "F.Cu" "F.Mask" "F.Paste")
			(net "GND")
		)
		(pad "137" smd rect
			(at -2.050034 57.375044 270)
			(size 0.519938 1.4986)
			(layers "F.Cu" "F.Mask" "F.Paste")
			(net "M_F_CPU1_SB_DQS_DP<3>")
		)
		(pad "138" smd rect
			(at -2.050034 58.224928 270)
			(size 0.519938 1.4986)
			(layers "F.Cu" "F.Mask" "F.Paste")
			(net "M_F_CPU1_SB_DQS_DN<3>")
		)
		(pad "139" smd rect
			(at -2.050034 59.075066 270)
			(size 0.519938 1.4986)
			(layers "F.Cu" "F.Mask" "F.Paste")
			(net "GND")
		)
		(pad "140" smd rect
			(at -2.050034 59.92495 270)
			(size 0.519938 1.4986)
			(layers "F.Cu" "F.Mask" "F.Paste")
			(net "M_F_CPU1_SB_DQ<28>")
		)
		(pad "141" smd rect
			(at -2.050034 60.775088 270)
			(size 0.519938 1.4986)
			(layers "F.Cu" "F.Mask" "F.Paste")
			(net "GND")
		)
		(pad "142" smd rect
			(at -2.050034 61.624972 270)
			(size 0.519938 1.4986)
			(layers "F.Cu" "F.Mask" "F.Paste")
			(net "M_F_CPU1_SB_DQ<29>")
		)
		(pad "143" smd rect
			(at -2.050034 62.47511 270)
			(size 0.519938 1.4986)
			(layers "F.Cu" "F.Mask" "F.Paste")
			(net "GND")
		)
		(pad "144" smd rect
			(at -2.050034 63.324994 270)
			(size 0.519938 1.4986)
			(layers "F.Cu" "F.Mask" "F.Paste")
			(net "TP_CHF_CPU1_DIMM2_FRU_1")
		)
		(pad "145" smd rect
			(at 2.050034 -63.324994 270)
			(size 0.519938 1.4986)
			(layers "F.Cu" "F.Mask" "F.Paste")
			(net "P12V_S3_AUX_CPU1_NVDIMM")
		)
		(pad "146" smd rect
			(at 2.050034 -62.47511 270)
			(size 0.519938 1.4986)
			(layers "F.Cu" "F.Mask" "F.Paste")
			(net "P12V_S3_AUX_CPU1_NVDIMM")
		)
		(pad "147" smd rect
			(at 2.050034 -61.624972 270)
			(size 0.519938 1.4986)
			(layers "F.Cu" "F.Mask" "F.Paste")
			(net "PWRGD_CHF_CPU1_DIMM2")
		)
		(pad "148" smd rect
			(at 2.050034 -60.775088 270)
			(size 0.519938 1.4986)
			(layers "F.Cu" "F.Mask" "F.Paste")
			(net "PD_CHF_CPU1_DIMM2_SAA")
		)
		(pad "149" smd rect
			(at 2.050034 -59.92495 270)
			(size 0.519938 1.4986)
			(layers "F.Cu" "F.Mask" "F.Paste")
			(net "TP_CHF_CPU1_DIMM2_FRU_2")
		)
		(pad "150" smd rect
			(at 2.050034 -59.075066 270)
			(size 0.519938 1.4986)
			(layers "F.Cu" "F.Mask" "F.Paste")
			(net "TP_CHF_CPU1_DIMM2_FRU_3")
		)
		(pad "151" smd rect
			(at 2.050034 -58.224928 270)
			(size 0.519938 1.4986)
			(layers "F.Cu" "F.Mask" "F.Paste")
			(net "GND")
		)
		(pad "152" smd rect
			(at 2.050034 -57.375044 270)
			(size 0.519938 1.4986)
			(layers "F.Cu" "F.Mask" "F.Paste")
			(net "M_F_CPU1_SA_DQ<2>")
		)
		(pad "153" smd rect
			(at 2.050034 -56.524906 270)
			(size 0.519938 1.4986)
			(layers "F.Cu" "F.Mask" "F.Paste")
			(net "GND")
		)
		(pad "154" smd rect
			(at 2.050034 -55.675022 270)
			(size 0.519938 1.4986)
			(layers "F.Cu" "F.Mask" "F.Paste")
			(net "M_F_CPU1_SA_DQ<3>")
		)
		(pad "155" smd rect
			(at 2.050034 -54.824884 270)
			(size 0.519938 1.4986)
			(layers "F.Cu" "F.Mask" "F.Paste")
			(net "GND")
		)
		(pad "156" smd rect
			(at 2.050034 -53.975 270)
			(size 0.519938 1.4986)
			(layers "F.Cu" "F.Mask" "F.Paste")
			(net "M_F_CPU1_SA_DQS_DN<5>")
		)
		(pad "157" smd rect
			(at 2.050034 -53.125116 270)
			(size 0.519938 1.4986)
			(layers "F.Cu" "F.Mask" "F.Paste")
			(net "M_F_CPU1_SA_DQS_DP<5>")
		)
		(pad "158" smd rect
			(at 2.050034 -52.274978 270)
			(size 0.519938 1.4986)
			(layers "F.Cu" "F.Mask" "F.Paste")
			(net "GND")
		)
		(pad "159" smd rect
			(at 2.050034 -51.425094 270)
			(size 0.519938 1.4986)
			(layers "F.Cu" "F.Mask" "F.Paste")
			(net "M_F_CPU1_SA_DQ<6>")
		)
		(pad "160" smd rect
			(at 2.050034 -50.574956 270)
			(size 0.519938 1.4986)
			(layers "F.Cu" "F.Mask" "F.Paste")
			(net "GND")
		)
		(pad "161" smd rect
			(at 2.050034 -49.725072 270)
			(size 0.519938 1.4986)
			(layers "F.Cu" "F.Mask" "F.Paste")
			(net "M_F_CPU1_SA_DQ<7>")
		)
		(pad "162" smd rect
			(at 2.050034 -48.874934 270)
			(size 0.519938 1.4986)
			(layers "F.Cu" "F.Mask" "F.Paste")
			(net "GND")
		)
		(pad "163" smd rect
			(at 2.050034 -48.02505 270)
			(size 0.519938 1.4986)
			(layers "F.Cu" "F.Mask" "F.Paste")
			(net "M_F_CPU1_SA_DQ<10>")
		)
		(pad "164" smd rect
			(at 2.050034 -47.174912 270)
			(size 0.519938 1.4986)
			(layers "F.Cu" "F.Mask" "F.Paste")
			(net "GND")
		)
		(pad "165" smd rect
			(at 2.050034 -46.325028 270)
			(size 0.519938 1.4986)
			(layers "F.Cu" "F.Mask" "F.Paste")
			(net "M_F_CPU1_SA_DQ<11>")
		)
		(pad "166" smd rect
			(at 2.050034 -45.47489 270)
			(size 0.519938 1.4986)
			(layers "F.Cu" "F.Mask" "F.Paste")
			(net "GND")
		)
		(pad "167" smd rect
			(at 2.050034 -44.625006 270)
			(size 0.519938 1.4986)
			(layers "F.Cu" "F.Mask" "F.Paste")
			(net "M_F_CPU1_SA_DQS_DN<6>")
		)
		(pad "168" smd rect
			(at 2.050034 -43.775122 270)
			(size 0.519938 1.4986)
			(layers "F.Cu" "F.Mask" "F.Paste")
			(net "M_F_CPU1_SA_DQS_DP<6>")
		)
		(pad "169" smd rect
			(at 2.050034 -42.924984 270)
			(size 0.519938 1.4986)
			(layers "F.Cu" "F.Mask" "F.Paste")
			(net "GND")
		)
		(pad "170" smd rect
			(at 2.050034 -42.0751 270)
			(size 0.519938 1.4986)
			(layers "F.Cu" "F.Mask" "F.Paste")
			(net "M_F_CPU1_SA_DQ<14>")
		)
		(pad "171" smd rect
			(at 2.050034 -41.224962 270)
			(size 0.519938 1.4986)
			(layers "F.Cu" "F.Mask" "F.Paste")
			(net "GND")
		)
		(pad "172" smd rect
			(at 2.050034 -40.375078 270)
			(size 0.519938 1.4986)
			(layers "F.Cu" "F.Mask" "F.Paste")
			(net "M_F_CPU1_SA_DQ<15>")
		)
		(pad "173" smd rect
			(at 2.050034 -39.52494 270)
			(size 0.519938 1.4986)
			(layers "F.Cu" "F.Mask" "F.Paste")
			(net "GND")
		)
		(pad "174" smd rect
			(at 2.050034 -38.675056 270)
			(size 0.519938 1.4986)
			(layers "F.Cu" "F.Mask" "F.Paste")
			(net "M_F_CPU1_SA_DQ<18>")
		)
		(pad "175" smd rect
			(at 2.050034 -37.824918 270)
			(size 0.519938 1.4986)
			(layers "F.Cu" "F.Mask" "F.Paste")
			(net "GND")
		)
		(pad "176" smd rect
			(at 2.050034 -36.975034 270)
			(size 0.519938 1.4986)
			(layers "F.Cu" "F.Mask" "F.Paste")
			(net "M_F_CPU1_SA_DQ<19>")
		)
		(pad "177" smd rect
			(at 2.050034 -36.124896 270)
			(size 0.519938 1.4986)
			(layers "F.Cu" "F.Mask" "F.Paste")
			(net "GND")
		)
		(pad "178" smd rect
			(at 2.050034 -35.275012 270)
			(size 0.519938 1.4986)
			(layers "F.Cu" "F.Mask" "F.Paste")
			(net "M_F_CPU1_SA_DQS_DN<7>")
		)
		(pad "179" smd rect
			(at 2.050034 -34.425128 270)
			(size 0.519938 1.4986)
			(layers "F.Cu" "F.Mask" "F.Paste")
			(net "M_F_CPU1_SA_DQS_DP<7>")
		)
		(pad "180" smd rect
			(at 2.050034 -33.57499 270)
			(size 0.519938 1.4986)
			(layers "F.Cu" "F.Mask" "F.Paste")
			(net "GND")
		)
		(pad "181" smd rect
			(at 2.050034 -32.725106 270)
			(size 0.519938 1.4986)
			(layers "F.Cu" "F.Mask" "F.Paste")
			(net "M_F_CPU1_SA_DQ<22>")
		)
		(pad "182" smd rect
			(at 2.050034 -31.874968 270)
			(size 0.519938 1.4986)
			(layers "F.Cu" "F.Mask" "F.Paste")
			(net "GND")
		)
		(pad "183" smd rect
			(at 2.050034 -31.025084 270)
			(size 0.519938 1.4986)
			(layers "F.Cu" "F.Mask" "F.Paste")
			(net "M_F_CPU1_SA_DQ<23>")
		)
		(pad "184" smd rect
			(at 2.050034 -30.174946 270)
			(size 0.519938 1.4986)
			(layers "F.Cu" "F.Mask" "F.Paste")
			(net "GND")
		)
		(pad "185" smd rect
			(at 2.050034 -29.325062 270)
			(size 0.519938 1.4986)
			(layers "F.Cu" "F.Mask" "F.Paste")
			(net "M_F_CPU1_SA_DQ<26>")
		)
		(pad "186" smd rect
			(at 2.050034 -28.474924 270)
			(size 0.519938 1.4986)
			(layers "F.Cu" "F.Mask" "F.Paste")
			(net "GND")
		)
		(pad "187" smd rect
			(at 2.050034 -27.62504 270)
			(size 0.519938 1.4986)
			(layers "F.Cu" "F.Mask" "F.Paste")
			(net "M_F_CPU1_SA_DQ<27>")
		)
		(pad "188" smd rect
			(at 2.050034 -26.774902 270)
			(size 0.519938 1.4986)
			(layers "F.Cu" "F.Mask" "F.Paste")
			(net "GND")
		)
		(pad "189" smd rect
			(at 2.050034 -25.925018 270)
			(size 0.519938 1.4986)
			(layers "F.Cu" "F.Mask" "F.Paste")
			(net "M_F_CPU1_SA_DQS_DN<8>")
		)
		(pad "190" smd rect
			(at 2.050034 -25.07488 270)
			(size 0.519938 1.4986)
			(layers "F.Cu" "F.Mask" "F.Paste")
			(net "M_F_CPU1_SA_DQS_DP<8>")
		)
		(pad "191" smd rect
			(at 2.050034 -24.224996 270)
			(size 0.519938 1.4986)
			(layers "F.Cu" "F.Mask" "F.Paste")
			(net "GND")
		)
		(pad "192" smd rect
			(at 2.050034 -23.375112 270)
			(size 0.519938 1.4986)
			(layers "F.Cu" "F.Mask" "F.Paste")
			(net "M_F_CPU1_SA_DQ<30>")
		)
		(pad "193" smd rect
			(at 2.050034 -22.524974 270)
			(size 0.519938 1.4986)
			(layers "F.Cu" "F.Mask" "F.Paste")
			(net "GND")
		)
		(pad "194" smd rect
			(at 2.050034 -21.67509 270)
			(size 0.519938 1.4986)
			(layers "F.Cu" "F.Mask" "F.Paste")
			(net "M_F_CPU1_SA_DQ<31>")
		)
		(pad "195" smd rect
			(at 2.050034 -20.824952 270)
			(size 0.519938 1.4986)
			(layers "F.Cu" "F.Mask" "F.Paste")
			(net "GND")
		)
		(pad "196" smd rect
			(at 2.050034 -19.975068 270)
			(size 0.519938 1.4986)
			(layers "F.Cu" "F.Mask" "F.Paste")
			(net "M_F_CPU1_SA_CB<2>")
		)
		(pad "197" smd rect
			(at 2.050034 -19.12493 270)
			(size 0.519938 1.4986)
			(layers "F.Cu" "F.Mask" "F.Paste")
			(net "GND")
		)
		(pad "198" smd rect
			(at 2.050034 -18.275046 270)
			(size 0.519938 1.4986)
			(layers "F.Cu" "F.Mask" "F.Paste")
			(net "M_F_CPU1_SA_CB<3>")
		)
		(pad "199" smd rect
			(at 2.050034 -17.424908 270)
			(size 0.519938 1.4986)
			(layers "F.Cu" "F.Mask" "F.Paste")
			(net "GND")
		)
		(pad "200" smd rect
			(at 2.050034 -16.575024 270)
			(size 0.519938 1.4986)
			(layers "F.Cu" "F.Mask" "F.Paste")
			(net "M_F_CPU1_SA_DQS_DN<9>")
		)
		(pad "201" smd rect
			(at 2.050034 -15.724886 270)
			(size 0.519938 1.4986)
			(layers "F.Cu" "F.Mask" "F.Paste")
			(net "M_F_CPU1_SA_DQS_DP<9>")
		)
		(pad "202" smd rect
			(at 2.050034 -14.875002 270)
			(size 0.519938 1.4986)
			(layers "F.Cu" "F.Mask" "F.Paste")
			(net "GND")
		)
		(pad "203" smd rect
			(at 2.050034 -14.025118 270)
			(size 0.519938 1.4986)
			(layers "F.Cu" "F.Mask" "F.Paste")
			(net "M_F_CPU1_SA_CB<6>")
		)
		(pad "204" smd rect
			(at 2.050034 -13.17498 270)
			(size 0.519938 1.4986)
			(layers "F.Cu" "F.Mask" "F.Paste")
			(net "GND")
		)
		(pad "205" smd rect
			(at 2.050034 -12.325096 270)
			(size 0.519938 1.4986)
			(layers "F.Cu" "F.Mask" "F.Paste")
			(net "M_F_CPU1_SA_CB<7>")
		)
		(pad "206" smd rect
			(at 2.050034 -11.474958 270)
			(size 0.519938 1.4986)
			(layers "F.Cu" "F.Mask" "F.Paste")
			(net "GND")
		)
		(pad "207" smd rect
			(at 2.050034 -10.625074 270)
			(size 0.519938 1.4986)
			(layers "F.Cu" "F.Mask" "F.Paste")
			(net "RST_M_EF_CPU1_FPGA_N")
		)
		(pad "208" smd rect
			(at 2.050034 -9.774936 270)
			(size 0.519938 1.4986)
			(layers "F.Cu" "F.Mask" "F.Paste")
			(net "GND")
		)
		(pad "209" smd rect
			(at 2.050034 -8.925052 270)
			(size 0.519938 1.4986)
			(layers "F.Cu" "F.Mask" "F.Paste")
			(net "M_F_CPU1_SA_CS_N<3>")
		)
		(pad "210" smd rect
			(at 2.050034 -8.074914 270)
			(size 0.519938 1.4986)
			(layers "F.Cu" "F.Mask" "F.Paste")
			(net "GND")
		)
		(pad "211" smd rect
			(at 2.050034 -7.22503 270)
			(size 0.519938 1.4986)
			(layers "F.Cu" "F.Mask" "F.Paste")
			(net "M_F_CPU1_SA_CA<1>")
		)
		(pad "212" smd rect
			(at 2.050034 -6.374892 270)
			(size 0.519938 1.4986)
			(layers "F.Cu" "F.Mask" "F.Paste")
			(net "GND")
		)
		(pad "213" smd rect
			(at 2.050034 -5.525008 270)
			(size 0.519938 1.4986)
			(layers "F.Cu" "F.Mask" "F.Paste")
			(net "M_F_CPU1_SA_CA<3>")
		)
		(pad "214" smd rect
			(at 2.050034 -4.675124 270)
			(size 0.519938 1.4986)
			(layers "F.Cu" "F.Mask" "F.Paste")
			(net "GND")
		)
		(pad "215" smd rect
			(at 2.050034 -3.824986 270)
			(size 0.519938 1.4986)
			(layers "F.Cu" "F.Mask" "F.Paste")
			(net "M_F_CPU1_SA_CA<5>")
		)
		(pad "216" smd rect
			(at 2.050034 -2.975102 270)
			(size 0.519938 1.4986)
			(layers "F.Cu" "F.Mask" "F.Paste")
			(net "GND")
		)
		(pad "217" smd rect
			(at 2.050034 -2.124964 270)
			(size 0.519938 1.4986)
			(layers "F.Cu" "F.Mask" "F.Paste")
			(net "M_F_CPU1_CLK_DP<1>")
		)
		(pad "218" smd rect
			(at 2.050034 -1.27508 270)
			(size 0.519938 1.4986)
			(layers "F.Cu" "F.Mask" "F.Paste")
			(net "M_F_CPU1_CLK_DN<1>")
		)
		(pad "219" smd rect
			(at 2.050034 -0.424942 270)
			(size 0.519938 1.4986)
			(layers "F.Cu" "F.Mask" "F.Paste")
			(net "GND")
		)
		(pad "220" smd rect
			(at 2.050034 5.525008 270)
			(size 0.519938 1.4986)
			(layers "F.Cu" "F.Mask" "F.Paste")
			(net "TP_CHF_CPU1_DIMM2_FRU_4")
		)
		(pad "221" smd rect
			(at 2.050034 6.374892 270)
			(size 0.519938 1.4986)
			(layers "F.Cu" "F.Mask" "F.Paste")
			(net "M_F_CPU1_SB_CA<1>")
		)
		(pad "222" smd rect
			(at 2.050034 7.22503 270)
			(size 0.519938 1.4986)
			(layers "F.Cu" "F.Mask" "F.Paste")
			(net "GND")
		)
		(pad "223" smd rect
			(at 2.050034 8.074914 270)
			(size 0.519938 1.4986)
			(layers "F.Cu" "F.Mask" "F.Paste")
			(net "M_F_CPU1_SB_CA<3>")
		)
		(pad "224" smd rect
			(at 2.050034 8.925052 270)
			(size 0.519938 1.4986)
			(layers "F.Cu" "F.Mask" "F.Paste")
			(net "GND")
		)
		(pad "225" smd rect
			(at 2.050034 9.774936 270)
			(size 0.519938 1.4986)
			(layers "F.Cu" "F.Mask" "F.Paste")
			(net "M_F_CPU1_SB_CA<5>")
		)
		(pad "226" smd rect
			(at 2.050034 10.625074 270)
			(size 0.519938 1.4986)
			(layers "F.Cu" "F.Mask" "F.Paste")
			(net "GND")
		)
		(pad "227" smd rect
			(at 2.050034 11.474958 270)
			(size 0.519938 1.4986)
			(layers "F.Cu" "F.Mask" "F.Paste")
			(net "M_F_CPU1_SB_PAR")
		)
		(pad "228" smd rect
			(at 2.050034 12.325096 270)
			(size 0.519938 1.4986)
			(layers "F.Cu" "F.Mask" "F.Paste")
			(net "GND")
		)
		(pad "229" smd rect
			(at 2.050034 13.17498 270)
			(size 0.519938 1.4986)
			(layers "F.Cu" "F.Mask" "F.Paste")
			(net "M_F_CPU1_SB_CS_N<3>")
		)
		(pad "230" smd rect
			(at 2.050034 14.025118 270)
			(size 0.519938 1.4986)
			(layers "F.Cu" "F.Mask" "F.Paste")
			(net "GND")
		)
		(pad "231" smd rect
			(at 2.050034 14.875002 270)
			(size 0.519938 1.4986)
			(layers "F.Cu" "F.Mask" "F.Paste")
			(net "TP_CHF_CPU1_DIMM2_FRU_5")
		)
		(pad "232" smd rect
			(at 2.050034 15.724886 270)
			(size 0.519938 1.4986)
			(layers "F.Cu" "F.Mask" "F.Paste")
			(net "TP_CHF_CPU1_DIMM2_FRU_6")
		)
		(pad "233" smd rect
			(at 2.050034 16.575024 270)
			(size 0.519938 1.4986)
			(layers "F.Cu" "F.Mask" "F.Paste")
			(net "GND")
		)
		(pad "234" smd rect
			(at 2.050034 17.424908 270)
			(size 0.519938 1.4986)
			(layers "F.Cu" "F.Mask" "F.Paste")
			(net "M_F_CPU1_SB_CB<6>")
		)
		(pad "235" smd rect
			(at 2.050034 18.275046 270)
			(size 0.519938 1.4986)
			(layers "F.Cu" "F.Mask" "F.Paste")
			(net "GND")
		)
		(pad "236" smd rect
			(at 2.050034 19.12493 270)
			(size 0.519938 1.4986)
			(layers "F.Cu" "F.Mask" "F.Paste")
			(net "M_F_CPU1_SB_CB<7>")
		)
		(pad "237" smd rect
			(at 2.050034 19.975068 270)
			(size 0.519938 1.4986)
			(layers "F.Cu" "F.Mask" "F.Paste")
			(net "GND")
		)
		(pad "238" smd rect
			(at 2.050034 20.824952 270)
			(size 0.519938 1.4986)
			(layers "F.Cu" "F.Mask" "F.Paste")
			(net "M_F_CPU1_SB_DQS_DN<4>")
		)
		(pad "239" smd rect
			(at 2.050034 21.67509 270)
			(size 0.519938 1.4986)
			(layers "F.Cu" "F.Mask" "F.Paste")
			(net "M_F_CPU1_SB_DQS_DP<4>")
		)
		(pad "240" smd rect
			(at 2.050034 22.524974 270)
			(size 0.519938 1.4986)
			(layers "F.Cu" "F.Mask" "F.Paste")
			(net "GND")
		)
		(pad "241" smd rect
			(at 2.050034 23.375112 270)
			(size 0.519938 1.4986)
			(layers "F.Cu" "F.Mask" "F.Paste")
			(net "M_F_CPU1_SB_CB<2>")
		)
		(pad "242" smd rect
			(at 2.050034 24.224996 270)
			(size 0.519938 1.4986)
			(layers "F.Cu" "F.Mask" "F.Paste")
			(net "GND")
		)
		(pad "243" smd rect
			(at 2.050034 25.07488 270)
			(size 0.519938 1.4986)
			(layers "F.Cu" "F.Mask" "F.Paste")
			(net "M_F_CPU1_SB_CB<3>")
		)
		(pad "244" smd rect
			(at 2.050034 25.925018 270)
			(size 0.519938 1.4986)
			(layers "F.Cu" "F.Mask" "F.Paste")
			(net "GND")
		)
		(pad "245" smd rect
			(at 2.050034 26.774902 270)
			(size 0.519938 1.4986)
			(layers "F.Cu" "F.Mask" "F.Paste")
			(net "M_F_CPU1_SB_DQ<2>")
		)
		(pad "246" smd rect
			(at 2.050034 27.62504 270)
			(size 0.519938 1.4986)
			(layers "F.Cu" "F.Mask" "F.Paste")
			(net "GND")
		)
		(pad "247" smd rect
			(at 2.050034 28.474924 270)
			(size 0.519938 1.4986)
			(layers "F.Cu" "F.Mask" "F.Paste")
			(net "M_F_CPU1_SB_DQ<3>")
		)
		(pad "248" smd rect
			(at 2.050034 29.325062 270)
			(size 0.519938 1.4986)
			(layers "F.Cu" "F.Mask" "F.Paste")
			(net "GND")
		)
		(pad "249" smd rect
			(at 2.050034 30.174946 270)
			(size 0.519938 1.4986)
			(layers "F.Cu" "F.Mask" "F.Paste")
			(net "M_F_CPU1_SB_DQS_DN<5>")
		)
		(pad "250" smd rect
			(at 2.050034 31.025084 270)
			(size 0.519938 1.4986)
			(layers "F.Cu" "F.Mask" "F.Paste")
			(net "M_F_CPU1_SB_DQS_DP<5>")
		)
		(pad "251" smd rect
			(at 2.050034 31.874968 270)
			(size 0.519938 1.4986)
			(layers "F.Cu" "F.Mask" "F.Paste")
			(net "GND")
		)
		(pad "252" smd rect
			(at 2.050034 32.725106 270)
			(size 0.519938 1.4986)
			(layers "F.Cu" "F.Mask" "F.Paste")
			(net "M_F_CPU1_SB_DQ<6>")
		)
		(pad "253" smd rect
			(at 2.050034 33.57499 270)
			(size 0.519938 1.4986)
			(layers "F.Cu" "F.Mask" "F.Paste")
			(net "GND")
		)
		(pad "254" smd rect
			(at 2.050034 34.425128 270)
			(size 0.519938 1.4986)
			(layers "F.Cu" "F.Mask" "F.Paste")
			(net "M_F_CPU1_SB_DQ<7>")
		)
		(pad "255" smd rect
			(at 2.050034 35.275012 270)
			(size 0.519938 1.4986)
			(layers "F.Cu" "F.Mask" "F.Paste")
			(net "GND")
		)
		(pad "256" smd rect
			(at 2.050034 36.124896 270)
			(size 0.519938 1.4986)
			(layers "F.Cu" "F.Mask" "F.Paste")
			(net "M_F_CPU1_SB_DQ<10>")
		)
		(pad "257" smd rect
			(at 2.050034 36.975034 270)
			(size 0.519938 1.4986)
			(layers "F.Cu" "F.Mask" "F.Paste")
			(net "GND")
		)
		(pad "258" smd rect
			(at 2.050034 37.824918 270)
			(size 0.519938 1.4986)
			(layers "F.Cu" "F.Mask" "F.Paste")
			(net "M_F_CPU1_SB_DQ<11>")
		)
		(pad "259" smd rect
			(at 2.050034 38.675056 270)
			(size 0.519938 1.4986)
			(layers "F.Cu" "F.Mask" "F.Paste")
			(net "GND")
		)
		(pad "260" smd rect
			(at 2.050034 39.52494 270)
			(size 0.519938 1.4986)
			(layers "F.Cu" "F.Mask" "F.Paste")
			(net "M_F_CPU1_SB_DQS_DN<6>")
		)
		(pad "261" smd rect
			(at 2.050034 40.375078 270)
			(size 0.519938 1.4986)
			(layers "F.Cu" "F.Mask" "F.Paste")
			(net "M_F_CPU1_SB_DQS_DP<6>")
		)
		(pad "262" smd rect
			(at 2.050034 41.224962 270)
			(size 0.519938 1.4986)
			(layers "F.Cu" "F.Mask" "F.Paste")
			(net "GND")
		)
		(pad "263" smd rect
			(at 2.050034 42.0751 270)
			(size 0.519938 1.4986)
			(layers "F.Cu" "F.Mask" "F.Paste")
			(net "M_F_CPU1_SB_DQ<14>")
		)
		(pad "264" smd rect
			(at 2.050034 42.924984 270)
			(size 0.519938 1.4986)
			(layers "F.Cu" "F.Mask" "F.Paste")
			(net "GND")
		)
		(pad "265" smd rect
			(at 2.050034 43.775122 270)
			(size 0.519938 1.4986)
			(layers "F.Cu" "F.Mask" "F.Paste")
			(net "M_F_CPU1_SB_DQ<15>")
		)
		(pad "266" smd rect
			(at 2.050034 44.625006 270)
			(size 0.519938 1.4986)
			(layers "F.Cu" "F.Mask" "F.Paste")
			(net "GND")
		)
		(pad "267" smd rect
			(at 2.050034 45.47489 270)
			(size 0.519938 1.4986)
			(layers "F.Cu" "F.Mask" "F.Paste")
			(net "M_F_CPU1_SB_DQ<18>")
		)
		(pad "268" smd rect
			(at 2.050034 46.325028 270)
			(size 0.519938 1.4986)
			(layers "F.Cu" "F.Mask" "F.Paste")
			(net "GND")
		)
		(pad "269" smd rect
			(at 2.050034 47.174912 270)
			(size 0.519938 1.4986)
			(layers "F.Cu" "F.Mask" "F.Paste")
			(net "M_F_CPU1_SB_DQ<19>")
		)
		(pad "270" smd rect
			(at 2.050034 48.02505 270)
			(size 0.519938 1.4986)
			(layers "F.Cu" "F.Mask" "F.Paste")
			(net "GND")
		)
		(pad "271" smd rect
			(at 2.050034 48.874934 270)
			(size 0.519938 1.4986)
			(layers "F.Cu" "F.Mask" "F.Paste")
			(net "M_F_CPU1_SB_DQS_DN<7>")
		)
		(pad "272" smd rect
			(at 2.050034 49.725072 270)
			(size 0.519938 1.4986)
			(layers "F.Cu" "F.Mask" "F.Paste")
			(net "M_F_CPU1_SB_DQS_DP<7>")
		)
		(pad "273" smd rect
			(at 2.050034 50.574956 270)
			(size 0.519938 1.4986)
			(layers "F.Cu" "F.Mask" "F.Paste")
			(net "GND")
		)
		(pad "274" smd rect
			(at 2.050034 51.425094 270)
			(size 0.519938 1.4986)
			(layers "F.Cu" "F.Mask" "F.Paste")
			(net "M_F_CPU1_SB_DQ<22>")
		)
		(pad "275" smd rect
			(at 2.050034 52.274978 270)
			(size 0.519938 1.4986)
			(layers "F.Cu" "F.Mask" "F.Paste")
			(net "GND")
		)
		(pad "276" smd rect
			(at 2.050034 53.125116 270)
			(size 0.519938 1.4986)
			(layers "F.Cu" "F.Mask" "F.Paste")
			(net "M_F_CPU1_SB_DQ<23>")
		)
		(pad "277" smd rect
			(at 2.050034 53.975 270)
			(size 0.519938 1.4986)
			(layers "F.Cu" "F.Mask" "F.Paste")
			(net "GND")
		)
		(pad "278" smd rect
			(at 2.050034 54.824884 270)
			(size 0.519938 1.4986)
			(layers "F.Cu" "F.Mask" "F.Paste")
			(net "M_F_CPU1_SB_DQ<26>")
		)
		(pad "279" smd rect
			(at 2.050034 55.675022 270)
			(size 0.519938 1.4986)
			(layers "F.Cu" "F.Mask" "F.Paste")
			(net "GND")
		)
		(pad "280" smd rect
			(at 2.050034 56.524906 270)
			(size 0.519938 1.4986)
			(layers "F.Cu" "F.Mask" "F.Paste")
			(net "M_F_CPU1_SB_DQ<27>")
		)
		(pad "281" smd rect
			(at 2.050034 57.375044 270)
			(size 0.519938 1.4986)
			(layers "F.Cu" "F.Mask" "F.Paste")
			(net "GND")
		)
		(pad "282" smd rect
			(at 2.050034 58.224928 270)
			(size 0.519938 1.4986)
			(layers "F.Cu" "F.Mask" "F.Paste")
			(net "M_F_CPU1_SB_DQS_DN<8>")
		)
		(pad "283" smd rect
			(at 2.050034 59.075066 270)
			(size 0.519938 1.4986)
			(layers "F.Cu" "F.Mask" "F.Paste")
			(net "M_F_CPU1_SB_DQS_DP<8>")
		)
		(pad "284" smd rect
			(at 2.050034 59.92495 270)
			(size 0.519938 1.4986)
			(layers "F.Cu" "F.Mask" "F.Paste")
			(net "GND")
		)
		(pad "285" smd rect
			(at 2.050034 60.775088 270)
			(size 0.519938 1.4986)
			(layers "F.Cu" "F.Mask" "F.Paste")
			(net "M_F_CPU1_SB_DQ<30>")
		)
		(pad "286" smd rect
			(at 2.050034 61.624972 270)
			(size 0.519938 1.4986)
			(layers "F.Cu" "F.Mask" "F.Paste")
			(net "GND")
		)
		(pad "287" smd rect
			(at 2.050034 62.47511 270)
			(size 0.519938 1.4986)
			(layers "F.Cu" "F.Mask" "F.Paste")
			(net "M_F_CPU1_SB_DQ<31>")
		)
		(pad "288" smd rect
			(at 2.050034 63.324994 270)
			(size 0.519938 1.4986)
			(layers "F.Cu" "F.Mask" "F.Paste")
			(net "GND")
		)
		(pad "G1" thru_hole oval
			(at 0 -68.97497)
			(size 2.8194 1.5748)
			(drill oval 2.4384 1.1938)
			(layers "*.Cu" "*.Mask")
			(remove_unused_layers no)
			(net "GND")
			(clearance 0.127)
			(thermal_gap 0.127)
		)
		(pad "G2" thru_hole oval
			(at 0 3.875024)
			(size 2.8194 1.5748)
			(drill oval 2.4384 1.1938)
			(layers "*.Cu" "*.Mask")
			(remove_unused_layers no)
			(net "GND")
			(clearance 0.127)
			(thermal_gap 0.127)
		)
		(pad "G3" thru_hole oval
			(at 0 68.97497)
			(size 2.8194 1.5748)
			(drill oval 2.4384 1.1938)
			(layers "*.Cu" "*.Mask")
			(remove_unused_layers no)
			(net "GND")
			(clearance 0.127)
			(thermal_gap 0.127)
		)
	)
	(footprint ""
		(layer "F.Cu")
		(at 351.97288 -363.692948 -90)
		(property "Reference" "R2372"
			(at 0 0 270)
			(layer "F.SilkS")
			(hide yes)
			(effects
				(font
					(size 1.27 1.27)
				)
			)
		)
		(property "Value" ""
			(at 0 0 270)
			(layer "F.Fab")
			(effects
				(font
					(size 1.27 1.27)
				)
			)
		)
		(duplicate_pad_numbers_are_jumpers no)
		(fp_line
			(start -0.7874 0.4064)
			(end -0.7874 -0.4064)
			(stroke
				(width 0.1524)
				(type default)
			)
			(layer "F.SilkS")
		)
		(fp_line
			(start 0.7874 0.4064)
			(end -0.7874 0.4064)
			(stroke
				(width 0.1524)
				(type default)
			)
			(layer "F.SilkS")
		)
		(fp_line
			(start -0.7874 -0.4064)
			(end 0.7874 -0.4064)
			(stroke
				(width 0.1524)
				(type default)
			)
			(layer "F.SilkS")
		)
		(fp_line
			(start 0.7874 -0.4064)
			(end 0.7874 0.4064)
			(stroke
				(width 0.1524)
				(type default)
			)
			(layer "F.SilkS")
		)
		(fp_line
			(start -0.67945 0.3048)
			(end -0.67945 -0.305054)
			(stroke
				(width 0.1)
				(type default)
			)
			(layer "F.Fab")
		)
		(fp_line
			(start -0.12065 0.3048)
			(end -0.67945 0.3048)
			(stroke
				(width 0.1)
				(type default)
			)
			(layer "F.Fab")
		)
		(fp_line
			(start 0.120396 0.3048)
			(end 0.120396 0.2794)
			(stroke
				(width 0.1)
				(type default)
			)
			(layer "F.Fab")
		)
		(fp_line
			(start 0.67945 0.3048)
			(end 0.120396 0.3048)
			(stroke
				(width 0.1)
				(type default)
			)
			(layer "F.Fab")
		)
		(fp_line
			(start -0.12065 0.2794)
			(end -0.12065 0.3048)
			(stroke
				(width 0.1)
				(type default)
			)
			(layer "F.Fab")
		)
		(fp_line
			(start 0.120396 0.2794)
			(end -0.12065 0.2794)
			(stroke
				(width 0.1)
				(type default)
			)
			(layer "F.Fab")
		)
		(fp_line
			(start -0.12065 -0.2794)
			(end 0.12065 -0.2794)
			(stroke
				(width 0.1)
				(type default)
			)
			(layer "F.Fab")
		)
		(fp_line
			(start 0.12065 -0.2794)
			(end 0.12065 -0.3048)
			(stroke
				(width 0.1)
				(type default)
			)
			(layer "F.Fab")
		)
		(fp_line
			(start 0.12065 -0.3048)
			(end 0.67945 -0.3048)
			(stroke
				(width 0.1)
				(type default)
			)
			(layer "F.Fab")
		)
		(fp_line
			(start 0.67945 -0.3048)
			(end 0.67945 0.3048)
			(stroke
				(width 0.1)
				(type default)
			)
			(layer "F.Fab")
		)
		(fp_line
			(start -0.67945 -0.305054)
			(end -0.12065 -0.305054)
			(stroke
				(width 0.1)
				(type default)
			)
			(layer "F.Fab")
		)
		(fp_line
			(start -0.12065 -0.305054)
			(end -0.12065 -0.2794)
			(stroke
				(width 0.1)
				(type default)
			)
			(layer "F.Fab")
		)
		(pad "1" smd circle
			(at -0.40005 0 270)
			(size 0 0)
			(layers "F.Cu" "F.Mask" "F.Paste")
			(net "SMB_VR_3V3AUX_SDA_R3")
		)
		(pad "2" smd circle
			(at 0.40005 0 270)
			(size 0 0)
			(layers "F.Cu" "F.Mask" "F.Paste")
			(net "SMB_DIO_PVCCIN_CPU0")
		)
	)
	(footprint ""
		(layer "F.Cu")
		(at 22.991572 -162.20567 -90)
		(property "Reference" "PC389"
			(at 0 0 270)
			(layer "F.SilkS")
			(hide yes)
			(effects
				(font
					(size 1.27 1.27)
				)
			)
		)
		(property "Value" ""
			(at 0 0 270)
			(layer "F.Fab")
			(effects
				(font
					(size 1.27 1.27)
				)
			)
		)
		(duplicate_pad_numbers_are_jumpers no)
		(fp_line
			(start -0.7874 0.4064)
			(end -0.7874 -0.4064)
			(stroke
				(width 0.1524)
				(type default)
			)
			(layer "F.SilkS")
		)
		(fp_line
			(start 0.7874 0.4064)
			(end -0.7874 0.4064)
			(stroke
				(width 0.1524)
				(type default)
			)
			(layer "F.SilkS")
		)
		(fp_line
			(start -0.7874 -0.4064)
			(end 0.7874 -0.4064)
			(stroke
				(width 0.1524)
				(type default)
			)
			(layer "F.SilkS")
		)
		(fp_line
			(start 0.7874 -0.4064)
			(end 0.7874 0.4064)
			(stroke
				(width 0.1524)
				(type default)
			)
			(layer "F.SilkS")
		)
		(fp_line
			(start -0.67945 0.3048)
			(end -0.67945 -0.305054)
			(stroke
				(width 0.1)
				(type default)
			)
			(layer "F.Fab")
		)
		(fp_line
			(start -0.12065 0.3048)
			(end -0.67945 0.3048)
			(stroke
				(width 0.1)
				(type default)
			)
			(layer "F.Fab")
		)
		(fp_line
			(start 0.120396 0.3048)
			(end 0.120396 0.2794)
			(stroke
				(width 0.1)
				(type default)
			)
			(layer "F.Fab")
		)
		(fp_line
			(start 0.67945 0.3048)
			(end 0.120396 0.3048)
			(stroke
				(width 0.1)
				(type default)
			)
			(layer "F.Fab")
		)
		(fp_line
			(start -0.12065 0.2794)
			(end -0.12065 0.3048)
			(stroke
				(width 0.1)
				(type default)
			)
			(layer "F.Fab")
		)
		(fp_line
			(start 0.120396 0.2794)
			(end -0.12065 0.2794)
			(stroke
				(width 0.1)
				(type default)
			)
			(layer "F.Fab")
		)
		(fp_line
			(start -0.12065 -0.2794)
			(end 0.12065 -0.2794)
			(stroke
				(width 0.1)
				(type default)
			)
			(layer "F.Fab")
		)
		(fp_line
			(start 0.12065 -0.2794)
			(end 0.12065 -0.3048)
			(stroke
				(width 0.1)
				(type default)
			)
			(layer "F.Fab")
		)
		(fp_line
			(start 0.12065 -0.3048)
			(end 0.67945 -0.3048)
			(stroke
				(width 0.1)
				(type default)
			)
			(layer "F.Fab")
		)
		(fp_line
			(start 0.67945 -0.3048)
			(end 0.67945 0.3048)
			(stroke
				(width 0.1)
				(type default)
			)
			(layer "F.Fab")
		)
		(fp_line
			(start -0.67945 -0.305054)
			(end -0.12065 -0.305054)
			(stroke
				(width 0.1)
				(type default)
			)
			(layer "F.Fab")
		)
		(fp_line
			(start -0.12065 -0.305054)
			(end -0.12065 -0.2794)
			(stroke
				(width 0.1)
				(type default)
			)
			(layer "F.Fab")
		)
		(pad "1" smd circle
			(at -0.40005 0 270)
			(size 0 0)
			(layers "F.Cu" "F.Mask" "F.Paste")
			(net "SH_PVCCD_HV_CPU1_R")
		)
		(pad "2" smd circle
			(at 0.40005 0 270)
			(size 0 0)
			(layers "F.Cu" "F.Mask" "F.Paste")
			(net "VSENSE_PVCCD_HV_CPU1_DN")
		)
	)
	(footprint ""
		(layer "F.Cu")
		(at 464.799934 -22.29993)
		(property "Reference" "H106"
			(at -6.743954 -4.50088 0)
			(unlocked yes)
			(layer "F.SilkS")
			(effects
				(font
					(size 0.7874 0.5842)
					(thickness 0.1524)
				)
				(justify left)
			)
		)
		(property "Value" ""
			(at 0 0 0)
			(layer "F.Fab")
			(effects
				(font
					(size 1.27 1.27)
				)
			)
		)
		(duplicate_pad_numbers_are_jumpers no)
		(pad "1" thru_hole circle
			(at 0 0)
			(size 10.0076 10.0076)
			(drill 5.6134)
			(layers "*.Cu" "*.Mask")
			(remove_unused_layers no)
			(net "GND")
			(clearance -1.9431)
		)
	)
	(footprint ""
		(layer "F.Cu")
		(at 4.699 -49.113948 180)
		(property "Reference" "R580"
			(at 0 0 180)
			(layer "F.SilkS")
			(hide yes)
			(effects
				(font
					(size 1.27 1.27)
				)
			)
		)
		(property "Value" ""
			(at 0 0 180)
			(layer "F.Fab")
			(effects
				(font
					(size 1.27 1.27)
				)
			)
		)
		(duplicate_pad_numbers_are_jumpers no)
		(fp_line
			(start 0.7874 0.4064)
			(end -0.7874 0.4064)
			(stroke
				(width 0.1524)
				(type default)
			)
			(layer "F.SilkS")
		)
		(fp_line
			(start 0.7874 -0.4064)
			(end 0.7874 0.4064)
			(stroke
				(width 0.1524)
				(type default)
			)
			(layer "F.SilkS")
		)
		(fp_line
			(start -0.7874 0.4064)
			(end -0.7874 -0.4064)
			(stroke
				(width 0.1524)
				(type default)
			)
			(layer "F.SilkS")
		)
		(fp_line
			(start -0.7874 -0.4064)
			(end 0.7874 -0.4064)
			(stroke
				(width 0.1524)
				(type default)
			)
			(layer "F.SilkS")
		)
		(fp_line
			(start 0.67945 0.3048)
			(end 0.120396 0.3048)
			(stroke
				(width 0.1)
				(type default)
			)
			(layer "F.Fab")
		)
		(fp_line
			(start 0.67945 -0.3048)
			(end 0.67945 0.3048)
			(stroke
				(width 0.1)
				(type default)
			)
			(layer "F.Fab")
		)
		(fp_line
			(start 0.12065 -0.2794)
			(end 0.12065 -0.3048)
			(stroke
				(width 0.1)
				(type default)
			)
			(layer "F.Fab")
		)
		(fp_line
			(start 0.12065 -0.3048)
			(end 0.67945 -0.3048)
			(stroke
				(width 0.1)
				(type default)
			)
			(layer "F.Fab")
		)
		(fp_line
			(start 0.120396 0.3048)
			(end 0.120396 0.2794)
			(stroke
				(width 0.1)
				(type default)
			)
			(layer "F.Fab")
		)
		(fp_line
			(start 0.120396 0.2794)
			(end -0.12065 0.2794)
			(stroke
				(width 0.1)
				(type default)
			)
			(layer "F.Fab")
		)
		(fp_line
			(start -0.12065 0.3048)
			(end -0.67945 0.3048)
			(stroke
				(width 0.1)
				(type default)
			)
			(layer "F.Fab")
		)
		(fp_line
			(start -0.12065 0.2794)
			(end -0.12065 0.3048)
			(stroke
				(width 0.1)
				(type default)
			)
			(layer "F.Fab")
		)
		(fp_line
			(start -0.12065 -0.2794)
			(end 0.12065 -0.2794)
			(stroke
				(width 0.1)
				(type default)
			)
			(layer "F.Fab")
		)
		(fp_line
			(start -0.12065 -0.305054)
			(end -0.12065 -0.2794)
			(stroke
				(width 0.1)
				(type default)
			)
			(layer "F.Fab")
		)
		(fp_line
			(start -0.67945 0.3048)
			(end -0.67945 -0.305054)
			(stroke
				(width 0.1)
				(type default)
			)
			(layer "F.Fab")
		)
		(fp_line
			(start -0.67945 -0.305054)
			(end -0.12065 -0.305054)
			(stroke
				(width 0.1)
				(type default)
			)
			(layer "F.Fab")
		)
		(pad "1" smd circle
			(at -0.40005 0 180)
			(size 0 0)
			(layers "F.Cu" "F.Mask" "F.Paste")
			(net "SMB_HOST_3V3AUX_SDA_R5")
		)
		(pad "2" smd circle
			(at 0.40005 0 180)
			(size 0 0)
			(layers "F.Cu" "F.Mask" "F.Paste")
			(net "SMB_HOST_BMC_3V3AUX_SDA")
		)
	)
	(footprint ""
		(layer "F.Cu")
		(at 210.74888 -44.795948)
		(property "Reference" "R3531"
			(at 0 0 0)
			(layer "F.SilkS")
			(hide yes)
			(effects
				(font
					(size 1.27 1.27)
				)
			)
		)
		(property "Value" ""
			(at 0 0 0)
			(layer "F.Fab")
			(effects
				(font
					(size 1.27 1.27)
				)
			)
		)
		(duplicate_pad_numbers_are_jumpers no)
		(fp_line
			(start -0.7874 -0.4064)
			(end 0.7874 -0.4064)
			(stroke
				(width 0.1524)
				(type default)
			)
			(layer "F.SilkS")
		)
		(fp_line
			(start -0.7874 0.4064)
			(end -0.7874 -0.4064)
			(stroke
				(width 0.1524)
				(type default)
			)
			(layer "F.SilkS")
		)
		(fp_line
			(start 0.7874 -0.4064)
			(end 0.7874 0.4064)
			(stroke
				(width 0.1524)
				(type default)
			)
			(layer "F.SilkS")
		)
		(fp_line
			(start 0.7874 0.4064)
			(end -0.7874 0.4064)
			(stroke
				(width 0.1524)
				(type default)
			)
			(layer "F.SilkS")
		)
		(fp_line
			(start -0.67945 -0.305054)
			(end -0.12065 -0.305054)
			(stroke
				(width 0.1)
				(type default)
			)
			(layer "F.Fab")
		)
		(fp_line
			(start -0.67945 0.3048)
			(end -0.67945 -0.305054)
			(stroke
				(width 0.1)
				(type default)
			)
			(layer "F.Fab")
		)
		(fp_line
			(start -0.12065 -0.305054)
			(end -0.12065 -0.2794)
			(stroke
				(width 0.1)
				(type default)
			)
			(layer "F.Fab")
		)
		(fp_line
			(start -0.12065 -0.2794)
			(end 0.12065 -0.2794)
			(stroke
				(width 0.1)
				(type default)
			)
			(layer "F.Fab")
		)
		(fp_line
			(start -0.12065 0.2794)
			(end -0.12065 0.3048)
			(stroke
				(width 0.1)
				(type default)
			)
			(layer "F.Fab")
		)
		(fp_line
			(start -0.12065 0.3048)
			(end -0.67945 0.3048)
			(stroke
				(width 0.1)
				(type default)
			)
			(layer "F.Fab")
		)
		(fp_line
			(start 0.120396 0.2794)
			(end -0.12065 0.2794)
			(stroke
				(width 0.1)
				(type default)
			)
			(layer "F.Fab")
		)
		(fp_line
			(start 0.120396 0.3048)
			(end 0.120396 0.2794)
			(stroke
				(width 0.1)
				(type default)
			)
			(layer "F.Fab")
		)
		(fp_line
			(start 0.12065 -0.3048)
			(end 0.67945 -0.3048)
			(stroke
				(width 0.1)
				(type default)
			)
			(layer "F.Fab")
		)
		(fp_line
			(start 0.12065 -0.2794)
			(end 0.12065 -0.3048)
			(stroke
				(width 0.1)
				(type default)
			)
			(layer "F.Fab")
		)
		(fp_line
			(start 0.67945 -0.3048)
			(end 0.67945 0.3048)
			(stroke
				(width 0.1)
				(type default)
			)
			(layer "F.Fab")
		)
		(fp_line
			(start 0.67945 0.3048)
			(end 0.120396 0.3048)
			(stroke
				(width 0.1)
				(type default)
			)
			(layer "F.Fab")
		)
		(pad "1" smd circle
			(at -0.40005 0)
			(size 0 0)
			(layers "F.Cu" "F.Mask" "F.Paste")
			(net "SMB_PCIE_E1S_ISO_EN")
		)
		(pad "2" smd circle
			(at 0.40005 0)
			(size 0 0)
			(layers "F.Cu" "F.Mask" "F.Paste")
			(net "SMB_PCIE_E1S_ISO_EN_R")
		)
	)
	(footprint ""
		(layer "F.Cu")
		(at 320.190622 -61.864748)
		(property "Reference" "R1475"
			(at 0 0 0)
			(layer "F.SilkS")
			(hide yes)
			(effects
				(font
					(size 1.27 1.27)
				)
			)
		)
		(property "Value" ""
			(at 0 0 0)
			(layer "F.Fab")
			(effects
				(font
					(size 1.27 1.27)
				)
			)
		)
		(duplicate_pad_numbers_are_jumpers no)
		(fp_line
			(start -0.7874 -0.4064)
			(end 0.7874 -0.4064)
			(stroke
				(width 0.1524)
				(type default)
			)
			(layer "F.SilkS")
		)
		(fp_line
			(start -0.7874 0.4064)
			(end -0.7874 -0.4064)
			(stroke
				(width 0.1524)
				(type default)
			)
			(layer "F.SilkS")
		)
		(fp_line
			(start 0.7874 -0.4064)
			(end 0.7874 0.4064)
			(stroke
				(width 0.1524)
				(type default)
			)
			(layer "F.SilkS")
		)
		(fp_line
			(start 0.7874 0.4064)
			(end -0.7874 0.4064)
			(stroke
				(width 0.1524)
				(type default)
			)
			(layer "F.SilkS")
		)
		(fp_line
			(start -0.67945 -0.305054)
			(end -0.12065 -0.305054)
			(stroke
				(width 0.1)
				(type default)
			)
			(layer "F.Fab")
		)
		(fp_line
			(start -0.67945 0.3048)
			(end -0.67945 -0.305054)
			(stroke
				(width 0.1)
				(type default)
			)
			(layer "F.Fab")
		)
		(fp_line
			(start -0.12065 -0.305054)
			(end -0.12065 -0.2794)
			(stroke
				(width 0.1)
				(type default)
			)
			(layer "F.Fab")
		)
		(fp_line
			(start -0.12065 -0.2794)
			(end 0.12065 -0.2794)
			(stroke
				(width 0.1)
				(type default)
			)
			(layer "F.Fab")
		)
		(fp_line
			(start -0.12065 0.2794)
			(end -0.12065 0.3048)
			(stroke
				(width 0.1)
				(type default)
			)
			(layer "F.Fab")
		)
		(fp_line
			(start -0.12065 0.3048)
			(end -0.67945 0.3048)
			(stroke
				(width 0.1)
				(type default)
			)
			(layer "F.Fab")
		)
		(fp_line
			(start 0.120396 0.2794)
			(end -0.12065 0.2794)
			(stroke
				(width 0.1)
				(type default)
			)
			(layer "F.Fab")
		)
		(fp_line
			(start 0.120396 0.3048)
			(end 0.120396 0.2794)
			(stroke
				(width 0.1)
				(type default)
			)
			(layer "F.Fab")
		)
		(fp_line
			(start 0.12065 -0.3048)
			(end 0.67945 -0.3048)
			(stroke
				(width 0.1)
				(type default)
			)
			(layer "F.Fab")
		)
		(fp_line
			(start 0.12065 -0.2794)
			(end 0.12065 -0.3048)
			(stroke
				(width 0.1)
				(type default)
			)
			(layer "F.Fab")
		)
		(fp_line
			(start 0.67945 -0.3048)
			(end 0.67945 0.3048)
			(stroke
				(width 0.1)
				(type default)
			)
			(layer "F.Fab")
		)
		(fp_line
			(start 0.67945 0.3048)
			(end 0.120396 0.3048)
			(stroke
				(width 0.1)
				(type default)
			)
			(layer "F.Fab")
		)
		(pad "1" smd circle
			(at -0.40005 0)
			(size 0 0)
			(layers "F.Cu" "F.Mask" "F.Paste")
			(net "P3V3_AUX")
		)
		(pad "2" smd circle
			(at 0.40005 0)
			(size 0 0)
			(layers "F.Cu" "F.Mask" "F.Paste")
			(net "FM_PCH_RING_OSC_BYPASS_MGPIO_TE")
		)
	)
	(footprint ""
		(layer "F.Cu")
		(at 335.5086 -69.002148 90)
		(property "Reference" "Y7"
			(at 3.099816 -1.5494 0)
			(unlocked yes)
			(layer "F.SilkS")
			(effects
				(font
					(size 0.7874 0.5842)
					(thickness 0.1524)
				)
				(justify left)
			)
		)
		(property "Value" ""
			(at 0 0 90)
			(layer "F.Fab")
			(effects
				(font
					(size 1.27 1.27)
				)
			)
		)
		(duplicate_pad_numbers_are_jumpers no)
		(fp_line
			(start 1.6002 -1.9558)
			(end 1.6002 1.9558)
			(stroke
				(width 0.1524)
				(type default)
			)
			(layer "F.SilkS")
		)
		(fp_line
			(start -1.6002 -1.9558)
			(end 1.6002 -1.9558)
			(stroke
				(width 0.1524)
				(type default)
			)
			(layer "F.SilkS")
		)
		(fp_line
			(start 1.6002 1.9558)
			(end -1.6002 1.9558)
			(stroke
				(width 0.1524)
				(type default)
			)
			(layer "F.SilkS")
		)
		(fp_line
			(start -1.6002 1.9558)
			(end -1.6002 -1.9558)
			(stroke
				(width 0.1524)
				(type default)
			)
			(layer "F.SilkS")
		)
		(fp_poly
			(pts
				(xy -0.820166 -4.432046) (xy -1.302766 -5.524246) (xy -0.235966 -5.524246)
			)
			(stroke
				(width 0)
				(type default)
			)
			(fill yes)
			(layer "F.SilkS")
		)
		(fp_line
			(start 1.299972 -1.649984)
			(end 1.299972 1.649984)
			(stroke
				(width 0.1)
				(type default)
			)
			(layer "F.Fab")
		)
		(fp_line
			(start -1.299972 -1.649984)
			(end 1.299972 -1.649984)
			(stroke
				(width 0.1)
				(type default)
			)
			(layer "F.Fab")
		)
		(fp_line
			(start 1.299972 1.649984)
			(end -1.299972 1.649984)
			(stroke
				(width 0.1)
				(type default)
			)
			(layer "F.Fab")
		)
		(fp_line
			(start -1.299972 1.649984)
			(end -1.299972 -1.649984)
			(stroke
				(width 0.1)
				(type default)
			)
			(layer "F.Fab")
		)
		(fp_poly
			(pts
				(xy -1.7145 -1.0668) (xy -2.8067 -1.651) (xy -2.8067 -0.5842)
			)
			(stroke
				(width 0)
				(type default)
			)
			(fill yes)
			(layer "F.Fab")
		)
		(pad "1" smd rect
			(at -0.849884 -1.100074 90)
			(size 1.2192 1.4224)
			(layers "F.Cu" "F.Mask" "F.Paste")
			(net "XTAL_PCH_25M_IN_R")
		)
		(pad "2" smd rect
			(at -0.849884 1.100074 90)
			(size 1.2192 1.4224)
			(layers "F.Cu" "F.Mask" "F.Paste")
			(net "GND")
		)
		(pad "3" smd rect
			(at 0.849884 1.100074 90)
			(size 1.2192 1.4224)
			(layers "F.Cu" "F.Mask" "F.Paste")
			(net "XTAL_PCH_25M_OUT")
		)
		(pad "4" smd rect
			(at 0.849884 -1.100074 90)
			(size 1.2192 1.4224)
			(layers "F.Cu" "F.Mask" "F.Paste")
			(net "GND")
		)
	)
	(footprint ""
		(layer "F.Cu")
		(at 369.129818 -387.779006 180)
		(property "Reference" "R4164"
			(at 0 0 180)
			(layer "F.SilkS")
			(hide yes)
			(effects
				(font
					(size 1.27 1.27)
				)
			)
		)
		(property "Value" ""
			(at 0 0 180)
			(layer "F.Fab")
			(effects
				(font
					(size 1.27 1.27)
				)
			)
		)
		(duplicate_pad_numbers_are_jumpers no)
		(fp_line
			(start 0.7874 0.4064)
			(end -0.7874 0.4064)
			(stroke
				(width 0.1524)
				(type default)
			)
			(layer "F.SilkS")
		)
		(fp_line
			(start 0.7874 -0.4064)
			(end 0.7874 0.4064)
			(stroke
				(width 0.1524)
				(type default)
			)
			(layer "F.SilkS")
		)
		(fp_line
			(start -0.7874 0.4064)
			(end -0.7874 -0.4064)
			(stroke
				(width 0.1524)
				(type default)
			)
			(layer "F.SilkS")
		)
		(fp_line
			(start -0.7874 -0.4064)
			(end 0.7874 -0.4064)
			(stroke
				(width 0.1524)
				(type default)
			)
			(layer "F.SilkS")
		)
		(fp_line
			(start 0.67945 0.3048)
			(end 0.120396 0.3048)
			(stroke
				(width 0.1)
				(type default)
			)
			(layer "F.Fab")
		)
		(fp_line
			(start 0.67945 -0.3048)
			(end 0.67945 0.3048)
			(stroke
				(width 0.1)
				(type default)
			)
			(layer "F.Fab")
		)
		(fp_line
			(start 0.12065 -0.2794)
			(end 0.12065 -0.3048)
			(stroke
				(width 0.1)
				(type default)
			)
			(layer "F.Fab")
		)
		(fp_line
			(start 0.12065 -0.3048)
			(end 0.67945 -0.3048)
			(stroke
				(width 0.1)
				(type default)
			)
			(layer "F.Fab")
		)
		(fp_line
			(start 0.120396 0.3048)
			(end 0.120396 0.2794)
			(stroke
				(width 0.1)
				(type default)
			)
			(layer "F.Fab")
		)
		(fp_line
			(start 0.120396 0.2794)
			(end -0.12065 0.2794)
			(stroke
				(width 0.1)
				(type default)
			)
			(layer "F.Fab")
		)
		(fp_line
			(start -0.12065 0.3048)
			(end -0.67945 0.3048)
			(stroke
				(width 0.1)
				(type default)
			)
			(layer "F.Fab")
		)
		(fp_line
			(start -0.12065 0.2794)
			(end -0.12065 0.3048)
			(stroke
				(width 0.1)
				(type default)
			)
			(layer "F.Fab")
		)
		(fp_line
			(start -0.12065 -0.2794)
			(end 0.12065 -0.2794)
			(stroke
				(width 0.1)
				(type default)
			)
			(layer "F.Fab")
		)
		(fp_line
			(start -0.12065 -0.305054)
			(end -0.12065 -0.2794)
			(stroke
				(width 0.1)
				(type default)
			)
			(layer "F.Fab")
		)
		(fp_line
			(start -0.67945 0.3048)
			(end -0.67945 -0.305054)
			(stroke
				(width 0.1)
				(type default)
			)
			(layer "F.Fab")
		)
		(fp_line
			(start -0.67945 -0.305054)
			(end -0.12065 -0.305054)
			(stroke
				(width 0.1)
				(type default)
			)
			(layer "F.Fab")
		)
		(pad "1" smd circle
			(at -0.40005 0 180)
			(size 0 0)
			(layers "F.Cu" "F.Mask" "F.Paste")
			(net "P3V3_AUX")
		)
		(pad "2" smd circle
			(at 0.40005 0 180)
			(size 0 0)
			(layers "F.Cu" "F.Mask" "F.Paste")
			(net "GPU_3V3IO_RSVD1_N")
		)
	)
	(footprint ""
		(layer "F.Cu")
		(at 67.680078 -408.517344 -90)
		(property "Reference" "C696"
			(at 0 0 270)
			(layer "F.SilkS")
			(hide yes)
			(effects
				(font
					(size 1.27 1.27)
				)
			)
		)
		(property "Value" ""
			(at 0 0 270)
			(layer "F.Fab")
			(effects
				(font
					(size 1.27 1.27)
				)
			)
		)
		(duplicate_pad_numbers_are_jumpers no)
		(fp_line
			(start -0.299974 0.150114)
			(end -0.299974 -0.150114)
			(stroke
				(width 0.1)
				(type default)
			)
			(layer "F.Fab")
		)
		(fp_line
			(start 0.299974 0.150114)
			(end -0.299974 0.150114)
			(stroke
				(width 0.1)
				(type default)
			)
			(layer "F.Fab")
		)
		(fp_line
			(start -0.299974 -0.150114)
			(end 0.299974 -0.150114)
			(stroke
				(width 0.1)
				(type default)
			)
			(layer "F.Fab")
		)
		(fp_line
			(start 0.299974 -0.150114)
			(end 0.299974 0.150114)
			(stroke
				(width 0.1)
				(type default)
			)
			(layer "F.Fab")
		)
		(pad "1" smd rect
			(at -0.2667 0 270)
			(size 0.3048 0.381)
			(layers "F.Cu" "F.Mask" "F.Paste")
			(net "P5E_CPU1_PE4_TX_C_DN<6>")
		)
		(pad "2" smd rect
			(at 0.2667 0 270)
			(size 0.3048 0.381)
			(layers "F.Cu" "F.Mask" "F.Paste")
			(net "P5E_CPU1_PE4_TX_DN<6>")
		)
	)
	(footprint ""
		(layer "F.Cu")
		(at 185.230008 -408.912822 180)
		(property "Reference" "PR3926"
			(at 0 0 180)
			(layer "F.SilkS")
			(hide yes)
			(effects
				(font
					(size 1.27 1.27)
				)
			)
		)
		(property "Value" ""
			(at 0 0 180)
			(layer "F.Fab")
			(effects
				(font
					(size 1.27 1.27)
				)
			)
		)
		(duplicate_pad_numbers_are_jumpers no)
		(fp_line
			(start 0.7874 0.4064)
			(end -0.7874 0.4064)
			(stroke
				(width 0.1524)
				(type default)
			)
			(layer "F.SilkS")
		)
		(fp_line
			(start 0.7874 -0.4064)
			(end 0.7874 0.4064)
			(stroke
				(width 0.1524)
				(type default)
			)
			(layer "F.SilkS")
		)
		(fp_line
			(start -0.7874 0.4064)
			(end -0.7874 -0.4064)
			(stroke
				(width 0.1524)
				(type default)
			)
			(layer "F.SilkS")
		)
		(fp_line
			(start -0.7874 -0.4064)
			(end 0.7874 -0.4064)
			(stroke
				(width 0.1524)
				(type default)
			)
			(layer "F.SilkS")
		)
		(fp_line
			(start 0.67945 0.3048)
			(end 0.120396 0.3048)
			(stroke
				(width 0.1)
				(type default)
			)
			(layer "F.Fab")
		)
		(fp_line
			(start 0.67945 -0.3048)
			(end 0.67945 0.3048)
			(stroke
				(width 0.1)
				(type default)
			)
			(layer "F.Fab")
		)
		(fp_line
			(start 0.12065 -0.2794)
			(end 0.12065 -0.3048)
			(stroke
				(width 0.1)
				(type default)
			)
			(layer "F.Fab")
		)
		(fp_line
			(start 0.12065 -0.3048)
			(end 0.67945 -0.3048)
			(stroke
				(width 0.1)
				(type default)
			)
			(layer "F.Fab")
		)
		(fp_line
			(start 0.120396 0.3048)
			(end 0.120396 0.2794)
			(stroke
				(width 0.1)
				(type default)
			)
			(layer "F.Fab")
		)
		(fp_line
			(start 0.120396 0.2794)
			(end -0.12065 0.2794)
			(stroke
				(width 0.1)
				(type default)
			)
			(layer "F.Fab")
		)
		(fp_line
			(start -0.12065 0.3048)
			(end -0.67945 0.3048)
			(stroke
				(width 0.1)
				(type default)
			)
			(layer "F.Fab")
		)
		(fp_line
			(start -0.12065 0.2794)
			(end -0.12065 0.3048)
			(stroke
				(width 0.1)
				(type default)
			)
			(layer "F.Fab")
		)
		(fp_line
			(start -0.12065 -0.2794)
			(end 0.12065 -0.2794)
			(stroke
				(width 0.1)
				(type default)
			)
			(layer "F.Fab")
		)
		(fp_line
			(start -0.12065 -0.305054)
			(end -0.12065 -0.2794)
			(stroke
				(width 0.1)
				(type default)
			)
			(layer "F.Fab")
		)
		(fp_line
			(start -0.67945 0.3048)
			(end -0.67945 -0.305054)
			(stroke
				(width 0.1)
				(type default)
			)
			(layer "F.Fab")
		)
		(fp_line
			(start -0.67945 -0.305054)
			(end -0.12065 -0.305054)
			(stroke
				(width 0.1)
				(type default)
			)
			(layer "F.Fab")
		)
		(pad "1" smd circle
			(at -0.40005 0 180)
			(size 0 0)
			(layers "F.Cu" "F.Mask" "F.Paste")
			(net "P12V_PSU")
		)
		(pad "2" smd circle
			(at 0.40005 0 180)
			(size 0 0)
			(layers "F.Cu" "F.Mask" "F.Paste")
			(net "HSC_VSENSE")
		)
	)
	(footprint ""
		(layer "F.Cu")
		(at 125.264926 -119.810784 -90)
		(property "Reference" "R861"
			(at 0 0 270)
			(layer "F.SilkS")
			(hide yes)
			(effects
				(font
					(size 1.27 1.27)
				)
			)
		)
		(property "Value" ""
			(at 0 0 270)
			(layer "F.Fab")
			(effects
				(font
					(size 1.27 1.27)
				)
			)
		)
		(duplicate_pad_numbers_are_jumpers no)
		(fp_line
			(start -0.7874 0.4064)
			(end -0.7874 -0.4064)
			(stroke
				(width 0.1524)
				(type default)
			)
			(layer "F.SilkS")
		)
		(fp_line
			(start 0.7874 0.4064)
			(end -0.7874 0.4064)
			(stroke
				(width 0.1524)
				(type default)
			)
			(layer "F.SilkS")
		)
		(fp_line
			(start -0.7874 -0.4064)
			(end 0.7874 -0.4064)
			(stroke
				(width 0.1524)
				(type default)
			)
			(layer "F.SilkS")
		)
		(fp_line
			(start 0.7874 -0.4064)
			(end 0.7874 0.4064)
			(stroke
				(width 0.1524)
				(type default)
			)
			(layer "F.SilkS")
		)
		(fp_line
			(start -0.67945 0.3048)
			(end -0.67945 -0.305054)
			(stroke
				(width 0.1)
				(type default)
			)
			(layer "F.Fab")
		)
		(fp_line
			(start -0.12065 0.3048)
			(end -0.67945 0.3048)
			(stroke
				(width 0.1)
				(type default)
			)
			(layer "F.Fab")
		)
		(fp_line
			(start 0.120396 0.3048)
			(end 0.120396 0.2794)
			(stroke
				(width 0.1)
				(type default)
			)
			(layer "F.Fab")
		)
		(fp_line
			(start 0.67945 0.3048)
			(end 0.120396 0.3048)
			(stroke
				(width 0.1)
				(type default)
			)
			(layer "F.Fab")
		)
		(fp_line
			(start -0.12065 0.2794)
			(end -0.12065 0.3048)
			(stroke
				(width 0.1)
				(type default)
			)
			(layer "F.Fab")
		)
		(fp_line
			(start 0.120396 0.2794)
			(end -0.12065 0.2794)
			(stroke
				(width 0.1)
				(type default)
			)
			(layer "F.Fab")
		)
		(fp_line
			(start -0.12065 -0.2794)
			(end 0.12065 -0.2794)
			(stroke
				(width 0.1)
				(type default)
			)
			(layer "F.Fab")
		)
		(fp_line
			(start 0.12065 -0.2794)
			(end 0.12065 -0.3048)
			(stroke
				(width 0.1)
				(type default)
			)
			(layer "F.Fab")
		)
		(fp_line
			(start 0.12065 -0.3048)
			(end 0.67945 -0.3048)
			(stroke
				(width 0.1)
				(type default)
			)
			(layer "F.Fab")
		)
		(fp_line
			(start 0.67945 -0.3048)
			(end 0.67945 0.3048)
			(stroke
				(width 0.1)
				(type default)
			)
			(layer "F.Fab")
		)
		(fp_line
			(start -0.67945 -0.305054)
			(end -0.12065 -0.305054)
			(stroke
				(width 0.1)
				(type default)
			)
			(layer "F.Fab")
		)
		(fp_line
			(start -0.12065 -0.305054)
			(end -0.12065 -0.2794)
			(stroke
				(width 0.1)
				(type default)
			)
			(layer "F.Fab")
		)
		(pad "1" smd circle
			(at -0.40005 0 270)
			(size 0 0)
			(layers "F.Cu" "F.Mask" "F.Paste")
			(net "RST_CPU1_DRAM_EF_N")
		)
		(pad "2" smd circle
			(at 0.40005 0 270)
			(size 0 0)
			(layers "F.Cu" "F.Mask" "F.Paste")
			(net "RST_CPU1_DRAM_EF_PLD_N")
		)
	)
	(footprint ""
		(layer "F.Cu")
		(at 292.61054 -93.482414 180)
		(property "Reference" "R1331"
			(at 0 0 180)
			(layer "F.SilkS")
			(hide yes)
			(effects
				(font
					(size 1.27 1.27)
				)
			)
		)
		(property "Value" ""
			(at 0 0 180)
			(layer "F.Fab")
			(effects
				(font
					(size 1.27 1.27)
				)
			)
		)
		(duplicate_pad_numbers_are_jumpers no)
		(fp_line
			(start 0.7874 0.4064)
			(end -0.7874 0.4064)
			(stroke
				(width 0.1524)
				(type default)
			)
			(layer "F.SilkS")
		)
		(fp_line
			(start 0.7874 -0.4064)
			(end 0.7874 0.4064)
			(stroke
				(width 0.1524)
				(type default)
			)
			(layer "F.SilkS")
		)
		(fp_line
			(start -0.7874 0.4064)
			(end -0.7874 -0.4064)
			(stroke
				(width 0.1524)
				(type default)
			)
			(layer "F.SilkS")
		)
		(fp_line
			(start -0.7874 -0.4064)
			(end 0.7874 -0.4064)
			(stroke
				(width 0.1524)
				(type default)
			)
			(layer "F.SilkS")
		)
		(fp_line
			(start 0.67945 0.3048)
			(end 0.120396 0.3048)
			(stroke
				(width 0.1)
				(type default)
			)
			(layer "F.Fab")
		)
		(fp_line
			(start 0.67945 -0.3048)
			(end 0.67945 0.3048)
			(stroke
				(width 0.1)
				(type default)
			)
			(layer "F.Fab")
		)
		(fp_line
			(start 0.12065 -0.2794)
			(end 0.12065 -0.3048)
			(stroke
				(width 0.1)
				(type default)
			)
			(layer "F.Fab")
		)
		(fp_line
			(start 0.12065 -0.3048)
			(end 0.67945 -0.3048)
			(stroke
				(width 0.1)
				(type default)
			)
			(layer "F.Fab")
		)
		(fp_line
			(start 0.120396 0.3048)
			(end 0.120396 0.2794)
			(stroke
				(width 0.1)
				(type default)
			)
			(layer "F.Fab")
		)
		(fp_line
			(start 0.120396 0.2794)
			(end -0.12065 0.2794)
			(stroke
				(width 0.1)
				(type default)
			)
			(layer "F.Fab")
		)
		(fp_line
			(start -0.12065 0.3048)
			(end -0.67945 0.3048)
			(stroke
				(width 0.1)
				(type default)
			)
			(layer "F.Fab")
		)
		(fp_line
			(start -0.12065 0.2794)
			(end -0.12065 0.3048)
			(stroke
				(width 0.1)
				(type default)
			)
			(layer "F.Fab")
		)
		(fp_line
			(start -0.12065 -0.2794)
			(end 0.12065 -0.2794)
			(stroke
				(width 0.1)
				(type default)
			)
			(layer "F.Fab")
		)
		(fp_line
			(start -0.12065 -0.305054)
			(end -0.12065 -0.2794)
			(stroke
				(width 0.1)
				(type default)
			)
			(layer "F.Fab")
		)
		(fp_line
			(start -0.67945 0.3048)
			(end -0.67945 -0.305054)
			(stroke
				(width 0.1)
				(type default)
			)
			(layer "F.Fab")
		)
		(fp_line
			(start -0.67945 -0.305054)
			(end -0.12065 -0.305054)
			(stroke
				(width 0.1)
				(type default)
			)
			(layer "F.Fab")
		)
		(pad "1" smd circle
			(at -0.40005 0 180)
			(size 0 0)
			(layers "F.Cu" "F.Mask" "F.Paste")
			(net "P3V3_AUX")
		)
		(pad "2" smd circle
			(at 0.40005 0 180)
			(size 0 0)
			(layers "F.Cu" "F.Mask" "F.Paste")
			(net "SMB_FRU_3V3AUX_SCL")
		)
	)
	(footprint ""
		(layer "F.Cu")
		(at 304.034952 -54.012592 180)
		(property "Reference" "R1341"
			(at 0 0 180)
			(layer "F.SilkS")
			(hide yes)
			(effects
				(font
					(size 1.27 1.27)
				)
			)
		)
		(property "Value" ""
			(at 0 0 180)
			(layer "F.Fab")
			(effects
				(font
					(size 1.27 1.27)
				)
			)
		)
		(duplicate_pad_numbers_are_jumpers no)
		(fp_line
			(start 0.7874 0.4064)
			(end -0.7874 0.4064)
			(stroke
				(width 0.1524)
				(type default)
			)
			(layer "F.SilkS")
		)
		(fp_line
			(start 0.7874 -0.4064)
			(end 0.7874 0.4064)
			(stroke
				(width 0.1524)
				(type default)
			)
			(layer "F.SilkS")
		)
		(fp_line
			(start -0.7874 0.4064)
			(end -0.7874 -0.4064)
			(stroke
				(width 0.1524)
				(type default)
			)
			(layer "F.SilkS")
		)
		(fp_line
			(start -0.7874 -0.4064)
			(end 0.7874 -0.4064)
			(stroke
				(width 0.1524)
				(type default)
			)
			(layer "F.SilkS")
		)
		(fp_line
			(start 0.67945 0.3048)
			(end 0.120396 0.3048)
			(stroke
				(width 0.1)
				(type default)
			)
			(layer "F.Fab")
		)
		(fp_line
			(start 0.67945 -0.3048)
			(end 0.67945 0.3048)
			(stroke
				(width 0.1)
				(type default)
			)
			(layer "F.Fab")
		)
		(fp_line
			(start 0.12065 -0.2794)
			(end 0.12065 -0.3048)
			(stroke
				(width 0.1)
				(type default)
			)
			(layer "F.Fab")
		)
		(fp_line
			(start 0.12065 -0.3048)
			(end 0.67945 -0.3048)
			(stroke
				(width 0.1)
				(type default)
			)
			(layer "F.Fab")
		)
		(fp_line
			(start 0.120396 0.3048)
			(end 0.120396 0.2794)
			(stroke
				(width 0.1)
				(type default)
			)
			(layer "F.Fab")
		)
		(fp_line
			(start 0.120396 0.2794)
			(end -0.12065 0.2794)
			(stroke
				(width 0.1)
				(type default)
			)
			(layer "F.Fab")
		)
		(fp_line
			(start -0.12065 0.3048)
			(end -0.67945 0.3048)
			(stroke
				(width 0.1)
				(type default)
			)
			(layer "F.Fab")
		)
		(fp_line
			(start -0.12065 0.2794)
			(end -0.12065 0.3048)
			(stroke
				(width 0.1)
				(type default)
			)
			(layer "F.Fab")
		)
		(fp_line
			(start -0.12065 -0.2794)
			(end 0.12065 -0.2794)
			(stroke
				(width 0.1)
				(type default)
			)
			(layer "F.Fab")
		)
		(fp_line
			(start -0.12065 -0.305054)
			(end -0.12065 -0.2794)
			(stroke
				(width 0.1)
				(type default)
			)
			(layer "F.Fab")
		)
		(fp_line
			(start -0.67945 0.3048)
			(end -0.67945 -0.305054)
			(stroke
				(width 0.1)
				(type default)
			)
			(layer "F.Fab")
		)
		(fp_line
			(start -0.67945 -0.305054)
			(end -0.12065 -0.305054)
			(stroke
				(width 0.1)
				(type default)
			)
			(layer "F.Fab")
		)
		(pad "1" smd circle
			(at -0.40005 0 180)
			(size 0 0)
			(layers "F.Cu" "F.Mask" "F.Paste")
			(net "FM_ADR_COMPLETE")
		)
		(pad "2" smd circle
			(at 0.40005 0 180)
			(size 0 0)
			(layers "F.Cu" "F.Mask" "F.Paste")
			(net "GND")
		)
	)
	(footprint ""
		(layer "F.Cu")
		(at 330.848716 -13.985748)
		(property "Reference" "U154"
			(at 3.25374 0.200152 0)
			(unlocked yes)
			(layer "F.SilkS")
			(effects
				(font
					(size 0.7874 0.5842)
					(thickness 0.1524)
				)
				(justify left)
			)
		)
		(property "Value" ""
			(at 0 0 0)
			(layer "F.Fab")
			(effects
				(font
					(size 1.27 1.27)
				)
			)
		)
		(duplicate_pad_numbers_are_jumpers no)
		(fp_line
			(start -1.400048 1.100074)
			(end -1.400048 -1.100074)
			(stroke
				(width 0.1524)
				(type default)
			)
			(layer "F.SilkS")
		)
		(fp_line
			(start 1.400048 -1.100074)
			(end -1.400048 -1.100074)
			(stroke
				(width 0.1524)
				(type default)
			)
			(layer "F.SilkS")
		)
		(fp_line
			(start 1.400048 -1.100074)
			(end 1.400048 1.100074)
			(stroke
				(width 0.1524)
				(type default)
			)
			(layer "F.SilkS")
		)
		(fp_line
			(start 1.400048 1.100074)
			(end -1.400048 1.100074)
			(stroke
				(width 0.1524)
				(type default)
			)
			(layer "F.SilkS")
		)
		(fp_poly
			(pts
				(xy -0.812292 -1.192276) (xy -0.534416 -2.02565) (xy 0.021082 -1.470152)
			)
			(stroke
				(width 0)
				(type default)
			)
			(fill yes)
			(layer "F.SilkS")
		)
		(fp_line
			(start -0.674878 -1.100074)
			(end 0.674878 -1.100074)
			(stroke
				(width 0.1)
				(type default)
			)
			(layer "F.Fab")
		)
		(fp_line
			(start -0.674878 1.100074)
			(end -0.674878 -1.100074)
			(stroke
				(width 0.1)
				(type default)
			)
			(layer "F.Fab")
		)
		(fp_line
			(start 0.674878 -1.100074)
			(end 0.674878 1.100074)
			(stroke
				(width 0.1)
				(type default)
			)
			(layer "F.Fab")
		)
		(fp_line
			(start 0.674878 1.100074)
			(end -0.674878 1.100074)
			(stroke
				(width 0.1)
				(type default)
			)
			(layer "F.Fab")
		)
		(fp_poly
			(pts
				(xy -1.590548 -0.649986) (xy -2.606548 -1.157986) (xy -2.606548 -0.141986)
			)
			(stroke
				(width 0)
				(type default)
			)
			(fill yes)
			(layer "F.Fab")
		)
		(pad "1" smd rect
			(at -0.94996 -0.649986 270)
			(size 0.4318 0.6096)
			(layers "F.Cu" "F.Mask" "F.Paste")
			(net "NC_ESPI_PLD_R_EN_BUF")
		)
		(pad "2" smd rect
			(at -0.94996 0 270)
			(size 0.4318 0.6096)
			(layers "F.Cu" "F.Mask" "F.Paste")
			(net "FM_ESPI_PLD_R1_EN")
		)
		(pad "3" smd rect
			(at -0.94996 0.649986 270)
			(size 0.4318 0.6096)
			(layers "F.Cu" "F.Mask" "F.Paste")
			(net "GND")
		)
		(pad "4" smd rect
			(at 0.94996 0.649986 270)
			(size 0.4318 0.6096)
			(layers "F.Cu" "F.Mask" "F.Paste")
			(net "FM_ESPI_PLD_R_EN_BUF")
		)
		(pad "5" smd rect
			(at 0.94996 -0.649986 270)
			(size 0.4318 0.6096)
			(layers "F.Cu" "F.Mask" "F.Paste")
			(net "P3V3_AUX")
		)
	)
	(footprint ""
		(layer "F.Cu")
		(at 38.774878 -16.099536 90)
		(property "Reference" "C822"
			(at 0 0 90)
			(layer "F.SilkS")
			(hide yes)
			(effects
				(font
					(size 1.27 1.27)
				)
			)
		)
		(property "Value" ""
			(at 0 0 90)
			(layer "F.Fab")
			(effects
				(font
					(size 1.27 1.27)
				)
			)
		)
		(duplicate_pad_numbers_are_jumpers no)
		(fp_line
			(start 0.299974 -0.150114)
			(end 0.299974 0.150114)
			(stroke
				(width 0.1)
				(type default)
			)
			(layer "F.Fab")
		)
		(fp_line
			(start -0.299974 -0.150114)
			(end 0.299974 -0.150114)
			(stroke
				(width 0.1)
				(type default)
			)
			(layer "F.Fab")
		)
		(fp_line
			(start 0.299974 0.150114)
			(end -0.299974 0.150114)
			(stroke
				(width 0.1)
				(type default)
			)
			(layer "F.Fab")
		)
		(fp_line
			(start -0.299974 0.150114)
			(end -0.299974 -0.150114)
			(stroke
				(width 0.1)
				(type default)
			)
			(layer "F.Fab")
		)
		(pad "1" smd rect
			(at -0.2667 0 90)
			(size 0.3048 0.381)
			(layers "F.Cu" "F.Mask" "F.Paste")
			(net "P5E_CPU1_PE1_TX_C_DN<7>")
		)
		(pad "2" smd rect
			(at 0.2667 0 90)
			(size 0.3048 0.381)
			(layers "F.Cu" "F.Mask" "F.Paste")
			(net "P5E_CPU1_PE1_TX_DN<7>")
		)
	)
	(footprint ""
		(layer "F.Cu")
		(at 165.15715 -431.087276 -90)
		(property "Reference" "R2707"
			(at 0 0 270)
			(layer "F.SilkS")
			(hide yes)
			(effects
				(font
					(size 1.27 1.27)
				)
			)
		)
		(property "Value" ""
			(at 0 0 270)
			(layer "F.Fab")
			(effects
				(font
					(size 1.27 1.27)
				)
			)
		)
		(duplicate_pad_numbers_are_jumpers no)
		(fp_line
			(start -0.7874 0.4064)
			(end -0.7874 -0.4064)
			(stroke
				(width 0.1524)
				(type default)
			)
			(layer "F.SilkS")
		)
		(fp_line
			(start 0.7874 0.4064)
			(end -0.7874 0.4064)
			(stroke
				(width 0.1524)
				(type default)
			)
			(layer "F.SilkS")
		)
		(fp_line
			(start -0.7874 -0.4064)
			(end 0.7874 -0.4064)
			(stroke
				(width 0.1524)
				(type default)
			)
			(layer "F.SilkS")
		)
		(fp_line
			(start 0.7874 -0.4064)
			(end 0.7874 0.4064)
			(stroke
				(width 0.1524)
				(type default)
			)
			(layer "F.SilkS")
		)
		(fp_line
			(start -0.67945 0.3048)
			(end -0.67945 -0.305054)
			(stroke
				(width 0.1)
				(type default)
			)
			(layer "F.Fab")
		)
		(fp_line
			(start -0.12065 0.3048)
			(end -0.67945 0.3048)
			(stroke
				(width 0.1)
				(type default)
			)
			(layer "F.Fab")
		)
		(fp_line
			(start 0.120396 0.3048)
			(end 0.120396 0.2794)
			(stroke
				(width 0.1)
				(type default)
			)
			(layer "F.Fab")
		)
		(fp_line
			(start 0.67945 0.3048)
			(end 0.120396 0.3048)
			(stroke
				(width 0.1)
				(type default)
			)
			(layer "F.Fab")
		)
		(fp_line
			(start -0.12065 0.2794)
			(end -0.12065 0.3048)
			(stroke
				(width 0.1)
				(type default)
			)
			(layer "F.Fab")
		)
		(fp_line
			(start 0.120396 0.2794)
			(end -0.12065 0.2794)
			(stroke
				(width 0.1)
				(type default)
			)
			(layer "F.Fab")
		)
		(fp_line
			(start -0.12065 -0.2794)
			(end 0.12065 -0.2794)
			(stroke
				(width 0.1)
				(type default)
			)
			(layer "F.Fab")
		)
		(fp_line
			(start 0.12065 -0.2794)
			(end 0.12065 -0.3048)
			(stroke
				(width 0.1)
				(type default)
			)
			(layer "F.Fab")
		)
		(fp_line
			(start 0.12065 -0.3048)
			(end 0.67945 -0.3048)
			(stroke
				(width 0.1)
				(type default)
			)
			(layer "F.Fab")
		)
		(fp_line
			(start 0.67945 -0.3048)
			(end 0.67945 0.3048)
			(stroke
				(width 0.1)
				(type default)
			)
			(layer "F.Fab")
		)
		(fp_line
			(start -0.67945 -0.305054)
			(end -0.12065 -0.305054)
			(stroke
				(width 0.1)
				(type default)
			)
			(layer "F.Fab")
		)
		(fp_line
			(start -0.12065 -0.305054)
			(end -0.12065 -0.2794)
			(stroke
				(width 0.1)
				(type default)
			)
			(layer "F.Fab")
		)
		(pad "1" smd circle
			(at -0.40005 0 270)
			(size 0 0)
			(layers "F.Cu" "F.Mask" "F.Paste")
			(net "SMB_BMC_SWB_EN")
		)
		(pad "2" smd circle
			(at 0.40005 0 270)
			(size 0 0)
			(layers "F.Cu" "F.Mask" "F.Paste")
			(net "SMB_BMC_SWB_EN_R")
		)
	)
	(footprint ""
		(layer "F.Cu")
		(at 105.315004 -245.634256 -90)
		(property "Reference" "C237"
			(at 0 0 270)
			(layer "F.SilkS")
			(hide yes)
			(effects
				(font
					(size 1.27 1.27)
				)
			)
		)
		(property "Value" ""
			(at 0 0 270)
			(layer "F.Fab")
			(effects
				(font
					(size 1.27 1.27)
				)
			)
		)
		(duplicate_pad_numbers_are_jumpers no)
		(fp_line
			(start -0.7874 0.4064)
			(end -0.7874 -0.4064)
			(stroke
				(width 0.1524)
				(type default)
			)
			(layer "F.SilkS")
		)
		(fp_line
			(start 0.7874 0.4064)
			(end -0.7874 0.4064)
			(stroke
				(width 0.1524)
				(type default)
			)
			(layer "F.SilkS")
		)
		(fp_line
			(start -0.7874 -0.4064)
			(end 0.7874 -0.4064)
			(stroke
				(width 0.1524)
				(type default)
			)
			(layer "F.SilkS")
		)
		(fp_line
			(start 0.7874 -0.4064)
			(end 0.7874 0.4064)
			(stroke
				(width 0.1524)
				(type default)
			)
			(layer "F.SilkS")
		)
		(fp_line
			(start -0.67945 0.3048)
			(end -0.67945 -0.305054)
			(stroke
				(width 0.1)
				(type default)
			)
			(layer "F.Fab")
		)
		(fp_line
			(start -0.12065 0.3048)
			(end -0.67945 0.3048)
			(stroke
				(width 0.1)
				(type default)
			)
			(layer "F.Fab")
		)
		(fp_line
			(start 0.120396 0.3048)
			(end 0.120396 0.2794)
			(stroke
				(width 0.1)
				(type default)
			)
			(layer "F.Fab")
		)
		(fp_line
			(start 0.67945 0.3048)
			(end 0.120396 0.3048)
			(stroke
				(width 0.1)
				(type default)
			)
			(layer "F.Fab")
		)
		(fp_line
			(start -0.12065 0.2794)
			(end -0.12065 0.3048)
			(stroke
				(width 0.1)
				(type default)
			)
			(layer "F.Fab")
		)
		(fp_line
			(start 0.120396 0.2794)
			(end -0.12065 0.2794)
			(stroke
				(width 0.1)
				(type default)
			)
			(layer "F.Fab")
		)
		(fp_line
			(start -0.12065 -0.2794)
			(end 0.12065 -0.2794)
			(stroke
				(width 0.1)
				(type default)
			)
			(layer "F.Fab")
		)
		(fp_line
			(start 0.12065 -0.2794)
			(end 0.12065 -0.3048)
			(stroke
				(width 0.1)
				(type default)
			)
			(layer "F.Fab")
		)
		(fp_line
			(start 0.12065 -0.3048)
			(end 0.67945 -0.3048)
			(stroke
				(width 0.1)
				(type default)
			)
			(layer "F.Fab")
		)
		(fp_line
			(start 0.67945 -0.3048)
			(end 0.67945 0.3048)
			(stroke
				(width 0.1)
				(type default)
			)
			(layer "F.Fab")
		)
		(fp_line
			(start -0.67945 -0.305054)
			(end -0.12065 -0.305054)
			(stroke
				(width 0.1)
				(type default)
			)
			(layer "F.Fab")
		)
		(fp_line
			(start -0.12065 -0.305054)
			(end -0.12065 -0.2794)
			(stroke
				(width 0.1)
				(type default)
			)
			(layer "F.Fab")
		)
		(pad "1" smd circle
			(at -0.40005 0 270)
			(size 0 0)
			(layers "F.Cu" "F.Mask" "F.Paste")
			(net "PVCCIN_CPU1")
		)
		(pad "2" smd circle
			(at 0.40005 0 270)
			(size 0 0)
			(layers "F.Cu" "F.Mask" "F.Paste")
			(net "GND")
		)
	)
	(footprint ""
		(layer "F.Cu")
		(at 117.22608 -119.846598 -90)
		(property "Reference" "R854"
			(at 0 0 270)
			(layer "F.SilkS")
			(hide yes)
			(effects
				(font
					(size 1.27 1.27)
				)
			)
		)
		(property "Value" ""
			(at 0 0 270)
			(layer "F.Fab")
			(effects
				(font
					(size 1.27 1.27)
				)
			)
		)
		(duplicate_pad_numbers_are_jumpers no)
		(fp_line
			(start -0.7874 0.4064)
			(end -0.7874 -0.4064)
			(stroke
				(width 0.1524)
				(type default)
			)
			(layer "F.SilkS")
		)
		(fp_line
			(start 0.7874 0.4064)
			(end -0.7874 0.4064)
			(stroke
				(width 0.1524)
				(type default)
			)
			(layer "F.SilkS")
		)
		(fp_line
			(start -0.7874 -0.4064)
			(end 0.7874 -0.4064)
			(stroke
				(width 0.1524)
				(type default)
			)
			(layer "F.SilkS")
		)
		(fp_line
			(start 0.7874 -0.4064)
			(end 0.7874 0.4064)
			(stroke
				(width 0.1524)
				(type default)
			)
			(layer "F.SilkS")
		)
		(fp_line
			(start -0.67945 0.3048)
			(end -0.67945 -0.305054)
			(stroke
				(width 0.1)
				(type default)
			)
			(layer "F.Fab")
		)
		(fp_line
			(start -0.12065 0.3048)
			(end -0.67945 0.3048)
			(stroke
				(width 0.1)
				(type default)
			)
			(layer "F.Fab")
		)
		(fp_line
			(start 0.120396 0.3048)
			(end 0.120396 0.2794)
			(stroke
				(width 0.1)
				(type default)
			)
			(layer "F.Fab")
		)
		(fp_line
			(start 0.67945 0.3048)
			(end 0.120396 0.3048)
			(stroke
				(width 0.1)
				(type default)
			)
			(layer "F.Fab")
		)
		(fp_line
			(start -0.12065 0.2794)
			(end -0.12065 0.3048)
			(stroke
				(width 0.1)
				(type default)
			)
			(layer "F.Fab")
		)
		(fp_line
			(start 0.120396 0.2794)
			(end -0.12065 0.2794)
			(stroke
				(width 0.1)
				(type default)
			)
			(layer "F.Fab")
		)
		(fp_line
			(start -0.12065 -0.2794)
			(end 0.12065 -0.2794)
			(stroke
				(width 0.1)
				(type default)
			)
			(layer "F.Fab")
		)
		(fp_line
			(start 0.12065 -0.2794)
			(end 0.12065 -0.3048)
			(stroke
				(width 0.1)
				(type default)
			)
			(layer "F.Fab")
		)
		(fp_line
			(start 0.12065 -0.3048)
			(end 0.67945 -0.3048)
			(stroke
				(width 0.1)
				(type default)
			)
			(layer "F.Fab")
		)
		(fp_line
			(start 0.67945 -0.3048)
			(end 0.67945 0.3048)
			(stroke
				(width 0.1)
				(type default)
			)
			(layer "F.Fab")
		)
		(fp_line
			(start -0.67945 -0.305054)
			(end -0.12065 -0.305054)
			(stroke
				(width 0.1)
				(type default)
			)
			(layer "F.Fab")
		)
		(fp_line
			(start -0.12065 -0.305054)
			(end -0.12065 -0.2794)
			(stroke
				(width 0.1)
				(type default)
			)
			(layer "F.Fab")
		)
		(pad "1" smd circle
			(at -0.40005 0 270)
			(size 0 0)
			(layers "F.Cu" "F.Mask" "F.Paste")
			(net "RST_CPU0_DRAM_GH_N")
		)
		(pad "2" smd circle
			(at 0.40005 0 270)
			(size 0 0)
			(layers "F.Cu" "F.Mask" "F.Paste")
			(net "RST_CPU0_DRAM_GH_PLD_N")
		)
	)
	(footprint ""
		(layer "F.Cu")
		(at 431.33518 -58.034428 90)
		(property "Reference" "C1340"
			(at 0 0 90)
			(layer "F.SilkS")
			(hide yes)
			(effects
				(font
					(size 1.27 1.27)
				)
			)
		)
		(property "Value" ""
			(at 0 0 90)
			(layer "F.Fab")
			(effects
				(font
					(size 1.27 1.27)
				)
			)
		)
		(duplicate_pad_numbers_are_jumpers no)
		(fp_line
			(start 1.524 -0.762)
			(end 1.524 0.762)
			(stroke
				(width 0.1524)
				(type default)
			)
			(layer "F.SilkS")
		)
		(fp_line
			(start -1.524 -0.762)
			(end 1.524 -0.762)
			(stroke
				(width 0.1524)
				(type default)
			)
			(layer "F.SilkS")
		)
		(fp_line
			(start 1.524 0.762)
			(end -1.524 0.762)
			(stroke
				(width 0.1524)
				(type default)
			)
			(layer "F.SilkS")
		)
		(fp_line
			(start -1.524 0.762)
			(end -1.524 -0.762)
			(stroke
				(width 0.1524)
				(type default)
			)
			(layer "F.SilkS")
		)
		(fp_line
			(start 1.1049 -0.724916)
			(end -1.1049 -0.724916)
			(stroke
				(width 0.1)
				(type default)
			)
			(layer "F.Fab")
		)
		(fp_line
			(start -1.1049 -0.724916)
			(end -1.1049 0.724916)
			(stroke
				(width 0.1)
				(type default)
			)
			(layer "F.Fab")
		)
		(fp_line
			(start 1.1049 0.724916)
			(end 1.1049 -0.724916)
			(stroke
				(width 0.1)
				(type default)
			)
			(layer "F.Fab")
		)
		(fp_line
			(start -1.1049 0.724916)
			(end 1.1049 0.724916)
			(stroke
				(width 0.1)
				(type default)
			)
			(layer "F.Fab")
		)
		(pad "1" smd rect
			(at -0.889 0 270)
			(size 1.016 1.27)
			(layers "F.Cu" "F.Mask" "F.Paste")
			(net "P3V3")
		)
		(pad "2" smd rect
			(at 0.889 0 270)
			(size 1.016 1.27)
			(layers "F.Cu" "F.Mask" "F.Paste")
			(net "GND")
		)
	)
	(footprint ""
		(layer "F.Cu")
		(at 179.352448 -401.239482 180)
		(property "Reference" "PC2103"
			(at 0 0 180)
			(layer "F.SilkS")
			(hide yes)
			(effects
				(font
					(size 1.27 1.27)
				)
			)
		)
		(property "Value" ""
			(at 0 0 180)
			(layer "F.Fab")
			(effects
				(font
					(size 1.27 1.27)
				)
			)
		)
		(duplicate_pad_numbers_are_jumpers no)
		(fp_line
			(start 0.7874 0.4064)
			(end -0.7874 0.4064)
			(stroke
				(width 0.1524)
				(type default)
			)
			(layer "F.SilkS")
		)
		(fp_line
			(start 0.7874 -0.4064)
			(end 0.7874 0.4064)
			(stroke
				(width 0.1524)
				(type default)
			)
			(layer "F.SilkS")
		)
		(fp_line
			(start -0.7874 0.4064)
			(end -0.7874 -0.4064)
			(stroke
				(width 0.1524)
				(type default)
			)
			(layer "F.SilkS")
		)
		(fp_line
			(start -0.7874 -0.4064)
			(end 0.7874 -0.4064)
			(stroke
				(width 0.1524)
				(type default)
			)
			(layer "F.SilkS")
		)
		(fp_line
			(start 0.67945 0.3048)
			(end 0.120396 0.3048)
			(stroke
				(width 0.1)
				(type default)
			)
			(layer "F.Fab")
		)
		(fp_line
			(start 0.67945 -0.3048)
			(end 0.67945 0.3048)
			(stroke
				(width 0.1)
				(type default)
			)
			(layer "F.Fab")
		)
		(fp_line
			(start 0.12065 -0.2794)
			(end 0.12065 -0.3048)
			(stroke
				(width 0.1)
				(type default)
			)
			(layer "F.Fab")
		)
		(fp_line
			(start 0.12065 -0.3048)
			(end 0.67945 -0.3048)
			(stroke
				(width 0.1)
				(type default)
			)
			(layer "F.Fab")
		)
		(fp_line
			(start 0.120396 0.3048)
			(end 0.120396 0.2794)
			(stroke
				(width 0.1)
				(type default)
			)
			(layer "F.Fab")
		)
		(fp_line
			(start 0.120396 0.2794)
			(end -0.12065 0.2794)
			(stroke
				(width 0.1)
				(type default)
			)
			(layer "F.Fab")
		)
		(fp_line
			(start -0.12065 0.3048)
			(end -0.67945 0.3048)
			(stroke
				(width 0.1)
				(type default)
			)
			(layer "F.Fab")
		)
		(fp_line
			(start -0.12065 0.2794)
			(end -0.12065 0.3048)
			(stroke
				(width 0.1)
				(type default)
			)
			(layer "F.Fab")
		)
		(fp_line
			(start -0.12065 -0.2794)
			(end 0.12065 -0.2794)
			(stroke
				(width 0.1)
				(type default)
			)
			(layer "F.Fab")
		)
		(fp_line
			(start -0.12065 -0.305054)
			(end -0.12065 -0.2794)
			(stroke
				(width 0.1)
				(type default)
			)
			(layer "F.Fab")
		)
		(fp_line
			(start -0.67945 0.3048)
			(end -0.67945 -0.305054)
			(stroke
				(width 0.1)
				(type default)
			)
			(layer "F.Fab")
		)
		(fp_line
			(start -0.67945 -0.305054)
			(end -0.12065 -0.305054)
			(stroke
				(width 0.1)
				(type default)
			)
			(layer "F.Fab")
		)
		(pad "1" smd circle
			(at -0.40005 0 180)
			(size 0 0)
			(layers "F.Cu" "F.Mask" "F.Paste")
			(net "HSC_VDD18")
		)
		(pad "2" smd circle
			(at 0.40005 0 180)
			(size 0 0)
			(layers "F.Cu" "F.Mask" "F.Paste")
			(net "AGND_HSC")
		)
	)
	(footprint ""
		(layer "F.Cu")
		(at 354.8126 -408.818588 180)
		(property "Reference" "R4558"
			(at 0 0 180)
			(layer "F.SilkS")
			(hide yes)
			(effects
				(font
					(size 1.27 1.27)
				)
			)
		)
		(property "Value" ""
			(at 0 0 180)
			(layer "F.Fab")
			(effects
				(font
					(size 1.27 1.27)
				)
			)
		)
		(duplicate_pad_numbers_are_jumpers no)
		(fp_line
			(start 0.7874 0.4064)
			(end -0.7874 0.4064)
			(stroke
				(width 0.1524)
				(type default)
			)
			(layer "F.SilkS")
		)
		(fp_line
			(start 0.7874 -0.4064)
			(end 0.7874 0.4064)
			(stroke
				(width 0.1524)
				(type default)
			)
			(layer "F.SilkS")
		)
		(fp_line
			(start -0.7874 0.4064)
			(end -0.7874 -0.4064)
			(stroke
				(width 0.1524)
				(type default)
			)
			(layer "F.SilkS")
		)
		(fp_line
			(start -0.7874 -0.4064)
			(end 0.7874 -0.4064)
			(stroke
				(width 0.1524)
				(type default)
			)
			(layer "F.SilkS")
		)
		(fp_line
			(start 0.67945 0.3048)
			(end 0.120396 0.3048)
			(stroke
				(width 0.1)
				(type default)
			)
			(layer "F.Fab")
		)
		(fp_line
			(start 0.67945 -0.3048)
			(end 0.67945 0.3048)
			(stroke
				(width 0.1)
				(type default)
			)
			(layer "F.Fab")
		)
		(fp_line
			(start 0.12065 -0.2794)
			(end 0.12065 -0.3048)
			(stroke
				(width 0.1)
				(type default)
			)
			(layer "F.Fab")
		)
		(fp_line
			(start 0.12065 -0.3048)
			(end 0.67945 -0.3048)
			(stroke
				(width 0.1)
				(type default)
			)
			(layer "F.Fab")
		)
		(fp_line
			(start 0.120396 0.3048)
			(end 0.120396 0.2794)
			(stroke
				(width 0.1)
				(type default)
			)
			(layer "F.Fab")
		)
		(fp_line
			(start 0.120396 0.2794)
			(end -0.12065 0.2794)
			(stroke
				(width 0.1)
				(type default)
			)
			(layer "F.Fab")
		)
		(fp_line
			(start -0.12065 0.3048)
			(end -0.67945 0.3048)
			(stroke
				(width 0.1)
				(type default)
			)
			(layer "F.Fab")
		)
		(fp_line
			(start -0.12065 0.2794)
			(end -0.12065 0.3048)
			(stroke
				(width 0.1)
				(type default)
			)
			(layer "F.Fab")
		)
		(fp_line
			(start -0.12065 -0.2794)
			(end 0.12065 -0.2794)
			(stroke
				(width 0.1)
				(type default)
			)
			(layer "F.Fab")
		)
		(fp_line
			(start -0.12065 -0.305054)
			(end -0.12065 -0.2794)
			(stroke
				(width 0.1)
				(type default)
			)
			(layer "F.Fab")
		)
		(fp_line
			(start -0.67945 0.3048)
			(end -0.67945 -0.305054)
			(stroke
				(width 0.1)
				(type default)
			)
			(layer "F.Fab")
		)
		(fp_line
			(start -0.67945 -0.305054)
			(end -0.12065 -0.305054)
			(stroke
				(width 0.1)
				(type default)
			)
			(layer "F.Fab")
		)
		(pad "1" smd circle
			(at -0.40005 0 180)
			(size 0 0)
			(layers "F.Cu" "F.Mask" "F.Paste")
			(net "SWB_HSC_EN")
		)
		(pad "2" smd circle
			(at 0.40005 0 180)
			(size 0 0)
			(layers "F.Cu" "F.Mask" "F.Paste")
			(net "SWB_HSC_EN_R")
		)
	)
	(footprint ""
		(layer "F.Cu")
		(at 362.14558 -408.544268)
		(property "Reference" "R4555"
			(at 0 0 0)
			(layer "F.SilkS")
			(hide yes)
			(effects
				(font
					(size 1.27 1.27)
				)
			)
		)
		(property "Value" ""
			(at 0 0 0)
			(layer "F.Fab")
			(effects
				(font
					(size 1.27 1.27)
				)
			)
		)
		(duplicate_pad_numbers_are_jumpers no)
		(fp_line
			(start -0.7874 -0.4064)
			(end 0.7874 -0.4064)
			(stroke
				(width 0.1524)
				(type default)
			)
			(layer "F.SilkS")
		)
		(fp_line
			(start -0.7874 0.4064)
			(end -0.7874 -0.4064)
			(stroke
				(width 0.1524)
				(type default)
			)
			(layer "F.SilkS")
		)
		(fp_line
			(start 0.7874 -0.4064)
			(end 0.7874 0.4064)
			(stroke
				(width 0.1524)
				(type default)
			)
			(layer "F.SilkS")
		)
		(fp_line
			(start 0.7874 0.4064)
			(end -0.7874 0.4064)
			(stroke
				(width 0.1524)
				(type default)
			)
			(layer "F.SilkS")
		)
		(fp_line
			(start -0.67945 -0.305054)
			(end -0.12065 -0.305054)
			(stroke
				(width 0.1)
				(type default)
			)
			(layer "F.Fab")
		)
		(fp_line
			(start -0.67945 0.3048)
			(end -0.67945 -0.305054)
			(stroke
				(width 0.1)
				(type default)
			)
			(layer "F.Fab")
		)
		(fp_line
			(start -0.12065 -0.305054)
			(end -0.12065 -0.2794)
			(stroke
				(width 0.1)
				(type default)
			)
			(layer "F.Fab")
		)
		(fp_line
			(start -0.12065 -0.2794)
			(end 0.12065 -0.2794)
			(stroke
				(width 0.1)
				(type default)
			)
			(layer "F.Fab")
		)
		(fp_line
			(start -0.12065 0.2794)
			(end -0.12065 0.3048)
			(stroke
				(width 0.1)
				(type default)
			)
			(layer "F.Fab")
		)
		(fp_line
			(start -0.12065 0.3048)
			(end -0.67945 0.3048)
			(stroke
				(width 0.1)
				(type default)
			)
			(layer "F.Fab")
		)
		(fp_line
			(start 0.120396 0.2794)
			(end -0.12065 0.2794)
			(stroke
				(width 0.1)
				(type default)
			)
			(layer "F.Fab")
		)
		(fp_line
			(start 0.120396 0.3048)
			(end 0.120396 0.2794)
			(stroke
				(width 0.1)
				(type default)
			)
			(layer "F.Fab")
		)
		(fp_line
			(start 0.12065 -0.3048)
			(end 0.67945 -0.3048)
			(stroke
				(width 0.1)
				(type default)
			)
			(layer "F.Fab")
		)
		(fp_line
			(start 0.12065 -0.2794)
			(end 0.12065 -0.3048)
			(stroke
				(width 0.1)
				(type default)
			)
			(layer "F.Fab")
		)
		(fp_line
			(start 0.67945 -0.3048)
			(end 0.67945 0.3048)
			(stroke
				(width 0.1)
				(type default)
			)
			(layer "F.Fab")
		)
		(fp_line
			(start 0.67945 0.3048)
			(end 0.120396 0.3048)
			(stroke
				(width 0.1)
				(type default)
			)
			(layer "F.Fab")
		)
		(pad "1" smd circle
			(at -0.40005 0)
			(size 0 0)
			(layers "F.Cu" "F.Mask" "F.Paste")
			(net "SWB_HSC_EN_BUF_R")
		)
		(pad "2" smd circle
			(at 0.40005 0)
			(size 0 0)
			(layers "F.Cu" "F.Mask" "F.Paste")
			(net "GND")
		)
	)
	(footprint ""
		(layer "F.Cu")
		(at 263.101582 -68.139056 180)
		(property "Reference" "PC113"
			(at 0 0 180)
			(layer "F.SilkS")
			(hide yes)
			(effects
				(font
					(size 1.27 1.27)
				)
			)
		)
		(property "Value" ""
			(at 0 0 180)
			(layer "F.Fab")
			(effects
				(font
					(size 1.27 1.27)
				)
			)
		)
		(duplicate_pad_numbers_are_jumpers no)
		(fp_line
			(start 0.7874 0.4064)
			(end -0.7874 0.4064)
			(stroke
				(width 0.1524)
				(type default)
			)
			(layer "F.SilkS")
		)
		(fp_line
			(start 0.7874 -0.4064)
			(end 0.7874 0.4064)
			(stroke
				(width 0.1524)
				(type default)
			)
			(layer "F.SilkS")
		)
		(fp_line
			(start -0.7874 0.4064)
			(end -0.7874 -0.4064)
			(stroke
				(width 0.1524)
				(type default)
			)
			(layer "F.SilkS")
		)
		(fp_line
			(start -0.7874 -0.4064)
			(end 0.7874 -0.4064)
			(stroke
				(width 0.1524)
				(type default)
			)
			(layer "F.SilkS")
		)
		(fp_line
			(start 0.67945 0.3048)
			(end 0.120396 0.3048)
			(stroke
				(width 0.1)
				(type default)
			)
			(layer "F.Fab")
		)
		(fp_line
			(start 0.67945 -0.3048)
			(end 0.67945 0.3048)
			(stroke
				(width 0.1)
				(type default)
			)
			(layer "F.Fab")
		)
		(fp_line
			(start 0.12065 -0.2794)
			(end 0.12065 -0.3048)
			(stroke
				(width 0.1)
				(type default)
			)
			(layer "F.Fab")
		)
		(fp_line
			(start 0.12065 -0.3048)
			(end 0.67945 -0.3048)
			(stroke
				(width 0.1)
				(type default)
			)
			(layer "F.Fab")
		)
		(fp_line
			(start 0.120396 0.3048)
			(end 0.120396 0.2794)
			(stroke
				(width 0.1)
				(type default)
			)
			(layer "F.Fab")
		)
		(fp_line
			(start 0.120396 0.2794)
			(end -0.12065 0.2794)
			(stroke
				(width 0.1)
				(type default)
			)
			(layer "F.Fab")
		)
		(fp_line
			(start -0.12065 0.3048)
			(end -0.67945 0.3048)
			(stroke
				(width 0.1)
				(type default)
			)
			(layer "F.Fab")
		)
		(fp_line
			(start -0.12065 0.2794)
			(end -0.12065 0.3048)
			(stroke
				(width 0.1)
				(type default)
			)
			(layer "F.Fab")
		)
		(fp_line
			(start -0.12065 -0.2794)
			(end 0.12065 -0.2794)
			(stroke
				(width 0.1)
				(type default)
			)
			(layer "F.Fab")
		)
		(fp_line
			(start -0.12065 -0.305054)
			(end -0.12065 -0.2794)
			(stroke
				(width 0.1)
				(type default)
			)
			(layer "F.Fab")
		)
		(fp_line
			(start -0.67945 0.3048)
			(end -0.67945 -0.305054)
			(stroke
				(width 0.1)
				(type default)
			)
			(layer "F.Fab")
		)
		(fp_line
			(start -0.67945 -0.305054)
			(end -0.12065 -0.305054)
			(stroke
				(width 0.1)
				(type default)
			)
			(layer "F.Fab")
		)
		(pad "1" smd circle
			(at -0.40005 0 180)
			(size 0 0)
			(layers "F.Cu" "F.Mask" "F.Paste")
			(net "P1V05_PCH_AUX_VCC")
		)
		(pad "2" smd circle
			(at 0.40005 0 180)
			(size 0 0)
			(layers "F.Cu" "F.Mask" "F.Paste")
			(net "GND")
		)
	)
	(footprint ""
		(layer "F.Cu")
		(at 118.804944 -75.031092 -90)
		(property "Reference" "C1321"
			(at 0 0 270)
			(layer "F.SilkS")
			(hide yes)
			(effects
				(font
					(size 1.27 1.27)
				)
			)
		)
		(property "Value" ""
			(at 0 0 270)
			(layer "F.Fab")
			(effects
				(font
					(size 1.27 1.27)
				)
			)
		)
		(duplicate_pad_numbers_are_jumpers no)
		(fp_line
			(start -0.7874 0.4064)
			(end -0.7874 -0.4064)
			(stroke
				(width 0.1524)
				(type default)
			)
			(layer "F.SilkS")
		)
		(fp_line
			(start 0.7874 0.4064)
			(end -0.7874 0.4064)
			(stroke
				(width 0.1524)
				(type default)
			)
			(layer "F.SilkS")
		)
		(fp_line
			(start -0.7874 -0.4064)
			(end 0.7874 -0.4064)
			(stroke
				(width 0.1524)
				(type default)
			)
			(layer "F.SilkS")
		)
		(fp_line
			(start 0.7874 -0.4064)
			(end 0.7874 0.4064)
			(stroke
				(width 0.1524)
				(type default)
			)
			(layer "F.SilkS")
		)
		(fp_line
			(start -0.67945 0.3048)
			(end -0.67945 -0.305054)
			(stroke
				(width 0.1)
				(type default)
			)
			(layer "F.Fab")
		)
		(fp_line
			(start -0.12065 0.3048)
			(end -0.67945 0.3048)
			(stroke
				(width 0.1)
				(type default)
			)
			(layer "F.Fab")
		)
		(fp_line
			(start 0.120396 0.3048)
			(end 0.120396 0.2794)
			(stroke
				(width 0.1)
				(type default)
			)
			(layer "F.Fab")
		)
		(fp_line
			(start 0.67945 0.3048)
			(end 0.120396 0.3048)
			(stroke
				(width 0.1)
				(type default)
			)
			(layer "F.Fab")
		)
		(fp_line
			(start -0.12065 0.2794)
			(end -0.12065 0.3048)
			(stroke
				(width 0.1)
				(type default)
			)
			(layer "F.Fab")
		)
		(fp_line
			(start 0.120396 0.2794)
			(end -0.12065 0.2794)
			(stroke
				(width 0.1)
				(type default)
			)
			(layer "F.Fab")
		)
		(fp_line
			(start -0.12065 -0.2794)
			(end 0.12065 -0.2794)
			(stroke
				(width 0.1)
				(type default)
			)
			(layer "F.Fab")
		)
		(fp_line
			(start 0.12065 -0.2794)
			(end 0.12065 -0.3048)
			(stroke
				(width 0.1)
				(type default)
			)
			(layer "F.Fab")
		)
		(fp_line
			(start 0.12065 -0.3048)
			(end 0.67945 -0.3048)
			(stroke
				(width 0.1)
				(type default)
			)
			(layer "F.Fab")
		)
		(fp_line
			(start 0.67945 -0.3048)
			(end 0.67945 0.3048)
			(stroke
				(width 0.1)
				(type default)
			)
			(layer "F.Fab")
		)
		(fp_line
			(start -0.67945 -0.305054)
			(end -0.12065 -0.305054)
			(stroke
				(width 0.1)
				(type default)
			)
			(layer "F.Fab")
		)
		(fp_line
			(start -0.12065 -0.305054)
			(end -0.12065 -0.2794)
			(stroke
				(width 0.1)
				(type default)
			)
			(layer "F.Fab")
		)
		(pad "1" smd circle
			(at -0.40005 0 270)
			(size 0 0)
			(layers "F.Cu" "F.Mask" "F.Paste")
			(net "P3V3_AUX")
		)
		(pad "2" smd circle
			(at 0.40005 0 270)
			(size 0 0)
			(layers "F.Cu" "F.Mask" "F.Paste")
			(net "GND")
		)
	)
	(footprint ""
		(layer "F.Cu")
		(at 47.401988 -5.569966 -90)
		(property "Reference" "J35"
			(at -16.848074 29.242004 0)
			(unlocked yes)
			(layer "F.SilkS")
			(effects
				(font
					(size 0.7874 0.5842)
					(thickness 0.1524)
				)
				(justify left)
			)
		)
		(property "Value" ""
			(at 0 0 270)
			(layer "F.Fab")
			(effects
				(font
					(size 1.27 1.27)
				)
			)
		)
		(duplicate_pad_numbers_are_jumpers no)
		(fp_line
			(start -7.420102 34.360104)
			(end 6.210046 34.360104)
			(stroke
				(width 0.1524)
				(type default)
			)
			(layer "F.SilkS")
		)
		(fp_line
			(start 6.210046 34.360104)
			(end 6.210046 -34.360104)
			(stroke
				(width 0.1524)
				(type default)
			)
			(layer "F.SilkS")
		)
		(fp_line
			(start -5.5499 33.8201)
			(end 5.5499 33.8201)
			(stroke
				(width 0.1524)
				(type default)
			)
			(layer "F.SilkS")
		)
		(fp_line
			(start 5.5499 33.8201)
			(end 5.5499 -33.8201)
			(stroke
				(width 0.1524)
				(type default)
			)
			(layer "F.SilkS")
		)
		(fp_line
			(start -5.5499 30.97784)
			(end -5.5499 33.8201)
			(stroke
				(width 0.1524)
				(type default)
			)
			(layer "F.SilkS")
		)
		(fp_line
			(start -5.5499 9.8806)
			(end -5.5499 14.13256)
			(stroke
				(width 0.1524)
				(type default)
			)
			(layer "F.SilkS")
		)
		(fp_line
			(start -5.5499 -1.9304)
			(end -5.5499 1.4224)
			(stroke
				(width 0.1524)
				(type default)
			)
			(layer "F.SilkS")
		)
		(fp_line
			(start -5.5499 -22.5425)
			(end -5.5499 -18.7833)
			(stroke
				(width 0.1524)
				(type default)
			)
			(layer "F.SilkS")
		)
		(fp_line
			(start -5.5499 -33.8201)
			(end -5.5499 -30.988)
			(stroke
				(width 0.1524)
				(type default)
			)
			(layer "F.SilkS")
		)
		(fp_line
			(start 5.5499 -33.8201)
			(end -5.5499 -33.8201)
			(stroke
				(width 0.1524)
				(type default)
			)
			(layer "F.SilkS")
		)
		(fp_line
			(start 6.210046 -34.360104)
			(end -7.420102 -34.360104)
			(stroke
				(width 0.1524)
				(type default)
			)
			(layer "F.SilkS")
		)
		(fp_poly
			(pts
				(xy 5.19938 -17.880838) (xy 5.19938 -18.896838) (xy 4.18338 -18.388838)
			)
			(stroke
				(width 0)
				(type default)
			)
			(fill yes)
			(layer "F.SilkS")
		)
		(fp_line
			(start -5.5499 33.8201)
			(end 5.5499 33.8201)
			(stroke
				(width 0.1)
				(type default)
			)
			(layer "F.Fab")
		)
		(fp_line
			(start 5.5499 33.8201)
			(end 5.5499 -33.8201)
			(stroke
				(width 0.1)
				(type default)
			)
			(layer "F.Fab")
		)
		(fp_line
			(start -5.5499 -33.8201)
			(end -5.5499 33.8201)
			(stroke
				(width 0.1)
				(type default)
			)
			(layer "F.Fab")
		)
		(fp_line
			(start 5.5499 -33.8201)
			(end -5.5499 -33.8201)
			(stroke
				(width 0.1)
				(type default)
			)
			(layer "F.Fab")
		)
		(fp_poly
			(pts
				(xy 7.4168 -17.957038) (xy 7.4168 -18.973038) (xy 6.4008 -18.465038)
			)
			(stroke
				(width 0)
				(type default)
			)
			(fill yes)
			(layer "F.Fab")
		)
		(pad "" np_thru_hole circle
			(at -0.599948 -32.079946 180)
			(size 1.1176 1.1176)
			(drill 1.1176)
			(layers "*.Cu" "*.Mask")
			(clearance 0.381)
			(thermal_gap 0.381)
		)
		(pad "" np_thru_hole circle
			(at 0.40005 32.085026 180)
			(size 1.1176 1.1176)
			(drill 1.1176)
			(layers "*.Cu" "*.Mask")
			(clearance 0.381)
			(thermal_gap 0.381)
		)
		(pad "A1" smd rect
			(at -2.750058 -18.465038 180)
			(size 0.381 1.4478)
			(layers "F.Cu" "F.Mask" "F.Paste")
			(net "GND")
		)
		(pad "A2" smd rect
			(at -2.750058 -17.86509 180)
			(size 0.381 1.4478)
			(layers "F.Cu" "F.Mask" "F.Paste")
			(net "GND")
		)
		(pad "A3" smd rect
			(at -2.750058 -17.264888 180)
			(size 0.381 1.4478)
			(layers "F.Cu" "F.Mask" "F.Paste")
			(net "GND")
		)
		(pad "A4" smd rect
			(at -2.750058 -16.66494 180)
			(size 0.381 1.4478)
			(layers "F.Cu" "F.Mask" "F.Paste")
			(net "GND")
		)
		(pad "A5" smd rect
			(at -2.750058 -16.064992 180)
			(size 0.381 1.4478)
			(layers "F.Cu" "F.Mask" "F.Paste")
			(net "GND")
		)
		(pad "A6" smd rect
			(at -2.750058 -15.465044 180)
			(size 0.381 1.4478)
			(layers "F.Cu" "F.Mask" "F.Paste")
			(net "GND")
		)
		(pad "A7" smd rect
			(at -2.750058 -14.865096 180)
			(size 0.381 1.4478)
			(layers "F.Cu" "F.Mask" "F.Paste")
			(net "SMB_OCP_V3_2_3V3AUX_BUF_R_SCL")
		)
		(pad "A8" smd rect
			(at -2.750058 -14.264894 180)
			(size 0.381 1.4478)
			(layers "F.Cu" "F.Mask" "F.Paste")
			(net "SMB_OCP_V3_2_3V3AUX_BUF_R_SDA")
		)
		(pad "A9" smd rect
			(at -2.750058 -13.664946 180)
			(size 0.381 1.4478)
			(layers "F.Cu" "F.Mask" "F.Paste")
			(net "RST_SMB_OCP_V3_2_N")
		)
		(pad "A10" smd rect
			(at -2.750058 -13.064998 180)
			(size 0.381 1.4478)
			(layers "F.Cu" "F.Mask" "F.Paste")
			(net "OCP_V3_1_PRSNTA_R_N")
		)
		(pad "A11" smd rect
			(at -2.750058 -12.46505 180)
			(size 0.381 1.4478)
			(layers "F.Cu" "F.Mask" "F.Paste")
			(net "RST_PERST1_OCP_V3_2_N")
		)
		(pad "A12" smd rect
			(at -2.750058 -11.865102 180)
			(size 0.381 1.4478)
			(layers "F.Cu" "F.Mask" "F.Paste")
			(net "OCP_V3_2_PRSNT2_R_N")
		)
		(pad "A13" smd rect
			(at -2.750058 -11.2649 180)
			(size 0.381 1.4478)
			(layers "F.Cu" "F.Mask" "F.Paste")
			(net "GND")
		)
		(pad "A14" smd rect
			(at -2.750058 -10.664952 180)
			(size 0.381 1.4478)
			(layers "F.Cu" "F.Mask" "F.Paste")
			(net "CLK_100M_OCP_V3_2_B_DN")
		)
		(pad "A15" smd rect
			(at -2.750058 -10.065004 180)
			(size 0.381 1.4478)
			(layers "F.Cu" "F.Mask" "F.Paste")
			(net "CLK_100M_OCP_V3_2_B_DP")
		)
		(pad "A16" smd rect
			(at -2.750058 -9.465056 180)
			(size 0.381 1.4478)
			(layers "F.Cu" "F.Mask" "F.Paste")
			(net "GND")
		)
		(pad "A17" smd rect
			(at -2.750058 -8.865108 180)
			(size 0.381 1.4478)
			(layers "F.Cu" "F.Mask" "F.Paste")
			(net "P5E_CPU1_PE1_RX_DN<0>")
		)
		(pad "A18" smd rect
			(at -2.750058 -8.264906 180)
			(size 0.381 1.4478)
			(layers "F.Cu" "F.Mask" "F.Paste")
			(net "P5E_CPU1_PE1_RX_DP<0>")
		)
		(pad "A19" smd rect
			(at -2.750058 -7.664958 180)
			(size 0.381 1.4478)
			(layers "F.Cu" "F.Mask" "F.Paste")
			(net "GND")
		)
		(pad "A20" smd rect
			(at -2.750058 -7.06501 180)
			(size 0.381 1.4478)
			(layers "F.Cu" "F.Mask" "F.Paste")
			(net "P5E_CPU1_PE1_RX_DN<1>")
		)
		(pad "A21" smd rect
			(at -2.750058 -6.465062 180)
			(size 0.381 1.4478)
			(layers "F.Cu" "F.Mask" "F.Paste")
			(net "P5E_CPU1_PE1_RX_DP<1>")
		)
		(pad "A22" smd rect
			(at -2.750058 -5.865114 180)
			(size 0.381 1.4478)
			(layers "F.Cu" "F.Mask" "F.Paste")
			(net "GND")
		)
		(pad "A23" smd rect
			(at -2.750058 -5.264912 180)
			(size 0.381 1.4478)
			(layers "F.Cu" "F.Mask" "F.Paste")
			(net "P5E_CPU1_PE1_RX_DN<2>")
		)
		(pad "A24" smd rect
			(at -2.750058 -4.664964 180)
			(size 0.381 1.4478)
			(layers "F.Cu" "F.Mask" "F.Paste")
			(net "P5E_CPU1_PE1_RX_DP<2>")
		)
		(pad "A25" smd rect
			(at -2.750058 -4.065016 180)
			(size 0.381 1.4478)
			(layers "F.Cu" "F.Mask" "F.Paste")
			(net "GND")
		)
		(pad "A26" smd rect
			(at -2.750058 -3.465068 180)
			(size 0.381 1.4478)
			(layers "F.Cu" "F.Mask" "F.Paste")
			(net "P5E_CPU1_PE1_RX_DN<3>")
		)
		(pad "A27" smd rect
			(at -2.750058 -2.86512 180)
			(size 0.381 1.4478)
			(layers "F.Cu" "F.Mask" "F.Paste")
			(net "P5E_CPU1_PE1_RX_DP<3>")
		)
		(pad "A28" smd rect
			(at -2.750058 -2.264918 180)
			(size 0.381 1.4478)
			(layers "F.Cu" "F.Mask" "F.Paste")
			(net "GND")
		)
		(pad "A29" smd rect
			(at -2.750058 1.74498 180)
			(size 0.381 1.4478)
			(layers "F.Cu" "F.Mask" "F.Paste")
			(net "GND")
		)
		(pad "A30" smd rect
			(at -2.750058 2.344928 180)
			(size 0.381 1.4478)
			(layers "F.Cu" "F.Mask" "F.Paste")
			(net "P5E_CPU1_PE1_RX_DN<4>")
		)
		(pad "A31" smd rect
			(at -2.750058 2.944876 180)
			(size 0.381 1.4478)
			(layers "F.Cu" "F.Mask" "F.Paste")
			(net "P5E_CPU1_PE1_RX_DP<4>")
		)
		(pad "A32" smd rect
			(at -2.750058 3.545078 180)
			(size 0.381 1.4478)
			(layers "F.Cu" "F.Mask" "F.Paste")
			(net "GND")
		)
		(pad "A33" smd rect
			(at -2.750058 4.145026 180)
			(size 0.381 1.4478)
			(layers "F.Cu" "F.Mask" "F.Paste")
			(net "P5E_CPU1_PE1_RX_DN<5>")
		)
		(pad "A34" smd rect
			(at -2.750058 4.744974 180)
			(size 0.381 1.4478)
			(layers "F.Cu" "F.Mask" "F.Paste")
			(net "P5E_CPU1_PE1_RX_DP<5>")
		)
		(pad "A35" smd rect
			(at -2.750058 5.344922 180)
			(size 0.381 1.4478)
			(layers "F.Cu" "F.Mask" "F.Paste")
			(net "GND")
		)
		(pad "A36" smd rect
			(at -2.750058 5.945124 180)
			(size 0.381 1.4478)
			(layers "F.Cu" "F.Mask" "F.Paste")
			(net "P5E_CPU1_PE1_RX_DN<6>")
		)
		(pad "A37" smd rect
			(at -2.750058 6.545072 180)
			(size 0.381 1.4478)
			(layers "F.Cu" "F.Mask" "F.Paste")
			(net "P5E_CPU1_PE1_RX_DP<6>")
		)
		(pad "A38" smd rect
			(at -2.750058 7.14502 180)
			(size 0.381 1.4478)
			(layers "F.Cu" "F.Mask" "F.Paste")
			(net "GND")
		)
		(pad "A39" smd rect
			(at -2.750058 7.744968 180)
			(size 0.381 1.4478)
			(layers "F.Cu" "F.Mask" "F.Paste")
			(net "P5E_CPU1_PE1_RX_DN<7>")
		)
		(pad "A40" smd rect
			(at -2.750058 8.344916 180)
			(size 0.381 1.4478)
			(layers "F.Cu" "F.Mask" "F.Paste")
			(net "P5E_CPU1_PE1_RX_DP<7>")
		)
		(pad "A41" smd rect
			(at -2.750058 8.945118 180)
			(size 0.381 1.4478)
			(layers "F.Cu" "F.Mask" "F.Paste")
			(net "GND")
		)
		(pad "A42" smd rect
			(at -2.750058 9.545066 180)
			(size 0.381 1.4478)
			(layers "F.Cu" "F.Mask" "F.Paste")
			(net "OCP_V3_2_PRSNT1_R_N")
		)
		(pad "A43" smd rect
			(at -2.750058 14.454886 180)
			(size 0.381 1.4478)
			(layers "F.Cu" "F.Mask" "F.Paste")
			(net "GND")
		)
		(pad "A44" smd rect
			(at -2.750058 15.055088 180)
			(size 0.381 1.4478)
			(layers "F.Cu" "F.Mask" "F.Paste")
			(net "P5E_CPU1_PE1_RX_DN<8>")
		)
		(pad "A45" smd rect
			(at -2.750058 15.655036 180)
			(size 0.381 1.4478)
			(layers "F.Cu" "F.Mask" "F.Paste")
			(net "P5E_CPU1_PE1_RX_DP<8>")
		)
		(pad "A46" smd rect
			(at -2.750058 16.254984 180)
			(size 0.381 1.4478)
			(layers "F.Cu" "F.Mask" "F.Paste")
			(net "GND")
		)
		(pad "A47" smd rect
			(at -2.750058 16.854932 180)
			(size 0.381 1.4478)
			(layers "F.Cu" "F.Mask" "F.Paste")
			(net "P5E_CPU1_PE1_RX_DN<9>")
		)
		(pad "A48" smd rect
			(at -2.750058 17.45488 180)
			(size 0.381 1.4478)
			(layers "F.Cu" "F.Mask" "F.Paste")
			(net "P5E_CPU1_PE1_RX_DP<9>")
		)
		(pad "A49" smd rect
			(at -2.750058 18.055082 180)
			(size 0.381 1.4478)
			(layers "F.Cu" "F.Mask" "F.Paste")
			(net "GND")
		)
		(pad "A50" smd rect
			(at -2.750058 18.65503 180)
			(size 0.381 1.4478)
			(layers "F.Cu" "F.Mask" "F.Paste")
			(net "P5E_CPU1_PE1_RX_DN<10>")
		)
		(pad "A51" smd rect
			(at -2.750058 19.254978 180)
			(size 0.381 1.4478)
			(layers "F.Cu" "F.Mask" "F.Paste")
			(net "P5E_CPU1_PE1_RX_DP<10>")
		)
		(pad "A52" smd rect
			(at -2.750058 19.854926 180)
			(size 0.381 1.4478)
			(layers "F.Cu" "F.Mask" "F.Paste")
			(net "GND")
		)
		(pad "A53" smd rect
			(at -2.750058 20.455128 180)
			(size 0.381 1.4478)
			(layers "F.Cu" "F.Mask" "F.Paste")
			(net "P5E_CPU1_PE1_RX_DN<11>")
		)
		(pad "A54" smd rect
			(at -2.750058 21.055076 180)
			(size 0.381 1.4478)
			(layers "F.Cu" "F.Mask" "F.Paste")
			(net "P5E_CPU1_PE1_RX_DP<11>")
		)
		(pad "A55" smd rect
			(at -2.750058 21.655024 180)
			(size 0.381 1.4478)
			(layers "F.Cu" "F.Mask" "F.Paste")
			(net "GND")
		)
		(pad "A56" smd rect
			(at -2.750058 22.254972 180)
			(size 0.381 1.4478)
			(layers "F.Cu" "F.Mask" "F.Paste")
			(net "P5E_CPU1_PE1_RX_DN<12>")
		)
		(pad "A57" smd rect
			(at -2.750058 22.85492 180)
			(size 0.381 1.4478)
			(layers "F.Cu" "F.Mask" "F.Paste")
			(net "P5E_CPU1_PE1_RX_DP<12>")
		)
		(pad "A58" smd rect
			(at -2.750058 23.455122 180)
			(size 0.381 1.4478)
			(layers "F.Cu" "F.Mask" "F.Paste")
			(net "GND")
		)
		(pad "A59" smd rect
			(at -2.750058 24.05507 180)
			(size 0.381 1.4478)
			(layers "F.Cu" "F.Mask" "F.Paste")
			(net "P5E_CPU1_PE1_RX_DN<13>")
		)
		(pad "A60" smd rect
			(at -2.750058 24.655018 180)
			(size 0.381 1.4478)
			(layers "F.Cu" "F.Mask" "F.Paste")
			(net "P5E_CPU1_PE1_RX_DP<13>")
		)
		(pad "A61" smd rect
			(at -2.750058 25.254966 180)
			(size 0.381 1.4478)
			(layers "F.Cu" "F.Mask" "F.Paste")
			(net "GND")
		)
		(pad "A62" smd rect
			(at -2.750058 25.854914 180)
			(size 0.381 1.4478)
			(layers "F.Cu" "F.Mask" "F.Paste")
			(net "P5E_CPU1_PE1_RX_DN<14>")
		)
		(pad "A63" smd rect
			(at -2.750058 26.455116 180)
			(size 0.381 1.4478)
			(layers "F.Cu" "F.Mask" "F.Paste")
			(net "P5E_CPU1_PE1_RX_DP<14>")
		)
		(pad "A64" smd rect
			(at -2.750058 27.055064 180)
			(size 0.381 1.4478)
			(layers "F.Cu" "F.Mask" "F.Paste")
			(net "GND")
		)
		(pad "A65" smd rect
			(at -2.750058 27.655012 180)
			(size 0.381 1.4478)
			(layers "F.Cu" "F.Mask" "F.Paste")
			(net "P5E_CPU1_PE1_RX_DN<15>")
		)
		(pad "A66" smd rect
			(at -2.750058 28.25496 180)
			(size 0.381 1.4478)
			(layers "F.Cu" "F.Mask" "F.Paste")
			(net "P5E_CPU1_PE1_RX_DP<15>")
		)
		(pad "A67" smd rect
			(at -2.750058 28.854908 180)
			(size 0.381 1.4478)
			(layers "F.Cu" "F.Mask" "F.Paste")
			(net "GND")
		)
		(pad "A68" smd rect
			(at -2.750058 29.45511 180)
			(size 0.381 1.4478)
			(layers "F.Cu" "F.Mask" "F.Paste")
			(net "USB2_5_R1_DN")
		)
		(pad "A69" smd rect
			(at -2.750058 30.055058 180)
			(size 0.381 1.4478)
			(layers "F.Cu" "F.Mask" "F.Paste")
			(net "USB2_5_R1_DP")
		)
		(pad "A70" smd rect
			(at -2.750058 30.655006 180)
			(size 0.381 1.4478)
			(layers "F.Cu" "F.Mask" "F.Paste")
			(net "OCP_V3_2_PWRBRK_N")
		)
		(pad "B1" smd rect
			(at -5.700014 -18.465038 180)
			(size 0.381 1.4478)
			(layers "F.Cu" "F.Mask" "F.Paste")
			(net "P12V_OCP_V3_2")
		)
		(pad "B2" smd rect
			(at -5.700014 -17.86509 180)
			(size 0.381 1.4478)
			(layers "F.Cu" "F.Mask" "F.Paste")
			(net "P12V_OCP_V3_2")
		)
		(pad "B3" smd rect
			(at -5.700014 -17.264888 180)
			(size 0.381 1.4478)
			(layers "F.Cu" "F.Mask" "F.Paste")
			(net "P12V_OCP_V3_2")
		)
		(pad "B4" smd rect
			(at -5.700014 -16.66494 180)
			(size 0.381 1.4478)
			(layers "F.Cu" "F.Mask" "F.Paste")
			(net "P12V_OCP_V3_2")
		)
		(pad "B5" smd rect
			(at -5.700014 -16.064992 180)
			(size 0.381 1.4478)
			(layers "F.Cu" "F.Mask" "F.Paste")
			(net "P12V_OCP_V3_2")
		)
		(pad "B6" smd rect
			(at -5.700014 -15.465044 180)
			(size 0.381 1.4478)
			(layers "F.Cu" "F.Mask" "F.Paste")
			(net "P12V_OCP_V3_2")
		)
		(pad "B7" smd rect
			(at -5.700014 -14.865096 180)
			(size 0.381 1.4478)
			(layers "F.Cu" "F.Mask" "F.Paste")
			(net "OCP_V3_2_BIF0_R_N")
		)
		(pad "B8" smd rect
			(at -5.700014 -14.264894 180)
			(size 0.381 1.4478)
			(layers "F.Cu" "F.Mask" "F.Paste")
			(net "OCP_V3_2_BIF1_R_N")
		)
		(pad "B9" smd rect
			(at -5.700014 -13.664946 180)
			(size 0.381 1.4478)
			(layers "F.Cu" "F.Mask" "F.Paste")
			(net "OCP_V3_2_BIF2_R_N")
		)
		(pad "B10" smd rect
			(at -5.700014 -13.064998 180)
			(size 0.381 1.4478)
			(layers "F.Cu" "F.Mask" "F.Paste")
			(net "RST_PERST0_OCP_V3_2_N")
		)
		(pad "B11" smd rect
			(at -5.700014 -12.46505 180)
			(size 0.381 1.4478)
			(layers "F.Cu" "F.Mask" "F.Paste")
			(net "P3V3_OCP_V3_2")
		)
		(pad "B12" smd rect
			(at -5.700014 -11.865102 180)
			(size 0.381 1.4478)
			(layers "F.Cu" "F.Mask" "F.Paste")
			(net "OCP_V3_2_AUX_PWR_EN_R")
		)
		(pad "B13" smd rect
			(at -5.700014 -11.2649 180)
			(size 0.381 1.4478)
			(layers "F.Cu" "F.Mask" "F.Paste")
			(net "GND")
		)
		(pad "B14" smd rect
			(at -5.700014 -10.664952 180)
			(size 0.381 1.4478)
			(layers "F.Cu" "F.Mask" "F.Paste")
			(net "CLK_100M_OCP_V3_2_A_DN")
		)
		(pad "B15" smd rect
			(at -5.700014 -10.065004 180)
			(size 0.381 1.4478)
			(layers "F.Cu" "F.Mask" "F.Paste")
			(net "CLK_100M_OCP_V3_2_A_DP")
		)
		(pad "B16" smd rect
			(at -5.700014 -9.465056 180)
			(size 0.381 1.4478)
			(layers "F.Cu" "F.Mask" "F.Paste")
			(net "GND")
		)
		(pad "B17" smd rect
			(at -5.700014 -8.865108 180)
			(size 0.381 1.4478)
			(layers "F.Cu" "F.Mask" "F.Paste")
			(net "P5E_CPU1_PE1_TX_C_DP<0>")
		)
		(pad "B18" smd rect
			(at -5.700014 -8.264906 180)
			(size 0.381 1.4478)
			(layers "F.Cu" "F.Mask" "F.Paste")
			(net "P5E_CPU1_PE1_TX_C_DN<0>")
		)
		(pad "B19" smd rect
			(at -5.700014 -7.664958 180)
			(size 0.381 1.4478)
			(layers "F.Cu" "F.Mask" "F.Paste")
			(net "GND")
		)
		(pad "B20" smd rect
			(at -5.700014 -7.06501 180)
			(size 0.381 1.4478)
			(layers "F.Cu" "F.Mask" "F.Paste")
			(net "P5E_CPU1_PE1_TX_C_DN<1>")
		)
		(pad "B21" smd rect
			(at -5.700014 -6.465062 180)
			(size 0.381 1.4478)
			(layers "F.Cu" "F.Mask" "F.Paste")
			(net "P5E_CPU1_PE1_TX_C_DP<1>")
		)
		(pad "B22" smd rect
			(at -5.700014 -5.865114 180)
			(size 0.381 1.4478)
			(layers "F.Cu" "F.Mask" "F.Paste")
			(net "GND")
		)
		(pad "B23" smd rect
			(at -5.700014 -5.264912 180)
			(size 0.381 1.4478)
			(layers "F.Cu" "F.Mask" "F.Paste")
			(net "P5E_CPU1_PE1_TX_C_DP<2>")
		)
		(pad "B24" smd rect
			(at -5.700014 -4.664964 180)
			(size 0.381 1.4478)
			(layers "F.Cu" "F.Mask" "F.Paste")
			(net "P5E_CPU1_PE1_TX_C_DN<2>")
		)
		(pad "B25" smd rect
			(at -5.700014 -4.065016 180)
			(size 0.381 1.4478)
			(layers "F.Cu" "F.Mask" "F.Paste")
			(net "GND")
		)
		(pad "B26" smd rect
			(at -5.700014 -3.465068 180)
			(size 0.381 1.4478)
			(layers "F.Cu" "F.Mask" "F.Paste")
			(net "P5E_CPU1_PE1_TX_C_DN<3>")
		)
		(pad "B27" smd rect
			(at -5.700014 -2.86512 180)
			(size 0.381 1.4478)
			(layers "F.Cu" "F.Mask" "F.Paste")
			(net "P5E_CPU1_PE1_TX_C_DP<3>")
		)
		(pad "B28" smd rect
			(at -5.700014 -2.264918 180)
			(size 0.381 1.4478)
			(layers "F.Cu" "F.Mask" "F.Paste")
			(net "GND")
		)
		(pad "B29" smd rect
			(at -5.700014 1.74498 180)
			(size 0.381 1.4478)
			(layers "F.Cu" "F.Mask" "F.Paste")
			(net "GND")
		)
		(pad "B30" smd rect
			(at -5.700014 2.344928 180)
			(size 0.381 1.4478)
			(layers "F.Cu" "F.Mask" "F.Paste")
			(net "P5E_CPU1_PE1_TX_C_DP<4>")
		)
		(pad "B31" smd rect
			(at -5.700014 2.944876 180)
			(size 0.381 1.4478)
			(layers "F.Cu" "F.Mask" "F.Paste")
			(net "P5E_CPU1_PE1_TX_C_DN<4>")
		)
		(pad "B32" smd rect
			(at -5.700014 3.545078 180)
			(size 0.381 1.4478)
			(layers "F.Cu" "F.Mask" "F.Paste")
			(net "GND")
		)
		(pad "B33" smd rect
			(at -5.700014 4.145026 180)
			(size 0.381 1.4478)
			(layers "F.Cu" "F.Mask" "F.Paste")
			(net "P5E_CPU1_PE1_TX_C_DN<5>")
		)
		(pad "B34" smd rect
			(at -5.700014 4.744974 180)
			(size 0.381 1.4478)
			(layers "F.Cu" "F.Mask" "F.Paste")
			(net "P5E_CPU1_PE1_TX_C_DP<5>")
		)
		(pad "B35" smd rect
			(at -5.700014 5.344922 180)
			(size 0.381 1.4478)
			(layers "F.Cu" "F.Mask" "F.Paste")
			(net "GND")
		)
		(pad "B36" smd rect
			(at -5.700014 5.945124 180)
			(size 0.381 1.4478)
			(layers "F.Cu" "F.Mask" "F.Paste")
			(net "P5E_CPU1_PE1_TX_C_DP<6>")
		)
		(pad "B37" smd rect
			(at -5.700014 6.545072 180)
			(size 0.381 1.4478)
			(layers "F.Cu" "F.Mask" "F.Paste")
			(net "P5E_CPU1_PE1_TX_C_DN<6>")
		)
		(pad "B38" smd rect
			(at -5.700014 7.14502 180)
			(size 0.381 1.4478)
			(layers "F.Cu" "F.Mask" "F.Paste")
			(net "GND")
		)
		(pad "B39" smd rect
			(at -5.700014 7.744968 180)
			(size 0.381 1.4478)
			(layers "F.Cu" "F.Mask" "F.Paste")
			(net "P5E_CPU1_PE1_TX_C_DN<7>")
		)
		(pad "B40" smd rect
			(at -5.700014 8.344916 180)
			(size 0.381 1.4478)
			(layers "F.Cu" "F.Mask" "F.Paste")
			(net "P5E_CPU1_PE1_TX_C_DP<7>")
		)
		(pad "B41" smd rect
			(at -5.700014 8.945118 180)
			(size 0.381 1.4478)
			(layers "F.Cu" "F.Mask" "F.Paste")
			(net "GND")
		)
		(pad "B42" smd rect
			(at -5.700014 9.545066 180)
			(size 0.381 1.4478)
			(layers "F.Cu" "F.Mask" "F.Paste")
			(net "OCP_V3_2_PRSNT0_R_N")
		)
		(pad "B43" smd rect
			(at -5.700014 14.454886 180)
			(size 0.381 1.4478)
			(layers "F.Cu" "F.Mask" "F.Paste")
			(net "GND")
		)
		(pad "B44" smd rect
			(at -5.700014 15.055088 180)
			(size 0.381 1.4478)
			(layers "F.Cu" "F.Mask" "F.Paste")
			(net "P5E_CPU1_PE1_TX_C_DP<8>")
		)
		(pad "B45" smd rect
			(at -5.700014 15.655036 180)
			(size 0.381 1.4478)
			(layers "F.Cu" "F.Mask" "F.Paste")
			(net "P5E_CPU1_PE1_TX_C_DN<8>")
		)
		(pad "B46" smd rect
			(at -5.700014 16.254984 180)
			(size 0.381 1.4478)
			(layers "F.Cu" "F.Mask" "F.Paste")
			(net "GND")
		)
		(pad "B47" smd rect
			(at -5.700014 16.854932 180)
			(size 0.381 1.4478)
			(layers "F.Cu" "F.Mask" "F.Paste")
			(net "P5E_CPU1_PE1_TX_C_DN<9>")
		)
		(pad "B48" smd rect
			(at -5.700014 17.45488 180)
			(size 0.381 1.4478)
			(layers "F.Cu" "F.Mask" "F.Paste")
			(net "P5E_CPU1_PE1_TX_C_DP<9>")
		)
		(pad "B49" smd rect
			(at -5.700014 18.055082 180)
			(size 0.381 1.4478)
			(layers "F.Cu" "F.Mask" "F.Paste")
			(net "GND")
		)
		(pad "B50" smd rect
			(at -5.700014 18.65503 180)
			(size 0.381 1.4478)
			(layers "F.Cu" "F.Mask" "F.Paste")
			(net "P5E_CPU1_PE1_TX_C_DP<10>")
		)
		(pad "B51" smd rect
			(at -5.700014 19.254978 180)
			(size 0.381 1.4478)
			(layers "F.Cu" "F.Mask" "F.Paste")
			(net "P5E_CPU1_PE1_TX_C_DN<10>")
		)
		(pad "B52" smd rect
			(at -5.700014 19.854926 180)
			(size 0.381 1.4478)
			(layers "F.Cu" "F.Mask" "F.Paste")
			(net "GND")
		)
		(pad "B53" smd rect
			(at -5.700014 20.455128 180)
			(size 0.381 1.4478)
			(layers "F.Cu" "F.Mask" "F.Paste")
			(net "P5E_CPU1_PE1_TX_C_DN<11>")
		)
		(pad "B54" smd rect
			(at -5.700014 21.055076 180)
			(size 0.381 1.4478)
			(layers "F.Cu" "F.Mask" "F.Paste")
			(net "P5E_CPU1_PE1_TX_C_DP<11>")
		)
		(pad "B55" smd rect
			(at -5.700014 21.655024 180)
			(size 0.381 1.4478)
			(layers "F.Cu" "F.Mask" "F.Paste")
			(net "GND")
		)
		(pad "B56" smd rect
			(at -5.700014 22.254972 180)
			(size 0.381 1.4478)
			(layers "F.Cu" "F.Mask" "F.Paste")
			(net "P5E_CPU1_PE1_TX_C_DP<12>")
		)
		(pad "B57" smd rect
			(at -5.700014 22.85492 180)
			(size 0.381 1.4478)
			(layers "F.Cu" "F.Mask" "F.Paste")
			(net "P5E_CPU1_PE1_TX_C_DN<12>")
		)
		(pad "B58" smd rect
			(at -5.700014 23.455122 180)
			(size 0.381 1.4478)
			(layers "F.Cu" "F.Mask" "F.Paste")
			(net "GND")
		)
		(pad "B59" smd rect
			(at -5.700014 24.05507 180)
			(size 0.381 1.4478)
			(layers "F.Cu" "F.Mask" "F.Paste")
			(net "P5E_CPU1_PE1_TX_C_DN<13>")
		)
		(pad "B60" smd rect
			(at -5.700014 24.655018 180)
			(size 0.381 1.4478)
			(layers "F.Cu" "F.Mask" "F.Paste")
			(net "P5E_CPU1_PE1_TX_C_DP<13>")
		)
		(pad "B61" smd rect
			(at -5.700014 25.254966 180)
			(size 0.381 1.4478)
			(layers "F.Cu" "F.Mask" "F.Paste")
			(net "GND")
		)
		(pad "B62" smd rect
			(at -5.700014 25.854914 180)
			(size 0.381 1.4478)
			(layers "F.Cu" "F.Mask" "F.Paste")
			(net "P5E_CPU1_PE1_TX_C_DP<14>")
		)
		(pad "B63" smd rect
			(at -5.700014 26.455116 180)
			(size 0.381 1.4478)
			(layers "F.Cu" "F.Mask" "F.Paste")
			(net "P5E_CPU1_PE1_TX_C_DN<14>")
		)
		(pad "B64" smd rect
			(at -5.700014 27.055064 180)
			(size 0.381 1.4478)
			(layers "F.Cu" "F.Mask" "F.Paste")
			(net "GND")
		)
		(pad "B65" smd rect
			(at -5.700014 27.655012 180)
			(size 0.381 1.4478)
			(layers "F.Cu" "F.Mask" "F.Paste")
			(net "P5E_CPU1_PE1_TX_C_DN<15>")
		)
		(pad "B66" smd rect
			(at -5.700014 28.25496 180)
			(size 0.381 1.4478)
			(layers "F.Cu" "F.Mask" "F.Paste")
			(net "P5E_CPU1_PE1_TX_C_DP<15>")
		)
		(pad "B67" smd rect
			(at -5.700014 28.854908 180)
			(size 0.381 1.4478)
			(layers "F.Cu" "F.Mask" "F.Paste")
			(net "GND")
		)
		(pad "B68" smd rect
			(at -5.700014 29.45511 180)
			(size 0.381 1.4478)
			(layers "F.Cu" "F.Mask" "F.Paste")
			(net "TP_OCP_V3_2_B68")
		)
		(pad "B69" smd rect
			(at -5.700014 30.055058 180)
			(size 0.381 1.4478)
			(layers "F.Cu" "F.Mask" "F.Paste")
			(net "TP_OCP_V3_2_B69")
		)
		(pad "B70" smd rect
			(at -5.700014 30.655006 180)
			(size 0.381 1.4478)
			(layers "F.Cu" "F.Mask" "F.Paste")
			(net "OCP_V3_2_PRSNT3_R_N")
		)
		(pad "G1" thru_hole circle
			(at 2.400046 -32.759904 180)
			(size 1.6256 1.6256)
			(drill 1.1176)
			(layers "*.Cu" "*.Mask")
			(remove_unused_layers no)
			(net "GND")
			(clearance 0)
		)
		(pad "G2" thru_hole circle
			(at 2.400046 -20.379944 180)
			(size 1.6256 1.6256)
			(drill 1.1176)
			(layers "*.Cu" "*.Mask")
			(remove_unused_layers no)
			(net "GND")
			(clearance 0)
		)
		(pad "G3" thru_hole circle
			(at 2.400046 0 180)
			(size 1.6256 1.6256)
			(drill 1.1176)
			(layers "*.Cu" "*.Mask")
			(remove_unused_layers no)
			(net "GND")
			(clearance 0)
		)
		(pad "G4" thru_hole circle
			(at 2.400046 12.5349 180)
			(size 1.6256 1.6256)
			(drill 1.1176)
			(layers "*.Cu" "*.Mask")
			(remove_unused_layers no)
			(net "GND")
			(clearance 0)
		)
		(pad "G5" thru_hole circle
			(at 2.400046 32.759904 180)
			(size 1.6256 1.6256)
			(drill 1.1176)
			(layers "*.Cu" "*.Mask")
			(remove_unused_layers no)
			(net "GND")
			(clearance 0)
		)
		(pad "OA1" smd rect
			(at -2.750058 -30.660086 180)
			(size 0.381 1.4478)
			(layers "F.Cu" "F.Mask" "F.Paste")
			(net "RST_PERST2_OCP_V3_2_N")
		)
		(pad "OA2" smd rect
			(at -2.750058 -30.059884 180)
			(size 0.381 1.4478)
			(layers "F.Cu" "F.Mask" "F.Paste")
			(net "RST_PERST3_OCP_V3_2_N")
		)
		(pad "OA3" smd rect
			(at -2.750058 -29.459936 180)
			(size 0.381 1.4478)
			(layers "F.Cu" "F.Mask" "F.Paste")
			(net "IRQ_LVC3_OCP_V3_2_WAKE_N")
		)
		(pad "OA4" smd rect
			(at -2.750058 -28.859988 180)
			(size 0.381 1.4478)
			(layers "F.Cu" "F.Mask" "F.Paste")
			(net "OCP_V3_2_ISO1_RBT_ARB_IN")
		)
		(pad "OA5" smd rect
			(at -2.750058 -28.26004 180)
			(size 0.381 1.4478)
			(layers "F.Cu" "F.Mask" "F.Paste")
			(net "OCP_V3_2_ISO2_RBT_ARB_OUT")
		)
		(pad "OA6" smd rect
			(at -2.750058 -27.660092 180)
			(size 0.381 1.4478)
			(layers "F.Cu" "F.Mask" "F.Paste")
			(net "OCP_V3_2_ID1")
		)
		(pad "OA7" smd rect
			(at -2.750058 -27.05989 180)
			(size 0.381 1.4478)
			(layers "F.Cu" "F.Mask" "F.Paste")
			(net "NCSI_OCP_V3_2_TX_EN")
		)
		(pad "OA8" smd rect
			(at -2.750058 -26.459942 180)
			(size 0.381 1.4478)
			(layers "F.Cu" "F.Mask" "F.Paste")
			(net "NCSI_OCP_V3_2_TXD1")
		)
		(pad "OA9" smd rect
			(at -2.750058 -25.859994 180)
			(size 0.381 1.4478)
			(layers "F.Cu" "F.Mask" "F.Paste")
			(net "NCSI_OCP_V3_2_TXD0")
		)
		(pad "OA10" smd rect
			(at -2.750058 -25.260046 180)
			(size 0.381 1.4478)
			(layers "F.Cu" "F.Mask" "F.Paste")
			(net "GND")
		)
		(pad "OA11" smd rect
			(at -2.750058 -24.660098 180)
			(size 0.381 1.4478)
			(layers "F.Cu" "F.Mask" "F.Paste")
			(net "CLK_100M_OCP_V3_2_D_DN")
		)
		(pad "OA12" smd rect
			(at -2.750058 -24.059896 180)
			(size 0.381 1.4478)
			(layers "F.Cu" "F.Mask" "F.Paste")
			(net "CLK_100M_OCP_V3_2_D_DP")
		)
		(pad "OA13" smd rect
			(at -2.750058 -23.459948 180)
			(size 0.381 1.4478)
			(layers "F.Cu" "F.Mask" "F.Paste")
			(net "GND")
		)
		(pad "OA14" smd rect
			(at -2.750058 -22.86 180)
			(size 0.381 1.4478)
			(layers "F.Cu" "F.Mask" "F.Paste")
			(net "CLK_50M_NCSI_OCP_V3_2_ISO")
		)
		(pad "OB1" smd rect
			(at -5.700014 -30.660086 180)
			(size 0.381 1.4478)
			(layers "F.Cu" "F.Mask" "F.Paste")
			(net "FM_OCP_V3_2_PWR_GOOD")
		)
		(pad "OB2" smd rect
			(at -5.700014 -30.059884 180)
			(size 0.381 1.4478)
			(layers "F.Cu" "F.Mask" "F.Paste")
			(net "OCP_V3_2_MAIN_PWR_EN_R")
		)
		(pad "OB3" smd rect
			(at -5.700014 -29.459936 180)
			(size 0.381 1.4478)
			(layers "F.Cu" "F.Mask" "F.Paste")
			(net "SGPIO_OCP_V3_2_LD_N")
		)
		(pad "OB4" smd rect
			(at -5.700014 -28.859988 180)
			(size 0.381 1.4478)
			(layers "F.Cu" "F.Mask" "F.Paste")
			(net "SGPIO_OCP_V3_2_DATAIN")
		)
		(pad "OB5" smd rect
			(at -5.700014 -28.26004 180)
			(size 0.381 1.4478)
			(layers "F.Cu" "F.Mask" "F.Paste")
			(net "SGPIO_OCP_V3_2_DATAOUT")
		)
		(pad "OB6" smd rect
			(at -5.700014 -27.660092 180)
			(size 0.381 1.4478)
			(layers "F.Cu" "F.Mask" "F.Paste")
			(net "SGPIO_OCP_V3_2_CLK")
		)
		(pad "OB7" smd rect
			(at -5.700014 -27.05989 180)
			(size 0.381 1.4478)
			(layers "F.Cu" "F.Mask" "F.Paste")
			(net "OCP_V3_2_ID0")
		)
		(pad "OB8" smd rect
			(at -5.700014 -26.459942 180)
			(size 0.381 1.4478)
			(layers "F.Cu" "F.Mask" "F.Paste")
			(net "NCSI_OCP_V3_2_RXD1")
		)
		(pad "OB9" smd rect
			(at -5.700014 -25.859994 180)
			(size 0.381 1.4478)
			(layers "F.Cu" "F.Mask" "F.Paste")
			(net "NCSI_OCP_V3_2_RXD0")
		)
		(pad "OB10" smd rect
			(at -5.700014 -25.260046 180)
			(size 0.381 1.4478)
			(layers "F.Cu" "F.Mask" "F.Paste")
			(net "GND")
		)
		(pad "OB11" smd rect
			(at -5.700014 -24.660098 180)
			(size 0.381 1.4478)
			(layers "F.Cu" "F.Mask" "F.Paste")
			(net "CLK_100M_OCP_V3_2_C_DN")
		)
		(pad "OB12" smd rect
			(at -5.700014 -24.059896 180)
			(size 0.381 1.4478)
			(layers "F.Cu" "F.Mask" "F.Paste")
			(net "CLK_100M_OCP_V3_2_C_DP")
		)
		(pad "OB13" smd rect
			(at -5.700014 -23.459948 180)
			(size 0.381 1.4478)
			(layers "F.Cu" "F.Mask" "F.Paste")
			(net "GND")
		)
		(pad "OB14" smd rect
			(at -5.700014 -22.86 180)
			(size 0.381 1.4478)
			(layers "F.Cu" "F.Mask" "F.Paste")
			(net "NCSI_OCP_V3_2_CRS_DV")
		)
		(zone
			(layers "F.Cu" "B.Cu" "In1.Cu" "In2.Cu" "In3.Cu" "In4.Cu" "In5.Cu" "In6.Cu"
				"In7.Cu" "In8.Cu" "In9.Cu" "In10.Cu" "In11.Cu" "In12.Cu" "In13.Cu" "In14.Cu"
				"In15.Cu" "In16.Cu"
			)
			(hatch none 0.5)
			(connect_pads
				(clearance 0)
			)
			(min_thickness 0.25)
			(keepout
				(tracks not_allowed)
				(vias allowed)
				(pads allowed)
				(copperpour not_allowed)
				(footprints allowed)
			)
			(placement
				(enabled no)
				(sheetname "")
			)
			(fill
				(thermal_gap 0.5)
				(thermal_bridge_width 0.5)
				(island_removal_mode 0)
			)
			(polygon
				(pts
					(arc
						(start 16.282162 -5.169916)
						(mid 14.351762 -5.169916)
						(end 16.282162 -5.169916)
					)
				)
			)
		)
		(zone
			(layers "F.Cu" "B.Cu" "In1.Cu" "In2.Cu" "In3.Cu" "In4.Cu" "In5.Cu" "In6.Cu"
				"In7.Cu" "In8.Cu" "In9.Cu" "In10.Cu" "In11.Cu" "In12.Cu" "In13.Cu" "In14.Cu"
				"In15.Cu" "In16.Cu"
			)
			(hatch none 0.5)
			(connect_pads
				(clearance 0)
			)
			(min_thickness 0.25)
			(keepout
				(tracks not_allowed)
				(vias allowed)
				(pads allowed)
				(copperpour not_allowed)
				(footprints allowed)
			)
			(placement
				(enabled no)
				(sheetname "")
			)
			(fill
				(thermal_gap 0.5)
				(thermal_bridge_width 0.5)
				(island_removal_mode 0)
			)
			(polygon
				(pts
					(arc
						(start 80.447134 -6.169914)
						(mid 78.516734 -6.169914)
						(end 80.447134 -6.169914)
					)
				)
			)
		)
	)
	(footprint ""
		(layer "F.Cu")
		(at 105.973372 -74.993246 -90)
		(property "Reference" "R3072"
			(at 0 0 270)
			(layer "F.SilkS")
			(hide yes)
			(effects
				(font
					(size 1.27 1.27)
				)
			)
		)
		(property "Value" ""
			(at 0 0 270)
			(layer "F.Fab")
			(effects
				(font
					(size 1.27 1.27)
				)
			)
		)
		(duplicate_pad_numbers_are_jumpers no)
		(fp_line
			(start -0.7874 0.4064)
			(end -0.7874 -0.4064)
			(stroke
				(width 0.1524)
				(type default)
			)
			(layer "F.SilkS")
		)
		(fp_line
			(start 0.7874 0.4064)
			(end -0.7874 0.4064)
			(stroke
				(width 0.1524)
				(type default)
			)
			(layer "F.SilkS")
		)
		(fp_line
			(start -0.7874 -0.4064)
			(end 0.7874 -0.4064)
			(stroke
				(width 0.1524)
				(type default)
			)
			(layer "F.SilkS")
		)
		(fp_line
			(start 0.7874 -0.4064)
			(end 0.7874 0.4064)
			(stroke
				(width 0.1524)
				(type default)
			)
			(layer "F.SilkS")
		)
		(fp_line
			(start -0.67945 0.3048)
			(end -0.67945 -0.305054)
			(stroke
				(width 0.1)
				(type default)
			)
			(layer "F.Fab")
		)
		(fp_line
			(start -0.12065 0.3048)
			(end -0.67945 0.3048)
			(stroke
				(width 0.1)
				(type default)
			)
			(layer "F.Fab")
		)
		(fp_line
			(start 0.120396 0.3048)
			(end 0.120396 0.2794)
			(stroke
				(width 0.1)
				(type default)
			)
			(layer "F.Fab")
		)
		(fp_line
			(start 0.67945 0.3048)
			(end 0.120396 0.3048)
			(stroke
				(width 0.1)
				(type default)
			)
			(layer "F.Fab")
		)
		(fp_line
			(start -0.12065 0.2794)
			(end -0.12065 0.3048)
			(stroke
				(width 0.1)
				(type default)
			)
			(layer "F.Fab")
		)
		(fp_line
			(start 0.120396 0.2794)
			(end -0.12065 0.2794)
			(stroke
				(width 0.1)
				(type default)
			)
			(layer "F.Fab")
		)
		(fp_line
			(start -0.12065 -0.2794)
			(end 0.12065 -0.2794)
			(stroke
				(width 0.1)
				(type default)
			)
			(layer "F.Fab")
		)
		(fp_line
			(start 0.12065 -0.2794)
			(end 0.12065 -0.3048)
			(stroke
				(width 0.1)
				(type default)
			)
			(layer "F.Fab")
		)
		(fp_line
			(start 0.12065 -0.3048)
			(end 0.67945 -0.3048)
			(stroke
				(width 0.1)
				(type default)
			)
			(layer "F.Fab")
		)
		(fp_line
			(start 0.67945 -0.3048)
			(end 0.67945 0.3048)
			(stroke
				(width 0.1)
				(type default)
			)
			(layer "F.Fab")
		)
		(fp_line
			(start -0.67945 -0.305054)
			(end -0.12065 -0.305054)
			(stroke
				(width 0.1)
				(type default)
			)
			(layer "F.Fab")
		)
		(fp_line
			(start -0.12065 -0.305054)
			(end -0.12065 -0.2794)
			(stroke
				(width 0.1)
				(type default)
			)
			(layer "F.Fab")
		)
		(pad "1" smd circle
			(at -0.40005 0 270)
			(size 0 0)
			(layers "F.Cu" "F.Mask" "F.Paste")
			(net "LED_PWRGD_P1V05_PCH_AUX")
		)
		(pad "2" smd circle
			(at 0.40005 0 270)
			(size 0 0)
			(layers "F.Cu" "F.Mask" "F.Paste")
			(net "P3V3_AUX")
		)
	)
	(footprint ""
		(layer "F.Cu")
		(at 460.74457 -36.70808 -90)
		(property "Reference" "R3784"
			(at 0 0 270)
			(layer "F.SilkS")
			(hide yes)
			(effects
				(font
					(size 1.27 1.27)
				)
			)
		)
		(property "Value" ""
			(at 0 0 270)
			(layer "F.Fab")
			(effects
				(font
					(size 1.27 1.27)
				)
			)
		)
		(duplicate_pad_numbers_are_jumpers no)
		(fp_line
			(start -0.7874 0.4064)
			(end -0.7874 -0.4064)
			(stroke
				(width 0.1524)
				(type default)
			)
			(layer "F.SilkS")
		)
		(fp_line
			(start 0.7874 0.4064)
			(end -0.7874 0.4064)
			(stroke
				(width 0.1524)
				(type default)
			)
			(layer "F.SilkS")
		)
		(fp_line
			(start -0.7874 -0.4064)
			(end 0.7874 -0.4064)
			(stroke
				(width 0.1524)
				(type default)
			)
			(layer "F.SilkS")
		)
		(fp_line
			(start 0.7874 -0.4064)
			(end 0.7874 0.4064)
			(stroke
				(width 0.1524)
				(type default)
			)
			(layer "F.SilkS")
		)
		(fp_line
			(start -0.67945 0.3048)
			(end -0.67945 -0.305054)
			(stroke
				(width 0.1)
				(type default)
			)
			(layer "F.Fab")
		)
		(fp_line
			(start -0.12065 0.3048)
			(end -0.67945 0.3048)
			(stroke
				(width 0.1)
				(type default)
			)
			(layer "F.Fab")
		)
		(fp_line
			(start 0.120396 0.3048)
			(end 0.120396 0.2794)
			(stroke
				(width 0.1)
				(type default)
			)
			(layer "F.Fab")
		)
		(fp_line
			(start 0.67945 0.3048)
			(end 0.120396 0.3048)
			(stroke
				(width 0.1)
				(type default)
			)
			(layer "F.Fab")
		)
		(fp_line
			(start -0.12065 0.2794)
			(end -0.12065 0.3048)
			(stroke
				(width 0.1)
				(type default)
			)
			(layer "F.Fab")
		)
		(fp_line
			(start 0.120396 0.2794)
			(end -0.12065 0.2794)
			(stroke
				(width 0.1)
				(type default)
			)
			(layer "F.Fab")
		)
		(fp_line
			(start -0.12065 -0.2794)
			(end 0.12065 -0.2794)
			(stroke
				(width 0.1)
				(type default)
			)
			(layer "F.Fab")
		)
		(fp_line
			(start 0.12065 -0.2794)
			(end 0.12065 -0.3048)
			(stroke
				(width 0.1)
				(type default)
			)
			(layer "F.Fab")
		)
		(fp_line
			(start 0.12065 -0.3048)
			(end 0.67945 -0.3048)
			(stroke
				(width 0.1)
				(type default)
			)
			(layer "F.Fab")
		)
		(fp_line
			(start 0.67945 -0.3048)
			(end 0.67945 0.3048)
			(stroke
				(width 0.1)
				(type default)
			)
			(layer "F.Fab")
		)
		(fp_line
			(start -0.67945 -0.305054)
			(end -0.12065 -0.305054)
			(stroke
				(width 0.1)
				(type default)
			)
			(layer "F.Fab")
		)
		(fp_line
			(start -0.12065 -0.305054)
			(end -0.12065 -0.2794)
			(stroke
				(width 0.1)
				(type default)
			)
			(layer "F.Fab")
		)
		(pad "1" smd circle
			(at -0.40005 0 270)
			(size 0 0)
			(layers "F.Cu" "F.Mask" "F.Paste")
			(net "P12V_OCP_UV_1_R")
		)
		(pad "2" smd circle
			(at 0.40005 0 270)
			(size 0 0)
			(layers "F.Cu" "F.Mask" "F.Paste")
			(net "P12V_OCP_UV_1")
		)
	)
	(footprint ""
		(layer "F.Cu")
		(at 352.270314 -256.654046 -90)
		(property "Reference" "C421"
			(at 0 0 270)
			(layer "F.SilkS")
			(hide yes)
			(effects
				(font
					(size 1.27 1.27)
				)
			)
		)
		(property "Value" ""
			(at 0 0 270)
			(layer "F.Fab")
			(effects
				(font
					(size 1.27 1.27)
				)
			)
		)
		(duplicate_pad_numbers_are_jumpers no)
		(fp_line
			(start -0.7874 0.4064)
			(end -0.7874 -0.4064)
			(stroke
				(width 0.1524)
				(type default)
			)
			(layer "F.SilkS")
		)
		(fp_line
			(start 0.7874 0.4064)
			(end -0.7874 0.4064)
			(stroke
				(width 0.1524)
				(type default)
			)
			(layer "F.SilkS")
		)
		(fp_line
			(start -0.7874 -0.4064)
			(end 0.7874 -0.4064)
			(stroke
				(width 0.1524)
				(type default)
			)
			(layer "F.SilkS")
		)
		(fp_line
			(start 0.7874 -0.4064)
			(end 0.7874 0.4064)
			(stroke
				(width 0.1524)
				(type default)
			)
			(layer "F.SilkS")
		)
		(fp_line
			(start -0.67945 0.3048)
			(end -0.67945 -0.305054)
			(stroke
				(width 0.1)
				(type default)
			)
			(layer "F.Fab")
		)
		(fp_line
			(start -0.12065 0.3048)
			(end -0.67945 0.3048)
			(stroke
				(width 0.1)
				(type default)
			)
			(layer "F.Fab")
		)
		(fp_line
			(start 0.120396 0.3048)
			(end 0.120396 0.2794)
			(stroke
				(width 0.1)
				(type default)
			)
			(layer "F.Fab")
		)
		(fp_line
			(start 0.67945 0.3048)
			(end 0.120396 0.3048)
			(stroke
				(width 0.1)
				(type default)
			)
			(layer "F.Fab")
		)
		(fp_line
			(start -0.12065 0.2794)
			(end -0.12065 0.3048)
			(stroke
				(width 0.1)
				(type default)
			)
			(layer "F.Fab")
		)
		(fp_line
			(start 0.120396 0.2794)
			(end -0.12065 0.2794)
			(stroke
				(width 0.1)
				(type default)
			)
			(layer "F.Fab")
		)
		(fp_line
			(start -0.12065 -0.2794)
			(end 0.12065 -0.2794)
			(stroke
				(width 0.1)
				(type default)
			)
			(layer "F.Fab")
		)
		(fp_line
			(start 0.12065 -0.2794)
			(end 0.12065 -0.3048)
			(stroke
				(width 0.1)
				(type default)
			)
			(layer "F.Fab")
		)
		(fp_line
			(start 0.12065 -0.3048)
			(end 0.67945 -0.3048)
			(stroke
				(width 0.1)
				(type default)
			)
			(layer "F.Fab")
		)
		(fp_line
			(start 0.67945 -0.3048)
			(end 0.67945 0.3048)
			(stroke
				(width 0.1)
				(type default)
			)
			(layer "F.Fab")
		)
		(fp_line
			(start -0.67945 -0.305054)
			(end -0.12065 -0.305054)
			(stroke
				(width 0.1)
				(type default)
			)
			(layer "F.Fab")
		)
		(fp_line
			(start -0.12065 -0.305054)
			(end -0.12065 -0.2794)
			(stroke
				(width 0.1)
				(type default)
			)
			(layer "F.Fab")
		)
		(pad "1" smd circle
			(at -0.40005 0 270)
			(size 0 0)
			(layers "F.Cu" "F.Mask" "F.Paste")
			(net "PVCCFA_EHV_CPU0")
		)
		(pad "2" smd circle
			(at 0.40005 0 270)
			(size 0 0)
			(layers "F.Cu" "F.Mask" "F.Paste")
			(net "GND")
		)
	)
	(footprint ""
		(layer "F.Cu")
		(at 259.064506 -75.923902 -90)
		(property "Reference" "R1389"
			(at 0 0 270)
			(layer "F.SilkS")
			(hide yes)
			(effects
				(font
					(size 1.27 1.27)
				)
			)
		)
		(property "Value" ""
			(at 0 0 270)
			(layer "F.Fab")
			(effects
				(font
					(size 1.27 1.27)
				)
			)
		)
		(duplicate_pad_numbers_are_jumpers no)
		(fp_line
			(start -0.7874 0.4064)
			(end -0.7874 -0.4064)
			(stroke
				(width 0.1524)
				(type default)
			)
			(layer "F.SilkS")
		)
		(fp_line
			(start 0.7874 0.4064)
			(end -0.7874 0.4064)
			(stroke
				(width 0.1524)
				(type default)
			)
			(layer "F.SilkS")
		)
		(fp_line
			(start -0.7874 -0.4064)
			(end 0.7874 -0.4064)
			(stroke
				(width 0.1524)
				(type default)
			)
			(layer "F.SilkS")
		)
		(fp_line
			(start 0.7874 -0.4064)
			(end 0.7874 0.4064)
			(stroke
				(width 0.1524)
				(type default)
			)
			(layer "F.SilkS")
		)
		(fp_line
			(start -0.67945 0.3048)
			(end -0.67945 -0.305054)
			(stroke
				(width 0.1)
				(type default)
			)
			(layer "F.Fab")
		)
		(fp_line
			(start -0.12065 0.3048)
			(end -0.67945 0.3048)
			(stroke
				(width 0.1)
				(type default)
			)
			(layer "F.Fab")
		)
		(fp_line
			(start 0.120396 0.3048)
			(end 0.120396 0.2794)
			(stroke
				(width 0.1)
				(type default)
			)
			(layer "F.Fab")
		)
		(fp_line
			(start 0.67945 0.3048)
			(end 0.120396 0.3048)
			(stroke
				(width 0.1)
				(type default)
			)
			(layer "F.Fab")
		)
		(fp_line
			(start -0.12065 0.2794)
			(end -0.12065 0.3048)
			(stroke
				(width 0.1)
				(type default)
			)
			(layer "F.Fab")
		)
		(fp_line
			(start 0.120396 0.2794)
			(end -0.12065 0.2794)
			(stroke
				(width 0.1)
				(type default)
			)
			(layer "F.Fab")
		)
		(fp_line
			(start -0.12065 -0.2794)
			(end 0.12065 -0.2794)
			(stroke
				(width 0.1)
				(type default)
			)
			(layer "F.Fab")
		)
		(fp_line
			(start 0.12065 -0.2794)
			(end 0.12065 -0.3048)
			(stroke
				(width 0.1)
				(type default)
			)
			(layer "F.Fab")
		)
		(fp_line
			(start 0.12065 -0.3048)
			(end 0.67945 -0.3048)
			(stroke
				(width 0.1)
				(type default)
			)
			(layer "F.Fab")
		)
		(fp_line
			(start 0.67945 -0.3048)
			(end 0.67945 0.3048)
			(stroke
				(width 0.1)
				(type default)
			)
			(layer "F.Fab")
		)
		(fp_line
			(start -0.67945 -0.305054)
			(end -0.12065 -0.305054)
			(stroke
				(width 0.1)
				(type default)
			)
			(layer "F.Fab")
		)
		(fp_line
			(start -0.12065 -0.305054)
			(end -0.12065 -0.2794)
			(stroke
				(width 0.1)
				(type default)
			)
			(layer "F.Fab")
		)
		(pad "1" smd circle
			(at -0.40005 0 270)
			(size 0 0)
			(layers "F.Cu" "F.Mask" "F.Paste")
			(net "FM_P1V05_PCH_AUX_EN")
		)
		(pad "2" smd circle
			(at 0.40005 0 270)
			(size 0 0)
			(layers "F.Cu" "F.Mask" "F.Paste")
			(net "FM_P1V05_PCH_AUX_R_EN")
		)
	)
	(footprint ""
		(layer "F.Cu")
		(at 126.862332 -341.716106 -90)
		(property "Reference" "PC1361"
			(at 0 0 270)
			(layer "F.SilkS")
			(hide yes)
			(effects
				(font
					(size 1.27 1.27)
				)
			)
		)
		(property "Value" ""
			(at 0 0 270)
			(layer "F.Fab")
			(effects
				(font
					(size 1.27 1.27)
				)
			)
		)
		(duplicate_pad_numbers_are_jumpers no)
		(fp_line
			(start -0.7874 0.4064)
			(end -0.7874 -0.4064)
			(stroke
				(width 0.1524)
				(type default)
			)
			(layer "F.SilkS")
		)
		(fp_line
			(start 0.7874 0.4064)
			(end -0.7874 0.4064)
			(stroke
				(width 0.1524)
				(type default)
			)
			(layer "F.SilkS")
		)
		(fp_line
			(start -0.7874 -0.4064)
			(end 0.7874 -0.4064)
			(stroke
				(width 0.1524)
				(type default)
			)
			(layer "F.SilkS")
		)
		(fp_line
			(start 0.7874 -0.4064)
			(end 0.7874 0.4064)
			(stroke
				(width 0.1524)
				(type default)
			)
			(layer "F.SilkS")
		)
		(fp_line
			(start -0.67945 0.3048)
			(end -0.67945 -0.305054)
			(stroke
				(width 0.1)
				(type default)
			)
			(layer "F.Fab")
		)
		(fp_line
			(start -0.12065 0.3048)
			(end -0.67945 0.3048)
			(stroke
				(width 0.1)
				(type default)
			)
			(layer "F.Fab")
		)
		(fp_line
			(start 0.120396 0.3048)
			(end 0.120396 0.2794)
			(stroke
				(width 0.1)
				(type default)
			)
			(layer "F.Fab")
		)
		(fp_line
			(start 0.67945 0.3048)
			(end 0.120396 0.3048)
			(stroke
				(width 0.1)
				(type default)
			)
			(layer "F.Fab")
		)
		(fp_line
			(start -0.12065 0.2794)
			(end -0.12065 0.3048)
			(stroke
				(width 0.1)
				(type default)
			)
			(layer "F.Fab")
		)
		(fp_line
			(start 0.120396 0.2794)
			(end -0.12065 0.2794)
			(stroke
				(width 0.1)
				(type default)
			)
			(layer "F.Fab")
		)
		(fp_line
			(start -0.12065 -0.2794)
			(end 0.12065 -0.2794)
			(stroke
				(width 0.1)
				(type default)
			)
			(layer "F.Fab")
		)
		(fp_line
			(start 0.12065 -0.2794)
			(end 0.12065 -0.3048)
			(stroke
				(width 0.1)
				(type default)
			)
			(layer "F.Fab")
		)
		(fp_line
			(start 0.12065 -0.3048)
			(end 0.67945 -0.3048)
			(stroke
				(width 0.1)
				(type default)
			)
			(layer "F.Fab")
		)
		(fp_line
			(start 0.67945 -0.3048)
			(end 0.67945 0.3048)
			(stroke
				(width 0.1)
				(type default)
			)
			(layer "F.Fab")
		)
		(fp_line
			(start -0.67945 -0.305054)
			(end -0.12065 -0.305054)
			(stroke
				(width 0.1)
				(type default)
			)
			(layer "F.Fab")
		)
		(fp_line
			(start -0.12065 -0.305054)
			(end -0.12065 -0.2794)
			(stroke
				(width 0.1)
				(type default)
			)
			(layer "F.Fab")
		)
		(pad "1" smd circle
			(at -0.40005 0 270)
			(size 0 0)
			(layers "F.Cu" "F.Mask" "F.Paste")
			(net "GND")
		)
		(pad "2" smd circle
			(at 0.40005 0 270)
			(size 0 0)
			(layers "F.Cu" "F.Mask" "F.Paste")
			(net "PVCCIN_CPU1_VREF")
		)
	)
	(footprint ""
		(layer "F.Cu")
		(at 298.16552 -406.6794)
		(property "Reference" "R4685"
			(at 0 0 0)
			(layer "F.SilkS")
			(hide yes)
			(effects
				(font
					(size 1.27 1.27)
				)
			)
		)
		(property "Value" ""
			(at 0 0 0)
			(layer "F.Fab")
			(effects
				(font
					(size 1.27 1.27)
				)
			)
		)
		(duplicate_pad_numbers_are_jumpers no)
		(fp_line
			(start -0.7874 -0.4064)
			(end 0.7874 -0.4064)
			(stroke
				(width 0.1524)
				(type default)
			)
			(layer "F.SilkS")
		)
		(fp_line
			(start -0.7874 0.4064)
			(end -0.7874 -0.4064)
			(stroke
				(width 0.1524)
				(type default)
			)
			(layer "F.SilkS")
		)
		(fp_line
			(start 0.7874 -0.4064)
			(end 0.7874 0.4064)
			(stroke
				(width 0.1524)
				(type default)
			)
			(layer "F.SilkS")
		)
		(fp_line
			(start 0.7874 0.4064)
			(end -0.7874 0.4064)
			(stroke
				(width 0.1524)
				(type default)
			)
			(layer "F.SilkS")
		)
		(fp_line
			(start -0.67945 -0.305054)
			(end -0.12065 -0.305054)
			(stroke
				(width 0.1)
				(type default)
			)
			(layer "F.Fab")
		)
		(fp_line
			(start -0.67945 0.3048)
			(end -0.67945 -0.305054)
			(stroke
				(width 0.1)
				(type default)
			)
			(layer "F.Fab")
		)
		(fp_line
			(start -0.12065 -0.305054)
			(end -0.12065 -0.2794)
			(stroke
				(width 0.1)
				(type default)
			)
			(layer "F.Fab")
		)
		(fp_line
			(start -0.12065 -0.2794)
			(end 0.12065 -0.2794)
			(stroke
				(width 0.1)
				(type default)
			)
			(layer "F.Fab")
		)
		(fp_line
			(start -0.12065 0.2794)
			(end -0.12065 0.3048)
			(stroke
				(width 0.1)
				(type default)
			)
			(layer "F.Fab")
		)
		(fp_line
			(start -0.12065 0.3048)
			(end -0.67945 0.3048)
			(stroke
				(width 0.1)
				(type default)
			)
			(layer "F.Fab")
		)
		(fp_line
			(start 0.120396 0.2794)
			(end -0.12065 0.2794)
			(stroke
				(width 0.1)
				(type default)
			)
			(layer "F.Fab")
		)
		(fp_line
			(start 0.120396 0.3048)
			(end 0.120396 0.2794)
			(stroke
				(width 0.1)
				(type default)
			)
			(layer "F.Fab")
		)
		(fp_line
			(start 0.12065 -0.3048)
			(end 0.67945 -0.3048)
			(stroke
				(width 0.1)
				(type default)
			)
			(layer "F.Fab")
		)
		(fp_line
			(start 0.12065 -0.2794)
			(end 0.12065 -0.3048)
			(stroke
				(width 0.1)
				(type default)
			)
			(layer "F.Fab")
		)
		(fp_line
			(start 0.67945 -0.3048)
			(end 0.67945 0.3048)
			(stroke
				(width 0.1)
				(type default)
			)
			(layer "F.Fab")
		)
		(fp_line
			(start 0.67945 0.3048)
			(end 0.120396 0.3048)
			(stroke
				(width 0.1)
				(type default)
			)
			(layer "F.Fab")
		)
		(pad "1" smd circle
			(at -0.40005 0)
			(size 0 0)
			(layers "F.Cu" "F.Mask" "F.Paste")
			(net "P3V3_AUX")
		)
		(pad "2" smd circle
			(at 0.40005 0)
			(size 0 0)
			(layers "F.Cu" "F.Mask" "F.Paste")
			(net "P12V_HSC_TEMP_ALERT_R_N")
		)
	)
	(footprint ""
		(layer "F.Cu")
		(at 136.3853 -112.363504)
		(property "Reference" "R4755"
			(at 0 0 0)
			(layer "F.SilkS")
			(hide yes)
			(effects
				(font
					(size 1.27 1.27)
				)
			)
		)
		(property "Value" ""
			(at 0 0 0)
			(layer "F.Fab")
			(effects
				(font
					(size 1.27 1.27)
				)
			)
		)
		(duplicate_pad_numbers_are_jumpers no)
		(fp_line
			(start -0.7874 -0.4064)
			(end 0.7874 -0.4064)
			(stroke
				(width 0.1524)
				(type default)
			)
			(layer "F.SilkS")
		)
		(fp_line
			(start -0.7874 0.4064)
			(end -0.7874 -0.4064)
			(stroke
				(width 0.1524)
				(type default)
			)
			(layer "F.SilkS")
		)
		(fp_line
			(start 0.7874 -0.4064)
			(end 0.7874 0.4064)
			(stroke
				(width 0.1524)
				(type default)
			)
			(layer "F.SilkS")
		)
		(fp_line
			(start 0.7874 0.4064)
			(end -0.7874 0.4064)
			(stroke
				(width 0.1524)
				(type default)
			)
			(layer "F.SilkS")
		)
		(fp_line
			(start -0.67945 -0.305054)
			(end -0.12065 -0.305054)
			(stroke
				(width 0.1)
				(type default)
			)
			(layer "F.Fab")
		)
		(fp_line
			(start -0.67945 0.3048)
			(end -0.67945 -0.305054)
			(stroke
				(width 0.1)
				(type default)
			)
			(layer "F.Fab")
		)
		(fp_line
			(start -0.12065 -0.305054)
			(end -0.12065 -0.2794)
			(stroke
				(width 0.1)
				(type default)
			)
			(layer "F.Fab")
		)
		(fp_line
			(start -0.12065 -0.2794)
			(end 0.12065 -0.2794)
			(stroke
				(width 0.1)
				(type default)
			)
			(layer "F.Fab")
		)
		(fp_line
			(start -0.12065 0.2794)
			(end -0.12065 0.3048)
			(stroke
				(width 0.1)
				(type default)
			)
			(layer "F.Fab")
		)
		(fp_line
			(start -0.12065 0.3048)
			(end -0.67945 0.3048)
			(stroke
				(width 0.1)
				(type default)
			)
			(layer "F.Fab")
		)
		(fp_line
			(start 0.120396 0.2794)
			(end -0.12065 0.2794)
			(stroke
				(width 0.1)
				(type default)
			)
			(layer "F.Fab")
		)
		(fp_line
			(start 0.120396 0.3048)
			(end 0.120396 0.2794)
			(stroke
				(width 0.1)
				(type default)
			)
			(layer "F.Fab")
		)
		(fp_line
			(start 0.12065 -0.3048)
			(end 0.67945 -0.3048)
			(stroke
				(width 0.1)
				(type default)
			)
			(layer "F.Fab")
		)
		(fp_line
			(start 0.12065 -0.2794)
			(end 0.12065 -0.3048)
			(stroke
				(width 0.1)
				(type default)
			)
			(layer "F.Fab")
		)
		(fp_line
			(start 0.67945 -0.3048)
			(end 0.67945 0.3048)
			(stroke
				(width 0.1)
				(type default)
			)
			(layer "F.Fab")
		)
		(fp_line
			(start 0.67945 0.3048)
			(end 0.120396 0.3048)
			(stroke
				(width 0.1)
				(type default)
			)
			(layer "F.Fab")
		)
		(pad "1" smd circle
			(at -0.40005 0)
			(size 0 0)
			(layers "F.Cu" "F.Mask" "F.Paste")
			(net "OCP_V3_2_AUX_PWR_PLD_EN")
		)
		(pad "2" smd circle
			(at 0.40005 0)
			(size 0 0)
			(layers "F.Cu" "F.Mask" "F.Paste")
			(net "OCP_V3_2_AUX_PWR_PLD_EN_R")
		)
	)
	(footprint ""
		(layer "F.Cu")
		(at 172.033184 -344.7796 -90)
		(property "Reference" "PL18"
			(at -1.768348 -4.904486 90)
			(unlocked yes)
			(layer "F.SilkS")
			(effects
				(font
					(size 0.7874 0.5842)
					(thickness 0.1524)
				)
				(justify left)
			)
		)
		(property "Value" ""
			(at 0 0 270)
			(layer "F.Fab")
			(effects
				(font
					(size 1.27 1.27)
				)
			)
		)
		(duplicate_pad_numbers_are_jumpers no)
		(fp_line
			(start -4.99999 3.750056)
			(end -4.99999 2.2479)
			(stroke
				(width 0.1524)
				(type default)
			)
			(layer "F.SilkS")
		)
		(fp_line
			(start 0 3.750056)
			(end -4.99999 3.750056)
			(stroke
				(width 0.1524)
				(type default)
			)
			(layer "F.SilkS")
		)
		(fp_line
			(start 4.99999 3.750056)
			(end 0 3.750056)
			(stroke
				(width 0.1524)
				(type default)
			)
			(layer "F.SilkS")
		)
		(fp_line
			(start 4.99999 2.2352)
			(end 4.99999 3.750056)
			(stroke
				(width 0.1524)
				(type default)
			)
			(layer "F.SilkS")
		)
		(fp_line
			(start -4.99999 -2.2479)
			(end -4.99999 -3.750056)
			(stroke
				(width 0.1524)
				(type default)
			)
			(layer "F.SilkS")
		)
		(fp_line
			(start -4.99999 -3.750056)
			(end 4.99999 -3.750056)
			(stroke
				(width 0.1524)
				(type default)
			)
			(layer "F.SilkS")
		)
		(fp_line
			(start 4.99999 -3.750056)
			(end 4.99999 -2.2479)
			(stroke
				(width 0.1524)
				(type default)
			)
			(layer "F.SilkS")
		)
		(fp_line
			(start -4.99999 3.750056)
			(end -4.99999 -3.750056)
			(stroke
				(width 0.1)
				(type default)
			)
			(layer "F.Fab")
		)
		(fp_line
			(start 0 3.750056)
			(end -4.99999 3.750056)
			(stroke
				(width 0.1)
				(type default)
			)
			(layer "F.Fab")
		)
		(fp_line
			(start 4.99999 3.750056)
			(end 0 3.750056)
			(stroke
				(width 0.1)
				(type default)
			)
			(layer "F.Fab")
		)
		(fp_line
			(start -4.99999 -3.750056)
			(end 4.99999 -3.750056)
			(stroke
				(width 0.1)
				(type default)
			)
			(layer "F.Fab")
		)
		(fp_line
			(start 4.99999 -3.750056)
			(end 4.99999 3.750056)
			(stroke
				(width 0.1)
				(type default)
			)
			(layer "F.Fab")
		)
		(pad "1" smd rect
			(at -3.299968 0 270)
			(size 3.302 4.2164)
			(layers "F.Cu" "F.Mask" "F.Paste")
			(net "SW_PVCCFA_EHV_FIVRA_CPU1_SW1")
		)
		(pad "2" smd rect
			(at 3.299968 0 270)
			(size 3.302 4.2164)
			(layers "F.Cu" "F.Mask" "F.Paste")
			(net "PVCCFA_EHV_FIVRA_CPU1")
		)
	)
	(footprint ""
		(layer "F.Cu")
		(at 365.46663 -238.162338 90)
		(property "Reference" "C416"
			(at 0 0 90)
			(layer "F.SilkS")
			(hide yes)
			(effects
				(font
					(size 1.27 1.27)
				)
			)
		)
		(property "Value" ""
			(at 0 0 90)
			(layer "F.Fab")
			(effects
				(font
					(size 1.27 1.27)
				)
			)
		)
		(duplicate_pad_numbers_are_jumpers no)
		(fp_line
			(start 0.7874 -0.4064)
			(end 0.7874 0.4064)
			(stroke
				(width 0.1524)
				(type default)
			)
			(layer "F.SilkS")
		)
		(fp_line
			(start -0.7874 -0.4064)
			(end 0.7874 -0.4064)
			(stroke
				(width 0.1524)
				(type default)
			)
			(layer "F.SilkS")
		)
		(fp_line
			(start 0.7874 0.4064)
			(end -0.7874 0.4064)
			(stroke
				(width 0.1524)
				(type default)
			)
			(layer "F.SilkS")
		)
		(fp_line
			(start -0.7874 0.4064)
			(end -0.7874 -0.4064)
			(stroke
				(width 0.1524)
				(type default)
			)
			(layer "F.SilkS")
		)
		(fp_line
			(start -0.12065 -0.305054)
			(end -0.12065 -0.2794)
			(stroke
				(width 0.1)
				(type default)
			)
			(layer "F.Fab")
		)
		(fp_line
			(start -0.67945 -0.305054)
			(end -0.12065 -0.305054)
			(stroke
				(width 0.1)
				(type default)
			)
			(layer "F.Fab")
		)
		(fp_line
			(start 0.67945 -0.3048)
			(end 0.67945 0.3048)
			(stroke
				(width 0.1)
				(type default)
			)
			(layer "F.Fab")
		)
		(fp_line
			(start 0.12065 -0.3048)
			(end 0.67945 -0.3048)
			(stroke
				(width 0.1)
				(type default)
			)
			(layer "F.Fab")
		)
		(fp_line
			(start 0.12065 -0.2794)
			(end 0.12065 -0.3048)
			(stroke
				(width 0.1)
				(type default)
			)
			(layer "F.Fab")
		)
		(fp_line
			(start -0.12065 -0.2794)
			(end 0.12065 -0.2794)
			(stroke
				(width 0.1)
				(type default)
			)
			(layer "F.Fab")
		)
		(fp_line
			(start 0.120396 0.2794)
			(end -0.12065 0.2794)
			(stroke
				(width 0.1)
				(type default)
			)
			(layer "F.Fab")
		)
		(fp_line
			(start -0.12065 0.2794)
			(end -0.12065 0.3048)
			(stroke
				(width 0.1)
				(type default)
			)
			(layer "F.Fab")
		)
		(fp_line
			(start 0.67945 0.3048)
			(end 0.120396 0.3048)
			(stroke
				(width 0.1)
				(type default)
			)
			(layer "F.Fab")
		)
		(fp_line
			(start 0.120396 0.3048)
			(end 0.120396 0.2794)
			(stroke
				(width 0.1)
				(type default)
			)
			(layer "F.Fab")
		)
		(fp_line
			(start -0.12065 0.3048)
			(end -0.67945 0.3048)
			(stroke
				(width 0.1)
				(type default)
			)
			(layer "F.Fab")
		)
		(fp_line
			(start -0.67945 0.3048)
			(end -0.67945 -0.305054)
			(stroke
				(width 0.1)
				(type default)
			)
			(layer "F.Fab")
		)
		(pad "1" smd circle
			(at -0.40005 0 90)
			(size 0 0)
			(layers "F.Cu" "F.Mask" "F.Paste")
			(net "PVCCINFAON_CPU0")
		)
		(pad "2" smd circle
			(at 0.40005 0 90)
			(size 0 0)
			(layers "F.Cu" "F.Mask" "F.Paste")
			(net "GND")
		)
	)
	(footprint ""
		(layer "F.Cu")
		(at 436.08625 -16.248126 -90)
		(property "Reference" "R419"
			(at 0 0 270)
			(layer "F.SilkS")
			(hide yes)
			(effects
				(font
					(size 1.27 1.27)
				)
			)
		)
		(property "Value" ""
			(at 0 0 270)
			(layer "F.Fab")
			(effects
				(font
					(size 1.27 1.27)
				)
			)
		)
		(duplicate_pad_numbers_are_jumpers no)
		(fp_line
			(start -0.7874 0.4064)
			(end -0.7874 -0.4064)
			(stroke
				(width 0.1524)
				(type default)
			)
			(layer "F.SilkS")
		)
		(fp_line
			(start 0.7874 0.4064)
			(end -0.7874 0.4064)
			(stroke
				(width 0.1524)
				(type default)
			)
			(layer "F.SilkS")
		)
		(fp_line
			(start -0.7874 -0.4064)
			(end 0.7874 -0.4064)
			(stroke
				(width 0.1524)
				(type default)
			)
			(layer "F.SilkS")
		)
		(fp_line
			(start 0.7874 -0.4064)
			(end 0.7874 0.4064)
			(stroke
				(width 0.1524)
				(type default)
			)
			(layer "F.SilkS")
		)
		(fp_line
			(start -0.67945 0.3048)
			(end -0.67945 -0.305054)
			(stroke
				(width 0.1)
				(type default)
			)
			(layer "F.Fab")
		)
		(fp_line
			(start -0.12065 0.3048)
			(end -0.67945 0.3048)
			(stroke
				(width 0.1)
				(type default)
			)
			(layer "F.Fab")
		)
		(fp_line
			(start 0.120396 0.3048)
			(end 0.120396 0.2794)
			(stroke
				(width 0.1)
				(type default)
			)
			(layer "F.Fab")
		)
		(fp_line
			(start 0.67945 0.3048)
			(end 0.120396 0.3048)
			(stroke
				(width 0.1)
				(type default)
			)
			(layer "F.Fab")
		)
		(fp_line
			(start -0.12065 0.2794)
			(end -0.12065 0.3048)
			(stroke
				(width 0.1)
				(type default)
			)
			(layer "F.Fab")
		)
		(fp_line
			(start 0.120396 0.2794)
			(end -0.12065 0.2794)
			(stroke
				(width 0.1)
				(type default)
			)
			(layer "F.Fab")
		)
		(fp_line
			(start -0.12065 -0.2794)
			(end 0.12065 -0.2794)
			(stroke
				(width 0.1)
				(type default)
			)
			(layer "F.Fab")
		)
		(fp_line
			(start 0.12065 -0.2794)
			(end 0.12065 -0.3048)
			(stroke
				(width 0.1)
				(type default)
			)
			(layer "F.Fab")
		)
		(fp_line
			(start 0.12065 -0.3048)
			(end 0.67945 -0.3048)
			(stroke
				(width 0.1)
				(type default)
			)
			(layer "F.Fab")
		)
		(fp_line
			(start 0.67945 -0.3048)
			(end 0.67945 0.3048)
			(stroke
				(width 0.1)
				(type default)
			)
			(layer "F.Fab")
		)
		(fp_line
			(start -0.67945 -0.305054)
			(end -0.12065 -0.305054)
			(stroke
				(width 0.1)
				(type default)
			)
			(layer "F.Fab")
		)
		(fp_line
			(start -0.12065 -0.305054)
			(end -0.12065 -0.2794)
			(stroke
				(width 0.1)
				(type default)
			)
			(layer "F.Fab")
		)
		(pad "1" smd circle
			(at -0.40005 0 270)
			(size 0 0)
			(layers "F.Cu" "F.Mask" "F.Paste")
			(net "RST_OCP_V3_1_BUF_N")
		)
		(pad "2" smd circle
			(at 0.40005 0 270)
			(size 0 0)
			(layers "F.Cu" "F.Mask" "F.Paste")
			(net "RST_PERST0_OCP_SFF_N")
		)
	)
	(footprint ""
		(layer "F.Cu")
		(at 20.014184 -112.314482)
		(property "Reference" "L16"
			(at 0 0 0)
			(layer "F.SilkS")
			(hide yes)
			(effects
				(font
					(size 1.27 1.27)
				)
			)
		)
		(property "Value" ""
			(at 0 0 0)
			(layer "F.Fab")
			(effects
				(font
					(size 1.27 1.27)
				)
			)
		)
		(duplicate_pad_numbers_are_jumpers no)
		(fp_line
			(start -1.27 -0.5842)
			(end 1.27 -0.5842)
			(stroke
				(width 0.1524)
				(type default)
			)
			(layer "F.SilkS")
		)
		(fp_line
			(start -1.27 -0.5588)
			(end -1.27 -0.5842)
			(stroke
				(width 0.1524)
				(type default)
			)
			(layer "F.SilkS")
		)
		(fp_line
			(start -1.27 0.5842)
			(end -1.27 -0.5842)
			(stroke
				(width 0.1524)
				(type default)
			)
			(layer "F.SilkS")
		)
		(fp_line
			(start -0.127 0.5842)
			(end -0.127 -0.5842)
			(stroke
				(width 0.1524)
				(type default)
			)
			(layer "F.SilkS")
		)
		(fp_line
			(start 0.127 0.5842)
			(end 0.127 -0.5842)
			(stroke
				(width 0.1524)
				(type default)
			)
			(layer "F.SilkS")
		)
		(fp_line
			(start 1.27 0.5842)
			(end -1.27 0.5842)
			(stroke
				(width 0.1524)
				(type default)
			)
			(layer "F.SilkS")
		)
		(fp_line
			(start 1.27 0.5842)
			(end 1.27 -0.5842)
			(stroke
				(width 0.1524)
				(type default)
			)
			(layer "F.SilkS")
		)
		(fp_line
			(start -1.194308 -0.406654)
			(end -0.9144 -0.406654)
			(stroke
				(width 0.1)
				(type default)
			)
			(layer "F.Fab")
		)
		(fp_line
			(start -1.194308 0.406654)
			(end -1.194308 -0.406654)
			(stroke
				(width 0.1)
				(type default)
			)
			(layer "F.Fab")
		)
		(fp_line
			(start -0.9144 -0.508)
			(end 0.9144 -0.508)
			(stroke
				(width 0.1)
				(type default)
			)
			(layer "F.Fab")
		)
		(fp_line
			(start -0.9144 -0.406654)
			(end -0.9144 -0.508)
			(stroke
				(width 0.1)
				(type default)
			)
			(layer "F.Fab")
		)
		(fp_line
			(start -0.9144 0.406654)
			(end -1.194308 0.406654)
			(stroke
				(width 0.1)
				(type default)
			)
			(layer "F.Fab")
		)
		(fp_line
			(start -0.9144 0.508)
			(end -0.9144 0.406654)
			(stroke
				(width 0.1)
				(type default)
			)
			(layer "F.Fab")
		)
		(fp_line
			(start 0.9144 -0.508)
			(end 0.9144 -0.406654)
			(stroke
				(width 0.1)
				(type default)
			)
			(layer "F.Fab")
		)
		(fp_line
			(start 0.9144 -0.406654)
			(end 1.1938 -0.406654)
			(stroke
				(width 0.1)
				(type default)
			)
			(layer "F.Fab")
		)
		(fp_line
			(start 0.9144 0.4064)
			(end 0.9144 0.508)
			(stroke
				(width 0.1)
				(type default)
			)
			(layer "F.Fab")
		)
		(fp_line
			(start 0.9144 0.508)
			(end -0.9144 0.508)
			(stroke
				(width 0.1)
				(type default)
			)
			(layer "F.Fab")
		)
		(fp_line
			(start 1.1938 -0.406654)
			(end 1.1938 0.4064)
			(stroke
				(width 0.1)
				(type default)
			)
			(layer "F.Fab")
		)
		(fp_line
			(start 1.1938 0.4064)
			(end 0.9144 0.4064)
			(stroke
				(width 0.1)
				(type default)
			)
			(layer "F.Fab")
		)
		(pad "1" smd rect
			(at -0.7366 0 270)
			(size 0.7112 0.8128)
			(layers "F.Cu" "F.Mask" "F.Paste")
			(net "P3V3_AUX")
		)
		(pad "2" smd rect
			(at 0.7366 0 270)
			(size 0.7112 0.8128)
			(layers "F.Cu" "F.Mask" "F.Paste")
			(net "P3V3_ADC128_VCC")
		)
	)
	(footprint ""
		(layer "F.Cu")
		(at 395.413738 -150.09241 -90)
		(property "Reference" "C569"
			(at 0 0 270)
			(layer "F.SilkS")
			(hide yes)
			(effects
				(font
					(size 1.27 1.27)
				)
			)
		)
		(property "Value" ""
			(at 0 0 270)
			(layer "F.Fab")
			(effects
				(font
					(size 1.27 1.27)
				)
			)
		)
		(duplicate_pad_numbers_are_jumpers no)
		(fp_line
			(start -0.7874 0.4064)
			(end -0.7874 -0.4064)
			(stroke
				(width 0.1524)
				(type default)
			)
			(layer "F.SilkS")
		)
		(fp_line
			(start 0.7874 0.4064)
			(end -0.7874 0.4064)
			(stroke
				(width 0.1524)
				(type default)
			)
			(layer "F.SilkS")
		)
		(fp_line
			(start -0.7874 -0.4064)
			(end 0.7874 -0.4064)
			(stroke
				(width 0.1524)
				(type default)
			)
			(layer "F.SilkS")
		)
		(fp_line
			(start 0.7874 -0.4064)
			(end 0.7874 0.4064)
			(stroke
				(width 0.1524)
				(type default)
			)
			(layer "F.SilkS")
		)
		(fp_line
			(start -0.67945 0.3048)
			(end -0.67945 -0.305054)
			(stroke
				(width 0.1)
				(type default)
			)
			(layer "F.Fab")
		)
		(fp_line
			(start -0.12065 0.3048)
			(end -0.67945 0.3048)
			(stroke
				(width 0.1)
				(type default)
			)
			(layer "F.Fab")
		)
		(fp_line
			(start 0.120396 0.3048)
			(end 0.120396 0.2794)
			(stroke
				(width 0.1)
				(type default)
			)
			(layer "F.Fab")
		)
		(fp_line
			(start 0.67945 0.3048)
			(end 0.120396 0.3048)
			(stroke
				(width 0.1)
				(type default)
			)
			(layer "F.Fab")
		)
		(fp_line
			(start -0.12065 0.2794)
			(end -0.12065 0.3048)
			(stroke
				(width 0.1)
				(type default)
			)
			(layer "F.Fab")
		)
		(fp_line
			(start 0.120396 0.2794)
			(end -0.12065 0.2794)
			(stroke
				(width 0.1)
				(type default)
			)
			(layer "F.Fab")
		)
		(fp_line
			(start -0.12065 -0.2794)
			(end 0.12065 -0.2794)
			(stroke
				(width 0.1)
				(type default)
			)
			(layer "F.Fab")
		)
		(fp_line
			(start 0.12065 -0.2794)
			(end 0.12065 -0.3048)
			(stroke
				(width 0.1)
				(type default)
			)
			(layer "F.Fab")
		)
		(fp_line
			(start 0.12065 -0.3048)
			(end 0.67945 -0.3048)
			(stroke
				(width 0.1)
				(type default)
			)
			(layer "F.Fab")
		)
		(fp_line
			(start 0.67945 -0.3048)
			(end 0.67945 0.3048)
			(stroke
				(width 0.1)
				(type default)
			)
			(layer "F.Fab")
		)
		(fp_line
			(start -0.67945 -0.305054)
			(end -0.12065 -0.305054)
			(stroke
				(width 0.1)
				(type default)
			)
			(layer "F.Fab")
		)
		(fp_line
			(start -0.12065 -0.305054)
			(end -0.12065 -0.2794)
			(stroke
				(width 0.1)
				(type default)
			)
			(layer "F.Fab")
		)
		(pad "1" smd circle
			(at -0.40005 0 270)
			(size 0 0)
			(layers "F.Cu" "F.Mask" "F.Paste")
			(net "P3V3_AUX")
		)
		(pad "2" smd circle
			(at 0.40005 0 270)
			(size 0 0)
			(layers "F.Cu" "F.Mask" "F.Paste")
			(net "GND")
		)
	)
	(footprint ""
		(layer "F.Cu")
		(at 416.3822 -17.612614 90)
		(property "Reference" "C857"
			(at 0 0 90)
			(layer "F.SilkS")
			(hide yes)
			(effects
				(font
					(size 1.27 1.27)
				)
			)
		)
		(property "Value" ""
			(at 0 0 90)
			(layer "F.Fab")
			(effects
				(font
					(size 1.27 1.27)
				)
			)
		)
		(duplicate_pad_numbers_are_jumpers no)
		(fp_line
			(start 0.299974 -0.150114)
			(end 0.299974 0.150114)
			(stroke
				(width 0.1)
				(type default)
			)
			(layer "F.Fab")
		)
		(fp_line
			(start -0.299974 -0.150114)
			(end 0.299974 -0.150114)
			(stroke
				(width 0.1)
				(type default)
			)
			(layer "F.Fab")
		)
		(fp_line
			(start 0.299974 0.150114)
			(end -0.299974 0.150114)
			(stroke
				(width 0.1)
				(type default)
			)
			(layer "F.Fab")
		)
		(fp_line
			(start -0.299974 0.150114)
			(end -0.299974 -0.150114)
			(stroke
				(width 0.1)
				(type default)
			)
			(layer "F.Fab")
		)
		(pad "1" smd rect
			(at -0.2667 0 90)
			(size 0.3048 0.381)
			(layers "F.Cu" "F.Mask" "F.Paste")
			(net "P5E_CPU0_PE1_TX_C_DP<6>")
		)
		(pad "2" smd rect
			(at 0.2667 0 90)
			(size 0.3048 0.381)
			(layers "F.Cu" "F.Mask" "F.Paste")
			(net "P5E_CPU0_PE1_TX_DP<6>")
		)
	)
	(footprint ""
		(layer "F.Cu")
		(at 193.93408 -354.904548 180)
		(property "Reference" "R629"
			(at 0 0 180)
			(layer "F.SilkS")
			(hide yes)
			(effects
				(font
					(size 1.27 1.27)
				)
			)
		)
		(property "Value" ""
			(at 0 0 180)
			(layer "F.Fab")
			(effects
				(font
					(size 1.27 1.27)
				)
			)
		)
		(duplicate_pad_numbers_are_jumpers no)
		(fp_line
			(start 0.7874 0.4064)
			(end -0.7874 0.4064)
			(stroke
				(width 0.1524)
				(type default)
			)
			(layer "F.SilkS")
		)
		(fp_line
			(start 0.7874 -0.4064)
			(end 0.7874 0.4064)
			(stroke
				(width 0.1524)
				(type default)
			)
			(layer "F.SilkS")
		)
		(fp_line
			(start -0.7874 0.4064)
			(end -0.7874 -0.4064)
			(stroke
				(width 0.1524)
				(type default)
			)
			(layer "F.SilkS")
		)
		(fp_line
			(start -0.7874 -0.4064)
			(end 0.7874 -0.4064)
			(stroke
				(width 0.1524)
				(type default)
			)
			(layer "F.SilkS")
		)
		(fp_line
			(start 0.67945 0.3048)
			(end 0.120396 0.3048)
			(stroke
				(width 0.1)
				(type default)
			)
			(layer "F.Fab")
		)
		(fp_line
			(start 0.67945 -0.3048)
			(end 0.67945 0.3048)
			(stroke
				(width 0.1)
				(type default)
			)
			(layer "F.Fab")
		)
		(fp_line
			(start 0.12065 -0.2794)
			(end 0.12065 -0.3048)
			(stroke
				(width 0.1)
				(type default)
			)
			(layer "F.Fab")
		)
		(fp_line
			(start 0.12065 -0.3048)
			(end 0.67945 -0.3048)
			(stroke
				(width 0.1)
				(type default)
			)
			(layer "F.Fab")
		)
		(fp_line
			(start 0.120396 0.3048)
			(end 0.120396 0.2794)
			(stroke
				(width 0.1)
				(type default)
			)
			(layer "F.Fab")
		)
		(fp_line
			(start 0.120396 0.2794)
			(end -0.12065 0.2794)
			(stroke
				(width 0.1)
				(type default)
			)
			(layer "F.Fab")
		)
		(fp_line
			(start -0.12065 0.3048)
			(end -0.67945 0.3048)
			(stroke
				(width 0.1)
				(type default)
			)
			(layer "F.Fab")
		)
		(fp_line
			(start -0.12065 0.2794)
			(end -0.12065 0.3048)
			(stroke
				(width 0.1)
				(type default)
			)
			(layer "F.Fab")
		)
		(fp_line
			(start -0.12065 -0.2794)
			(end 0.12065 -0.2794)
			(stroke
				(width 0.1)
				(type default)
			)
			(layer "F.Fab")
		)
		(fp_line
			(start -0.12065 -0.305054)
			(end -0.12065 -0.2794)
			(stroke
				(width 0.1)
				(type default)
			)
			(layer "F.Fab")
		)
		(fp_line
			(start -0.67945 0.3048)
			(end -0.67945 -0.305054)
			(stroke
				(width 0.1)
				(type default)
			)
			(layer "F.Fab")
		)
		(fp_line
			(start -0.67945 -0.305054)
			(end -0.12065 -0.305054)
			(stroke
				(width 0.1)
				(type default)
			)
			(layer "F.Fab")
		)
		(pad "1" smd circle
			(at -0.40005 0 180)
			(size 0 0)
			(layers "F.Cu" "F.Mask" "F.Paste")
			(net "P3V3_AUX")
		)
		(pad "2" smd circle
			(at 0.40005 0 180)
			(size 0 0)
			(layers "F.Cu" "F.Mask" "F.Paste")
			(net "PU_PIROM_CPU1_ADDR0")
		)
	)
	(footprint ""
		(layer "F.Cu")
		(at 431.433478 -364.574328)
		(property "Reference" "PC1674"
			(at 0 0 0)
			(layer "F.SilkS")
			(hide yes)
			(effects
				(font
					(size 1.27 1.27)
				)
			)
		)
		(property "Value" ""
			(at 0 0 0)
			(layer "F.Fab")
			(effects
				(font
					(size 1.27 1.27)
				)
			)
		)
		(duplicate_pad_numbers_are_jumpers no)
		(fp_line
			(start -1.524 -0.762)
			(end 1.524 -0.762)
			(stroke
				(width 0.1524)
				(type default)
			)
			(layer "F.SilkS")
		)
		(fp_line
			(start -1.524 0.762)
			(end -1.524 -0.762)
			(stroke
				(width 0.1524)
				(type default)
			)
			(layer "F.SilkS")
		)
		(fp_line
			(start 1.524 -0.762)
			(end 1.524 0.762)
			(stroke
				(width 0.1524)
				(type default)
			)
			(layer "F.SilkS")
		)
		(fp_line
			(start 1.524 0.762)
			(end -1.524 0.762)
			(stroke
				(width 0.1524)
				(type default)
			)
			(layer "F.SilkS")
		)
		(fp_line
			(start -1.1049 -0.724916)
			(end -1.1049 0.724916)
			(stroke
				(width 0.1)
				(type default)
			)
			(layer "F.Fab")
		)
		(fp_line
			(start -1.1049 0.724916)
			(end 1.1049 0.724916)
			(stroke
				(width 0.1)
				(type default)
			)
			(layer "F.Fab")
		)
		(fp_line
			(start 1.1049 -0.724916)
			(end -1.1049 -0.724916)
			(stroke
				(width 0.1)
				(type default)
			)
			(layer "F.Fab")
		)
		(fp_line
			(start 1.1049 0.724916)
			(end 1.1049 -0.724916)
			(stroke
				(width 0.1)
				(type default)
			)
			(layer "F.Fab")
		)
		(pad "1" smd rect
			(at -0.889 0 180)
			(size 1.016 1.27)
			(layers "F.Cu" "F.Mask" "F.Paste")
			(net "SW_P12V_PVCCFA_EHV_FIVRA_CPU0_R")
		)
		(pad "2" smd rect
			(at 0.889 0 180)
			(size 1.016 1.27)
			(layers "F.Cu" "F.Mask" "F.Paste")
			(net "GND")
		)
	)
	(footprint ""
		(layer "F.Cu")
		(at 28.081732 -416.016948)
		(property "Reference" "Q72"
			(at 0.2286 -1.918208 0)
			(unlocked yes)
			(layer "F.SilkS")
			(effects
				(font
					(size 0.7874 0.5842)
					(thickness 0.1524)
				)
				(justify left)
			)
		)
		(property "Value" ""
			(at 0 0 0)
			(layer "F.Fab")
			(effects
				(font
					(size 1.27 1.27)
				)
			)
		)
		(duplicate_pad_numbers_are_jumpers no)
		(fp_line
			(start -1.332738 -1.100074)
			(end -0.4826 -1.100074)
			(stroke
				(width 0.1524)
				(type default)
			)
			(layer "F.SilkS")
		)
		(fp_line
			(start -1.332738 1.100074)
			(end -1.332738 -1.100074)
			(stroke
				(width 0.1524)
				(type default)
			)
			(layer "F.SilkS")
		)
		(fp_line
			(start -0.4826 -1.100074)
			(end 0 -0.541274)
			(stroke
				(width 0.1524)
				(type default)
			)
			(layer "F.SilkS")
		)
		(fp_line
			(start 0 -0.541274)
			(end 0.4826 -1.100074)
			(stroke
				(width 0.1524)
				(type default)
			)
			(layer "F.SilkS")
		)
		(fp_line
			(start 0.4826 -1.100074)
			(end 1.332738 -1.100074)
			(stroke
				(width 0.1524)
				(type default)
			)
			(layer "F.SilkS")
		)
		(fp_line
			(start 1.332738 -1.100074)
			(end 1.332738 1.100074)
			(stroke
				(width 0.1524)
				(type default)
			)
			(layer "F.SilkS")
		)
		(fp_line
			(start 1.332738 1.100074)
			(end -1.332738 1.100074)
			(stroke
				(width 0.1524)
				(type default)
			)
			(layer "F.SilkS")
		)
		(fp_poly
			(pts
				(xy -0.94996 -1.23317) (xy -1.300988 -1.935226) (xy -0.598932 -1.935226)
			)
			(stroke
				(width 0)
				(type default)
			)
			(fill yes)
			(layer "F.SilkS")
		)
		(fp_line
			(start -0.674878 -1.100074)
			(end 0.674878 -1.100074)
			(stroke
				(width 0.1)
				(type default)
			)
			(layer "F.Fab")
		)
		(fp_line
			(start -0.674878 1.100074)
			(end -0.674878 -1.100074)
			(stroke
				(width 0.1)
				(type default)
			)
			(layer "F.Fab")
		)
		(fp_line
			(start 0.674878 -1.100074)
			(end 0.674878 1.100074)
			(stroke
				(width 0.1)
				(type default)
			)
			(layer "F.Fab")
		)
		(fp_line
			(start 0.674878 1.100074)
			(end -0.674878 1.100074)
			(stroke
				(width 0.1)
				(type default)
			)
			(layer "F.Fab")
		)
		(fp_poly
			(pts
				(xy -2.2352 -0.298958) (xy -2.2352 -1.001014) (xy -1.533144 -0.649986)
			)
			(stroke
				(width 0)
				(type default)
			)
			(fill yes)
			(layer "F.Fab")
		)
		(pad "1" smd rect
			(at -0.94996 -0.649986 90)
			(size 0.4318 0.508)
			(layers "F.Cu" "F.Mask" "F.Paste")
			(net "GND")
		)
		(pad "2" smd rect
			(at -0.94996 0 90)
			(size 0.4318 0.508)
			(layers "F.Cu" "F.Mask" "F.Paste")
			(net "FM_GPU_PWRGD")
		)
		(pad "3" smd rect
			(at -0.94996 0.649986 90)
			(size 0.4318 0.508)
			(layers "F.Cu" "F.Mask" "F.Paste")
			(net "FM_GPU_PWRGD_ISO")
		)
		(pad "4" smd rect
			(at 0.94996 0.649986 90)
			(size 0.4318 0.508)
			(layers "F.Cu" "F.Mask" "F.Paste")
			(net "GND")
		)
		(pad "5" smd rect
			(at 0.94996 0 90)
			(size 0.4318 0.508)
			(layers "F.Cu" "F.Mask" "F.Paste")
			(net "FM_GPU_PWRGD_N")
		)
		(pad "6" smd rect
			(at 0.94996 -0.649986 90)
			(size 0.4318 0.508)
			(layers "F.Cu" "F.Mask" "F.Paste")
			(net "FM_GPU_PWRGD_N")
		)
	)
	(footprint ""
		(layer "F.Cu")
		(at 422.273984 -361.896914 -90)
		(property "Reference" "PC1213_P0_3"
			(at 0 0 270)
			(layer "F.SilkS")
			(hide yes)
			(effects
				(font
					(size 1.27 1.27)
				)
			)
		)
		(property "Value" ""
			(at 0 0 270)
			(layer "F.Fab")
			(effects
				(font
					(size 1.27 1.27)
				)
			)
		)
		(duplicate_pad_numbers_are_jumpers no)
		(fp_line
			(start -0.7874 0.4064)
			(end -0.7874 -0.4064)
			(stroke
				(width 0.1524)
				(type default)
			)
			(layer "F.SilkS")
		)
		(fp_line
			(start 0.7874 0.4064)
			(end -0.7874 0.4064)
			(stroke
				(width 0.1524)
				(type default)
			)
			(layer "F.SilkS")
		)
		(fp_line
			(start -0.7874 -0.4064)
			(end 0.7874 -0.4064)
			(stroke
				(width 0.1524)
				(type default)
			)
			(layer "F.SilkS")
		)
		(fp_line
			(start 0.7874 -0.4064)
			(end 0.7874 0.4064)
			(stroke
				(width 0.1524)
				(type default)
			)
			(layer "F.SilkS")
		)
		(fp_line
			(start -0.67945 0.3048)
			(end -0.67945 -0.305054)
			(stroke
				(width 0.1)
				(type default)
			)
			(layer "F.Fab")
		)
		(fp_line
			(start -0.12065 0.3048)
			(end -0.67945 0.3048)
			(stroke
				(width 0.1)
				(type default)
			)
			(layer "F.Fab")
		)
		(fp_line
			(start 0.120396 0.3048)
			(end 0.120396 0.2794)
			(stroke
				(width 0.1)
				(type default)
			)
			(layer "F.Fab")
		)
		(fp_line
			(start 0.67945 0.3048)
			(end 0.120396 0.3048)
			(stroke
				(width 0.1)
				(type default)
			)
			(layer "F.Fab")
		)
		(fp_line
			(start -0.12065 0.2794)
			(end -0.12065 0.3048)
			(stroke
				(width 0.1)
				(type default)
			)
			(layer "F.Fab")
		)
		(fp_line
			(start 0.120396 0.2794)
			(end -0.12065 0.2794)
			(stroke
				(width 0.1)
				(type default)
			)
			(layer "F.Fab")
		)
		(fp_line
			(start -0.12065 -0.2794)
			(end 0.12065 -0.2794)
			(stroke
				(width 0.1)
				(type default)
			)
			(layer "F.Fab")
		)
		(fp_line
			(start 0.12065 -0.2794)
			(end 0.12065 -0.3048)
			(stroke
				(width 0.1)
				(type default)
			)
			(layer "F.Fab")
		)
		(fp_line
			(start 0.12065 -0.3048)
			(end 0.67945 -0.3048)
			(stroke
				(width 0.1)
				(type default)
			)
			(layer "F.Fab")
		)
		(fp_line
			(start 0.67945 -0.3048)
			(end 0.67945 0.3048)
			(stroke
				(width 0.1)
				(type default)
			)
			(layer "F.Fab")
		)
		(fp_line
			(start -0.67945 -0.305054)
			(end -0.12065 -0.305054)
			(stroke
				(width 0.1)
				(type default)
			)
			(layer "F.Fab")
		)
		(fp_line
			(start -0.12065 -0.305054)
			(end -0.12065 -0.2794)
			(stroke
				(width 0.1)
				(type default)
			)
			(layer "F.Fab")
		)
		(pad "1" smd circle
			(at -0.40005 0 270)
			(size 0 0)
			(layers "F.Cu" "F.Mask" "F.Paste")
			(net "PVCCFA_EHV_FIVRA_CPU0_PVCC1")
		)
		(pad "2" smd circle
			(at 0.40005 0 270)
			(size 0 0)
			(layers "F.Cu" "F.Mask" "F.Paste")
			(net "GND")
		)
	)
	(footprint ""
		(layer "F.Cu")
		(at 383.65049 -402.371052 -90)
		(property "Reference" "C943"
			(at 0 0 270)
			(layer "F.SilkS")
			(hide yes)
			(effects
				(font
					(size 1.27 1.27)
				)
			)
		)
		(property "Value" ""
			(at 0 0 270)
			(layer "F.Fab")
			(effects
				(font
					(size 1.27 1.27)
				)
			)
		)
		(duplicate_pad_numbers_are_jumpers no)
		(fp_line
			(start -0.299974 0.150114)
			(end -0.299974 -0.150114)
			(stroke
				(width 0.1)
				(type default)
			)
			(layer "F.Fab")
		)
		(fp_line
			(start 0.299974 0.150114)
			(end -0.299974 0.150114)
			(stroke
				(width 0.1)
				(type default)
			)
			(layer "F.Fab")
		)
		(fp_line
			(start -0.299974 -0.150114)
			(end 0.299974 -0.150114)
			(stroke
				(width 0.1)
				(type default)
			)
			(layer "F.Fab")
		)
		(fp_line
			(start 0.299974 -0.150114)
			(end 0.299974 0.150114)
			(stroke
				(width 0.1)
				(type default)
			)
			(layer "F.Fab")
		)
		(pad "1" smd rect
			(at -0.2667 0 270)
			(size 0.3048 0.381)
			(layers "F.Cu" "F.Mask" "F.Paste")
			(net "P5E_CPU0_PE2_TX_C_DP<11>")
		)
		(pad "2" smd rect
			(at 0.2667 0 270)
			(size 0.3048 0.381)
			(layers "F.Cu" "F.Mask" "F.Paste")
			(net "P5E_CPU0_PE2_TX_DP<11>")
		)
	)
	(footprint ""
		(layer "F.Cu")
		(at 143.832834 -408.517344 -90)
		(property "Reference" "C1531"
			(at 0 0 270)
			(layer "F.SilkS")
			(hide yes)
			(effects
				(font
					(size 1.27 1.27)
				)
			)
		)
		(property "Value" ""
			(at 0 0 270)
			(layer "F.Fab")
			(effects
				(font
					(size 1.27 1.27)
				)
			)
		)
		(duplicate_pad_numbers_are_jumpers no)
		(fp_line
			(start -0.299974 0.150114)
			(end -0.299974 -0.150114)
			(stroke
				(width 0.1)
				(type default)
			)
			(layer "F.Fab")
		)
		(fp_line
			(start 0.299974 0.150114)
			(end -0.299974 0.150114)
			(stroke
				(width 0.1)
				(type default)
			)
			(layer "F.Fab")
		)
		(fp_line
			(start -0.299974 -0.150114)
			(end 0.299974 -0.150114)
			(stroke
				(width 0.1)
				(type default)
			)
			(layer "F.Fab")
		)
		(fp_line
			(start 0.299974 -0.150114)
			(end 0.299974 0.150114)
			(stroke
				(width 0.1)
				(type default)
			)
			(layer "F.Fab")
		)
		(pad "1" smd rect
			(at -0.2667 0 270)
			(size 0.3048 0.381)
			(layers "F.Cu" "F.Mask" "F.Paste")
			(net "P5E_CPU1_PE3_TX_C_DP<8>")
		)
		(pad "2" smd rect
			(at 0.2667 0 270)
			(size 0.3048 0.381)
			(layers "F.Cu" "F.Mask" "F.Paste")
			(net "P5E_CPU1_PE3_TX_DP<8>")
		)
	)
	(footprint ""
		(layer "F.Cu")
		(at 366.06988 -294.01008 180)
		(property "Reference" "C220"
			(at 0 0 180)
			(layer "F.SilkS")
			(hide yes)
			(effects
				(font
					(size 1.27 1.27)
				)
			)
		)
		(property "Value" ""
			(at 0 0 180)
			(layer "F.Fab")
			(effects
				(font
					(size 1.27 1.27)
				)
			)
		)
		(duplicate_pad_numbers_are_jumpers no)
		(fp_line
			(start 1.524 0.762)
			(end -1.524 0.762)
			(stroke
				(width 0.1524)
				(type default)
			)
			(layer "F.SilkS")
		)
		(fp_line
			(start 1.524 -0.762)
			(end 1.524 0.762)
			(stroke
				(width 0.1524)
				(type default)
			)
			(layer "F.SilkS")
		)
		(fp_line
			(start -1.524 0.762)
			(end -1.524 -0.762)
			(stroke
				(width 0.1524)
				(type default)
			)
			(layer "F.SilkS")
		)
		(fp_line
			(start -1.524 -0.762)
			(end 1.524 -0.762)
			(stroke
				(width 0.1524)
				(type default)
			)
			(layer "F.SilkS")
		)
		(fp_line
			(start 1.1049 0.724916)
			(end 1.1049 -0.724916)
			(stroke
				(width 0.1)
				(type default)
			)
			(layer "F.Fab")
		)
		(fp_line
			(start 1.1049 -0.724916)
			(end -1.1049 -0.724916)
			(stroke
				(width 0.1)
				(type default)
			)
			(layer "F.Fab")
		)
		(fp_line
			(start -1.1049 0.724916)
			(end 1.1049 0.724916)
			(stroke
				(width 0.1)
				(type default)
			)
			(layer "F.Fab")
		)
		(fp_line
			(start -1.1049 -0.724916)
			(end -1.1049 0.724916)
			(stroke
				(width 0.1)
				(type default)
			)
			(layer "F.Fab")
		)
		(pad "1" smd rect
			(at -0.889 0)
			(size 1.016 1.27)
			(layers "F.Cu" "F.Mask" "F.Paste")
			(net "PVCCIN_CPU0")
		)
		(pad "2" smd rect
			(at 0.889 0)
			(size 1.016 1.27)
			(layers "F.Cu" "F.Mask" "F.Paste")
			(net "GND")
		)
	)
	(footprint ""
		(layer "F.Cu")
		(at 120.269 -60.035948 90)
		(property "Reference" "R4623"
			(at 0 0 90)
			(layer "F.SilkS")
			(hide yes)
			(effects
				(font
					(size 1.27 1.27)
				)
			)
		)
		(property "Value" ""
			(at 0 0 90)
			(layer "F.Fab")
			(effects
				(font
					(size 1.27 1.27)
				)
			)
		)
		(duplicate_pad_numbers_are_jumpers no)
		(fp_line
			(start 0.7874 -0.4064)
			(end 0.7874 0.4064)
			(stroke
				(width 0.1524)
				(type default)
			)
			(layer "F.SilkS")
		)
		(fp_line
			(start -0.7874 -0.4064)
			(end 0.7874 -0.4064)
			(stroke
				(width 0.1524)
				(type default)
			)
			(layer "F.SilkS")
		)
		(fp_line
			(start 0.7874 0.4064)
			(end -0.7874 0.4064)
			(stroke
				(width 0.1524)
				(type default)
			)
			(layer "F.SilkS")
		)
		(fp_line
			(start -0.7874 0.4064)
			(end -0.7874 -0.4064)
			(stroke
				(width 0.1524)
				(type default)
			)
			(layer "F.SilkS")
		)
		(fp_line
			(start -0.12065 -0.305054)
			(end -0.12065 -0.2794)
			(stroke
				(width 0.1)
				(type default)
			)
			(layer "F.Fab")
		)
		(fp_line
			(start -0.67945 -0.305054)
			(end -0.12065 -0.305054)
			(stroke
				(width 0.1)
				(type default)
			)
			(layer "F.Fab")
		)
		(fp_line
			(start 0.67945 -0.3048)
			(end 0.67945 0.3048)
			(stroke
				(width 0.1)
				(type default)
			)
			(layer "F.Fab")
		)
		(fp_line
			(start 0.12065 -0.3048)
			(end 0.67945 -0.3048)
			(stroke
				(width 0.1)
				(type default)
			)
			(layer "F.Fab")
		)
		(fp_line
			(start 0.12065 -0.2794)
			(end 0.12065 -0.3048)
			(stroke
				(width 0.1)
				(type default)
			)
			(layer "F.Fab")
		)
		(fp_line
			(start -0.12065 -0.2794)
			(end 0.12065 -0.2794)
			(stroke
				(width 0.1)
				(type default)
			)
			(layer "F.Fab")
		)
		(fp_line
			(start 0.120396 0.2794)
			(end -0.12065 0.2794)
			(stroke
				(width 0.1)
				(type default)
			)
			(layer "F.Fab")
		)
		(fp_line
			(start -0.12065 0.2794)
			(end -0.12065 0.3048)
			(stroke
				(width 0.1)
				(type default)
			)
			(layer "F.Fab")
		)
		(fp_line
			(start 0.67945 0.3048)
			(end 0.120396 0.3048)
			(stroke
				(width 0.1)
				(type default)
			)
			(layer "F.Fab")
		)
		(fp_line
			(start 0.120396 0.3048)
			(end 0.120396 0.2794)
			(stroke
				(width 0.1)
				(type default)
			)
			(layer "F.Fab")
		)
		(fp_line
			(start -0.12065 0.3048)
			(end -0.67945 0.3048)
			(stroke
				(width 0.1)
				(type default)
			)
			(layer "F.Fab")
		)
		(fp_line
			(start -0.67945 0.3048)
			(end -0.67945 -0.305054)
			(stroke
				(width 0.1)
				(type default)
			)
			(layer "F.Fab")
		)
		(pad "1" smd circle
			(at -0.40005 0 90)
			(size 0 0)
			(layers "F.Cu" "F.Mask" "F.Paste")
			(net "P3V3_AUX")
		)
		(pad "2" smd circle
			(at 0.40005 0 90)
			(size 0 0)
			(layers "F.Cu" "F.Mask" "F.Paste")
			(net "PU_JTAG_SW_PU")
		)
	)
	(footprint ""
		(layer "F.Cu")
		(at 382.875028 -206.024734)
		(property "Reference" "H21"
			(at 5.236972 -2.066544 0)
			(unlocked yes)
			(layer "F.SilkS")
			(effects
				(font
					(size 0.7874 0.5842)
					(thickness 0.1524)
				)
				(justify left)
			)
		)
		(property "Value" ""
			(at 0 0 0)
			(layer "F.Fab")
			(effects
				(font
					(size 1.27 1.27)
				)
			)
		)
		(duplicate_pad_numbers_are_jumpers no)
		(fp_arc
			(start -1.202944 -2.222754)
			(mid 1.293612 -2.171092)
			(end 2.5273 0)
			(stroke
				(width 0.1524)
				(type default)
			)
			(layer "F.SilkS")
		)
		(fp_arc
			(start 2.5273 0)
			(mid 0.497397 2.477827)
			(end -2.331466 0.97536)
			(stroke
				(width 0.1524)
				(type default)
			)
			(layer "F.SilkS")
		)
		(fp_circle
			(center 0 0)
			(end 2.5273 0)
			(stroke
				(width 0.1524)
				(type default)
			)
			(fill no)
			(layer "B.SilkS")
		)
		(fp_circle
			(center 0 0)
			(end 2.5273 0)
			(stroke
				(width 0.1)
				(type default)
			)
			(fill no)
			(layer "B.Fab")
		)
		(fp_circle
			(center 0 0)
			(end 2.5273 0)
			(stroke
				(width 0.1)
				(type default)
			)
			(fill no)
			(layer "F.Fab")
		)
		(pad "" np_thru_hole circle
			(at 0 0)
			(size 3.429 3.429)
			(drill 3.429)
			(layers "*.Cu" "*.Mask")
			(clearance 0.381)
			(thermal_gap 0.381)
		)
	)
	(footprint ""
		(layer "F.Cu")
		(at 173.899322 -28.03779 -90)
		(property "Reference" "PR4011"
			(at 0 0 270)
			(layer "F.SilkS")
			(hide yes)
			(effects
				(font
					(size 1.27 1.27)
				)
			)
		)
		(property "Value" ""
			(at 0 0 270)
			(layer "F.Fab")
			(effects
				(font
					(size 1.27 1.27)
				)
			)
		)
		(duplicate_pad_numbers_are_jumpers no)
		(fp_line
			(start -0.7874 0.4064)
			(end -0.7874 -0.4064)
			(stroke
				(width 0.1524)
				(type default)
			)
			(layer "F.SilkS")
		)
		(fp_line
			(start 0.7874 0.4064)
			(end -0.7874 0.4064)
			(stroke
				(width 0.1524)
				(type default)
			)
			(layer "F.SilkS")
		)
		(fp_line
			(start -0.7874 -0.4064)
			(end 0.7874 -0.4064)
			(stroke
				(width 0.1524)
				(type default)
			)
			(layer "F.SilkS")
		)
		(fp_line
			(start 0.7874 -0.4064)
			(end 0.7874 0.4064)
			(stroke
				(width 0.1524)
				(type default)
			)
			(layer "F.SilkS")
		)
		(fp_line
			(start -0.67945 0.3048)
			(end -0.67945 -0.305054)
			(stroke
				(width 0.1)
				(type default)
			)
			(layer "F.Fab")
		)
		(fp_line
			(start -0.12065 0.3048)
			(end -0.67945 0.3048)
			(stroke
				(width 0.1)
				(type default)
			)
			(layer "F.Fab")
		)
		(fp_line
			(start 0.120396 0.3048)
			(end 0.120396 0.2794)
			(stroke
				(width 0.1)
				(type default)
			)
			(layer "F.Fab")
		)
		(fp_line
			(start 0.67945 0.3048)
			(end 0.120396 0.3048)
			(stroke
				(width 0.1)
				(type default)
			)
			(layer "F.Fab")
		)
		(fp_line
			(start -0.12065 0.2794)
			(end -0.12065 0.3048)
			(stroke
				(width 0.1)
				(type default)
			)
			(layer "F.Fab")
		)
		(fp_line
			(start 0.120396 0.2794)
			(end -0.12065 0.2794)
			(stroke
				(width 0.1)
				(type default)
			)
			(layer "F.Fab")
		)
		(fp_line
			(start -0.12065 -0.2794)
			(end 0.12065 -0.2794)
			(stroke
				(width 0.1)
				(type default)
			)
			(layer "F.Fab")
		)
		(fp_line
			(start 0.12065 -0.2794)
			(end 0.12065 -0.3048)
			(stroke
				(width 0.1)
				(type default)
			)
			(layer "F.Fab")
		)
		(fp_line
			(start 0.12065 -0.3048)
			(end 0.67945 -0.3048)
			(stroke
				(width 0.1)
				(type default)
			)
			(layer "F.Fab")
		)
		(fp_line
			(start 0.67945 -0.3048)
			(end 0.67945 0.3048)
			(stroke
				(width 0.1)
				(type default)
			)
			(layer "F.Fab")
		)
		(fp_line
			(start -0.67945 -0.305054)
			(end -0.12065 -0.305054)
			(stroke
				(width 0.1)
				(type default)
			)
			(layer "F.Fab")
		)
		(fp_line
			(start -0.12065 -0.305054)
			(end -0.12065 -0.2794)
			(stroke
				(width 0.1)
				(type default)
			)
			(layer "F.Fab")
		)
		(pad "1" smd circle
			(at -0.40005 0 270)
			(size 0 0)
			(layers "F.Cu" "F.Mask" "F.Paste")
			(net "P12V_SCM_OV_FB")
		)
		(pad "2" smd circle
			(at 0.40005 0 270)
			(size 0 0)
			(layers "F.Cu" "F.Mask" "F.Paste")
			(net "GND")
		)
	)
	(footprint ""
		(layer "F.Cu")
		(at 492.12627 -468.00135)
		(property "Reference" "U1_DC"
			(at -0.90551 1.402842 0)
			(unlocked yes)
			(layer "F.SilkS")
			(effects
				(font
					(size 0.7874 0.5842)
					(thickness 0.1524)
				)
				(justify left)
			)
		)
		(property "Value" ""
			(at 0 0 0)
			(layer "F.Fab")
			(effects
				(font
					(size 1.27 1.27)
				)
			)
		)
		(duplicate_pad_numbers_are_jumpers no)
		(pad "1" smd circle
			(at 0 0)
			(size 0.762 0.762)
			(layers "F.Cu" "F.Mask" "F.Paste")
			(net "Net_8486")
		)
	)
	(footprint ""
		(layer "F.Cu")
		(at 354.270818 -245.634002 -90)
		(property "Reference" "C987"
			(at 0 0 270)
			(layer "F.SilkS")
			(hide yes)
			(effects
				(font
					(size 1.27 1.27)
				)
			)
		)
		(property "Value" ""
			(at 0 0 270)
			(layer "F.Fab")
			(effects
				(font
					(size 1.27 1.27)
				)
			)
		)
		(duplicate_pad_numbers_are_jumpers no)
		(fp_line
			(start -0.7874 0.4064)
			(end -0.7874 -0.4064)
			(stroke
				(width 0.1524)
				(type default)
			)
			(layer "F.SilkS")
		)
		(fp_line
			(start 0.7874 0.4064)
			(end -0.7874 0.4064)
			(stroke
				(width 0.1524)
				(type default)
			)
			(layer "F.SilkS")
		)
		(fp_line
			(start -0.7874 -0.4064)
			(end 0.7874 -0.4064)
			(stroke
				(width 0.1524)
				(type default)
			)
			(layer "F.SilkS")
		)
		(fp_line
			(start 0.7874 -0.4064)
			(end 0.7874 0.4064)
			(stroke
				(width 0.1524)
				(type default)
			)
			(layer "F.SilkS")
		)
		(fp_line
			(start -0.67945 0.3048)
			(end -0.67945 -0.305054)
			(stroke
				(width 0.1)
				(type default)
			)
			(layer "F.Fab")
		)
		(fp_line
			(start -0.12065 0.3048)
			(end -0.67945 0.3048)
			(stroke
				(width 0.1)
				(type default)
			)
			(layer "F.Fab")
		)
		(fp_line
			(start 0.120396 0.3048)
			(end 0.120396 0.2794)
			(stroke
				(width 0.1)
				(type default)
			)
			(layer "F.Fab")
		)
		(fp_line
			(start 0.67945 0.3048)
			(end 0.120396 0.3048)
			(stroke
				(width 0.1)
				(type default)
			)
			(layer "F.Fab")
		)
		(fp_line
			(start -0.12065 0.2794)
			(end -0.12065 0.3048)
			(stroke
				(width 0.1)
				(type default)
			)
			(layer "F.Fab")
		)
		(fp_line
			(start 0.120396 0.2794)
			(end -0.12065 0.2794)
			(stroke
				(width 0.1)
				(type default)
			)
			(layer "F.Fab")
		)
		(fp_line
			(start -0.12065 -0.2794)
			(end 0.12065 -0.2794)
			(stroke
				(width 0.1)
				(type default)
			)
			(layer "F.Fab")
		)
		(fp_line
			(start 0.12065 -0.2794)
			(end 0.12065 -0.3048)
			(stroke
				(width 0.1)
				(type default)
			)
			(layer "F.Fab")
		)
		(fp_line
			(start 0.12065 -0.3048)
			(end 0.67945 -0.3048)
			(stroke
				(width 0.1)
				(type default)
			)
			(layer "F.Fab")
		)
		(fp_line
			(start 0.67945 -0.3048)
			(end 0.67945 0.3048)
			(stroke
				(width 0.1)
				(type default)
			)
			(layer "F.Fab")
		)
		(fp_line
			(start -0.67945 -0.305054)
			(end -0.12065 -0.305054)
			(stroke
				(width 0.1)
				(type default)
			)
			(layer "F.Fab")
		)
		(fp_line
			(start -0.12065 -0.305054)
			(end -0.12065 -0.2794)
			(stroke
				(width 0.1)
				(type default)
			)
			(layer "F.Fab")
		)
		(pad "1" smd circle
			(at -0.40005 0 270)
			(size 0 0)
			(layers "F.Cu" "F.Mask" "F.Paste")
			(net "PVCCIN_CPU0")
		)
		(pad "2" smd circle
			(at 0.40005 0 270)
			(size 0 0)
			(layers "F.Cu" "F.Mask" "F.Paste")
			(net "GND")
		)
	)
	(footprint ""
		(layer "F.Cu")
		(at 263.517126 -93.457776)
		(property "Reference" "R519"
			(at 0 0 0)
			(layer "F.SilkS")
			(hide yes)
			(effects
				(font
					(size 1.27 1.27)
				)
			)
		)
		(property "Value" ""
			(at 0 0 0)
			(layer "F.Fab")
			(effects
				(font
					(size 1.27 1.27)
				)
			)
		)
		(duplicate_pad_numbers_are_jumpers no)
		(fp_line
			(start -1.2954 -0.5842)
			(end 1.2954 -0.5842)
			(stroke
				(width 0.1524)
				(type default)
			)
			(layer "F.SilkS")
		)
		(fp_line
			(start -1.2954 0.5842)
			(end -1.2954 -0.5842)
			(stroke
				(width 0.1524)
				(type default)
			)
			(layer "F.SilkS")
		)
		(fp_line
			(start 1.2954 -0.5842)
			(end 1.2954 0.5842)
			(stroke
				(width 0.1524)
				(type default)
			)
			(layer "F.SilkS")
		)
		(fp_line
			(start 1.2954 0.5842)
			(end -1.2954 0.5842)
			(stroke
				(width 0.1524)
				(type default)
			)
			(layer "F.SilkS")
		)
		(fp_line
			(start -1.1938 -0.406654)
			(end -0.8636 -0.406654)
			(stroke
				(width 0.1)
				(type default)
			)
			(layer "F.Fab")
		)
		(fp_line
			(start -1.1938 0.4064)
			(end -1.1938 -0.406654)
			(stroke
				(width 0.1)
				(type default)
			)
			(layer "F.Fab")
		)
		(fp_line
			(start -0.8636 -0.4572)
			(end 0.8636 -0.4572)
			(stroke
				(width 0.1)
				(type default)
			)
			(layer "F.Fab")
		)
		(fp_line
			(start -0.8636 -0.406654)
			(end -0.8636 -0.4572)
			(stroke
				(width 0.1)
				(type default)
			)
			(layer "F.Fab")
		)
		(fp_line
			(start -0.8636 0.4064)
			(end -1.1938 0.4064)
			(stroke
				(width 0.1)
				(type default)
			)
			(layer "F.Fab")
		)
		(fp_line
			(start -0.8636 0.4318)
			(end -0.8636 0.4064)
			(stroke
				(width 0.1)
				(type default)
			)
			(layer "F.Fab")
		)
		(fp_line
			(start -0.8636 0.4572)
			(end -0.8636 0.4318)
			(stroke
				(width 0.1)
				(type default)
			)
			(layer "F.Fab")
		)
		(fp_line
			(start 0.8636 -0.4572)
			(end 0.8636 -0.406654)
			(stroke
				(width 0.1)
				(type default)
			)
			(layer "F.Fab")
		)
		(fp_line
			(start 0.8636 -0.406654)
			(end 1.1938 -0.406654)
			(stroke
				(width 0.1)
				(type default)
			)
			(layer "F.Fab")
		)
		(fp_line
			(start 0.8636 0.4064)
			(end 0.8636 0.4572)
			(stroke
				(width 0.1)
				(type default)
			)
			(layer "F.Fab")
		)
		(fp_line
			(start 0.8636 0.4572)
			(end -0.8636 0.4572)
			(stroke
				(width 0.1)
				(type default)
			)
			(layer "F.Fab")
		)
		(fp_line
			(start 1.1938 -0.406654)
			(end 1.1938 0.4064)
			(stroke
				(width 0.1)
				(type default)
			)
			(layer "F.Fab")
		)
		(fp_line
			(start 1.1938 0.4064)
			(end 0.8636 0.4064)
			(stroke
				(width 0.1)
				(type default)
			)
			(layer "F.Fab")
		)
		(pad "1" smd rect
			(at -0.7366 0 270)
			(size 0.7112 0.8128)
			(layers "F.Cu" "F.Mask" "F.Paste")
			(net "P3V3_AUX_CLK_GEN_VDD_CK440")
		)
		(pad "2" smd rect
			(at 0.7366 0 270)
			(size 0.7112 0.8128)
			(layers "F.Cu" "F.Mask" "F.Paste")
			(net "P3V3_AUX_CLK_GEN_VDDA100M_CK440")
		)
	)
	(footprint ""
		(layer "F.Cu")
		(at 173.358048 -47.049944)
		(property "Reference" "J59"
			(at 5.590032 -12.227814 0)
			(unlocked yes)
			(layer "F.SilkS")
			(effects
				(font
					(size 0.7874 0.5842)
					(thickness 0.1524)
				)
				(justify left)
			)
		)
		(property "Value" ""
			(at 0 0 0)
			(layer "F.Fab")
			(effects
				(font
					(size 1.27 1.27)
				)
			)
		)
		(duplicate_pad_numbers_are_jumpers no)
		(fp_line
			(start -4.325112 -10.999978)
			(end 1.451102 -10.999978)
			(stroke
				(width 0.1524)
				(type default)
			)
			(layer "F.SilkS")
		)
		(fp_line
			(start -4.325112 -9.266682)
			(end -4.325112 -10.999978)
			(stroke
				(width 0.1524)
				(type default)
			)
			(layer "F.SilkS")
		)
		(fp_line
			(start -4.325112 7.233412)
			(end -4.325112 5.26669)
			(stroke
				(width 0.1524)
				(type default)
			)
			(layer "F.SilkS")
		)
		(fp_line
			(start -4.325112 10.999978)
			(end -4.325112 9.266682)
			(stroke
				(width 0.1524)
				(type default)
			)
			(layer "F.SilkS")
		)
		(fp_line
			(start -4.2037 6.34238)
			(end -3.1623 6.34238)
			(stroke
				(width 0.1524)
				(type default)
			)
			(layer "F.SilkS")
		)
		(fp_line
			(start -4.2037 6.34238)
			(end -3.1623 7.00278)
			(stroke
				(width 0.1524)
				(type default)
			)
			(layer "F.SilkS")
		)
		(fp_line
			(start -3.57505 -10.925048)
			(end -3.57505 -9.266682)
			(stroke
				(width 0.1524)
				(type default)
			)
			(layer "F.SilkS")
		)
		(fp_line
			(start -3.57505 5.26669)
			(end -3.57505 7.233412)
			(stroke
				(width 0.1524)
				(type default)
			)
			(layer "F.SilkS")
		)
		(fp_line
			(start -3.57505 9.266682)
			(end -3.57505 10.925048)
			(stroke
				(width 0.1524)
				(type default)
			)
			(layer "F.SilkS")
		)
		(fp_line
			(start -3.57505 10.925048)
			(end -2.2352 10.925048)
			(stroke
				(width 0.1524)
				(type default)
			)
			(layer "F.SilkS")
		)
		(fp_line
			(start -3.1623 6.34238)
			(end -3.1369 6.36778)
			(stroke
				(width 0.1524)
				(type default)
			)
			(layer "F.SilkS")
		)
		(fp_line
			(start -3.1623 6.34238)
			(end -1.0287 6.34238)
			(stroke
				(width 0.1524)
				(type default)
			)
			(layer "F.SilkS")
		)
		(fp_line
			(start -3.1623 7.00278)
			(end -3.1623 6.34238)
			(stroke
				(width 0.1524)
				(type default)
			)
			(layer "F.SilkS")
		)
		(fp_line
			(start -3.1369 5.73278)
			(end -4.2037 6.34238)
			(stroke
				(width 0.1524)
				(type default)
			)
			(layer "F.SilkS")
		)
		(fp_line
			(start -3.1369 6.36778)
			(end -3.1369 5.73278)
			(stroke
				(width 0.1524)
				(type default)
			)
			(layer "F.SilkS")
		)
		(fp_line
			(start -2.1082 10.999978)
			(end -4.325112 10.999978)
			(stroke
				(width 0.1524)
				(type default)
			)
			(layer "F.SilkS")
		)
		(fp_line
			(start -1.0287 4.181856)
			(end -1.6002 3.6576)
			(stroke
				(width 0.1524)
				(type default)
			)
			(layer "F.SilkS")
		)
		(fp_line
			(start -1.0287 6.34238)
			(end -1.0287 4.181856)
			(stroke
				(width 0.1524)
				(type default)
			)
			(layer "F.SilkS")
		)
		(fp_line
			(start -0.8128 10.925048)
			(end 1.451102 10.925048)
			(stroke
				(width 0.1524)
				(type default)
			)
			(layer "F.SilkS")
		)
		(fp_line
			(start 1.4478 10.999978)
			(end -0.9398 10.999978)
			(stroke
				(width 0.1524)
				(type default)
			)
			(layer "F.SilkS")
		)
		(fp_line
			(start 1.451102 -10.925048)
			(end -3.57505 -10.925048)
			(stroke
				(width 0.1524)
				(type default)
			)
			(layer "F.SilkS")
		)
		(fp_line
			(start 3.57505 6.983222)
			(end 3.57505 5.016754)
			(stroke
				(width 0.1524)
				(type default)
			)
			(layer "F.SilkS")
		)
		(fp_line
			(start 3.875024 5.016754)
			(end 3.875024 6.983222)
			(stroke
				(width 0.1524)
				(type default)
			)
			(layer "F.SilkS")
		)
		(fp_poly
			(pts
				(xy 5.715 -8.741918) (xy 4.699 -9.249918) (xy 5.715 -9.757918)
			)
			(stroke
				(width 0)
				(type default)
			)
			(fill yes)
			(layer "F.SilkS")
		)
		(fp_line
			(start -3.57505 -10.925048)
			(end -3.57505 10.925048)
			(stroke
				(width 0.1)
				(type default)
			)
			(layer "F.Fab")
		)
		(fp_line
			(start -3.57505 10.925048)
			(end 3.57505 10.925048)
			(stroke
				(width 0.1)
				(type default)
			)
			(layer "F.Fab")
		)
		(fp_line
			(start 3.57505 -10.925048)
			(end -3.57505 -10.925048)
			(stroke
				(width 0.1)
				(type default)
			)
			(layer "F.Fab")
		)
		(fp_line
			(start 3.57505 10.925048)
			(end 3.57505 -10.925048)
			(stroke
				(width 0.1)
				(type default)
			)
			(layer "F.Fab")
		)
		(fp_poly
			(pts
				(xy 5.715 -8.741918) (xy 5.715 -9.757918) (xy 4.699 -9.249918)
			)
			(stroke
				(width 0)
				(type default)
			)
			(fill yes)
			(layer "F.Fab")
		)
		(fp_text user "CONNECTOR KEEPOUT ZONE"
			(at -8.197088 -11.958574 0)
			(unlocked yes)
			(layer "F.SilkS")
			(effects
				(font
					(size 0.635 0.4064)
					(thickness 0.1524)
				)
				(justify left)
			)
		)
		(fp_text user "74"
			(at -5.961888 10.182606 0)
			(unlocked yes)
			(layer "F.SilkS")
			(effects
				(font
					(size 0.7874 0.5842)
					(thickness 0.1524)
				)
			)
		)
		(fp_text user "68"
			(at -5.748528 7.309866 0)
			(unlocked yes)
			(layer "F.SilkS")
			(effects
				(font
					(size 0.7874 0.5842)
					(thickness 0.1524)
				)
			)
		)
		(fp_text user "58"
			(at -5.585968 4.863846 0)
			(unlocked yes)
			(layer "F.SilkS")
			(effects
				(font
					(size 0.7874 0.5842)
					(thickness 0.1524)
				)
			)
		)
		(fp_text user "2"
			(at -5.255768 -9.098534 0)
			(unlocked yes)
			(layer "F.SilkS")
			(effects
				(font
					(size 0.7874 0.5842)
					(thickness 0.1524)
				)
			)
		)
		(fp_text user "57"
			(at 5.379212 5.641086 0)
			(unlocked yes)
			(layer "F.SilkS")
			(effects
				(font
					(size 0.7874 0.5842)
					(thickness 0.1524)
				)
			)
		)
		(fp_text user "75"
			(at 5.447792 10.228326 0)
			(unlocked yes)
			(layer "F.SilkS")
			(effects
				(font
					(size 0.7874 0.5842)
					(thickness 0.1524)
				)
			)
		)
		(fp_text user "67"
			(at 5.518912 7.850886 0)
			(unlocked yes)
			(layer "F.SilkS")
			(effects
				(font
					(size 0.7874 0.5842)
					(thickness 0.1524)
				)
			)
		)
		(fp_text user "74"
			(at -5.369052 9.398 270)
			(unlocked yes)
			(layer "F.Fab")
			(effects
				(font
					(size 0.7874 0.5842)
					(thickness 0.1524)
				)
			)
		)
		(fp_text user "2"
			(at -5.350764 -8.999982 270)
			(unlocked yes)
			(layer "F.Fab")
			(effects
				(font
					(size 0.7874 0.5842)
					(thickness 0.1524)
				)
			)
		)
		(fp_text user "58"
			(at -5.350764 4.74599 270)
			(unlocked yes)
			(layer "F.Fab")
			(effects
				(font
					(size 0.7874 0.5842)
					(thickness 0.1524)
				)
			)
		)
		(fp_text user "68"
			(at -5.343652 7.0104 270)
			(unlocked yes)
			(layer "F.Fab")
			(effects
				(font
					(size 0.7874 0.5842)
					(thickness 0.1524)
				)
			)
		)
		(fp_text user "57"
			(at 5.247386 4.470654 270)
			(unlocked yes)
			(layer "F.Fab")
			(effects
				(font
					(size 0.7874 0.5842)
					(thickness 0.1524)
				)
			)
		)
		(fp_text user "75"
			(at 5.248148 9.3472 270)
			(unlocked yes)
			(layer "F.Fab")
			(effects
				(font
					(size 0.7874 0.5842)
					(thickness 0.1524)
				)
			)
		)
		(fp_text user "67"
			(at 5.273548 7.0358 270)
			(unlocked yes)
			(layer "F.Fab")
			(effects
				(font
					(size 0.7874 0.5842)
					(thickness 0.1524)
				)
			)
		)
		(pad "" np_thru_hole circle
			(at -1.525016 -9.99998 270)
			(size 1.1684 1.1684)
			(drill 1.1684)
			(layers "*.Cu" "*.Mask")
			(clearance 0.381)
			(thermal_gap 0.381)
		)
		(pad "" np_thru_hole circle
			(at -1.525016 9.99998 270)
			(size 1.651 1.651)
			(drill 1.651)
			(layers "*.Cu" "*.Mask")
			(clearance 0.381)
			(thermal_gap 0.381)
		)
		(pad "1" smd rect
			(at 3.750056 -9.249918 270)
			(size 0.2794 1.6002)
			(layers "F.Cu" "F.Mask" "F.Paste")
			(net "PCIE_M2_SSD0_PRSNT_N")
		)
		(pad "2" smd rect
			(at -3.800094 -8.999982 270)
			(size 0.2794 1.6002)
			(layers "F.Cu" "F.Mask" "F.Paste")
			(net "P3V3_M2_0")
		)
		(pad "3" smd rect
			(at 3.750056 -8.750046 270)
			(size 0.2794 1.6002)
			(layers "F.Cu" "F.Mask" "F.Paste")
			(net "GND")
		)
		(pad "4" smd rect
			(at -3.800094 -8.50011 270)
			(size 0.2794 1.6002)
			(layers "F.Cu" "F.Mask" "F.Paste")
			(net "P3V3_M2_0")
		)
		(pad "5" smd rect
			(at 3.750056 -8.24992 270)
			(size 0.2794 1.6002)
			(layers "F.Cu" "F.Mask" "F.Paste")
			(net "P3E_PCH_M2_RX_DN<0>")
		)
		(pad "6" smd rect
			(at -3.800094 -7.999984 270)
			(size 0.2794 1.6002)
			(layers "F.Cu" "F.Mask" "F.Paste")
			(net "NC_M2_0_NC1")
		)
		(pad "7" smd rect
			(at 3.750056 -7.750048 270)
			(size 0.2794 1.6002)
			(layers "F.Cu" "F.Mask" "F.Paste")
			(net "P3E_PCH_M2_RX_DP<0>")
		)
		(pad "8" smd rect
			(at -3.800094 -7.500112 270)
			(size 0.2794 1.6002)
			(layers "F.Cu" "F.Mask" "F.Paste")
			(net "NC_M2_0_NC2")
		)
		(pad "9" smd rect
			(at 3.750056 -7.249922 270)
			(size 0.2794 1.6002)
			(layers "F.Cu" "F.Mask" "F.Paste")
			(net "GND")
		)
		(pad "10" smd rect
			(at -3.800094 -6.999986 270)
			(size 0.2794 1.6002)
			(layers "F.Cu" "F.Mask" "F.Paste")
			(net "LED_M2_SSD_0_ACT_N")
		)
		(pad "11" smd rect
			(at 3.750056 -6.75005 270)
			(size 0.2794 1.6002)
			(layers "F.Cu" "F.Mask" "F.Paste")
			(net "P3E_PCH_M2_TX_C_DP<0>")
		)
		(pad "12" smd rect
			(at -3.800094 -6.500114 270)
			(size 0.2794 1.6002)
			(layers "F.Cu" "F.Mask" "F.Paste")
			(net "P3V3_M2_0")
		)
		(pad "13" smd rect
			(at 3.750056 -6.249924 270)
			(size 0.2794 1.6002)
			(layers "F.Cu" "F.Mask" "F.Paste")
			(net "P3E_PCH_M2_TX_C_DN<0>")
		)
		(pad "14" smd rect
			(at -3.800094 -5.999988 270)
			(size 0.2794 1.6002)
			(layers "F.Cu" "F.Mask" "F.Paste")
			(net "P3V3_M2_0")
		)
		(pad "15" smd rect
			(at 3.750056 -5.750052 270)
			(size 0.2794 1.6002)
			(layers "F.Cu" "F.Mask" "F.Paste")
			(net "GND")
		)
		(pad "16" smd rect
			(at -3.800094 -5.500116 270)
			(size 0.2794 1.6002)
			(layers "F.Cu" "F.Mask" "F.Paste")
			(net "P3V3_M2_0")
		)
		(pad "17" smd rect
			(at 3.750056 -5.249926 270)
			(size 0.2794 1.6002)
			(layers "F.Cu" "F.Mask" "F.Paste")
			(net "P3E_PCH_M2_RX_DN<1>")
		)
		(pad "18" smd rect
			(at -3.800094 -4.99999 270)
			(size 0.2794 1.6002)
			(layers "F.Cu" "F.Mask" "F.Paste")
			(net "P3V3_M2_0")
		)
		(pad "19" smd rect
			(at 3.750056 -4.750054 270)
			(size 0.2794 1.6002)
			(layers "F.Cu" "F.Mask" "F.Paste")
			(net "P3E_PCH_M2_RX_DP<1>")
		)
		(pad "20" smd rect
			(at -3.800094 -4.500118 270)
			(size 0.2794 1.6002)
			(layers "F.Cu" "F.Mask" "F.Paste")
			(net "NC_M2_0_NC3")
		)
		(pad "21" smd rect
			(at 3.750056 -4.249928 270)
			(size 0.2794 1.6002)
			(layers "F.Cu" "F.Mask" "F.Paste")
			(net "GND")
		)
		(pad "22" smd rect
			(at -3.800094 -3.999992 270)
			(size 0.2794 1.6002)
			(layers "F.Cu" "F.Mask" "F.Paste")
			(net "NC_M2_0_NC4")
		)
		(pad "23" smd rect
			(at 3.750056 -3.750056 270)
			(size 0.2794 1.6002)
			(layers "F.Cu" "F.Mask" "F.Paste")
			(net "P3E_PCH_M2_TX_C_DP<1>")
		)
		(pad "24" smd rect
			(at -3.800094 -3.50012 270)
			(size 0.2794 1.6002)
			(layers "F.Cu" "F.Mask" "F.Paste")
			(net "NC_M2_0_NC5")
		)
		(pad "25" smd rect
			(at 3.750056 -3.24993 270)
			(size 0.2794 1.6002)
			(layers "F.Cu" "F.Mask" "F.Paste")
			(net "P3E_PCH_M2_TX_C_DN<1>")
		)
		(pad "26" smd rect
			(at -3.800094 -2.999994 270)
			(size 0.2794 1.6002)
			(layers "F.Cu" "F.Mask" "F.Paste")
			(net "NC_M2_0_NC6")
		)
		(pad "27" smd rect
			(at 3.750056 -2.750058 270)
			(size 0.2794 1.6002)
			(layers "F.Cu" "F.Mask" "F.Paste")
			(net "GND")
		)
		(pad "28" smd rect
			(at -3.800094 -2.500122 270)
			(size 0.2794 1.6002)
			(layers "F.Cu" "F.Mask" "F.Paste")
			(net "NC_M2_0_NC7")
		)
		(pad "29" smd rect
			(at 3.750056 -2.249932 270)
			(size 0.2794 1.6002)
			(layers "F.Cu" "F.Mask" "F.Paste")
			(net "P3E_PCH_M2_RX_DN<2>")
		)
		(pad "30" smd rect
			(at -3.800094 -1.999996 270)
			(size 0.2794 1.6002)
			(layers "F.Cu" "F.Mask" "F.Paste")
			(net "NC_M2_0_NC8")
		)
		(pad "31" smd rect
			(at 3.750056 -1.75006 270)
			(size 0.2794 1.6002)
			(layers "F.Cu" "F.Mask" "F.Paste")
			(net "P3E_PCH_M2_RX_DP<2>")
		)
		(pad "32" smd rect
			(at -3.800094 -1.500124 270)
			(size 0.2794 1.6002)
			(layers "F.Cu" "F.Mask" "F.Paste")
			(net "NC_M2_0_NC9")
		)
		(pad "33" smd rect
			(at 3.750056 -1.249934 270)
			(size 0.2794 1.6002)
			(layers "F.Cu" "F.Mask" "F.Paste")
			(net "GND")
		)
		(pad "34" smd rect
			(at -3.800094 -0.999998 270)
			(size 0.2794 1.6002)
			(layers "F.Cu" "F.Mask" "F.Paste")
			(net "NC_M2_0_NC10")
		)
		(pad "35" smd rect
			(at 3.750056 -0.750062 270)
			(size 0.2794 1.6002)
			(layers "F.Cu" "F.Mask" "F.Paste")
			(net "P3E_PCH_M2_TX_C_DP<2>")
		)
		(pad "36" smd rect
			(at -3.800094 -0.499872 270)
			(size 0.2794 1.6002)
			(layers "F.Cu" "F.Mask" "F.Paste")
			(net "NC_M2_0_NC11")
		)
		(pad "37" smd rect
			(at 3.750056 -0.249936 270)
			(size 0.2794 1.6002)
			(layers "F.Cu" "F.Mask" "F.Paste")
			(net "P3E_PCH_M2_TX_C_DN<2>")
		)
		(pad "38" smd rect
			(at -3.800094 0 270)
			(size 0.2794 1.6002)
			(layers "F.Cu" "F.Mask" "F.Paste")
			(net "PD_M2_0_DEVSLP")
		)
		(pad "39" smd rect
			(at 3.750056 0.249936 270)
			(size 0.2794 1.6002)
			(layers "F.Cu" "F.Mask" "F.Paste")
			(net "GND")
		)
		(pad "40" smd rect
			(at -3.800094 0.499872 270)
			(size 0.2794 1.6002)
			(layers "F.Cu" "F.Mask" "F.Paste")
			(net "SMB_M2_P0_1V8AUX_SCL")
		)
		(pad "41" smd rect
			(at 3.750056 0.750062 270)
			(size 0.2794 1.6002)
			(layers "F.Cu" "F.Mask" "F.Paste")
			(net "P3E_PCH_M2_RX_DN<3>")
		)
		(pad "42" smd rect
			(at -3.800094 0.999998 270)
			(size 0.2794 1.6002)
			(layers "F.Cu" "F.Mask" "F.Paste")
			(net "SMB_M2_P0_1V8AUX_SDA")
		)
		(pad "43" smd rect
			(at 3.750056 1.249934 270)
			(size 0.2794 1.6002)
			(layers "F.Cu" "F.Mask" "F.Paste")
			(net "P3E_PCH_M2_RX_DP<3>")
		)
		(pad "44" smd rect
			(at -3.800094 1.500124 270)
			(size 0.2794 1.6002)
			(layers "F.Cu" "F.Mask" "F.Paste")
			(net "NC_M2_0_NC14")
		)
		(pad "45" smd rect
			(at 3.750056 1.75006 270)
			(size 0.2794 1.6002)
			(layers "F.Cu" "F.Mask" "F.Paste")
			(net "GND")
		)
		(pad "46" smd rect
			(at -3.800094 1.999996 270)
			(size 0.2794 1.6002)
			(layers "F.Cu" "F.Mask" "F.Paste")
			(net "NC_M2_0_NC15")
		)
		(pad "47" smd rect
			(at 3.750056 2.249932 270)
			(size 0.2794 1.6002)
			(layers "F.Cu" "F.Mask" "F.Paste")
			(net "P3E_PCH_M2_TX_C_DP<3>")
		)
		(pad "48" smd rect
			(at -3.800094 2.500122 270)
			(size 0.2794 1.6002)
			(layers "F.Cu" "F.Mask" "F.Paste")
			(net "NC_M2_0_NC16")
		)
		(pad "49" smd rect
			(at 3.750056 2.750058 270)
			(size 0.2794 1.6002)
			(layers "F.Cu" "F.Mask" "F.Paste")
			(net "P3E_PCH_M2_TX_C_DN<3>")
		)
		(pad "50" smd rect
			(at -3.800094 2.999994 270)
			(size 0.2794 1.6002)
			(layers "F.Cu" "F.Mask" "F.Paste")
			(net "RST_PCIE_PCH_DEV_0_N")
		)
		(pad "51" smd rect
			(at 3.750056 3.24993 270)
			(size 0.2794 1.6002)
			(layers "F.Cu" "F.Mask" "F.Paste")
			(net "GND")
		)
		(pad "52" smd rect
			(at -3.800094 3.50012 270)
			(size 0.2794 1.6002)
			(layers "F.Cu" "F.Mask" "F.Paste")
			(net "M2_SSD0_CLKREQ_EN_N_BUF")
		)
		(pad "53" smd rect
			(at 3.750056 3.750056 270)
			(size 0.2794 1.6002)
			(layers "F.Cu" "F.Mask" "F.Paste")
			(net "CLK_100M_PE_M2_0_DN")
		)
		(pad "54" smd rect
			(at -3.800094 3.999992 270)
			(size 0.2794 1.6002)
			(layers "F.Cu" "F.Mask" "F.Paste")
			(net "M2_0_PEWAKE_N")
		)
		(pad "55" smd rect
			(at 3.750056 4.249928 270)
			(size 0.2794 1.6002)
			(layers "F.Cu" "F.Mask" "F.Paste")
			(net "CLK_100M_PE_M2_0_DP")
		)
		(pad "56" smd rect
			(at -3.800094 4.500118 270)
			(size 0.2794 1.6002)
			(layers "F.Cu" "F.Mask" "F.Paste")
			(net "NC_M2_0_NC17")
		)
		(pad "57" smd rect
			(at 3.750056 4.750054 270)
			(size 0.2794 1.6002)
			(layers "F.Cu" "F.Mask" "F.Paste")
			(net "GND")
		)
		(pad "58" smd rect
			(at -3.800094 4.99999 270)
			(size 0.2794 1.6002)
			(layers "F.Cu" "F.Mask" "F.Paste")
			(net "NC_M2_0_NC18")
		)
		(pad "67" smd rect
			(at 3.750056 7.249922 270)
			(size 0.2794 1.6002)
			(layers "F.Cu" "F.Mask" "F.Paste")
			(net "NC_M2_0_NC19")
		)
		(pad "68" smd rect
			(at -3.800094 7.500112 270)
			(size 0.2794 1.6002)
			(layers "F.Cu" "F.Mask" "F.Paste")
			(net "NC_M2_0_SUSCLK")
		)
		(pad "69" smd rect
			(at 3.750056 7.750048 270)
			(size 0.2794 1.6002)
			(layers "F.Cu" "F.Mask" "F.Paste")
			(net "FM_M2_SSD_0_PEDET")
		)
		(pad "70" smd rect
			(at -3.800094 7.999984 270)
			(size 0.2794 1.6002)
			(layers "F.Cu" "F.Mask" "F.Paste")
			(net "P3V3_M2_0")
		)
		(pad "71" smd rect
			(at 3.750056 8.24992 270)
			(size 0.2794 1.6002)
			(layers "F.Cu" "F.Mask" "F.Paste")
			(net "GND")
		)
		(pad "72" smd rect
			(at -3.800094 8.50011 270)
			(size 0.2794 1.6002)
			(layers "F.Cu" "F.Mask" "F.Paste")
			(net "P3V3_M2_0")
		)
		(pad "73" smd rect
			(at 3.750056 8.750046 270)
			(size 0.2794 1.6002)
			(layers "F.Cu" "F.Mask" "F.Paste")
			(net "GND")
		)
		(pad "74" smd rect
			(at -3.800094 8.999982 270)
			(size 0.2794 1.6002)
			(layers "F.Cu" "F.Mask" "F.Paste")
			(net "P3V3_M2_0")
		)
		(pad "75" smd rect
			(at 3.750056 9.249918 270)
			(size 0.2794 1.6002)
			(layers "F.Cu" "F.Mask" "F.Paste")
			(net "GND")
		)
		(pad "G1" smd rect
			(at 2.975102 -10.349992 270)
			(size 1.2446 2.794)
			(layers "F.Cu" "F.Mask" "F.Paste")
			(net "GND")
		)
		(pad "G2" smd rect
			(at 2.975102 10.349992 270)
			(size 1.2446 2.794)
			(layers "F.Cu" "F.Mask" "F.Paste")
			(net "GND")
		)
		(zone
			(layers "F.Cu" "B.Cu" "In1.Cu" "In2.Cu" "In3.Cu" "In4.Cu" "In5.Cu" "In6.Cu"
				"In7.Cu" "In8.Cu" "In9.Cu" "In10.Cu" "In11.Cu" "In12.Cu" "In13.Cu" "In14.Cu"
				"In15.Cu" "In16.Cu"
			)
			(hatch none 0.5)
			(connect_pads
				(clearance 0)
			)
			(min_thickness 0.25)
			(keepout
				(tracks not_allowed)
				(vias allowed)
				(pads allowed)
				(copperpour not_allowed)
				(footprints allowed)
			)
			(placement
				(enabled no)
				(sheetname "")
			)
			(fill
				(thermal_gap 0.5)
				(thermal_bridge_width 0.5)
				(island_removal_mode 0)
			)
			(polygon
				(pts
					(arc
						(start 172.823632 -57.049924)
						(mid 170.842432 -57.049924)
						(end 172.823632 -57.049924)
					)
				)
			)
		)
		(zone
			(layers "F.Cu" "B.Cu" "In1.Cu" "In2.Cu" "In3.Cu" "In4.Cu" "In5.Cu" "In6.Cu"
				"In7.Cu" "In8.Cu" "In9.Cu" "In10.Cu" "In11.Cu" "In12.Cu" "In13.Cu" "In14.Cu"
				"In15.Cu" "In16.Cu"
			)
			(hatch none 0.5)
			(connect_pads
				(clearance 0)
			)
			(min_thickness 0.25)
			(keepout
				(tracks not_allowed)
				(vias allowed)
				(pads allowed)
				(copperpour not_allowed)
				(footprints allowed)
			)
			(placement
				(enabled no)
				(sheetname "")
			)
			(fill
				(thermal_gap 0.5)
				(thermal_bridge_width 0.5)
				(island_removal_mode 0)
			)
			(polygon
				(pts
					(arc
						(start 173.064932 -37.049964)
						(mid 170.601132 -37.049964)
						(end 173.064932 -37.049964)
					)
				)
			)
		)
	)
	(footprint ""
		(layer "F.Cu")
		(at 173.453552 -420.324534)
		(property "Reference" "Q102"
			(at -1.52908 -1.750568 0)
			(unlocked yes)
			(layer "F.SilkS")
			(effects
				(font
					(size 0.7874 0.5842)
					(thickness 0.1524)
				)
				(justify left)
			)
		)
		(property "Value" ""
			(at 0 0 0)
			(layer "F.Fab")
			(effects
				(font
					(size 1.27 1.27)
				)
			)
		)
		(duplicate_pad_numbers_are_jumpers no)
		(fp_line
			(start -1.332738 -1.100074)
			(end -0.4826 -1.100074)
			(stroke
				(width 0.1524)
				(type default)
			)
			(layer "F.SilkS")
		)
		(fp_line
			(start -1.332738 1.100074)
			(end -1.332738 -1.100074)
			(stroke
				(width 0.1524)
				(type default)
			)
			(layer "F.SilkS")
		)
		(fp_line
			(start -0.4826 -1.100074)
			(end 0 -0.541274)
			(stroke
				(width 0.1524)
				(type default)
			)
			(layer "F.SilkS")
		)
		(fp_line
			(start 0 -0.541274)
			(end 0.4826 -1.100074)
			(stroke
				(width 0.1524)
				(type default)
			)
			(layer "F.SilkS")
		)
		(fp_line
			(start 0.4826 -1.100074)
			(end 1.332738 -1.100074)
			(stroke
				(width 0.1524)
				(type default)
			)
			(layer "F.SilkS")
		)
		(fp_line
			(start 1.332738 -1.100074)
			(end 1.332738 1.100074)
			(stroke
				(width 0.1524)
				(type default)
			)
			(layer "F.SilkS")
		)
		(fp_line
			(start 1.332738 1.100074)
			(end -1.332738 1.100074)
			(stroke
				(width 0.1524)
				(type default)
			)
			(layer "F.SilkS")
		)
		(fp_poly
			(pts
				(xy -2.385568 -1.650746) (xy -1.683512 -1.299718) (xy -2.385568 -0.94869)
			)
			(stroke
				(width 0)
				(type default)
			)
			(fill yes)
			(layer "F.SilkS")
		)
		(fp_line
			(start -0.674878 -1.100074)
			(end 0.674878 -1.100074)
			(stroke
				(width 0.1)
				(type default)
			)
			(layer "F.Fab")
		)
		(fp_line
			(start -0.674878 1.100074)
			(end -0.674878 -1.100074)
			(stroke
				(width 0.1)
				(type default)
			)
			(layer "F.Fab")
		)
		(fp_line
			(start 0.674878 -1.100074)
			(end 0.674878 1.100074)
			(stroke
				(width 0.1)
				(type default)
			)
			(layer "F.Fab")
		)
		(fp_line
			(start 0.674878 1.100074)
			(end -0.674878 1.100074)
			(stroke
				(width 0.1)
				(type default)
			)
			(layer "F.Fab")
		)
		(fp_poly
			(pts
				(xy -2.2352 -0.298958) (xy -2.2352 -1.001014) (xy -1.533144 -0.649986)
			)
			(stroke
				(width 0)
				(type default)
			)
			(fill yes)
			(layer "F.Fab")
		)
		(pad "1" smd rect
			(at -0.94996 -0.649986 90)
			(size 0.4318 0.508)
			(layers "F.Cu" "F.Mask" "F.Paste")
			(net "GND")
		)
		(pad "2" smd rect
			(at -0.94996 0 90)
			(size 0.4318 0.508)
			(layers "F.Cu" "F.Mask" "F.Paste")
			(net "GPU_BASE_HMC_READY")
		)
		(pad "3" smd rect
			(at -0.94996 0.649986 90)
			(size 0.4318 0.508)
			(layers "F.Cu" "F.Mask" "F.Paste")
			(net "GPU_BASE_HMC_READY_ISO")
		)
		(pad "4" smd rect
			(at 0.94996 0.649986 90)
			(size 0.4318 0.508)
			(layers "F.Cu" "F.Mask" "F.Paste")
			(net "GND")
		)
		(pad "5" smd rect
			(at 0.94996 0 90)
			(size 0.4318 0.508)
			(layers "F.Cu" "F.Mask" "F.Paste")
			(net "GPU_BASE_HMC_READY_N")
		)
		(pad "6" smd rect
			(at 0.94996 -0.649986 90)
			(size 0.4318 0.508)
			(layers "F.Cu" "F.Mask" "F.Paste")
			(net "GPU_BASE_HMC_READY_N")
		)
	)
	(footprint ""
		(layer "F.Cu")
		(at 250.30303 -44.979082 -90)
		(property "Reference" "PR3960"
			(at 0 0 270)
			(layer "F.SilkS")
			(hide yes)
			(effects
				(font
					(size 1.27 1.27)
				)
			)
		)
		(property "Value" ""
			(at 0 0 270)
			(layer "F.Fab")
			(effects
				(font
					(size 1.27 1.27)
				)
			)
		)
		(duplicate_pad_numbers_are_jumpers no)
		(fp_line
			(start -0.7874 0.4064)
			(end -0.7874 -0.4064)
			(stroke
				(width 0.1524)
				(type default)
			)
			(layer "F.SilkS")
		)
		(fp_line
			(start 0.7874 0.4064)
			(end -0.7874 0.4064)
			(stroke
				(width 0.1524)
				(type default)
			)
			(layer "F.SilkS")
		)
		(fp_line
			(start -0.7874 -0.4064)
			(end 0.7874 -0.4064)
			(stroke
				(width 0.1524)
				(type default)
			)
			(layer "F.SilkS")
		)
		(fp_line
			(start 0.7874 -0.4064)
			(end 0.7874 0.4064)
			(stroke
				(width 0.1524)
				(type default)
			)
			(layer "F.SilkS")
		)
		(fp_line
			(start -0.67945 0.3048)
			(end -0.67945 -0.305054)
			(stroke
				(width 0.1)
				(type default)
			)
			(layer "F.Fab")
		)
		(fp_line
			(start -0.12065 0.3048)
			(end -0.67945 0.3048)
			(stroke
				(width 0.1)
				(type default)
			)
			(layer "F.Fab")
		)
		(fp_line
			(start 0.120396 0.3048)
			(end 0.120396 0.2794)
			(stroke
				(width 0.1)
				(type default)
			)
			(layer "F.Fab")
		)
		(fp_line
			(start 0.67945 0.3048)
			(end 0.120396 0.3048)
			(stroke
				(width 0.1)
				(type default)
			)
			(layer "F.Fab")
		)
		(fp_line
			(start -0.12065 0.2794)
			(end -0.12065 0.3048)
			(stroke
				(width 0.1)
				(type default)
			)
			(layer "F.Fab")
		)
		(fp_line
			(start 0.120396 0.2794)
			(end -0.12065 0.2794)
			(stroke
				(width 0.1)
				(type default)
			)
			(layer "F.Fab")
		)
		(fp_line
			(start -0.12065 -0.2794)
			(end 0.12065 -0.2794)
			(stroke
				(width 0.1)
				(type default)
			)
			(layer "F.Fab")
		)
		(fp_line
			(start 0.12065 -0.2794)
			(end 0.12065 -0.3048)
			(stroke
				(width 0.1)
				(type default)
			)
			(layer "F.Fab")
		)
		(fp_line
			(start 0.12065 -0.3048)
			(end 0.67945 -0.3048)
			(stroke
				(width 0.1)
				(type default)
			)
			(layer "F.Fab")
		)
		(fp_line
			(start 0.67945 -0.3048)
			(end 0.67945 0.3048)
			(stroke
				(width 0.1)
				(type default)
			)
			(layer "F.Fab")
		)
		(fp_line
			(start -0.67945 -0.305054)
			(end -0.12065 -0.305054)
			(stroke
				(width 0.1)
				(type default)
			)
			(layer "F.Fab")
		)
		(fp_line
			(start -0.12065 -0.305054)
			(end -0.12065 -0.2794)
			(stroke
				(width 0.1)
				(type default)
			)
			(layer "F.Fab")
		)
		(pad "1" smd circle
			(at -0.40005 0 270)
			(size 0 0)
			(layers "F.Cu" "F.Mask" "F.Paste")
			(net "P12V_AUX")
		)
		(pad "2" smd circle
			(at 0.40005 0 270)
			(size 0 0)
			(layers "F.Cu" "F.Mask" "F.Paste")
			(net "P12V_E1S_UV_0")
		)
	)
	(footprint ""
		(layer "F.Cu")
		(at 344.64879 -70.52056 90)
		(property "Reference" "C151"
			(at 0 0 90)
			(layer "F.SilkS")
			(hide yes)
			(effects
				(font
					(size 1.27 1.27)
				)
			)
		)
		(property "Value" ""
			(at 0 0 90)
			(layer "F.Fab")
			(effects
				(font
					(size 1.27 1.27)
				)
			)
		)
		(duplicate_pad_numbers_are_jumpers no)
		(fp_line
			(start 0.299974 -0.150114)
			(end 0.299974 0.150114)
			(stroke
				(width 0.1)
				(type default)
			)
			(layer "F.Fab")
		)
		(fp_line
			(start -0.299974 -0.150114)
			(end 0.299974 -0.150114)
			(stroke
				(width 0.1)
				(type default)
			)
			(layer "F.Fab")
		)
		(fp_line
			(start 0.299974 0.150114)
			(end -0.299974 0.150114)
			(stroke
				(width 0.1)
				(type default)
			)
			(layer "F.Fab")
		)
		(fp_line
			(start -0.299974 0.150114)
			(end -0.299974 -0.150114)
			(stroke
				(width 0.1)
				(type default)
			)
			(layer "F.Fab")
		)
		(pad "1" smd rect
			(at -0.2667 0 90)
			(size 0.3048 0.381)
			(layers "F.Cu" "F.Mask" "F.Paste")
			(net "DMI_CPU0_PCH_TX_C_DN<1>")
		)
		(pad "2" smd rect
			(at 0.2667 0 90)
			(size 0.3048 0.381)
			(layers "F.Cu" "F.Mask" "F.Paste")
			(net "DMI_CPU0_PCH_TX_DN<1>")
		)
	)
	(footprint ""
		(layer "F.Cu")
		(at 22.92223 -427.500034)
		(property "Reference" "R2738"
			(at 0 0 0)
			(layer "F.SilkS")
			(hide yes)
			(effects
				(font
					(size 1.27 1.27)
				)
			)
		)
		(property "Value" ""
			(at 0 0 0)
			(layer "F.Fab")
			(effects
				(font
					(size 1.27 1.27)
				)
			)
		)
		(duplicate_pad_numbers_are_jumpers no)
		(fp_line
			(start -0.7874 -0.4064)
			(end 0.7874 -0.4064)
			(stroke
				(width 0.1524)
				(type default)
			)
			(layer "F.SilkS")
		)
		(fp_line
			(start -0.7874 0.4064)
			(end -0.7874 -0.4064)
			(stroke
				(width 0.1524)
				(type default)
			)
			(layer "F.SilkS")
		)
		(fp_line
			(start 0.7874 -0.4064)
			(end 0.7874 0.4064)
			(stroke
				(width 0.1524)
				(type default)
			)
			(layer "F.SilkS")
		)
		(fp_line
			(start 0.7874 0.4064)
			(end -0.7874 0.4064)
			(stroke
				(width 0.1524)
				(type default)
			)
			(layer "F.SilkS")
		)
		(fp_line
			(start -0.67945 -0.305054)
			(end -0.12065 -0.305054)
			(stroke
				(width 0.1)
				(type default)
			)
			(layer "F.Fab")
		)
		(fp_line
			(start -0.67945 0.3048)
			(end -0.67945 -0.305054)
			(stroke
				(width 0.1)
				(type default)
			)
			(layer "F.Fab")
		)
		(fp_line
			(start -0.12065 -0.305054)
			(end -0.12065 -0.2794)
			(stroke
				(width 0.1)
				(type default)
			)
			(layer "F.Fab")
		)
		(fp_line
			(start -0.12065 -0.2794)
			(end 0.12065 -0.2794)
			(stroke
				(width 0.1)
				(type default)
			)
			(layer "F.Fab")
		)
		(fp_line
			(start -0.12065 0.2794)
			(end -0.12065 0.3048)
			(stroke
				(width 0.1)
				(type default)
			)
			(layer "F.Fab")
		)
		(fp_line
			(start -0.12065 0.3048)
			(end -0.67945 0.3048)
			(stroke
				(width 0.1)
				(type default)
			)
			(layer "F.Fab")
		)
		(fp_line
			(start 0.120396 0.2794)
			(end -0.12065 0.2794)
			(stroke
				(width 0.1)
				(type default)
			)
			(layer "F.Fab")
		)
		(fp_line
			(start 0.120396 0.3048)
			(end 0.120396 0.2794)
			(stroke
				(width 0.1)
				(type default)
			)
			(layer "F.Fab")
		)
		(fp_line
			(start 0.12065 -0.3048)
			(end 0.67945 -0.3048)
			(stroke
				(width 0.1)
				(type default)
			)
			(layer "F.Fab")
		)
		(fp_line
			(start 0.12065 -0.2794)
			(end 0.12065 -0.3048)
			(stroke
				(width 0.1)
				(type default)
			)
			(layer "F.Fab")
		)
		(fp_line
			(start 0.67945 -0.3048)
			(end 0.67945 0.3048)
			(stroke
				(width 0.1)
				(type default)
			)
			(layer "F.Fab")
		)
		(fp_line
			(start 0.67945 0.3048)
			(end 0.120396 0.3048)
			(stroke
				(width 0.1)
				(type default)
			)
			(layer "F.Fab")
		)
		(pad "1" smd circle
			(at -0.40005 0)
			(size 0 0)
			(layers "F.Cu" "F.Mask" "F.Paste")
			(net "RST_PERST_SWB_N")
		)
		(pad "2" smd circle
			(at 0.40005 0)
			(size 0 0)
			(layers "F.Cu" "F.Mask" "F.Paste")
			(net "RST_PERST_SWB_R_N")
		)
	)
	(footprint ""
		(layer "F.Cu")
		(at 435.91226 -92.700348)
		(property "Reference" "C2027"
			(at 0 0 0)
			(layer "F.SilkS")
			(hide yes)
			(effects
				(font
					(size 1.27 1.27)
				)
			)
		)
		(property "Value" ""
			(at 0 0 0)
			(layer "F.Fab")
			(effects
				(font
					(size 1.27 1.27)
				)
			)
		)
		(duplicate_pad_numbers_are_jumpers no)
		(fp_line
			(start -0.7874 -0.4064)
			(end 0.7874 -0.4064)
			(stroke
				(width 0.1524)
				(type default)
			)
			(layer "F.SilkS")
		)
		(fp_line
			(start -0.7874 0.4064)
			(end -0.7874 -0.4064)
			(stroke
				(width 0.1524)
				(type default)
			)
			(layer "F.SilkS")
		)
		(fp_line
			(start 0.7874 -0.4064)
			(end 0.7874 0.4064)
			(stroke
				(width 0.1524)
				(type default)
			)
			(layer "F.SilkS")
		)
		(fp_line
			(start 0.7874 0.4064)
			(end -0.7874 0.4064)
			(stroke
				(width 0.1524)
				(type default)
			)
			(layer "F.SilkS")
		)
		(fp_line
			(start -0.67945 -0.305054)
			(end -0.12065 -0.305054)
			(stroke
				(width 0.1)
				(type default)
			)
			(layer "F.Fab")
		)
		(fp_line
			(start -0.67945 0.3048)
			(end -0.67945 -0.305054)
			(stroke
				(width 0.1)
				(type default)
			)
			(layer "F.Fab")
		)
		(fp_line
			(start -0.12065 -0.305054)
			(end -0.12065 -0.2794)
			(stroke
				(width 0.1)
				(type default)
			)
			(layer "F.Fab")
		)
		(fp_line
			(start -0.12065 -0.2794)
			(end 0.12065 -0.2794)
			(stroke
				(width 0.1)
				(type default)
			)
			(layer "F.Fab")
		)
		(fp_line
			(start -0.12065 0.2794)
			(end -0.12065 0.3048)
			(stroke
				(width 0.1)
				(type default)
			)
			(layer "F.Fab")
		)
		(fp_line
			(start -0.12065 0.3048)
			(end -0.67945 0.3048)
			(stroke
				(width 0.1)
				(type default)
			)
			(layer "F.Fab")
		)
		(fp_line
			(start 0.120396 0.2794)
			(end -0.12065 0.2794)
			(stroke
				(width 0.1)
				(type default)
			)
			(layer "F.Fab")
		)
		(fp_line
			(start 0.120396 0.3048)
			(end 0.120396 0.2794)
			(stroke
				(width 0.1)
				(type default)
			)
			(layer "F.Fab")
		)
		(fp_line
			(start 0.12065 -0.3048)
			(end 0.67945 -0.3048)
			(stroke
				(width 0.1)
				(type default)
			)
			(layer "F.Fab")
		)
		(fp_line
			(start 0.12065 -0.2794)
			(end 0.12065 -0.3048)
			(stroke
				(width 0.1)
				(type default)
			)
			(layer "F.Fab")
		)
		(fp_line
			(start 0.67945 -0.3048)
			(end 0.67945 0.3048)
			(stroke
				(width 0.1)
				(type default)
			)
			(layer "F.Fab")
		)
		(fp_line
			(start 0.67945 0.3048)
			(end 0.120396 0.3048)
			(stroke
				(width 0.1)
				(type default)
			)
			(layer "F.Fab")
		)
		(pad "1" smd circle
			(at -0.40005 0)
			(size 0 0)
			(layers "F.Cu" "F.Mask" "F.Paste")
			(net "VSENSE_P3V3_INA230_1_INP")
		)
		(pad "2" smd circle
			(at 0.40005 0)
			(size 0 0)
			(layers "F.Cu" "F.Mask" "F.Paste")
			(net "VSENSE_P3V3_INA230_1_INN")
		)
	)
	(footprint ""
		(layer "F.Cu")
		(at 17.899888 -51.999896)
		(property "Reference" "J100"
			(at -2.413 -12.080748 0)
			(unlocked yes)
			(layer "F.SilkS")
			(effects
				(font
					(size 0.7874 0.5842)
					(thickness 0.1524)
				)
			)
		)
		(property "Value" ""
			(at 0 0 0)
			(layer "F.Fab")
			(effects
				(font
					(size 1.27 1.27)
				)
			)
		)
		(duplicate_pad_numbers_are_jumpers no)
		(fp_line
			(start -3.150108 -11.325098)
			(end 3.150108 -11.325098)
			(stroke
				(width 0.1524)
				(type default)
			)
			(layer "F.SilkS")
		)
		(fp_line
			(start -3.150108 -9.596882)
			(end -3.150108 -11.325098)
			(stroke
				(width 0.1524)
				(type default)
			)
			(layer "F.SilkS")
		)
		(fp_line
			(start -3.150108 -7.596886)
			(end -3.150108 -8.403082)
			(stroke
				(width 0.1524)
				(type default)
			)
			(layer "F.SilkS")
		)
		(fp_line
			(start -3.150108 -5.59689)
			(end -3.150108 -6.403086)
			(stroke
				(width 0.1524)
				(type default)
			)
			(layer "F.SilkS")
		)
		(fp_line
			(start -3.150108 -3.596894)
			(end -3.150108 -4.40309)
			(stroke
				(width 0.1524)
				(type default)
			)
			(layer "F.SilkS")
		)
		(fp_line
			(start -3.150108 -1.596898)
			(end -3.150108 -2.403094)
			(stroke
				(width 0.1524)
				(type default)
			)
			(layer "F.SilkS")
		)
		(fp_line
			(start -3.150108 0.403098)
			(end -3.150108 -0.403098)
			(stroke
				(width 0.1524)
				(type default)
			)
			(layer "F.SilkS")
		)
		(fp_line
			(start -3.150108 2.403094)
			(end -3.150108 1.596898)
			(stroke
				(width 0.1524)
				(type default)
			)
			(layer "F.SilkS")
		)
		(fp_line
			(start -3.150108 4.40309)
			(end -3.150108 3.596894)
			(stroke
				(width 0.1524)
				(type default)
			)
			(layer "F.SilkS")
		)
		(fp_line
			(start -3.150108 6.403086)
			(end -3.150108 5.59689)
			(stroke
				(width 0.1524)
				(type default)
			)
			(layer "F.SilkS")
		)
		(fp_line
			(start -3.150108 8.403082)
			(end -3.150108 7.596886)
			(stroke
				(width 0.1524)
				(type default)
			)
			(layer "F.SilkS")
		)
		(fp_line
			(start -3.150108 11.325098)
			(end -3.150108 9.596882)
			(stroke
				(width 0.1524)
				(type default)
			)
			(layer "F.SilkS")
		)
		(fp_line
			(start 3.150108 -11.325098)
			(end 3.150108 -9.596882)
			(stroke
				(width 0.1524)
				(type default)
			)
			(layer "F.SilkS")
		)
		(fp_line
			(start 3.150108 -8.403082)
			(end 3.150108 -7.596886)
			(stroke
				(width 0.1524)
				(type default)
			)
			(layer "F.SilkS")
		)
		(fp_line
			(start 3.150108 -6.403086)
			(end 3.150108 -5.59689)
			(stroke
				(width 0.1524)
				(type default)
			)
			(layer "F.SilkS")
		)
		(fp_line
			(start 3.150108 -4.40309)
			(end 3.150108 -3.596894)
			(stroke
				(width 0.1524)
				(type default)
			)
			(layer "F.SilkS")
		)
		(fp_line
			(start 3.150108 -2.403094)
			(end 3.150108 -1.596898)
			(stroke
				(width 0.1524)
				(type default)
			)
			(layer "F.SilkS")
		)
		(fp_line
			(start 3.150108 -0.403098)
			(end 3.150108 0.403098)
			(stroke
				(width 0.1524)
				(type default)
			)
			(layer "F.SilkS")
		)
		(fp_line
			(start 3.150108 1.596898)
			(end 3.150108 2.403094)
			(stroke
				(width 0.1524)
				(type default)
			)
			(layer "F.SilkS")
		)
		(fp_line
			(start 3.150108 3.596894)
			(end 3.150108 4.40309)
			(stroke
				(width 0.1524)
				(type default)
			)
			(layer "F.SilkS")
		)
		(fp_line
			(start 3.150108 5.59689)
			(end 3.150108 6.403086)
			(stroke
				(width 0.1524)
				(type default)
			)
			(layer "F.SilkS")
		)
		(fp_line
			(start 3.150108 7.596886)
			(end 3.150108 8.403082)
			(stroke
				(width 0.1524)
				(type default)
			)
			(layer "F.SilkS")
		)
		(fp_line
			(start 3.150108 9.596882)
			(end 3.150108 11.325098)
			(stroke
				(width 0.1524)
				(type default)
			)
			(layer "F.SilkS")
		)
		(fp_line
			(start 3.150108 11.325098)
			(end -3.150108 11.325098)
			(stroke
				(width 0.1524)
				(type default)
			)
			(layer "F.SilkS")
		)
		(fp_rect
			(start -3.150108 0.491998)
			(end -2.249932 -0.491998)
			(stroke
				(width 0)
				(type default)
			)
			(fill yes)
			(layer "F.SilkS")
		)
		(fp_poly
			(pts
				(xy -4.967224 -9.487662) (xy -3.951224 -8.979662) (xy -4.967224 -8.471662)
			)
			(stroke
				(width 0)
				(type default)
			)
			(fill yes)
			(layer "F.SilkS")
		)
		(fp_line
			(start -3.150108 -11.325098)
			(end 3.150108 -11.325098)
			(stroke
				(width 0.1)
				(type default)
			)
			(layer "F.Fab")
		)
		(fp_line
			(start -3.150108 11.325098)
			(end -3.150108 -11.325098)
			(stroke
				(width 0.1)
				(type default)
			)
			(layer "F.Fab")
		)
		(fp_line
			(start 3.150108 -11.325098)
			(end 3.150108 11.325098)
			(stroke
				(width 0.1)
				(type default)
			)
			(layer "F.Fab")
		)
		(fp_line
			(start 3.150108 11.325098)
			(end -3.150108 11.325098)
			(stroke
				(width 0.1)
				(type default)
			)
			(layer "F.Fab")
		)
		(fp_poly
			(pts
				(xy -4.728464 -9.507982) (xy -4.728464 -8.491982) (xy -3.712464 -8.999982)
			)
			(stroke
				(width 0)
				(type default)
			)
			(fill yes)
			(layer "F.Fab")
		)
		(pad "" np_thru_hole circle
			(at 0 -7.999984 270)
			(size 1.016 1.016)
			(drill 1.016)
			(layers "*.Cu" "*.Mask")
			(clearance 0.381)
			(thermal_gap 0.381)
		)
		(pad "" np_thru_hole circle
			(at 0 7.999984 270)
			(size 1.016 1.016)
			(drill 1.016)
			(layers "*.Cu" "*.Mask")
			(clearance 0.381)
			(thermal_gap 0.381)
		)
		(pad "1" smd rect
			(at -2.124964 -8.999982 270)
			(size 0.9144 2.7686)
			(layers "F.Cu" "F.Mask" "F.Paste")
			(net "SMB_SML0_ME_SCL")
		)
		(pad "2" smd rect
			(at 2.124964 -8.999982 270)
			(size 0.9144 2.7686)
			(layers "F.Cu" "F.Mask" "F.Paste")
			(net "GND")
		)
		(pad "3" smd rect
			(at -2.124964 -6.999986 270)
			(size 0.9144 2.7686)
			(layers "F.Cu" "F.Mask" "F.Paste")
			(net "SMB_SML0_ME_SDA")
		)
		(pad "4" smd rect
			(at 2.124964 -6.999986 270)
			(size 0.9144 2.7686)
			(layers "F.Cu" "F.Mask" "F.Paste")
			(net "IRQ_SML0_ALERT_R1_N")
		)
		(pad "5" smd rect
			(at -2.124964 -4.99999 270)
			(size 0.9144 2.7686)
			(layers "F.Cu" "F.Mask" "F.Paste")
			(net "SMB_PMBUS_SML1_ME_SCL")
		)
		(pad "6" smd rect
			(at 2.124964 -4.99999 270)
			(size 0.9144 2.7686)
			(layers "F.Cu" "F.Mask" "F.Paste")
			(net "GND")
		)
		(pad "7" smd rect
			(at -2.124964 -2.999994 270)
			(size 0.9144 2.7686)
			(layers "F.Cu" "F.Mask" "F.Paste")
			(net "SMB_PMBUS_SML1_ME_SDA")
		)
		(pad "8" smd rect
			(at 2.124964 -2.999994 270)
			(size 0.9144 2.7686)
			(layers "F.Cu" "F.Mask" "F.Paste")
			(net "IRQ_SML1_PMBUS_ALERT_R_N")
		)
		(pad "9" smd rect
			(at -2.124964 -0.999998 270)
			(size 0.9144 2.7686)
			(layers "F.Cu" "F.Mask" "F.Paste")
			(net "RST_RSMRST_NM_HDR_N")
		)
		(pad "10" smd rect
			(at 2.124964 -0.999998 270)
			(size 0.9144 2.7686)
			(layers "F.Cu" "F.Mask" "F.Paste")
			(net "GND")
		)
		(pad "11" smd rect
			(at -2.124964 0.999998 270)
			(size 0.9144 2.7686)
			(layers "F.Cu" "F.Mask" "F.Paste")
			(net "SMB_HOST_ME_SCL")
		)
		(pad "12" smd rect
			(at 2.124964 0.999998 270)
			(size 0.9144 2.7686)
			(layers "F.Cu" "F.Mask" "F.Paste")
			(net "GND")
		)
		(pad "13" smd rect
			(at -2.124964 2.999994 270)
			(size 0.9144 2.7686)
			(layers "F.Cu" "F.Mask" "F.Paste")
			(net "SMB_HOST_ME_SDA")
		)
		(pad "14" smd rect
			(at 2.124964 2.999994 270)
			(size 0.9144 2.7686)
			(layers "F.Cu" "F.Mask" "F.Paste")
			(net "Net_8591")
		)
		(pad "15" smd rect
			(at -2.124964 4.99999 270)
			(size 0.9144 2.7686)
			(layers "F.Cu" "F.Mask" "F.Paste")
			(net "GND")
		)
		(pad "16" smd rect
			(at 2.124964 4.99999 270)
			(size 0.9144 2.7686)
			(layers "F.Cu" "F.Mask" "F.Paste")
			(net "PECI_BMC_ME")
		)
		(pad "17" smd rect
			(at -2.124964 6.999986 270)
			(size 0.9144 2.7686)
			(layers "F.Cu" "F.Mask" "F.Paste")
			(net "GND")
		)
		(pad "18" smd rect
			(at 2.124964 6.999986 270)
			(size 0.9144 2.7686)
			(layers "F.Cu" "F.Mask" "F.Paste")
			(net "PWRGD_PS_PWROK_ME_CONN")
		)
		(pad "19" smd rect
			(at -2.124964 8.999982 270)
			(size 0.9144 2.7686)
			(layers "F.Cu" "F.Mask" "F.Paste")
			(net "FM_BIOS_POST_CMPLT_HDR_N")
		)
		(pad "20" smd rect
			(at 2.124964 8.999982 270)
			(size 0.9144 2.7686)
			(layers "F.Cu" "F.Mask" "F.Paste")
			(net "Net_8590")
		)
		(zone
			(layers "F.Cu" "B.Cu" "In1.Cu" "In2.Cu" "In3.Cu" "In4.Cu" "In5.Cu" "In6.Cu"
				"In7.Cu" "In8.Cu" "In9.Cu" "In10.Cu" "In11.Cu" "In12.Cu" "In13.Cu" "In14.Cu"
				"In15.Cu" "In16.Cu"
			)
			(hatch none 0.5)
			(connect_pads
				(clearance 0)
			)
			(min_thickness 0.25)
			(keepout
				(tracks not_allowed)
				(vias allowed)
				(pads allowed)
				(copperpour not_allowed)
				(footprints allowed)
			)
			(placement
				(enabled no)
				(sheetname "")
			)
			(fill
				(thermal_gap 0.5)
				(thermal_bridge_width 0.5)
				(island_removal_mode 0)
			)
			(polygon
				(pts
					(arc
						(start 18.814288 -59.99988)
						(mid 16.985488 -59.99988)
						(end 18.814288 -59.99988)
					)
				)
			)
		)
		(zone
			(layers "F.Cu" "B.Cu" "In1.Cu" "In2.Cu" "In3.Cu" "In4.Cu" "In5.Cu" "In6.Cu"
				"In7.Cu" "In8.Cu" "In9.Cu" "In10.Cu" "In11.Cu" "In12.Cu" "In13.Cu" "In14.Cu"
				"In15.Cu" "In16.Cu"
			)
			(hatch none 0.5)
			(connect_pads
				(clearance 0)
			)
			(min_thickness 0.25)
			(keepout
				(tracks not_allowed)
				(vias allowed)
				(pads allowed)
				(copperpour not_allowed)
				(footprints allowed)
			)
			(placement
				(enabled no)
				(sheetname "")
			)
			(fill
				(thermal_gap 0.5)
				(thermal_bridge_width 0.5)
				(island_removal_mode 0)
			)
			(polygon
				(pts
					(arc
						(start 18.814288 -43.999912)
						(mid 16.985488 -43.999912)
						(end 18.814288 -43.999912)
					)
				)
			)
		)
	)
	(footprint ""
		(layer "F.Cu")
		(at 369.81511 -409.6512)
		(property "Reference" "R4739"
			(at 0 0 0)
			(layer "F.SilkS")
			(hide yes)
			(effects
				(font
					(size 1.27 1.27)
				)
			)
		)
		(property "Value" ""
			(at 0 0 0)
			(layer "F.Fab")
			(effects
				(font
					(size 1.27 1.27)
				)
			)
		)
		(duplicate_pad_numbers_are_jumpers no)
		(fp_line
			(start -0.7874 -0.4064)
			(end 0.7874 -0.4064)
			(stroke
				(width 0.1524)
				(type default)
			)
			(layer "F.SilkS")
		)
		(fp_line
			(start -0.7874 0.4064)
			(end -0.7874 -0.4064)
			(stroke
				(width 0.1524)
				(type default)
			)
			(layer "F.SilkS")
		)
		(fp_line
			(start 0.7874 -0.4064)
			(end 0.7874 0.4064)
			(stroke
				(width 0.1524)
				(type default)
			)
			(layer "F.SilkS")
		)
		(fp_line
			(start 0.7874 0.4064)
			(end -0.7874 0.4064)
			(stroke
				(width 0.1524)
				(type default)
			)
			(layer "F.SilkS")
		)
		(fp_line
			(start -0.67945 -0.305054)
			(end -0.12065 -0.305054)
			(stroke
				(width 0.1)
				(type default)
			)
			(layer "F.Fab")
		)
		(fp_line
			(start -0.67945 0.3048)
			(end -0.67945 -0.305054)
			(stroke
				(width 0.1)
				(type default)
			)
			(layer "F.Fab")
		)
		(fp_line
			(start -0.12065 -0.305054)
			(end -0.12065 -0.2794)
			(stroke
				(width 0.1)
				(type default)
			)
			(layer "F.Fab")
		)
		(fp_line
			(start -0.12065 -0.2794)
			(end 0.12065 -0.2794)
			(stroke
				(width 0.1)
				(type default)
			)
			(layer "F.Fab")
		)
		(fp_line
			(start -0.12065 0.2794)
			(end -0.12065 0.3048)
			(stroke
				(width 0.1)
				(type default)
			)
			(layer "F.Fab")
		)
		(fp_line
			(start -0.12065 0.3048)
			(end -0.67945 0.3048)
			(stroke
				(width 0.1)
				(type default)
			)
			(layer "F.Fab")
		)
		(fp_line
			(start 0.120396 0.2794)
			(end -0.12065 0.2794)
			(stroke
				(width 0.1)
				(type default)
			)
			(layer "F.Fab")
		)
		(fp_line
			(start 0.120396 0.3048)
			(end 0.120396 0.2794)
			(stroke
				(width 0.1)
				(type default)
			)
			(layer "F.Fab")
		)
		(fp_line
			(start 0.12065 -0.3048)
			(end 0.67945 -0.3048)
			(stroke
				(width 0.1)
				(type default)
			)
			(layer "F.Fab")
		)
		(fp_line
			(start 0.12065 -0.2794)
			(end 0.12065 -0.3048)
			(stroke
				(width 0.1)
				(type default)
			)
			(layer "F.Fab")
		)
		(fp_line
			(start 0.67945 -0.3048)
			(end 0.67945 0.3048)
			(stroke
				(width 0.1)
				(type default)
			)
			(layer "F.Fab")
		)
		(fp_line
			(start 0.67945 0.3048)
			(end 0.120396 0.3048)
			(stroke
				(width 0.1)
				(type default)
			)
			(layer "F.Fab")
		)
		(pad "1" smd circle
			(at -0.40005 0)
			(size 0 0)
			(layers "F.Cu" "F.Mask" "F.Paste")
			(net "P3V3_AUX")
		)
		(pad "2" smd circle
			(at 0.40005 0)
			(size 0 0)
			(layers "F.Cu" "F.Mask" "F.Paste")
			(net "PRSNT_CABLE_SWB_B1")
		)
	)
	(footprint ""
		(layer "F.Cu")
		(at 39.032688 -439.198512 180)
		(property "Reference" "U200"
			(at 0.153416 -2.198878 0)
			(unlocked yes)
			(layer "F.SilkS")
			(effects
				(font
					(size 0.7874 0.5842)
					(thickness 0.1524)
				)
				(justify left)
			)
		)
		(property "Value" ""
			(at 0 0 180)
			(layer "F.Fab")
			(effects
				(font
					(size 1.27 1.27)
				)
			)
		)
		(duplicate_pad_numbers_are_jumpers no)
		(fp_line
			(start 1.3716 1.524)
			(end -1.3716 1.524)
			(stroke
				(width 0.1524)
				(type default)
			)
			(layer "F.SilkS")
		)
		(fp_line
			(start 1.3716 -1.524)
			(end 1.3716 1.524)
			(stroke
				(width 0.1524)
				(type default)
			)
			(layer "F.SilkS")
		)
		(fp_line
			(start 0.508 -1.524)
			(end 1.3716 -1.524)
			(stroke
				(width 0.1524)
				(type default)
			)
			(layer "F.SilkS")
		)
		(fp_line
			(start 0 -1.016)
			(end 0.508 -1.524)
			(stroke
				(width 0.1524)
				(type default)
			)
			(layer "F.SilkS")
		)
		(fp_line
			(start -0.508 -1.524)
			(end 0 -1.016)
			(stroke
				(width 0.1524)
				(type default)
			)
			(layer "F.SilkS")
		)
		(fp_line
			(start -1.3716 1.524)
			(end -1.3716 -1.524)
			(stroke
				(width 0.1524)
				(type default)
			)
			(layer "F.SilkS")
		)
		(fp_line
			(start -1.3716 -1.524)
			(end -0.508 -1.524)
			(stroke
				(width 0.1524)
				(type default)
			)
			(layer "F.SilkS")
		)
		(fp_poly
			(pts
				(xy -3.70332 -1.270508) (xy -3.1496 -0.94234) (xy -3.70332 -0.645668)
			)
			(stroke
				(width 0)
				(type default)
			)
			(fill yes)
			(layer "F.SilkS")
		)
		(fp_line
			(start 2.54 1.0668)
			(end 1.5494 1.0668)
			(stroke
				(width 0.1)
				(type default)
			)
			(layer "F.Fab")
		)
		(fp_line
			(start 2.54 -1.0668)
			(end 2.54 1.0668)
			(stroke
				(width 0.1)
				(type default)
			)
			(layer "F.Fab")
		)
		(fp_line
			(start 1.5494 1.524)
			(end -1.5494 1.524)
			(stroke
				(width 0.1)
				(type default)
			)
			(layer "F.Fab")
		)
		(fp_line
			(start 1.5494 1.0668)
			(end 1.5494 1.524)
			(stroke
				(width 0.1)
				(type default)
			)
			(layer "F.Fab")
		)
		(fp_line
			(start 1.5494 -1.0668)
			(end 2.54 -1.0668)
			(stroke
				(width 0.1)
				(type default)
			)
			(layer "F.Fab")
		)
		(fp_line
			(start 1.5494 -1.0668)
			(end 1.5494 1.0668)
			(stroke
				(width 0.1)
				(type default)
			)
			(layer "F.Fab")
		)
		(fp_line
			(start 1.5494 -1.524)
			(end 1.5494 -1.0668)
			(stroke
				(width 0.1)
				(type default)
			)
			(layer "F.Fab")
		)
		(fp_line
			(start -1.5494 1.524)
			(end -1.5494 1.0668)
			(stroke
				(width 0.1)
				(type default)
			)
			(layer "F.Fab")
		)
		(fp_line
			(start -1.5494 1.0668)
			(end -1.5494 -1.0668)
			(stroke
				(width 0.1)
				(type default)
			)
			(layer "F.Fab")
		)
		(fp_line
			(start -1.5494 1.0668)
			(end -2.54 1.0668)
			(stroke
				(width 0.1)
				(type default)
			)
			(layer "F.Fab")
		)
		(fp_line
			(start -1.5494 -1.0668)
			(end -1.5494 -1.524)
			(stroke
				(width 0.1)
				(type default)
			)
			(layer "F.Fab")
		)
		(fp_line
			(start -1.5494 -1.524)
			(end 1.5494 -1.524)
			(stroke
				(width 0.1)
				(type default)
			)
			(layer "F.Fab")
		)
		(fp_line
			(start -2.54 1.0668)
			(end -2.54 -1.0668)
			(stroke
				(width 0.1)
				(type default)
			)
			(layer "F.Fab")
		)
		(fp_line
			(start -2.54 -1.0668)
			(end -1.5494 -1.0668)
			(stroke
				(width 0.1)
				(type default)
			)
			(layer "F.Fab")
		)
		(fp_poly
			(pts
				(xy -3.60172 -0.719328) (xy -3.60172 -1.344168) (xy -3.048 -1.016)
			)
			(stroke
				(width 0)
				(type default)
			)
			(fill yes)
			(layer "F.Fab")
		)
		(pad "1" smd rect
			(at -2.232406 -0.975106 90)
			(size 0.3556 1.4224)
			(layers "F.Cu" "F.Mask" "F.Paste")
			(net "SMB_BMC_GPU_EN_R3")
		)
		(pad "2" smd rect
			(at -2.232406 -0.32512 90)
			(size 0.3556 1.4224)
			(layers "F.Cu" "F.Mask" "F.Paste")
			(net "SMB_2_BMC_GPU_BUF_R_SCL")
		)
		(pad "3" smd rect
			(at -2.232406 0.32512 90)
			(size 0.3556 1.4224)
			(layers "F.Cu" "F.Mask" "F.Paste")
			(net "SMB_2_BMC_GPU_R_SCL")
		)
		(pad "4" smd rect
			(at -2.232406 0.975106 90)
			(size 0.3556 1.4224)
			(layers "F.Cu" "F.Mask" "F.Paste")
			(net "GND")
		)
		(pad "5" smd rect
			(at 2.232406 0.975106 90)
			(size 0.3556 1.4224)
			(layers "F.Cu" "F.Mask" "F.Paste")
			(net "Net_1937")
		)
		(pad "6" smd rect
			(at 2.232406 0.32512 90)
			(size 0.3556 1.4224)
			(layers "F.Cu" "F.Mask" "F.Paste")
			(net "SMB_2_BMC_GPU_R_SDA")
		)
		(pad "7" smd rect
			(at 2.232406 -0.32512 90)
			(size 0.3556 1.4224)
			(layers "F.Cu" "F.Mask" "F.Paste")
			(net "SMB_2_BMC_GPU_BUF_R_SDA")
		)
		(pad "8" smd rect
			(at 2.232406 -0.975106 90)
			(size 0.3556 1.4224)
			(layers "F.Cu" "F.Mask" "F.Paste")
			(net "P3V3_AUX")
		)
	)
	(footprint ""
		(layer "F.Cu")
		(at 118.671594 -93.404182 -90)
		(property "Reference" "C2243"
			(at 0 0 270)
			(layer "F.SilkS")
			(hide yes)
			(effects
				(font
					(size 1.27 1.27)
				)
			)
		)
		(property "Value" ""
			(at 0 0 270)
			(layer "F.Fab")
			(effects
				(font
					(size 1.27 1.27)
				)
			)
		)
		(duplicate_pad_numbers_are_jumpers no)
		(fp_line
			(start -0.7874 0.4064)
			(end -0.7874 -0.4064)
			(stroke
				(width 0.1524)
				(type default)
			)
			(layer "F.SilkS")
		)
		(fp_line
			(start 0.7874 0.4064)
			(end -0.7874 0.4064)
			(stroke
				(width 0.1524)
				(type default)
			)
			(layer "F.SilkS")
		)
		(fp_line
			(start -0.7874 -0.4064)
			(end 0.7874 -0.4064)
			(stroke
				(width 0.1524)
				(type default)
			)
			(layer "F.SilkS")
		)
		(fp_line
			(start 0.7874 -0.4064)
			(end 0.7874 0.4064)
			(stroke
				(width 0.1524)
				(type default)
			)
			(layer "F.SilkS")
		)
		(fp_line
			(start -0.67945 0.3048)
			(end -0.67945 -0.305054)
			(stroke
				(width 0.1)
				(type default)
			)
			(layer "F.Fab")
		)
		(fp_line
			(start -0.12065 0.3048)
			(end -0.67945 0.3048)
			(stroke
				(width 0.1)
				(type default)
			)
			(layer "F.Fab")
		)
		(fp_line
			(start 0.120396 0.3048)
			(end 0.120396 0.2794)
			(stroke
				(width 0.1)
				(type default)
			)
			(layer "F.Fab")
		)
		(fp_line
			(start 0.67945 0.3048)
			(end 0.120396 0.3048)
			(stroke
				(width 0.1)
				(type default)
			)
			(layer "F.Fab")
		)
		(fp_line
			(start -0.12065 0.2794)
			(end -0.12065 0.3048)
			(stroke
				(width 0.1)
				(type default)
			)
			(layer "F.Fab")
		)
		(fp_line
			(start 0.120396 0.2794)
			(end -0.12065 0.2794)
			(stroke
				(width 0.1)
				(type default)
			)
			(layer "F.Fab")
		)
		(fp_line
			(start -0.12065 -0.2794)
			(end 0.12065 -0.2794)
			(stroke
				(width 0.1)
				(type default)
			)
			(layer "F.Fab")
		)
		(fp_line
			(start 0.12065 -0.2794)
			(end 0.12065 -0.3048)
			(stroke
				(width 0.1)
				(type default)
			)
			(layer "F.Fab")
		)
		(fp_line
			(start 0.12065 -0.3048)
			(end 0.67945 -0.3048)
			(stroke
				(width 0.1)
				(type default)
			)
			(layer "F.Fab")
		)
		(fp_line
			(start 0.67945 -0.3048)
			(end 0.67945 0.3048)
			(stroke
				(width 0.1)
				(type default)
			)
			(layer "F.Fab")
		)
		(fp_line
			(start -0.67945 -0.305054)
			(end -0.12065 -0.305054)
			(stroke
				(width 0.1)
				(type default)
			)
			(layer "F.Fab")
		)
		(fp_line
			(start -0.12065 -0.305054)
			(end -0.12065 -0.2794)
			(stroke
				(width 0.1)
				(type default)
			)
			(layer "F.Fab")
		)
		(pad "1" smd circle
			(at -0.40005 0 270)
			(size 0 0)
			(layers "F.Cu" "F.Mask" "F.Paste")
			(net "P3V3")
		)
		(pad "2" smd circle
			(at 0.40005 0 270)
			(size 0 0)
			(layers "F.Cu" "F.Mask" "F.Paste")
			(net "GND")
		)
	)
	(footprint ""
		(layer "F.Cu")
		(at 145.34388 -56.225948 180)
		(property "Reference" "R2410"
			(at 0 0 180)
			(layer "F.SilkS")
			(hide yes)
			(effects
				(font
					(size 1.27 1.27)
				)
			)
		)
		(property "Value" ""
			(at 0 0 180)
			(layer "F.Fab")
			(effects
				(font
					(size 1.27 1.27)
				)
			)
		)
		(duplicate_pad_numbers_are_jumpers no)
		(fp_line
			(start 0.7874 0.4064)
			(end -0.7874 0.4064)
			(stroke
				(width 0.1524)
				(type default)
			)
			(layer "F.SilkS")
		)
		(fp_line
			(start 0.7874 -0.4064)
			(end 0.7874 0.4064)
			(stroke
				(width 0.1524)
				(type default)
			)
			(layer "F.SilkS")
		)
		(fp_line
			(start -0.7874 0.4064)
			(end -0.7874 -0.4064)
			(stroke
				(width 0.1524)
				(type default)
			)
			(layer "F.SilkS")
		)
		(fp_line
			(start -0.7874 -0.4064)
			(end 0.7874 -0.4064)
			(stroke
				(width 0.1524)
				(type default)
			)
			(layer "F.SilkS")
		)
		(fp_line
			(start 0.67945 0.3048)
			(end 0.120396 0.3048)
			(stroke
				(width 0.1)
				(type default)
			)
			(layer "F.Fab")
		)
		(fp_line
			(start 0.67945 -0.3048)
			(end 0.67945 0.3048)
			(stroke
				(width 0.1)
				(type default)
			)
			(layer "F.Fab")
		)
		(fp_line
			(start 0.12065 -0.2794)
			(end 0.12065 -0.3048)
			(stroke
				(width 0.1)
				(type default)
			)
			(layer "F.Fab")
		)
		(fp_line
			(start 0.12065 -0.3048)
			(end 0.67945 -0.3048)
			(stroke
				(width 0.1)
				(type default)
			)
			(layer "F.Fab")
		)
		(fp_line
			(start 0.120396 0.3048)
			(end 0.120396 0.2794)
			(stroke
				(width 0.1)
				(type default)
			)
			(layer "F.Fab")
		)
		(fp_line
			(start 0.120396 0.2794)
			(end -0.12065 0.2794)
			(stroke
				(width 0.1)
				(type default)
			)
			(layer "F.Fab")
		)
		(fp_line
			(start -0.12065 0.3048)
			(end -0.67945 0.3048)
			(stroke
				(width 0.1)
				(type default)
			)
			(layer "F.Fab")
		)
		(fp_line
			(start -0.12065 0.2794)
			(end -0.12065 0.3048)
			(stroke
				(width 0.1)
				(type default)
			)
			(layer "F.Fab")
		)
		(fp_line
			(start -0.12065 -0.2794)
			(end 0.12065 -0.2794)
			(stroke
				(width 0.1)
				(type default)
			)
			(layer "F.Fab")
		)
		(fp_line
			(start -0.12065 -0.305054)
			(end -0.12065 -0.2794)
			(stroke
				(width 0.1)
				(type default)
			)
			(layer "F.Fab")
		)
		(fp_line
			(start -0.67945 0.3048)
			(end -0.67945 -0.305054)
			(stroke
				(width 0.1)
				(type default)
			)
			(layer "F.Fab")
		)
		(fp_line
			(start -0.67945 -0.305054)
			(end -0.12065 -0.305054)
			(stroke
				(width 0.1)
				(type default)
			)
			(layer "F.Fab")
		)
		(pad "1" smd circle
			(at -0.40005 0 180)
			(size 0 0)
			(layers "F.Cu" "F.Mask" "F.Paste")
			(net "SMB_M2_P0_1V8AUX_SDA_R")
		)
		(pad "2" smd circle
			(at 0.40005 0 180)
			(size 0 0)
			(layers "F.Cu" "F.Mask" "F.Paste")
			(net "SMB_M2_P0_1V8AUX_SDA")
		)
	)
	(footprint ""
		(layer "F.Cu")
		(at 239.949736 -39.424864)
		(property "Reference" "H76"
			(at -0.155702 -3.208274 0)
			(unlocked yes)
			(layer "B.SilkS")
			(effects
				(font
					(size 0.7874 0.5842)
					(thickness 0.1524)
				)
				(justify left mirror)
			)
		)
		(property "Value" ""
			(at 0 0 0)
			(layer "F.Fab")
			(effects
				(font
					(size 1.27 1.27)
				)
			)
		)
		(duplicate_pad_numbers_are_jumpers no)
		(pad "1" thru_hole rect
			(at 0 0)
			(size 4.2164 5.0038)
			(drill 2.0066
				(offset 0.099822 0)
			)
			(layers "*.Cu" "*.Mask")
			(remove_unused_layers no)
			(net "GND")
			(clearance -0.8509)
			(padstack
				(mode front_inner_back)
				(layer "Inner"
					(shape circle)
					(size 4.0132 4.0132)
					(clearance -0.7493)
				)
				(layer "B.Cu"
					(shape circle)
					(size 4.0132 4.0132)
					(clearance -0.7493)
				)
			)
		)
	)
	(footprint ""
		(layer "F.Cu")
		(at 352.217736 -338.86013)
		(property "Reference" "PR150"
			(at 0 0 0)
			(layer "F.SilkS")
			(hide yes)
			(effects
				(font
					(size 1.27 1.27)
				)
			)
		)
		(property "Value" ""
			(at 0 0 0)
			(layer "F.Fab")
			(effects
				(font
					(size 1.27 1.27)
				)
			)
		)
		(duplicate_pad_numbers_are_jumpers no)
		(fp_line
			(start -0.7874 -0.4064)
			(end 0.7874 -0.4064)
			(stroke
				(width 0.1524)
				(type default)
			)
			(layer "F.SilkS")
		)
		(fp_line
			(start -0.7874 0.4064)
			(end -0.7874 -0.4064)
			(stroke
				(width 0.1524)
				(type default)
			)
			(layer "F.SilkS")
		)
		(fp_line
			(start 0.7874 -0.4064)
			(end 0.7874 0.4064)
			(stroke
				(width 0.1524)
				(type default)
			)
			(layer "F.SilkS")
		)
		(fp_line
			(start 0.7874 0.4064)
			(end -0.7874 0.4064)
			(stroke
				(width 0.1524)
				(type default)
			)
			(layer "F.SilkS")
		)
		(fp_line
			(start -0.67945 -0.305054)
			(end -0.12065 -0.305054)
			(stroke
				(width 0.1)
				(type default)
			)
			(layer "F.Fab")
		)
		(fp_line
			(start -0.67945 0.3048)
			(end -0.67945 -0.305054)
			(stroke
				(width 0.1)
				(type default)
			)
			(layer "F.Fab")
		)
		(fp_line
			(start -0.12065 -0.305054)
			(end -0.12065 -0.2794)
			(stroke
				(width 0.1)
				(type default)
			)
			(layer "F.Fab")
		)
		(fp_line
			(start -0.12065 -0.2794)
			(end 0.12065 -0.2794)
			(stroke
				(width 0.1)
				(type default)
			)
			(layer "F.Fab")
		)
		(fp_line
			(start -0.12065 0.2794)
			(end -0.12065 0.3048)
			(stroke
				(width 0.1)
				(type default)
			)
			(layer "F.Fab")
		)
		(fp_line
			(start -0.12065 0.3048)
			(end -0.67945 0.3048)
			(stroke
				(width 0.1)
				(type default)
			)
			(layer "F.Fab")
		)
		(fp_line
			(start 0.120396 0.2794)
			(end -0.12065 0.2794)
			(stroke
				(width 0.1)
				(type default)
			)
			(layer "F.Fab")
		)
		(fp_line
			(start 0.120396 0.3048)
			(end 0.120396 0.2794)
			(stroke
				(width 0.1)
				(type default)
			)
			(layer "F.Fab")
		)
		(fp_line
			(start 0.12065 -0.3048)
			(end 0.67945 -0.3048)
			(stroke
				(width 0.1)
				(type default)
			)
			(layer "F.Fab")
		)
		(fp_line
			(start 0.12065 -0.2794)
			(end 0.12065 -0.3048)
			(stroke
				(width 0.1)
				(type default)
			)
			(layer "F.Fab")
		)
		(fp_line
			(start 0.67945 -0.3048)
			(end 0.67945 0.3048)
			(stroke
				(width 0.1)
				(type default)
			)
			(layer "F.Fab")
		)
		(fp_line
			(start 0.67945 0.3048)
			(end 0.120396 0.3048)
			(stroke
				(width 0.1)
				(type default)
			)
			(layer "F.Fab")
		)
		(pad "1" smd circle
			(at -0.40005 0)
			(size 0 0)
			(layers "F.Cu" "F.Mask" "F.Paste")
			(net "PVCCIN_CPU0_LSET2")
		)
		(pad "2" smd circle
			(at 0.40005 0)
			(size 0 0)
			(layers "F.Cu" "F.Mask" "F.Paste")
			(net "GND")
		)
	)
	(footprint ""
		(layer "F.Cu")
		(at 61.543438 -31.887922 90)
		(property "Reference" "R3874"
			(at 0 0 90)
			(layer "F.SilkS")
			(hide yes)
			(effects
				(font
					(size 1.27 1.27)
				)
			)
		)
		(property "Value" ""
			(at 0 0 90)
			(layer "F.Fab")
			(effects
				(font
					(size 1.27 1.27)
				)
			)
		)
		(duplicate_pad_numbers_are_jumpers no)
		(fp_line
			(start 0.7874 -0.4064)
			(end 0.7874 0.4064)
			(stroke
				(width 0.1524)
				(type default)
			)
			(layer "F.SilkS")
		)
		(fp_line
			(start -0.7874 -0.4064)
			(end 0.7874 -0.4064)
			(stroke
				(width 0.1524)
				(type default)
			)
			(layer "F.SilkS")
		)
		(fp_line
			(start 0.7874 0.4064)
			(end -0.7874 0.4064)
			(stroke
				(width 0.1524)
				(type default)
			)
			(layer "F.SilkS")
		)
		(fp_line
			(start -0.7874 0.4064)
			(end -0.7874 -0.4064)
			(stroke
				(width 0.1524)
				(type default)
			)
			(layer "F.SilkS")
		)
		(fp_line
			(start -0.12065 -0.305054)
			(end -0.12065 -0.2794)
			(stroke
				(width 0.1)
				(type default)
			)
			(layer "F.Fab")
		)
		(fp_line
			(start -0.67945 -0.305054)
			(end -0.12065 -0.305054)
			(stroke
				(width 0.1)
				(type default)
			)
			(layer "F.Fab")
		)
		(fp_line
			(start 0.67945 -0.3048)
			(end 0.67945 0.3048)
			(stroke
				(width 0.1)
				(type default)
			)
			(layer "F.Fab")
		)
		(fp_line
			(start 0.12065 -0.3048)
			(end 0.67945 -0.3048)
			(stroke
				(width 0.1)
				(type default)
			)
			(layer "F.Fab")
		)
		(fp_line
			(start 0.12065 -0.2794)
			(end 0.12065 -0.3048)
			(stroke
				(width 0.1)
				(type default)
			)
			(layer "F.Fab")
		)
		(fp_line
			(start -0.12065 -0.2794)
			(end 0.12065 -0.2794)
			(stroke
				(width 0.1)
				(type default)
			)
			(layer "F.Fab")
		)
		(fp_line
			(start 0.120396 0.2794)
			(end -0.12065 0.2794)
			(stroke
				(width 0.1)
				(type default)
			)
			(layer "F.Fab")
		)
		(fp_line
			(start -0.12065 0.2794)
			(end -0.12065 0.3048)
			(stroke
				(width 0.1)
				(type default)
			)
			(layer "F.Fab")
		)
		(fp_line
			(start 0.67945 0.3048)
			(end 0.120396 0.3048)
			(stroke
				(width 0.1)
				(type default)
			)
			(layer "F.Fab")
		)
		(fp_line
			(start 0.120396 0.3048)
			(end 0.120396 0.2794)
			(stroke
				(width 0.1)
				(type default)
			)
			(layer "F.Fab")
		)
		(fp_line
			(start -0.12065 0.3048)
			(end -0.67945 0.3048)
			(stroke
				(width 0.1)
				(type default)
			)
			(layer "F.Fab")
		)
		(fp_line
			(start -0.67945 0.3048)
			(end -0.67945 -0.305054)
			(stroke
				(width 0.1)
				(type default)
			)
			(layer "F.Fab")
		)
		(pad "1" smd circle
			(at -0.40005 0 90)
			(size 0 0)
			(layers "F.Cu" "F.Mask" "F.Paste")
			(net "P12V_OCP_IMON_2")
		)
		(pad "2" smd circle
			(at 0.40005 0 90)
			(size 0 0)
			(layers "F.Cu" "F.Mask" "F.Paste")
			(net "P12V_OCP_V3_2_ISENSE_MPS_TIC")
		)
	)
	(footprint ""
		(layer "F.Cu")
		(at 201.00036 -116.804948 180)
		(property "Reference" "R4157"
			(at 0 0 180)
			(layer "F.SilkS")
			(hide yes)
			(effects
				(font
					(size 1.27 1.27)
				)
			)
		)
		(property "Value" ""
			(at 0 0 180)
			(layer "F.Fab")
			(effects
				(font
					(size 1.27 1.27)
				)
			)
		)
		(duplicate_pad_numbers_are_jumpers no)
		(fp_line
			(start 0.7874 0.4064)
			(end -0.7874 0.4064)
			(stroke
				(width 0.1524)
				(type default)
			)
			(layer "F.SilkS")
		)
		(fp_line
			(start 0.7874 -0.4064)
			(end 0.7874 0.4064)
			(stroke
				(width 0.1524)
				(type default)
			)
			(layer "F.SilkS")
		)
		(fp_line
			(start -0.7874 0.4064)
			(end -0.7874 -0.4064)
			(stroke
				(width 0.1524)
				(type default)
			)
			(layer "F.SilkS")
		)
		(fp_line
			(start -0.7874 -0.4064)
			(end 0.7874 -0.4064)
			(stroke
				(width 0.1524)
				(type default)
			)
			(layer "F.SilkS")
		)
		(fp_line
			(start 0.67945 0.3048)
			(end 0.120396 0.3048)
			(stroke
				(width 0.1)
				(type default)
			)
			(layer "F.Fab")
		)
		(fp_line
			(start 0.67945 -0.3048)
			(end 0.67945 0.3048)
			(stroke
				(width 0.1)
				(type default)
			)
			(layer "F.Fab")
		)
		(fp_line
			(start 0.12065 -0.2794)
			(end 0.12065 -0.3048)
			(stroke
				(width 0.1)
				(type default)
			)
			(layer "F.Fab")
		)
		(fp_line
			(start 0.12065 -0.3048)
			(end 0.67945 -0.3048)
			(stroke
				(width 0.1)
				(type default)
			)
			(layer "F.Fab")
		)
		(fp_line
			(start 0.120396 0.3048)
			(end 0.120396 0.2794)
			(stroke
				(width 0.1)
				(type default)
			)
			(layer "F.Fab")
		)
		(fp_line
			(start 0.120396 0.2794)
			(end -0.12065 0.2794)
			(stroke
				(width 0.1)
				(type default)
			)
			(layer "F.Fab")
		)
		(fp_line
			(start -0.12065 0.3048)
			(end -0.67945 0.3048)
			(stroke
				(width 0.1)
				(type default)
			)
			(layer "F.Fab")
		)
		(fp_line
			(start -0.12065 0.2794)
			(end -0.12065 0.3048)
			(stroke
				(width 0.1)
				(type default)
			)
			(layer "F.Fab")
		)
		(fp_line
			(start -0.12065 -0.2794)
			(end 0.12065 -0.2794)
			(stroke
				(width 0.1)
				(type default)
			)
			(layer "F.Fab")
		)
		(fp_line
			(start -0.12065 -0.305054)
			(end -0.12065 -0.2794)
			(stroke
				(width 0.1)
				(type default)
			)
			(layer "F.Fab")
		)
		(fp_line
			(start -0.67945 0.3048)
			(end -0.67945 -0.305054)
			(stroke
				(width 0.1)
				(type default)
			)
			(layer "F.Fab")
		)
		(fp_line
			(start -0.67945 -0.305054)
			(end -0.12065 -0.305054)
			(stroke
				(width 0.1)
				(type default)
			)
			(layer "F.Fab")
		)
		(pad "1" smd circle
			(at -0.40005 0 180)
			(size 0 0)
			(layers "F.Cu" "F.Mask" "F.Paste")
			(net "PRSNT_CABLE_GPU_A1_ISO_N")
		)
		(pad "2" smd circle
			(at 0.40005 0 180)
			(size 0 0)
			(layers "F.Cu" "F.Mask" "F.Paste")
			(net "PRSNT_CABLE_GPU_A1_ISO_R_N")
		)
	)
	(footprint ""
		(layer "F.Cu")
		(at 504.058428 -303.58588 90)
		(property "Reference" "X3"
			(at -2.637536 3.163062 90)
			(unlocked yes)
			(layer "F.SilkS")
			(effects
				(font
					(size 0.7874 0.5842)
					(thickness 0.1524)
				)
				(justify left)
			)
		)
		(property "Value" ""
			(at 0 0 90)
			(layer "F.Fab")
			(effects
				(font
					(size 1.27 1.27)
				)
			)
		)
		(property "Device Type" "TP_TDR_4P_FTS_MPKT4_H025P0200_I"
			(at 1.30175 1.27 180)
			(unlocked yes)
			(layer "F.Fab")
			(hide yes)
			(effects
				(font
					(size 0.635 0.4064)
					(thickness 0.1524)
				)
			)
		)
		(property "User Part Number" "TP15"
			(at 1.30175 1.27 180)
			(unlocked yes)
			(layer "Cmts.User")
			(hide yes)
			(effects
				(font
					(size 0.635 0.4064)
					(thickness 0.1524)
				)
			)
		)
		(duplicate_pad_numbers_are_jumpers no)
		(fp_line
			(start 2.54 -1.27)
			(end 0 -1.27)
			(stroke
				(width 0.1524)
				(type default)
			)
			(layer "F.SilkS")
		)
		(fp_line
			(start 0 -1.27)
			(end 0 -0.635)
			(stroke
				(width 0.1524)
				(type default)
			)
			(layer "F.SilkS")
		)
		(fp_line
			(start 2.54 -1.1303)
			(end 2.54 -1.27)
			(stroke
				(width 0.1524)
				(type default)
			)
			(layer "F.SilkS")
		)
		(fp_line
			(start 0 0.635)
			(end 0 1.905)
			(stroke
				(width 0.1524)
				(type default)
			)
			(layer "F.SilkS")
		)
		(fp_line
			(start 2.54 1.4097)
			(end 2.54 1.1303)
			(stroke
				(width 0.1524)
				(type default)
			)
			(layer "F.SilkS")
		)
		(fp_line
			(start 0 3.175)
			(end 0 3.81)
			(stroke
				(width 0.1524)
				(type default)
			)
			(layer "F.SilkS")
		)
		(fp_line
			(start 2.54 3.81)
			(end 2.54 3.6703)
			(stroke
				(width 0.1524)
				(type default)
			)
			(layer "F.SilkS")
		)
		(fp_line
			(start 0 3.81)
			(end 2.54 3.81)
			(stroke
				(width 0.1524)
				(type default)
			)
			(layer "F.SilkS")
		)
		(fp_poly
			(pts
				(xy -0.761746 0) (xy -2.285746 0.762) (xy -2.285746 -0.762)
			)
			(stroke
				(width 0)
				(type default)
			)
			(fill yes)
			(layer "F.SilkS")
		)
		(fp_line
			(start 2.54 -1.27)
			(end 0 -1.27)
			(stroke
				(width 0.1)
				(type default)
			)
			(layer "F.Fab")
		)
		(fp_line
			(start 0 -1.27)
			(end 0 3.81)
			(stroke
				(width 0.1)
				(type default)
			)
			(layer "F.Fab")
		)
		(fp_line
			(start 2.54 3.81)
			(end 2.54 -1.27)
			(stroke
				(width 0.1)
				(type default)
			)
			(layer "F.Fab")
		)
		(fp_line
			(start 0 3.81)
			(end 2.54 3.81)
			(stroke
				(width 0.1)
				(type default)
			)
			(layer "F.Fab")
		)
		(fp_poly
			(pts
				(xy -0.761746 0) (xy -2.285746 -0.762) (xy -2.285746 0.762)
			)
			(stroke
				(width 0)
				(type default)
			)
			(fill yes)
			(layer "F.Fab")
		)
		(pad "1" thru_hole circle
			(at 0 0 90)
			(size 1.0033 1.0033)
			(drill 0.249936)
			(layers "*.Cu" "*.Mask")
			(remove_unused_layers no)
			(net "TDR_DIFF_85_IN2_DP")
			(clearance 0.10795)
			(thermal_gap 0.10795)
			(padstack
				(mode front_inner_back)
				(layer "Inner"
					(shape circle)
					(size 0.8001 0.8001)
					(clearance 0.1524)
				)
				(layer "B.Cu"
					(shape circle)
					(size 1.0033 1.0033)
					(clearance 0.10795)
				)
			)
		)
		(pad "2" thru_hole circle
			(at 2.54 0 90)
			(size 1.9939 1.9939)
			(drill 0.249936)
			(layers "*.Cu" "*.Mask")
			(remove_unused_layers no)
			(net "T1_GND")
			(clearance 0.10795)
			(thermal_gap 0.10795)
			(padstack
				(mode front_inner_back)
				(layer "Inner"
					(shape circle)
					(size 0.8001 0.8001)
					(clearance 0.1524)
				)
				(layer "B.Cu"
					(shape circle)
					(size 1.9939 1.9939)
					(clearance 0.10795)
				)
			)
		)
		(pad "3" thru_hole circle
			(at 2.54 2.54 90)
			(size 1.9939 1.9939)
			(drill 0.249936)
			(layers "*.Cu" "*.Mask")
			(remove_unused_layers no)
			(net "T1_GND")
			(clearance 0.10795)
			(thermal_gap 0.10795)
			(padstack
				(mode front_inner_back)
				(layer "Inner"
					(shape circle)
					(size 0.8001 0.8001)
					(clearance 0.1524)
				)
				(layer "B.Cu"
					(shape circle)
					(size 1.9939 1.9939)
					(clearance 0.10795)
				)
			)
		)
		(pad "4" thru_hole circle
			(at 0 2.54 90)
			(size 1.0033 1.0033)
			(drill 0.249936)
			(layers "*.Cu" "*.Mask")
			(remove_unused_layers no)
			(net "TDR_DIFF_85_IN2_DN")
			(clearance 0.10795)
			(thermal_gap 0.10795)
			(padstack
				(mode front_inner_back)
				(layer "Inner"
					(shape circle)
					(size 0.8001 0.8001)
					(clearance 0.1524)
				)
				(layer "B.Cu"
					(shape circle)
					(size 1.0033 1.0033)
					(clearance 0.10795)
				)
			)
		)
	)
	(footprint ""
		(layer "F.Cu")
		(at 444.598552 -25.477978)
		(property "Reference" "PC2160"
			(at 0 0 0)
			(layer "F.SilkS")
			(hide yes)
			(effects
				(font
					(size 1.27 1.27)
				)
			)
		)
		(property "Value" ""
			(at 0 0 0)
			(layer "F.Fab")
			(effects
				(font
					(size 1.27 1.27)
				)
			)
		)
		(duplicate_pad_numbers_are_jumpers no)
		(fp_line
			(start -0.7874 -0.4064)
			(end 0.7874 -0.4064)
			(stroke
				(width 0.1524)
				(type default)
			)
			(layer "F.SilkS")
		)
		(fp_line
			(start -0.7874 0.4064)
			(end -0.7874 -0.4064)
			(stroke
				(width 0.1524)
				(type default)
			)
			(layer "F.SilkS")
		)
		(fp_line
			(start 0.7874 -0.4064)
			(end 0.7874 0.4064)
			(stroke
				(width 0.1524)
				(type default)
			)
			(layer "F.SilkS")
		)
		(fp_line
			(start 0.7874 0.4064)
			(end -0.7874 0.4064)
			(stroke
				(width 0.1524)
				(type default)
			)
			(layer "F.SilkS")
		)
		(fp_line
			(start -0.67945 -0.305054)
			(end -0.12065 -0.305054)
			(stroke
				(width 0.1)
				(type default)
			)
			(layer "F.Fab")
		)
		(fp_line
			(start -0.67945 0.3048)
			(end -0.67945 -0.305054)
			(stroke
				(width 0.1)
				(type default)
			)
			(layer "F.Fab")
		)
		(fp_line
			(start -0.12065 -0.305054)
			(end -0.12065 -0.2794)
			(stroke
				(width 0.1)
				(type default)
			)
			(layer "F.Fab")
		)
		(fp_line
			(start -0.12065 -0.2794)
			(end 0.12065 -0.2794)
			(stroke
				(width 0.1)
				(type default)
			)
			(layer "F.Fab")
		)
		(fp_line
			(start -0.12065 0.2794)
			(end -0.12065 0.3048)
			(stroke
				(width 0.1)
				(type default)
			)
			(layer "F.Fab")
		)
		(fp_line
			(start -0.12065 0.3048)
			(end -0.67945 0.3048)
			(stroke
				(width 0.1)
				(type default)
			)
			(layer "F.Fab")
		)
		(fp_line
			(start 0.120396 0.2794)
			(end -0.12065 0.2794)
			(stroke
				(width 0.1)
				(type default)
			)
			(layer "F.Fab")
		)
		(fp_line
			(start 0.120396 0.3048)
			(end 0.120396 0.2794)
			(stroke
				(width 0.1)
				(type default)
			)
			(layer "F.Fab")
		)
		(fp_line
			(start 0.12065 -0.3048)
			(end 0.67945 -0.3048)
			(stroke
				(width 0.1)
				(type default)
			)
			(layer "F.Fab")
		)
		(fp_line
			(start 0.12065 -0.2794)
			(end 0.12065 -0.3048)
			(stroke
				(width 0.1)
				(type default)
			)
			(layer "F.Fab")
		)
		(fp_line
			(start 0.67945 -0.3048)
			(end 0.67945 0.3048)
			(stroke
				(width 0.1)
				(type default)
			)
			(layer "F.Fab")
		)
		(fp_line
			(start 0.67945 0.3048)
			(end 0.120396 0.3048)
			(stroke
				(width 0.1)
				(type default)
			)
			(layer "F.Fab")
		)
		(pad "1" smd circle
			(at -0.40005 0)
			(size 0 0)
			(layers "F.Cu" "F.Mask" "F.Paste")
			(net "P12V_OCP_SFF")
		)
		(pad "2" smd circle
			(at 0.40005 0)
			(size 0 0)
			(layers "F.Cu" "F.Mask" "F.Paste")
			(net "GND")
		)
	)
	(footprint ""
		(layer "F.Cu")
		(at 47.954438 -402.371052 -90)
		(property "Reference" "C710"
			(at 0 0 270)
			(layer "F.SilkS")
			(hide yes)
			(effects
				(font
					(size 1.27 1.27)
				)
			)
		)
		(property "Value" ""
			(at 0 0 270)
			(layer "F.Fab")
			(effects
				(font
					(size 1.27 1.27)
				)
			)
		)
		(duplicate_pad_numbers_are_jumpers no)
		(fp_line
			(start -0.299974 0.150114)
			(end -0.299974 -0.150114)
			(stroke
				(width 0.1)
				(type default)
			)
			(layer "F.Fab")
		)
		(fp_line
			(start 0.299974 0.150114)
			(end -0.299974 0.150114)
			(stroke
				(width 0.1)
				(type default)
			)
			(layer "F.Fab")
		)
		(fp_line
			(start -0.299974 -0.150114)
			(end 0.299974 -0.150114)
			(stroke
				(width 0.1)
				(type default)
			)
			(layer "F.Fab")
		)
		(fp_line
			(start 0.299974 -0.150114)
			(end 0.299974 0.150114)
			(stroke
				(width 0.1)
				(type default)
			)
			(layer "F.Fab")
		)
		(pad "1" smd rect
			(at -0.2667 0 270)
			(size 0.3048 0.381)
			(layers "F.Cu" "F.Mask" "F.Paste")
			(net "P5E_CPU1_PE0_TX_C_DN<15>")
		)
		(pad "2" smd rect
			(at 0.2667 0 270)
			(size 0.3048 0.381)
			(layers "F.Cu" "F.Mask" "F.Paste")
			(net "P5E_CPU1_PE0_TX_DN<15>")
		)
	)
	(footprint ""
		(layer "F.Cu")
		(at 365.46663 -251.375418 90)
		(property "Reference" "C1036"
			(at 0 0 90)
			(layer "F.SilkS")
			(hide yes)
			(effects
				(font
					(size 1.27 1.27)
				)
			)
		)
		(property "Value" ""
			(at 0 0 90)
			(layer "F.Fab")
			(effects
				(font
					(size 1.27 1.27)
				)
			)
		)
		(duplicate_pad_numbers_are_jumpers no)
		(fp_line
			(start 0.7874 -0.4064)
			(end 0.7874 0.4064)
			(stroke
				(width 0.1524)
				(type default)
			)
			(layer "F.SilkS")
		)
		(fp_line
			(start -0.7874 -0.4064)
			(end 0.7874 -0.4064)
			(stroke
				(width 0.1524)
				(type default)
			)
			(layer "F.SilkS")
		)
		(fp_line
			(start 0.7874 0.4064)
			(end -0.7874 0.4064)
			(stroke
				(width 0.1524)
				(type default)
			)
			(layer "F.SilkS")
		)
		(fp_line
			(start -0.7874 0.4064)
			(end -0.7874 -0.4064)
			(stroke
				(width 0.1524)
				(type default)
			)
			(layer "F.SilkS")
		)
		(fp_line
			(start -0.12065 -0.305054)
			(end -0.12065 -0.2794)
			(stroke
				(width 0.1)
				(type default)
			)
			(layer "F.Fab")
		)
		(fp_line
			(start -0.67945 -0.305054)
			(end -0.12065 -0.305054)
			(stroke
				(width 0.1)
				(type default)
			)
			(layer "F.Fab")
		)
		(fp_line
			(start 0.67945 -0.3048)
			(end 0.67945 0.3048)
			(stroke
				(width 0.1)
				(type default)
			)
			(layer "F.Fab")
		)
		(fp_line
			(start 0.12065 -0.3048)
			(end 0.67945 -0.3048)
			(stroke
				(width 0.1)
				(type default)
			)
			(layer "F.Fab")
		)
		(fp_line
			(start 0.12065 -0.2794)
			(end 0.12065 -0.3048)
			(stroke
				(width 0.1)
				(type default)
			)
			(layer "F.Fab")
		)
		(fp_line
			(start -0.12065 -0.2794)
			(end 0.12065 -0.2794)
			(stroke
				(width 0.1)
				(type default)
			)
			(layer "F.Fab")
		)
		(fp_line
			(start 0.120396 0.2794)
			(end -0.12065 0.2794)
			(stroke
				(width 0.1)
				(type default)
			)
			(layer "F.Fab")
		)
		(fp_line
			(start -0.12065 0.2794)
			(end -0.12065 0.3048)
			(stroke
				(width 0.1)
				(type default)
			)
			(layer "F.Fab")
		)
		(fp_line
			(start 0.67945 0.3048)
			(end 0.120396 0.3048)
			(stroke
				(width 0.1)
				(type default)
			)
			(layer "F.Fab")
		)
		(fp_line
			(start 0.120396 0.3048)
			(end 0.120396 0.2794)
			(stroke
				(width 0.1)
				(type default)
			)
			(layer "F.Fab")
		)
		(fp_line
			(start -0.12065 0.3048)
			(end -0.67945 0.3048)
			(stroke
				(width 0.1)
				(type default)
			)
			(layer "F.Fab")
		)
		(fp_line
			(start -0.67945 0.3048)
			(end -0.67945 -0.305054)
			(stroke
				(width 0.1)
				(type default)
			)
			(layer "F.Fab")
		)
		(pad "1" smd circle
			(at -0.40005 0 90)
			(size 0 0)
			(layers "F.Cu" "F.Mask" "F.Paste")
			(net "PVCCIN_CPU0")
		)
		(pad "2" smd circle
			(at 0.40005 0 90)
			(size 0 0)
			(layers "F.Cu" "F.Mask" "F.Paste")
			(net "GND")
		)
	)
	(footprint ""
		(layer "F.Cu")
		(at 61.553598 -408.517344 -90)
		(property "Reference" "C700"
			(at 0 0 270)
			(layer "F.SilkS")
			(hide yes)
			(effects
				(font
					(size 1.27 1.27)
				)
			)
		)
		(property "Value" ""
			(at 0 0 270)
			(layer "F.Fab")
			(effects
				(font
					(size 1.27 1.27)
				)
			)
		)
		(duplicate_pad_numbers_are_jumpers no)
		(fp_line
			(start -0.299974 0.150114)
			(end -0.299974 -0.150114)
			(stroke
				(width 0.1)
				(type default)
			)
			(layer "F.Fab")
		)
		(fp_line
			(start 0.299974 0.150114)
			(end -0.299974 0.150114)
			(stroke
				(width 0.1)
				(type default)
			)
			(layer "F.Fab")
		)
		(fp_line
			(start -0.299974 -0.150114)
			(end 0.299974 -0.150114)
			(stroke
				(width 0.1)
				(type default)
			)
			(layer "F.Fab")
		)
		(fp_line
			(start 0.299974 -0.150114)
			(end 0.299974 0.150114)
			(stroke
				(width 0.1)
				(type default)
			)
			(layer "F.Fab")
		)
		(pad "1" smd rect
			(at -0.2667 0 270)
			(size 0.3048 0.381)
			(layers "F.Cu" "F.Mask" "F.Paste")
			(net "P5E_CPU1_PE4_TX_C_DN<4>")
		)
		(pad "2" smd rect
			(at 0.2667 0 270)
			(size 0.3048 0.381)
			(layers "F.Cu" "F.Mask" "F.Paste")
			(net "P5E_CPU1_PE4_TX_DN<4>")
		)
	)
	(footprint ""
		(layer "F.Cu")
		(at 197.41388 -101.145848)
		(property "Reference" "R210"
			(at 0 0 0)
			(layer "F.SilkS")
			(hide yes)
			(effects
				(font
					(size 1.27 1.27)
				)
			)
		)
		(property "Value" ""
			(at 0 0 0)
			(layer "F.Fab")
			(effects
				(font
					(size 1.27 1.27)
				)
			)
		)
		(duplicate_pad_numbers_are_jumpers no)
		(fp_line
			(start -0.7874 -0.4064)
			(end 0.7874 -0.4064)
			(stroke
				(width 0.1524)
				(type default)
			)
			(layer "F.SilkS")
		)
		(fp_line
			(start -0.7874 0.4064)
			(end -0.7874 -0.4064)
			(stroke
				(width 0.1524)
				(type default)
			)
			(layer "F.SilkS")
		)
		(fp_line
			(start 0.7874 -0.4064)
			(end 0.7874 0.4064)
			(stroke
				(width 0.1524)
				(type default)
			)
			(layer "F.SilkS")
		)
		(fp_line
			(start 0.7874 0.4064)
			(end -0.7874 0.4064)
			(stroke
				(width 0.1524)
				(type default)
			)
			(layer "F.SilkS")
		)
		(fp_line
			(start -0.67945 -0.305054)
			(end -0.12065 -0.305054)
			(stroke
				(width 0.1)
				(type default)
			)
			(layer "F.Fab")
		)
		(fp_line
			(start -0.67945 0.3048)
			(end -0.67945 -0.305054)
			(stroke
				(width 0.1)
				(type default)
			)
			(layer "F.Fab")
		)
		(fp_line
			(start -0.12065 -0.305054)
			(end -0.12065 -0.2794)
			(stroke
				(width 0.1)
				(type default)
			)
			(layer "F.Fab")
		)
		(fp_line
			(start -0.12065 -0.2794)
			(end 0.12065 -0.2794)
			(stroke
				(width 0.1)
				(type default)
			)
			(layer "F.Fab")
		)
		(fp_line
			(start -0.12065 0.2794)
			(end -0.12065 0.3048)
			(stroke
				(width 0.1)
				(type default)
			)
			(layer "F.Fab")
		)
		(fp_line
			(start -0.12065 0.3048)
			(end -0.67945 0.3048)
			(stroke
				(width 0.1)
				(type default)
			)
			(layer "F.Fab")
		)
		(fp_line
			(start 0.120396 0.2794)
			(end -0.12065 0.2794)
			(stroke
				(width 0.1)
				(type default)
			)
			(layer "F.Fab")
		)
		(fp_line
			(start 0.120396 0.3048)
			(end 0.120396 0.2794)
			(stroke
				(width 0.1)
				(type default)
			)
			(layer "F.Fab")
		)
		(fp_line
			(start 0.12065 -0.3048)
			(end 0.67945 -0.3048)
			(stroke
				(width 0.1)
				(type default)
			)
			(layer "F.Fab")
		)
		(fp_line
			(start 0.12065 -0.2794)
			(end 0.12065 -0.3048)
			(stroke
				(width 0.1)
				(type default)
			)
			(layer "F.Fab")
		)
		(fp_line
			(start 0.67945 -0.3048)
			(end 0.67945 0.3048)
			(stroke
				(width 0.1)
				(type default)
			)
			(layer "F.Fab")
		)
		(fp_line
			(start 0.67945 0.3048)
			(end 0.120396 0.3048)
			(stroke
				(width 0.1)
				(type default)
			)
			(layer "F.Fab")
		)
		(pad "1" smd circle
			(at -0.40005 0)
			(size 0 0)
			(layers "F.Cu" "F.Mask" "F.Paste")
			(net "H_CPU1_MEMHOT_IN_LVC1_R_N")
		)
		(pad "2" smd circle
			(at 0.40005 0)
			(size 0 0)
			(layers "F.Cu" "F.Mask" "F.Paste")
			(net "H_CPU1_MEMHOT_IN_LVC1_R1_N")
		)
	)
	(footprint ""
		(layer "F.Cu")
		(at 165.31463 -133.77672 -90)
		(property "Reference" "R1642"
			(at 0 0 270)
			(layer "F.SilkS")
			(hide yes)
			(effects
				(font
					(size 1.27 1.27)
				)
			)
		)
		(property "Value" ""
			(at 0 0 270)
			(layer "F.Fab")
			(effects
				(font
					(size 1.27 1.27)
				)
			)
		)
		(duplicate_pad_numbers_are_jumpers no)
		(fp_line
			(start -0.7874 0.4064)
			(end -0.7874 -0.4064)
			(stroke
				(width 0.1524)
				(type default)
			)
			(layer "F.SilkS")
		)
		(fp_line
			(start 0.7874 0.4064)
			(end -0.7874 0.4064)
			(stroke
				(width 0.1524)
				(type default)
			)
			(layer "F.SilkS")
		)
		(fp_line
			(start -0.7874 -0.4064)
			(end 0.7874 -0.4064)
			(stroke
				(width 0.1524)
				(type default)
			)
			(layer "F.SilkS")
		)
		(fp_line
			(start 0.7874 -0.4064)
			(end 0.7874 0.4064)
			(stroke
				(width 0.1524)
				(type default)
			)
			(layer "F.SilkS")
		)
		(fp_line
			(start -0.67945 0.3048)
			(end -0.67945 -0.305054)
			(stroke
				(width 0.1)
				(type default)
			)
			(layer "F.Fab")
		)
		(fp_line
			(start -0.12065 0.3048)
			(end -0.67945 0.3048)
			(stroke
				(width 0.1)
				(type default)
			)
			(layer "F.Fab")
		)
		(fp_line
			(start 0.120396 0.3048)
			(end 0.120396 0.2794)
			(stroke
				(width 0.1)
				(type default)
			)
			(layer "F.Fab")
		)
		(fp_line
			(start 0.67945 0.3048)
			(end 0.120396 0.3048)
			(stroke
				(width 0.1)
				(type default)
			)
			(layer "F.Fab")
		)
		(fp_line
			(start -0.12065 0.2794)
			(end -0.12065 0.3048)
			(stroke
				(width 0.1)
				(type default)
			)
			(layer "F.Fab")
		)
		(fp_line
			(start 0.120396 0.2794)
			(end -0.12065 0.2794)
			(stroke
				(width 0.1)
				(type default)
			)
			(layer "F.Fab")
		)
		(fp_line
			(start -0.12065 -0.2794)
			(end 0.12065 -0.2794)
			(stroke
				(width 0.1)
				(type default)
			)
			(layer "F.Fab")
		)
		(fp_line
			(start 0.12065 -0.2794)
			(end 0.12065 -0.3048)
			(stroke
				(width 0.1)
				(type default)
			)
			(layer "F.Fab")
		)
		(fp_line
			(start 0.12065 -0.3048)
			(end 0.67945 -0.3048)
			(stroke
				(width 0.1)
				(type default)
			)
			(layer "F.Fab")
		)
		(fp_line
			(start 0.67945 -0.3048)
			(end 0.67945 0.3048)
			(stroke
				(width 0.1)
				(type default)
			)
			(layer "F.Fab")
		)
		(fp_line
			(start -0.67945 -0.305054)
			(end -0.12065 -0.305054)
			(stroke
				(width 0.1)
				(type default)
			)
			(layer "F.Fab")
		)
		(fp_line
			(start -0.12065 -0.305054)
			(end -0.12065 -0.2794)
			(stroke
				(width 0.1)
				(type default)
			)
			(layer "F.Fab")
		)
		(pad "1" smd circle
			(at -0.40005 0 270)
			(size 0 0)
			(layers "F.Cu" "F.Mask" "F.Paste")
			(net "P12V_AUX")
		)
		(pad "2" smd circle
			(at 0.40005 0 270)
			(size 0 0)
			(layers "F.Cu" "F.Mask" "F.Paste")
			(net "VR_P5V_EN_D_R")
		)
	)
	(footprint ""
		(layer "F.Cu")
		(at 22.809454 -107.777026 180)
		(property "Reference" "R3670"
			(at 0 0 180)
			(layer "F.SilkS")
			(hide yes)
			(effects
				(font
					(size 1.27 1.27)
				)
			)
		)
		(property "Value" ""
			(at 0 0 180)
			(layer "F.Fab")
			(effects
				(font
					(size 1.27 1.27)
				)
			)
		)
		(duplicate_pad_numbers_are_jumpers no)
		(fp_line
			(start 0.7874 0.4064)
			(end -0.7874 0.4064)
			(stroke
				(width 0.1524)
				(type default)
			)
			(layer "F.SilkS")
		)
		(fp_line
			(start 0.7874 -0.4064)
			(end 0.7874 0.4064)
			(stroke
				(width 0.1524)
				(type default)
			)
			(layer "F.SilkS")
		)
		(fp_line
			(start -0.7874 0.4064)
			(end -0.7874 -0.4064)
			(stroke
				(width 0.1524)
				(type default)
			)
			(layer "F.SilkS")
		)
		(fp_line
			(start -0.7874 -0.4064)
			(end 0.7874 -0.4064)
			(stroke
				(width 0.1524)
				(type default)
			)
			(layer "F.SilkS")
		)
		(fp_line
			(start 0.67945 0.3048)
			(end 0.120396 0.3048)
			(stroke
				(width 0.1)
				(type default)
			)
			(layer "F.Fab")
		)
		(fp_line
			(start 0.67945 -0.3048)
			(end 0.67945 0.3048)
			(stroke
				(width 0.1)
				(type default)
			)
			(layer "F.Fab")
		)
		(fp_line
			(start 0.12065 -0.2794)
			(end 0.12065 -0.3048)
			(stroke
				(width 0.1)
				(type default)
			)
			(layer "F.Fab")
		)
		(fp_line
			(start 0.12065 -0.3048)
			(end 0.67945 -0.3048)
			(stroke
				(width 0.1)
				(type default)
			)
			(layer "F.Fab")
		)
		(fp_line
			(start 0.120396 0.3048)
			(end 0.120396 0.2794)
			(stroke
				(width 0.1)
				(type default)
			)
			(layer "F.Fab")
		)
		(fp_line
			(start 0.120396 0.2794)
			(end -0.12065 0.2794)
			(stroke
				(width 0.1)
				(type default)
			)
			(layer "F.Fab")
		)
		(fp_line
			(start -0.12065 0.3048)
			(end -0.67945 0.3048)
			(stroke
				(width 0.1)
				(type default)
			)
			(layer "F.Fab")
		)
		(fp_line
			(start -0.12065 0.2794)
			(end -0.12065 0.3048)
			(stroke
				(width 0.1)
				(type default)
			)
			(layer "F.Fab")
		)
		(fp_line
			(start -0.12065 -0.2794)
			(end 0.12065 -0.2794)
			(stroke
				(width 0.1)
				(type default)
			)
			(layer "F.Fab")
		)
		(fp_line
			(start -0.12065 -0.305054)
			(end -0.12065 -0.2794)
			(stroke
				(width 0.1)
				(type default)
			)
			(layer "F.Fab")
		)
		(fp_line
			(start -0.67945 0.3048)
			(end -0.67945 -0.305054)
			(stroke
				(width 0.1)
				(type default)
			)
			(layer "F.Fab")
		)
		(fp_line
			(start -0.67945 -0.305054)
			(end -0.12065 -0.305054)
			(stroke
				(width 0.1)
				(type default)
			)
			(layer "F.Fab")
		)
		(pad "1" smd circle
			(at -0.40005 0 180)
			(size 0 0)
			(layers "F.Cu" "F.Mask" "F.Paste")
			(net "ADC128_A0")
		)
		(pad "2" smd circle
			(at 0.40005 0 180)
			(size 0 0)
			(layers "F.Cu" "F.Mask" "F.Paste")
			(net "GND")
		)
	)
	(footprint ""
		(layer "F.Cu")
		(at 258.18338 -92.258388 180)
		(property "Reference" "R3640"
			(at 0 0 180)
			(layer "F.SilkS")
			(hide yes)
			(effects
				(font
					(size 1.27 1.27)
				)
			)
		)
		(property "Value" ""
			(at 0 0 180)
			(layer "F.Fab")
			(effects
				(font
					(size 1.27 1.27)
				)
			)
		)
		(duplicate_pad_numbers_are_jumpers no)
		(fp_line
			(start 0.7874 0.4064)
			(end -0.7874 0.4064)
			(stroke
				(width 0.1524)
				(type default)
			)
			(layer "F.SilkS")
		)
		(fp_line
			(start 0.7874 -0.4064)
			(end 0.7874 0.4064)
			(stroke
				(width 0.1524)
				(type default)
			)
			(layer "F.SilkS")
		)
		(fp_line
			(start -0.7874 0.4064)
			(end -0.7874 -0.4064)
			(stroke
				(width 0.1524)
				(type default)
			)
			(layer "F.SilkS")
		)
		(fp_line
			(start -0.7874 -0.4064)
			(end 0.7874 -0.4064)
			(stroke
				(width 0.1524)
				(type default)
			)
			(layer "F.SilkS")
		)
		(fp_line
			(start 0.67945 0.3048)
			(end 0.120396 0.3048)
			(stroke
				(width 0.1)
				(type default)
			)
			(layer "F.Fab")
		)
		(fp_line
			(start 0.67945 -0.3048)
			(end 0.67945 0.3048)
			(stroke
				(width 0.1)
				(type default)
			)
			(layer "F.Fab")
		)
		(fp_line
			(start 0.12065 -0.2794)
			(end 0.12065 -0.3048)
			(stroke
				(width 0.1)
				(type default)
			)
			(layer "F.Fab")
		)
		(fp_line
			(start 0.12065 -0.3048)
			(end 0.67945 -0.3048)
			(stroke
				(width 0.1)
				(type default)
			)
			(layer "F.Fab")
		)
		(fp_line
			(start 0.120396 0.3048)
			(end 0.120396 0.2794)
			(stroke
				(width 0.1)
				(type default)
			)
			(layer "F.Fab")
		)
		(fp_line
			(start 0.120396 0.2794)
			(end -0.12065 0.2794)
			(stroke
				(width 0.1)
				(type default)
			)
			(layer "F.Fab")
		)
		(fp_line
			(start -0.12065 0.3048)
			(end -0.67945 0.3048)
			(stroke
				(width 0.1)
				(type default)
			)
			(layer "F.Fab")
		)
		(fp_line
			(start -0.12065 0.2794)
			(end -0.12065 0.3048)
			(stroke
				(width 0.1)
				(type default)
			)
			(layer "F.Fab")
		)
		(fp_line
			(start -0.12065 -0.2794)
			(end 0.12065 -0.2794)
			(stroke
				(width 0.1)
				(type default)
			)
			(layer "F.Fab")
		)
		(fp_line
			(start -0.12065 -0.305054)
			(end -0.12065 -0.2794)
			(stroke
				(width 0.1)
				(type default)
			)
			(layer "F.Fab")
		)
		(fp_line
			(start -0.67945 0.3048)
			(end -0.67945 -0.305054)
			(stroke
				(width 0.1)
				(type default)
			)
			(layer "F.Fab")
		)
		(fp_line
			(start -0.67945 -0.305054)
			(end -0.12065 -0.305054)
			(stroke
				(width 0.1)
				(type default)
			)
			(layer "F.Fab")
		)
		(pad "1" smd circle
			(at -0.40005 0 180)
			(size 0 0)
			(layers "F.Cu" "F.Mask" "F.Paste")
			(net "P3V3_AUX")
		)
		(pad "2" smd circle
			(at 0.40005 0 180)
			(size 0 0)
			(layers "F.Cu" "F.Mask" "F.Paste")
			(net "CK440Q_OE_3")
		)
	)
	(footprint ""
		(layer "F.Cu")
		(at 46.085506 -395.699996)
		(property "Reference" "R4651"
			(at 0 0 0)
			(layer "F.SilkS")
			(hide yes)
			(effects
				(font
					(size 1.27 1.27)
				)
			)
		)
		(property "Value" ""
			(at 0 0 0)
			(layer "F.Fab")
			(effects
				(font
					(size 1.27 1.27)
				)
			)
		)
		(duplicate_pad_numbers_are_jumpers no)
		(fp_line
			(start -0.7874 -0.4064)
			(end 0.7874 -0.4064)
			(stroke
				(width 0.1524)
				(type default)
			)
			(layer "F.SilkS")
		)
		(fp_line
			(start -0.7874 0.4064)
			(end -0.7874 -0.4064)
			(stroke
				(width 0.1524)
				(type default)
			)
			(layer "F.SilkS")
		)
		(fp_line
			(start 0.7874 -0.4064)
			(end 0.7874 0.4064)
			(stroke
				(width 0.1524)
				(type default)
			)
			(layer "F.SilkS")
		)
		(fp_line
			(start 0.7874 0.4064)
			(end -0.7874 0.4064)
			(stroke
				(width 0.1524)
				(type default)
			)
			(layer "F.SilkS")
		)
		(fp_line
			(start -0.67945 -0.305054)
			(end -0.12065 -0.305054)
			(stroke
				(width 0.1)
				(type default)
			)
			(layer "F.Fab")
		)
		(fp_line
			(start -0.67945 0.3048)
			(end -0.67945 -0.305054)
			(stroke
				(width 0.1)
				(type default)
			)
			(layer "F.Fab")
		)
		(fp_line
			(start -0.12065 -0.305054)
			(end -0.12065 -0.2794)
			(stroke
				(width 0.1)
				(type default)
			)
			(layer "F.Fab")
		)
		(fp_line
			(start -0.12065 -0.2794)
			(end 0.12065 -0.2794)
			(stroke
				(width 0.1)
				(type default)
			)
			(layer "F.Fab")
		)
		(fp_line
			(start -0.12065 0.2794)
			(end -0.12065 0.3048)
			(stroke
				(width 0.1)
				(type default)
			)
			(layer "F.Fab")
		)
		(fp_line
			(start -0.12065 0.3048)
			(end -0.67945 0.3048)
			(stroke
				(width 0.1)
				(type default)
			)
			(layer "F.Fab")
		)
		(fp_line
			(start 0.120396 0.2794)
			(end -0.12065 0.2794)
			(stroke
				(width 0.1)
				(type default)
			)
			(layer "F.Fab")
		)
		(fp_line
			(start 0.120396 0.3048)
			(end 0.120396 0.2794)
			(stroke
				(width 0.1)
				(type default)
			)
			(layer "F.Fab")
		)
		(fp_line
			(start 0.12065 -0.3048)
			(end 0.67945 -0.3048)
			(stroke
				(width 0.1)
				(type default)
			)
			(layer "F.Fab")
		)
		(fp_line
			(start 0.12065 -0.2794)
			(end 0.12065 -0.3048)
			(stroke
				(width 0.1)
				(type default)
			)
			(layer "F.Fab")
		)
		(fp_line
			(start 0.67945 -0.3048)
			(end 0.67945 0.3048)
			(stroke
				(width 0.1)
				(type default)
			)
			(layer "F.Fab")
		)
		(fp_line
			(start 0.67945 0.3048)
			(end 0.120396 0.3048)
			(stroke
				(width 0.1)
				(type default)
			)
			(layer "F.Fab")
		)
		(pad "1" smd circle
			(at -0.40005 0)
			(size 0 0)
			(layers "F.Cu" "F.Mask" "F.Paste")
			(net "FM_P2E_EN2_N")
		)
		(pad "2" smd circle
			(at 0.40005 0)
			(size 0 0)
			(layers "F.Cu" "F.Mask" "F.Paste")
			(net "CLK_GEN2_GPU_FPGA_OE_OR_N")
		)
	)
	(footprint ""
		(layer "F.Cu")
		(at 308.96687 -428.9298)
		(property "Reference" "R4572"
			(at 0 0 0)
			(layer "F.SilkS")
			(hide yes)
			(effects
				(font
					(size 1.27 1.27)
				)
			)
		)
		(property "Value" ""
			(at 0 0 0)
			(layer "F.Fab")
			(effects
				(font
					(size 1.27 1.27)
				)
			)
		)
		(duplicate_pad_numbers_are_jumpers no)
		(fp_line
			(start -0.7874 -0.4064)
			(end 0.7874 -0.4064)
			(stroke
				(width 0.1524)
				(type default)
			)
			(layer "F.SilkS")
		)
		(fp_line
			(start -0.7874 0.4064)
			(end -0.7874 -0.4064)
			(stroke
				(width 0.1524)
				(type default)
			)
			(layer "F.SilkS")
		)
		(fp_line
			(start 0.7874 -0.4064)
			(end 0.7874 0.4064)
			(stroke
				(width 0.1524)
				(type default)
			)
			(layer "F.SilkS")
		)
		(fp_line
			(start 0.7874 0.4064)
			(end -0.7874 0.4064)
			(stroke
				(width 0.1524)
				(type default)
			)
			(layer "F.SilkS")
		)
		(fp_line
			(start -0.67945 -0.305054)
			(end -0.12065 -0.305054)
			(stroke
				(width 0.1)
				(type default)
			)
			(layer "F.Fab")
		)
		(fp_line
			(start -0.67945 0.3048)
			(end -0.67945 -0.305054)
			(stroke
				(width 0.1)
				(type default)
			)
			(layer "F.Fab")
		)
		(fp_line
			(start -0.12065 -0.305054)
			(end -0.12065 -0.2794)
			(stroke
				(width 0.1)
				(type default)
			)
			(layer "F.Fab")
		)
		(fp_line
			(start -0.12065 -0.2794)
			(end 0.12065 -0.2794)
			(stroke
				(width 0.1)
				(type default)
			)
			(layer "F.Fab")
		)
		(fp_line
			(start -0.12065 0.2794)
			(end -0.12065 0.3048)
			(stroke
				(width 0.1)
				(type default)
			)
			(layer "F.Fab")
		)
		(fp_line
			(start -0.12065 0.3048)
			(end -0.67945 0.3048)
			(stroke
				(width 0.1)
				(type default)
			)
			(layer "F.Fab")
		)
		(fp_line
			(start 0.120396 0.2794)
			(end -0.12065 0.2794)
			(stroke
				(width 0.1)
				(type default)
			)
			(layer "F.Fab")
		)
		(fp_line
			(start 0.120396 0.3048)
			(end 0.120396 0.2794)
			(stroke
				(width 0.1)
				(type default)
			)
			(layer "F.Fab")
		)
		(fp_line
			(start 0.12065 -0.3048)
			(end 0.67945 -0.3048)
			(stroke
				(width 0.1)
				(type default)
			)
			(layer "F.Fab")
		)
		(fp_line
			(start 0.12065 -0.2794)
			(end 0.12065 -0.3048)
			(stroke
				(width 0.1)
				(type default)
			)
			(layer "F.Fab")
		)
		(fp_line
			(start 0.67945 -0.3048)
			(end 0.67945 0.3048)
			(stroke
				(width 0.1)
				(type default)
			)
			(layer "F.Fab")
		)
		(fp_line
			(start 0.67945 0.3048)
			(end 0.120396 0.3048)
			(stroke
				(width 0.1)
				(type default)
			)
			(layer "F.Fab")
		)
		(pad "1" smd circle
			(at -0.40005 0)
			(size 0 0)
			(layers "F.Cu" "F.Mask" "F.Paste")
			(net "GPU_3V3IO_RSVD1_FFU")
		)
		(pad "2" smd circle
			(at 0.40005 0)
			(size 0 0)
			(layers "F.Cu" "F.Mask" "F.Paste")
			(net "GPU_3V3IO_RSVD1_FFU_ISO")
		)
	)
	(footprint ""
		(layer "F.Cu")
		(at 114.557556 -355.340666 -90)
		(property "Reference" "PR242"
			(at 0 0 270)
			(layer "F.SilkS")
			(hide yes)
			(effects
				(font
					(size 1.27 1.27)
				)
			)
		)
		(property "Value" ""
			(at 0 0 270)
			(layer "F.Fab")
			(effects
				(font
					(size 1.27 1.27)
				)
			)
		)
		(duplicate_pad_numbers_are_jumpers no)
		(fp_line
			(start -0.7874 0.4064)
			(end -0.7874 -0.4064)
			(stroke
				(width 0.1524)
				(type default)
			)
			(layer "F.SilkS")
		)
		(fp_line
			(start 0.7874 0.4064)
			(end -0.7874 0.4064)
			(stroke
				(width 0.1524)
				(type default)
			)
			(layer "F.SilkS")
		)
		(fp_line
			(start -0.7874 -0.4064)
			(end 0.7874 -0.4064)
			(stroke
				(width 0.1524)
				(type default)
			)
			(layer "F.SilkS")
		)
		(fp_line
			(start 0.7874 -0.4064)
			(end 0.7874 0.4064)
			(stroke
				(width 0.1524)
				(type default)
			)
			(layer "F.SilkS")
		)
		(fp_line
			(start -0.67945 0.3048)
			(end -0.67945 -0.305054)
			(stroke
				(width 0.1)
				(type default)
			)
			(layer "F.Fab")
		)
		(fp_line
			(start -0.12065 0.3048)
			(end -0.67945 0.3048)
			(stroke
				(width 0.1)
				(type default)
			)
			(layer "F.Fab")
		)
		(fp_line
			(start 0.120396 0.3048)
			(end 0.120396 0.2794)
			(stroke
				(width 0.1)
				(type default)
			)
			(layer "F.Fab")
		)
		(fp_line
			(start 0.67945 0.3048)
			(end 0.120396 0.3048)
			(stroke
				(width 0.1)
				(type default)
			)
			(layer "F.Fab")
		)
		(fp_line
			(start -0.12065 0.2794)
			(end -0.12065 0.3048)
			(stroke
				(width 0.1)
				(type default)
			)
			(layer "F.Fab")
		)
		(fp_line
			(start 0.120396 0.2794)
			(end -0.12065 0.2794)
			(stroke
				(width 0.1)
				(type default)
			)
			(layer "F.Fab")
		)
		(fp_line
			(start -0.12065 -0.2794)
			(end 0.12065 -0.2794)
			(stroke
				(width 0.1)
				(type default)
			)
			(layer "F.Fab")
		)
		(fp_line
			(start 0.12065 -0.2794)
			(end 0.12065 -0.3048)
			(stroke
				(width 0.1)
				(type default)
			)
			(layer "F.Fab")
		)
		(fp_line
			(start 0.12065 -0.3048)
			(end 0.67945 -0.3048)
			(stroke
				(width 0.1)
				(type default)
			)
			(layer "F.Fab")
		)
		(fp_line
			(start 0.67945 -0.3048)
			(end 0.67945 0.3048)
			(stroke
				(width 0.1)
				(type default)
			)
			(layer "F.Fab")
		)
		(fp_line
			(start -0.67945 -0.305054)
			(end -0.12065 -0.305054)
			(stroke
				(width 0.1)
				(type default)
			)
			(layer "F.Fab")
		)
		(fp_line
			(start -0.12065 -0.305054)
			(end -0.12065 -0.2794)
			(stroke
				(width 0.1)
				(type default)
			)
			(layer "F.Fab")
		)
		(pad "1" smd circle
			(at -0.40005 0 270)
			(size 0 0)
			(layers "F.Cu" "F.Mask" "F.Paste")
			(net "SH_PVCCFA_EHV_FIVRA_CPU1")
		)
		(pad "2" smd circle
			(at 0.40005 0 270)
			(size 0 0)
			(layers "F.Cu" "F.Mask" "F.Paste")
			(net "SH_PVCCFA_EHV_FIVRA_CPU1_R")
		)
	)
	(footprint ""
		(layer "F.Cu")
		(at 303.543208 -369.067588)
		(property "Reference" "PC1670"
			(at 0 0 0)
			(layer "F.SilkS")
			(hide yes)
			(effects
				(font
					(size 1.27 1.27)
				)
			)
		)
		(property "Value" ""
			(at 0 0 0)
			(layer "F.Fab")
			(effects
				(font
					(size 1.27 1.27)
				)
			)
		)
		(duplicate_pad_numbers_are_jumpers no)
		(fp_line
			(start -1.524 -0.762)
			(end 1.524 -0.762)
			(stroke
				(width 0.1524)
				(type default)
			)
			(layer "F.SilkS")
		)
		(fp_line
			(start -1.524 0.762)
			(end -1.524 -0.762)
			(stroke
				(width 0.1524)
				(type default)
			)
			(layer "F.SilkS")
		)
		(fp_line
			(start 1.524 -0.762)
			(end 1.524 0.762)
			(stroke
				(width 0.1524)
				(type default)
			)
			(layer "F.SilkS")
		)
		(fp_line
			(start 1.524 0.762)
			(end -1.524 0.762)
			(stroke
				(width 0.1524)
				(type default)
			)
			(layer "F.SilkS")
		)
		(fp_line
			(start -1.1049 -0.724916)
			(end -1.1049 0.724916)
			(stroke
				(width 0.1)
				(type default)
			)
			(layer "F.Fab")
		)
		(fp_line
			(start -1.1049 0.724916)
			(end 1.1049 0.724916)
			(stroke
				(width 0.1)
				(type default)
			)
			(layer "F.Fab")
		)
		(fp_line
			(start 1.1049 -0.724916)
			(end -1.1049 -0.724916)
			(stroke
				(width 0.1)
				(type default)
			)
			(layer "F.Fab")
		)
		(fp_line
			(start 1.1049 0.724916)
			(end 1.1049 -0.724916)
			(stroke
				(width 0.1)
				(type default)
			)
			(layer "F.Fab")
		)
		(pad "1" smd rect
			(at -0.889 0 180)
			(size 1.016 1.27)
			(layers "F.Cu" "F.Mask" "F.Paste")
			(net "SW_P12V_PVCCFA_EHV_FIVRA_CPU0_L")
		)
		(pad "2" smd rect
			(at 0.889 0 180)
			(size 1.016 1.27)
			(layers "F.Cu" "F.Mask" "F.Paste")
			(net "GND")
		)
	)
	(footprint ""
		(layer "F.Cu")
		(at 369.461796 -324.445376)
		(property "Reference" "PL11"
			(at 8.906764 3.735578 0)
			(unlocked yes)
			(layer "F.SilkS")
			(effects
				(font
					(size 0.7874 0.5842)
					(thickness 0.1524)
				)
				(justify left)
			)
		)
		(property "Value" ""
			(at 0 0 0)
			(layer "F.Fab")
			(effects
				(font
					(size 1.27 1.27)
				)
			)
		)
		(duplicate_pad_numbers_are_jumpers no)
		(fp_line
			(start -3.750056 -5.500116)
			(end -2.393442 -5.500116)
			(stroke
				(width 0.1524)
				(type default)
			)
			(layer "F.SilkS")
		)
		(fp_line
			(start -3.750056 5.500116)
			(end -3.750056 -5.500116)
			(stroke
				(width 0.1524)
				(type default)
			)
			(layer "F.SilkS")
		)
		(fp_line
			(start -2.393442 5.500116)
			(end -3.750056 5.500116)
			(stroke
				(width 0.1524)
				(type default)
			)
			(layer "F.SilkS")
		)
		(fp_line
			(start 2.393442 5.500116)
			(end 3.750056 5.500116)
			(stroke
				(width 0.1524)
				(type default)
			)
			(layer "F.SilkS")
		)
		(fp_line
			(start 3.750056 -5.500116)
			(end 2.393442 -5.500116)
			(stroke
				(width 0.1524)
				(type default)
			)
			(layer "F.SilkS")
		)
		(fp_line
			(start 3.750056 5.500116)
			(end 3.750056 -5.500116)
			(stroke
				(width 0.1524)
				(type default)
			)
			(layer "F.SilkS")
		)
		(fp_poly
			(pts
				(xy -3.302762 -6.909816) (xy -2.943352 -5.832094) (xy -4.021074 -6.191504)
			)
			(stroke
				(width 0)
				(type default)
			)
			(fill yes)
			(layer "F.SilkS")
		)
		(fp_line
			(start -3.750056 -5.500116)
			(end -3.750056 5.500116)
			(stroke
				(width 0.1)
				(type default)
			)
			(layer "F.Fab")
		)
		(fp_line
			(start -3.750056 5.500116)
			(end 3.750056 5.500116)
			(stroke
				(width 0.1)
				(type default)
			)
			(layer "F.Fab")
		)
		(fp_line
			(start 3.750056 -5.500116)
			(end -3.750056 -5.500116)
			(stroke
				(width 0.1)
				(type default)
			)
			(layer "F.Fab")
		)
		(fp_line
			(start 3.750056 5.500116)
			(end 3.750056 -5.500116)
			(stroke
				(width 0.1)
				(type default)
			)
			(layer "F.Fab")
		)
		(fp_poly
			(pts
				(xy -4.9276 -4.757928) (xy -4.9276 -3.741928) (xy -3.9116 -4.249928)
			)
			(stroke
				(width 0)
				(type default)
			)
			(fill yes)
			(layer "F.Fab")
		)
		(pad "1" smd rect
			(at 0 -4.249928 270)
			(size 2.413 4.5212)
			(layers "F.Cu" "F.Mask" "F.Paste")
			(net "SW_PVCCIN_CPU0_SW4")
		)
		(pad "2" smd rect
			(at 0 -1.175004 270)
			(size 1.3716 4.5212)
			(layers "F.Cu" "F.Mask" "F.Paste")
			(net "IND_P0_CPL4")
		)
		(pad "3" smd rect
			(at 0 1.175004 270)
			(size 1.3716 4.5212)
			(layers "F.Cu" "F.Mask" "F.Paste")
			(net "IND_P0_CPL5")
		)
		(pad "4" smd rect
			(at 0 4.249928 270)
			(size 2.413 4.5212)
			(layers "F.Cu" "F.Mask" "F.Paste")
			(net "PVCCIN_CPU0")
		)
	)
	(footprint ""
		(layer "F.Cu")
		(at 116.561616 -249.320558 -90)
		(property "Reference" "C309"
			(at 0 0 270)
			(layer "F.SilkS")
			(hide yes)
			(effects
				(font
					(size 1.27 1.27)
				)
			)
		)
		(property "Value" ""
			(at 0 0 270)
			(layer "F.Fab")
			(effects
				(font
					(size 1.27 1.27)
				)
			)
		)
		(duplicate_pad_numbers_are_jumpers no)
		(fp_line
			(start -0.7874 0.4064)
			(end -0.7874 -0.4064)
			(stroke
				(width 0.1524)
				(type default)
			)
			(layer "F.SilkS")
		)
		(fp_line
			(start 0.7874 0.4064)
			(end -0.7874 0.4064)
			(stroke
				(width 0.1524)
				(type default)
			)
			(layer "F.SilkS")
		)
		(fp_line
			(start -0.7874 -0.4064)
			(end 0.7874 -0.4064)
			(stroke
				(width 0.1524)
				(type default)
			)
			(layer "F.SilkS")
		)
		(fp_line
			(start 0.7874 -0.4064)
			(end 0.7874 0.4064)
			(stroke
				(width 0.1524)
				(type default)
			)
			(layer "F.SilkS")
		)
		(fp_line
			(start -0.67945 0.3048)
			(end -0.67945 -0.305054)
			(stroke
				(width 0.1)
				(type default)
			)
			(layer "F.Fab")
		)
		(fp_line
			(start -0.12065 0.3048)
			(end -0.67945 0.3048)
			(stroke
				(width 0.1)
				(type default)
			)
			(layer "F.Fab")
		)
		(fp_line
			(start 0.120396 0.3048)
			(end 0.120396 0.2794)
			(stroke
				(width 0.1)
				(type default)
			)
			(layer "F.Fab")
		)
		(fp_line
			(start 0.67945 0.3048)
			(end 0.120396 0.3048)
			(stroke
				(width 0.1)
				(type default)
			)
			(layer "F.Fab")
		)
		(fp_line
			(start -0.12065 0.2794)
			(end -0.12065 0.3048)
			(stroke
				(width 0.1)
				(type default)
			)
			(layer "F.Fab")
		)
		(fp_line
			(start 0.120396 0.2794)
			(end -0.12065 0.2794)
			(stroke
				(width 0.1)
				(type default)
			)
			(layer "F.Fab")
		)
		(fp_line
			(start -0.12065 -0.2794)
			(end 0.12065 -0.2794)
			(stroke
				(width 0.1)
				(type default)
			)
			(layer "F.Fab")
		)
		(fp_line
			(start 0.12065 -0.2794)
			(end 0.12065 -0.3048)
			(stroke
				(width 0.1)
				(type default)
			)
			(layer "F.Fab")
		)
		(fp_line
			(start 0.12065 -0.3048)
			(end 0.67945 -0.3048)
			(stroke
				(width 0.1)
				(type default)
			)
			(layer "F.Fab")
		)
		(fp_line
			(start 0.67945 -0.3048)
			(end 0.67945 0.3048)
			(stroke
				(width 0.1)
				(type default)
			)
			(layer "F.Fab")
		)
		(fp_line
			(start -0.67945 -0.305054)
			(end -0.12065 -0.305054)
			(stroke
				(width 0.1)
				(type default)
			)
			(layer "F.Fab")
		)
		(fp_line
			(start -0.12065 -0.305054)
			(end -0.12065 -0.2794)
			(stroke
				(width 0.1)
				(type default)
			)
			(layer "F.Fab")
		)
		(pad "1" smd circle
			(at -0.40005 0 270)
			(size 0 0)
			(layers "F.Cu" "F.Mask" "F.Paste")
			(net "PVCCIN_CPU1")
		)
		(pad "2" smd circle
			(at 0.40005 0 270)
			(size 0 0)
			(layers "F.Cu" "F.Mask" "F.Paste")
			(net "GND")
		)
	)
	(footprint ""
		(layer "F.Cu")
		(at 258.12496 -360.76382)
		(property "Reference" "H113"
			(at -6.92404 -7.717028 0)
			(unlocked yes)
			(layer "F.SilkS")
			(effects
				(font
					(size 0.7874 0.5842)
					(thickness 0.1524)
				)
				(justify left)
			)
		)
		(property "Value" ""
			(at 0 0 0)
			(layer "F.Fab")
			(effects
				(font
					(size 1.27 1.27)
				)
			)
		)
		(duplicate_pad_numbers_are_jumpers no)
		(fp_circle
			(center 0 0)
			(end 7.999984 0)
			(stroke
				(width 0.1524)
				(type default)
			)
			(fill no)
			(layer "F.SilkS")
		)
		(fp_circle
			(center 0 0)
			(end 7.999984 0)
			(stroke
				(width 0.1524)
				(type default)
			)
			(fill no)
			(layer "B.SilkS")
		)
		(fp_circle
			(center 0 0)
			(end 7.999984 0)
			(stroke
				(width 0.1)
				(type default)
			)
			(fill no)
			(layer "B.Fab")
		)
		(fp_circle
			(center 0 0)
			(end 7.999984 0)
			(stroke
				(width 0.1)
				(type default)
			)
			(fill no)
			(layer "F.Fab")
		)
		(pad "" np_thru_hole circle
			(at 0 0)
			(size 4.0132 4.0132)
			(drill 4.0132)
			(layers "*.Cu" "*.Mask")
			(clearance 0.381)
			(thermal_gap 0.381)
		)
		(pad "2" thru_hole circle
			(at 3.2639 0)
			(size 0.9144 0.9144)
			(drill 0.5588)
			(layers "*.Cu" "*.Mask")
			(remove_unused_layers no)
			(net "GND")
			(clearance 0.0762)
			(thermal_gap 0.0762)
		)
		(pad "3" thru_hole circle
			(at 2.307844 -2.307844)
			(size 0.9144 0.9144)
			(drill 0.5588)
			(layers "*.Cu" "*.Mask")
			(remove_unused_layers no)
			(net "GND")
			(clearance 0.0762)
			(thermal_gap 0.0762)
		)
		(pad "4" thru_hole circle
			(at 0 -3.2639)
			(size 0.9144 0.9144)
			(drill 0.5588)
			(layers "*.Cu" "*.Mask")
			(remove_unused_layers no)
			(net "GND")
			(clearance 0.0762)
			(thermal_gap 0.0762)
		)
		(pad "5" thru_hole circle
			(at -2.307844 -2.307844)
			(size 0.9144 0.9144)
			(drill 0.5588)
			(layers "*.Cu" "*.Mask")
			(remove_unused_layers no)
			(net "GND")
			(clearance 0.0762)
			(thermal_gap 0.0762)
		)
		(pad "6" thru_hole circle
			(at -3.2639 0)
			(size 0.9144 0.9144)
			(drill 0.5588)
			(layers "*.Cu" "*.Mask")
			(remove_unused_layers no)
			(net "GND")
			(clearance 0.0762)
			(thermal_gap 0.0762)
		)
		(pad "7" thru_hole circle
			(at -2.307844 2.307844)
			(size 0.9144 0.9144)
			(drill 0.5588)
			(layers "*.Cu" "*.Mask")
			(remove_unused_layers no)
			(net "GND")
			(clearance 0.0762)
			(thermal_gap 0.0762)
		)
		(pad "8" thru_hole circle
			(at 0 3.2639)
			(size 0.9144 0.9144)
			(drill 0.5588)
			(layers "*.Cu" "*.Mask")
			(remove_unused_layers no)
			(net "GND")
			(clearance 0.0762)
			(thermal_gap 0.0762)
		)
		(pad "9" thru_hole circle
			(at 2.307844 2.307844)
			(size 0.9144 0.9144)
			(drill 0.5588)
			(layers "*.Cu" "*.Mask")
			(remove_unused_layers no)
			(net "GND")
			(clearance 0.0762)
			(thermal_gap 0.0762)
		)
		(zone
			(layer "F.Cu")
			(hatch none 0.5)
			(connect_pads
				(clearance 0)
			)
			(min_thickness 0.25)
			(keepout
				(tracks not_allowed)
				(vias allowed)
				(pads allowed)
				(copperpour not_allowed)
				(footprints allowed)
			)
			(placement
				(enabled no)
				(sheetname "")
			)
			(fill
				(thermal_gap 0.5)
				(thermal_bridge_width 0.5)
				(island_removal_mode 0)
			)
			(polygon
				(pts
					(arc
						(start 258.12496 -356.49662)
						(mid 253.85776 -360.76382)
						(end 258.12496 -365.03102)
					)
					(arc
						(start 258.12496 -368.763804)
						(mid 252.468117 -366.420663)
						(end 250.124976 -360.76382)
					)
					(arc
						(start 250.124976 -360.76382)
						(mid 252.468117 -355.106977)
						(end 258.12496 -352.763836)
					)
				)
			)
		)
		(zone
			(layer "F.Cu")
			(hatch none 0.5)
			(connect_pads
				(clearance 0)
			)
			(min_thickness 0.25)
			(keepout
				(tracks not_allowed)
				(vias allowed)
				(pads allowed)
				(copperpour not_allowed)
				(footprints allowed)
			)
			(placement
				(enabled no)
				(sheetname "")
			)
			(fill
				(thermal_gap 0.5)
				(thermal_bridge_width 0.5)
				(island_removal_mode 0)
			)
			(polygon
				(pts
					(arc
						(start 258.12496 -356.49662)
						(mid 262.39216 -360.76382)
						(end 258.12496 -365.03102)
					)
					(arc
						(start 258.12496 -368.763804)
						(mid 263.781803 -366.420663)
						(end 266.124944 -360.76382)
					)
					(arc
						(start 266.124944 -360.76382)
						(mid 263.781803 -355.106977)
						(end 258.12496 -352.763836)
					)
				)
			)
		)
		(zone
			(layers "F.Cu" "B.Cu" "In1.Cu" "In2.Cu" "In3.Cu" "In4.Cu" "In5.Cu" "In6.Cu"
				"In7.Cu" "In8.Cu" "In9.Cu" "In10.Cu" "In11.Cu" "In12.Cu" "In13.Cu" "In14.Cu"
				"In15.Cu" "In16.Cu"
			)
			(hatch none 0.5)
			(connect_pads
				(clearance 0)
			)
			(min_thickness 0.25)
			(keepout
				(tracks not_allowed)
				(vias allowed)
				(pads allowed)
				(copperpour not_allowed)
				(footprints allowed)
			)
			(placement
				(enabled no)
				(sheetname "")
			)
			(fill
				(thermal_gap 0.5)
				(thermal_bridge_width 0.5)
				(island_removal_mode 0)
			)
			(polygon
				(pts
					(arc
						(start 260.63702 -360.76382)
						(mid 255.6129 -360.76382)
						(end 260.63702 -360.76382)
					)
				)
			)
		)
		(zone
			(layer "B.Cu")
			(hatch none 0.5)
			(connect_pads
				(clearance 0)
			)
			(min_thickness 0.25)
			(keepout
				(tracks not_allowed)
				(vias allowed)
				(pads allowed)
				(copperpour not_allowed)
				(footprints allowed)
			)
			(placement
				(enabled no)
				(sheetname "")
			)
			(fill
				(thermal_gap 0.5)
				(thermal_bridge_width 0.5)
				(island_removal_mode 0)
			)
			(polygon
				(pts
					(arc
						(start 258.12496 -365.28502)
						(mid 253.60376 -360.76382)
						(end 258.12496 -356.24262)
					)
					(arc
						(start 258.12496 -356.72522)
						(mid 254.08636 -360.76382)
						(end 258.12496 -364.80242)
					)
				)
			)
		)
		(zone
			(layer "B.Cu")
			(hatch none 0.5)
			(connect_pads
				(clearance 0)
			)
			(min_thickness 0.25)
			(keepout
				(tracks not_allowed)
				(vias allowed)
				(pads allowed)
				(copperpour not_allowed)
				(footprints allowed)
			)
			(placement
				(enabled no)
				(sheetname "")
			)
			(fill
				(thermal_gap 0.5)
				(thermal_bridge_width 0.5)
				(island_removal_mode 0)
			)
			(polygon
				(pts
					(arc
						(start 258.12496 -365.28502)
						(mid 262.64616 -360.76382)
						(end 258.12496 -356.24262)
					)
					(arc
						(start 258.12496 -356.72522)
						(mid 262.16356 -360.76382)
						(end 258.12496 -364.80242)
					)
				)
			)
		)
	)
	(footprint ""
		(layer "F.Cu")
		(at 182.82158 -417.7157)
		(property "Reference" "C2390"
			(at 0 0 0)
			(layer "F.SilkS")
			(hide yes)
			(effects
				(font
					(size 1.27 1.27)
				)
			)
		)
		(property "Value" ""
			(at 0 0 0)
			(layer "F.Fab")
			(effects
				(font
					(size 1.27 1.27)
				)
			)
		)
		(duplicate_pad_numbers_are_jumpers no)
		(fp_line
			(start -0.7874 -0.4064)
			(end 0.7874 -0.4064)
			(stroke
				(width 0.1524)
				(type default)
			)
			(layer "F.SilkS")
		)
		(fp_line
			(start -0.7874 0.4064)
			(end -0.7874 -0.4064)
			(stroke
				(width 0.1524)
				(type default)
			)
			(layer "F.SilkS")
		)
		(fp_line
			(start 0.7874 -0.4064)
			(end 0.7874 0.4064)
			(stroke
				(width 0.1524)
				(type default)
			)
			(layer "F.SilkS")
		)
		(fp_line
			(start 0.7874 0.4064)
			(end -0.7874 0.4064)
			(stroke
				(width 0.1524)
				(type default)
			)
			(layer "F.SilkS")
		)
		(fp_line
			(start -0.67945 -0.305054)
			(end -0.12065 -0.305054)
			(stroke
				(width 0.1)
				(type default)
			)
			(layer "F.Fab")
		)
		(fp_line
			(start -0.67945 0.3048)
			(end -0.67945 -0.305054)
			(stroke
				(width 0.1)
				(type default)
			)
			(layer "F.Fab")
		)
		(fp_line
			(start -0.12065 -0.305054)
			(end -0.12065 -0.2794)
			(stroke
				(width 0.1)
				(type default)
			)
			(layer "F.Fab")
		)
		(fp_line
			(start -0.12065 -0.2794)
			(end 0.12065 -0.2794)
			(stroke
				(width 0.1)
				(type default)
			)
			(layer "F.Fab")
		)
		(fp_line
			(start -0.12065 0.2794)
			(end -0.12065 0.3048)
			(stroke
				(width 0.1)
				(type default)
			)
			(layer "F.Fab")
		)
		(fp_line
			(start -0.12065 0.3048)
			(end -0.67945 0.3048)
			(stroke
				(width 0.1)
				(type default)
			)
			(layer "F.Fab")
		)
		(fp_line
			(start 0.120396 0.2794)
			(end -0.12065 0.2794)
			(stroke
				(width 0.1)
				(type default)
			)
			(layer "F.Fab")
		)
		(fp_line
			(start 0.120396 0.3048)
			(end 0.120396 0.2794)
			(stroke
				(width 0.1)
				(type default)
			)
			(layer "F.Fab")
		)
		(fp_line
			(start 0.12065 -0.3048)
			(end 0.67945 -0.3048)
			(stroke
				(width 0.1)
				(type default)
			)
			(layer "F.Fab")
		)
		(fp_line
			(start 0.12065 -0.2794)
			(end 0.12065 -0.3048)
			(stroke
				(width 0.1)
				(type default)
			)
			(layer "F.Fab")
		)
		(fp_line
			(start 0.67945 -0.3048)
			(end 0.67945 0.3048)
			(stroke
				(width 0.1)
				(type default)
			)
			(layer "F.Fab")
		)
		(fp_line
			(start 0.67945 0.3048)
			(end 0.120396 0.3048)
			(stroke
				(width 0.1)
				(type default)
			)
			(layer "F.Fab")
		)
		(pad "1" smd circle
			(at -0.40005 0)
			(size 0 0)
			(layers "F.Cu" "F.Mask" "F.Paste")
			(net "P12V_AUX")
		)
		(pad "2" smd circle
			(at 0.40005 0)
			(size 0 0)
			(layers "F.Cu" "F.Mask" "F.Paste")
			(net "GND")
		)
	)
	(footprint ""
		(layer "F.Cu")
		(at 117.22608 -122.132598 90)
		(property "Reference" "R938"
			(at 0 0 90)
			(layer "F.SilkS")
			(hide yes)
			(effects
				(font
					(size 1.27 1.27)
				)
			)
		)
		(property "Value" ""
			(at 0 0 90)
			(layer "F.Fab")
			(effects
				(font
					(size 1.27 1.27)
				)
			)
		)
		(duplicate_pad_numbers_are_jumpers no)
		(fp_line
			(start 0.7874 -0.4064)
			(end 0.7874 0.4064)
			(stroke
				(width 0.1524)
				(type default)
			)
			(layer "F.SilkS")
		)
		(fp_line
			(start -0.7874 -0.4064)
			(end 0.7874 -0.4064)
			(stroke
				(width 0.1524)
				(type default)
			)
			(layer "F.SilkS")
		)
		(fp_line
			(start 0.7874 0.4064)
			(end -0.7874 0.4064)
			(stroke
				(width 0.1524)
				(type default)
			)
			(layer "F.SilkS")
		)
		(fp_line
			(start -0.7874 0.4064)
			(end -0.7874 -0.4064)
			(stroke
				(width 0.1524)
				(type default)
			)
			(layer "F.SilkS")
		)
		(fp_line
			(start -0.12065 -0.305054)
			(end -0.12065 -0.2794)
			(stroke
				(width 0.1)
				(type default)
			)
			(layer "F.Fab")
		)
		(fp_line
			(start -0.67945 -0.305054)
			(end -0.12065 -0.305054)
			(stroke
				(width 0.1)
				(type default)
			)
			(layer "F.Fab")
		)
		(fp_line
			(start 0.67945 -0.3048)
			(end 0.67945 0.3048)
			(stroke
				(width 0.1)
				(type default)
			)
			(layer "F.Fab")
		)
		(fp_line
			(start 0.12065 -0.3048)
			(end 0.67945 -0.3048)
			(stroke
				(width 0.1)
				(type default)
			)
			(layer "F.Fab")
		)
		(fp_line
			(start 0.12065 -0.2794)
			(end 0.12065 -0.3048)
			(stroke
				(width 0.1)
				(type default)
			)
			(layer "F.Fab")
		)
		(fp_line
			(start -0.12065 -0.2794)
			(end 0.12065 -0.2794)
			(stroke
				(width 0.1)
				(type default)
			)
			(layer "F.Fab")
		)
		(fp_line
			(start 0.120396 0.2794)
			(end -0.12065 0.2794)
			(stroke
				(width 0.1)
				(type default)
			)
			(layer "F.Fab")
		)
		(fp_line
			(start -0.12065 0.2794)
			(end -0.12065 0.3048)
			(stroke
				(width 0.1)
				(type default)
			)
			(layer "F.Fab")
		)
		(fp_line
			(start 0.67945 0.3048)
			(end 0.120396 0.3048)
			(stroke
				(width 0.1)
				(type default)
			)
			(layer "F.Fab")
		)
		(fp_line
			(start 0.120396 0.3048)
			(end 0.120396 0.2794)
			(stroke
				(width 0.1)
				(type default)
			)
			(layer "F.Fab")
		)
		(fp_line
			(start -0.12065 0.3048)
			(end -0.67945 0.3048)
			(stroke
				(width 0.1)
				(type default)
			)
			(layer "F.Fab")
		)
		(fp_line
			(start -0.67945 0.3048)
			(end -0.67945 -0.305054)
			(stroke
				(width 0.1)
				(type default)
			)
			(layer "F.Fab")
		)
		(pad "1" smd circle
			(at -0.40005 0 90)
			(size 0 0)
			(layers "F.Cu" "F.Mask" "F.Paste")
			(net "RST_CPU0_DRAM_GH_N")
		)
		(pad "2" smd circle
			(at 0.40005 0 90)
			(size 0 0)
			(layers "F.Cu" "F.Mask" "F.Paste")
			(net "GND")
		)
	)
	(footprint ""
		(layer "F.Cu")
		(at 335.933288 -408.517344 -90)
		(property "Reference" "C922"
			(at 0 0 270)
			(layer "F.SilkS")
			(hide yes)
			(effects
				(font
					(size 1.27 1.27)
				)
			)
		)
		(property "Value" ""
			(at 0 0 270)
			(layer "F.Fab")
			(effects
				(font
					(size 1.27 1.27)
				)
			)
		)
		(duplicate_pad_numbers_are_jumpers no)
		(fp_line
			(start -0.299974 0.150114)
			(end -0.299974 -0.150114)
			(stroke
				(width 0.1)
				(type default)
			)
			(layer "F.Fab")
		)
		(fp_line
			(start 0.299974 0.150114)
			(end -0.299974 0.150114)
			(stroke
				(width 0.1)
				(type default)
			)
			(layer "F.Fab")
		)
		(fp_line
			(start -0.299974 -0.150114)
			(end 0.299974 -0.150114)
			(stroke
				(width 0.1)
				(type default)
			)
			(layer "F.Fab")
		)
		(fp_line
			(start 0.299974 -0.150114)
			(end 0.299974 0.150114)
			(stroke
				(width 0.1)
				(type default)
			)
			(layer "F.Fab")
		)
		(pad "1" smd rect
			(at -0.2667 0 270)
			(size 0.3048 0.381)
			(layers "F.Cu" "F.Mask" "F.Paste")
			(net "P5E_CPU0_PE0_TX_C_DN<5>")
		)
		(pad "2" smd rect
			(at 0.2667 0 270)
			(size 0.3048 0.381)
			(layers "F.Cu" "F.Mask" "F.Paste")
			(net "P5E_CPU0_PE0_TX_DN<5>")
		)
	)
	(footprint ""
		(layer "F.Cu")
		(at 352.163888 -408.517344 -90)
		(property "Reference" "C933"
			(at 0 0 270)
			(layer "F.SilkS")
			(hide yes)
			(effects
				(font
					(size 1.27 1.27)
				)
			)
		)
		(property "Value" ""
			(at 0 0 270)
			(layer "F.Fab")
			(effects
				(font
					(size 1.27 1.27)
				)
			)
		)
		(duplicate_pad_numbers_are_jumpers no)
		(fp_line
			(start -0.299974 0.150114)
			(end -0.299974 -0.150114)
			(stroke
				(width 0.1)
				(type default)
			)
			(layer "F.Fab")
		)
		(fp_line
			(start 0.299974 0.150114)
			(end -0.299974 0.150114)
			(stroke
				(width 0.1)
				(type default)
			)
			(layer "F.Fab")
		)
		(fp_line
			(start -0.299974 -0.150114)
			(end 0.299974 -0.150114)
			(stroke
				(width 0.1)
				(type default)
			)
			(layer "F.Fab")
		)
		(fp_line
			(start 0.299974 -0.150114)
			(end 0.299974 0.150114)
			(stroke
				(width 0.1)
				(type default)
			)
			(layer "F.Fab")
		)
		(pad "1" smd rect
			(at -0.2667 0 270)
			(size 0.3048 0.381)
			(layers "F.Cu" "F.Mask" "F.Paste")
			(net "P5E_CPU0_PE0_TX_C_DP<0>")
		)
		(pad "2" smd rect
			(at 0.2667 0 270)
			(size 0.3048 0.381)
			(layers "F.Cu" "F.Mask" "F.Paste")
			(net "P5E_CPU0_PE0_TX_DP<0>")
		)
	)
	(footprint ""
		(layer "F.Cu")
		(at 181.15788 -97.119948 90)
		(property "Reference" "R219"
			(at 0 0 90)
			(layer "F.SilkS")
			(hide yes)
			(effects
				(font
					(size 1.27 1.27)
				)
			)
		)
		(property "Value" ""
			(at 0 0 90)
			(layer "F.Fab")
			(effects
				(font
					(size 1.27 1.27)
				)
			)
		)
		(duplicate_pad_numbers_are_jumpers no)
		(fp_line
			(start 0.7874 -0.4064)
			(end 0.7874 0.4064)
			(stroke
				(width 0.1524)
				(type default)
			)
			(layer "F.SilkS")
		)
		(fp_line
			(start -0.7874 -0.4064)
			(end 0.7874 -0.4064)
			(stroke
				(width 0.1524)
				(type default)
			)
			(layer "F.SilkS")
		)
		(fp_line
			(start 0.7874 0.4064)
			(end -0.7874 0.4064)
			(stroke
				(width 0.1524)
				(type default)
			)
			(layer "F.SilkS")
		)
		(fp_line
			(start -0.7874 0.4064)
			(end -0.7874 -0.4064)
			(stroke
				(width 0.1524)
				(type default)
			)
			(layer "F.SilkS")
		)
		(fp_line
			(start -0.12065 -0.305054)
			(end -0.12065 -0.2794)
			(stroke
				(width 0.1)
				(type default)
			)
			(layer "F.Fab")
		)
		(fp_line
			(start -0.67945 -0.305054)
			(end -0.12065 -0.305054)
			(stroke
				(width 0.1)
				(type default)
			)
			(layer "F.Fab")
		)
		(fp_line
			(start 0.67945 -0.3048)
			(end 0.67945 0.3048)
			(stroke
				(width 0.1)
				(type default)
			)
			(layer "F.Fab")
		)
		(fp_line
			(start 0.12065 -0.3048)
			(end 0.67945 -0.3048)
			(stroke
				(width 0.1)
				(type default)
			)
			(layer "F.Fab")
		)
		(fp_line
			(start 0.12065 -0.2794)
			(end 0.12065 -0.3048)
			(stroke
				(width 0.1)
				(type default)
			)
			(layer "F.Fab")
		)
		(fp_line
			(start -0.12065 -0.2794)
			(end 0.12065 -0.2794)
			(stroke
				(width 0.1)
				(type default)
			)
			(layer "F.Fab")
		)
		(fp_line
			(start 0.120396 0.2794)
			(end -0.12065 0.2794)
			(stroke
				(width 0.1)
				(type default)
			)
			(layer "F.Fab")
		)
		(fp_line
			(start -0.12065 0.2794)
			(end -0.12065 0.3048)
			(stroke
				(width 0.1)
				(type default)
			)
			(layer "F.Fab")
		)
		(fp_line
			(start 0.67945 0.3048)
			(end 0.120396 0.3048)
			(stroke
				(width 0.1)
				(type default)
			)
			(layer "F.Fab")
		)
		(fp_line
			(start 0.120396 0.3048)
			(end 0.120396 0.2794)
			(stroke
				(width 0.1)
				(type default)
			)
			(layer "F.Fab")
		)
		(fp_line
			(start -0.12065 0.3048)
			(end -0.67945 0.3048)
			(stroke
				(width 0.1)
				(type default)
			)
			(layer "F.Fab")
		)
		(fp_line
			(start -0.67945 0.3048)
			(end -0.67945 -0.305054)
			(stroke
				(width 0.1)
				(type default)
			)
			(layer "F.Fab")
		)
		(pad "1" smd circle
			(at -0.40005 0 90)
			(size 0 0)
			(layers "F.Cu" "F.Mask" "F.Paste")
			(net "PVNN_TERM_CPU0")
		)
		(pad "2" smd circle
			(at 0.40005 0 90)
			(size 0 0)
			(layers "F.Cu" "F.Mask" "F.Paste")
			(net "H_CPU0_MEMHOT_IN_LVC1_R1_N")
		)
	)
	(footprint ""
		(layer "F.Cu")
		(at 77.107542 -345.402662 90)
		(property "Reference" "PC480"
			(at 0 0 90)
			(layer "F.SilkS")
			(hide yes)
			(effects
				(font
					(size 1.27 1.27)
				)
			)
		)
		(property "Value" ""
			(at 0 0 90)
			(layer "F.Fab")
			(effects
				(font
					(size 1.27 1.27)
				)
			)
		)
		(duplicate_pad_numbers_are_jumpers no)
		(fp_line
			(start 0.7874 -0.4064)
			(end 0.7874 0.4064)
			(stroke
				(width 0.1524)
				(type default)
			)
			(layer "F.SilkS")
		)
		(fp_line
			(start -0.7874 -0.4064)
			(end 0.7874 -0.4064)
			(stroke
				(width 0.1524)
				(type default)
			)
			(layer "F.SilkS")
		)
		(fp_line
			(start 0.7874 0.4064)
			(end -0.7874 0.4064)
			(stroke
				(width 0.1524)
				(type default)
			)
			(layer "F.SilkS")
		)
		(fp_line
			(start -0.7874 0.4064)
			(end -0.7874 -0.4064)
			(stroke
				(width 0.1524)
				(type default)
			)
			(layer "F.SilkS")
		)
		(fp_line
			(start -0.12065 -0.305054)
			(end -0.12065 -0.2794)
			(stroke
				(width 0.1)
				(type default)
			)
			(layer "F.Fab")
		)
		(fp_line
			(start -0.67945 -0.305054)
			(end -0.12065 -0.305054)
			(stroke
				(width 0.1)
				(type default)
			)
			(layer "F.Fab")
		)
		(fp_line
			(start 0.67945 -0.3048)
			(end 0.67945 0.3048)
			(stroke
				(width 0.1)
				(type default)
			)
			(layer "F.Fab")
		)
		(fp_line
			(start 0.12065 -0.3048)
			(end 0.67945 -0.3048)
			(stroke
				(width 0.1)
				(type default)
			)
			(layer "F.Fab")
		)
		(fp_line
			(start 0.12065 -0.2794)
			(end 0.12065 -0.3048)
			(stroke
				(width 0.1)
				(type default)
			)
			(layer "F.Fab")
		)
		(fp_line
			(start -0.12065 -0.2794)
			(end 0.12065 -0.2794)
			(stroke
				(width 0.1)
				(type default)
			)
			(layer "F.Fab")
		)
		(fp_line
			(start 0.120396 0.2794)
			(end -0.12065 0.2794)
			(stroke
				(width 0.1)
				(type default)
			)
			(layer "F.Fab")
		)
		(fp_line
			(start -0.12065 0.2794)
			(end -0.12065 0.3048)
			(stroke
				(width 0.1)
				(type default)
			)
			(layer "F.Fab")
		)
		(fp_line
			(start 0.67945 0.3048)
			(end 0.120396 0.3048)
			(stroke
				(width 0.1)
				(type default)
			)
			(layer "F.Fab")
		)
		(fp_line
			(start 0.120396 0.3048)
			(end 0.120396 0.2794)
			(stroke
				(width 0.1)
				(type default)
			)
			(layer "F.Fab")
		)
		(fp_line
			(start -0.12065 0.3048)
			(end -0.67945 0.3048)
			(stroke
				(width 0.1)
				(type default)
			)
			(layer "F.Fab")
		)
		(fp_line
			(start -0.67945 0.3048)
			(end -0.67945 -0.305054)
			(stroke
				(width 0.1)
				(type default)
			)
			(layer "F.Fab")
		)
		(pad "1" smd circle
			(at -0.40005 0 90)
			(size 0 0)
			(layers "F.Cu" "F.Mask" "F.Paste")
			(net "PVCCIN_CPU1_VDD7")
		)
		(pad "2" smd circle
			(at 0.40005 0 90)
			(size 0 0)
			(layers "F.Cu" "F.Mask" "F.Paste")
			(net "GND")
		)
	)
	(footprint ""
		(layer "F.Cu")
		(at 112.799876 -79.078836)
		(property "Reference" "D97"
			(at -55.73141 38.649402 90)
			(unlocked yes)
			(layer "F.SilkS")
			(effects
				(font
					(size 0.635 0.4064)
					(thickness 0.1524)
				)
				(justify left)
			)
		)
		(property "Value" ""
			(at 0 0 0)
			(layer "F.Fab")
			(effects
				(font
					(size 1.27 1.27)
				)
			)
		)
		(duplicate_pad_numbers_are_jumpers no)
		(fp_line
			(start -0.90678 0.4826)
			(end -0.90678 -0.4699)
			(stroke
				(width 0.1524)
				(type default)
			)
			(layer "F.SilkS")
		)
		(fp_line
			(start -0.89408 -0.4826)
			(end 0.90678 -0.4826)
			(stroke
				(width 0.1524)
				(type default)
			)
			(layer "F.SilkS")
		)
		(fp_line
			(start -0.79248 -0.4826)
			(end 1.03378 -0.4826)
			(stroke
				(width 0.1524)
				(type default)
			)
			(layer "F.SilkS")
		)
		(fp_line
			(start -0.64008 -0.4826)
			(end 1.16078 -0.4826)
			(stroke
				(width 0.1524)
				(type default)
			)
			(layer "F.SilkS")
		)
		(fp_line
			(start 0.90678 -0.4826)
			(end 0.90678 0.4826)
			(stroke
				(width 0.1524)
				(type default)
			)
			(layer "F.SilkS")
		)
		(fp_line
			(start 0.90678 0.4826)
			(end -0.90678 0.4826)
			(stroke
				(width 0.1524)
				(type default)
			)
			(layer "F.SilkS")
		)
		(fp_line
			(start 1.03378 -0.4826)
			(end 1.03378 0.4826)
			(stroke
				(width 0.1524)
				(type default)
			)
			(layer "F.SilkS")
		)
		(fp_line
			(start 1.03378 0.4826)
			(end -0.79248 0.4826)
			(stroke
				(width 0.1524)
				(type default)
			)
			(layer "F.SilkS")
		)
		(fp_line
			(start 1.16078 -0.4826)
			(end 1.16078 0.4826)
			(stroke
				(width 0.1524)
				(type default)
			)
			(layer "F.SilkS")
		)
		(fp_line
			(start 1.16078 0.4826)
			(end -0.64008 0.4826)
			(stroke
				(width 0.1524)
				(type default)
			)
			(layer "F.SilkS")
		)
		(fp_line
			(start -0.499872 -0.249936)
			(end 0.499872 -0.249936)
			(stroke
				(width 0.1)
				(type default)
			)
			(layer "F.Fab")
		)
		(fp_line
			(start -0.499872 0.249936)
			(end -0.499872 -0.249936)
			(stroke
				(width 0.1)
				(type default)
			)
			(layer "F.Fab")
		)
		(fp_line
			(start 0.499872 -0.249936)
			(end 0.499872 0.249936)
			(stroke
				(width 0.1)
				(type default)
			)
			(layer "F.Fab")
		)
		(fp_line
			(start 0.499872 0.249936)
			(end -0.499872 0.249936)
			(stroke
				(width 0.1)
				(type default)
			)
			(layer "F.Fab")
		)
		(pad "A" smd rect
			(at -0.47498 0)
			(size 0.6096 0.7112)
			(layers "F.Cu" "F.Mask" "F.Paste")
			(net "LED_P5V_AUX")
		)
		(pad "C" smd rect
			(at 0.47498 0)
			(size 0.6096 0.7112)
			(layers "F.Cu" "F.Mask" "F.Paste")
			(net "GND")
		)
	)
	(footprint ""
		(layer "F.Cu")
		(at 298.036996 -43.594274 90)
		(property "Reference" "R1343"
			(at 0 0 90)
			(layer "F.SilkS")
			(hide yes)
			(effects
				(font
					(size 1.27 1.27)
				)
			)
		)
		(property "Value" ""
			(at 0 0 90)
			(layer "F.Fab")
			(effects
				(font
					(size 1.27 1.27)
				)
			)
		)
		(duplicate_pad_numbers_are_jumpers no)
		(fp_line
			(start 0.7874 -0.4064)
			(end 0.7874 0.4064)
			(stroke
				(width 0.1524)
				(type default)
			)
			(layer "F.SilkS")
		)
		(fp_line
			(start -0.7874 -0.4064)
			(end 0.7874 -0.4064)
			(stroke
				(width 0.1524)
				(type default)
			)
			(layer "F.SilkS")
		)
		(fp_line
			(start 0.7874 0.4064)
			(end -0.7874 0.4064)
			(stroke
				(width 0.1524)
				(type default)
			)
			(layer "F.SilkS")
		)
		(fp_line
			(start -0.7874 0.4064)
			(end -0.7874 -0.4064)
			(stroke
				(width 0.1524)
				(type default)
			)
			(layer "F.SilkS")
		)
		(fp_line
			(start -0.12065 -0.305054)
			(end -0.12065 -0.2794)
			(stroke
				(width 0.1)
				(type default)
			)
			(layer "F.Fab")
		)
		(fp_line
			(start -0.67945 -0.305054)
			(end -0.12065 -0.305054)
			(stroke
				(width 0.1)
				(type default)
			)
			(layer "F.Fab")
		)
		(fp_line
			(start 0.67945 -0.3048)
			(end 0.67945 0.3048)
			(stroke
				(width 0.1)
				(type default)
			)
			(layer "F.Fab")
		)
		(fp_line
			(start 0.12065 -0.3048)
			(end 0.67945 -0.3048)
			(stroke
				(width 0.1)
				(type default)
			)
			(layer "F.Fab")
		)
		(fp_line
			(start 0.12065 -0.2794)
			(end 0.12065 -0.3048)
			(stroke
				(width 0.1)
				(type default)
			)
			(layer "F.Fab")
		)
		(fp_line
			(start -0.12065 -0.2794)
			(end 0.12065 -0.2794)
			(stroke
				(width 0.1)
				(type default)
			)
			(layer "F.Fab")
		)
		(fp_line
			(start 0.120396 0.2794)
			(end -0.12065 0.2794)
			(stroke
				(width 0.1)
				(type default)
			)
			(layer "F.Fab")
		)
		(fp_line
			(start -0.12065 0.2794)
			(end -0.12065 0.3048)
			(stroke
				(width 0.1)
				(type default)
			)
			(layer "F.Fab")
		)
		(fp_line
			(start 0.67945 0.3048)
			(end 0.120396 0.3048)
			(stroke
				(width 0.1)
				(type default)
			)
			(layer "F.Fab")
		)
		(fp_line
			(start 0.120396 0.3048)
			(end 0.120396 0.2794)
			(stroke
				(width 0.1)
				(type default)
			)
			(layer "F.Fab")
		)
		(fp_line
			(start -0.12065 0.3048)
			(end -0.67945 0.3048)
			(stroke
				(width 0.1)
				(type default)
			)
			(layer "F.Fab")
		)
		(fp_line
			(start -0.67945 0.3048)
			(end -0.67945 -0.305054)
			(stroke
				(width 0.1)
				(type default)
			)
			(layer "F.Fab")
		)
		(pad "1" smd circle
			(at -0.40005 0 90)
			(size 0 0)
			(layers "F.Cu" "F.Mask" "F.Paste")
			(net "P1V05_PCH_AUX")
		)
		(pad "2" smd circle
			(at 0.40005 0 90)
			(size 0 0)
			(layers "F.Cu" "F.Mask" "F.Paste")
			(net "FM_PASSWORD_CLEAR_N")
		)
	)
	(footprint ""
		(layer "F.Cu")
		(at 37.890196 -122.380502 -90)
		(property "Reference" "R1793"
			(at 0 0 270)
			(layer "F.SilkS")
			(hide yes)
			(effects
				(font
					(size 1.27 1.27)
				)
			)
		)
		(property "Value" ""
			(at 0 0 270)
			(layer "F.Fab")
			(effects
				(font
					(size 1.27 1.27)
				)
			)
		)
		(duplicate_pad_numbers_are_jumpers no)
		(fp_line
			(start -0.7874 0.4064)
			(end -0.7874 -0.4064)
			(stroke
				(width 0.1524)
				(type default)
			)
			(layer "F.SilkS")
		)
		(fp_line
			(start 0.7874 0.4064)
			(end -0.7874 0.4064)
			(stroke
				(width 0.1524)
				(type default)
			)
			(layer "F.SilkS")
		)
		(fp_line
			(start -0.7874 -0.4064)
			(end 0.7874 -0.4064)
			(stroke
				(width 0.1524)
				(type default)
			)
			(layer "F.SilkS")
		)
		(fp_line
			(start 0.7874 -0.4064)
			(end 0.7874 0.4064)
			(stroke
				(width 0.1524)
				(type default)
			)
			(layer "F.SilkS")
		)
		(fp_line
			(start -0.67945 0.3048)
			(end -0.67945 -0.305054)
			(stroke
				(width 0.1)
				(type default)
			)
			(layer "F.Fab")
		)
		(fp_line
			(start -0.12065 0.3048)
			(end -0.67945 0.3048)
			(stroke
				(width 0.1)
				(type default)
			)
			(layer "F.Fab")
		)
		(fp_line
			(start 0.120396 0.3048)
			(end 0.120396 0.2794)
			(stroke
				(width 0.1)
				(type default)
			)
			(layer "F.Fab")
		)
		(fp_line
			(start 0.67945 0.3048)
			(end 0.120396 0.3048)
			(stroke
				(width 0.1)
				(type default)
			)
			(layer "F.Fab")
		)
		(fp_line
			(start -0.12065 0.2794)
			(end -0.12065 0.3048)
			(stroke
				(width 0.1)
				(type default)
			)
			(layer "F.Fab")
		)
		(fp_line
			(start 0.120396 0.2794)
			(end -0.12065 0.2794)
			(stroke
				(width 0.1)
				(type default)
			)
			(layer "F.Fab")
		)
		(fp_line
			(start -0.12065 -0.2794)
			(end 0.12065 -0.2794)
			(stroke
				(width 0.1)
				(type default)
			)
			(layer "F.Fab")
		)
		(fp_line
			(start 0.12065 -0.2794)
			(end 0.12065 -0.3048)
			(stroke
				(width 0.1)
				(type default)
			)
			(layer "F.Fab")
		)
		(fp_line
			(start 0.12065 -0.3048)
			(end 0.67945 -0.3048)
			(stroke
				(width 0.1)
				(type default)
			)
			(layer "F.Fab")
		)
		(fp_line
			(start 0.67945 -0.3048)
			(end 0.67945 0.3048)
			(stroke
				(width 0.1)
				(type default)
			)
			(layer "F.Fab")
		)
		(fp_line
			(start -0.67945 -0.305054)
			(end -0.12065 -0.305054)
			(stroke
				(width 0.1)
				(type default)
			)
			(layer "F.Fab")
		)
		(fp_line
			(start -0.12065 -0.305054)
			(end -0.12065 -0.2794)
			(stroke
				(width 0.1)
				(type default)
			)
			(layer "F.Fab")
		)
		(pad "1" smd circle
			(at -0.40005 0 270)
			(size 0 0)
			(layers "F.Cu" "F.Mask" "F.Paste")
			(net "SMB_VR_3V3AUX_SCL_R1")
		)
		(pad "2" smd circle
			(at 0.40005 0 270)
			(size 0 0)
			(layers "F.Cu" "F.Mask" "F.Paste")
			(net "SMB_SEN_MAM_3V3AUX_SCL")
		)
	)
	(footprint ""
		(layer "F.Cu")
		(at 412.585662 -364.563914 90)
		(property "Reference" "PC600"
			(at 0 0 90)
			(layer "F.SilkS")
			(hide yes)
			(effects
				(font
					(size 1.27 1.27)
				)
			)
		)
		(property "Value" ""
			(at 0 0 90)
			(layer "F.Fab")
			(effects
				(font
					(size 1.27 1.27)
				)
			)
		)
		(duplicate_pad_numbers_are_jumpers no)
		(fp_line
			(start 0.7874 -0.4064)
			(end 0.7874 0.4064)
			(stroke
				(width 0.1524)
				(type default)
			)
			(layer "F.SilkS")
		)
		(fp_line
			(start -0.7874 -0.4064)
			(end 0.7874 -0.4064)
			(stroke
				(width 0.1524)
				(type default)
			)
			(layer "F.SilkS")
		)
		(fp_line
			(start 0.7874 0.4064)
			(end -0.7874 0.4064)
			(stroke
				(width 0.1524)
				(type default)
			)
			(layer "F.SilkS")
		)
		(fp_line
			(start -0.7874 0.4064)
			(end -0.7874 -0.4064)
			(stroke
				(width 0.1524)
				(type default)
			)
			(layer "F.SilkS")
		)
		(fp_line
			(start -0.12065 -0.305054)
			(end -0.12065 -0.2794)
			(stroke
				(width 0.1)
				(type default)
			)
			(layer "F.Fab")
		)
		(fp_line
			(start -0.67945 -0.305054)
			(end -0.12065 -0.305054)
			(stroke
				(width 0.1)
				(type default)
			)
			(layer "F.Fab")
		)
		(fp_line
			(start 0.67945 -0.3048)
			(end 0.67945 0.3048)
			(stroke
				(width 0.1)
				(type default)
			)
			(layer "F.Fab")
		)
		(fp_line
			(start 0.12065 -0.3048)
			(end 0.67945 -0.3048)
			(stroke
				(width 0.1)
				(type default)
			)
			(layer "F.Fab")
		)
		(fp_line
			(start 0.12065 -0.2794)
			(end 0.12065 -0.3048)
			(stroke
				(width 0.1)
				(type default)
			)
			(layer "F.Fab")
		)
		(fp_line
			(start -0.12065 -0.2794)
			(end 0.12065 -0.2794)
			(stroke
				(width 0.1)
				(type default)
			)
			(layer "F.Fab")
		)
		(fp_line
			(start 0.120396 0.2794)
			(end -0.12065 0.2794)
			(stroke
				(width 0.1)
				(type default)
			)
			(layer "F.Fab")
		)
		(fp_line
			(start -0.12065 0.2794)
			(end -0.12065 0.3048)
			(stroke
				(width 0.1)
				(type default)
			)
			(layer "F.Fab")
		)
		(fp_line
			(start 0.67945 0.3048)
			(end 0.120396 0.3048)
			(stroke
				(width 0.1)
				(type default)
			)
			(layer "F.Fab")
		)
		(fp_line
			(start 0.120396 0.3048)
			(end 0.120396 0.2794)
			(stroke
				(width 0.1)
				(type default)
			)
			(layer "F.Fab")
		)
		(fp_line
			(start -0.12065 0.3048)
			(end -0.67945 0.3048)
			(stroke
				(width 0.1)
				(type default)
			)
			(layer "F.Fab")
		)
		(fp_line
			(start -0.67945 0.3048)
			(end -0.67945 -0.305054)
			(stroke
				(width 0.1)
				(type default)
			)
			(layer "F.Fab")
		)
		(pad "1" smd circle
			(at -0.40005 0 90)
			(size 0 0)
			(layers "F.Cu" "F.Mask" "F.Paste")
			(net "PVCCFA_EHV_FIVRA_CPU0_VDD1")
		)
		(pad "2" smd circle
			(at 0.40005 0 90)
			(size 0 0)
			(layers "F.Cu" "F.Mask" "F.Paste")
			(net "GND")
		)
	)
	(footprint ""
		(layer "F.Cu")
		(at 352.301048 -249.320304 -90)
		(property "Reference" "C1030"
			(at 0 0 270)
			(layer "F.SilkS")
			(hide yes)
			(effects
				(font
					(size 1.27 1.27)
				)
			)
		)
		(property "Value" ""
			(at 0 0 270)
			(layer "F.Fab")
			(effects
				(font
					(size 1.27 1.27)
				)
			)
		)
		(duplicate_pad_numbers_are_jumpers no)
		(fp_line
			(start -0.7874 0.4064)
			(end -0.7874 -0.4064)
			(stroke
				(width 0.1524)
				(type default)
			)
			(layer "F.SilkS")
		)
		(fp_line
			(start 0.7874 0.4064)
			(end -0.7874 0.4064)
			(stroke
				(width 0.1524)
				(type default)
			)
			(layer "F.SilkS")
		)
		(fp_line
			(start -0.7874 -0.4064)
			(end 0.7874 -0.4064)
			(stroke
				(width 0.1524)
				(type default)
			)
			(layer "F.SilkS")
		)
		(fp_line
			(start 0.7874 -0.4064)
			(end 0.7874 0.4064)
			(stroke
				(width 0.1524)
				(type default)
			)
			(layer "F.SilkS")
		)
		(fp_line
			(start -0.67945 0.3048)
			(end -0.67945 -0.305054)
			(stroke
				(width 0.1)
				(type default)
			)
			(layer "F.Fab")
		)
		(fp_line
			(start -0.12065 0.3048)
			(end -0.67945 0.3048)
			(stroke
				(width 0.1)
				(type default)
			)
			(layer "F.Fab")
		)
		(fp_line
			(start 0.120396 0.3048)
			(end 0.120396 0.2794)
			(stroke
				(width 0.1)
				(type default)
			)
			(layer "F.Fab")
		)
		(fp_line
			(start 0.67945 0.3048)
			(end 0.120396 0.3048)
			(stroke
				(width 0.1)
				(type default)
			)
			(layer "F.Fab")
		)
		(fp_line
			(start -0.12065 0.2794)
			(end -0.12065 0.3048)
			(stroke
				(width 0.1)
				(type default)
			)
			(layer "F.Fab")
		)
		(fp_line
			(start 0.120396 0.2794)
			(end -0.12065 0.2794)
			(stroke
				(width 0.1)
				(type default)
			)
			(layer "F.Fab")
		)
		(fp_line
			(start -0.12065 -0.2794)
			(end 0.12065 -0.2794)
			(stroke
				(width 0.1)
				(type default)
			)
			(layer "F.Fab")
		)
		(fp_line
			(start 0.12065 -0.2794)
			(end 0.12065 -0.3048)
			(stroke
				(width 0.1)
				(type default)
			)
			(layer "F.Fab")
		)
		(fp_line
			(start 0.12065 -0.3048)
			(end 0.67945 -0.3048)
			(stroke
				(width 0.1)
				(type default)
			)
			(layer "F.Fab")
		)
		(fp_line
			(start 0.67945 -0.3048)
			(end 0.67945 0.3048)
			(stroke
				(width 0.1)
				(type default)
			)
			(layer "F.Fab")
		)
		(fp_line
			(start -0.67945 -0.305054)
			(end -0.12065 -0.305054)
			(stroke
				(width 0.1)
				(type default)
			)
			(layer "F.Fab")
		)
		(fp_line
			(start -0.12065 -0.305054)
			(end -0.12065 -0.2794)
			(stroke
				(width 0.1)
				(type default)
			)
			(layer "F.Fab")
		)
		(pad "1" smd circle
			(at -0.40005 0 270)
			(size 0 0)
			(layers "F.Cu" "F.Mask" "F.Paste")
			(net "PVCCIN_CPU0")
		)
		(pad "2" smd circle
			(at 0.40005 0 270)
			(size 0 0)
			(layers "F.Cu" "F.Mask" "F.Paste")
			(net "GND")
		)
	)
	(footprint ""
		(layer "F.Cu")
		(at 514.718808 -303.6316 90)
		(property "Reference" "X8"
			(at -2.734056 3.043682 90)
			(unlocked yes)
			(layer "F.SilkS")
			(effects
				(font
					(size 0.7874 0.5842)
					(thickness 0.1524)
				)
				(justify left)
			)
		)
		(property "Value" ""
			(at 0 0 90)
			(layer "F.Fab")
			(effects
				(font
					(size 1.27 1.27)
				)
			)
		)
		(property "Device Type" "TP_TDR_4P_FTS_MPKT4_H025P0200_I"
			(at 1.30175 1.27 180)
			(unlocked yes)
			(layer "F.Fab")
			(hide yes)
			(effects
				(font
					(size 0.635 0.4064)
					(thickness 0.1524)
				)
			)
		)
		(property "User Part Number" "TP15"
			(at 1.30175 1.27 180)
			(unlocked yes)
			(layer "Cmts.User")
			(hide yes)
			(effects
				(font
					(size 0.635 0.4064)
					(thickness 0.1524)
				)
			)
		)
		(duplicate_pad_numbers_are_jumpers no)
		(fp_line
			(start 2.54 -1.27)
			(end 0 -1.27)
			(stroke
				(width 0.1524)
				(type default)
			)
			(layer "F.SilkS")
		)
		(fp_line
			(start 0 -1.27)
			(end 0 -0.635)
			(stroke
				(width 0.1524)
				(type default)
			)
			(layer "F.SilkS")
		)
		(fp_line
			(start 2.54 -1.1303)
			(end 2.54 -1.27)
			(stroke
				(width 0.1524)
				(type default)
			)
			(layer "F.SilkS")
		)
		(fp_line
			(start 0 0.635)
			(end 0 1.905)
			(stroke
				(width 0.1524)
				(type default)
			)
			(layer "F.SilkS")
		)
		(fp_line
			(start 2.54 1.4097)
			(end 2.54 1.1303)
			(stroke
				(width 0.1524)
				(type default)
			)
			(layer "F.SilkS")
		)
		(fp_line
			(start 0 3.175)
			(end 0 3.81)
			(stroke
				(width 0.1524)
				(type default)
			)
			(layer "F.SilkS")
		)
		(fp_line
			(start 2.54 3.81)
			(end 2.54 3.6703)
			(stroke
				(width 0.1524)
				(type default)
			)
			(layer "F.SilkS")
		)
		(fp_line
			(start 0 3.81)
			(end 2.54 3.81)
			(stroke
				(width 0.1524)
				(type default)
			)
			(layer "F.SilkS")
		)
		(fp_poly
			(pts
				(xy -0.761746 0) (xy -2.285746 0.762) (xy -2.285746 -0.762)
			)
			(stroke
				(width 0)
				(type default)
			)
			(fill yes)
			(layer "F.SilkS")
		)
		(fp_line
			(start 2.54 -1.27)
			(end 0 -1.27)
			(stroke
				(width 0.1)
				(type default)
			)
			(layer "F.Fab")
		)
		(fp_line
			(start 0 -1.27)
			(end 0 3.81)
			(stroke
				(width 0.1)
				(type default)
			)
			(layer "F.Fab")
		)
		(fp_line
			(start 2.54 3.81)
			(end 2.54 -1.27)
			(stroke
				(width 0.1)
				(type default)
			)
			(layer "F.Fab")
		)
		(fp_line
			(start 0 3.81)
			(end 2.54 3.81)
			(stroke
				(width 0.1)
				(type default)
			)
			(layer "F.Fab")
		)
		(fp_poly
			(pts
				(xy -0.761746 0) (xy -2.285746 -0.762) (xy -2.285746 0.762)
			)
			(stroke
				(width 0)
				(type default)
			)
			(fill yes)
			(layer "F.Fab")
		)
		(pad "1" thru_hole circle
			(at 0 0 90)
			(size 1.0033 1.0033)
			(drill 0.249936)
			(layers "*.Cu" "*.Mask")
			(remove_unused_layers no)
			(net "TDR_DIFF_85_IN1_DN")
			(clearance 0.10795)
			(thermal_gap 0.10795)
			(padstack
				(mode front_inner_back)
				(layer "Inner"
					(shape circle)
					(size 0.8001 0.8001)
					(clearance 0.1524)
				)
				(layer "B.Cu"
					(shape circle)
					(size 1.0033 1.0033)
					(clearance 0.10795)
				)
			)
		)
		(pad "2" thru_hole circle
			(at 2.54 0 90)
			(size 1.9939 1.9939)
			(drill 0.249936)
			(layers "*.Cu" "*.Mask")
			(remove_unused_layers no)
			(net "T1_GND")
			(clearance 0.10795)
			(thermal_gap 0.10795)
			(padstack
				(mode front_inner_back)
				(layer "Inner"
					(shape circle)
					(size 0.8001 0.8001)
					(clearance 0.1524)
				)
				(layer "B.Cu"
					(shape circle)
					(size 1.9939 1.9939)
					(clearance 0.10795)
				)
			)
		)
		(pad "3" thru_hole circle
			(at 2.54 2.54 90)
			(size 1.9939 1.9939)
			(drill 0.249936)
			(layers "*.Cu" "*.Mask")
			(remove_unused_layers no)
			(net "T1_GND")
			(clearance 0.10795)
			(thermal_gap 0.10795)
			(padstack
				(mode front_inner_back)
				(layer "Inner"
					(shape circle)
					(size 0.8001 0.8001)
					(clearance 0.1524)
				)
				(layer "B.Cu"
					(shape circle)
					(size 1.9939 1.9939)
					(clearance 0.10795)
				)
			)
		)
		(pad "4" thru_hole circle
			(at 0 2.54 90)
			(size 1.0033 1.0033)
			(drill 0.249936)
			(layers "*.Cu" "*.Mask")
			(remove_unused_layers no)
			(net "TDR_DIFF_85_IN1_DP")
			(clearance 0.10795)
			(thermal_gap 0.10795)
			(padstack
				(mode front_inner_back)
				(layer "Inner"
					(shape circle)
					(size 0.8001 0.8001)
					(clearance 0.1524)
				)
				(layer "B.Cu"
					(shape circle)
					(size 1.0033 1.0033)
					(clearance 0.10795)
				)
			)
		)
	)
	(footprint ""
		(layer "F.Cu")
		(at 143.895318 -114.73434)
		(property "Reference" "C2377"
			(at 0 0 0)
			(layer "F.SilkS")
			(hide yes)
			(effects
				(font
					(size 1.27 1.27)
				)
			)
		)
		(property "Value" ""
			(at 0 0 0)
			(layer "F.Fab")
			(effects
				(font
					(size 1.27 1.27)
				)
			)
		)
		(duplicate_pad_numbers_are_jumpers no)
		(fp_line
			(start -0.7874 -0.4064)
			(end 0.7874 -0.4064)
			(stroke
				(width 0.1524)
				(type default)
			)
			(layer "F.SilkS")
		)
		(fp_line
			(start -0.7874 0.4064)
			(end -0.7874 -0.4064)
			(stroke
				(width 0.1524)
				(type default)
			)
			(layer "F.SilkS")
		)
		(fp_line
			(start 0.7874 -0.4064)
			(end 0.7874 0.4064)
			(stroke
				(width 0.1524)
				(type default)
			)
			(layer "F.SilkS")
		)
		(fp_line
			(start 0.7874 0.4064)
			(end -0.7874 0.4064)
			(stroke
				(width 0.1524)
				(type default)
			)
			(layer "F.SilkS")
		)
		(fp_line
			(start -0.67945 -0.305054)
			(end -0.12065 -0.305054)
			(stroke
				(width 0.1)
				(type default)
			)
			(layer "F.Fab")
		)
		(fp_line
			(start -0.67945 0.3048)
			(end -0.67945 -0.305054)
			(stroke
				(width 0.1)
				(type default)
			)
			(layer "F.Fab")
		)
		(fp_line
			(start -0.12065 -0.305054)
			(end -0.12065 -0.2794)
			(stroke
				(width 0.1)
				(type default)
			)
			(layer "F.Fab")
		)
		(fp_line
			(start -0.12065 -0.2794)
			(end 0.12065 -0.2794)
			(stroke
				(width 0.1)
				(type default)
			)
			(layer "F.Fab")
		)
		(fp_line
			(start -0.12065 0.2794)
			(end -0.12065 0.3048)
			(stroke
				(width 0.1)
				(type default)
			)
			(layer "F.Fab")
		)
		(fp_line
			(start -0.12065 0.3048)
			(end -0.67945 0.3048)
			(stroke
				(width 0.1)
				(type default)
			)
			(layer "F.Fab")
		)
		(fp_line
			(start 0.120396 0.2794)
			(end -0.12065 0.2794)
			(stroke
				(width 0.1)
				(type default)
			)
			(layer "F.Fab")
		)
		(fp_line
			(start 0.120396 0.3048)
			(end 0.120396 0.2794)
			(stroke
				(width 0.1)
				(type default)
			)
			(layer "F.Fab")
		)
		(fp_line
			(start 0.12065 -0.3048)
			(end 0.67945 -0.3048)
			(stroke
				(width 0.1)
				(type default)
			)
			(layer "F.Fab")
		)
		(fp_line
			(start 0.12065 -0.2794)
			(end 0.12065 -0.3048)
			(stroke
				(width 0.1)
				(type default)
			)
			(layer "F.Fab")
		)
		(fp_line
			(start 0.67945 -0.3048)
			(end 0.67945 0.3048)
			(stroke
				(width 0.1)
				(type default)
			)
			(layer "F.Fab")
		)
		(fp_line
			(start 0.67945 0.3048)
			(end 0.120396 0.3048)
			(stroke
				(width 0.1)
				(type default)
			)
			(layer "F.Fab")
		)
		(pad "1" smd circle
			(at -0.40005 0)
			(size 0 0)
			(layers "F.Cu" "F.Mask" "F.Paste")
			(net "P3V3_AUX")
		)
		(pad "2" smd circle
			(at 0.40005 0)
			(size 0 0)
			(layers "F.Cu" "F.Mask" "F.Paste")
			(net "GND")
		)
	)
	(footprint ""
		(layer "F.Cu")
		(at 90.09888 -57.368948 180)
		(property "Reference" "R3025"
			(at 0 0 180)
			(layer "F.SilkS")
			(hide yes)
			(effects
				(font
					(size 1.27 1.27)
				)
			)
		)
		(property "Value" ""
			(at 0 0 180)
			(layer "F.Fab")
			(effects
				(font
					(size 1.27 1.27)
				)
			)
		)
		(duplicate_pad_numbers_are_jumpers no)
		(fp_line
			(start 0.7874 0.4064)
			(end -0.7874 0.4064)
			(stroke
				(width 0.1524)
				(type default)
			)
			(layer "F.SilkS")
		)
		(fp_line
			(start 0.7874 -0.4064)
			(end 0.7874 0.4064)
			(stroke
				(width 0.1524)
				(type default)
			)
			(layer "F.SilkS")
		)
		(fp_line
			(start -0.7874 0.4064)
			(end -0.7874 -0.4064)
			(stroke
				(width 0.1524)
				(type default)
			)
			(layer "F.SilkS")
		)
		(fp_line
			(start -0.7874 -0.4064)
			(end 0.7874 -0.4064)
			(stroke
				(width 0.1524)
				(type default)
			)
			(layer "F.SilkS")
		)
		(fp_line
			(start 0.67945 0.3048)
			(end 0.120396 0.3048)
			(stroke
				(width 0.1)
				(type default)
			)
			(layer "F.Fab")
		)
		(fp_line
			(start 0.67945 -0.3048)
			(end 0.67945 0.3048)
			(stroke
				(width 0.1)
				(type default)
			)
			(layer "F.Fab")
		)
		(fp_line
			(start 0.12065 -0.2794)
			(end 0.12065 -0.3048)
			(stroke
				(width 0.1)
				(type default)
			)
			(layer "F.Fab")
		)
		(fp_line
			(start 0.12065 -0.3048)
			(end 0.67945 -0.3048)
			(stroke
				(width 0.1)
				(type default)
			)
			(layer "F.Fab")
		)
		(fp_line
			(start 0.120396 0.3048)
			(end 0.120396 0.2794)
			(stroke
				(width 0.1)
				(type default)
			)
			(layer "F.Fab")
		)
		(fp_line
			(start 0.120396 0.2794)
			(end -0.12065 0.2794)
			(stroke
				(width 0.1)
				(type default)
			)
			(layer "F.Fab")
		)
		(fp_line
			(start -0.12065 0.3048)
			(end -0.67945 0.3048)
			(stroke
				(width 0.1)
				(type default)
			)
			(layer "F.Fab")
		)
		(fp_line
			(start -0.12065 0.2794)
			(end -0.12065 0.3048)
			(stroke
				(width 0.1)
				(type default)
			)
			(layer "F.Fab")
		)
		(fp_line
			(start -0.12065 -0.2794)
			(end 0.12065 -0.2794)
			(stroke
				(width 0.1)
				(type default)
			)
			(layer "F.Fab")
		)
		(fp_line
			(start -0.12065 -0.305054)
			(end -0.12065 -0.2794)
			(stroke
				(width 0.1)
				(type default)
			)
			(layer "F.Fab")
		)
		(fp_line
			(start -0.67945 0.3048)
			(end -0.67945 -0.305054)
			(stroke
				(width 0.1)
				(type default)
			)
			(layer "F.Fab")
		)
		(fp_line
			(start -0.67945 -0.305054)
			(end -0.12065 -0.305054)
			(stroke
				(width 0.1)
				(type default)
			)
			(layer "F.Fab")
		)
		(pad "1" smd circle
			(at -0.40005 0 180)
			(size 0 0)
			(layers "F.Cu" "F.Mask" "F.Paste")
			(net "FM_REMOTE_DEBUG_DET_R")
		)
		(pad "2" smd circle
			(at 0.40005 0 180)
			(size 0 0)
			(layers "F.Cu" "F.Mask" "F.Paste")
			(net "GND")
		)
	)
	(footprint ""
		(layer "F.Cu")
		(at 157.08884 -31.341568 -90)
		(property "Reference" "R4466"
			(at 0 0 270)
			(layer "F.SilkS")
			(hide yes)
			(effects
				(font
					(size 1.27 1.27)
				)
			)
		)
		(property "Value" ""
			(at 0 0 270)
			(layer "F.Fab")
			(effects
				(font
					(size 1.27 1.27)
				)
			)
		)
		(duplicate_pad_numbers_are_jumpers no)
		(fp_line
			(start -0.7874 0.4064)
			(end -0.7874 -0.4064)
			(stroke
				(width 0.1524)
				(type default)
			)
			(layer "F.SilkS")
		)
		(fp_line
			(start 0.7874 0.4064)
			(end -0.7874 0.4064)
			(stroke
				(width 0.1524)
				(type default)
			)
			(layer "F.SilkS")
		)
		(fp_line
			(start -0.7874 -0.4064)
			(end 0.7874 -0.4064)
			(stroke
				(width 0.1524)
				(type default)
			)
			(layer "F.SilkS")
		)
		(fp_line
			(start 0.7874 -0.4064)
			(end 0.7874 0.4064)
			(stroke
				(width 0.1524)
				(type default)
			)
			(layer "F.SilkS")
		)
		(fp_line
			(start -0.67945 0.3048)
			(end -0.67945 -0.305054)
			(stroke
				(width 0.1)
				(type default)
			)
			(layer "F.Fab")
		)
		(fp_line
			(start -0.12065 0.3048)
			(end -0.67945 0.3048)
			(stroke
				(width 0.1)
				(type default)
			)
			(layer "F.Fab")
		)
		(fp_line
			(start 0.120396 0.3048)
			(end 0.120396 0.2794)
			(stroke
				(width 0.1)
				(type default)
			)
			(layer "F.Fab")
		)
		(fp_line
			(start 0.67945 0.3048)
			(end 0.120396 0.3048)
			(stroke
				(width 0.1)
				(type default)
			)
			(layer "F.Fab")
		)
		(fp_line
			(start -0.12065 0.2794)
			(end -0.12065 0.3048)
			(stroke
				(width 0.1)
				(type default)
			)
			(layer "F.Fab")
		)
		(fp_line
			(start 0.120396 0.2794)
			(end -0.12065 0.2794)
			(stroke
				(width 0.1)
				(type default)
			)
			(layer "F.Fab")
		)
		(fp_line
			(start -0.12065 -0.2794)
			(end 0.12065 -0.2794)
			(stroke
				(width 0.1)
				(type default)
			)
			(layer "F.Fab")
		)
		(fp_line
			(start 0.12065 -0.2794)
			(end 0.12065 -0.3048)
			(stroke
				(width 0.1)
				(type default)
			)
			(layer "F.Fab")
		)
		(fp_line
			(start 0.12065 -0.3048)
			(end 0.67945 -0.3048)
			(stroke
				(width 0.1)
				(type default)
			)
			(layer "F.Fab")
		)
		(fp_line
			(start 0.67945 -0.3048)
			(end 0.67945 0.3048)
			(stroke
				(width 0.1)
				(type default)
			)
			(layer "F.Fab")
		)
		(fp_line
			(start -0.67945 -0.305054)
			(end -0.12065 -0.305054)
			(stroke
				(width 0.1)
				(type default)
			)
			(layer "F.Fab")
		)
		(fp_line
			(start -0.12065 -0.305054)
			(end -0.12065 -0.2794)
			(stroke
				(width 0.1)
				(type default)
			)
			(layer "F.Fab")
		)
		(pad "1" smd circle
			(at -0.40005 0 270)
			(size 0 0)
			(layers "F.Cu" "F.Mask" "F.Paste")
			(net "USB_HUB_2_TEST")
		)
		(pad "2" smd circle
			(at 0.40005 0 270)
			(size 0 0)
			(layers "F.Cu" "F.Mask" "F.Paste")
			(net "GND")
		)
	)
	(footprint ""
		(layer "F.Cu")
		(at 377.52401 -402.371052 -90)
		(property "Reference" "C939"
			(at 0 0 270)
			(layer "F.SilkS")
			(hide yes)
			(effects
				(font
					(size 1.27 1.27)
				)
			)
		)
		(property "Value" ""
			(at 0 0 270)
			(layer "F.Fab")
			(effects
				(font
					(size 1.27 1.27)
				)
			)
		)
		(duplicate_pad_numbers_are_jumpers no)
		(fp_line
			(start -0.299974 0.150114)
			(end -0.299974 -0.150114)
			(stroke
				(width 0.1)
				(type default)
			)
			(layer "F.Fab")
		)
		(fp_line
			(start 0.299974 0.150114)
			(end -0.299974 0.150114)
			(stroke
				(width 0.1)
				(type default)
			)
			(layer "F.Fab")
		)
		(fp_line
			(start -0.299974 -0.150114)
			(end 0.299974 -0.150114)
			(stroke
				(width 0.1)
				(type default)
			)
			(layer "F.Fab")
		)
		(fp_line
			(start 0.299974 -0.150114)
			(end 0.299974 0.150114)
			(stroke
				(width 0.1)
				(type default)
			)
			(layer "F.Fab")
		)
		(pad "1" smd rect
			(at -0.2667 0 270)
			(size 0.3048 0.381)
			(layers "F.Cu" "F.Mask" "F.Paste")
			(net "P5E_CPU0_PE2_TX_C_DP<13>")
		)
		(pad "2" smd rect
			(at 0.2667 0 270)
			(size 0.3048 0.381)
			(layers "F.Cu" "F.Mask" "F.Paste")
			(net "P5E_CPU0_PE2_TX_DP<13>")
		)
	)
	(footprint ""
		(layer "F.Cu")
		(at 183.878982 -34.794952 90)
		(property "Reference" "PC2231"
			(at 0 0 90)
			(layer "F.SilkS")
			(hide yes)
			(effects
				(font
					(size 1.27 1.27)
				)
			)
		)
		(property "Value" ""
			(at 0 0 90)
			(layer "F.Fab")
			(effects
				(font
					(size 1.27 1.27)
				)
			)
		)
		(duplicate_pad_numbers_are_jumpers no)
		(fp_line
			(start 0.7874 -0.4064)
			(end 0.7874 0.4064)
			(stroke
				(width 0.1524)
				(type default)
			)
			(layer "F.SilkS")
		)
		(fp_line
			(start -0.7874 -0.4064)
			(end 0.7874 -0.4064)
			(stroke
				(width 0.1524)
				(type default)
			)
			(layer "F.SilkS")
		)
		(fp_line
			(start 0.7874 0.4064)
			(end -0.7874 0.4064)
			(stroke
				(width 0.1524)
				(type default)
			)
			(layer "F.SilkS")
		)
		(fp_line
			(start -0.7874 0.4064)
			(end -0.7874 -0.4064)
			(stroke
				(width 0.1524)
				(type default)
			)
			(layer "F.SilkS")
		)
		(fp_line
			(start -0.12065 -0.305054)
			(end -0.12065 -0.2794)
			(stroke
				(width 0.1)
				(type default)
			)
			(layer "F.Fab")
		)
		(fp_line
			(start -0.67945 -0.305054)
			(end -0.12065 -0.305054)
			(stroke
				(width 0.1)
				(type default)
			)
			(layer "F.Fab")
		)
		(fp_line
			(start 0.67945 -0.3048)
			(end 0.67945 0.3048)
			(stroke
				(width 0.1)
				(type default)
			)
			(layer "F.Fab")
		)
		(fp_line
			(start 0.12065 -0.3048)
			(end 0.67945 -0.3048)
			(stroke
				(width 0.1)
				(type default)
			)
			(layer "F.Fab")
		)
		(fp_line
			(start 0.12065 -0.2794)
			(end 0.12065 -0.3048)
			(stroke
				(width 0.1)
				(type default)
			)
			(layer "F.Fab")
		)
		(fp_line
			(start -0.12065 -0.2794)
			(end 0.12065 -0.2794)
			(stroke
				(width 0.1)
				(type default)
			)
			(layer "F.Fab")
		)
		(fp_line
			(start 0.120396 0.2794)
			(end -0.12065 0.2794)
			(stroke
				(width 0.1)
				(type default)
			)
			(layer "F.Fab")
		)
		(fp_line
			(start -0.12065 0.2794)
			(end -0.12065 0.3048)
			(stroke
				(width 0.1)
				(type default)
			)
			(layer "F.Fab")
		)
		(fp_line
			(start 0.67945 0.3048)
			(end 0.120396 0.3048)
			(stroke
				(width 0.1)
				(type default)
			)
			(layer "F.Fab")
		)
		(fp_line
			(start 0.120396 0.3048)
			(end 0.120396 0.2794)
			(stroke
				(width 0.1)
				(type default)
			)
			(layer "F.Fab")
		)
		(fp_line
			(start -0.12065 0.3048)
			(end -0.67945 0.3048)
			(stroke
				(width 0.1)
				(type default)
			)
			(layer "F.Fab")
		)
		(fp_line
			(start -0.67945 0.3048)
			(end -0.67945 -0.305054)
			(stroke
				(width 0.1)
				(type default)
			)
			(layer "F.Fab")
		)
		(pad "1" smd circle
			(at -0.40005 0 90)
			(size 0 0)
			(layers "F.Cu" "F.Mask" "F.Paste")
			(net "P12V_AUX")
		)
		(pad "2" smd circle
			(at 0.40005 0 90)
			(size 0 0)
			(layers "F.Cu" "F.Mask" "F.Paste")
			(net "GND")
		)
	)
	(footprint ""
		(layer "F.Cu")
		(at 113.349024 -324.445376)
		(property "Reference" "PL29"
			(at 15.954756 6.788658 0)
			(unlocked yes)
			(layer "F.SilkS")
			(effects
				(font
					(size 0.7874 0.5842)
					(thickness 0.1524)
				)
				(justify left)
			)
		)
		(property "Value" ""
			(at 0 0 0)
			(layer "F.Fab")
			(effects
				(font
					(size 1.27 1.27)
				)
			)
		)
		(duplicate_pad_numbers_are_jumpers no)
		(fp_line
			(start -3.750056 -5.500116)
			(end -2.393442 -5.500116)
			(stroke
				(width 0.1524)
				(type default)
			)
			(layer "F.SilkS")
		)
		(fp_line
			(start -3.750056 5.500116)
			(end -3.750056 -5.500116)
			(stroke
				(width 0.1524)
				(type default)
			)
			(layer "F.SilkS")
		)
		(fp_line
			(start -2.393442 5.500116)
			(end -3.750056 5.500116)
			(stroke
				(width 0.1524)
				(type default)
			)
			(layer "F.SilkS")
		)
		(fp_line
			(start 2.393442 5.500116)
			(end 3.750056 5.500116)
			(stroke
				(width 0.1524)
				(type default)
			)
			(layer "F.SilkS")
		)
		(fp_line
			(start 3.750056 -5.500116)
			(end 2.393442 -5.500116)
			(stroke
				(width 0.1524)
				(type default)
			)
			(layer "F.SilkS")
		)
		(fp_line
			(start 3.750056 5.500116)
			(end 3.750056 -5.500116)
			(stroke
				(width 0.1524)
				(type default)
			)
			(layer "F.SilkS")
		)
		(fp_poly
			(pts
				(xy -3.554476 -7.016496) (xy -3.19532 -5.938774) (xy -4.273042 -6.29793)
			)
			(stroke
				(width 0)
				(type default)
			)
			(fill yes)
			(layer "F.SilkS")
		)
		(fp_line
			(start -3.750056 -5.500116)
			(end -3.750056 5.500116)
			(stroke
				(width 0.1)
				(type default)
			)
			(layer "F.Fab")
		)
		(fp_line
			(start -3.750056 5.500116)
			(end 3.750056 5.500116)
			(stroke
				(width 0.1)
				(type default)
			)
			(layer "F.Fab")
		)
		(fp_line
			(start 3.750056 -5.500116)
			(end -3.750056 -5.500116)
			(stroke
				(width 0.1)
				(type default)
			)
			(layer "F.Fab")
		)
		(fp_line
			(start 3.750056 5.500116)
			(end 3.750056 -5.500116)
			(stroke
				(width 0.1)
				(type default)
			)
			(layer "F.Fab")
		)
		(fp_poly
			(pts
				(xy -4.9276 -4.757928) (xy -4.9276 -3.741928) (xy -3.9116 -4.249928)
			)
			(stroke
				(width 0)
				(type default)
			)
			(fill yes)
			(layer "F.Fab")
		)
		(pad "1" smd rect
			(at 0 -4.249928 270)
			(size 2.413 4.5212)
			(layers "F.Cu" "F.Mask" "F.Paste")
			(net "SW_PVCCIN_CPU1_SW3")
		)
		(pad "2" smd rect
			(at 0 -1.175004 270)
			(size 1.3716 4.5212)
			(layers "F.Cu" "F.Mask" "F.Paste")
			(net "IND_P1_CPL3")
		)
		(pad "3" smd rect
			(at 0 1.175004 270)
			(size 1.3716 4.5212)
			(layers "F.Cu" "F.Mask" "F.Paste")
			(net "IND_P1_CPL2")
		)
		(pad "4" smd rect
			(at 0 4.249928 270)
			(size 2.413 4.5212)
			(layers "F.Cu" "F.Mask" "F.Paste")
			(net "PVCCIN_CPU1")
		)
	)
	(footprint ""
		(layer "F.Cu")
		(at 149.68982 -22.73808 90)
		(property "Reference" "R3778"
			(at 0 0 90)
			(layer "F.SilkS")
			(hide yes)
			(effects
				(font
					(size 1.27 1.27)
				)
			)
		)
		(property "Value" ""
			(at 0 0 90)
			(layer "F.Fab")
			(effects
				(font
					(size 1.27 1.27)
				)
			)
		)
		(duplicate_pad_numbers_are_jumpers no)
		(fp_line
			(start 0.7874 -0.4064)
			(end 0.7874 0.4064)
			(stroke
				(width 0.1524)
				(type default)
			)
			(layer "F.SilkS")
		)
		(fp_line
			(start -0.7874 -0.4064)
			(end 0.7874 -0.4064)
			(stroke
				(width 0.1524)
				(type default)
			)
			(layer "F.SilkS")
		)
		(fp_line
			(start 0.7874 0.4064)
			(end -0.7874 0.4064)
			(stroke
				(width 0.1524)
				(type default)
			)
			(layer "F.SilkS")
		)
		(fp_line
			(start -0.7874 0.4064)
			(end -0.7874 -0.4064)
			(stroke
				(width 0.1524)
				(type default)
			)
			(layer "F.SilkS")
		)
		(fp_line
			(start -0.12065 -0.305054)
			(end -0.12065 -0.2794)
			(stroke
				(width 0.1)
				(type default)
			)
			(layer "F.Fab")
		)
		(fp_line
			(start -0.67945 -0.305054)
			(end -0.12065 -0.305054)
			(stroke
				(width 0.1)
				(type default)
			)
			(layer "F.Fab")
		)
		(fp_line
			(start 0.67945 -0.3048)
			(end 0.67945 0.3048)
			(stroke
				(width 0.1)
				(type default)
			)
			(layer "F.Fab")
		)
		(fp_line
			(start 0.12065 -0.3048)
			(end 0.67945 -0.3048)
			(stroke
				(width 0.1)
				(type default)
			)
			(layer "F.Fab")
		)
		(fp_line
			(start 0.12065 -0.2794)
			(end 0.12065 -0.3048)
			(stroke
				(width 0.1)
				(type default)
			)
			(layer "F.Fab")
		)
		(fp_line
			(start -0.12065 -0.2794)
			(end 0.12065 -0.2794)
			(stroke
				(width 0.1)
				(type default)
			)
			(layer "F.Fab")
		)
		(fp_line
			(start 0.120396 0.2794)
			(end -0.12065 0.2794)
			(stroke
				(width 0.1)
				(type default)
			)
			(layer "F.Fab")
		)
		(fp_line
			(start -0.12065 0.2794)
			(end -0.12065 0.3048)
			(stroke
				(width 0.1)
				(type default)
			)
			(layer "F.Fab")
		)
		(fp_line
			(start 0.67945 0.3048)
			(end 0.120396 0.3048)
			(stroke
				(width 0.1)
				(type default)
			)
			(layer "F.Fab")
		)
		(fp_line
			(start 0.120396 0.3048)
			(end 0.120396 0.2794)
			(stroke
				(width 0.1)
				(type default)
			)
			(layer "F.Fab")
		)
		(fp_line
			(start -0.12065 0.3048)
			(end -0.67945 0.3048)
			(stroke
				(width 0.1)
				(type default)
			)
			(layer "F.Fab")
		)
		(fp_line
			(start -0.67945 0.3048)
			(end -0.67945 -0.305054)
			(stroke
				(width 0.1)
				(type default)
			)
			(layer "F.Fab")
		)
		(pad "1" smd circle
			(at -0.40005 0 90)
			(size 0 0)
			(layers "F.Cu" "F.Mask" "F.Paste")
			(net "FM_SOL_UART_CH_SEL_R")
		)
		(pad "2" smd circle
			(at 0.40005 0 90)
			(size 0 0)
			(layers "F.Cu" "F.Mask" "F.Paste")
			(net "FM_SOL_UART_CH_SEL")
		)
	)
	(footprint ""
		(layer "F.Cu")
		(at 356.616 -417.159948 180)
		(property "Reference" "R4559"
			(at 0 0 180)
			(layer "F.SilkS")
			(hide yes)
			(effects
				(font
					(size 1.27 1.27)
				)
			)
		)
		(property "Value" ""
			(at 0 0 180)
			(layer "F.Fab")
			(effects
				(font
					(size 1.27 1.27)
				)
			)
		)
		(duplicate_pad_numbers_are_jumpers no)
		(fp_line
			(start 0.7874 0.4064)
			(end -0.7874 0.4064)
			(stroke
				(width 0.1524)
				(type default)
			)
			(layer "F.SilkS")
		)
		(fp_line
			(start 0.7874 -0.4064)
			(end 0.7874 0.4064)
			(stroke
				(width 0.1524)
				(type default)
			)
			(layer "F.SilkS")
		)
		(fp_line
			(start -0.7874 0.4064)
			(end -0.7874 -0.4064)
			(stroke
				(width 0.1524)
				(type default)
			)
			(layer "F.SilkS")
		)
		(fp_line
			(start -0.7874 -0.4064)
			(end 0.7874 -0.4064)
			(stroke
				(width 0.1524)
				(type default)
			)
			(layer "F.SilkS")
		)
		(fp_line
			(start 0.67945 0.3048)
			(end 0.120396 0.3048)
			(stroke
				(width 0.1)
				(type default)
			)
			(layer "F.Fab")
		)
		(fp_line
			(start 0.67945 -0.3048)
			(end 0.67945 0.3048)
			(stroke
				(width 0.1)
				(type default)
			)
			(layer "F.Fab")
		)
		(fp_line
			(start 0.12065 -0.2794)
			(end 0.12065 -0.3048)
			(stroke
				(width 0.1)
				(type default)
			)
			(layer "F.Fab")
		)
		(fp_line
			(start 0.12065 -0.3048)
			(end 0.67945 -0.3048)
			(stroke
				(width 0.1)
				(type default)
			)
			(layer "F.Fab")
		)
		(fp_line
			(start 0.120396 0.3048)
			(end 0.120396 0.2794)
			(stroke
				(width 0.1)
				(type default)
			)
			(layer "F.Fab")
		)
		(fp_line
			(start 0.120396 0.2794)
			(end -0.12065 0.2794)
			(stroke
				(width 0.1)
				(type default)
			)
			(layer "F.Fab")
		)
		(fp_line
			(start -0.12065 0.3048)
			(end -0.67945 0.3048)
			(stroke
				(width 0.1)
				(type default)
			)
			(layer "F.Fab")
		)
		(fp_line
			(start -0.12065 0.2794)
			(end -0.12065 0.3048)
			(stroke
				(width 0.1)
				(type default)
			)
			(layer "F.Fab")
		)
		(fp_line
			(start -0.12065 -0.2794)
			(end 0.12065 -0.2794)
			(stroke
				(width 0.1)
				(type default)
			)
			(layer "F.Fab")
		)
		(fp_line
			(start -0.12065 -0.305054)
			(end -0.12065 -0.2794)
			(stroke
				(width 0.1)
				(type default)
			)
			(layer "F.Fab")
		)
		(fp_line
			(start -0.67945 0.3048)
			(end -0.67945 -0.305054)
			(stroke
				(width 0.1)
				(type default)
			)
			(layer "F.Fab")
		)
		(fp_line
			(start -0.67945 -0.305054)
			(end -0.12065 -0.305054)
			(stroke
				(width 0.1)
				(type default)
			)
			(layer "F.Fab")
		)
		(pad "1" smd circle
			(at -0.40005 0 180)
			(size 0 0)
			(layers "F.Cu" "F.Mask" "F.Paste")
			(net "SWB_HSC_PWRGD")
		)
		(pad "2" smd circle
			(at 0.40005 0 180)
			(size 0 0)
			(layers "F.Cu" "F.Mask" "F.Paste")
			(net "GND")
		)
	)
	(footprint ""
		(layer "F.Cu")
		(at 422.509188 -154.251914 180)
		(property "Reference" "PC1348"
			(at 0 0 180)
			(layer "F.SilkS")
			(hide yes)
			(effects
				(font
					(size 1.27 1.27)
				)
			)
		)
		(property "Value" ""
			(at 0 0 180)
			(layer "F.Fab")
			(effects
				(font
					(size 1.27 1.27)
				)
			)
		)
		(duplicate_pad_numbers_are_jumpers no)
		(fp_line
			(start 0.7874 0.4064)
			(end -0.7874 0.4064)
			(stroke
				(width 0.1524)
				(type default)
			)
			(layer "F.SilkS")
		)
		(fp_line
			(start 0.7874 -0.4064)
			(end 0.7874 0.4064)
			(stroke
				(width 0.1524)
				(type default)
			)
			(layer "F.SilkS")
		)
		(fp_line
			(start -0.7874 0.4064)
			(end -0.7874 -0.4064)
			(stroke
				(width 0.1524)
				(type default)
			)
			(layer "F.SilkS")
		)
		(fp_line
			(start -0.7874 -0.4064)
			(end 0.7874 -0.4064)
			(stroke
				(width 0.1524)
				(type default)
			)
			(layer "F.SilkS")
		)
		(fp_line
			(start 0.67945 0.3048)
			(end 0.120396 0.3048)
			(stroke
				(width 0.1)
				(type default)
			)
			(layer "F.Fab")
		)
		(fp_line
			(start 0.67945 -0.3048)
			(end 0.67945 0.3048)
			(stroke
				(width 0.1)
				(type default)
			)
			(layer "F.Fab")
		)
		(fp_line
			(start 0.12065 -0.2794)
			(end 0.12065 -0.3048)
			(stroke
				(width 0.1)
				(type default)
			)
			(layer "F.Fab")
		)
		(fp_line
			(start 0.12065 -0.3048)
			(end 0.67945 -0.3048)
			(stroke
				(width 0.1)
				(type default)
			)
			(layer "F.Fab")
		)
		(fp_line
			(start 0.120396 0.3048)
			(end 0.120396 0.2794)
			(stroke
				(width 0.1)
				(type default)
			)
			(layer "F.Fab")
		)
		(fp_line
			(start 0.120396 0.2794)
			(end -0.12065 0.2794)
			(stroke
				(width 0.1)
				(type default)
			)
			(layer "F.Fab")
		)
		(fp_line
			(start -0.12065 0.3048)
			(end -0.67945 0.3048)
			(stroke
				(width 0.1)
				(type default)
			)
			(layer "F.Fab")
		)
		(fp_line
			(start -0.12065 0.2794)
			(end -0.12065 0.3048)
			(stroke
				(width 0.1)
				(type default)
			)
			(layer "F.Fab")
		)
		(fp_line
			(start -0.12065 -0.2794)
			(end 0.12065 -0.2794)
			(stroke
				(width 0.1)
				(type default)
			)
			(layer "F.Fab")
		)
		(fp_line
			(start -0.12065 -0.305054)
			(end -0.12065 -0.2794)
			(stroke
				(width 0.1)
				(type default)
			)
			(layer "F.Fab")
		)
		(fp_line
			(start -0.67945 0.3048)
			(end -0.67945 -0.305054)
			(stroke
				(width 0.1)
				(type default)
			)
			(layer "F.Fab")
		)
		(fp_line
			(start -0.67945 -0.305054)
			(end -0.12065 -0.305054)
			(stroke
				(width 0.1)
				(type default)
			)
			(layer "F.Fab")
		)
		(pad "1" smd circle
			(at -0.40005 0 180)
			(size 0 0)
			(layers "F.Cu" "F.Mask" "F.Paste")
			(net "GND")
		)
		(pad "2" smd circle
			(at 0.40005 0 180)
			(size 0 0)
			(layers "F.Cu" "F.Mask" "F.Paste")
			(net "PVCCINFAON_CPU0_VREF")
		)
	)
	(footprint ""
		(layer "F.Cu")
		(at 118.49608 -119.846598 90)
		(property "Reference" "R4053"
			(at 0 0 90)
			(layer "F.SilkS")
			(hide yes)
			(effects
				(font
					(size 1.27 1.27)
				)
			)
		)
		(property "Value" ""
			(at 0 0 90)
			(layer "F.Fab")
			(effects
				(font
					(size 1.27 1.27)
				)
			)
		)
		(duplicate_pad_numbers_are_jumpers no)
		(fp_line
			(start 0.7874 -0.4064)
			(end 0.7874 0.4064)
			(stroke
				(width 0.1524)
				(type default)
			)
			(layer "F.SilkS")
		)
		(fp_line
			(start -0.7874 -0.4064)
			(end 0.7874 -0.4064)
			(stroke
				(width 0.1524)
				(type default)
			)
			(layer "F.SilkS")
		)
		(fp_line
			(start 0.7874 0.4064)
			(end -0.7874 0.4064)
			(stroke
				(width 0.1524)
				(type default)
			)
			(layer "F.SilkS")
		)
		(fp_line
			(start -0.7874 0.4064)
			(end -0.7874 -0.4064)
			(stroke
				(width 0.1524)
				(type default)
			)
			(layer "F.SilkS")
		)
		(fp_line
			(start -0.12065 -0.305054)
			(end -0.12065 -0.2794)
			(stroke
				(width 0.1)
				(type default)
			)
			(layer "F.Fab")
		)
		(fp_line
			(start -0.67945 -0.305054)
			(end -0.12065 -0.305054)
			(stroke
				(width 0.1)
				(type default)
			)
			(layer "F.Fab")
		)
		(fp_line
			(start 0.67945 -0.3048)
			(end 0.67945 0.3048)
			(stroke
				(width 0.1)
				(type default)
			)
			(layer "F.Fab")
		)
		(fp_line
			(start 0.12065 -0.3048)
			(end 0.67945 -0.3048)
			(stroke
				(width 0.1)
				(type default)
			)
			(layer "F.Fab")
		)
		(fp_line
			(start 0.12065 -0.2794)
			(end 0.12065 -0.3048)
			(stroke
				(width 0.1)
				(type default)
			)
			(layer "F.Fab")
		)
		(fp_line
			(start -0.12065 -0.2794)
			(end 0.12065 -0.2794)
			(stroke
				(width 0.1)
				(type default)
			)
			(layer "F.Fab")
		)
		(fp_line
			(start 0.120396 0.2794)
			(end -0.12065 0.2794)
			(stroke
				(width 0.1)
				(type default)
			)
			(layer "F.Fab")
		)
		(fp_line
			(start -0.12065 0.2794)
			(end -0.12065 0.3048)
			(stroke
				(width 0.1)
				(type default)
			)
			(layer "F.Fab")
		)
		(fp_line
			(start 0.67945 0.3048)
			(end 0.120396 0.3048)
			(stroke
				(width 0.1)
				(type default)
			)
			(layer "F.Fab")
		)
		(fp_line
			(start 0.120396 0.3048)
			(end 0.120396 0.2794)
			(stroke
				(width 0.1)
				(type default)
			)
			(layer "F.Fab")
		)
		(fp_line
			(start -0.12065 0.3048)
			(end -0.67945 0.3048)
			(stroke
				(width 0.1)
				(type default)
			)
			(layer "F.Fab")
		)
		(fp_line
			(start -0.67945 0.3048)
			(end -0.67945 -0.305054)
			(stroke
				(width 0.1)
				(type default)
			)
			(layer "F.Fab")
		)
		(pad "1" smd circle
			(at -0.40005 0 90)
			(size 0 0)
			(layers "F.Cu" "F.Mask" "F.Paste")
			(net "PD_GTL2014_BMC_JTAG_DIR_0")
		)
		(pad "2" smd circle
			(at 0.40005 0 90)
			(size 0 0)
			(layers "F.Cu" "F.Mask" "F.Paste")
			(net "GND")
		)
	)
	(footprint ""
		(layer "F.Cu")
		(at 169.57294 -28.425648 -90)
		(property "Reference" "R4176"
			(at 0 0 270)
			(layer "F.SilkS")
			(hide yes)
			(effects
				(font
					(size 1.27 1.27)
				)
			)
		)
		(property "Value" ""
			(at 0 0 270)
			(layer "F.Fab")
			(effects
				(font
					(size 1.27 1.27)
				)
			)
		)
		(duplicate_pad_numbers_are_jumpers no)
		(fp_line
			(start -0.7874 0.4064)
			(end -0.7874 -0.4064)
			(stroke
				(width 0.1524)
				(type default)
			)
			(layer "F.SilkS")
		)
		(fp_line
			(start 0.7874 0.4064)
			(end -0.7874 0.4064)
			(stroke
				(width 0.1524)
				(type default)
			)
			(layer "F.SilkS")
		)
		(fp_line
			(start -0.7874 -0.4064)
			(end 0.7874 -0.4064)
			(stroke
				(width 0.1524)
				(type default)
			)
			(layer "F.SilkS")
		)
		(fp_line
			(start 0.7874 -0.4064)
			(end 0.7874 0.4064)
			(stroke
				(width 0.1524)
				(type default)
			)
			(layer "F.SilkS")
		)
		(fp_line
			(start -0.67945 0.3048)
			(end -0.67945 -0.305054)
			(stroke
				(width 0.1)
				(type default)
			)
			(layer "F.Fab")
		)
		(fp_line
			(start -0.12065 0.3048)
			(end -0.67945 0.3048)
			(stroke
				(width 0.1)
				(type default)
			)
			(layer "F.Fab")
		)
		(fp_line
			(start 0.120396 0.3048)
			(end 0.120396 0.2794)
			(stroke
				(width 0.1)
				(type default)
			)
			(layer "F.Fab")
		)
		(fp_line
			(start 0.67945 0.3048)
			(end 0.120396 0.3048)
			(stroke
				(width 0.1)
				(type default)
			)
			(layer "F.Fab")
		)
		(fp_line
			(start -0.12065 0.2794)
			(end -0.12065 0.3048)
			(stroke
				(width 0.1)
				(type default)
			)
			(layer "F.Fab")
		)
		(fp_line
			(start 0.120396 0.2794)
			(end -0.12065 0.2794)
			(stroke
				(width 0.1)
				(type default)
			)
			(layer "F.Fab")
		)
		(fp_line
			(start -0.12065 -0.2794)
			(end 0.12065 -0.2794)
			(stroke
				(width 0.1)
				(type default)
			)
			(layer "F.Fab")
		)
		(fp_line
			(start 0.12065 -0.2794)
			(end 0.12065 -0.3048)
			(stroke
				(width 0.1)
				(type default)
			)
			(layer "F.Fab")
		)
		(fp_line
			(start 0.12065 -0.3048)
			(end 0.67945 -0.3048)
			(stroke
				(width 0.1)
				(type default)
			)
			(layer "F.Fab")
		)
		(fp_line
			(start 0.67945 -0.3048)
			(end 0.67945 0.3048)
			(stroke
				(width 0.1)
				(type default)
			)
			(layer "F.Fab")
		)
		(fp_line
			(start -0.67945 -0.305054)
			(end -0.12065 -0.305054)
			(stroke
				(width 0.1)
				(type default)
			)
			(layer "F.Fab")
		)
		(fp_line
			(start -0.12065 -0.305054)
			(end -0.12065 -0.2794)
			(stroke
				(width 0.1)
				(type default)
			)
			(layer "F.Fab")
		)
		(pad "1" smd circle
			(at -0.40005 0 270)
			(size 0 0)
			(layers "F.Cu" "F.Mask" "F.Paste")
			(net "P3V3_AUX")
		)
		(pad "2" smd circle
			(at 0.40005 0 270)
			(size 0 0)
			(layers "F.Cu" "F.Mask" "F.Paste")
			(net "FM_LPC_ESPI_SEL")
		)
	)
	(footprint ""
		(layer "F.Cu")
		(at 27.595322 -133.430518 -90)
		(property "Reference" "PR274"
			(at 0 0 270)
			(layer "F.SilkS")
			(hide yes)
			(effects
				(font
					(size 1.27 1.27)
				)
			)
		)
		(property "Value" ""
			(at 0 0 270)
			(layer "F.Fab")
			(effects
				(font
					(size 1.27 1.27)
				)
			)
		)
		(duplicate_pad_numbers_are_jumpers no)
		(fp_line
			(start -0.7874 0.4064)
			(end -0.7874 -0.4064)
			(stroke
				(width 0.1524)
				(type default)
			)
			(layer "F.SilkS")
		)
		(fp_line
			(start 0.7874 0.4064)
			(end -0.7874 0.4064)
			(stroke
				(width 0.1524)
				(type default)
			)
			(layer "F.SilkS")
		)
		(fp_line
			(start -0.7874 -0.4064)
			(end 0.7874 -0.4064)
			(stroke
				(width 0.1524)
				(type default)
			)
			(layer "F.SilkS")
		)
		(fp_line
			(start 0.7874 -0.4064)
			(end 0.7874 0.4064)
			(stroke
				(width 0.1524)
				(type default)
			)
			(layer "F.SilkS")
		)
		(fp_line
			(start -0.67945 0.3048)
			(end -0.67945 -0.305054)
			(stroke
				(width 0.1)
				(type default)
			)
			(layer "F.Fab")
		)
		(fp_line
			(start -0.12065 0.3048)
			(end -0.67945 0.3048)
			(stroke
				(width 0.1)
				(type default)
			)
			(layer "F.Fab")
		)
		(fp_line
			(start 0.120396 0.3048)
			(end 0.120396 0.2794)
			(stroke
				(width 0.1)
				(type default)
			)
			(layer "F.Fab")
		)
		(fp_line
			(start 0.67945 0.3048)
			(end 0.120396 0.3048)
			(stroke
				(width 0.1)
				(type default)
			)
			(layer "F.Fab")
		)
		(fp_line
			(start -0.12065 0.2794)
			(end -0.12065 0.3048)
			(stroke
				(width 0.1)
				(type default)
			)
			(layer "F.Fab")
		)
		(fp_line
			(start 0.120396 0.2794)
			(end -0.12065 0.2794)
			(stroke
				(width 0.1)
				(type default)
			)
			(layer "F.Fab")
		)
		(fp_line
			(start -0.12065 -0.2794)
			(end 0.12065 -0.2794)
			(stroke
				(width 0.1)
				(type default)
			)
			(layer "F.Fab")
		)
		(fp_line
			(start 0.12065 -0.2794)
			(end 0.12065 -0.3048)
			(stroke
				(width 0.1)
				(type default)
			)
			(layer "F.Fab")
		)
		(fp_line
			(start 0.12065 -0.3048)
			(end 0.67945 -0.3048)
			(stroke
				(width 0.1)
				(type default)
			)
			(layer "F.Fab")
		)
		(fp_line
			(start 0.67945 -0.3048)
			(end 0.67945 0.3048)
			(stroke
				(width 0.1)
				(type default)
			)
			(layer "F.Fab")
		)
		(fp_line
			(start -0.67945 -0.305054)
			(end -0.12065 -0.305054)
			(stroke
				(width 0.1)
				(type default)
			)
			(layer "F.Fab")
		)
		(fp_line
			(start -0.12065 -0.305054)
			(end -0.12065 -0.2794)
			(stroke
				(width 0.1)
				(type default)
			)
			(layer "F.Fab")
		)
		(pad "1" smd circle
			(at -0.40005 0 270)
			(size 0 0)
			(layers "F.Cu" "F.Mask" "F.Paste")
			(net "SH_PVCCFA_EHV_CPU1")
		)
		(pad "2" smd circle
			(at 0.40005 0 270)
			(size 0 0)
			(layers "F.Cu" "F.Mask" "F.Paste")
			(net "SH_PVCCFA_EHV_CPU1_R")
		)
	)
	(footprint ""
		(layer "F.Cu")
		(at 202.322684 -105.315004 90)
		(property "Reference" "R4713"
			(at 0 0 90)
			(layer "F.SilkS")
			(hide yes)
			(effects
				(font
					(size 1.27 1.27)
				)
			)
		)
		(property "Value" ""
			(at 0 0 90)
			(layer "F.Fab")
			(effects
				(font
					(size 1.27 1.27)
				)
			)
		)
		(duplicate_pad_numbers_are_jumpers no)
		(fp_line
			(start 0.7874 -0.4064)
			(end 0.7874 0.4064)
			(stroke
				(width 0.1524)
				(type default)
			)
			(layer "F.SilkS")
		)
		(fp_line
			(start -0.7874 -0.4064)
			(end 0.7874 -0.4064)
			(stroke
				(width 0.1524)
				(type default)
			)
			(layer "F.SilkS")
		)
		(fp_line
			(start 0.7874 0.4064)
			(end -0.7874 0.4064)
			(stroke
				(width 0.1524)
				(type default)
			)
			(layer "F.SilkS")
		)
		(fp_line
			(start -0.7874 0.4064)
			(end -0.7874 -0.4064)
			(stroke
				(width 0.1524)
				(type default)
			)
			(layer "F.SilkS")
		)
		(fp_line
			(start -0.12065 -0.305054)
			(end -0.12065 -0.2794)
			(stroke
				(width 0.1)
				(type default)
			)
			(layer "F.Fab")
		)
		(fp_line
			(start -0.67945 -0.305054)
			(end -0.12065 -0.305054)
			(stroke
				(width 0.1)
				(type default)
			)
			(layer "F.Fab")
		)
		(fp_line
			(start 0.67945 -0.3048)
			(end 0.67945 0.3048)
			(stroke
				(width 0.1)
				(type default)
			)
			(layer "F.Fab")
		)
		(fp_line
			(start 0.12065 -0.3048)
			(end 0.67945 -0.3048)
			(stroke
				(width 0.1)
				(type default)
			)
			(layer "F.Fab")
		)
		(fp_line
			(start 0.12065 -0.2794)
			(end 0.12065 -0.3048)
			(stroke
				(width 0.1)
				(type default)
			)
			(layer "F.Fab")
		)
		(fp_line
			(start -0.12065 -0.2794)
			(end 0.12065 -0.2794)
			(stroke
				(width 0.1)
				(type default)
			)
			(layer "F.Fab")
		)
		(fp_line
			(start 0.120396 0.2794)
			(end -0.12065 0.2794)
			(stroke
				(width 0.1)
				(type default)
			)
			(layer "F.Fab")
		)
		(fp_line
			(start -0.12065 0.2794)
			(end -0.12065 0.3048)
			(stroke
				(width 0.1)
				(type default)
			)
			(layer "F.Fab")
		)
		(fp_line
			(start 0.67945 0.3048)
			(end 0.120396 0.3048)
			(stroke
				(width 0.1)
				(type default)
			)
			(layer "F.Fab")
		)
		(fp_line
			(start 0.120396 0.3048)
			(end 0.120396 0.2794)
			(stroke
				(width 0.1)
				(type default)
			)
			(layer "F.Fab")
		)
		(fp_line
			(start -0.12065 0.3048)
			(end -0.67945 0.3048)
			(stroke
				(width 0.1)
				(type default)
			)
			(layer "F.Fab")
		)
		(fp_line
			(start -0.67945 0.3048)
			(end -0.67945 -0.305054)
			(stroke
				(width 0.1)
				(type default)
			)
			(layer "F.Fab")
		)
		(pad "1" smd circle
			(at -0.40005 0 90)
			(size 0 0)
			(layers "F.Cu" "F.Mask" "F.Paste")
			(net "RST_PFR_OVR_SRTC")
		)
		(pad "2" smd circle
			(at 0.40005 0 90)
			(size 0 0)
			(layers "F.Cu" "F.Mask" "F.Paste")
			(net "GND")
		)
	)
	(footprint ""
		(layer "F.Cu")
		(at 453.345804 -71.245984 -90)
		(property "Reference" "PC570"
			(at 0 0 270)
			(layer "F.SilkS")
			(hide yes)
			(effects
				(font
					(size 1.27 1.27)
				)
			)
		)
		(property "Value" ""
			(at 0 0 270)
			(layer "F.Fab")
			(effects
				(font
					(size 1.27 1.27)
				)
			)
		)
		(duplicate_pad_numbers_are_jumpers no)
		(fp_line
			(start -1.524 0.762)
			(end -1.524 -0.762)
			(stroke
				(width 0.1524)
				(type default)
			)
			(layer "F.SilkS")
		)
		(fp_line
			(start 1.524 0.762)
			(end -1.524 0.762)
			(stroke
				(width 0.1524)
				(type default)
			)
			(layer "F.SilkS")
		)
		(fp_line
			(start -1.524 -0.762)
			(end 1.524 -0.762)
			(stroke
				(width 0.1524)
				(type default)
			)
			(layer "F.SilkS")
		)
		(fp_line
			(start 1.524 -0.762)
			(end 1.524 0.762)
			(stroke
				(width 0.1524)
				(type default)
			)
			(layer "F.SilkS")
		)
		(fp_line
			(start -1.1049 0.724916)
			(end 1.1049 0.724916)
			(stroke
				(width 0.1)
				(type default)
			)
			(layer "F.Fab")
		)
		(fp_line
			(start 1.1049 0.724916)
			(end 1.1049 -0.724916)
			(stroke
				(width 0.1)
				(type default)
			)
			(layer "F.Fab")
		)
		(fp_line
			(start -1.1049 -0.724916)
			(end -1.1049 0.724916)
			(stroke
				(width 0.1)
				(type default)
			)
			(layer "F.Fab")
		)
		(fp_line
			(start 1.1049 -0.724916)
			(end -1.1049 -0.724916)
			(stroke
				(width 0.1)
				(type default)
			)
			(layer "F.Fab")
		)
		(pad "1" smd rect
			(at -0.889 0 90)
			(size 1.016 1.27)
			(layers "F.Cu" "F.Mask" "F.Paste")
			(net "SW_P3V3_AUX_FLT")
		)
		(pad "2" smd rect
			(at 0.889 0 90)
			(size 1.016 1.27)
			(layers "F.Cu" "F.Mask" "F.Paste")
			(net "GND")
		)
	)
	(footprint ""
		(layer "F.Cu")
		(at 180.79212 -411.20822 90)
		(property "Reference" "R4792"
			(at 0 0 90)
			(layer "F.SilkS")
			(hide yes)
			(effects
				(font
					(size 1.27 1.27)
				)
			)
		)
		(property "Value" ""
			(at 0 0 90)
			(layer "F.Fab")
			(effects
				(font
					(size 1.27 1.27)
				)
			)
		)
		(duplicate_pad_numbers_are_jumpers no)
		(fp_line
			(start 0.7874 -0.4064)
			(end 0.7874 0.4064)
			(stroke
				(width 0.1524)
				(type default)
			)
			(layer "F.SilkS")
		)
		(fp_line
			(start -0.7874 -0.4064)
			(end 0.7874 -0.4064)
			(stroke
				(width 0.1524)
				(type default)
			)
			(layer "F.SilkS")
		)
		(fp_line
			(start 0.7874 0.4064)
			(end -0.7874 0.4064)
			(stroke
				(width 0.1524)
				(type default)
			)
			(layer "F.SilkS")
		)
		(fp_line
			(start -0.7874 0.4064)
			(end -0.7874 -0.4064)
			(stroke
				(width 0.1524)
				(type default)
			)
			(layer "F.SilkS")
		)
		(fp_line
			(start -0.12065 -0.305054)
			(end -0.12065 -0.2794)
			(stroke
				(width 0.1)
				(type default)
			)
			(layer "F.Fab")
		)
		(fp_line
			(start -0.67945 -0.305054)
			(end -0.12065 -0.305054)
			(stroke
				(width 0.1)
				(type default)
			)
			(layer "F.Fab")
		)
		(fp_line
			(start 0.67945 -0.3048)
			(end 0.67945 0.3048)
			(stroke
				(width 0.1)
				(type default)
			)
			(layer "F.Fab")
		)
		(fp_line
			(start 0.12065 -0.3048)
			(end 0.67945 -0.3048)
			(stroke
				(width 0.1)
				(type default)
			)
			(layer "F.Fab")
		)
		(fp_line
			(start 0.12065 -0.2794)
			(end 0.12065 -0.3048)
			(stroke
				(width 0.1)
				(type default)
			)
			(layer "F.Fab")
		)
		(fp_line
			(start -0.12065 -0.2794)
			(end 0.12065 -0.2794)
			(stroke
				(width 0.1)
				(type default)
			)
			(layer "F.Fab")
		)
		(fp_line
			(start 0.120396 0.2794)
			(end -0.12065 0.2794)
			(stroke
				(width 0.1)
				(type default)
			)
			(layer "F.Fab")
		)
		(fp_line
			(start -0.12065 0.2794)
			(end -0.12065 0.3048)
			(stroke
				(width 0.1)
				(type default)
			)
			(layer "F.Fab")
		)
		(fp_line
			(start 0.67945 0.3048)
			(end 0.120396 0.3048)
			(stroke
				(width 0.1)
				(type default)
			)
			(layer "F.Fab")
		)
		(fp_line
			(start 0.120396 0.3048)
			(end 0.120396 0.2794)
			(stroke
				(width 0.1)
				(type default)
			)
			(layer "F.Fab")
		)
		(fp_line
			(start -0.12065 0.3048)
			(end -0.67945 0.3048)
			(stroke
				(width 0.1)
				(type default)
			)
			(layer "F.Fab")
		)
		(fp_line
			(start -0.67945 0.3048)
			(end -0.67945 -0.305054)
			(stroke
				(width 0.1)
				(type default)
			)
			(layer "F.Fab")
		)
		(pad "1" smd circle
			(at -0.40005 0 90)
			(size 0 0)
			(layers "F.Cu" "F.Mask" "F.Paste")
			(net "P3V3_AUX")
		)
		(pad "2" smd circle
			(at 0.40005 0 90)
			(size 0 0)
			(layers "F.Cu" "F.Mask" "F.Paste")
			(net "OC_P2V5_COMP")
		)
	)
	(footprint ""
		(layer "F.Cu")
		(at 185.928762 -26.788872 180)
		(property "Reference" "PR4008"
			(at 0 0 180)
			(layer "F.SilkS")
			(hide yes)
			(effects
				(font
					(size 1.27 1.27)
				)
			)
		)
		(property "Value" ""
			(at 0 0 180)
			(layer "F.Fab")
			(effects
				(font
					(size 1.27 1.27)
				)
			)
		)
		(duplicate_pad_numbers_are_jumpers no)
		(fp_line
			(start 0.7874 0.4064)
			(end -0.7874 0.4064)
			(stroke
				(width 0.1524)
				(type default)
			)
			(layer "F.SilkS")
		)
		(fp_line
			(start 0.7874 -0.4064)
			(end 0.7874 0.4064)
			(stroke
				(width 0.1524)
				(type default)
			)
			(layer "F.SilkS")
		)
		(fp_line
			(start -0.7874 0.4064)
			(end -0.7874 -0.4064)
			(stroke
				(width 0.1524)
				(type default)
			)
			(layer "F.SilkS")
		)
		(fp_line
			(start -0.7874 -0.4064)
			(end 0.7874 -0.4064)
			(stroke
				(width 0.1524)
				(type default)
			)
			(layer "F.SilkS")
		)
		(fp_line
			(start 0.67945 0.3048)
			(end 0.120396 0.3048)
			(stroke
				(width 0.1)
				(type default)
			)
			(layer "F.Fab")
		)
		(fp_line
			(start 0.67945 -0.3048)
			(end 0.67945 0.3048)
			(stroke
				(width 0.1)
				(type default)
			)
			(layer "F.Fab")
		)
		(fp_line
			(start 0.12065 -0.2794)
			(end 0.12065 -0.3048)
			(stroke
				(width 0.1)
				(type default)
			)
			(layer "F.Fab")
		)
		(fp_line
			(start 0.12065 -0.3048)
			(end 0.67945 -0.3048)
			(stroke
				(width 0.1)
				(type default)
			)
			(layer "F.Fab")
		)
		(fp_line
			(start 0.120396 0.3048)
			(end 0.120396 0.2794)
			(stroke
				(width 0.1)
				(type default)
			)
			(layer "F.Fab")
		)
		(fp_line
			(start 0.120396 0.2794)
			(end -0.12065 0.2794)
			(stroke
				(width 0.1)
				(type default)
			)
			(layer "F.Fab")
		)
		(fp_line
			(start -0.12065 0.3048)
			(end -0.67945 0.3048)
			(stroke
				(width 0.1)
				(type default)
			)
			(layer "F.Fab")
		)
		(fp_line
			(start -0.12065 0.2794)
			(end -0.12065 0.3048)
			(stroke
				(width 0.1)
				(type default)
			)
			(layer "F.Fab")
		)
		(fp_line
			(start -0.12065 -0.2794)
			(end 0.12065 -0.2794)
			(stroke
				(width 0.1)
				(type default)
			)
			(layer "F.Fab")
		)
		(fp_line
			(start -0.12065 -0.305054)
			(end -0.12065 -0.2794)
			(stroke
				(width 0.1)
				(type default)
			)
			(layer "F.Fab")
		)
		(fp_line
			(start -0.67945 0.3048)
			(end -0.67945 -0.305054)
			(stroke
				(width 0.1)
				(type default)
			)
			(layer "F.Fab")
		)
		(fp_line
			(start -0.67945 -0.305054)
			(end -0.12065 -0.305054)
			(stroke
				(width 0.1)
				(type default)
			)
			(layer "F.Fab")
		)
		(pad "1" smd circle
			(at -0.40005 0 180)
			(size 0 0)
			(layers "F.Cu" "F.Mask" "F.Paste")
			(net "P12V_SCM_SENSE")
		)
		(pad "2" smd circle
			(at 0.40005 0 180)
			(size 0 0)
			(layers "F.Cu" "F.Mask" "F.Paste")
			(net "GND")
		)
	)
	(footprint ""
		(layer "F.Cu")
		(at 234.126278 -245.411498 90)
		(property "Reference" "R4080"
			(at 0 0 90)
			(layer "F.SilkS")
			(hide yes)
			(effects
				(font
					(size 1.27 1.27)
				)
			)
		)
		(property "Value" ""
			(at 0 0 90)
			(layer "F.Fab")
			(effects
				(font
					(size 1.27 1.27)
				)
			)
		)
		(duplicate_pad_numbers_are_jumpers no)
		(fp_line
			(start 0.7874 -0.4064)
			(end 0.7874 0.4064)
			(stroke
				(width 0.1524)
				(type default)
			)
			(layer "F.SilkS")
		)
		(fp_line
			(start -0.7874 -0.4064)
			(end 0.7874 -0.4064)
			(stroke
				(width 0.1524)
				(type default)
			)
			(layer "F.SilkS")
		)
		(fp_line
			(start 0.7874 0.4064)
			(end -0.7874 0.4064)
			(stroke
				(width 0.1524)
				(type default)
			)
			(layer "F.SilkS")
		)
		(fp_line
			(start -0.7874 0.4064)
			(end -0.7874 -0.4064)
			(stroke
				(width 0.1524)
				(type default)
			)
			(layer "F.SilkS")
		)
		(fp_line
			(start -0.12065 -0.305054)
			(end -0.12065 -0.2794)
			(stroke
				(width 0.1)
				(type default)
			)
			(layer "F.Fab")
		)
		(fp_line
			(start -0.67945 -0.305054)
			(end -0.12065 -0.305054)
			(stroke
				(width 0.1)
				(type default)
			)
			(layer "F.Fab")
		)
		(fp_line
			(start 0.67945 -0.3048)
			(end 0.67945 0.3048)
			(stroke
				(width 0.1)
				(type default)
			)
			(layer "F.Fab")
		)
		(fp_line
			(start 0.12065 -0.3048)
			(end 0.67945 -0.3048)
			(stroke
				(width 0.1)
				(type default)
			)
			(layer "F.Fab")
		)
		(fp_line
			(start 0.12065 -0.2794)
			(end 0.12065 -0.3048)
			(stroke
				(width 0.1)
				(type default)
			)
			(layer "F.Fab")
		)
		(fp_line
			(start -0.12065 -0.2794)
			(end 0.12065 -0.2794)
			(stroke
				(width 0.1)
				(type default)
			)
			(layer "F.Fab")
		)
		(fp_line
			(start 0.120396 0.2794)
			(end -0.12065 0.2794)
			(stroke
				(width 0.1)
				(type default)
			)
			(layer "F.Fab")
		)
		(fp_line
			(start -0.12065 0.2794)
			(end -0.12065 0.3048)
			(stroke
				(width 0.1)
				(type default)
			)
			(layer "F.Fab")
		)
		(fp_line
			(start 0.67945 0.3048)
			(end 0.120396 0.3048)
			(stroke
				(width 0.1)
				(type default)
			)
			(layer "F.Fab")
		)
		(fp_line
			(start 0.120396 0.3048)
			(end 0.120396 0.2794)
			(stroke
				(width 0.1)
				(type default)
			)
			(layer "F.Fab")
		)
		(fp_line
			(start -0.12065 0.3048)
			(end -0.67945 0.3048)
			(stroke
				(width 0.1)
				(type default)
			)
			(layer "F.Fab")
		)
		(fp_line
			(start -0.67945 0.3048)
			(end -0.67945 -0.305054)
			(stroke
				(width 0.1)
				(type default)
			)
			(layer "F.Fab")
		)
		(pad "1" smd circle
			(at -0.40005 0 90)
			(size 0 0)
			(layers "F.Cu" "F.Mask" "F.Paste")
			(net "P3V3_AUX")
		)
		(pad "2" smd circle
			(at 0.40005 0 90)
			(size 0 0)
			(layers "F.Cu" "F.Mask" "F.Paste")
			(net "P3V3_PWRGD_CLKGEN")
		)
	)
	(footprint ""
		(layer "F.Cu")
		(at 64.708024 -40.208708 90)
		(property "Reference" "R4067"
			(at 0 0 90)
			(layer "F.SilkS")
			(hide yes)
			(effects
				(font
					(size 1.27 1.27)
				)
			)
		)
		(property "Value" ""
			(at 0 0 90)
			(layer "F.Fab")
			(effects
				(font
					(size 1.27 1.27)
				)
			)
		)
		(duplicate_pad_numbers_are_jumpers no)
		(fp_line
			(start 0.7874 -0.4064)
			(end 0.7874 0.4064)
			(stroke
				(width 0.1524)
				(type default)
			)
			(layer "F.SilkS")
		)
		(fp_line
			(start -0.7874 -0.4064)
			(end 0.7874 -0.4064)
			(stroke
				(width 0.1524)
				(type default)
			)
			(layer "F.SilkS")
		)
		(fp_line
			(start 0.7874 0.4064)
			(end -0.7874 0.4064)
			(stroke
				(width 0.1524)
				(type default)
			)
			(layer "F.SilkS")
		)
		(fp_line
			(start -0.7874 0.4064)
			(end -0.7874 -0.4064)
			(stroke
				(width 0.1524)
				(type default)
			)
			(layer "F.SilkS")
		)
		(fp_line
			(start -0.12065 -0.305054)
			(end -0.12065 -0.2794)
			(stroke
				(width 0.1)
				(type default)
			)
			(layer "F.Fab")
		)
		(fp_line
			(start -0.67945 -0.305054)
			(end -0.12065 -0.305054)
			(stroke
				(width 0.1)
				(type default)
			)
			(layer "F.Fab")
		)
		(fp_line
			(start 0.67945 -0.3048)
			(end 0.67945 0.3048)
			(stroke
				(width 0.1)
				(type default)
			)
			(layer "F.Fab")
		)
		(fp_line
			(start 0.12065 -0.3048)
			(end 0.67945 -0.3048)
			(stroke
				(width 0.1)
				(type default)
			)
			(layer "F.Fab")
		)
		(fp_line
			(start 0.12065 -0.2794)
			(end 0.12065 -0.3048)
			(stroke
				(width 0.1)
				(type default)
			)
			(layer "F.Fab")
		)
		(fp_line
			(start -0.12065 -0.2794)
			(end 0.12065 -0.2794)
			(stroke
				(width 0.1)
				(type default)
			)
			(layer "F.Fab")
		)
		(fp_line
			(start 0.120396 0.2794)
			(end -0.12065 0.2794)
			(stroke
				(width 0.1)
				(type default)
			)
			(layer "F.Fab")
		)
		(fp_line
			(start -0.12065 0.2794)
			(end -0.12065 0.3048)
			(stroke
				(width 0.1)
				(type default)
			)
			(layer "F.Fab")
		)
		(fp_line
			(start 0.67945 0.3048)
			(end 0.120396 0.3048)
			(stroke
				(width 0.1)
				(type default)
			)
			(layer "F.Fab")
		)
		(fp_line
			(start 0.120396 0.3048)
			(end 0.120396 0.2794)
			(stroke
				(width 0.1)
				(type default)
			)
			(layer "F.Fab")
		)
		(fp_line
			(start -0.12065 0.3048)
			(end -0.67945 0.3048)
			(stroke
				(width 0.1)
				(type default)
			)
			(layer "F.Fab")
		)
		(fp_line
			(start -0.67945 0.3048)
			(end -0.67945 -0.305054)
			(stroke
				(width 0.1)
				(type default)
			)
			(layer "F.Fab")
		)
		(pad "1" smd circle
			(at -0.40005 0 90)
			(size 0 0)
			(layers "F.Cu" "F.Mask" "F.Paste")
			(net "P12V_AUX")
		)
		(pad "2" smd circle
			(at 0.40005 0 90)
			(size 0 0)
			(layers "F.Cu" "F.Mask" "F.Paste")
			(net "P3V3_OCP_2_EN_G")
		)
	)
	(footprint ""
		(layer "F.Cu")
		(at 137.176256 -64.694308)
		(property "Reference" "Q46"
			(at -0.3937 2.62763 0)
			(unlocked yes)
			(layer "F.SilkS")
			(effects
				(font
					(size 0.7874 0.5842)
					(thickness 0.1524)
				)
				(justify left)
			)
		)
		(property "Value" ""
			(at 0 0 0)
			(layer "F.Fab")
			(effects
				(font
					(size 1.27 1.27)
				)
			)
		)
		(duplicate_pad_numbers_are_jumpers no)
		(fp_line
			(start -1.603248 -1.500124)
			(end 1.603248 -1.500124)
			(stroke
				(width 0.1524)
				(type default)
			)
			(layer "F.SilkS")
		)
		(fp_line
			(start -1.603248 1.500124)
			(end -1.603248 -1.500124)
			(stroke
				(width 0.1524)
				(type default)
			)
			(layer "F.SilkS")
		)
		(fp_line
			(start 1.603248 -1.500124)
			(end 1.603248 1.500124)
			(stroke
				(width 0.1524)
				(type default)
			)
			(layer "F.SilkS")
		)
		(fp_line
			(start 1.603248 1.500124)
			(end -1.603248 1.500124)
			(stroke
				(width 0.1524)
				(type default)
			)
			(layer "F.SilkS")
		)
		(fp_line
			(start -1.249934 -1.169924)
			(end -1.249934 -0.729996)
			(stroke
				(width 0.1)
				(type default)
			)
			(layer "F.Fab")
		)
		(fp_line
			(start -1.249934 -0.729996)
			(end -0.6985 -0.729996)
			(stroke
				(width 0.1)
				(type default)
			)
			(layer "F.Fab")
		)
		(fp_line
			(start -1.249934 0.729996)
			(end -1.249934 1.169924)
			(stroke
				(width 0.1)
				(type default)
			)
			(layer "F.Fab")
		)
		(fp_line
			(start -1.249934 1.169924)
			(end -0.700024 1.169924)
			(stroke
				(width 0.1)
				(type default)
			)
			(layer "F.Fab")
		)
		(fp_line
			(start -0.700024 -1.500124)
			(end -0.700024 -1.169924)
			(stroke
				(width 0.1)
				(type default)
			)
			(layer "F.Fab")
		)
		(fp_line
			(start -0.700024 -1.169924)
			(end -1.249934 -1.169924)
			(stroke
				(width 0.1)
				(type default)
			)
			(layer "F.Fab")
		)
		(fp_line
			(start -0.700024 1.169924)
			(end -0.700024 1.500124)
			(stroke
				(width 0.1)
				(type default)
			)
			(layer "F.Fab")
		)
		(fp_line
			(start -0.700024 1.500124)
			(end 0.700024 1.500124)
			(stroke
				(width 0.1)
				(type default)
			)
			(layer "F.Fab")
		)
		(fp_line
			(start -0.6985 -0.729996)
			(end -0.6985 0.729996)
			(stroke
				(width 0.1)
				(type default)
			)
			(layer "F.Fab")
		)
		(fp_line
			(start -0.6985 0.729996)
			(end -1.249934 0.729996)
			(stroke
				(width 0.1)
				(type default)
			)
			(layer "F.Fab")
		)
		(fp_line
			(start 0.700024 -1.500124)
			(end -0.700024 -1.500124)
			(stroke
				(width 0.1)
				(type default)
			)
			(layer "F.Fab")
		)
		(fp_line
			(start 0.700024 -0.219964)
			(end 0.700024 -1.500124)
			(stroke
				(width 0.1)
				(type default)
			)
			(layer "F.Fab")
		)
		(fp_line
			(start 0.700024 0.219964)
			(end 1.249934 0.219964)
			(stroke
				(width 0.1)
				(type default)
			)
			(layer "F.Fab")
		)
		(fp_line
			(start 0.700024 1.500124)
			(end 0.700024 0.219964)
			(stroke
				(width 0.1)
				(type default)
			)
			(layer "F.Fab")
		)
		(fp_line
			(start 1.249934 -0.219964)
			(end 0.700024 -0.219964)
			(stroke
				(width 0.1)
				(type default)
			)
			(layer "F.Fab")
		)
		(fp_line
			(start 1.249934 0.219964)
			(end 1.249934 -0.219964)
			(stroke
				(width 0.1)
				(type default)
			)
			(layer "F.Fab")
		)
		(fp_rect
			(start -0.700024 1.500124)
			(end 0.700024 -1.500124)
			(stroke
				(width 0)
				(type default)
			)
			(fill no)
			(layer "F.Fab")
		)
		(pad "D" smd rect
			(at 0.999998 0 270)
			(size 0.8128 0.9144)
			(layers "F.Cu" "F.Mask" "F.Paste")
			(net "E1S_0_PRSNT")
		)
		(pad "G" smd rect
			(at -0.999998 -0.94996 270)
			(size 0.8128 0.9144)
			(layers "F.Cu" "F.Mask" "F.Paste")
			(net "E1S_0_PRSNT_N")
		)
		(pad "S" smd rect
			(at -0.999998 0.94996 270)
			(size 0.8128 0.9144)
			(layers "F.Cu" "F.Mask" "F.Paste")
			(net "GND")
		)
	)
	(footprint ""
		(layer "F.Cu")
		(at 460.1845 -45.693838)
		(property "Reference" "R1824"
			(at 0 0 0)
			(layer "F.SilkS")
			(hide yes)
			(effects
				(font
					(size 1.27 1.27)
				)
			)
		)
		(property "Value" ""
			(at 0 0 0)
			(layer "F.Fab")
			(effects
				(font
					(size 1.27 1.27)
				)
			)
		)
		(duplicate_pad_numbers_are_jumpers no)
		(fp_line
			(start -0.7874 -0.4064)
			(end 0.7874 -0.4064)
			(stroke
				(width 0.1524)
				(type default)
			)
			(layer "F.SilkS")
		)
		(fp_line
			(start -0.7874 0.4064)
			(end -0.7874 -0.4064)
			(stroke
				(width 0.1524)
				(type default)
			)
			(layer "F.SilkS")
		)
		(fp_line
			(start 0.7874 -0.4064)
			(end 0.7874 0.4064)
			(stroke
				(width 0.1524)
				(type default)
			)
			(layer "F.SilkS")
		)
		(fp_line
			(start 0.7874 0.4064)
			(end -0.7874 0.4064)
			(stroke
				(width 0.1524)
				(type default)
			)
			(layer "F.SilkS")
		)
		(fp_line
			(start -0.67945 -0.305054)
			(end -0.12065 -0.305054)
			(stroke
				(width 0.1)
				(type default)
			)
			(layer "F.Fab")
		)
		(fp_line
			(start -0.67945 0.3048)
			(end -0.67945 -0.305054)
			(stroke
				(width 0.1)
				(type default)
			)
			(layer "F.Fab")
		)
		(fp_line
			(start -0.12065 -0.305054)
			(end -0.12065 -0.2794)
			(stroke
				(width 0.1)
				(type default)
			)
			(layer "F.Fab")
		)
		(fp_line
			(start -0.12065 -0.2794)
			(end 0.12065 -0.2794)
			(stroke
				(width 0.1)
				(type default)
			)
			(layer "F.Fab")
		)
		(fp_line
			(start -0.12065 0.2794)
			(end -0.12065 0.3048)
			(stroke
				(width 0.1)
				(type default)
			)
			(layer "F.Fab")
		)
		(fp_line
			(start -0.12065 0.3048)
			(end -0.67945 0.3048)
			(stroke
				(width 0.1)
				(type default)
			)
			(layer "F.Fab")
		)
		(fp_line
			(start 0.120396 0.2794)
			(end -0.12065 0.2794)
			(stroke
				(width 0.1)
				(type default)
			)
			(layer "F.Fab")
		)
		(fp_line
			(start 0.120396 0.3048)
			(end 0.120396 0.2794)
			(stroke
				(width 0.1)
				(type default)
			)
			(layer "F.Fab")
		)
		(fp_line
			(start 0.12065 -0.3048)
			(end 0.67945 -0.3048)
			(stroke
				(width 0.1)
				(type default)
			)
			(layer "F.Fab")
		)
		(fp_line
			(start 0.12065 -0.2794)
			(end 0.12065 -0.3048)
			(stroke
				(width 0.1)
				(type default)
			)
			(layer "F.Fab")
		)
		(fp_line
			(start 0.67945 -0.3048)
			(end 0.67945 0.3048)
			(stroke
				(width 0.1)
				(type default)
			)
			(layer "F.Fab")
		)
		(fp_line
			(start 0.67945 0.3048)
			(end 0.120396 0.3048)
			(stroke
				(width 0.1)
				(type default)
			)
			(layer "F.Fab")
		)
		(pad "1" smd circle
			(at -0.40005 0)
			(size 0 0)
			(layers "F.Cu" "F.Mask" "F.Paste")
			(net "P3V3_OCP_SFF")
		)
		(pad "2" smd circle
			(at 0.40005 0)
			(size 0 0)
			(layers "F.Cu" "F.Mask" "F.Paste")
			(net "IRQ_LVC3_OCP_SFF_WAKE_N")
		)
	)
	(footprint ""
		(layer "F.Cu")
		(at 354.251514 -256.654046 -90)
		(property "Reference" "C974"
			(at 0 0 270)
			(layer "F.SilkS")
			(hide yes)
			(effects
				(font
					(size 1.27 1.27)
				)
			)
		)
		(property "Value" ""
			(at 0 0 270)
			(layer "F.Fab")
			(effects
				(font
					(size 1.27 1.27)
				)
			)
		)
		(duplicate_pad_numbers_are_jumpers no)
		(fp_line
			(start -0.7874 0.4064)
			(end -0.7874 -0.4064)
			(stroke
				(width 0.1524)
				(type default)
			)
			(layer "F.SilkS")
		)
		(fp_line
			(start 0.7874 0.4064)
			(end -0.7874 0.4064)
			(stroke
				(width 0.1524)
				(type default)
			)
			(layer "F.SilkS")
		)
		(fp_line
			(start -0.7874 -0.4064)
			(end 0.7874 -0.4064)
			(stroke
				(width 0.1524)
				(type default)
			)
			(layer "F.SilkS")
		)
		(fp_line
			(start 0.7874 -0.4064)
			(end 0.7874 0.4064)
			(stroke
				(width 0.1524)
				(type default)
			)
			(layer "F.SilkS")
		)
		(fp_line
			(start -0.67945 0.3048)
			(end -0.67945 -0.305054)
			(stroke
				(width 0.1)
				(type default)
			)
			(layer "F.Fab")
		)
		(fp_line
			(start -0.12065 0.3048)
			(end -0.67945 0.3048)
			(stroke
				(width 0.1)
				(type default)
			)
			(layer "F.Fab")
		)
		(fp_line
			(start 0.120396 0.3048)
			(end 0.120396 0.2794)
			(stroke
				(width 0.1)
				(type default)
			)
			(layer "F.Fab")
		)
		(fp_line
			(start 0.67945 0.3048)
			(end 0.120396 0.3048)
			(stroke
				(width 0.1)
				(type default)
			)
			(layer "F.Fab")
		)
		(fp_line
			(start -0.12065 0.2794)
			(end -0.12065 0.3048)
			(stroke
				(width 0.1)
				(type default)
			)
			(layer "F.Fab")
		)
		(fp_line
			(start 0.120396 0.2794)
			(end -0.12065 0.2794)
			(stroke
				(width 0.1)
				(type default)
			)
			(layer "F.Fab")
		)
		(fp_line
			(start -0.12065 -0.2794)
			(end 0.12065 -0.2794)
			(stroke
				(width 0.1)
				(type default)
			)
			(layer "F.Fab")
		)
		(fp_line
			(start 0.12065 -0.2794)
			(end 0.12065 -0.3048)
			(stroke
				(width 0.1)
				(type default)
			)
			(layer "F.Fab")
		)
		(fp_line
			(start 0.12065 -0.3048)
			(end 0.67945 -0.3048)
			(stroke
				(width 0.1)
				(type default)
			)
			(layer "F.Fab")
		)
		(fp_line
			(start 0.67945 -0.3048)
			(end 0.67945 0.3048)
			(stroke
				(width 0.1)
				(type default)
			)
			(layer "F.Fab")
		)
		(fp_line
			(start -0.67945 -0.305054)
			(end -0.12065 -0.305054)
			(stroke
				(width 0.1)
				(type default)
			)
			(layer "F.Fab")
		)
		(fp_line
			(start -0.12065 -0.305054)
			(end -0.12065 -0.2794)
			(stroke
				(width 0.1)
				(type default)
			)
			(layer "F.Fab")
		)
		(pad "1" smd circle
			(at -0.40005 0 270)
			(size 0 0)
			(layers "F.Cu" "F.Mask" "F.Paste")
			(net "PVCCIN_CPU0")
		)
		(pad "2" smd circle
			(at 0.40005 0 270)
			(size 0 0)
			(layers "F.Cu" "F.Mask" "F.Paste")
			(net "GND")
		)
	)
	(footprint ""
		(layer "F.Cu")
		(at 166.37 -23.713948 90)
		(property "Reference" "R144"
			(at 0 0 90)
			(layer "F.SilkS")
			(hide yes)
			(effects
				(font
					(size 1.27 1.27)
				)
			)
		)
		(property "Value" ""
			(at 0 0 90)
			(layer "F.Fab")
			(effects
				(font
					(size 1.27 1.27)
				)
			)
		)
		(duplicate_pad_numbers_are_jumpers no)
		(fp_line
			(start 0.7874 -0.4064)
			(end 0.7874 0.4064)
			(stroke
				(width 0.1524)
				(type default)
			)
			(layer "F.SilkS")
		)
		(fp_line
			(start -0.7874 -0.4064)
			(end 0.7874 -0.4064)
			(stroke
				(width 0.1524)
				(type default)
			)
			(layer "F.SilkS")
		)
		(fp_line
			(start 0.7874 0.4064)
			(end -0.7874 0.4064)
			(stroke
				(width 0.1524)
				(type default)
			)
			(layer "F.SilkS")
		)
		(fp_line
			(start -0.7874 0.4064)
			(end -0.7874 -0.4064)
			(stroke
				(width 0.1524)
				(type default)
			)
			(layer "F.SilkS")
		)
		(fp_line
			(start -0.12065 -0.305054)
			(end -0.12065 -0.2794)
			(stroke
				(width 0.1)
				(type default)
			)
			(layer "F.Fab")
		)
		(fp_line
			(start -0.67945 -0.305054)
			(end -0.12065 -0.305054)
			(stroke
				(width 0.1)
				(type default)
			)
			(layer "F.Fab")
		)
		(fp_line
			(start 0.67945 -0.3048)
			(end 0.67945 0.3048)
			(stroke
				(width 0.1)
				(type default)
			)
			(layer "F.Fab")
		)
		(fp_line
			(start 0.12065 -0.3048)
			(end 0.67945 -0.3048)
			(stroke
				(width 0.1)
				(type default)
			)
			(layer "F.Fab")
		)
		(fp_line
			(start 0.12065 -0.2794)
			(end 0.12065 -0.3048)
			(stroke
				(width 0.1)
				(type default)
			)
			(layer "F.Fab")
		)
		(fp_line
			(start -0.12065 -0.2794)
			(end 0.12065 -0.2794)
			(stroke
				(width 0.1)
				(type default)
			)
			(layer "F.Fab")
		)
		(fp_line
			(start 0.120396 0.2794)
			(end -0.12065 0.2794)
			(stroke
				(width 0.1)
				(type default)
			)
			(layer "F.Fab")
		)
		(fp_line
			(start -0.12065 0.2794)
			(end -0.12065 0.3048)
			(stroke
				(width 0.1)
				(type default)
			)
			(layer "F.Fab")
		)
		(fp_line
			(start 0.67945 0.3048)
			(end 0.120396 0.3048)
			(stroke
				(width 0.1)
				(type default)
			)
			(layer "F.Fab")
		)
		(fp_line
			(start 0.120396 0.3048)
			(end 0.120396 0.2794)
			(stroke
				(width 0.1)
				(type default)
			)
			(layer "F.Fab")
		)
		(fp_line
			(start -0.12065 0.3048)
			(end -0.67945 0.3048)
			(stroke
				(width 0.1)
				(type default)
			)
			(layer "F.Fab")
		)
		(fp_line
			(start -0.67945 0.3048)
			(end -0.67945 -0.305054)
			(stroke
				(width 0.1)
				(type default)
			)
			(layer "F.Fab")
		)
		(pad "1" smd circle
			(at -0.40005 0 90)
			(size 0 0)
			(layers "F.Cu" "F.Mask" "F.Paste")
			(net "PECI_BMC")
		)
		(pad "2" smd circle
			(at 0.40005 0 90)
			(size 0 0)
			(layers "F.Cu" "F.Mask" "F.Paste")
			(net "PECI_BMC_R")
		)
	)
	(footprint ""
		(layer "F.Cu")
		(at 163.88715 -425.245276 -90)
		(property "Reference" "U175"
			(at 1.581404 -2.540762 90)
			(unlocked yes)
			(layer "F.SilkS")
			(effects
				(font
					(size 0.7874 0.5842)
					(thickness 0.1524)
				)
				(justify left)
			)
		)
		(property "Value" ""
			(at 0 0 270)
			(layer "F.Fab")
			(effects
				(font
					(size 1.27 1.27)
				)
			)
		)
		(duplicate_pad_numbers_are_jumpers no)
		(fp_line
			(start -1.3716 1.524)
			(end -1.3716 -1.524)
			(stroke
				(width 0.1524)
				(type default)
			)
			(layer "F.SilkS")
		)
		(fp_line
			(start 1.3716 1.524)
			(end -1.3716 1.524)
			(stroke
				(width 0.1524)
				(type default)
			)
			(layer "F.SilkS")
		)
		(fp_line
			(start 0 -1.016)
			(end 0.508 -1.524)
			(stroke
				(width 0.1524)
				(type default)
			)
			(layer "F.SilkS")
		)
		(fp_line
			(start -1.3716 -1.524)
			(end -0.508 -1.524)
			(stroke
				(width 0.1524)
				(type default)
			)
			(layer "F.SilkS")
		)
		(fp_line
			(start -0.508 -1.524)
			(end 0 -1.016)
			(stroke
				(width 0.1524)
				(type default)
			)
			(layer "F.SilkS")
		)
		(fp_line
			(start 0.508 -1.524)
			(end 1.3716 -1.524)
			(stroke
				(width 0.1524)
				(type default)
			)
			(layer "F.SilkS")
		)
		(fp_line
			(start 1.3716 -1.524)
			(end 1.3716 1.524)
			(stroke
				(width 0.1524)
				(type default)
			)
			(layer "F.SilkS")
		)
		(fp_poly
			(pts
				(xy -3.60172 -1.344168) (xy -3.048 -1.016) (xy -3.60172 -0.719328)
			)
			(stroke
				(width 0)
				(type default)
			)
			(fill yes)
			(layer "F.SilkS")
		)
		(fp_line
			(start -1.5494 1.524)
			(end -1.5494 1.0668)
			(stroke
				(width 0.1)
				(type default)
			)
			(layer "F.Fab")
		)
		(fp_line
			(start 1.5494 1.524)
			(end -1.5494 1.524)
			(stroke
				(width 0.1)
				(type default)
			)
			(layer "F.Fab")
		)
		(fp_line
			(start -2.54 1.0668)
			(end -2.54 -1.0668)
			(stroke
				(width 0.1)
				(type default)
			)
			(layer "F.Fab")
		)
		(fp_line
			(start -1.5494 1.0668)
			(end -2.54 1.0668)
			(stroke
				(width 0.1)
				(type default)
			)
			(layer "F.Fab")
		)
		(fp_line
			(start -1.5494 1.0668)
			(end -1.5494 -1.0668)
			(stroke
				(width 0.1)
				(type default)
			)
			(layer "F.Fab")
		)
		(fp_line
			(start 1.5494 1.0668)
			(end 1.5494 1.524)
			(stroke
				(width 0.1)
				(type default)
			)
			(layer "F.Fab")
		)
		(fp_line
			(start 2.54 1.0668)
			(end 1.5494 1.0668)
			(stroke
				(width 0.1)
				(type default)
			)
			(layer "F.Fab")
		)
		(fp_line
			(start -2.54 -1.0668)
			(end -1.5494 -1.0668)
			(stroke
				(width 0.1)
				(type default)
			)
			(layer "F.Fab")
		)
		(fp_line
			(start -1.5494 -1.0668)
			(end -1.5494 -1.524)
			(stroke
				(width 0.1)
				(type default)
			)
			(layer "F.Fab")
		)
		(fp_line
			(start 1.5494 -1.0668)
			(end 1.5494 1.0668)
			(stroke
				(width 0.1)
				(type default)
			)
			(layer "F.Fab")
		)
		(fp_line
			(start 1.5494 -1.0668)
			(end 2.54 -1.0668)
			(stroke
				(width 0.1)
				(type default)
			)
			(layer "F.Fab")
		)
		(fp_line
			(start 2.54 -1.0668)
			(end 2.54 1.0668)
			(stroke
				(width 0.1)
				(type default)
			)
			(layer "F.Fab")
		)
		(fp_line
			(start -1.5494 -1.524)
			(end 1.5494 -1.524)
			(stroke
				(width 0.1)
				(type default)
			)
			(layer "F.Fab")
		)
		(fp_line
			(start 1.5494 -1.524)
			(end 1.5494 -1.0668)
			(stroke
				(width 0.1)
				(type default)
			)
			(layer "F.Fab")
		)
		(fp_poly
			(pts
				(xy -3.60172 -0.719328) (xy -3.60172 -1.344168) (xy -3.048 -1.016)
			)
			(stroke
				(width 0)
				(type default)
			)
			(fill yes)
			(layer "F.Fab")
		)
		(pad "1" smd rect
			(at -2.232406 -0.975106 180)
			(size 0.3556 1.4224)
			(layers "F.Cu" "F.Mask" "F.Paste")
			(net "SMB_BMC_SWB_EN_R")
		)
		(pad "2" smd rect
			(at -2.232406 -0.32512 180)
			(size 0.3556 1.4224)
			(layers "F.Cu" "F.Mask" "F.Paste")
			(net "SMB_BMC_SWB_BUF_R_SCL")
		)
		(pad "3" smd rect
			(at -2.232406 0.32512 180)
			(size 0.3556 1.4224)
			(layers "F.Cu" "F.Mask" "F.Paste")
			(net "SMB_BMC_SWB_R_SCL")
		)
		(pad "4" smd rect
			(at -2.232406 0.975106 180)
			(size 0.3556 1.4224)
			(layers "F.Cu" "F.Mask" "F.Paste")
			(net "GND")
		)
		(pad "5" smd rect
			(at 2.232406 0.975106 180)
			(size 0.3556 1.4224)
			(layers "F.Cu" "F.Mask" "F.Paste")
			(net "Net_1934")
		)
		(pad "6" smd rect
			(at 2.232406 0.32512 180)
			(size 0.3556 1.4224)
			(layers "F.Cu" "F.Mask" "F.Paste")
			(net "SMB_BMC_SWB_R_SDA")
		)
		(pad "7" smd rect
			(at 2.232406 -0.32512 180)
			(size 0.3556 1.4224)
			(layers "F.Cu" "F.Mask" "F.Paste")
			(net "SMB_BMC_SWB_BUF_R_SDA")
		)
		(pad "8" smd rect
			(at 2.232406 -0.975106 180)
			(size 0.3556 1.4224)
			(layers "F.Cu" "F.Mask" "F.Paste")
			(net "P3V3_AUX")
		)
	)
	(footprint ""
		(layer "F.Cu")
		(at 27.0383 -126.332996 180)
		(property "Reference" "PC476"
			(at 0 0 180)
			(layer "F.SilkS")
			(hide yes)
			(effects
				(font
					(size 1.27 1.27)
				)
			)
		)
		(property "Value" ""
			(at 0 0 180)
			(layer "F.Fab")
			(effects
				(font
					(size 1.27 1.27)
				)
			)
		)
		(duplicate_pad_numbers_are_jumpers no)
		(fp_line
			(start 0.7874 0.4064)
			(end -0.7874 0.4064)
			(stroke
				(width 0.1524)
				(type default)
			)
			(layer "F.SilkS")
		)
		(fp_line
			(start 0.7874 -0.4064)
			(end 0.7874 0.4064)
			(stroke
				(width 0.1524)
				(type default)
			)
			(layer "F.SilkS")
		)
		(fp_line
			(start -0.7874 0.4064)
			(end -0.7874 -0.4064)
			(stroke
				(width 0.1524)
				(type default)
			)
			(layer "F.SilkS")
		)
		(fp_line
			(start -0.7874 -0.4064)
			(end 0.7874 -0.4064)
			(stroke
				(width 0.1524)
				(type default)
			)
			(layer "F.SilkS")
		)
		(fp_line
			(start 0.67945 0.3048)
			(end 0.120396 0.3048)
			(stroke
				(width 0.1)
				(type default)
			)
			(layer "F.Fab")
		)
		(fp_line
			(start 0.67945 -0.3048)
			(end 0.67945 0.3048)
			(stroke
				(width 0.1)
				(type default)
			)
			(layer "F.Fab")
		)
		(fp_line
			(start 0.12065 -0.2794)
			(end 0.12065 -0.3048)
			(stroke
				(width 0.1)
				(type default)
			)
			(layer "F.Fab")
		)
		(fp_line
			(start 0.12065 -0.3048)
			(end 0.67945 -0.3048)
			(stroke
				(width 0.1)
				(type default)
			)
			(layer "F.Fab")
		)
		(fp_line
			(start 0.120396 0.3048)
			(end 0.120396 0.2794)
			(stroke
				(width 0.1)
				(type default)
			)
			(layer "F.Fab")
		)
		(fp_line
			(start 0.120396 0.2794)
			(end -0.12065 0.2794)
			(stroke
				(width 0.1)
				(type default)
			)
			(layer "F.Fab")
		)
		(fp_line
			(start -0.12065 0.3048)
			(end -0.67945 0.3048)
			(stroke
				(width 0.1)
				(type default)
			)
			(layer "F.Fab")
		)
		(fp_line
			(start -0.12065 0.2794)
			(end -0.12065 0.3048)
			(stroke
				(width 0.1)
				(type default)
			)
			(layer "F.Fab")
		)
		(fp_line
			(start -0.12065 -0.2794)
			(end 0.12065 -0.2794)
			(stroke
				(width 0.1)
				(type default)
			)
			(layer "F.Fab")
		)
		(fp_line
			(start -0.12065 -0.305054)
			(end -0.12065 -0.2794)
			(stroke
				(width 0.1)
				(type default)
			)
			(layer "F.Fab")
		)
		(fp_line
			(start -0.67945 0.3048)
			(end -0.67945 -0.305054)
			(stroke
				(width 0.1)
				(type default)
			)
			(layer "F.Fab")
		)
		(fp_line
			(start -0.67945 -0.305054)
			(end -0.12065 -0.305054)
			(stroke
				(width 0.1)
				(type default)
			)
			(layer "F.Fab")
		)
		(pad "1" smd circle
			(at -0.40005 0 180)
			(size 0 0)
			(layers "F.Cu" "F.Mask" "F.Paste")
			(net "PVCCINFAON_CPU1_VCC")
		)
		(pad "2" smd circle
			(at 0.40005 0 180)
			(size 0 0)
			(layers "F.Cu" "F.Mask" "F.Paste")
			(net "GND")
		)
	)
	(footprint ""
		(layer "F.Cu")
		(at 446.780158 -177.78476)
		(property "Reference" "PC1206"
			(at 0 0 0)
			(layer "F.SilkS")
			(hide yes)
			(effects
				(font
					(size 1.27 1.27)
				)
			)
		)
		(property "Value" ""
			(at 0 0 0)
			(layer "F.Fab")
			(effects
				(font
					(size 1.27 1.27)
				)
			)
		)
		(duplicate_pad_numbers_are_jumpers no)
		(fp_line
			(start -1.524 -0.762)
			(end 1.524 -0.762)
			(stroke
				(width 0.1524)
				(type default)
			)
			(layer "F.SilkS")
		)
		(fp_line
			(start -1.524 0.762)
			(end -1.524 -0.762)
			(stroke
				(width 0.1524)
				(type default)
			)
			(layer "F.SilkS")
		)
		(fp_line
			(start 1.524 -0.762)
			(end 1.524 0.762)
			(stroke
				(width 0.1524)
				(type default)
			)
			(layer "F.SilkS")
		)
		(fp_line
			(start 1.524 0.762)
			(end -1.524 0.762)
			(stroke
				(width 0.1524)
				(type default)
			)
			(layer "F.SilkS")
		)
		(fp_line
			(start -1.1049 -0.724916)
			(end -1.1049 0.724916)
			(stroke
				(width 0.1)
				(type default)
			)
			(layer "F.Fab")
		)
		(fp_line
			(start -1.1049 0.724916)
			(end 1.1049 0.724916)
			(stroke
				(width 0.1)
				(type default)
			)
			(layer "F.Fab")
		)
		(fp_line
			(start 1.1049 -0.724916)
			(end -1.1049 -0.724916)
			(stroke
				(width 0.1)
				(type default)
			)
			(layer "F.Fab")
		)
		(fp_line
			(start 1.1049 0.724916)
			(end 1.1049 -0.724916)
			(stroke
				(width 0.1)
				(type default)
			)
			(layer "F.Fab")
		)
		(pad "1" smd rect
			(at -0.889 0 180)
			(size 1.016 1.27)
			(layers "F.Cu" "F.Mask" "F.Paste")
			(net "PVNN_MAIN_CPU0")
		)
		(pad "2" smd rect
			(at 0.889 0 180)
			(size 1.016 1.27)
			(layers "F.Cu" "F.Mask" "F.Paste")
			(net "GND")
		)
	)
	(footprint ""
		(layer "F.Cu")
		(at 297.147234 -15.572994 180)
		(property "Reference" "R4196"
			(at 0 0 180)
			(layer "F.SilkS")
			(hide yes)
			(effects
				(font
					(size 1.27 1.27)
				)
			)
		)
		(property "Value" ""
			(at 0 0 180)
			(layer "F.Fab")
			(effects
				(font
					(size 1.27 1.27)
				)
			)
		)
		(duplicate_pad_numbers_are_jumpers no)
		(fp_line
			(start 0.7874 0.4064)
			(end -0.7874 0.4064)
			(stroke
				(width 0.1524)
				(type default)
			)
			(layer "F.SilkS")
		)
		(fp_line
			(start 0.7874 -0.4064)
			(end 0.7874 0.4064)
			(stroke
				(width 0.1524)
				(type default)
			)
			(layer "F.SilkS")
		)
		(fp_line
			(start -0.7874 0.4064)
			(end -0.7874 -0.4064)
			(stroke
				(width 0.1524)
				(type default)
			)
			(layer "F.SilkS")
		)
		(fp_line
			(start -0.7874 -0.4064)
			(end 0.7874 -0.4064)
			(stroke
				(width 0.1524)
				(type default)
			)
			(layer "F.SilkS")
		)
		(fp_line
			(start 0.67945 0.3048)
			(end 0.120396 0.3048)
			(stroke
				(width 0.1)
				(type default)
			)
			(layer "F.Fab")
		)
		(fp_line
			(start 0.67945 -0.3048)
			(end 0.67945 0.3048)
			(stroke
				(width 0.1)
				(type default)
			)
			(layer "F.Fab")
		)
		(fp_line
			(start 0.12065 -0.2794)
			(end 0.12065 -0.3048)
			(stroke
				(width 0.1)
				(type default)
			)
			(layer "F.Fab")
		)
		(fp_line
			(start 0.12065 -0.3048)
			(end 0.67945 -0.3048)
			(stroke
				(width 0.1)
				(type default)
			)
			(layer "F.Fab")
		)
		(fp_line
			(start 0.120396 0.3048)
			(end 0.120396 0.2794)
			(stroke
				(width 0.1)
				(type default)
			)
			(layer "F.Fab")
		)
		(fp_line
			(start 0.120396 0.2794)
			(end -0.12065 0.2794)
			(stroke
				(width 0.1)
				(type default)
			)
			(layer "F.Fab")
		)
		(fp_line
			(start -0.12065 0.3048)
			(end -0.67945 0.3048)
			(stroke
				(width 0.1)
				(type default)
			)
			(layer "F.Fab")
		)
		(fp_line
			(start -0.12065 0.2794)
			(end -0.12065 0.3048)
			(stroke
				(width 0.1)
				(type default)
			)
			(layer "F.Fab")
		)
		(fp_line
			(start -0.12065 -0.2794)
			(end 0.12065 -0.2794)
			(stroke
				(width 0.1)
				(type default)
			)
			(layer "F.Fab")
		)
		(fp_line
			(start -0.12065 -0.305054)
			(end -0.12065 -0.2794)
			(stroke
				(width 0.1)
				(type default)
			)
			(layer "F.Fab")
		)
		(fp_line
			(start -0.67945 0.3048)
			(end -0.67945 -0.305054)
			(stroke
				(width 0.1)
				(type default)
			)
			(layer "F.Fab")
		)
		(fp_line
			(start -0.67945 -0.305054)
			(end -0.12065 -0.305054)
			(stroke
				(width 0.1)
				(type default)
			)
			(layer "F.Fab")
		)
		(pad "1" smd circle
			(at -0.40005 0 180)
			(size 0 0)
			(layers "F.Cu" "F.Mask" "F.Paste")
			(net "P3V3_AUX")
		)
		(pad "2" smd circle
			(at 0.40005 0 180)
			(size 0 0)
			(layers "F.Cu" "F.Mask" "F.Paste")
			(net "U271_1_ADD1")
		)
	)
	(footprint ""
		(layer "F.Cu")
		(at 36.605718 -354.65385)
		(property "Reference" "PR702"
			(at 0 0 0)
			(layer "F.SilkS")
			(hide yes)
			(effects
				(font
					(size 1.27 1.27)
				)
			)
		)
		(property "Value" ""
			(at 0 0 0)
			(layer "F.Fab")
			(effects
				(font
					(size 1.27 1.27)
				)
			)
		)
		(duplicate_pad_numbers_are_jumpers no)
		(fp_line
			(start -0.7874 -0.4064)
			(end 0.7874 -0.4064)
			(stroke
				(width 0.1524)
				(type default)
			)
			(layer "F.SilkS")
		)
		(fp_line
			(start -0.7874 0.4064)
			(end -0.7874 -0.4064)
			(stroke
				(width 0.1524)
				(type default)
			)
			(layer "F.SilkS")
		)
		(fp_line
			(start 0.7874 -0.4064)
			(end 0.7874 0.4064)
			(stroke
				(width 0.1524)
				(type default)
			)
			(layer "F.SilkS")
		)
		(fp_line
			(start 0.7874 0.4064)
			(end -0.7874 0.4064)
			(stroke
				(width 0.1524)
				(type default)
			)
			(layer "F.SilkS")
		)
		(fp_line
			(start -0.67945 -0.305054)
			(end -0.12065 -0.305054)
			(stroke
				(width 0.1)
				(type default)
			)
			(layer "F.Fab")
		)
		(fp_line
			(start -0.67945 0.3048)
			(end -0.67945 -0.305054)
			(stroke
				(width 0.1)
				(type default)
			)
			(layer "F.Fab")
		)
		(fp_line
			(start -0.12065 -0.305054)
			(end -0.12065 -0.2794)
			(stroke
				(width 0.1)
				(type default)
			)
			(layer "F.Fab")
		)
		(fp_line
			(start -0.12065 -0.2794)
			(end 0.12065 -0.2794)
			(stroke
				(width 0.1)
				(type default)
			)
			(layer "F.Fab")
		)
		(fp_line
			(start -0.12065 0.2794)
			(end -0.12065 0.3048)
			(stroke
				(width 0.1)
				(type default)
			)
			(layer "F.Fab")
		)
		(fp_line
			(start -0.12065 0.3048)
			(end -0.67945 0.3048)
			(stroke
				(width 0.1)
				(type default)
			)
			(layer "F.Fab")
		)
		(fp_line
			(start 0.120396 0.2794)
			(end -0.12065 0.2794)
			(stroke
				(width 0.1)
				(type default)
			)
			(layer "F.Fab")
		)
		(fp_line
			(start 0.120396 0.3048)
			(end 0.120396 0.2794)
			(stroke
				(width 0.1)
				(type default)
			)
			(layer "F.Fab")
		)
		(fp_line
			(start 0.12065 -0.3048)
			(end 0.67945 -0.3048)
			(stroke
				(width 0.1)
				(type default)
			)
			(layer "F.Fab")
		)
		(fp_line
			(start 0.12065 -0.2794)
			(end 0.12065 -0.3048)
			(stroke
				(width 0.1)
				(type default)
			)
			(layer "F.Fab")
		)
		(fp_line
			(start 0.67945 -0.3048)
			(end 0.67945 0.3048)
			(stroke
				(width 0.1)
				(type default)
			)
			(layer "F.Fab")
		)
		(fp_line
			(start 0.67945 0.3048)
			(end 0.120396 0.3048)
			(stroke
				(width 0.1)
				(type default)
			)
			(layer "F.Fab")
		)
		(pad "1" smd circle
			(at -0.40005 0)
			(size 0 0)
			(layers "F.Cu" "F.Mask" "F.Paste")
			(net "P5V")
		)
		(pad "2" smd circle
			(at 0.40005 0)
			(size 0 0)
			(layers "F.Cu" "F.Mask" "F.Paste")
			(net "PVCCFA_EHV_FIVRA_CPU1_PVCC2")
		)
	)
	(footprint ""
		(layer "F.Cu")
		(at 280.761948 -258.091686)
		(property "Reference" "J6"
			(at -3.683 -81.702148 0)
			(unlocked yes)
			(layer "F.SilkS")
			(effects
				(font
					(size 0.7874 0.5842)
					(thickness 0.1524)
				)
				(justify left)
			)
		)
		(property "Value" ""
			(at 0 0 0)
			(layer "F.Fab")
			(effects
				(font
					(size 1.27 1.27)
				)
			)
		)
		(duplicate_pad_numbers_are_jumpers no)
		(fp_line
			(start -3.24993 -81.000092)
			(end -3.24993 78.022958)
			(stroke
				(width 0.1524)
				(type default)
			)
			(layer "F.SilkS")
		)
		(fp_line
			(start 3.24993 -81.000092)
			(end -3.24993 -81.000092)
			(stroke
				(width 0.1524)
				(type default)
			)
			(layer "F.SilkS")
		)
		(fp_line
			(start 3.24993 -72.00011)
			(end -3.24993 -72.00011)
			(stroke
				(width 0.1524)
				(type default)
			)
			(layer "F.SilkS")
		)
		(fp_line
			(start 3.24993 72.00011)
			(end -3.24993 72.00011)
			(stroke
				(width 0.1524)
				(type default)
			)
			(layer "F.SilkS")
		)
		(fp_line
			(start 3.24993 81.000092)
			(end 3.24993 -81.000092)
			(stroke
				(width 0.1524)
				(type default)
			)
			(layer "F.SilkS")
		)
		(fp_poly
			(pts
				(xy -4.171696 -63.877698) (xy -3.155696 -63.369698) (xy -4.171696 -62.861698)
			)
			(stroke
				(width 0)
				(type default)
			)
			(fill yes)
			(layer "F.SilkS")
		)
		(fp_line
			(start -3.24993 -81.000092)
			(end -3.24993 81.000092)
			(stroke
				(width 0.1)
				(type default)
			)
			(layer "F.Fab")
		)
		(fp_line
			(start -3.24993 81.000092)
			(end 3.24993 81.000092)
			(stroke
				(width 0.1)
				(type default)
			)
			(layer "F.Fab")
		)
		(fp_line
			(start 3.24993 -81.000092)
			(end -3.24993 -81.000092)
			(stroke
				(width 0.1)
				(type default)
			)
			(layer "F.Fab")
		)
		(fp_line
			(start 3.24993 -72.00011)
			(end -3.24993 -72.00011)
			(stroke
				(width 0.1)
				(type default)
			)
			(layer "F.Fab")
		)
		(fp_line
			(start 3.24993 -71.000112)
			(end -3.24993 -71.000112)
			(stroke
				(width 0.1)
				(type default)
			)
			(layer "F.Fab")
		)
		(fp_line
			(start 3.24993 71.000112)
			(end -3.24993 71.000112)
			(stroke
				(width 0.1)
				(type default)
			)
			(layer "F.Fab")
		)
		(fp_line
			(start 3.24993 72.00011)
			(end -3.24993 72.00011)
			(stroke
				(width 0.1)
				(type default)
			)
			(layer "F.Fab")
		)
		(fp_line
			(start 3.24993 81.000092)
			(end 3.24993 -81.000092)
			(stroke
				(width 0.1)
				(type default)
			)
			(layer "F.Fab")
		)
		(fp_poly
			(pts
				(xy -4.445 -63.832994) (xy -4.445 -62.816994) (xy -3.429 -63.324994)
			)
			(stroke
				(width 0)
				(type default)
			)
			(fill yes)
			(layer "F.Fab")
		)
		(pad "1" smd rect
			(at -2.050034 -63.324994 270)
			(size 0.519938 1.4986)
			(layers "F.Cu" "F.Mask" "F.Paste")
			(net "P12V_S3_AUX_CPU0_NVDIMM")
		)
		(pad "2" smd rect
			(at -2.050034 -62.47511 270)
			(size 0.519938 1.4986)
			(layers "F.Cu" "F.Mask" "F.Paste")
			(net "TP_CHC_CPU0_DIMM2_FRU_0")
		)
		(pad "3" smd rect
			(at -2.050034 -61.624972 270)
			(size 0.519938 1.4986)
			(layers "F.Cu" "F.Mask" "F.Paste")
			(net "P3V3_AUX")
		)
		(pad "4" smd rect
			(at -2.050034 -60.775088 270)
			(size 0.519938 1.4986)
			(layers "F.Cu" "F.Mask" "F.Paste")
			(net "I3C_SPD_DDRABCD_CPU0_LVC1_SCL_5")
		)
		(pad "5" smd rect
			(at -2.050034 -59.92495 270)
			(size 0.519938 1.4986)
			(layers "F.Cu" "F.Mask" "F.Paste")
			(net "I3C_SPD_DDRABCD_CPU0_LVC1_SDA")
		)
		(pad "6" smd rect
			(at -2.050034 -59.075066 270)
			(size 0.519938 1.4986)
			(layers "F.Cu" "F.Mask" "F.Paste")
			(net "GND")
		)
		(pad "7" smd rect
			(at -2.050034 -58.224928 270)
			(size 0.519938 1.4986)
			(layers "F.Cu" "F.Mask" "F.Paste")
			(net "M_C_CPU0_SA_DQ<0>")
		)
		(pad "8" smd rect
			(at -2.050034 -57.375044 270)
			(size 0.519938 1.4986)
			(layers "F.Cu" "F.Mask" "F.Paste")
			(net "GND")
		)
		(pad "9" smd rect
			(at -2.050034 -56.524906 270)
			(size 0.519938 1.4986)
			(layers "F.Cu" "F.Mask" "F.Paste")
			(net "M_C_CPU0_SA_DQ<1>")
		)
		(pad "10" smd rect
			(at -2.050034 -55.675022 270)
			(size 0.519938 1.4986)
			(layers "F.Cu" "F.Mask" "F.Paste")
			(net "GND")
		)
		(pad "11" smd rect
			(at -2.050034 -54.824884 270)
			(size 0.519938 1.4986)
			(layers "F.Cu" "F.Mask" "F.Paste")
			(net "M_C_CPU0_SA_DQS_DP<0>")
		)
		(pad "12" smd rect
			(at -2.050034 -53.975 270)
			(size 0.519938 1.4986)
			(layers "F.Cu" "F.Mask" "F.Paste")
			(net "M_C_CPU0_SA_DQS_DN<0>")
		)
		(pad "13" smd rect
			(at -2.050034 -53.125116 270)
			(size 0.519938 1.4986)
			(layers "F.Cu" "F.Mask" "F.Paste")
			(net "GND")
		)
		(pad "14" smd rect
			(at -2.050034 -52.274978 270)
			(size 0.519938 1.4986)
			(layers "F.Cu" "F.Mask" "F.Paste")
			(net "M_C_CPU0_SA_DQ<4>")
		)
		(pad "15" smd rect
			(at -2.050034 -51.425094 270)
			(size 0.519938 1.4986)
			(layers "F.Cu" "F.Mask" "F.Paste")
			(net "GND")
		)
		(pad "16" smd rect
			(at -2.050034 -50.574956 270)
			(size 0.519938 1.4986)
			(layers "F.Cu" "F.Mask" "F.Paste")
			(net "M_C_CPU0_SA_DQ<5>")
		)
		(pad "17" smd rect
			(at -2.050034 -49.725072 270)
			(size 0.519938 1.4986)
			(layers "F.Cu" "F.Mask" "F.Paste")
			(net "GND")
		)
		(pad "18" smd rect
			(at -2.050034 -48.874934 270)
			(size 0.519938 1.4986)
			(layers "F.Cu" "F.Mask" "F.Paste")
			(net "M_C_CPU0_SA_DQ<8>")
		)
		(pad "19" smd rect
			(at -2.050034 -48.02505 270)
			(size 0.519938 1.4986)
			(layers "F.Cu" "F.Mask" "F.Paste")
			(net "GND")
		)
		(pad "20" smd rect
			(at -2.050034 -47.174912 270)
			(size 0.519938 1.4986)
			(layers "F.Cu" "F.Mask" "F.Paste")
			(net "M_C_CPU0_SA_DQ<9>")
		)
		(pad "21" smd rect
			(at -2.050034 -46.325028 270)
			(size 0.519938 1.4986)
			(layers "F.Cu" "F.Mask" "F.Paste")
			(net "GND")
		)
		(pad "22" smd rect
			(at -2.050034 -45.47489 270)
			(size 0.519938 1.4986)
			(layers "F.Cu" "F.Mask" "F.Paste")
			(net "M_C_CPU0_SA_DQS_DP<1>")
		)
		(pad "23" smd rect
			(at -2.050034 -44.625006 270)
			(size 0.519938 1.4986)
			(layers "F.Cu" "F.Mask" "F.Paste")
			(net "M_C_CPU0_SA_DQS_DN<1>")
		)
		(pad "24" smd rect
			(at -2.050034 -43.775122 270)
			(size 0.519938 1.4986)
			(layers "F.Cu" "F.Mask" "F.Paste")
			(net "GND")
		)
		(pad "25" smd rect
			(at -2.050034 -42.924984 270)
			(size 0.519938 1.4986)
			(layers "F.Cu" "F.Mask" "F.Paste")
			(net "M_C_CPU0_SA_DQ<12>")
		)
		(pad "26" smd rect
			(at -2.050034 -42.0751 270)
			(size 0.519938 1.4986)
			(layers "F.Cu" "F.Mask" "F.Paste")
			(net "GND")
		)
		(pad "27" smd rect
			(at -2.050034 -41.224962 270)
			(size 0.519938 1.4986)
			(layers "F.Cu" "F.Mask" "F.Paste")
			(net "M_C_CPU0_SA_DQ<13>")
		)
		(pad "28" smd rect
			(at -2.050034 -40.375078 270)
			(size 0.519938 1.4986)
			(layers "F.Cu" "F.Mask" "F.Paste")
			(net "GND")
		)
		(pad "29" smd rect
			(at -2.050034 -39.52494 270)
			(size 0.519938 1.4986)
			(layers "F.Cu" "F.Mask" "F.Paste")
			(net "M_C_CPU0_SA_DQ<16>")
		)
		(pad "30" smd rect
			(at -2.050034 -38.675056 270)
			(size 0.519938 1.4986)
			(layers "F.Cu" "F.Mask" "F.Paste")
			(net "GND")
		)
		(pad "31" smd rect
			(at -2.050034 -37.824918 270)
			(size 0.519938 1.4986)
			(layers "F.Cu" "F.Mask" "F.Paste")
			(net "M_C_CPU0_SA_DQ<17>")
		)
		(pad "32" smd rect
			(at -2.050034 -36.975034 270)
			(size 0.519938 1.4986)
			(layers "F.Cu" "F.Mask" "F.Paste")
			(net "GND")
		)
		(pad "33" smd rect
			(at -2.050034 -36.124896 270)
			(size 0.519938 1.4986)
			(layers "F.Cu" "F.Mask" "F.Paste")
			(net "M_C_CPU0_SA_DQS_DP<2>")
		)
		(pad "34" smd rect
			(at -2.050034 -35.275012 270)
			(size 0.519938 1.4986)
			(layers "F.Cu" "F.Mask" "F.Paste")
			(net "M_C_CPU0_SA_DQS_DN<2>")
		)
		(pad "35" smd rect
			(at -2.050034 -34.425128 270)
			(size 0.519938 1.4986)
			(layers "F.Cu" "F.Mask" "F.Paste")
			(net "GND")
		)
		(pad "36" smd rect
			(at -2.050034 -33.57499 270)
			(size 0.519938 1.4986)
			(layers "F.Cu" "F.Mask" "F.Paste")
			(net "M_C_CPU0_SA_DQ<20>")
		)
		(pad "37" smd rect
			(at -2.050034 -32.725106 270)
			(size 0.519938 1.4986)
			(layers "F.Cu" "F.Mask" "F.Paste")
			(net "GND")
		)
		(pad "38" smd rect
			(at -2.050034 -31.874968 270)
			(size 0.519938 1.4986)
			(layers "F.Cu" "F.Mask" "F.Paste")
			(net "M_C_CPU0_SA_DQ<21>")
		)
		(pad "39" smd rect
			(at -2.050034 -31.025084 270)
			(size 0.519938 1.4986)
			(layers "F.Cu" "F.Mask" "F.Paste")
			(net "GND")
		)
		(pad "40" smd rect
			(at -2.050034 -30.174946 270)
			(size 0.519938 1.4986)
			(layers "F.Cu" "F.Mask" "F.Paste")
			(net "M_C_CPU0_SA_DQ<24>")
		)
		(pad "41" smd rect
			(at -2.050034 -29.325062 270)
			(size 0.519938 1.4986)
			(layers "F.Cu" "F.Mask" "F.Paste")
			(net "GND")
		)
		(pad "42" smd rect
			(at -2.050034 -28.474924 270)
			(size 0.519938 1.4986)
			(layers "F.Cu" "F.Mask" "F.Paste")
			(net "M_C_CPU0_SA_DQ<25>")
		)
		(pad "43" smd rect
			(at -2.050034 -27.62504 270)
			(size 0.519938 1.4986)
			(layers "F.Cu" "F.Mask" "F.Paste")
			(net "GND")
		)
		(pad "44" smd rect
			(at -2.050034 -26.774902 270)
			(size 0.519938 1.4986)
			(layers "F.Cu" "F.Mask" "F.Paste")
			(net "M_C_CPU0_SA_DQS_DP<3>")
		)
		(pad "45" smd rect
			(at -2.050034 -25.925018 270)
			(size 0.519938 1.4986)
			(layers "F.Cu" "F.Mask" "F.Paste")
			(net "M_C_CPU0_SA_DQS_DN<3>")
		)
		(pad "46" smd rect
			(at -2.050034 -25.07488 270)
			(size 0.519938 1.4986)
			(layers "F.Cu" "F.Mask" "F.Paste")
			(net "GND")
		)
		(pad "47" smd rect
			(at -2.050034 -24.224996 270)
			(size 0.519938 1.4986)
			(layers "F.Cu" "F.Mask" "F.Paste")
			(net "M_C_CPU0_SA_DQ<28>")
		)
		(pad "48" smd rect
			(at -2.050034 -23.375112 270)
			(size 0.519938 1.4986)
			(layers "F.Cu" "F.Mask" "F.Paste")
			(net "GND")
		)
		(pad "49" smd rect
			(at -2.050034 -22.524974 270)
			(size 0.519938 1.4986)
			(layers "F.Cu" "F.Mask" "F.Paste")
			(net "M_C_CPU0_SA_DQ<29>")
		)
		(pad "50" smd rect
			(at -2.050034 -21.67509 270)
			(size 0.519938 1.4986)
			(layers "F.Cu" "F.Mask" "F.Paste")
			(net "GND")
		)
		(pad "51" smd rect
			(at -2.050034 -20.824952 270)
			(size 0.519938 1.4986)
			(layers "F.Cu" "F.Mask" "F.Paste")
			(net "M_C_CPU0_SA_CB<0>")
		)
		(pad "52" smd rect
			(at -2.050034 -19.975068 270)
			(size 0.519938 1.4986)
			(layers "F.Cu" "F.Mask" "F.Paste")
			(net "GND")
		)
		(pad "53" smd rect
			(at -2.050034 -19.12493 270)
			(size 0.519938 1.4986)
			(layers "F.Cu" "F.Mask" "F.Paste")
			(net "M_C_CPU0_SA_CB<1>")
		)
		(pad "54" smd rect
			(at -2.050034 -18.275046 270)
			(size 0.519938 1.4986)
			(layers "F.Cu" "F.Mask" "F.Paste")
			(net "GND")
		)
		(pad "55" smd rect
			(at -2.050034 -17.424908 270)
			(size 0.519938 1.4986)
			(layers "F.Cu" "F.Mask" "F.Paste")
			(net "M_C_CPU0_SA_DQS_DP<4>")
		)
		(pad "56" smd rect
			(at -2.050034 -16.575024 270)
			(size 0.519938 1.4986)
			(layers "F.Cu" "F.Mask" "F.Paste")
			(net "M_C_CPU0_SA_DQS_DN<4>")
		)
		(pad "57" smd rect
			(at -2.050034 -15.724886 270)
			(size 0.519938 1.4986)
			(layers "F.Cu" "F.Mask" "F.Paste")
			(net "GND")
		)
		(pad "58" smd rect
			(at -2.050034 -14.875002 270)
			(size 0.519938 1.4986)
			(layers "F.Cu" "F.Mask" "F.Paste")
			(net "M_C_CPU0_SA_CB<4>")
		)
		(pad "59" smd rect
			(at -2.050034 -14.025118 270)
			(size 0.519938 1.4986)
			(layers "F.Cu" "F.Mask" "F.Paste")
			(net "GND")
		)
		(pad "60" smd rect
			(at -2.050034 -13.17498 270)
			(size 0.519938 1.4986)
			(layers "F.Cu" "F.Mask" "F.Paste")
			(net "M_C_CPU0_SA_CB<5>")
		)
		(pad "61" smd rect
			(at -2.050034 -12.325096 270)
			(size 0.519938 1.4986)
			(layers "F.Cu" "F.Mask" "F.Paste")
			(net "GND")
		)
		(pad "62" smd rect
			(at -2.050034 -11.474958 270)
			(size 0.519938 1.4986)
			(layers "F.Cu" "F.Mask" "F.Paste")
			(net "M_C_CPU0_ALERT_N")
		)
		(pad "63" smd rect
			(at -2.050034 -10.625074 270)
			(size 0.519938 1.4986)
			(layers "F.Cu" "F.Mask" "F.Paste")
			(net "GND")
		)
		(pad "64" smd rect
			(at -2.050034 -9.774936 270)
			(size 0.519938 1.4986)
			(layers "F.Cu" "F.Mask" "F.Paste")
			(net "M_C_CPU0_SA_CS_N<2>")
		)
		(pad "65" smd rect
			(at -2.050034 -8.925052 270)
			(size 0.519938 1.4986)
			(layers "F.Cu" "F.Mask" "F.Paste")
			(net "GND")
		)
		(pad "66" smd rect
			(at -2.050034 -8.074914 270)
			(size 0.519938 1.4986)
			(layers "F.Cu" "F.Mask" "F.Paste")
			(net "M_C_CPU0_SA_CA<0>")
		)
		(pad "67" smd rect
			(at -2.050034 -7.22503 270)
			(size 0.519938 1.4986)
			(layers "F.Cu" "F.Mask" "F.Paste")
			(net "GND")
		)
		(pad "68" smd rect
			(at -2.050034 -6.374892 270)
			(size 0.519938 1.4986)
			(layers "F.Cu" "F.Mask" "F.Paste")
			(net "M_C_CPU0_SA_CA<2>")
		)
		(pad "69" smd rect
			(at -2.050034 -5.525008 270)
			(size 0.519938 1.4986)
			(layers "F.Cu" "F.Mask" "F.Paste")
			(net "GND")
		)
		(pad "70" smd rect
			(at -2.050034 -4.675124 270)
			(size 0.519938 1.4986)
			(layers "F.Cu" "F.Mask" "F.Paste")
			(net "M_C_CPU0_SA_CA<4>")
		)
		(pad "71" smd rect
			(at -2.050034 -3.824986 270)
			(size 0.519938 1.4986)
			(layers "F.Cu" "F.Mask" "F.Paste")
			(net "GND")
		)
		(pad "72" smd rect
			(at -2.050034 -2.975102 270)
			(size 0.519938 1.4986)
			(layers "F.Cu" "F.Mask" "F.Paste")
			(net "M_C_CPU0_SA_CA<6>")
		)
		(pad "73" smd rect
			(at -2.050034 -2.124964 270)
			(size 0.519938 1.4986)
			(layers "F.Cu" "F.Mask" "F.Paste")
			(net "GND")
		)
		(pad "74" smd rect
			(at -2.050034 -1.27508 270)
			(size 0.519938 1.4986)
			(layers "F.Cu" "F.Mask" "F.Paste")
			(net "M_C_CPU0_SA_PAR")
		)
		(pad "75" smd rect
			(at -2.050034 -0.424942 270)
			(size 0.519938 1.4986)
			(layers "F.Cu" "F.Mask" "F.Paste")
			(net "GND")
		)
		(pad "76" smd rect
			(at -2.050034 5.525008 270)
			(size 0.519938 1.4986)
			(layers "F.Cu" "F.Mask" "F.Paste")
			(net "M_C_CPU0_SB_CA<0>")
		)
		(pad "77" smd rect
			(at -2.050034 6.374892 270)
			(size 0.519938 1.4986)
			(layers "F.Cu" "F.Mask" "F.Paste")
			(net "GND")
		)
		(pad "78" smd rect
			(at -2.050034 7.22503 270)
			(size 0.519938 1.4986)
			(layers "F.Cu" "F.Mask" "F.Paste")
			(net "M_C_CPU0_SB_CA<2>")
		)
		(pad "79" smd rect
			(at -2.050034 8.074914 270)
			(size 0.519938 1.4986)
			(layers "F.Cu" "F.Mask" "F.Paste")
			(net "GND")
		)
		(pad "80" smd rect
			(at -2.050034 8.925052 270)
			(size 0.519938 1.4986)
			(layers "F.Cu" "F.Mask" "F.Paste")
			(net "M_C_CPU0_SB_CA<4>")
		)
		(pad "81" smd rect
			(at -2.050034 9.774936 270)
			(size 0.519938 1.4986)
			(layers "F.Cu" "F.Mask" "F.Paste")
			(net "GND")
		)
		(pad "82" smd rect
			(at -2.050034 10.625074 270)
			(size 0.519938 1.4986)
			(layers "F.Cu" "F.Mask" "F.Paste")
			(net "M_C_CPU0_SB_CA<6>")
		)
		(pad "83" smd rect
			(at -2.050034 11.474958 270)
			(size 0.519938 1.4986)
			(layers "F.Cu" "F.Mask" "F.Paste")
			(net "GND")
		)
		(pad "84" smd rect
			(at -2.050034 12.325096 270)
			(size 0.519938 1.4986)
			(layers "F.Cu" "F.Mask" "F.Paste")
			(net "M_C_CPU0_SB_CS_N<2>")
		)
		(pad "85" smd rect
			(at -2.050034 13.17498 270)
			(size 0.519938 1.4986)
			(layers "F.Cu" "F.Mask" "F.Paste")
			(net "GND")
		)
		(pad "86" smd rect
			(at -2.050034 14.025118 270)
			(size 0.519938 1.4986)
			(layers "F.Cu" "F.Mask" "F.Paste")
			(net "M_C_CPU0_SA_RSP<1>")
		)
		(pad "87" smd rect
			(at -2.050034 14.875002 270)
			(size 0.519938 1.4986)
			(layers "F.Cu" "F.Mask" "F.Paste")
			(net "M_C_CPU0_SB_RSP<1>")
		)
		(pad "88" smd rect
			(at -2.050034 15.724886 270)
			(size 0.519938 1.4986)
			(layers "F.Cu" "F.Mask" "F.Paste")
			(net "GND")
		)
		(pad "89" smd rect
			(at -2.050034 16.575024 270)
			(size 0.519938 1.4986)
			(layers "F.Cu" "F.Mask" "F.Paste")
			(net "M_C_CPU0_SB_CB<4>")
		)
		(pad "90" smd rect
			(at -2.050034 17.424908 270)
			(size 0.519938 1.4986)
			(layers "F.Cu" "F.Mask" "F.Paste")
			(net "GND")
		)
		(pad "91" smd rect
			(at -2.050034 18.275046 270)
			(size 0.519938 1.4986)
			(layers "F.Cu" "F.Mask" "F.Paste")
			(net "M_C_CPU0_SB_CB<5>")
		)
		(pad "92" smd rect
			(at -2.050034 19.12493 270)
			(size 0.519938 1.4986)
			(layers "F.Cu" "F.Mask" "F.Paste")
			(net "GND")
		)
		(pad "93" smd rect
			(at -2.050034 19.975068 270)
			(size 0.519938 1.4986)
			(layers "F.Cu" "F.Mask" "F.Paste")
			(net "M_C_CPU0_SB_DQS_DP<9>")
		)
		(pad "94" smd rect
			(at -2.050034 20.824952 270)
			(size 0.519938 1.4986)
			(layers "F.Cu" "F.Mask" "F.Paste")
			(net "M_C_CPU0_SB_DQS_DN<9>")
		)
		(pad "95" smd rect
			(at -2.050034 21.67509 270)
			(size 0.519938 1.4986)
			(layers "F.Cu" "F.Mask" "F.Paste")
			(net "GND")
		)
		(pad "96" smd rect
			(at -2.050034 22.524974 270)
			(size 0.519938 1.4986)
			(layers "F.Cu" "F.Mask" "F.Paste")
			(net "M_C_CPU0_SB_CB<0>")
		)
		(pad "97" smd rect
			(at -2.050034 23.375112 270)
			(size 0.519938 1.4986)
			(layers "F.Cu" "F.Mask" "F.Paste")
			(net "GND")
		)
		(pad "98" smd rect
			(at -2.050034 24.224996 270)
			(size 0.519938 1.4986)
			(layers "F.Cu" "F.Mask" "F.Paste")
			(net "M_C_CPU0_SB_CB<1>")
		)
		(pad "99" smd rect
			(at -2.050034 25.07488 270)
			(size 0.519938 1.4986)
			(layers "F.Cu" "F.Mask" "F.Paste")
			(net "GND")
		)
		(pad "100" smd rect
			(at -2.050034 25.925018 270)
			(size 0.519938 1.4986)
			(layers "F.Cu" "F.Mask" "F.Paste")
			(net "M_C_CPU0_SB_DQ<0>")
		)
		(pad "101" smd rect
			(at -2.050034 26.774902 270)
			(size 0.519938 1.4986)
			(layers "F.Cu" "F.Mask" "F.Paste")
			(net "GND")
		)
		(pad "102" smd rect
			(at -2.050034 27.62504 270)
			(size 0.519938 1.4986)
			(layers "F.Cu" "F.Mask" "F.Paste")
			(net "M_C_CPU0_SB_DQ<1>")
		)
		(pad "103" smd rect
			(at -2.050034 28.474924 270)
			(size 0.519938 1.4986)
			(layers "F.Cu" "F.Mask" "F.Paste")
			(net "GND")
		)
		(pad "104" smd rect
			(at -2.050034 29.325062 270)
			(size 0.519938 1.4986)
			(layers "F.Cu" "F.Mask" "F.Paste")
			(net "M_C_CPU0_SB_DQS_DP<0>")
		)
		(pad "105" smd rect
			(at -2.050034 30.174946 270)
			(size 0.519938 1.4986)
			(layers "F.Cu" "F.Mask" "F.Paste")
			(net "M_C_CPU0_SB_DQS_DN<0>")
		)
		(pad "106" smd rect
			(at -2.050034 31.025084 270)
			(size 0.519938 1.4986)
			(layers "F.Cu" "F.Mask" "F.Paste")
			(net "GND")
		)
		(pad "107" smd rect
			(at -2.050034 31.874968 270)
			(size 0.519938 1.4986)
			(layers "F.Cu" "F.Mask" "F.Paste")
			(net "M_C_CPU0_SB_DQ<4>")
		)
		(pad "108" smd rect
			(at -2.050034 32.725106 270)
			(size 0.519938 1.4986)
			(layers "F.Cu" "F.Mask" "F.Paste")
			(net "GND")
		)
		(pad "109" smd rect
			(at -2.050034 33.57499 270)
			(size 0.519938 1.4986)
			(layers "F.Cu" "F.Mask" "F.Paste")
			(net "M_C_CPU0_SB_DQ<5>")
		)
		(pad "110" smd rect
			(at -2.050034 34.425128 270)
			(size 0.519938 1.4986)
			(layers "F.Cu" "F.Mask" "F.Paste")
			(net "GND")
		)
		(pad "111" smd rect
			(at -2.050034 35.275012 270)
			(size 0.519938 1.4986)
			(layers "F.Cu" "F.Mask" "F.Paste")
			(net "M_C_CPU0_SB_DQ<8>")
		)
		(pad "112" smd rect
			(at -2.050034 36.124896 270)
			(size 0.519938 1.4986)
			(layers "F.Cu" "F.Mask" "F.Paste")
			(net "GND")
		)
		(pad "113" smd rect
			(at -2.050034 36.975034 270)
			(size 0.519938 1.4986)
			(layers "F.Cu" "F.Mask" "F.Paste")
			(net "M_C_CPU0_SB_DQ<9>")
		)
		(pad "114" smd rect
			(at -2.050034 37.824918 270)
			(size 0.519938 1.4986)
			(layers "F.Cu" "F.Mask" "F.Paste")
			(net "GND")
		)
		(pad "115" smd rect
			(at -2.050034 38.675056 270)
			(size 0.519938 1.4986)
			(layers "F.Cu" "F.Mask" "F.Paste")
			(net "M_C_CPU0_SB_DQS_DP<1>")
		)
		(pad "116" smd rect
			(at -2.050034 39.52494 270)
			(size 0.519938 1.4986)
			(layers "F.Cu" "F.Mask" "F.Paste")
			(net "M_C_CPU0_SB_DQS_DN<1>")
		)
		(pad "117" smd rect
			(at -2.050034 40.375078 270)
			(size 0.519938 1.4986)
			(layers "F.Cu" "F.Mask" "F.Paste")
			(net "GND")
		)
		(pad "118" smd rect
			(at -2.050034 41.224962 270)
			(size 0.519938 1.4986)
			(layers "F.Cu" "F.Mask" "F.Paste")
			(net "M_C_CPU0_SB_DQ<12>")
		)
		(pad "119" smd rect
			(at -2.050034 42.0751 270)
			(size 0.519938 1.4986)
			(layers "F.Cu" "F.Mask" "F.Paste")
			(net "GND")
		)
		(pad "120" smd rect
			(at -2.050034 42.924984 270)
			(size 0.519938 1.4986)
			(layers "F.Cu" "F.Mask" "F.Paste")
			(net "M_C_CPU0_SB_DQ<13>")
		)
		(pad "121" smd rect
			(at -2.050034 43.775122 270)
			(size 0.519938 1.4986)
			(layers "F.Cu" "F.Mask" "F.Paste")
			(net "GND")
		)
		(pad "122" smd rect
			(at -2.050034 44.625006 270)
			(size 0.519938 1.4986)
			(layers "F.Cu" "F.Mask" "F.Paste")
			(net "M_C_CPU0_SB_DQ<16>")
		)
		(pad "123" smd rect
			(at -2.050034 45.47489 270)
			(size 0.519938 1.4986)
			(layers "F.Cu" "F.Mask" "F.Paste")
			(net "GND")
		)
		(pad "124" smd rect
			(at -2.050034 46.325028 270)
			(size 0.519938 1.4986)
			(layers "F.Cu" "F.Mask" "F.Paste")
			(net "M_C_CPU0_SB_DQ<17>")
		)
		(pad "125" smd rect
			(at -2.050034 47.174912 270)
			(size 0.519938 1.4986)
			(layers "F.Cu" "F.Mask" "F.Paste")
			(net "GND")
		)
		(pad "126" smd rect
			(at -2.050034 48.02505 270)
			(size 0.519938 1.4986)
			(layers "F.Cu" "F.Mask" "F.Paste")
			(net "M_C_CPU0_SB_DQS_DP<2>")
		)
		(pad "127" smd rect
			(at -2.050034 48.874934 270)
			(size 0.519938 1.4986)
			(layers "F.Cu" "F.Mask" "F.Paste")
			(net "M_C_CPU0_SB_DQS_DN<2>")
		)
		(pad "128" smd rect
			(at -2.050034 49.725072 270)
			(size 0.519938 1.4986)
			(layers "F.Cu" "F.Mask" "F.Paste")
			(net "GND")
		)
		(pad "129" smd rect
			(at -2.050034 50.574956 270)
			(size 0.519938 1.4986)
			(layers "F.Cu" "F.Mask" "F.Paste")
			(net "M_C_CPU0_SB_DQ<20>")
		)
		(pad "130" smd rect
			(at -2.050034 51.425094 270)
			(size 0.519938 1.4986)
			(layers "F.Cu" "F.Mask" "F.Paste")
			(net "GND")
		)
		(pad "131" smd rect
			(at -2.050034 52.274978 270)
			(size 0.519938 1.4986)
			(layers "F.Cu" "F.Mask" "F.Paste")
			(net "M_C_CPU0_SB_DQ<21>")
		)
		(pad "132" smd rect
			(at -2.050034 53.125116 270)
			(size 0.519938 1.4986)
			(layers "F.Cu" "F.Mask" "F.Paste")
			(net "GND")
		)
		(pad "133" smd rect
			(at -2.050034 53.975 270)
			(size 0.519938 1.4986)
			(layers "F.Cu" "F.Mask" "F.Paste")
			(net "M_C_CPU0_SB_DQ<24>")
		)
		(pad "134" smd rect
			(at -2.050034 54.824884 270)
			(size 0.519938 1.4986)
			(layers "F.Cu" "F.Mask" "F.Paste")
			(net "GND")
		)
		(pad "135" smd rect
			(at -2.050034 55.675022 270)
			(size 0.519938 1.4986)
			(layers "F.Cu" "F.Mask" "F.Paste")
			(net "M_C_CPU0_SB_DQ<25>")
		)
		(pad "136" smd rect
			(at -2.050034 56.524906 270)
			(size 0.519938 1.4986)
			(layers "F.Cu" "F.Mask" "F.Paste")
			(net "GND")
		)
		(pad "137" smd rect
			(at -2.050034 57.375044 270)
			(size 0.519938 1.4986)
			(layers "F.Cu" "F.Mask" "F.Paste")
			(net "M_C_CPU0_SB_DQS_DP<3>")
		)
		(pad "138" smd rect
			(at -2.050034 58.224928 270)
			(size 0.519938 1.4986)
			(layers "F.Cu" "F.Mask" "F.Paste")
			(net "M_C_CPU0_SB_DQS_DN<3>")
		)
		(pad "139" smd rect
			(at -2.050034 59.075066 270)
			(size 0.519938 1.4986)
			(layers "F.Cu" "F.Mask" "F.Paste")
			(net "GND")
		)
		(pad "140" smd rect
			(at -2.050034 59.92495 270)
			(size 0.519938 1.4986)
			(layers "F.Cu" "F.Mask" "F.Paste")
			(net "M_C_CPU0_SB_DQ<28>")
		)
		(pad "141" smd rect
			(at -2.050034 60.775088 270)
			(size 0.519938 1.4986)
			(layers "F.Cu" "F.Mask" "F.Paste")
			(net "GND")
		)
		(pad "142" smd rect
			(at -2.050034 61.624972 270)
			(size 0.519938 1.4986)
			(layers "F.Cu" "F.Mask" "F.Paste")
			(net "M_C_CPU0_SB_DQ<29>")
		)
		(pad "143" smd rect
			(at -2.050034 62.47511 270)
			(size 0.519938 1.4986)
			(layers "F.Cu" "F.Mask" "F.Paste")
			(net "GND")
		)
		(pad "144" smd rect
			(at -2.050034 63.324994 270)
			(size 0.519938 1.4986)
			(layers "F.Cu" "F.Mask" "F.Paste")
			(net "TP_CHC_CPU0_DIMM2_FRU_1")
		)
		(pad "145" smd rect
			(at 2.050034 -63.324994 270)
			(size 0.519938 1.4986)
			(layers "F.Cu" "F.Mask" "F.Paste")
			(net "P12V_S3_AUX_CPU0_NVDIMM")
		)
		(pad "146" smd rect
			(at 2.050034 -62.47511 270)
			(size 0.519938 1.4986)
			(layers "F.Cu" "F.Mask" "F.Paste")
			(net "P12V_S3_AUX_CPU0_NVDIMM")
		)
		(pad "147" smd rect
			(at 2.050034 -61.624972 270)
			(size 0.519938 1.4986)
			(layers "F.Cu" "F.Mask" "F.Paste")
			(net "PWRGD_CHC_CPU0_DIMM2")
		)
		(pad "148" smd rect
			(at 2.050034 -60.775088 270)
			(size 0.519938 1.4986)
			(layers "F.Cu" "F.Mask" "F.Paste")
			(net "PD_CHC_CPU0_DIMM2_SAA")
		)
		(pad "149" smd rect
			(at 2.050034 -59.92495 270)
			(size 0.519938 1.4986)
			(layers "F.Cu" "F.Mask" "F.Paste")
			(net "TP_CHC_CPU0_DIMM2_FRU_2")
		)
		(pad "150" smd rect
			(at 2.050034 -59.075066 270)
			(size 0.519938 1.4986)
			(layers "F.Cu" "F.Mask" "F.Paste")
			(net "TP_CHC_CPU0_DIMM2_FRU_3")
		)
		(pad "151" smd rect
			(at 2.050034 -58.224928 270)
			(size 0.519938 1.4986)
			(layers "F.Cu" "F.Mask" "F.Paste")
			(net "GND")
		)
		(pad "152" smd rect
			(at 2.050034 -57.375044 270)
			(size 0.519938 1.4986)
			(layers "F.Cu" "F.Mask" "F.Paste")
			(net "M_C_CPU0_SA_DQ<2>")
		)
		(pad "153" smd rect
			(at 2.050034 -56.524906 270)
			(size 0.519938 1.4986)
			(layers "F.Cu" "F.Mask" "F.Paste")
			(net "GND")
		)
		(pad "154" smd rect
			(at 2.050034 -55.675022 270)
			(size 0.519938 1.4986)
			(layers "F.Cu" "F.Mask" "F.Paste")
			(net "M_C_CPU0_SA_DQ<3>")
		)
		(pad "155" smd rect
			(at 2.050034 -54.824884 270)
			(size 0.519938 1.4986)
			(layers "F.Cu" "F.Mask" "F.Paste")
			(net "GND")
		)
		(pad "156" smd rect
			(at 2.050034 -53.975 270)
			(size 0.519938 1.4986)
			(layers "F.Cu" "F.Mask" "F.Paste")
			(net "M_C_CPU0_SA_DQS_DN<5>")
		)
		(pad "157" smd rect
			(at 2.050034 -53.125116 270)
			(size 0.519938 1.4986)
			(layers "F.Cu" "F.Mask" "F.Paste")
			(net "M_C_CPU0_SA_DQS_DP<5>")
		)
		(pad "158" smd rect
			(at 2.050034 -52.274978 270)
			(size 0.519938 1.4986)
			(layers "F.Cu" "F.Mask" "F.Paste")
			(net "GND")
		)
		(pad "159" smd rect
			(at 2.050034 -51.425094 270)
			(size 0.519938 1.4986)
			(layers "F.Cu" "F.Mask" "F.Paste")
			(net "M_C_CPU0_SA_DQ<6>")
		)
		(pad "160" smd rect
			(at 2.050034 -50.574956 270)
			(size 0.519938 1.4986)
			(layers "F.Cu" "F.Mask" "F.Paste")
			(net "GND")
		)
		(pad "161" smd rect
			(at 2.050034 -49.725072 270)
			(size 0.519938 1.4986)
			(layers "F.Cu" "F.Mask" "F.Paste")
			(net "M_C_CPU0_SA_DQ<7>")
		)
		(pad "162" smd rect
			(at 2.050034 -48.874934 270)
			(size 0.519938 1.4986)
			(layers "F.Cu" "F.Mask" "F.Paste")
			(net "GND")
		)
		(pad "163" smd rect
			(at 2.050034 -48.02505 270)
			(size 0.519938 1.4986)
			(layers "F.Cu" "F.Mask" "F.Paste")
			(net "M_C_CPU0_SA_DQ<10>")
		)
		(pad "164" smd rect
			(at 2.050034 -47.174912 270)
			(size 0.519938 1.4986)
			(layers "F.Cu" "F.Mask" "F.Paste")
			(net "GND")
		)
		(pad "165" smd rect
			(at 2.050034 -46.325028 270)
			(size 0.519938 1.4986)
			(layers "F.Cu" "F.Mask" "F.Paste")
			(net "M_C_CPU0_SA_DQ<11>")
		)
		(pad "166" smd rect
			(at 2.050034 -45.47489 270)
			(size 0.519938 1.4986)
			(layers "F.Cu" "F.Mask" "F.Paste")
			(net "GND")
		)
		(pad "167" smd rect
			(at 2.050034 -44.625006 270)
			(size 0.519938 1.4986)
			(layers "F.Cu" "F.Mask" "F.Paste")
			(net "M_C_CPU0_SA_DQS_DN<6>")
		)
		(pad "168" smd rect
			(at 2.050034 -43.775122 270)
			(size 0.519938 1.4986)
			(layers "F.Cu" "F.Mask" "F.Paste")
			(net "M_C_CPU0_SA_DQS_DP<6>")
		)
		(pad "169" smd rect
			(at 2.050034 -42.924984 270)
			(size 0.519938 1.4986)
			(layers "F.Cu" "F.Mask" "F.Paste")
			(net "GND")
		)
		(pad "170" smd rect
			(at 2.050034 -42.0751 270)
			(size 0.519938 1.4986)
			(layers "F.Cu" "F.Mask" "F.Paste")
			(net "M_C_CPU0_SA_DQ<14>")
		)
		(pad "171" smd rect
			(at 2.050034 -41.224962 270)
			(size 0.519938 1.4986)
			(layers "F.Cu" "F.Mask" "F.Paste")
			(net "GND")
		)
		(pad "172" smd rect
			(at 2.050034 -40.375078 270)
			(size 0.519938 1.4986)
			(layers "F.Cu" "F.Mask" "F.Paste")
			(net "M_C_CPU0_SA_DQ<15>")
		)
		(pad "173" smd rect
			(at 2.050034 -39.52494 270)
			(size 0.519938 1.4986)
			(layers "F.Cu" "F.Mask" "F.Paste")
			(net "GND")
		)
		(pad "174" smd rect
			(at 2.050034 -38.675056 270)
			(size 0.519938 1.4986)
			(layers "F.Cu" "F.Mask" "F.Paste")
			(net "M_C_CPU0_SA_DQ<18>")
		)
		(pad "175" smd rect
			(at 2.050034 -37.824918 270)
			(size 0.519938 1.4986)
			(layers "F.Cu" "F.Mask" "F.Paste")
			(net "GND")
		)
		(pad "176" smd rect
			(at 2.050034 -36.975034 270)
			(size 0.519938 1.4986)
			(layers "F.Cu" "F.Mask" "F.Paste")
			(net "M_C_CPU0_SA_DQ<19>")
		)
		(pad "177" smd rect
			(at 2.050034 -36.124896 270)
			(size 0.519938 1.4986)
			(layers "F.Cu" "F.Mask" "F.Paste")
			(net "GND")
		)
		(pad "178" smd rect
			(at 2.050034 -35.275012 270)
			(size 0.519938 1.4986)
			(layers "F.Cu" "F.Mask" "F.Paste")
			(net "M_C_CPU0_SA_DQS_DN<7>")
		)
		(pad "179" smd rect
			(at 2.050034 -34.425128 270)
			(size 0.519938 1.4986)
			(layers "F.Cu" "F.Mask" "F.Paste")
			(net "M_C_CPU0_SA_DQS_DP<7>")
		)
		(pad "180" smd rect
			(at 2.050034 -33.57499 270)
			(size 0.519938 1.4986)
			(layers "F.Cu" "F.Mask" "F.Paste")
			(net "GND")
		)
		(pad "181" smd rect
			(at 2.050034 -32.725106 270)
			(size 0.519938 1.4986)
			(layers "F.Cu" "F.Mask" "F.Paste")
			(net "M_C_CPU0_SA_DQ<22>")
		)
		(pad "182" smd rect
			(at 2.050034 -31.874968 270)
			(size 0.519938 1.4986)
			(layers "F.Cu" "F.Mask" "F.Paste")
			(net "GND")
		)
		(pad "183" smd rect
			(at 2.050034 -31.025084 270)
			(size 0.519938 1.4986)
			(layers "F.Cu" "F.Mask" "F.Paste")
			(net "M_C_CPU0_SA_DQ<23>")
		)
		(pad "184" smd rect
			(at 2.050034 -30.174946 270)
			(size 0.519938 1.4986)
			(layers "F.Cu" "F.Mask" "F.Paste")
			(net "GND")
		)
		(pad "185" smd rect
			(at 2.050034 -29.325062 270)
			(size 0.519938 1.4986)
			(layers "F.Cu" "F.Mask" "F.Paste")
			(net "M_C_CPU0_SA_DQ<26>")
		)
		(pad "186" smd rect
			(at 2.050034 -28.474924 270)
			(size 0.519938 1.4986)
			(layers "F.Cu" "F.Mask" "F.Paste")
			(net "GND")
		)
		(pad "187" smd rect
			(at 2.050034 -27.62504 270)
			(size 0.519938 1.4986)
			(layers "F.Cu" "F.Mask" "F.Paste")
			(net "M_C_CPU0_SA_DQ<27>")
		)
		(pad "188" smd rect
			(at 2.050034 -26.774902 270)
			(size 0.519938 1.4986)
			(layers "F.Cu" "F.Mask" "F.Paste")
			(net "GND")
		)
		(pad "189" smd rect
			(at 2.050034 -25.925018 270)
			(size 0.519938 1.4986)
			(layers "F.Cu" "F.Mask" "F.Paste")
			(net "M_C_CPU0_SA_DQS_DN<8>")
		)
		(pad "190" smd rect
			(at 2.050034 -25.07488 270)
			(size 0.519938 1.4986)
			(layers "F.Cu" "F.Mask" "F.Paste")
			(net "M_C_CPU0_SA_DQS_DP<8>")
		)
		(pad "191" smd rect
			(at 2.050034 -24.224996 270)
			(size 0.519938 1.4986)
			(layers "F.Cu" "F.Mask" "F.Paste")
			(net "GND")
		)
		(pad "192" smd rect
			(at 2.050034 -23.375112 270)
			(size 0.519938 1.4986)
			(layers "F.Cu" "F.Mask" "F.Paste")
			(net "M_C_CPU0_SA_DQ<30>")
		)
		(pad "193" smd rect
			(at 2.050034 -22.524974 270)
			(size 0.519938 1.4986)
			(layers "F.Cu" "F.Mask" "F.Paste")
			(net "GND")
		)
		(pad "194" smd rect
			(at 2.050034 -21.67509 270)
			(size 0.519938 1.4986)
			(layers "F.Cu" "F.Mask" "F.Paste")
			(net "M_C_CPU0_SA_DQ<31>")
		)
		(pad "195" smd rect
			(at 2.050034 -20.824952 270)
			(size 0.519938 1.4986)
			(layers "F.Cu" "F.Mask" "F.Paste")
			(net "GND")
		)
		(pad "196" smd rect
			(at 2.050034 -19.975068 270)
			(size 0.519938 1.4986)
			(layers "F.Cu" "F.Mask" "F.Paste")
			(net "M_C_CPU0_SA_CB<2>")
		)
		(pad "197" smd rect
			(at 2.050034 -19.12493 270)
			(size 0.519938 1.4986)
			(layers "F.Cu" "F.Mask" "F.Paste")
			(net "GND")
		)
		(pad "198" smd rect
			(at 2.050034 -18.275046 270)
			(size 0.519938 1.4986)
			(layers "F.Cu" "F.Mask" "F.Paste")
			(net "M_C_CPU0_SA_CB<3>")
		)
		(pad "199" smd rect
			(at 2.050034 -17.424908 270)
			(size 0.519938 1.4986)
			(layers "F.Cu" "F.Mask" "F.Paste")
			(net "GND")
		)
		(pad "200" smd rect
			(at 2.050034 -16.575024 270)
			(size 0.519938 1.4986)
			(layers "F.Cu" "F.Mask" "F.Paste")
			(net "M_C_CPU0_SA_DQS_DN<9>")
		)
		(pad "201" smd rect
			(at 2.050034 -15.724886 270)
			(size 0.519938 1.4986)
			(layers "F.Cu" "F.Mask" "F.Paste")
			(net "M_C_CPU0_SA_DQS_DP<9>")
		)
		(pad "202" smd rect
			(at 2.050034 -14.875002 270)
			(size 0.519938 1.4986)
			(layers "F.Cu" "F.Mask" "F.Paste")
			(net "GND")
		)
		(pad "203" smd rect
			(at 2.050034 -14.025118 270)
			(size 0.519938 1.4986)
			(layers "F.Cu" "F.Mask" "F.Paste")
			(net "M_C_CPU0_SA_CB<6>")
		)
		(pad "204" smd rect
			(at 2.050034 -13.17498 270)
			(size 0.519938 1.4986)
			(layers "F.Cu" "F.Mask" "F.Paste")
			(net "GND")
		)
		(pad "205" smd rect
			(at 2.050034 -12.325096 270)
			(size 0.519938 1.4986)
			(layers "F.Cu" "F.Mask" "F.Paste")
			(net "M_C_CPU0_SA_CB<7>")
		)
		(pad "206" smd rect
			(at 2.050034 -11.474958 270)
			(size 0.519938 1.4986)
			(layers "F.Cu" "F.Mask" "F.Paste")
			(net "GND")
		)
		(pad "207" smd rect
			(at 2.050034 -10.625074 270)
			(size 0.519938 1.4986)
			(layers "F.Cu" "F.Mask" "F.Paste")
			(net "RST_M_CD_CPU0_FPGA_N")
		)
		(pad "208" smd rect
			(at 2.050034 -9.774936 270)
			(size 0.519938 1.4986)
			(layers "F.Cu" "F.Mask" "F.Paste")
			(net "GND")
		)
		(pad "209" smd rect
			(at 2.050034 -8.925052 270)
			(size 0.519938 1.4986)
			(layers "F.Cu" "F.Mask" "F.Paste")
			(net "M_C_CPU0_SA_CS_N<3>")
		)
		(pad "210" smd rect
			(at 2.050034 -8.074914 270)
			(size 0.519938 1.4986)
			(layers "F.Cu" "F.Mask" "F.Paste")
			(net "GND")
		)
		(pad "211" smd rect
			(at 2.050034 -7.22503 270)
			(size 0.519938 1.4986)
			(layers "F.Cu" "F.Mask" "F.Paste")
			(net "M_C_CPU0_SA_CA<1>")
		)
		(pad "212" smd rect
			(at 2.050034 -6.374892 270)
			(size 0.519938 1.4986)
			(layers "F.Cu" "F.Mask" "F.Paste")
			(net "GND")
		)
		(pad "213" smd rect
			(at 2.050034 -5.525008 270)
			(size 0.519938 1.4986)
			(layers "F.Cu" "F.Mask" "F.Paste")
			(net "M_C_CPU0_SA_CA<3>")
		)
		(pad "214" smd rect
			(at 2.050034 -4.675124 270)
			(size 0.519938 1.4986)
			(layers "F.Cu" "F.Mask" "F.Paste")
			(net "GND")
		)
		(pad "215" smd rect
			(at 2.050034 -3.824986 270)
			(size 0.519938 1.4986)
			(layers "F.Cu" "F.Mask" "F.Paste")
			(net "M_C_CPU0_SA_CA<5>")
		)
		(pad "216" smd rect
			(at 2.050034 -2.975102 270)
			(size 0.519938 1.4986)
			(layers "F.Cu" "F.Mask" "F.Paste")
			(net "GND")
		)
		(pad "217" smd rect
			(at 2.050034 -2.124964 270)
			(size 0.519938 1.4986)
			(layers "F.Cu" "F.Mask" "F.Paste")
			(net "M_C_CPU0_CLK_DP<1>")
		)
		(pad "218" smd rect
			(at 2.050034 -1.27508 270)
			(size 0.519938 1.4986)
			(layers "F.Cu" "F.Mask" "F.Paste")
			(net "M_C_CPU0_CLK_DN<1>")
		)
		(pad "219" smd rect
			(at 2.050034 -0.424942 270)
			(size 0.519938 1.4986)
			(layers "F.Cu" "F.Mask" "F.Paste")
			(net "GND")
		)
		(pad "220" smd rect
			(at 2.050034 5.525008 270)
			(size 0.519938 1.4986)
			(layers "F.Cu" "F.Mask" "F.Paste")
			(net "TP_CHC_CPU0_DIMM2_FRU_4")
		)
		(pad "221" smd rect
			(at 2.050034 6.374892 270)
			(size 0.519938 1.4986)
			(layers "F.Cu" "F.Mask" "F.Paste")
			(net "M_C_CPU0_SB_CA<1>")
		)
		(pad "222" smd rect
			(at 2.050034 7.22503 270)
			(size 0.519938 1.4986)
			(layers "F.Cu" "F.Mask" "F.Paste")
			(net "GND")
		)
		(pad "223" smd rect
			(at 2.050034 8.074914 270)
			(size 0.519938 1.4986)
			(layers "F.Cu" "F.Mask" "F.Paste")
			(net "M_C_CPU0_SB_CA<3>")
		)
		(pad "224" smd rect
			(at 2.050034 8.925052 270)
			(size 0.519938 1.4986)
			(layers "F.Cu" "F.Mask" "F.Paste")
			(net "GND")
		)
		(pad "225" smd rect
			(at 2.050034 9.774936 270)
			(size 0.519938 1.4986)
			(layers "F.Cu" "F.Mask" "F.Paste")
			(net "M_C_CPU0_SB_CA<5>")
		)
		(pad "226" smd rect
			(at 2.050034 10.625074 270)
			(size 0.519938 1.4986)
			(layers "F.Cu" "F.Mask" "F.Paste")
			(net "GND")
		)
		(pad "227" smd rect
			(at 2.050034 11.474958 270)
			(size 0.519938 1.4986)
			(layers "F.Cu" "F.Mask" "F.Paste")
			(net "M_C_CPU0_SB_PAR")
		)
		(pad "228" smd rect
			(at 2.050034 12.325096 270)
			(size 0.519938 1.4986)
			(layers "F.Cu" "F.Mask" "F.Paste")
			(net "GND")
		)
		(pad "229" smd rect
			(at 2.050034 13.17498 270)
			(size 0.519938 1.4986)
			(layers "F.Cu" "F.Mask" "F.Paste")
			(net "M_C_CPU0_SB_CS_N<3>")
		)
		(pad "230" smd rect
			(at 2.050034 14.025118 270)
			(size 0.519938 1.4986)
			(layers "F.Cu" "F.Mask" "F.Paste")
			(net "GND")
		)
		(pad "231" smd rect
			(at 2.050034 14.875002 270)
			(size 0.519938 1.4986)
			(layers "F.Cu" "F.Mask" "F.Paste")
			(net "TP_CHC_CPU0_DIMM2_FRU_5")
		)
		(pad "232" smd rect
			(at 2.050034 15.724886 270)
			(size 0.519938 1.4986)
			(layers "F.Cu" "F.Mask" "F.Paste")
			(net "TP_CHC_CPU0_DIMM2_FRU_6")
		)
		(pad "233" smd rect
			(at 2.050034 16.575024 270)
			(size 0.519938 1.4986)
			(layers "F.Cu" "F.Mask" "F.Paste")
			(net "GND")
		)
		(pad "234" smd rect
			(at 2.050034 17.424908 270)
			(size 0.519938 1.4986)
			(layers "F.Cu" "F.Mask" "F.Paste")
			(net "M_C_CPU0_SB_CB<6>")
		)
		(pad "235" smd rect
			(at 2.050034 18.275046 270)
			(size 0.519938 1.4986)
			(layers "F.Cu" "F.Mask" "F.Paste")
			(net "GND")
		)
		(pad "236" smd rect
			(at 2.050034 19.12493 270)
			(size 0.519938 1.4986)
			(layers "F.Cu" "F.Mask" "F.Paste")
			(net "M_C_CPU0_SB_CB<7>")
		)
		(pad "237" smd rect
			(at 2.050034 19.975068 270)
			(size 0.519938 1.4986)
			(layers "F.Cu" "F.Mask" "F.Paste")
			(net "GND")
		)
		(pad "238" smd rect
			(at 2.050034 20.824952 270)
			(size 0.519938 1.4986)
			(layers "F.Cu" "F.Mask" "F.Paste")
			(net "M_C_CPU0_SB_DQS_DN<4>")
		)
		(pad "239" smd rect
			(at 2.050034 21.67509 270)
			(size 0.519938 1.4986)
			(layers "F.Cu" "F.Mask" "F.Paste")
			(net "M_C_CPU0_SB_DQS_DP<4>")
		)
		(pad "240" smd rect
			(at 2.050034 22.524974 270)
			(size 0.519938 1.4986)
			(layers "F.Cu" "F.Mask" "F.Paste")
			(net "GND")
		)
		(pad "241" smd rect
			(at 2.050034 23.375112 270)
			(size 0.519938 1.4986)
			(layers "F.Cu" "F.Mask" "F.Paste")
			(net "M_C_CPU0_SB_CB<2>")
		)
		(pad "242" smd rect
			(at 2.050034 24.224996 270)
			(size 0.519938 1.4986)
			(layers "F.Cu" "F.Mask" "F.Paste")
			(net "GND")
		)
		(pad "243" smd rect
			(at 2.050034 25.07488 270)
			(size 0.519938 1.4986)
			(layers "F.Cu" "F.Mask" "F.Paste")
			(net "M_C_CPU0_SB_CB<3>")
		)
		(pad "244" smd rect
			(at 2.050034 25.925018 270)
			(size 0.519938 1.4986)
			(layers "F.Cu" "F.Mask" "F.Paste")
			(net "GND")
		)
		(pad "245" smd rect
			(at 2.050034 26.774902 270)
			(size 0.519938 1.4986)
			(layers "F.Cu" "F.Mask" "F.Paste")
			(net "M_C_CPU0_SB_DQ<2>")
		)
		(pad "246" smd rect
			(at 2.050034 27.62504 270)
			(size 0.519938 1.4986)
			(layers "F.Cu" "F.Mask" "F.Paste")
			(net "GND")
		)
		(pad "247" smd rect
			(at 2.050034 28.474924 270)
			(size 0.519938 1.4986)
			(layers "F.Cu" "F.Mask" "F.Paste")
			(net "M_C_CPU0_SB_DQ<3>")
		)
		(pad "248" smd rect
			(at 2.050034 29.325062 270)
			(size 0.519938 1.4986)
			(layers "F.Cu" "F.Mask" "F.Paste")
			(net "GND")
		)
		(pad "249" smd rect
			(at 2.050034 30.174946 270)
			(size 0.519938 1.4986)
			(layers "F.Cu" "F.Mask" "F.Paste")
			(net "M_C_CPU0_SB_DQS_DN<5>")
		)
		(pad "250" smd rect
			(at 2.050034 31.025084 270)
			(size 0.519938 1.4986)
			(layers "F.Cu" "F.Mask" "F.Paste")
			(net "M_C_CPU0_SB_DQS_DP<5>")
		)
		(pad "251" smd rect
			(at 2.050034 31.874968 270)
			(size 0.519938 1.4986)
			(layers "F.Cu" "F.Mask" "F.Paste")
			(net "GND")
		)
		(pad "252" smd rect
			(at 2.050034 32.725106 270)
			(size 0.519938 1.4986)
			(layers "F.Cu" "F.Mask" "F.Paste")
			(net "M_C_CPU0_SB_DQ<6>")
		)
		(pad "253" smd rect
			(at 2.050034 33.57499 270)
			(size 0.519938 1.4986)
			(layers "F.Cu" "F.Mask" "F.Paste")
			(net "GND")
		)
		(pad "254" smd rect
			(at 2.050034 34.425128 270)
			(size 0.519938 1.4986)
			(layers "F.Cu" "F.Mask" "F.Paste")
			(net "M_C_CPU0_SB_DQ<7>")
		)
		(pad "255" smd rect
			(at 2.050034 35.275012 270)
			(size 0.519938 1.4986)
			(layers "F.Cu" "F.Mask" "F.Paste")
			(net "GND")
		)
		(pad "256" smd rect
			(at 2.050034 36.124896 270)
			(size 0.519938 1.4986)
			(layers "F.Cu" "F.Mask" "F.Paste")
			(net "M_C_CPU0_SB_DQ<10>")
		)
		(pad "257" smd rect
			(at 2.050034 36.975034 270)
			(size 0.519938 1.4986)
			(layers "F.Cu" "F.Mask" "F.Paste")
			(net "GND")
		)
		(pad "258" smd rect
			(at 2.050034 37.824918 270)
			(size 0.519938 1.4986)
			(layers "F.Cu" "F.Mask" "F.Paste")
			(net "M_C_CPU0_SB_DQ<11>")
		)
		(pad "259" smd rect
			(at 2.050034 38.675056 270)
			(size 0.519938 1.4986)
			(layers "F.Cu" "F.Mask" "F.Paste")
			(net "GND")
		)
		(pad "260" smd rect
			(at 2.050034 39.52494 270)
			(size 0.519938 1.4986)
			(layers "F.Cu" "F.Mask" "F.Paste")
			(net "M_C_CPU0_SB_DQS_DN<6>")
		)
		(pad "261" smd rect
			(at 2.050034 40.375078 270)
			(size 0.519938 1.4986)
			(layers "F.Cu" "F.Mask" "F.Paste")
			(net "M_C_CPU0_SB_DQS_DP<6>")
		)
		(pad "262" smd rect
			(at 2.050034 41.224962 270)
			(size 0.519938 1.4986)
			(layers "F.Cu" "F.Mask" "F.Paste")
			(net "GND")
		)
		(pad "263" smd rect
			(at 2.050034 42.0751 270)
			(size 0.519938 1.4986)
			(layers "F.Cu" "F.Mask" "F.Paste")
			(net "M_C_CPU0_SB_DQ<14>")
		)
		(pad "264" smd rect
			(at 2.050034 42.924984 270)
			(size 0.519938 1.4986)
			(layers "F.Cu" "F.Mask" "F.Paste")
			(net "GND")
		)
		(pad "265" smd rect
			(at 2.050034 43.775122 270)
			(size 0.519938 1.4986)
			(layers "F.Cu" "F.Mask" "F.Paste")
			(net "M_C_CPU0_SB_DQ<15>")
		)
		(pad "266" smd rect
			(at 2.050034 44.625006 270)
			(size 0.519938 1.4986)
			(layers "F.Cu" "F.Mask" "F.Paste")
			(net "GND")
		)
		(pad "267" smd rect
			(at 2.050034 45.47489 270)
			(size 0.519938 1.4986)
			(layers "F.Cu" "F.Mask" "F.Paste")
			(net "M_C_CPU0_SB_DQ<18>")
		)
		(pad "268" smd rect
			(at 2.050034 46.325028 270)
			(size 0.519938 1.4986)
			(layers "F.Cu" "F.Mask" "F.Paste")
			(net "GND")
		)
		(pad "269" smd rect
			(at 2.050034 47.174912 270)
			(size 0.519938 1.4986)
			(layers "F.Cu" "F.Mask" "F.Paste")
			(net "M_C_CPU0_SB_DQ<19>")
		)
		(pad "270" smd rect
			(at 2.050034 48.02505 270)
			(size 0.519938 1.4986)
			(layers "F.Cu" "F.Mask" "F.Paste")
			(net "GND")
		)
		(pad "271" smd rect
			(at 2.050034 48.874934 270)
			(size 0.519938 1.4986)
			(layers "F.Cu" "F.Mask" "F.Paste")
			(net "M_C_CPU0_SB_DQS_DN<7>")
		)
		(pad "272" smd rect
			(at 2.050034 49.725072 270)
			(size 0.519938 1.4986)
			(layers "F.Cu" "F.Mask" "F.Paste")
			(net "M_C_CPU0_SB_DQS_DP<7>")
		)
		(pad "273" smd rect
			(at 2.050034 50.574956 270)
			(size 0.519938 1.4986)
			(layers "F.Cu" "F.Mask" "F.Paste")
			(net "GND")
		)
		(pad "274" smd rect
			(at 2.050034 51.425094 270)
			(size 0.519938 1.4986)
			(layers "F.Cu" "F.Mask" "F.Paste")
			(net "M_C_CPU0_SB_DQ<22>")
		)
		(pad "275" smd rect
			(at 2.050034 52.274978 270)
			(size 0.519938 1.4986)
			(layers "F.Cu" "F.Mask" "F.Paste")
			(net "GND")
		)
		(pad "276" smd rect
			(at 2.050034 53.125116 270)
			(size 0.519938 1.4986)
			(layers "F.Cu" "F.Mask" "F.Paste")
			(net "M_C_CPU0_SB_DQ<23>")
		)
		(pad "277" smd rect
			(at 2.050034 53.975 270)
			(size 0.519938 1.4986)
			(layers "F.Cu" "F.Mask" "F.Paste")
			(net "GND")
		)
		(pad "278" smd rect
			(at 2.050034 54.824884 270)
			(size 0.519938 1.4986)
			(layers "F.Cu" "F.Mask" "F.Paste")
			(net "M_C_CPU0_SB_DQ<26>")
		)
		(pad "279" smd rect
			(at 2.050034 55.675022 270)
			(size 0.519938 1.4986)
			(layers "F.Cu" "F.Mask" "F.Paste")
			(net "GND")
		)
		(pad "280" smd rect
			(at 2.050034 56.524906 270)
			(size 0.519938 1.4986)
			(layers "F.Cu" "F.Mask" "F.Paste")
			(net "M_C_CPU0_SB_DQ<27>")
		)
		(pad "281" smd rect
			(at 2.050034 57.375044 270)
			(size 0.519938 1.4986)
			(layers "F.Cu" "F.Mask" "F.Paste")
			(net "GND")
		)
		(pad "282" smd rect
			(at 2.050034 58.224928 270)
			(size 0.519938 1.4986)
			(layers "F.Cu" "F.Mask" "F.Paste")
			(net "M_C_CPU0_SB_DQS_DN<8>")
		)
		(pad "283" smd rect
			(at 2.050034 59.075066 270)
			(size 0.519938 1.4986)
			(layers "F.Cu" "F.Mask" "F.Paste")
			(net "M_C_CPU0_SB_DQS_DP<8>")
		)
		(pad "284" smd rect
			(at 2.050034 59.92495 270)
			(size 0.519938 1.4986)
			(layers "F.Cu" "F.Mask" "F.Paste")
			(net "GND")
		)
		(pad "285" smd rect
			(at 2.050034 60.775088 270)
			(size 0.519938 1.4986)
			(layers "F.Cu" "F.Mask" "F.Paste")
			(net "M_C_CPU0_SB_DQ<30>")
		)
		(pad "286" smd rect
			(at 2.050034 61.624972 270)
			(size 0.519938 1.4986)
			(layers "F.Cu" "F.Mask" "F.Paste")
			(net "GND")
		)
		(pad "287" smd rect
			(at 2.050034 62.47511 270)
			(size 0.519938 1.4986)
			(layers "F.Cu" "F.Mask" "F.Paste")
			(net "M_C_CPU0_SB_DQ<31>")
		)
		(pad "288" smd rect
			(at 2.050034 63.324994 270)
			(size 0.519938 1.4986)
			(layers "F.Cu" "F.Mask" "F.Paste")
			(net "GND")
		)
		(pad "G1" thru_hole oval
			(at 0 -68.97497)
			(size 2.8194 1.5748)
			(drill oval 2.4384 1.1938)
			(layers "*.Cu" "*.Mask")
			(remove_unused_layers no)
			(net "GND")
			(clearance 0.127)
			(thermal_gap 0.127)
		)
		(pad "G2" thru_hole oval
			(at 0 3.875024)
			(size 2.8194 1.5748)
			(drill oval 2.4384 1.1938)
			(layers "*.Cu" "*.Mask")
			(remove_unused_layers no)
			(net "GND")
			(clearance 0.127)
			(thermal_gap 0.127)
		)
		(pad "G3" thru_hole oval
			(at 0 68.97497)
			(size 2.8194 1.5748)
			(drill oval 2.4384 1.1938)
			(layers "*.Cu" "*.Mask")
			(remove_unused_layers no)
			(net "GND")
			(clearance 0.127)
			(thermal_gap 0.127)
		)
	)
	(footprint ""
		(layer "F.Cu")
		(at 204.68336 -67.20332)
		(property "Reference" "D144"
			(at -1.397 2.82067 0)
			(unlocked yes)
			(layer "F.SilkS")
			(effects
				(font
					(size 0.7874 0.5842)
					(thickness 0.1524)
				)
				(justify left)
			)
		)
		(property "Value" ""
			(at 0 0 0)
			(layer "F.Fab")
			(effects
				(font
					(size 1.27 1.27)
				)
			)
		)
		(duplicate_pad_numbers_are_jumpers no)
		(fp_line
			(start -1.3208 -0.5588)
			(end 1.3208 -0.5588)
			(stroke
				(width 0.1524)
				(type default)
			)
			(layer "F.SilkS")
		)
		(fp_line
			(start -1.3208 0.5588)
			(end -1.3208 -0.5588)
			(stroke
				(width 0.1524)
				(type default)
			)
			(layer "F.SilkS")
		)
		(fp_line
			(start 1.3208 -0.5588)
			(end 1.3208 0.5588)
			(stroke
				(width 0.1524)
				(type default)
			)
			(layer "F.SilkS")
		)
		(fp_line
			(start 1.3208 0.5588)
			(end -1.3208 0.5588)
			(stroke
				(width 0.1524)
				(type default)
			)
			(layer "F.SilkS")
		)
		(fp_line
			(start 1.4732 -0.5588)
			(end 1.4732 0.5588)
			(stroke
				(width 0.1524)
				(type default)
			)
			(layer "F.SilkS")
		)
		(fp_line
			(start 1.6256 0.5588)
			(end 1.6256 -0.5588)
			(stroke
				(width 0.1524)
				(type default)
			)
			(layer "F.SilkS")
		)
		(fp_line
			(start 1.778 -0.5588)
			(end 1.3208 -0.5588)
			(stroke
				(width 0.1524)
				(type default)
			)
			(layer "F.SilkS")
		)
		(fp_line
			(start 1.778 -0.5588)
			(end 1.778 0.5588)
			(stroke
				(width 0.1524)
				(type default)
			)
			(layer "F.SilkS")
		)
		(fp_line
			(start 1.778 0.5588)
			(end 1.3208 0.5588)
			(stroke
				(width 0.1524)
				(type default)
			)
			(layer "F.SilkS")
		)
		(fp_line
			(start -0.899922 -0.40005)
			(end 0.899922 -0.40005)
			(stroke
				(width 0.1)
				(type default)
			)
			(layer "F.Fab")
		)
		(fp_line
			(start -0.899922 0.40005)
			(end -0.899922 -0.40005)
			(stroke
				(width 0.1)
				(type default)
			)
			(layer "F.Fab")
		)
		(fp_line
			(start 0.899922 -0.40005)
			(end 0.899922 0.40005)
			(stroke
				(width 0.1)
				(type default)
			)
			(layer "F.Fab")
		)
		(fp_line
			(start 0.899922 0.40005)
			(end -0.899922 0.40005)
			(stroke
				(width 0.1)
				(type default)
			)
			(layer "F.Fab")
		)
		(fp_text user "+"
			(at -1.61036 0.99187 0)
			(unlocked yes)
			(layer "F.SilkS")
			(effects
				(font
					(size 1.905 1.4224)
					(thickness 0.1524)
				)
				(justify left)
			)
		)
		(fp_text user "-"
			(at 0.14224 1.01727 0)
			(unlocked yes)
			(layer "F.SilkS")
			(effects
				(font
					(size 1.905 1.4224)
					(thickness 0.1524)
				)
				(justify left)
			)
		)
		(fp_text user "+"
			(at -2.6162 -0.22225 0)
			(unlocked yes)
			(layer "F.Fab")
			(effects
				(font
					(size 1.905 1.4224)
					(thickness 0.1524)
				)
				(justify left)
			)
		)
		(fp_text user "-"
			(at 1.651 -0.22225 0)
			(unlocked yes)
			(layer "F.Fab")
			(effects
				(font
					(size 1.905 1.4224)
					(thickness 0.1524)
				)
				(justify left)
			)
		)
		(pad "A" smd rect
			(at -0.750062 0)
			(size 0.8128 0.8128)
			(layers "F.Cu" "F.Mask" "F.Paste")
			(net "LED_P12V_SCM_FAULT")
		)
		(pad "C" smd rect
			(at 0.750062 0)
			(size 0.8128 0.8128)
			(layers "F.Cu" "F.Mask" "F.Paste")
			(net "LED_P12V_SCM_FAULT_D2")
		)
	)
	(footprint ""
		(layer "F.Cu")
		(at 300.733714 -14.506194)
		(property "Reference" "R4189"
			(at 0 0 0)
			(layer "F.SilkS")
			(hide yes)
			(effects
				(font
					(size 1.27 1.27)
				)
			)
		)
		(property "Value" ""
			(at 0 0 0)
			(layer "F.Fab")
			(effects
				(font
					(size 1.27 1.27)
				)
			)
		)
		(duplicate_pad_numbers_are_jumpers no)
		(fp_line
			(start -0.7874 -0.4064)
			(end 0.7874 -0.4064)
			(stroke
				(width 0.1524)
				(type default)
			)
			(layer "F.SilkS")
		)
		(fp_line
			(start -0.7874 0.4064)
			(end -0.7874 -0.4064)
			(stroke
				(width 0.1524)
				(type default)
			)
			(layer "F.SilkS")
		)
		(fp_line
			(start 0.7874 -0.4064)
			(end 0.7874 0.4064)
			(stroke
				(width 0.1524)
				(type default)
			)
			(layer "F.SilkS")
		)
		(fp_line
			(start 0.7874 0.4064)
			(end -0.7874 0.4064)
			(stroke
				(width 0.1524)
				(type default)
			)
			(layer "F.SilkS")
		)
		(fp_line
			(start -0.67945 -0.305054)
			(end -0.12065 -0.305054)
			(stroke
				(width 0.1)
				(type default)
			)
			(layer "F.Fab")
		)
		(fp_line
			(start -0.67945 0.3048)
			(end -0.67945 -0.305054)
			(stroke
				(width 0.1)
				(type default)
			)
			(layer "F.Fab")
		)
		(fp_line
			(start -0.12065 -0.305054)
			(end -0.12065 -0.2794)
			(stroke
				(width 0.1)
				(type default)
			)
			(layer "F.Fab")
		)
		(fp_line
			(start -0.12065 -0.2794)
			(end 0.12065 -0.2794)
			(stroke
				(width 0.1)
				(type default)
			)
			(layer "F.Fab")
		)
		(fp_line
			(start -0.12065 0.2794)
			(end -0.12065 0.3048)
			(stroke
				(width 0.1)
				(type default)
			)
			(layer "F.Fab")
		)
		(fp_line
			(start -0.12065 0.3048)
			(end -0.67945 0.3048)
			(stroke
				(width 0.1)
				(type default)
			)
			(layer "F.Fab")
		)
		(fp_line
			(start 0.120396 0.2794)
			(end -0.12065 0.2794)
			(stroke
				(width 0.1)
				(type default)
			)
			(layer "F.Fab")
		)
		(fp_line
			(start 0.120396 0.3048)
			(end 0.120396 0.2794)
			(stroke
				(width 0.1)
				(type default)
			)
			(layer "F.Fab")
		)
		(fp_line
			(start 0.12065 -0.3048)
			(end 0.67945 -0.3048)
			(stroke
				(width 0.1)
				(type default)
			)
			(layer "F.Fab")
		)
		(fp_line
			(start 0.12065 -0.2794)
			(end 0.12065 -0.3048)
			(stroke
				(width 0.1)
				(type default)
			)
			(layer "F.Fab")
		)
		(fp_line
			(start 0.67945 -0.3048)
			(end 0.67945 0.3048)
			(stroke
				(width 0.1)
				(type default)
			)
			(layer "F.Fab")
		)
		(fp_line
			(start 0.67945 0.3048)
			(end 0.120396 0.3048)
			(stroke
				(width 0.1)
				(type default)
			)
			(layer "F.Fab")
		)
		(pad "1" smd circle
			(at -0.40005 0)
			(size 0 0)
			(layers "F.Cu" "F.Mask" "F.Paste")
			(net "U271_1_ADD2")
		)
		(pad "2" smd circle
			(at 0.40005 0)
			(size 0 0)
			(layers "F.Cu" "F.Mask" "F.Paste")
			(net "GND")
		)
	)
	(footprint ""
		(layer "F.Cu")
		(at 349.0849 -63.312548)
		(property "Reference" "C142"
			(at 0 0 0)
			(layer "F.SilkS")
			(hide yes)
			(effects
				(font
					(size 1.27 1.27)
				)
			)
		)
		(property "Value" ""
			(at 0 0 0)
			(layer "F.Fab")
			(effects
				(font
					(size 1.27 1.27)
				)
			)
		)
		(duplicate_pad_numbers_are_jumpers no)
		(fp_line
			(start -0.299974 -0.150114)
			(end 0.299974 -0.150114)
			(stroke
				(width 0.1)
				(type default)
			)
			(layer "F.Fab")
		)
		(fp_line
			(start -0.299974 0.150114)
			(end -0.299974 -0.150114)
			(stroke
				(width 0.1)
				(type default)
			)
			(layer "F.Fab")
		)
		(fp_line
			(start 0.299974 -0.150114)
			(end 0.299974 0.150114)
			(stroke
				(width 0.1)
				(type default)
			)
			(layer "F.Fab")
		)
		(fp_line
			(start 0.299974 0.150114)
			(end -0.299974 0.150114)
			(stroke
				(width 0.1)
				(type default)
			)
			(layer "F.Fab")
		)
		(pad "1" smd rect
			(at -0.2667 0)
			(size 0.3048 0.381)
			(layers "F.Cu" "F.Mask" "F.Paste")
			(net "DMI_CPU0_PCH_TX_C_DP<6>")
		)
		(pad "2" smd rect
			(at 0.2667 0)
			(size 0.3048 0.381)
			(layers "F.Cu" "F.Mask" "F.Paste")
			(net "DMI_CPU0_PCH_TX_DP<6>")
		)
		(zone
			(layer "In1.Cu")
			(hatch none 0.5)
			(connect_pads
				(clearance 0)
			)
			(min_thickness 0.25)
			(keepout
				(tracks not_allowed)
				(vias allowed)
				(pads allowed)
				(copperpour not_allowed)
				(footprints allowed)
			)
			(placement
				(enabled no)
				(sheetname "")
			)
			(fill
				(thermal_gap 0.5)
				(thermal_bridge_width 0.5)
				(island_removal_mode 0)
			)
			(polygon
				(pts
					(arc
						(start 348.6912 -63.071248)
						(mid 348.637318 -63.093566)
						(end 348.615 -63.147448)
					)
					(arc
						(start 348.615 -63.477648)
						(mid 348.637318 -63.53153)
						(end 348.6912 -63.553848)
					)
					(arc
						(start 348.9452 -63.553848)
						(mid 348.999082 -63.53153)
						(end 349.0214 -63.477648)
					)
					(arc
						(start 349.0214 -63.147448)
						(mid 348.999082 -63.093566)
						(end 348.9452 -63.071248)
					)
				)
			)
		)
		(zone
			(layer "In1.Cu")
			(hatch none 0.5)
			(connect_pads
				(clearance 0)
			)
			(min_thickness 0.25)
			(keepout
				(tracks not_allowed)
				(vias allowed)
				(pads allowed)
				(copperpour not_allowed)
				(footprints allowed)
			)
			(placement
				(enabled no)
				(sheetname "")
			)
			(fill
				(thermal_gap 0.5)
				(thermal_bridge_width 0.5)
				(island_removal_mode 0)
			)
			(polygon
				(pts
					(arc
						(start 349.2246 -63.071248)
						(mid 349.170718 -63.093566)
						(end 349.1484 -63.147448)
					)
					(arc
						(start 349.1484 -63.477648)
						(mid 349.170718 -63.53153)
						(end 349.2246 -63.553848)
					)
					(arc
						(start 349.4786 -63.553848)
						(mid 349.532482 -63.53153)
						(end 349.5548 -63.477648)
					)
					(arc
						(start 349.5548 -63.147448)
						(mid 349.532482 -63.093566)
						(end 349.4786 -63.071248)
					)
				)
			)
		)
	)
	(footprint ""
		(layer "F.Cu")
		(at 22.356826 -174.113952)
		(property "Reference" "PC238"
			(at 0 0 0)
			(layer "F.SilkS")
			(hide yes)
			(effects
				(font
					(size 1.27 1.27)
				)
			)
		)
		(property "Value" ""
			(at 0 0 0)
			(layer "F.Fab")
			(effects
				(font
					(size 1.27 1.27)
				)
			)
		)
		(duplicate_pad_numbers_are_jumpers no)
		(fp_line
			(start -0.7874 -0.4064)
			(end 0.7874 -0.4064)
			(stroke
				(width 0.1524)
				(type default)
			)
			(layer "F.SilkS")
		)
		(fp_line
			(start -0.7874 0.4064)
			(end -0.7874 -0.4064)
			(stroke
				(width 0.1524)
				(type default)
			)
			(layer "F.SilkS")
		)
		(fp_line
			(start 0.7874 -0.4064)
			(end 0.7874 0.4064)
			(stroke
				(width 0.1524)
				(type default)
			)
			(layer "F.SilkS")
		)
		(fp_line
			(start 0.7874 0.4064)
			(end -0.7874 0.4064)
			(stroke
				(width 0.1524)
				(type default)
			)
			(layer "F.SilkS")
		)
		(fp_line
			(start -0.67945 -0.305054)
			(end -0.12065 -0.305054)
			(stroke
				(width 0.1)
				(type default)
			)
			(layer "F.Fab")
		)
		(fp_line
			(start -0.67945 0.3048)
			(end -0.67945 -0.305054)
			(stroke
				(width 0.1)
				(type default)
			)
			(layer "F.Fab")
		)
		(fp_line
			(start -0.12065 -0.305054)
			(end -0.12065 -0.2794)
			(stroke
				(width 0.1)
				(type default)
			)
			(layer "F.Fab")
		)
		(fp_line
			(start -0.12065 -0.2794)
			(end 0.12065 -0.2794)
			(stroke
				(width 0.1)
				(type default)
			)
			(layer "F.Fab")
		)
		(fp_line
			(start -0.12065 0.2794)
			(end -0.12065 0.3048)
			(stroke
				(width 0.1)
				(type default)
			)
			(layer "F.Fab")
		)
		(fp_line
			(start -0.12065 0.3048)
			(end -0.67945 0.3048)
			(stroke
				(width 0.1)
				(type default)
			)
			(layer "F.Fab")
		)
		(fp_line
			(start 0.120396 0.2794)
			(end -0.12065 0.2794)
			(stroke
				(width 0.1)
				(type default)
			)
			(layer "F.Fab")
		)
		(fp_line
			(start 0.120396 0.3048)
			(end 0.120396 0.2794)
			(stroke
				(width 0.1)
				(type default)
			)
			(layer "F.Fab")
		)
		(fp_line
			(start 0.12065 -0.3048)
			(end 0.67945 -0.3048)
			(stroke
				(width 0.1)
				(type default)
			)
			(layer "F.Fab")
		)
		(fp_line
			(start 0.12065 -0.2794)
			(end 0.12065 -0.3048)
			(stroke
				(width 0.1)
				(type default)
			)
			(layer "F.Fab")
		)
		(fp_line
			(start 0.67945 -0.3048)
			(end 0.67945 0.3048)
			(stroke
				(width 0.1)
				(type default)
			)
			(layer "F.Fab")
		)
		(fp_line
			(start 0.67945 0.3048)
			(end 0.120396 0.3048)
			(stroke
				(width 0.1)
				(type default)
			)
			(layer "F.Fab")
		)
		(pad "1" smd circle
			(at -0.40005 0)
			(size 0 0)
			(layers "F.Cu" "F.Mask" "F.Paste")
			(net "PVNN_MAIN_CPU1_FB")
		)
		(pad "2" smd circle
			(at 0.40005 0)
			(size 0 0)
			(layers "F.Cu" "F.Mask" "F.Paste")
			(net "PVNN_MAIN_CPU1_FB_RC")
		)
	)
	(footprint ""
		(layer "F.Cu")
		(at 260.561582 -76.533502)
		(property "Reference" "PR1328"
			(at 0 0 0)
			(layer "F.SilkS")
			(hide yes)
			(effects
				(font
					(size 1.27 1.27)
				)
			)
		)
		(property "Value" ""
			(at 0 0 0)
			(layer "F.Fab")
			(effects
				(font
					(size 1.27 1.27)
				)
			)
		)
		(duplicate_pad_numbers_are_jumpers no)
		(fp_line
			(start -0.7874 -0.4064)
			(end 0.7874 -0.4064)
			(stroke
				(width 0.1524)
				(type default)
			)
			(layer "F.SilkS")
		)
		(fp_line
			(start -0.7874 0.4064)
			(end -0.7874 -0.4064)
			(stroke
				(width 0.1524)
				(type default)
			)
			(layer "F.SilkS")
		)
		(fp_line
			(start 0.7874 -0.4064)
			(end 0.7874 0.4064)
			(stroke
				(width 0.1524)
				(type default)
			)
			(layer "F.SilkS")
		)
		(fp_line
			(start 0.7874 0.4064)
			(end -0.7874 0.4064)
			(stroke
				(width 0.1524)
				(type default)
			)
			(layer "F.SilkS")
		)
		(fp_line
			(start -0.67945 -0.305054)
			(end -0.12065 -0.305054)
			(stroke
				(width 0.1)
				(type default)
			)
			(layer "F.Fab")
		)
		(fp_line
			(start -0.67945 0.3048)
			(end -0.67945 -0.305054)
			(stroke
				(width 0.1)
				(type default)
			)
			(layer "F.Fab")
		)
		(fp_line
			(start -0.12065 -0.305054)
			(end -0.12065 -0.2794)
			(stroke
				(width 0.1)
				(type default)
			)
			(layer "F.Fab")
		)
		(fp_line
			(start -0.12065 -0.2794)
			(end 0.12065 -0.2794)
			(stroke
				(width 0.1)
				(type default)
			)
			(layer "F.Fab")
		)
		(fp_line
			(start -0.12065 0.2794)
			(end -0.12065 0.3048)
			(stroke
				(width 0.1)
				(type default)
			)
			(layer "F.Fab")
		)
		(fp_line
			(start -0.12065 0.3048)
			(end -0.67945 0.3048)
			(stroke
				(width 0.1)
				(type default)
			)
			(layer "F.Fab")
		)
		(fp_line
			(start 0.120396 0.2794)
			(end -0.12065 0.2794)
			(stroke
				(width 0.1)
				(type default)
			)
			(layer "F.Fab")
		)
		(fp_line
			(start 0.120396 0.3048)
			(end 0.120396 0.2794)
			(stroke
				(width 0.1)
				(type default)
			)
			(layer "F.Fab")
		)
		(fp_line
			(start 0.12065 -0.3048)
			(end 0.67945 -0.3048)
			(stroke
				(width 0.1)
				(type default)
			)
			(layer "F.Fab")
		)
		(fp_line
			(start 0.12065 -0.2794)
			(end 0.12065 -0.3048)
			(stroke
				(width 0.1)
				(type default)
			)
			(layer "F.Fab")
		)
		(fp_line
			(start 0.67945 -0.3048)
			(end 0.67945 0.3048)
			(stroke
				(width 0.1)
				(type default)
			)
			(layer "F.Fab")
		)
		(fp_line
			(start 0.67945 0.3048)
			(end 0.120396 0.3048)
			(stroke
				(width 0.1)
				(type default)
			)
			(layer "F.Fab")
		)
		(pad "1" smd circle
			(at -0.40005 0)
			(size 0 0)
			(layers "F.Cu" "F.Mask" "F.Paste")
			(net "P1V05_PCH_AUX_FB")
		)
		(pad "2" smd circle
			(at 0.40005 0)
			(size 0 0)
			(layers "F.Cu" "F.Mask" "F.Paste")
			(net "SH_P1V05_PCH_AUX_P")
		)
	)
	(footprint ""
		(layer "F.Cu")
		(at 477.30537 -148.043392 90)
		(property "Reference" "X44"
			(at -3.136392 -1.5367 90)
			(unlocked yes)
			(layer "F.SilkS")
			(effects
				(font
					(size 0.7874 0.5842)
					(thickness 0.1524)
				)
				(justify left)
			)
		)
		(property "Value" ""
			(at 0 0 90)
			(layer "F.Fab")
			(effects
				(font
					(size 1.27 1.27)
				)
			)
		)
		(property "Device Type" "TP_TDR_4P_FTS_TH-TP_TDR_4P_DIPA"
			(at 1.30175 1.27 180)
			(unlocked yes)
			(layer "F.Fab")
			(hide yes)
			(effects
				(font
					(size 0.635 0.4064)
					(thickness 0.1524)
				)
			)
		)
		(property "User Part Number" "N_A"
			(at 1.30175 1.27 180)
			(unlocked yes)
			(layer "Cmts.User")
			(hide yes)
			(effects
				(font
					(size 0.635 0.4064)
					(thickness 0.1524)
				)
			)
		)
		(duplicate_pad_numbers_are_jumpers no)
		(fp_line
			(start 2.54 -1.27)
			(end 0 -1.27)
			(stroke
				(width 0.1524)
				(type default)
			)
			(layer "F.SilkS")
		)
		(fp_line
			(start 0 -1.27)
			(end 0 -0.635)
			(stroke
				(width 0.1524)
				(type default)
			)
			(layer "F.SilkS")
		)
		(fp_line
			(start 2.54 -1.1303)
			(end 2.54 -1.27)
			(stroke
				(width 0.1524)
				(type default)
			)
			(layer "F.SilkS")
		)
		(fp_line
			(start 0 0.635)
			(end 0 1.905)
			(stroke
				(width 0.1524)
				(type default)
			)
			(layer "F.SilkS")
		)
		(fp_line
			(start 2.54 1.4097)
			(end 2.54 1.1303)
			(stroke
				(width 0.1524)
				(type default)
			)
			(layer "F.SilkS")
		)
		(fp_line
			(start 0 3.175)
			(end 0 3.81)
			(stroke
				(width 0.1524)
				(type default)
			)
			(layer "F.SilkS")
		)
		(fp_line
			(start 2.54 3.81)
			(end 2.54 3.6703)
			(stroke
				(width 0.1524)
				(type default)
			)
			(layer "F.SilkS")
		)
		(fp_line
			(start 0 3.81)
			(end 2.54 3.81)
			(stroke
				(width 0.1524)
				(type default)
			)
			(layer "F.SilkS")
		)
		(fp_poly
			(pts
				(xy -0.761746 0) (xy -2.285746 -0.762) (xy -2.285746 0.762)
			)
			(stroke
				(width 0)
				(type default)
			)
			(fill yes)
			(layer "F.SilkS")
		)
		(fp_line
			(start 2.54 -1.27)
			(end 0 -1.27)
			(stroke
				(width 0.1)
				(type default)
			)
			(layer "F.Fab")
		)
		(fp_line
			(start 0 -1.27)
			(end 0 3.81)
			(stroke
				(width 0.1)
				(type default)
			)
			(layer "F.Fab")
		)
		(fp_line
			(start 2.54 3.81)
			(end 2.54 -1.27)
			(stroke
				(width 0.1)
				(type default)
			)
			(layer "F.Fab")
		)
		(fp_line
			(start 0 3.81)
			(end 2.54 3.81)
			(stroke
				(width 0.1)
				(type default)
			)
			(layer "F.Fab")
		)
		(fp_poly
			(pts
				(xy -0.761746 0) (xy -2.285746 -0.762) (xy -2.285746 0.762)
			)
			(stroke
				(width 0)
				(type default)
			)
			(fill yes)
			(layer "F.Fab")
		)
		(pad "1" thru_hole circle
			(at 0 0 90)
			(size 1.0033 1.0033)
			(drill 0.249936)
			(layers "*.Cu" "*.Mask")
			(remove_unused_layers no)
			(net "TDR_DIFF_85_NECK_IN3_DN")
			(clearance 0.10795)
			(thermal_gap 0.10795)
			(padstack
				(mode front_inner_back)
				(layer "Inner"
					(shape circle)
					(size 0.8001 0.8001)
					(clearance 0.1524)
				)
				(layer "B.Cu"
					(shape circle)
					(size 1.0033 1.0033)
					(clearance 0.10795)
				)
			)
		)
		(pad "2" thru_hole circle
			(at 2.54 0 90)
			(size 1.9939 1.9939)
			(drill 0.249936)
			(layers "*.Cu" "*.Mask")
			(remove_unused_layers no)
			(net "T1_GND")
			(clearance 0.10795)
			(thermal_gap 0.10795)
			(padstack
				(mode front_inner_back)
				(layer "Inner"
					(shape circle)
					(size 0.8001 0.8001)
					(clearance 0.1524)
				)
				(layer "B.Cu"
					(shape circle)
					(size 1.9939 1.9939)
					(clearance 0.10795)
				)
			)
		)
		(pad "3" thru_hole circle
			(at 2.54 2.54 90)
			(size 1.9939 1.9939)
			(drill 0.249936)
			(layers "*.Cu" "*.Mask")
			(remove_unused_layers no)
			(net "T1_GND")
			(clearance 0.10795)
			(thermal_gap 0.10795)
			(padstack
				(mode front_inner_back)
				(layer "Inner"
					(shape circle)
					(size 0.8001 0.8001)
					(clearance 0.1524)
				)
				(layer "B.Cu"
					(shape circle)
					(size 1.9939 1.9939)
					(clearance 0.10795)
				)
			)
		)
		(pad "4" thru_hole circle
			(at 0 2.54 90)
			(size 1.0033 1.0033)
			(drill 0.249936)
			(layers "*.Cu" "*.Mask")
			(remove_unused_layers no)
			(net "TDR_DIFF_85_NECK_IN3_DP")
			(clearance 0.10795)
			(thermal_gap 0.10795)
			(padstack
				(mode front_inner_back)
				(layer "Inner"
					(shape circle)
					(size 0.8001 0.8001)
					(clearance 0.1524)
				)
				(layer "B.Cu"
					(shape circle)
					(size 1.0033 1.0033)
					(clearance 0.10795)
				)
			)
		)
	)
	(footprint ""
		(layer "F.Cu")
		(at 372.207282 -61.581792)
		(property "Reference" "C545"
			(at 0 0 0)
			(layer "F.SilkS")
			(hide yes)
			(effects
				(font
					(size 1.27 1.27)
				)
			)
		)
		(property "Value" ""
			(at 0 0 0)
			(layer "F.Fab")
			(effects
				(font
					(size 1.27 1.27)
				)
			)
		)
		(duplicate_pad_numbers_are_jumpers no)
		(fp_line
			(start -0.7874 -0.4064)
			(end 0.7874 -0.4064)
			(stroke
				(width 0.1524)
				(type default)
			)
			(layer "F.SilkS")
		)
		(fp_line
			(start -0.7874 0.4064)
			(end -0.7874 -0.4064)
			(stroke
				(width 0.1524)
				(type default)
			)
			(layer "F.SilkS")
		)
		(fp_line
			(start 0.7874 -0.4064)
			(end 0.7874 0.4064)
			(stroke
				(width 0.1524)
				(type default)
			)
			(layer "F.SilkS")
		)
		(fp_line
			(start 0.7874 0.4064)
			(end -0.7874 0.4064)
			(stroke
				(width 0.1524)
				(type default)
			)
			(layer "F.SilkS")
		)
		(fp_line
			(start -0.67945 -0.305054)
			(end -0.12065 -0.305054)
			(stroke
				(width 0.1)
				(type default)
			)
			(layer "F.Fab")
		)
		(fp_line
			(start -0.67945 0.3048)
			(end -0.67945 -0.305054)
			(stroke
				(width 0.1)
				(type default)
			)
			(layer "F.Fab")
		)
		(fp_line
			(start -0.12065 -0.305054)
			(end -0.12065 -0.2794)
			(stroke
				(width 0.1)
				(type default)
			)
			(layer "F.Fab")
		)
		(fp_line
			(start -0.12065 -0.2794)
			(end 0.12065 -0.2794)
			(stroke
				(width 0.1)
				(type default)
			)
			(layer "F.Fab")
		)
		(fp_line
			(start -0.12065 0.2794)
			(end -0.12065 0.3048)
			(stroke
				(width 0.1)
				(type default)
			)
			(layer "F.Fab")
		)
		(fp_line
			(start -0.12065 0.3048)
			(end -0.67945 0.3048)
			(stroke
				(width 0.1)
				(type default)
			)
			(layer "F.Fab")
		)
		(fp_line
			(start 0.120396 0.2794)
			(end -0.12065 0.2794)
			(stroke
				(width 0.1)
				(type default)
			)
			(layer "F.Fab")
		)
		(fp_line
			(start 0.120396 0.3048)
			(end 0.120396 0.2794)
			(stroke
				(width 0.1)
				(type default)
			)
			(layer "F.Fab")
		)
		(fp_line
			(start 0.12065 -0.3048)
			(end 0.67945 -0.3048)
			(stroke
				(width 0.1)
				(type default)
			)
			(layer "F.Fab")
		)
		(fp_line
			(start 0.12065 -0.2794)
			(end 0.12065 -0.3048)
			(stroke
				(width 0.1)
				(type default)
			)
			(layer "F.Fab")
		)
		(fp_line
			(start 0.67945 -0.3048)
			(end 0.67945 0.3048)
			(stroke
				(width 0.1)
				(type default)
			)
			(layer "F.Fab")
		)
		(fp_line
			(start 0.67945 0.3048)
			(end 0.120396 0.3048)
			(stroke
				(width 0.1)
				(type default)
			)
			(layer "F.Fab")
		)
		(pad "1" smd circle
			(at -0.40005 0)
			(size 0 0)
			(layers "F.Cu" "F.Mask" "F.Paste")
			(net "P3V3_AUX")
		)
		(pad "2" smd circle
			(at 0.40005 0)
			(size 0 0)
			(layers "F.Cu" "F.Mask" "F.Paste")
			(net "GND")
		)
	)
	(footprint ""
		(layer "F.Cu")
		(at 498.693948 -148.08454 90)
		(property "Reference" "X15"
			(at -3.42646 3.325622 90)
			(unlocked yes)
			(layer "F.SilkS")
			(effects
				(font
					(size 0.7874 0.5842)
					(thickness 0.1524)
				)
				(justify left)
			)
		)
		(property "Value" ""
			(at 0 0 90)
			(layer "F.Fab")
			(effects
				(font
					(size 1.27 1.27)
				)
			)
		)
		(property "Device Type" "TP_TDR_4P_FTS_MPKT4_H025P0200_I"
			(at 1.30175 1.27 180)
			(unlocked yes)
			(layer "F.Fab")
			(hide yes)
			(effects
				(font
					(size 0.635 0.4064)
					(thickness 0.1524)
				)
			)
		)
		(property "User Part Number" "TP15"
			(at 1.30175 1.27 180)
			(unlocked yes)
			(layer "Cmts.User")
			(hide yes)
			(effects
				(font
					(size 0.635 0.4064)
					(thickness 0.1524)
				)
			)
		)
		(duplicate_pad_numbers_are_jumpers no)
		(fp_line
			(start 2.54 -1.27)
			(end 0 -1.27)
			(stroke
				(width 0.1524)
				(type default)
			)
			(layer "F.SilkS")
		)
		(fp_line
			(start 0 -1.27)
			(end 0 -0.635)
			(stroke
				(width 0.1524)
				(type default)
			)
			(layer "F.SilkS")
		)
		(fp_line
			(start 2.54 -1.1303)
			(end 2.54 -1.27)
			(stroke
				(width 0.1524)
				(type default)
			)
			(layer "F.SilkS")
		)
		(fp_line
			(start 0 0.635)
			(end 0 1.905)
			(stroke
				(width 0.1524)
				(type default)
			)
			(layer "F.SilkS")
		)
		(fp_line
			(start 2.54 1.4097)
			(end 2.54 1.1303)
			(stroke
				(width 0.1524)
				(type default)
			)
			(layer "F.SilkS")
		)
		(fp_line
			(start 0 3.175)
			(end 0 3.81)
			(stroke
				(width 0.1524)
				(type default)
			)
			(layer "F.SilkS")
		)
		(fp_line
			(start 2.54 3.81)
			(end 2.54 3.6703)
			(stroke
				(width 0.1524)
				(type default)
			)
			(layer "F.SilkS")
		)
		(fp_line
			(start 0 3.81)
			(end 2.54 3.81)
			(stroke
				(width 0.1524)
				(type default)
			)
			(layer "F.SilkS")
		)
		(fp_poly
			(pts
				(xy -0.761746 0) (xy -2.285746 0.762) (xy -2.285746 -0.762)
			)
			(stroke
				(width 0)
				(type default)
			)
			(fill yes)
			(layer "F.SilkS")
		)
		(fp_line
			(start 2.54 -1.27)
			(end 0 -1.27)
			(stroke
				(width 0.1)
				(type default)
			)
			(layer "F.Fab")
		)
		(fp_line
			(start 0 -1.27)
			(end 0 3.81)
			(stroke
				(width 0.1)
				(type default)
			)
			(layer "F.Fab")
		)
		(fp_line
			(start 2.54 3.81)
			(end 2.54 -1.27)
			(stroke
				(width 0.1)
				(type default)
			)
			(layer "F.Fab")
		)
		(fp_line
			(start 0 3.81)
			(end 2.54 3.81)
			(stroke
				(width 0.1)
				(type default)
			)
			(layer "F.Fab")
		)
		(fp_poly
			(pts
				(xy -0.761746 0) (xy -2.285746 -0.762) (xy -2.285746 0.762)
			)
			(stroke
				(width 0)
				(type default)
			)
			(fill yes)
			(layer "F.Fab")
		)
		(pad "1" thru_hole circle
			(at 0 0 90)
			(size 1.0033 1.0033)
			(drill 0.249936)
			(layers "*.Cu" "*.Mask")
			(remove_unused_layers no)
			(net "TDR_DIFF_100_IN2_DP")
			(clearance 0.10795)
			(thermal_gap 0.10795)
			(padstack
				(mode front_inner_back)
				(layer "Inner"
					(shape circle)
					(size 0.8001 0.8001)
					(clearance 0.1524)
				)
				(layer "B.Cu"
					(shape circle)
					(size 1.0033 1.0033)
					(clearance 0.10795)
				)
			)
		)
		(pad "2" thru_hole circle
			(at 2.54 0 90)
			(size 1.9939 1.9939)
			(drill 0.249936)
			(layers "*.Cu" "*.Mask")
			(remove_unused_layers no)
			(net "T1_GND")
			(clearance 0.10795)
			(thermal_gap 0.10795)
			(padstack
				(mode front_inner_back)
				(layer "Inner"
					(shape circle)
					(size 0.8001 0.8001)
					(clearance 0.1524)
				)
				(layer "B.Cu"
					(shape circle)
					(size 1.9939 1.9939)
					(clearance 0.10795)
				)
			)
		)
		(pad "3" thru_hole circle
			(at 2.54 2.54 90)
			(size 1.9939 1.9939)
			(drill 0.249936)
			(layers "*.Cu" "*.Mask")
			(remove_unused_layers no)
			(net "T1_GND")
			(clearance 0.10795)
			(thermal_gap 0.10795)
			(padstack
				(mode front_inner_back)
				(layer "Inner"
					(shape circle)
					(size 0.8001 0.8001)
					(clearance 0.1524)
				)
				(layer "B.Cu"
					(shape circle)
					(size 1.9939 1.9939)
					(clearance 0.10795)
				)
			)
		)
		(pad "4" thru_hole circle
			(at 0 2.54 90)
			(size 1.0033 1.0033)
			(drill 0.249936)
			(layers "*.Cu" "*.Mask")
			(remove_unused_layers no)
			(net "TDR_DIFF_100_IN2_DN")
			(clearance 0.10795)
			(thermal_gap 0.10795)
			(padstack
				(mode front_inner_back)
				(layer "Inner"
					(shape circle)
					(size 0.8001 0.8001)
					(clearance 0.1524)
				)
				(layer "B.Cu"
					(shape circle)
					(size 1.0033 1.0033)
					(clearance 0.10795)
				)
			)
		)
	)
	(footprint ""
		(layer "F.Cu")
		(at 157.02788 -117.566948 180)
		(property "Reference" "R3174"
			(at 0 0 180)
			(layer "F.SilkS")
			(hide yes)
			(effects
				(font
					(size 1.27 1.27)
				)
			)
		)
		(property "Value" ""
			(at 0 0 180)
			(layer "F.Fab")
			(effects
				(font
					(size 1.27 1.27)
				)
			)
		)
		(duplicate_pad_numbers_are_jumpers no)
		(fp_line
			(start 0.7874 0.4064)
			(end -0.7874 0.4064)
			(stroke
				(width 0.1524)
				(type default)
			)
			(layer "F.SilkS")
		)
		(fp_line
			(start 0.7874 -0.4064)
			(end 0.7874 0.4064)
			(stroke
				(width 0.1524)
				(type default)
			)
			(layer "F.SilkS")
		)
		(fp_line
			(start -0.7874 0.4064)
			(end -0.7874 -0.4064)
			(stroke
				(width 0.1524)
				(type default)
			)
			(layer "F.SilkS")
		)
		(fp_line
			(start -0.7874 -0.4064)
			(end 0.7874 -0.4064)
			(stroke
				(width 0.1524)
				(type default)
			)
			(layer "F.SilkS")
		)
		(fp_line
			(start 0.67945 0.3048)
			(end 0.120396 0.3048)
			(stroke
				(width 0.1)
				(type default)
			)
			(layer "F.Fab")
		)
		(fp_line
			(start 0.67945 -0.3048)
			(end 0.67945 0.3048)
			(stroke
				(width 0.1)
				(type default)
			)
			(layer "F.Fab")
		)
		(fp_line
			(start 0.12065 -0.2794)
			(end 0.12065 -0.3048)
			(stroke
				(width 0.1)
				(type default)
			)
			(layer "F.Fab")
		)
		(fp_line
			(start 0.12065 -0.3048)
			(end 0.67945 -0.3048)
			(stroke
				(width 0.1)
				(type default)
			)
			(layer "F.Fab")
		)
		(fp_line
			(start 0.120396 0.3048)
			(end 0.120396 0.2794)
			(stroke
				(width 0.1)
				(type default)
			)
			(layer "F.Fab")
		)
		(fp_line
			(start 0.120396 0.2794)
			(end -0.12065 0.2794)
			(stroke
				(width 0.1)
				(type default)
			)
			(layer "F.Fab")
		)
		(fp_line
			(start -0.12065 0.3048)
			(end -0.67945 0.3048)
			(stroke
				(width 0.1)
				(type default)
			)
			(layer "F.Fab")
		)
		(fp_line
			(start -0.12065 0.2794)
			(end -0.12065 0.3048)
			(stroke
				(width 0.1)
				(type default)
			)
			(layer "F.Fab")
		)
		(fp_line
			(start -0.12065 -0.2794)
			(end 0.12065 -0.2794)
			(stroke
				(width 0.1)
				(type default)
			)
			(layer "F.Fab")
		)
		(fp_line
			(start -0.12065 -0.305054)
			(end -0.12065 -0.2794)
			(stroke
				(width 0.1)
				(type default)
			)
			(layer "F.Fab")
		)
		(fp_line
			(start -0.67945 0.3048)
			(end -0.67945 -0.305054)
			(stroke
				(width 0.1)
				(type default)
			)
			(layer "F.Fab")
		)
		(fp_line
			(start -0.67945 -0.305054)
			(end -0.12065 -0.305054)
			(stroke
				(width 0.1)
				(type default)
			)
			(layer "F.Fab")
		)
		(pad "1" smd circle
			(at -0.40005 0 180)
			(size 0 0)
			(layers "F.Cu" "F.Mask" "F.Paste")
			(net "SGPIO_OCP_V3_2_DATAIN")
		)
		(pad "2" smd circle
			(at 0.40005 0 180)
			(size 0 0)
			(layers "F.Cu" "F.Mask" "F.Paste")
			(net "P3V3_OCP_V3_2")
		)
	)
	(footprint ""
		(layer "F.Cu")
		(at 107.28833 -240.277142 90)
		(property "Reference" "C296"
			(at 0 0 90)
			(layer "F.SilkS")
			(hide yes)
			(effects
				(font
					(size 1.27 1.27)
				)
			)
		)
		(property "Value" ""
			(at 0 0 90)
			(layer "F.Fab")
			(effects
				(font
					(size 1.27 1.27)
				)
			)
		)
		(duplicate_pad_numbers_are_jumpers no)
		(fp_line
			(start 0.7874 -0.4064)
			(end 0.7874 0.4064)
			(stroke
				(width 0.1524)
				(type default)
			)
			(layer "F.SilkS")
		)
		(fp_line
			(start -0.7874 -0.4064)
			(end 0.7874 -0.4064)
			(stroke
				(width 0.1524)
				(type default)
			)
			(layer "F.SilkS")
		)
		(fp_line
			(start 0.7874 0.4064)
			(end -0.7874 0.4064)
			(stroke
				(width 0.1524)
				(type default)
			)
			(layer "F.SilkS")
		)
		(fp_line
			(start -0.7874 0.4064)
			(end -0.7874 -0.4064)
			(stroke
				(width 0.1524)
				(type default)
			)
			(layer "F.SilkS")
		)
		(fp_line
			(start -0.12065 -0.305054)
			(end -0.12065 -0.2794)
			(stroke
				(width 0.1)
				(type default)
			)
			(layer "F.Fab")
		)
		(fp_line
			(start -0.67945 -0.305054)
			(end -0.12065 -0.305054)
			(stroke
				(width 0.1)
				(type default)
			)
			(layer "F.Fab")
		)
		(fp_line
			(start 0.67945 -0.3048)
			(end 0.67945 0.3048)
			(stroke
				(width 0.1)
				(type default)
			)
			(layer "F.Fab")
		)
		(fp_line
			(start 0.12065 -0.3048)
			(end 0.67945 -0.3048)
			(stroke
				(width 0.1)
				(type default)
			)
			(layer "F.Fab")
		)
		(fp_line
			(start 0.12065 -0.2794)
			(end 0.12065 -0.3048)
			(stroke
				(width 0.1)
				(type default)
			)
			(layer "F.Fab")
		)
		(fp_line
			(start -0.12065 -0.2794)
			(end 0.12065 -0.2794)
			(stroke
				(width 0.1)
				(type default)
			)
			(layer "F.Fab")
		)
		(fp_line
			(start 0.120396 0.2794)
			(end -0.12065 0.2794)
			(stroke
				(width 0.1)
				(type default)
			)
			(layer "F.Fab")
		)
		(fp_line
			(start -0.12065 0.2794)
			(end -0.12065 0.3048)
			(stroke
				(width 0.1)
				(type default)
			)
			(layer "F.Fab")
		)
		(fp_line
			(start 0.67945 0.3048)
			(end 0.120396 0.3048)
			(stroke
				(width 0.1)
				(type default)
			)
			(layer "F.Fab")
		)
		(fp_line
			(start 0.120396 0.3048)
			(end 0.120396 0.2794)
			(stroke
				(width 0.1)
				(type default)
			)
			(layer "F.Fab")
		)
		(fp_line
			(start -0.12065 0.3048)
			(end -0.67945 0.3048)
			(stroke
				(width 0.1)
				(type default)
			)
			(layer "F.Fab")
		)
		(fp_line
			(start -0.67945 0.3048)
			(end -0.67945 -0.305054)
			(stroke
				(width 0.1)
				(type default)
			)
			(layer "F.Fab")
		)
		(pad "1" smd circle
			(at -0.40005 0 90)
			(size 0 0)
			(layers "F.Cu" "F.Mask" "F.Paste")
			(net "PVCCIN_CPU1")
		)
		(pad "2" smd circle
			(at 0.40005 0 90)
			(size 0 0)
			(layers "F.Cu" "F.Mask" "F.Paste")
			(net "GND")
		)
	)
	(footprint ""
		(layer "F.Cu")
		(at 101.833934 -391.61974)
		(property "Reference" "R3461"
			(at 0 0 0)
			(layer "F.SilkS")
			(hide yes)
			(effects
				(font
					(size 1.27 1.27)
				)
			)
		)
		(property "Value" ""
			(at 0 0 0)
			(layer "F.Fab")
			(effects
				(font
					(size 1.27 1.27)
				)
			)
		)
		(duplicate_pad_numbers_are_jumpers no)
		(fp_line
			(start -0.7874 -0.4064)
			(end 0.7874 -0.4064)
			(stroke
				(width 0.1524)
				(type default)
			)
			(layer "F.SilkS")
		)
		(fp_line
			(start -0.7874 0.4064)
			(end -0.7874 -0.4064)
			(stroke
				(width 0.1524)
				(type default)
			)
			(layer "F.SilkS")
		)
		(fp_line
			(start 0.7874 -0.4064)
			(end 0.7874 0.4064)
			(stroke
				(width 0.1524)
				(type default)
			)
			(layer "F.SilkS")
		)
		(fp_line
			(start 0.7874 0.4064)
			(end -0.7874 0.4064)
			(stroke
				(width 0.1524)
				(type default)
			)
			(layer "F.SilkS")
		)
		(fp_line
			(start -0.67945 -0.305054)
			(end -0.12065 -0.305054)
			(stroke
				(width 0.1)
				(type default)
			)
			(layer "F.Fab")
		)
		(fp_line
			(start -0.67945 0.3048)
			(end -0.67945 -0.305054)
			(stroke
				(width 0.1)
				(type default)
			)
			(layer "F.Fab")
		)
		(fp_line
			(start -0.12065 -0.305054)
			(end -0.12065 -0.2794)
			(stroke
				(width 0.1)
				(type default)
			)
			(layer "F.Fab")
		)
		(fp_line
			(start -0.12065 -0.2794)
			(end 0.12065 -0.2794)
			(stroke
				(width 0.1)
				(type default)
			)
			(layer "F.Fab")
		)
		(fp_line
			(start -0.12065 0.2794)
			(end -0.12065 0.3048)
			(stroke
				(width 0.1)
				(type default)
			)
			(layer "F.Fab")
		)
		(fp_line
			(start -0.12065 0.3048)
			(end -0.67945 0.3048)
			(stroke
				(width 0.1)
				(type default)
			)
			(layer "F.Fab")
		)
		(fp_line
			(start 0.120396 0.2794)
			(end -0.12065 0.2794)
			(stroke
				(width 0.1)
				(type default)
			)
			(layer "F.Fab")
		)
		(fp_line
			(start 0.120396 0.3048)
			(end 0.120396 0.2794)
			(stroke
				(width 0.1)
				(type default)
			)
			(layer "F.Fab")
		)
		(fp_line
			(start 0.12065 -0.3048)
			(end 0.67945 -0.3048)
			(stroke
				(width 0.1)
				(type default)
			)
			(layer "F.Fab")
		)
		(fp_line
			(start 0.12065 -0.2794)
			(end 0.12065 -0.3048)
			(stroke
				(width 0.1)
				(type default)
			)
			(layer "F.Fab")
		)
		(fp_line
			(start 0.67945 -0.3048)
			(end 0.67945 0.3048)
			(stroke
				(width 0.1)
				(type default)
			)
			(layer "F.Fab")
		)
		(fp_line
			(start 0.67945 0.3048)
			(end 0.120396 0.3048)
			(stroke
				(width 0.1)
				(type default)
			)
			(layer "F.Fab")
		)
		(pad "1" smd circle
			(at -0.40005 0)
			(size 0 0)
			(layers "F.Cu" "F.Mask" "F.Paste")
			(net "P3V3_AUX")
		)
		(pad "2" smd circle
			(at 0.40005 0)
			(size 0 0)
			(layers "F.Cu" "F.Mask" "F.Paste")
			(net "GPU_NVS_PWR_BRAKE_N_R")
		)
	)
	(footprint ""
		(layer "F.Cu")
		(at 418.2491 -371.783356)
		(property "Reference" "PL101"
			(at -1.12014 -4.478528 0)
			(unlocked yes)
			(layer "F.SilkS")
			(effects
				(font
					(size 0.7874 0.5842)
					(thickness 0.1524)
				)
				(justify left)
			)
		)
		(property "Value" ""
			(at 0 0 0)
			(layer "F.Fab")
			(effects
				(font
					(size 1.27 1.27)
				)
			)
		)
		(duplicate_pad_numbers_are_jumpers no)
		(fp_line
			(start -2.249932 -2.249932)
			(end 2.249932 -2.249932)
			(stroke
				(width 0.1524)
				(type default)
			)
			(layer "F.SilkS")
		)
		(fp_line
			(start -2.249932 -1.3843)
			(end -2.249932 -2.249932)
			(stroke
				(width 0.1524)
				(type default)
			)
			(layer "F.SilkS")
		)
		(fp_line
			(start -2.249932 2.249932)
			(end -2.249932 1.3843)
			(stroke
				(width 0.1524)
				(type default)
			)
			(layer "F.SilkS")
		)
		(fp_line
			(start 2.249932 -2.249932)
			(end 2.249932 -1.3843)
			(stroke
				(width 0.1524)
				(type default)
			)
			(layer "F.SilkS")
		)
		(fp_line
			(start 2.249932 1.3843)
			(end 2.249932 2.249932)
			(stroke
				(width 0.1524)
				(type default)
			)
			(layer "F.SilkS")
		)
		(fp_line
			(start 2.249932 2.249932)
			(end -2.249932 2.249932)
			(stroke
				(width 0.1524)
				(type default)
			)
			(layer "F.SilkS")
		)
		(fp_line
			(start -2.249932 -2.249932)
			(end 2.249932 -2.249932)
			(stroke
				(width 0.1)
				(type default)
			)
			(layer "F.Fab")
		)
		(fp_line
			(start -2.249932 2.249932)
			(end -2.249932 -2.249932)
			(stroke
				(width 0.1)
				(type default)
			)
			(layer "F.Fab")
		)
		(fp_line
			(start 2.249932 -2.249932)
			(end 2.249932 2.249932)
			(stroke
				(width 0.1)
				(type default)
			)
			(layer "F.Fab")
		)
		(fp_line
			(start 2.249932 2.249932)
			(end -2.249932 2.249932)
			(stroke
				(width 0.1)
				(type default)
			)
			(layer "F.Fab")
		)
		(pad "1" smd rect
			(at -1.82499 0)
			(size 1.0668 2.5146)
			(layers "F.Cu" "F.Mask" "F.Paste")
			(net "P12V_AUX")
		)
		(pad "2" smd rect
			(at 1.82499 0)
			(size 1.0668 2.5146)
			(layers "F.Cu" "F.Mask" "F.Paste")
			(net "SW_P12V_PVCCFA_EHV_FIVRA_CPU0_R")
		)
	)
	(footprint ""
		(layer "F.Cu")
		(at 154.34945 -81.889346 -90)
		(property "Reference" "R3223"
			(at 0 0 270)
			(layer "F.SilkS")
			(hide yes)
			(effects
				(font
					(size 1.27 1.27)
				)
			)
		)
		(property "Value" ""
			(at 0 0 270)
			(layer "F.Fab")
			(effects
				(font
					(size 1.27 1.27)
				)
			)
		)
		(duplicate_pad_numbers_are_jumpers no)
		(fp_line
			(start -0.7874 0.4064)
			(end -0.7874 -0.4064)
			(stroke
				(width 0.1524)
				(type default)
			)
			(layer "F.SilkS")
		)
		(fp_line
			(start 0.7874 0.4064)
			(end -0.7874 0.4064)
			(stroke
				(width 0.1524)
				(type default)
			)
			(layer "F.SilkS")
		)
		(fp_line
			(start -0.7874 -0.4064)
			(end 0.7874 -0.4064)
			(stroke
				(width 0.1524)
				(type default)
			)
			(layer "F.SilkS")
		)
		(fp_line
			(start 0.7874 -0.4064)
			(end 0.7874 0.4064)
			(stroke
				(width 0.1524)
				(type default)
			)
			(layer "F.SilkS")
		)
		(fp_line
			(start -0.67945 0.3048)
			(end -0.67945 -0.305054)
			(stroke
				(width 0.1)
				(type default)
			)
			(layer "F.Fab")
		)
		(fp_line
			(start -0.12065 0.3048)
			(end -0.67945 0.3048)
			(stroke
				(width 0.1)
				(type default)
			)
			(layer "F.Fab")
		)
		(fp_line
			(start 0.120396 0.3048)
			(end 0.120396 0.2794)
			(stroke
				(width 0.1)
				(type default)
			)
			(layer "F.Fab")
		)
		(fp_line
			(start 0.67945 0.3048)
			(end 0.120396 0.3048)
			(stroke
				(width 0.1)
				(type default)
			)
			(layer "F.Fab")
		)
		(fp_line
			(start -0.12065 0.2794)
			(end -0.12065 0.3048)
			(stroke
				(width 0.1)
				(type default)
			)
			(layer "F.Fab")
		)
		(fp_line
			(start 0.120396 0.2794)
			(end -0.12065 0.2794)
			(stroke
				(width 0.1)
				(type default)
			)
			(layer "F.Fab")
		)
		(fp_line
			(start -0.12065 -0.2794)
			(end 0.12065 -0.2794)
			(stroke
				(width 0.1)
				(type default)
			)
			(layer "F.Fab")
		)
		(fp_line
			(start 0.12065 -0.2794)
			(end 0.12065 -0.3048)
			(stroke
				(width 0.1)
				(type default)
			)
			(layer "F.Fab")
		)
		(fp_line
			(start 0.12065 -0.3048)
			(end 0.67945 -0.3048)
			(stroke
				(width 0.1)
				(type default)
			)
			(layer "F.Fab")
		)
		(fp_line
			(start 0.67945 -0.3048)
			(end 0.67945 0.3048)
			(stroke
				(width 0.1)
				(type default)
			)
			(layer "F.Fab")
		)
		(fp_line
			(start -0.67945 -0.305054)
			(end -0.12065 -0.305054)
			(stroke
				(width 0.1)
				(type default)
			)
			(layer "F.Fab")
		)
		(fp_line
			(start -0.12065 -0.305054)
			(end -0.12065 -0.2794)
			(stroke
				(width 0.1)
				(type default)
			)
			(layer "F.Fab")
		)
		(pad "1" smd circle
			(at -0.40005 0 270)
			(size 0 0)
			(layers "F.Cu" "F.Mask" "F.Paste")
			(net "SMB_S3M_CPU0_PIROM_3V3AUX_SDA")
		)
		(pad "2" smd circle
			(at 0.40005 0 270)
			(size 0 0)
			(layers "F.Cu" "F.Mask" "F.Paste")
			(net "P3V3_AUX")
		)
	)
	(footprint ""
		(layer "F.Cu")
		(at 96.039686 -423.820336 -90)
		(property "Reference" "Q108"
			(at 6.415278 4.683506 0)
			(unlocked yes)
			(layer "F.SilkS")
			(effects
				(font
					(size 0.7874 0.5842)
					(thickness 0.1524)
				)
				(justify left)
			)
		)
		(property "Value" ""
			(at 0 0 270)
			(layer "F.Fab")
			(effects
				(font
					(size 1.27 1.27)
				)
			)
		)
		(duplicate_pad_numbers_are_jumpers no)
		(fp_line
			(start -1.332738 1.100074)
			(end -1.332738 -1.100074)
			(stroke
				(width 0.1524)
				(type default)
			)
			(layer "F.SilkS")
		)
		(fp_line
			(start 1.332738 1.100074)
			(end -1.332738 1.100074)
			(stroke
				(width 0.1524)
				(type default)
			)
			(layer "F.SilkS")
		)
		(fp_line
			(start 0 -0.541274)
			(end 0.4826 -1.100074)
			(stroke
				(width 0.1524)
				(type default)
			)
			(layer "F.SilkS")
		)
		(fp_line
			(start -1.332738 -1.100074)
			(end -0.4826 -1.100074)
			(stroke
				(width 0.1524)
				(type default)
			)
			(layer "F.SilkS")
		)
		(fp_line
			(start -0.4826 -1.100074)
			(end 0 -0.541274)
			(stroke
				(width 0.1524)
				(type default)
			)
			(layer "F.SilkS")
		)
		(fp_line
			(start 0.4826 -1.100074)
			(end 1.332738 -1.100074)
			(stroke
				(width 0.1524)
				(type default)
			)
			(layer "F.SilkS")
		)
		(fp_line
			(start 1.332738 -1.100074)
			(end 1.332738 1.100074)
			(stroke
				(width 0.1524)
				(type default)
			)
			(layer "F.SilkS")
		)
		(fp_poly
			(pts
				(xy -2.44856 -1.462532) (xy -1.746504 -1.111504) (xy -2.44856 -0.760476)
			)
			(stroke
				(width 0)
				(type default)
			)
			(fill yes)
			(layer "F.SilkS")
		)
		(fp_line
			(start -0.674878 1.100074)
			(end -0.674878 -1.100074)
			(stroke
				(width 0.1)
				(type default)
			)
			(layer "F.Fab")
		)
		(fp_line
			(start 0.674878 1.100074)
			(end -0.674878 1.100074)
			(stroke
				(width 0.1)
				(type default)
			)
			(layer "F.Fab")
		)
		(fp_line
			(start -0.674878 -1.100074)
			(end 0.674878 -1.100074)
			(stroke
				(width 0.1)
				(type default)
			)
			(layer "F.Fab")
		)
		(fp_line
			(start 0.674878 -1.100074)
			(end 0.674878 1.100074)
			(stroke
				(width 0.1)
				(type default)
			)
			(layer "F.Fab")
		)
		(fp_poly
			(pts
				(xy -2.2352 -0.298958) (xy -2.2352 -1.001014) (xy -1.533144 -0.649986)
			)
			(stroke
				(width 0)
				(type default)
			)
			(fill yes)
			(layer "F.Fab")
		)
		(pad "1" smd rect
			(at -0.94996 -0.649986)
			(size 0.4318 0.508)
			(layers "F.Cu" "F.Mask" "F.Paste")
			(net "GND")
		)
		(pad "2" smd rect
			(at -0.94996 0)
			(size 0.4318 0.508)
			(layers "F.Cu" "F.Mask" "F.Paste")
			(net "GPU_FPGA_EROT_FATALERR_N")
		)
		(pad "3" smd rect
			(at -0.94996 0.649986)
			(size 0.4318 0.508)
			(layers "F.Cu" "F.Mask" "F.Paste")
			(net "GPU_FPGA_EROT_FATALERR_ISO_N")
		)
		(pad "4" smd rect
			(at 0.94996 0.649986)
			(size 0.4318 0.508)
			(layers "F.Cu" "F.Mask" "F.Paste")
			(net "GND")
		)
		(pad "5" smd rect
			(at 0.94996 0)
			(size 0.4318 0.508)
			(layers "F.Cu" "F.Mask" "F.Paste")
			(net "GPU_FPGA_EROT_FATALERR")
		)
		(pad "6" smd rect
			(at 0.94996 -0.649986)
			(size 0.4318 0.508)
			(layers "F.Cu" "F.Mask" "F.Paste")
			(net "GPU_FPGA_EROT_FATALERR")
		)
	)
	(footprint ""
		(layer "F.Cu")
		(at 214.344504 -17.766792 -90)
		(property "Reference" "U90"
			(at -1.504696 -2.230882 0)
			(unlocked yes)
			(layer "F.SilkS")
			(effects
				(font
					(size 0.7874 0.5842)
					(thickness 0.1524)
				)
				(justify left)
			)
		)
		(property "Value" ""
			(at 0 0 270)
			(layer "F.Fab")
			(effects
				(font
					(size 1.27 1.27)
				)
			)
		)
		(duplicate_pad_numbers_are_jumpers no)
		(fp_line
			(start -2.25044 1.5494)
			(end -2.25044 1.3208)
			(stroke
				(width 0.1524)
				(type default)
			)
			(layer "F.SilkS")
		)
		(fp_line
			(start 2.25044 1.5494)
			(end -2.25044 1.5494)
			(stroke
				(width 0.1524)
				(type default)
			)
			(layer "F.SilkS")
		)
		(fp_line
			(start 2.25044 1.3208)
			(end 2.25044 1.5494)
			(stroke
				(width 0.1524)
				(type default)
			)
			(layer "F.SilkS")
		)
		(fp_line
			(start 0 -0.9652)
			(end -0.5842 -1.5494)
			(stroke
				(width 0.1524)
				(type default)
			)
			(layer "F.SilkS")
		)
		(fp_line
			(start 2.25044 -1.3208)
			(end 2.25044 -1.5494)
			(stroke
				(width 0.1524)
				(type default)
			)
			(layer "F.SilkS")
		)
		(fp_line
			(start -2.25044 -1.5494)
			(end -2.25044 -1.3208)
			(stroke
				(width 0.1524)
				(type default)
			)
			(layer "F.SilkS")
		)
		(fp_line
			(start -0.5842 -1.5494)
			(end -2.25044 -1.5494)
			(stroke
				(width 0.1524)
				(type default)
			)
			(layer "F.SilkS")
		)
		(fp_line
			(start 0.5842 -1.5494)
			(end 0 -0.9652)
			(stroke
				(width 0.1524)
				(type default)
			)
			(layer "F.SilkS")
		)
		(fp_line
			(start 2.0066 -1.5494)
			(end 0.5842 -1.5494)
			(stroke
				(width 0.1524)
				(type default)
			)
			(layer "F.SilkS")
		)
		(fp_line
			(start 2.25044 -1.5494)
			(end 0.5842 -1.5494)
			(stroke
				(width 0.1524)
				(type default)
			)
			(layer "F.SilkS")
		)
		(fp_poly
			(pts
				(xy -4.36372 -1.344168) (xy -3.81 -1.016) (xy -4.36372 -0.719328)
			)
			(stroke
				(width 0)
				(type default)
			)
			(fill yes)
			(layer "F.SilkS")
		)
		(fp_line
			(start -2.25044 1.5494)
			(end 2.25044 1.5494)
			(stroke
				(width 0.1)
				(type default)
			)
			(layer "F.Fab")
		)
		(fp_line
			(start -2.25044 1.5494)
			(end -2.25044 1.12522)
			(stroke
				(width 0.1)
				(type default)
			)
			(layer "F.Fab")
		)
		(fp_line
			(start 2.25044 1.5494)
			(end 2.25044 1.12522)
			(stroke
				(width 0.1)
				(type default)
			)
			(layer "F.Fab")
		)
		(fp_line
			(start 2.25044 1.5494)
			(end 2.25044 -1.5494)
			(stroke
				(width 0.1)
				(type default)
			)
			(layer "F.Fab")
		)
		(fp_line
			(start 2.25044 1.143)
			(end 2.25044 1.0922)
			(stroke
				(width 0.1)
				(type default)
			)
			(layer "F.Fab")
		)
		(fp_line
			(start -3.302 1.12522)
			(end -3.302 -1.12522)
			(stroke
				(width 0.1)
				(type default)
			)
			(layer "F.Fab")
		)
		(fp_line
			(start -2.25044 1.12522)
			(end -3.302 1.12522)
			(stroke
				(width 0.1)
				(type default)
			)
			(layer "F.Fab")
		)
		(fp_line
			(start 2.25044 1.12522)
			(end 3.302 1.12522)
			(stroke
				(width 0.1)
				(type default)
			)
			(layer "F.Fab")
		)
		(fp_line
			(start 3.302 1.12522)
			(end 3.302 -1.12522)
			(stroke
				(width 0.1)
				(type default)
			)
			(layer "F.Fab")
		)
		(fp_line
			(start -3.302 -1.12522)
			(end -2.25044 -1.12522)
			(stroke
				(width 0.1)
				(type default)
			)
			(layer "F.Fab")
		)
		(fp_line
			(start -2.25044 -1.12522)
			(end -2.25044 -1.5494)
			(stroke
				(width 0.1)
				(type default)
			)
			(layer "F.Fab")
		)
		(fp_line
			(start 2.25044 -1.12522)
			(end 2.25044 -1.4986)
			(stroke
				(width 0.1)
				(type default)
			)
			(layer "F.Fab")
		)
		(fp_line
			(start 3.302 -1.12522)
			(end 2.25044 -1.12522)
			(stroke
				(width 0.1)
				(type default)
			)
			(layer "F.Fab")
		)
		(fp_line
			(start -2.25044 -1.5494)
			(end -2.25044 1.5494)
			(stroke
				(width 0.1)
				(type default)
			)
			(layer "F.Fab")
		)
		(fp_line
			(start 2.25044 -1.5494)
			(end -2.25044 -1.5494)
			(stroke
				(width 0.1)
				(type default)
			)
			(layer "F.Fab")
		)
		(fp_poly
			(pts
				(xy -4.36372 -0.719328) (xy -4.36372 -1.344168) (xy -3.81 -1.016)
			)
			(stroke
				(width 0)
				(type default)
			)
			(fill yes)
			(layer "F.Fab")
		)
		(pad "1" smd rect
			(at -2.921 -0.975106 180)
			(size 0.3556 1.4986)
			(layers "F.Cu" "F.Mask" "F.Paste")
			(net "CLK_50M_RMII_R")
		)
		(pad "2" smd rect
			(at -2.921 -0.32512 180)
			(size 0.3556 1.4986)
			(layers "F.Cu" "F.Mask" "F.Paste")
			(net "CLK_50M_EN")
		)
		(pad "3" smd rect
			(at -2.921 0.32512 180)
			(size 0.3556 1.4986)
			(layers "F.Cu" "F.Mask" "F.Paste")
			(net "CLK_50M_BMC_MAC_R")
		)
		(pad "4" smd rect
			(at -2.921 0.975106 180)
			(size 0.3556 1.4986)
			(layers "F.Cu" "F.Mask" "F.Paste")
			(net "GND")
		)
		(pad "5" smd rect
			(at 2.921 0.975106 180)
			(size 0.3556 1.4986)
			(layers "F.Cu" "F.Mask" "F.Paste")
			(net "CLK_50M_NCSI_OCP_1")
		)
		(pad "6" smd rect
			(at 2.921 0.32512 180)
			(size 0.3556 1.4986)
			(layers "F.Cu" "F.Mask" "F.Paste")
			(net "P3V3_AUX")
		)
		(pad "7" smd rect
			(at 2.921 -0.32512 180)
			(size 0.3556 1.4986)
			(layers "F.Cu" "F.Mask" "F.Paste")
			(net "CLK_50M_NCSI_OCP_2")
		)
		(pad "8" smd rect
			(at 2.921 -0.975106 180)
			(size 0.3556 1.4986)
			(layers "F.Cu" "F.Mask" "F.Paste")
			(net "TP_CLK_50M_PCH_LOM")
		)
	)
	(footprint ""
		(layer "F.Cu")
		(at 154.966416 -31.341568 90)
		(property "Reference" "R4453"
			(at 0 0 90)
			(layer "F.SilkS")
			(hide yes)
			(effects
				(font
					(size 1.27 1.27)
				)
			)
		)
		(property "Value" ""
			(at 0 0 90)
			(layer "F.Fab")
			(effects
				(font
					(size 1.27 1.27)
				)
			)
		)
		(duplicate_pad_numbers_are_jumpers no)
		(fp_line
			(start 0.7874 -0.4064)
			(end 0.7874 0.4064)
			(stroke
				(width 0.1524)
				(type default)
			)
			(layer "F.SilkS")
		)
		(fp_line
			(start -0.7874 -0.4064)
			(end 0.7874 -0.4064)
			(stroke
				(width 0.1524)
				(type default)
			)
			(layer "F.SilkS")
		)
		(fp_line
			(start 0.7874 0.4064)
			(end -0.7874 0.4064)
			(stroke
				(width 0.1524)
				(type default)
			)
			(layer "F.SilkS")
		)
		(fp_line
			(start -0.7874 0.4064)
			(end -0.7874 -0.4064)
			(stroke
				(width 0.1524)
				(type default)
			)
			(layer "F.SilkS")
		)
		(fp_line
			(start -0.12065 -0.305054)
			(end -0.12065 -0.2794)
			(stroke
				(width 0.1)
				(type default)
			)
			(layer "F.Fab")
		)
		(fp_line
			(start -0.67945 -0.305054)
			(end -0.12065 -0.305054)
			(stroke
				(width 0.1)
				(type default)
			)
			(layer "F.Fab")
		)
		(fp_line
			(start 0.67945 -0.3048)
			(end 0.67945 0.3048)
			(stroke
				(width 0.1)
				(type default)
			)
			(layer "F.Fab")
		)
		(fp_line
			(start 0.12065 -0.3048)
			(end 0.67945 -0.3048)
			(stroke
				(width 0.1)
				(type default)
			)
			(layer "F.Fab")
		)
		(fp_line
			(start 0.12065 -0.2794)
			(end 0.12065 -0.3048)
			(stroke
				(width 0.1)
				(type default)
			)
			(layer "F.Fab")
		)
		(fp_line
			(start -0.12065 -0.2794)
			(end 0.12065 -0.2794)
			(stroke
				(width 0.1)
				(type default)
			)
			(layer "F.Fab")
		)
		(fp_line
			(start 0.120396 0.2794)
			(end -0.12065 0.2794)
			(stroke
				(width 0.1)
				(type default)
			)
			(layer "F.Fab")
		)
		(fp_line
			(start -0.12065 0.2794)
			(end -0.12065 0.3048)
			(stroke
				(width 0.1)
				(type default)
			)
			(layer "F.Fab")
		)
		(fp_line
			(start 0.67945 0.3048)
			(end 0.120396 0.3048)
			(stroke
				(width 0.1)
				(type default)
			)
			(layer "F.Fab")
		)
		(fp_line
			(start 0.120396 0.3048)
			(end 0.120396 0.2794)
			(stroke
				(width 0.1)
				(type default)
			)
			(layer "F.Fab")
		)
		(fp_line
			(start -0.12065 0.3048)
			(end -0.67945 0.3048)
			(stroke
				(width 0.1)
				(type default)
			)
			(layer "F.Fab")
		)
		(fp_line
			(start -0.67945 0.3048)
			(end -0.67945 -0.305054)
			(stroke
				(width 0.1)
				(type default)
			)
			(layer "F.Fab")
		)
		(pad "1" smd circle
			(at -0.40005 0 90)
			(size 0 0)
			(layers "F.Cu" "F.Mask" "F.Paste")
			(net "GND")
		)
		(pad "2" smd circle
			(at 0.40005 0 90)
			(size 0 0)
			(layers "F.Cu" "F.Mask" "F.Paste")
			(net "RST_USB_HUB_2_R_N")
		)
	)
	(footprint ""
		(layer "F.Cu")
		(at 364.50143 -241.976656 -90)
		(property "Reference" "C1025"
			(at 0 0 270)
			(layer "F.SilkS")
			(hide yes)
			(effects
				(font
					(size 1.27 1.27)
				)
			)
		)
		(property "Value" ""
			(at 0 0 270)
			(layer "F.Fab")
			(effects
				(font
					(size 1.27 1.27)
				)
			)
		)
		(duplicate_pad_numbers_are_jumpers no)
		(fp_line
			(start -0.7874 0.4064)
			(end -0.7874 -0.4064)
			(stroke
				(width 0.1524)
				(type default)
			)
			(layer "F.SilkS")
		)
		(fp_line
			(start 0.7874 0.4064)
			(end -0.7874 0.4064)
			(stroke
				(width 0.1524)
				(type default)
			)
			(layer "F.SilkS")
		)
		(fp_line
			(start -0.7874 -0.4064)
			(end 0.7874 -0.4064)
			(stroke
				(width 0.1524)
				(type default)
			)
			(layer "F.SilkS")
		)
		(fp_line
			(start 0.7874 -0.4064)
			(end 0.7874 0.4064)
			(stroke
				(width 0.1524)
				(type default)
			)
			(layer "F.SilkS")
		)
		(fp_line
			(start -0.67945 0.3048)
			(end -0.67945 -0.305054)
			(stroke
				(width 0.1)
				(type default)
			)
			(layer "F.Fab")
		)
		(fp_line
			(start -0.12065 0.3048)
			(end -0.67945 0.3048)
			(stroke
				(width 0.1)
				(type default)
			)
			(layer "F.Fab")
		)
		(fp_line
			(start 0.120396 0.3048)
			(end 0.120396 0.2794)
			(stroke
				(width 0.1)
				(type default)
			)
			(layer "F.Fab")
		)
		(fp_line
			(start 0.67945 0.3048)
			(end 0.120396 0.3048)
			(stroke
				(width 0.1)
				(type default)
			)
			(layer "F.Fab")
		)
		(fp_line
			(start -0.12065 0.2794)
			(end -0.12065 0.3048)
			(stroke
				(width 0.1)
				(type default)
			)
			(layer "F.Fab")
		)
		(fp_line
			(start 0.120396 0.2794)
			(end -0.12065 0.2794)
			(stroke
				(width 0.1)
				(type default)
			)
			(layer "F.Fab")
		)
		(fp_line
			(start -0.12065 -0.2794)
			(end 0.12065 -0.2794)
			(stroke
				(width 0.1)
				(type default)
			)
			(layer "F.Fab")
		)
		(fp_line
			(start 0.12065 -0.2794)
			(end 0.12065 -0.3048)
			(stroke
				(width 0.1)
				(type default)
			)
			(layer "F.Fab")
		)
		(fp_line
			(start 0.12065 -0.3048)
			(end 0.67945 -0.3048)
			(stroke
				(width 0.1)
				(type default)
			)
			(layer "F.Fab")
		)
		(fp_line
			(start 0.67945 -0.3048)
			(end 0.67945 0.3048)
			(stroke
				(width 0.1)
				(type default)
			)
			(layer "F.Fab")
		)
		(fp_line
			(start -0.67945 -0.305054)
			(end -0.12065 -0.305054)
			(stroke
				(width 0.1)
				(type default)
			)
			(layer "F.Fab")
		)
		(fp_line
			(start -0.12065 -0.305054)
			(end -0.12065 -0.2794)
			(stroke
				(width 0.1)
				(type default)
			)
			(layer "F.Fab")
		)
		(pad "1" smd circle
			(at -0.40005 0 270)
			(size 0 0)
			(layers "F.Cu" "F.Mask" "F.Paste")
			(net "PVCCIN_CPU0")
		)
		(pad "2" smd circle
			(at 0.40005 0 270)
			(size 0 0)
			(layers "F.Cu" "F.Mask" "F.Paste")
			(net "GND")
		)
	)
	(footprint ""
		(layer "F.Cu")
		(at 27.628596 -387.246876)
		(property "Reference" "R3265"
			(at 0 0 0)
			(layer "F.SilkS")
			(hide yes)
			(effects
				(font
					(size 1.27 1.27)
				)
			)
		)
		(property "Value" ""
			(at 0 0 0)
			(layer "F.Fab")
			(effects
				(font
					(size 1.27 1.27)
				)
			)
		)
		(duplicate_pad_numbers_are_jumpers no)
		(fp_line
			(start -0.7874 -0.4064)
			(end 0.7874 -0.4064)
			(stroke
				(width 0.1524)
				(type default)
			)
			(layer "F.SilkS")
		)
		(fp_line
			(start -0.7874 0.4064)
			(end -0.7874 -0.4064)
			(stroke
				(width 0.1524)
				(type default)
			)
			(layer "F.SilkS")
		)
		(fp_line
			(start 0.7874 -0.4064)
			(end 0.7874 0.4064)
			(stroke
				(width 0.1524)
				(type default)
			)
			(layer "F.SilkS")
		)
		(fp_line
			(start 0.7874 0.4064)
			(end -0.7874 0.4064)
			(stroke
				(width 0.1524)
				(type default)
			)
			(layer "F.SilkS")
		)
		(fp_line
			(start -0.67945 -0.305054)
			(end -0.12065 -0.305054)
			(stroke
				(width 0.1)
				(type default)
			)
			(layer "F.Fab")
		)
		(fp_line
			(start -0.67945 0.3048)
			(end -0.67945 -0.305054)
			(stroke
				(width 0.1)
				(type default)
			)
			(layer "F.Fab")
		)
		(fp_line
			(start -0.12065 -0.305054)
			(end -0.12065 -0.2794)
			(stroke
				(width 0.1)
				(type default)
			)
			(layer "F.Fab")
		)
		(fp_line
			(start -0.12065 -0.2794)
			(end 0.12065 -0.2794)
			(stroke
				(width 0.1)
				(type default)
			)
			(layer "F.Fab")
		)
		(fp_line
			(start -0.12065 0.2794)
			(end -0.12065 0.3048)
			(stroke
				(width 0.1)
				(type default)
			)
			(layer "F.Fab")
		)
		(fp_line
			(start -0.12065 0.3048)
			(end -0.67945 0.3048)
			(stroke
				(width 0.1)
				(type default)
			)
			(layer "F.Fab")
		)
		(fp_line
			(start 0.120396 0.2794)
			(end -0.12065 0.2794)
			(stroke
				(width 0.1)
				(type default)
			)
			(layer "F.Fab")
		)
		(fp_line
			(start 0.120396 0.3048)
			(end 0.120396 0.2794)
			(stroke
				(width 0.1)
				(type default)
			)
			(layer "F.Fab")
		)
		(fp_line
			(start 0.12065 -0.3048)
			(end 0.67945 -0.3048)
			(stroke
				(width 0.1)
				(type default)
			)
			(layer "F.Fab")
		)
		(fp_line
			(start 0.12065 -0.2794)
			(end 0.12065 -0.3048)
			(stroke
				(width 0.1)
				(type default)
			)
			(layer "F.Fab")
		)
		(fp_line
			(start 0.67945 -0.3048)
			(end 0.67945 0.3048)
			(stroke
				(width 0.1)
				(type default)
			)
			(layer "F.Fab")
		)
		(fp_line
			(start 0.67945 0.3048)
			(end 0.120396 0.3048)
			(stroke
				(width 0.1)
				(type default)
			)
			(layer "F.Fab")
		)
		(pad "1" smd circle
			(at -0.40005 0)
			(size 0 0)
			(layers "F.Cu" "F.Mask" "F.Paste")
			(net "CLK_GEN2_GPU_FPGA_OE_OR_N")
		)
		(pad "2" smd circle
			(at 0.40005 0)
			(size 0 0)
			(layers "F.Cu" "F.Mask" "F.Paste")
			(net "GND")
		)
	)
	(footprint ""
		(layer "F.Cu")
		(at 252.735842 -92.24137)
		(property "Reference" "R1390"
			(at 0 0 0)
			(layer "F.SilkS")
			(hide yes)
			(effects
				(font
					(size 1.27 1.27)
				)
			)
		)
		(property "Value" ""
			(at 0 0 0)
			(layer "F.Fab")
			(effects
				(font
					(size 1.27 1.27)
				)
			)
		)
		(duplicate_pad_numbers_are_jumpers no)
		(fp_line
			(start -0.7874 -0.4064)
			(end 0.7874 -0.4064)
			(stroke
				(width 0.1524)
				(type default)
			)
			(layer "F.SilkS")
		)
		(fp_line
			(start -0.7874 0.4064)
			(end -0.7874 -0.4064)
			(stroke
				(width 0.1524)
				(type default)
			)
			(layer "F.SilkS")
		)
		(fp_line
			(start 0.7874 -0.4064)
			(end 0.7874 0.4064)
			(stroke
				(width 0.1524)
				(type default)
			)
			(layer "F.SilkS")
		)
		(fp_line
			(start 0.7874 0.4064)
			(end -0.7874 0.4064)
			(stroke
				(width 0.1524)
				(type default)
			)
			(layer "F.SilkS")
		)
		(fp_line
			(start -0.67945 -0.305054)
			(end -0.12065 -0.305054)
			(stroke
				(width 0.1)
				(type default)
			)
			(layer "F.Fab")
		)
		(fp_line
			(start -0.67945 0.3048)
			(end -0.67945 -0.305054)
			(stroke
				(width 0.1)
				(type default)
			)
			(layer "F.Fab")
		)
		(fp_line
			(start -0.12065 -0.305054)
			(end -0.12065 -0.2794)
			(stroke
				(width 0.1)
				(type default)
			)
			(layer "F.Fab")
		)
		(fp_line
			(start -0.12065 -0.2794)
			(end 0.12065 -0.2794)
			(stroke
				(width 0.1)
				(type default)
			)
			(layer "F.Fab")
		)
		(fp_line
			(start -0.12065 0.2794)
			(end -0.12065 0.3048)
			(stroke
				(width 0.1)
				(type default)
			)
			(layer "F.Fab")
		)
		(fp_line
			(start -0.12065 0.3048)
			(end -0.67945 0.3048)
			(stroke
				(width 0.1)
				(type default)
			)
			(layer "F.Fab")
		)
		(fp_line
			(start 0.120396 0.2794)
			(end -0.12065 0.2794)
			(stroke
				(width 0.1)
				(type default)
			)
			(layer "F.Fab")
		)
		(fp_line
			(start 0.120396 0.3048)
			(end 0.120396 0.2794)
			(stroke
				(width 0.1)
				(type default)
			)
			(layer "F.Fab")
		)
		(fp_line
			(start 0.12065 -0.3048)
			(end 0.67945 -0.3048)
			(stroke
				(width 0.1)
				(type default)
			)
			(layer "F.Fab")
		)
		(fp_line
			(start 0.12065 -0.2794)
			(end 0.12065 -0.3048)
			(stroke
				(width 0.1)
				(type default)
			)
			(layer "F.Fab")
		)
		(fp_line
			(start 0.67945 -0.3048)
			(end 0.67945 0.3048)
			(stroke
				(width 0.1)
				(type default)
			)
			(layer "F.Fab")
		)
		(fp_line
			(start 0.67945 0.3048)
			(end 0.120396 0.3048)
			(stroke
				(width 0.1)
				(type default)
			)
			(layer "F.Fab")
		)
		(pad "1" smd circle
			(at -0.40005 0)
			(size 0 0)
			(layers "F.Cu" "F.Mask" "F.Paste")
			(net "FM_PLD_CLKS_DEV_EN")
		)
		(pad "2" smd circle
			(at 0.40005 0)
			(size 0 0)
			(layers "F.Cu" "F.Mask" "F.Paste")
			(net "GND")
		)
	)
	(footprint ""
		(layer "F.Cu")
		(at 163.50488 -437.479948)
		(property "Reference" "R3448"
			(at 0 0 0)
			(layer "F.SilkS")
			(hide yes)
			(effects
				(font
					(size 1.27 1.27)
				)
			)
		)
		(property "Value" ""
			(at 0 0 0)
			(layer "F.Fab")
			(effects
				(font
					(size 1.27 1.27)
				)
			)
		)
		(duplicate_pad_numbers_are_jumpers no)
		(fp_line
			(start -0.7874 -0.4064)
			(end 0.7874 -0.4064)
			(stroke
				(width 0.1524)
				(type default)
			)
			(layer "F.SilkS")
		)
		(fp_line
			(start -0.7874 0.4064)
			(end -0.7874 -0.4064)
			(stroke
				(width 0.1524)
				(type default)
			)
			(layer "F.SilkS")
		)
		(fp_line
			(start 0.7874 -0.4064)
			(end 0.7874 0.4064)
			(stroke
				(width 0.1524)
				(type default)
			)
			(layer "F.SilkS")
		)
		(fp_line
			(start 0.7874 0.4064)
			(end -0.7874 0.4064)
			(stroke
				(width 0.1524)
				(type default)
			)
			(layer "F.SilkS")
		)
		(fp_line
			(start -0.67945 -0.305054)
			(end -0.12065 -0.305054)
			(stroke
				(width 0.1)
				(type default)
			)
			(layer "F.Fab")
		)
		(fp_line
			(start -0.67945 0.3048)
			(end -0.67945 -0.305054)
			(stroke
				(width 0.1)
				(type default)
			)
			(layer "F.Fab")
		)
		(fp_line
			(start -0.12065 -0.305054)
			(end -0.12065 -0.2794)
			(stroke
				(width 0.1)
				(type default)
			)
			(layer "F.Fab")
		)
		(fp_line
			(start -0.12065 -0.2794)
			(end 0.12065 -0.2794)
			(stroke
				(width 0.1)
				(type default)
			)
			(layer "F.Fab")
		)
		(fp_line
			(start -0.12065 0.2794)
			(end -0.12065 0.3048)
			(stroke
				(width 0.1)
				(type default)
			)
			(layer "F.Fab")
		)
		(fp_line
			(start -0.12065 0.3048)
			(end -0.67945 0.3048)
			(stroke
				(width 0.1)
				(type default)
			)
			(layer "F.Fab")
		)
		(fp_line
			(start 0.120396 0.2794)
			(end -0.12065 0.2794)
			(stroke
				(width 0.1)
				(type default)
			)
			(layer "F.Fab")
		)
		(fp_line
			(start 0.120396 0.3048)
			(end 0.120396 0.2794)
			(stroke
				(width 0.1)
				(type default)
			)
			(layer "F.Fab")
		)
		(fp_line
			(start 0.12065 -0.3048)
			(end 0.67945 -0.3048)
			(stroke
				(width 0.1)
				(type default)
			)
			(layer "F.Fab")
		)
		(fp_line
			(start 0.12065 -0.2794)
			(end 0.12065 -0.3048)
			(stroke
				(width 0.1)
				(type default)
			)
			(layer "F.Fab")
		)
		(fp_line
			(start 0.67945 -0.3048)
			(end 0.67945 0.3048)
			(stroke
				(width 0.1)
				(type default)
			)
			(layer "F.Fab")
		)
		(fp_line
			(start 0.67945 0.3048)
			(end 0.120396 0.3048)
			(stroke
				(width 0.1)
				(type default)
			)
			(layer "F.Fab")
		)
		(pad "1" smd circle
			(at -0.40005 0)
			(size 0 0)
			(layers "F.Cu" "F.Mask" "F.Paste")
			(net "P3V3_AUX")
		)
		(pad "2" smd circle
			(at 0.40005 0)
			(size 0 0)
			(layers "F.Cu" "F.Mask" "F.Paste")
			(net "GPU_FPGA_BOOT_EN")
		)
	)
	(footprint ""
		(layer "F.Cu")
		(at 98.33864 -33.736788 180)
		(property "Reference" "R3264"
			(at 0 0 180)
			(layer "F.SilkS")
			(hide yes)
			(effects
				(font
					(size 1.27 1.27)
				)
			)
		)
		(property "Value" ""
			(at 0 0 180)
			(layer "F.Fab")
			(effects
				(font
					(size 1.27 1.27)
				)
			)
		)
		(duplicate_pad_numbers_are_jumpers no)
		(fp_line
			(start 0.7874 0.4064)
			(end -0.7874 0.4064)
			(stroke
				(width 0.1524)
				(type default)
			)
			(layer "F.SilkS")
		)
		(fp_line
			(start 0.7874 -0.4064)
			(end 0.7874 0.4064)
			(stroke
				(width 0.1524)
				(type default)
			)
			(layer "F.SilkS")
		)
		(fp_line
			(start -0.7874 0.4064)
			(end -0.7874 -0.4064)
			(stroke
				(width 0.1524)
				(type default)
			)
			(layer "F.SilkS")
		)
		(fp_line
			(start -0.7874 -0.4064)
			(end 0.7874 -0.4064)
			(stroke
				(width 0.1524)
				(type default)
			)
			(layer "F.SilkS")
		)
		(fp_line
			(start 0.67945 0.3048)
			(end 0.120396 0.3048)
			(stroke
				(width 0.1)
				(type default)
			)
			(layer "F.Fab")
		)
		(fp_line
			(start 0.67945 -0.3048)
			(end 0.67945 0.3048)
			(stroke
				(width 0.1)
				(type default)
			)
			(layer "F.Fab")
		)
		(fp_line
			(start 0.12065 -0.2794)
			(end 0.12065 -0.3048)
			(stroke
				(width 0.1)
				(type default)
			)
			(layer "F.Fab")
		)
		(fp_line
			(start 0.12065 -0.3048)
			(end 0.67945 -0.3048)
			(stroke
				(width 0.1)
				(type default)
			)
			(layer "F.Fab")
		)
		(fp_line
			(start 0.120396 0.3048)
			(end 0.120396 0.2794)
			(stroke
				(width 0.1)
				(type default)
			)
			(layer "F.Fab")
		)
		(fp_line
			(start 0.120396 0.2794)
			(end -0.12065 0.2794)
			(stroke
				(width 0.1)
				(type default)
			)
			(layer "F.Fab")
		)
		(fp_line
			(start -0.12065 0.3048)
			(end -0.67945 0.3048)
			(stroke
				(width 0.1)
				(type default)
			)
			(layer "F.Fab")
		)
		(fp_line
			(start -0.12065 0.2794)
			(end -0.12065 0.3048)
			(stroke
				(width 0.1)
				(type default)
			)
			(layer "F.Fab")
		)
		(fp_line
			(start -0.12065 -0.2794)
			(end 0.12065 -0.2794)
			(stroke
				(width 0.1)
				(type default)
			)
			(layer "F.Fab")
		)
		(fp_line
			(start -0.12065 -0.305054)
			(end -0.12065 -0.2794)
			(stroke
				(width 0.1)
				(type default)
			)
			(layer "F.Fab")
		)
		(fp_line
			(start -0.67945 0.3048)
			(end -0.67945 -0.305054)
			(stroke
				(width 0.1)
				(type default)
			)
			(layer "F.Fab")
		)
		(fp_line
			(start -0.67945 -0.305054)
			(end -0.12065 -0.305054)
			(stroke
				(width 0.1)
				(type default)
			)
			(layer "F.Fab")
		)
		(pad "1" smd circle
			(at -0.40005 0 180)
			(size 0 0)
			(layers "F.Cu" "F.Mask" "F.Paste")
			(net "HP_LVC3_OCP_V3_2_R_EN")
		)
		(pad "2" smd circle
			(at 0.40005 0 180)
			(size 0 0)
			(layers "F.Cu" "F.Mask" "F.Paste")
			(net "HP_LVC3_OCP_V3_2_EN")
		)
	)
	(footprint ""
		(layer "F.Cu")
		(at 427.097952 -124.91466 180)
		(property "Reference" "PR634"
			(at 0 0 180)
			(layer "F.SilkS")
			(hide yes)
			(effects
				(font
					(size 1.27 1.27)
				)
			)
		)
		(property "Value" ""
			(at 0 0 180)
			(layer "F.Fab")
			(effects
				(font
					(size 1.27 1.27)
				)
			)
		)
		(duplicate_pad_numbers_are_jumpers no)
		(fp_line
			(start 0.7874 0.4064)
			(end -0.7874 0.4064)
			(stroke
				(width 0.1524)
				(type default)
			)
			(layer "F.SilkS")
		)
		(fp_line
			(start 0.7874 -0.4064)
			(end 0.7874 0.4064)
			(stroke
				(width 0.1524)
				(type default)
			)
			(layer "F.SilkS")
		)
		(fp_line
			(start -0.7874 0.4064)
			(end -0.7874 -0.4064)
			(stroke
				(width 0.1524)
				(type default)
			)
			(layer "F.SilkS")
		)
		(fp_line
			(start -0.7874 -0.4064)
			(end 0.7874 -0.4064)
			(stroke
				(width 0.1524)
				(type default)
			)
			(layer "F.SilkS")
		)
		(fp_line
			(start 0.67945 0.3048)
			(end 0.120396 0.3048)
			(stroke
				(width 0.1)
				(type default)
			)
			(layer "F.Fab")
		)
		(fp_line
			(start 0.67945 -0.3048)
			(end 0.67945 0.3048)
			(stroke
				(width 0.1)
				(type default)
			)
			(layer "F.Fab")
		)
		(fp_line
			(start 0.12065 -0.2794)
			(end 0.12065 -0.3048)
			(stroke
				(width 0.1)
				(type default)
			)
			(layer "F.Fab")
		)
		(fp_line
			(start 0.12065 -0.3048)
			(end 0.67945 -0.3048)
			(stroke
				(width 0.1)
				(type default)
			)
			(layer "F.Fab")
		)
		(fp_line
			(start 0.120396 0.3048)
			(end 0.120396 0.2794)
			(stroke
				(width 0.1)
				(type default)
			)
			(layer "F.Fab")
		)
		(fp_line
			(start 0.120396 0.2794)
			(end -0.12065 0.2794)
			(stroke
				(width 0.1)
				(type default)
			)
			(layer "F.Fab")
		)
		(fp_line
			(start -0.12065 0.3048)
			(end -0.67945 0.3048)
			(stroke
				(width 0.1)
				(type default)
			)
			(layer "F.Fab")
		)
		(fp_line
			(start -0.12065 0.2794)
			(end -0.12065 0.3048)
			(stroke
				(width 0.1)
				(type default)
			)
			(layer "F.Fab")
		)
		(fp_line
			(start -0.12065 -0.2794)
			(end 0.12065 -0.2794)
			(stroke
				(width 0.1)
				(type default)
			)
			(layer "F.Fab")
		)
		(fp_line
			(start -0.12065 -0.305054)
			(end -0.12065 -0.2794)
			(stroke
				(width 0.1)
				(type default)
			)
			(layer "F.Fab")
		)
		(fp_line
			(start -0.67945 0.3048)
			(end -0.67945 -0.305054)
			(stroke
				(width 0.1)
				(type default)
			)
			(layer "F.Fab")
		)
		(fp_line
			(start -0.67945 -0.305054)
			(end -0.12065 -0.305054)
			(stroke
				(width 0.1)
				(type default)
			)
			(layer "F.Fab")
		)
		(pad "1" smd circle
			(at -0.40005 0 180)
			(size 0 0)
			(layers "F.Cu" "F.Mask" "F.Paste")
			(net "PVCCD_HV_CPU0_ATSEN")
		)
		(pad "2" smd circle
			(at 0.40005 0 180)
			(size 0 0)
			(layers "F.Cu" "F.Mask" "F.Paste")
			(net "GND")
		)
	)
	(footprint ""
		(layer "F.Cu")
		(at 366.95888 -357.114348 90)
		(property "Reference" "PR2336"
			(at 0 0 90)
			(layer "F.SilkS")
			(hide yes)
			(effects
				(font
					(size 1.27 1.27)
				)
			)
		)
		(property "Value" ""
			(at 0 0 90)
			(layer "F.Fab")
			(effects
				(font
					(size 1.27 1.27)
				)
			)
		)
		(duplicate_pad_numbers_are_jumpers no)
		(fp_line
			(start 0.7874 -0.4064)
			(end 0.7874 0.4064)
			(stroke
				(width 0.1524)
				(type default)
			)
			(layer "F.SilkS")
		)
		(fp_line
			(start -0.7874 -0.4064)
			(end 0.7874 -0.4064)
			(stroke
				(width 0.1524)
				(type default)
			)
			(layer "F.SilkS")
		)
		(fp_line
			(start 0.7874 0.4064)
			(end -0.7874 0.4064)
			(stroke
				(width 0.1524)
				(type default)
			)
			(layer "F.SilkS")
		)
		(fp_line
			(start -0.7874 0.4064)
			(end -0.7874 -0.4064)
			(stroke
				(width 0.1524)
				(type default)
			)
			(layer "F.SilkS")
		)
		(fp_line
			(start -0.12065 -0.305054)
			(end -0.12065 -0.2794)
			(stroke
				(width 0.1)
				(type default)
			)
			(layer "F.Fab")
		)
		(fp_line
			(start -0.67945 -0.305054)
			(end -0.12065 -0.305054)
			(stroke
				(width 0.1)
				(type default)
			)
			(layer "F.Fab")
		)
		(fp_line
			(start 0.67945 -0.3048)
			(end 0.67945 0.3048)
			(stroke
				(width 0.1)
				(type default)
			)
			(layer "F.Fab")
		)
		(fp_line
			(start 0.12065 -0.3048)
			(end 0.67945 -0.3048)
			(stroke
				(width 0.1)
				(type default)
			)
			(layer "F.Fab")
		)
		(fp_line
			(start 0.12065 -0.2794)
			(end 0.12065 -0.3048)
			(stroke
				(width 0.1)
				(type default)
			)
			(layer "F.Fab")
		)
		(fp_line
			(start -0.12065 -0.2794)
			(end 0.12065 -0.2794)
			(stroke
				(width 0.1)
				(type default)
			)
			(layer "F.Fab")
		)
		(fp_line
			(start 0.120396 0.2794)
			(end -0.12065 0.2794)
			(stroke
				(width 0.1)
				(type default)
			)
			(layer "F.Fab")
		)
		(fp_line
			(start -0.12065 0.2794)
			(end -0.12065 0.3048)
			(stroke
				(width 0.1)
				(type default)
			)
			(layer "F.Fab")
		)
		(fp_line
			(start 0.67945 0.3048)
			(end 0.120396 0.3048)
			(stroke
				(width 0.1)
				(type default)
			)
			(layer "F.Fab")
		)
		(fp_line
			(start 0.120396 0.3048)
			(end 0.120396 0.2794)
			(stroke
				(width 0.1)
				(type default)
			)
			(layer "F.Fab")
		)
		(fp_line
			(start -0.12065 0.3048)
			(end -0.67945 0.3048)
			(stroke
				(width 0.1)
				(type default)
			)
			(layer "F.Fab")
		)
		(fp_line
			(start -0.67945 0.3048)
			(end -0.67945 -0.305054)
			(stroke
				(width 0.1)
				(type default)
			)
			(layer "F.Fab")
		)
		(pad "1" smd circle
			(at -0.40005 0 90)
			(size 0 0)
			(layers "F.Cu" "F.Mask" "F.Paste")
			(net "PVPP_HBM_CPU0_FB")
		)
		(pad "2" smd circle
			(at 0.40005 0 90)
			(size 0 0)
			(layers "F.Cu" "F.Mask" "F.Paste")
			(net "FM_HBM_VPP_SEL_CPU0_D")
		)
	)
	(footprint ""
		(layer "F.Cu")
		(at 298.342304 -426.478446 -90)
		(property "Reference" "R4138"
			(at 0 0 270)
			(layer "F.SilkS")
			(hide yes)
			(effects
				(font
					(size 1.27 1.27)
				)
			)
		)
		(property "Value" ""
			(at 0 0 270)
			(layer "F.Fab")
			(effects
				(font
					(size 1.27 1.27)
				)
			)
		)
		(duplicate_pad_numbers_are_jumpers no)
		(fp_line
			(start -0.7874 0.4064)
			(end -0.7874 -0.4064)
			(stroke
				(width 0.1524)
				(type default)
			)
			(layer "F.SilkS")
		)
		(fp_line
			(start 0.7874 0.4064)
			(end -0.7874 0.4064)
			(stroke
				(width 0.1524)
				(type default)
			)
			(layer "F.SilkS")
		)
		(fp_line
			(start -0.7874 -0.4064)
			(end 0.7874 -0.4064)
			(stroke
				(width 0.1524)
				(type default)
			)
			(layer "F.SilkS")
		)
		(fp_line
			(start 0.7874 -0.4064)
			(end 0.7874 0.4064)
			(stroke
				(width 0.1524)
				(type default)
			)
			(layer "F.SilkS")
		)
		(fp_line
			(start -0.67945 0.3048)
			(end -0.67945 -0.305054)
			(stroke
				(width 0.1)
				(type default)
			)
			(layer "F.Fab")
		)
		(fp_line
			(start -0.12065 0.3048)
			(end -0.67945 0.3048)
			(stroke
				(width 0.1)
				(type default)
			)
			(layer "F.Fab")
		)
		(fp_line
			(start 0.120396 0.3048)
			(end 0.120396 0.2794)
			(stroke
				(width 0.1)
				(type default)
			)
			(layer "F.Fab")
		)
		(fp_line
			(start 0.67945 0.3048)
			(end 0.120396 0.3048)
			(stroke
				(width 0.1)
				(type default)
			)
			(layer "F.Fab")
		)
		(fp_line
			(start -0.12065 0.2794)
			(end -0.12065 0.3048)
			(stroke
				(width 0.1)
				(type default)
			)
			(layer "F.Fab")
		)
		(fp_line
			(start 0.120396 0.2794)
			(end -0.12065 0.2794)
			(stroke
				(width 0.1)
				(type default)
			)
			(layer "F.Fab")
		)
		(fp_line
			(start -0.12065 -0.2794)
			(end 0.12065 -0.2794)
			(stroke
				(width 0.1)
				(type default)
			)
			(layer "F.Fab")
		)
		(fp_line
			(start 0.12065 -0.2794)
			(end 0.12065 -0.3048)
			(stroke
				(width 0.1)
				(type default)
			)
			(layer "F.Fab")
		)
		(fp_line
			(start 0.12065 -0.3048)
			(end 0.67945 -0.3048)
			(stroke
				(width 0.1)
				(type default)
			)
			(layer "F.Fab")
		)
		(fp_line
			(start 0.67945 -0.3048)
			(end 0.67945 0.3048)
			(stroke
				(width 0.1)
				(type default)
			)
			(layer "F.Fab")
		)
		(fp_line
			(start -0.67945 -0.305054)
			(end -0.12065 -0.305054)
			(stroke
				(width 0.1)
				(type default)
			)
			(layer "F.Fab")
		)
		(fp_line
			(start -0.12065 -0.305054)
			(end -0.12065 -0.2794)
			(stroke
				(width 0.1)
				(type default)
			)
			(layer "F.Fab")
		)
		(pad "1" smd circle
			(at -0.40005 0 270)
			(size 0 0)
			(layers "F.Cu" "F.Mask" "F.Paste")
			(net "P3V3_AUX")
		)
		(pad "2" smd circle
			(at 0.40005 0 270)
			(size 0 0)
			(layers "F.Cu" "F.Mask" "F.Paste")
			(net "GPU_3V3IO_RSVD5_FFU_N")
		)
	)
	(footprint ""
		(layer "F.Cu")
		(at 300.84395 -417.2204)
		(property "Reference" "R4573"
			(at 0 0 0)
			(layer "F.SilkS")
			(hide yes)
			(effects
				(font
					(size 1.27 1.27)
				)
			)
		)
		(property "Value" ""
			(at 0 0 0)
			(layer "F.Fab")
			(effects
				(font
					(size 1.27 1.27)
				)
			)
		)
		(duplicate_pad_numbers_are_jumpers no)
		(fp_line
			(start -0.7874 -0.4064)
			(end 0.7874 -0.4064)
			(stroke
				(width 0.1524)
				(type default)
			)
			(layer "F.SilkS")
		)
		(fp_line
			(start -0.7874 0.4064)
			(end -0.7874 -0.4064)
			(stroke
				(width 0.1524)
				(type default)
			)
			(layer "F.SilkS")
		)
		(fp_line
			(start 0.7874 -0.4064)
			(end 0.7874 0.4064)
			(stroke
				(width 0.1524)
				(type default)
			)
			(layer "F.SilkS")
		)
		(fp_line
			(start 0.7874 0.4064)
			(end -0.7874 0.4064)
			(stroke
				(width 0.1524)
				(type default)
			)
			(layer "F.SilkS")
		)
		(fp_line
			(start -0.67945 -0.305054)
			(end -0.12065 -0.305054)
			(stroke
				(width 0.1)
				(type default)
			)
			(layer "F.Fab")
		)
		(fp_line
			(start -0.67945 0.3048)
			(end -0.67945 -0.305054)
			(stroke
				(width 0.1)
				(type default)
			)
			(layer "F.Fab")
		)
		(fp_line
			(start -0.12065 -0.305054)
			(end -0.12065 -0.2794)
			(stroke
				(width 0.1)
				(type default)
			)
			(layer "F.Fab")
		)
		(fp_line
			(start -0.12065 -0.2794)
			(end 0.12065 -0.2794)
			(stroke
				(width 0.1)
				(type default)
			)
			(layer "F.Fab")
		)
		(fp_line
			(start -0.12065 0.2794)
			(end -0.12065 0.3048)
			(stroke
				(width 0.1)
				(type default)
			)
			(layer "F.Fab")
		)
		(fp_line
			(start -0.12065 0.3048)
			(end -0.67945 0.3048)
			(stroke
				(width 0.1)
				(type default)
			)
			(layer "F.Fab")
		)
		(fp_line
			(start 0.120396 0.2794)
			(end -0.12065 0.2794)
			(stroke
				(width 0.1)
				(type default)
			)
			(layer "F.Fab")
		)
		(fp_line
			(start 0.120396 0.3048)
			(end 0.120396 0.2794)
			(stroke
				(width 0.1)
				(type default)
			)
			(layer "F.Fab")
		)
		(fp_line
			(start 0.12065 -0.3048)
			(end 0.67945 -0.3048)
			(stroke
				(width 0.1)
				(type default)
			)
			(layer "F.Fab")
		)
		(fp_line
			(start 0.12065 -0.2794)
			(end 0.12065 -0.3048)
			(stroke
				(width 0.1)
				(type default)
			)
			(layer "F.Fab")
		)
		(fp_line
			(start 0.67945 -0.3048)
			(end 0.67945 0.3048)
			(stroke
				(width 0.1)
				(type default)
			)
			(layer "F.Fab")
		)
		(fp_line
			(start 0.67945 0.3048)
			(end 0.120396 0.3048)
			(stroke
				(width 0.1)
				(type default)
			)
			(layer "F.Fab")
		)
		(pad "1" smd circle
			(at -0.40005 0)
			(size 0 0)
			(layers "F.Cu" "F.Mask" "F.Paste")
			(net "PRSNT_CABLE_GPU_B3_N")
		)
		(pad "2" smd circle
			(at 0.40005 0)
			(size 0 0)
			(layers "F.Cu" "F.Mask" "F.Paste")
			(net "PRSNT_CABLE_GPU_B3_ISO_N")
		)
	)
	(footprint ""
		(layer "F.Cu")
		(at 131.425696 -341.729822 -90)
		(property "Reference" "PC510"
			(at 0 0 270)
			(layer "F.SilkS")
			(hide yes)
			(effects
				(font
					(size 1.27 1.27)
				)
			)
		)
		(property "Value" ""
			(at 0 0 270)
			(layer "F.Fab")
			(effects
				(font
					(size 1.27 1.27)
				)
			)
		)
		(duplicate_pad_numbers_are_jumpers no)
		(fp_line
			(start -0.7874 0.4064)
			(end -0.7874 -0.4064)
			(stroke
				(width 0.1524)
				(type default)
			)
			(layer "F.SilkS")
		)
		(fp_line
			(start 0.7874 0.4064)
			(end -0.7874 0.4064)
			(stroke
				(width 0.1524)
				(type default)
			)
			(layer "F.SilkS")
		)
		(fp_line
			(start -0.7874 -0.4064)
			(end 0.7874 -0.4064)
			(stroke
				(width 0.1524)
				(type default)
			)
			(layer "F.SilkS")
		)
		(fp_line
			(start 0.7874 -0.4064)
			(end 0.7874 0.4064)
			(stroke
				(width 0.1524)
				(type default)
			)
			(layer "F.SilkS")
		)
		(fp_line
			(start -0.67945 0.3048)
			(end -0.67945 -0.305054)
			(stroke
				(width 0.1)
				(type default)
			)
			(layer "F.Fab")
		)
		(fp_line
			(start -0.12065 0.3048)
			(end -0.67945 0.3048)
			(stroke
				(width 0.1)
				(type default)
			)
			(layer "F.Fab")
		)
		(fp_line
			(start 0.120396 0.3048)
			(end 0.120396 0.2794)
			(stroke
				(width 0.1)
				(type default)
			)
			(layer "F.Fab")
		)
		(fp_line
			(start 0.67945 0.3048)
			(end 0.120396 0.3048)
			(stroke
				(width 0.1)
				(type default)
			)
			(layer "F.Fab")
		)
		(fp_line
			(start -0.12065 0.2794)
			(end -0.12065 0.3048)
			(stroke
				(width 0.1)
				(type default)
			)
			(layer "F.Fab")
		)
		(fp_line
			(start 0.120396 0.2794)
			(end -0.12065 0.2794)
			(stroke
				(width 0.1)
				(type default)
			)
			(layer "F.Fab")
		)
		(fp_line
			(start -0.12065 -0.2794)
			(end 0.12065 -0.2794)
			(stroke
				(width 0.1)
				(type default)
			)
			(layer "F.Fab")
		)
		(fp_line
			(start 0.12065 -0.2794)
			(end 0.12065 -0.3048)
			(stroke
				(width 0.1)
				(type default)
			)
			(layer "F.Fab")
		)
		(fp_line
			(start 0.12065 -0.3048)
			(end 0.67945 -0.3048)
			(stroke
				(width 0.1)
				(type default)
			)
			(layer "F.Fab")
		)
		(fp_line
			(start 0.67945 -0.3048)
			(end 0.67945 0.3048)
			(stroke
				(width 0.1)
				(type default)
			)
			(layer "F.Fab")
		)
		(fp_line
			(start -0.67945 -0.305054)
			(end -0.12065 -0.305054)
			(stroke
				(width 0.1)
				(type default)
			)
			(layer "F.Fab")
		)
		(fp_line
			(start -0.12065 -0.305054)
			(end -0.12065 -0.2794)
			(stroke
				(width 0.1)
				(type default)
			)
			(layer "F.Fab")
		)
		(pad "1" smd circle
			(at -0.40005 0 270)
			(size 0 0)
			(layers "F.Cu" "F.Mask" "F.Paste")
			(net "SW_PVCCIN_CPU1_BOOT5_R")
		)
		(pad "2" smd circle
			(at 0.40005 0 270)
			(size 0 0)
			(layers "F.Cu" "F.Mask" "F.Paste")
			(net "SW_PVCCIN_CPU1_BOOTR5")
		)
	)
	(footprint ""
		(layer "F.Cu")
		(at 168.11371 -129.553716 90)
		(property "Reference" "R1640"
			(at 0 0 90)
			(layer "F.SilkS")
			(hide yes)
			(effects
				(font
					(size 1.27 1.27)
				)
			)
		)
		(property "Value" ""
			(at 0 0 90)
			(layer "F.Fab")
			(effects
				(font
					(size 1.27 1.27)
				)
			)
		)
		(duplicate_pad_numbers_are_jumpers no)
		(fp_line
			(start 0.7874 -0.4064)
			(end 0.7874 0.4064)
			(stroke
				(width 0.1524)
				(type default)
			)
			(layer "F.SilkS")
		)
		(fp_line
			(start -0.7874 -0.4064)
			(end 0.7874 -0.4064)
			(stroke
				(width 0.1524)
				(type default)
			)
			(layer "F.SilkS")
		)
		(fp_line
			(start 0.7874 0.4064)
			(end -0.7874 0.4064)
			(stroke
				(width 0.1524)
				(type default)
			)
			(layer "F.SilkS")
		)
		(fp_line
			(start -0.7874 0.4064)
			(end -0.7874 -0.4064)
			(stroke
				(width 0.1524)
				(type default)
			)
			(layer "F.SilkS")
		)
		(fp_line
			(start -0.12065 -0.305054)
			(end -0.12065 -0.2794)
			(stroke
				(width 0.1)
				(type default)
			)
			(layer "F.Fab")
		)
		(fp_line
			(start -0.67945 -0.305054)
			(end -0.12065 -0.305054)
			(stroke
				(width 0.1)
				(type default)
			)
			(layer "F.Fab")
		)
		(fp_line
			(start 0.67945 -0.3048)
			(end 0.67945 0.3048)
			(stroke
				(width 0.1)
				(type default)
			)
			(layer "F.Fab")
		)
		(fp_line
			(start 0.12065 -0.3048)
			(end 0.67945 -0.3048)
			(stroke
				(width 0.1)
				(type default)
			)
			(layer "F.Fab")
		)
		(fp_line
			(start 0.12065 -0.2794)
			(end 0.12065 -0.3048)
			(stroke
				(width 0.1)
				(type default)
			)
			(layer "F.Fab")
		)
		(fp_line
			(start -0.12065 -0.2794)
			(end 0.12065 -0.2794)
			(stroke
				(width 0.1)
				(type default)
			)
			(layer "F.Fab")
		)
		(fp_line
			(start 0.120396 0.2794)
			(end -0.12065 0.2794)
			(stroke
				(width 0.1)
				(type default)
			)
			(layer "F.Fab")
		)
		(fp_line
			(start -0.12065 0.2794)
			(end -0.12065 0.3048)
			(stroke
				(width 0.1)
				(type default)
			)
			(layer "F.Fab")
		)
		(fp_line
			(start 0.67945 0.3048)
			(end 0.120396 0.3048)
			(stroke
				(width 0.1)
				(type default)
			)
			(layer "F.Fab")
		)
		(fp_line
			(start 0.120396 0.3048)
			(end 0.120396 0.2794)
			(stroke
				(width 0.1)
				(type default)
			)
			(layer "F.Fab")
		)
		(fp_line
			(start -0.12065 0.3048)
			(end -0.67945 0.3048)
			(stroke
				(width 0.1)
				(type default)
			)
			(layer "F.Fab")
		)
		(fp_line
			(start -0.67945 0.3048)
			(end -0.67945 -0.305054)
			(stroke
				(width 0.1)
				(type default)
			)
			(layer "F.Fab")
		)
		(pad "1" smd circle
			(at -0.40005 0 90)
			(size 0 0)
			(layers "F.Cu" "F.Mask" "F.Paste")
			(net "FM_P5V_EN")
		)
		(pad "2" smd circle
			(at 0.40005 0 90)
			(size 0 0)
			(layers "F.Cu" "F.Mask" "F.Paste")
			(net "VR_P5V_EN")
		)
	)
	(footprint ""
		(layer "F.Cu")
		(at 22.86889 -182.595266 180)
		(property "Reference" "PC2222"
			(at 0 0 180)
			(layer "F.SilkS")
			(hide yes)
			(effects
				(font
					(size 1.27 1.27)
				)
			)
		)
		(property "Value" ""
			(at 0 0 180)
			(layer "F.Fab")
			(effects
				(font
					(size 1.27 1.27)
				)
			)
		)
		(duplicate_pad_numbers_are_jumpers no)
		(fp_line
			(start 0.7874 0.4064)
			(end -0.7874 0.4064)
			(stroke
				(width 0.1524)
				(type default)
			)
			(layer "F.SilkS")
		)
		(fp_line
			(start 0.7874 -0.4064)
			(end 0.7874 0.4064)
			(stroke
				(width 0.1524)
				(type default)
			)
			(layer "F.SilkS")
		)
		(fp_line
			(start -0.7874 0.4064)
			(end -0.7874 -0.4064)
			(stroke
				(width 0.1524)
				(type default)
			)
			(layer "F.SilkS")
		)
		(fp_line
			(start -0.7874 -0.4064)
			(end 0.7874 -0.4064)
			(stroke
				(width 0.1524)
				(type default)
			)
			(layer "F.SilkS")
		)
		(fp_line
			(start 0.67945 0.3048)
			(end 0.120396 0.3048)
			(stroke
				(width 0.1)
				(type default)
			)
			(layer "F.Fab")
		)
		(fp_line
			(start 0.67945 -0.3048)
			(end 0.67945 0.3048)
			(stroke
				(width 0.1)
				(type default)
			)
			(layer "F.Fab")
		)
		(fp_line
			(start 0.12065 -0.2794)
			(end 0.12065 -0.3048)
			(stroke
				(width 0.1)
				(type default)
			)
			(layer "F.Fab")
		)
		(fp_line
			(start 0.12065 -0.3048)
			(end 0.67945 -0.3048)
			(stroke
				(width 0.1)
				(type default)
			)
			(layer "F.Fab")
		)
		(fp_line
			(start 0.120396 0.3048)
			(end 0.120396 0.2794)
			(stroke
				(width 0.1)
				(type default)
			)
			(layer "F.Fab")
		)
		(fp_line
			(start 0.120396 0.2794)
			(end -0.12065 0.2794)
			(stroke
				(width 0.1)
				(type default)
			)
			(layer "F.Fab")
		)
		(fp_line
			(start -0.12065 0.3048)
			(end -0.67945 0.3048)
			(stroke
				(width 0.1)
				(type default)
			)
			(layer "F.Fab")
		)
		(fp_line
			(start -0.12065 0.2794)
			(end -0.12065 0.3048)
			(stroke
				(width 0.1)
				(type default)
			)
			(layer "F.Fab")
		)
		(fp_line
			(start -0.12065 -0.2794)
			(end 0.12065 -0.2794)
			(stroke
				(width 0.1)
				(type default)
			)
			(layer "F.Fab")
		)
		(fp_line
			(start -0.12065 -0.305054)
			(end -0.12065 -0.2794)
			(stroke
				(width 0.1)
				(type default)
			)
			(layer "F.Fab")
		)
		(fp_line
			(start -0.67945 0.3048)
			(end -0.67945 -0.305054)
			(stroke
				(width 0.1)
				(type default)
			)
			(layer "F.Fab")
		)
		(fp_line
			(start -0.67945 -0.305054)
			(end -0.12065 -0.305054)
			(stroke
				(width 0.1)
				(type default)
			)
			(layer "F.Fab")
		)
		(pad "1" smd circle
			(at -0.40005 0 180)
			(size 0 0)
			(layers "F.Cu" "F.Mask" "F.Paste")
			(net "PVNN_MAIN_CPU1_VCC")
		)
		(pad "2" smd circle
			(at 0.40005 0 180)
			(size 0 0)
			(layers "F.Cu" "F.Mask" "F.Paste")
			(net "GND")
		)
	)
	(footprint ""
		(layer "F.Cu")
		(at 107.2896 -251.375672 90)
		(property "Reference" "C291"
			(at 0 0 90)
			(layer "F.SilkS")
			(hide yes)
			(effects
				(font
					(size 1.27 1.27)
				)
			)
		)
		(property "Value" ""
			(at 0 0 90)
			(layer "F.Fab")
			(effects
				(font
					(size 1.27 1.27)
				)
			)
		)
		(duplicate_pad_numbers_are_jumpers no)
		(fp_line
			(start 0.7874 -0.4064)
			(end 0.7874 0.4064)
			(stroke
				(width 0.1524)
				(type default)
			)
			(layer "F.SilkS")
		)
		(fp_line
			(start -0.7874 -0.4064)
			(end 0.7874 -0.4064)
			(stroke
				(width 0.1524)
				(type default)
			)
			(layer "F.SilkS")
		)
		(fp_line
			(start 0.7874 0.4064)
			(end -0.7874 0.4064)
			(stroke
				(width 0.1524)
				(type default)
			)
			(layer "F.SilkS")
		)
		(fp_line
			(start -0.7874 0.4064)
			(end -0.7874 -0.4064)
			(stroke
				(width 0.1524)
				(type default)
			)
			(layer "F.SilkS")
		)
		(fp_line
			(start -0.12065 -0.305054)
			(end -0.12065 -0.2794)
			(stroke
				(width 0.1)
				(type default)
			)
			(layer "F.Fab")
		)
		(fp_line
			(start -0.67945 -0.305054)
			(end -0.12065 -0.305054)
			(stroke
				(width 0.1)
				(type default)
			)
			(layer "F.Fab")
		)
		(fp_line
			(start 0.67945 -0.3048)
			(end 0.67945 0.3048)
			(stroke
				(width 0.1)
				(type default)
			)
			(layer "F.Fab")
		)
		(fp_line
			(start 0.12065 -0.3048)
			(end 0.67945 -0.3048)
			(stroke
				(width 0.1)
				(type default)
			)
			(layer "F.Fab")
		)
		(fp_line
			(start 0.12065 -0.2794)
			(end 0.12065 -0.3048)
			(stroke
				(width 0.1)
				(type default)
			)
			(layer "F.Fab")
		)
		(fp_line
			(start -0.12065 -0.2794)
			(end 0.12065 -0.2794)
			(stroke
				(width 0.1)
				(type default)
			)
			(layer "F.Fab")
		)
		(fp_line
			(start 0.120396 0.2794)
			(end -0.12065 0.2794)
			(stroke
				(width 0.1)
				(type default)
			)
			(layer "F.Fab")
		)
		(fp_line
			(start -0.12065 0.2794)
			(end -0.12065 0.3048)
			(stroke
				(width 0.1)
				(type default)
			)
			(layer "F.Fab")
		)
		(fp_line
			(start 0.67945 0.3048)
			(end 0.120396 0.3048)
			(stroke
				(width 0.1)
				(type default)
			)
			(layer "F.Fab")
		)
		(fp_line
			(start 0.120396 0.3048)
			(end 0.120396 0.2794)
			(stroke
				(width 0.1)
				(type default)
			)
			(layer "F.Fab")
		)
		(fp_line
			(start -0.12065 0.3048)
			(end -0.67945 0.3048)
			(stroke
				(width 0.1)
				(type default)
			)
			(layer "F.Fab")
		)
		(fp_line
			(start -0.67945 0.3048)
			(end -0.67945 -0.305054)
			(stroke
				(width 0.1)
				(type default)
			)
			(layer "F.Fab")
		)
		(pad "1" smd circle
			(at -0.40005 0 90)
			(size 0 0)
			(layers "F.Cu" "F.Mask" "F.Paste")
			(net "PVCCIN_CPU1")
		)
		(pad "2" smd circle
			(at 0.40005 0 90)
			(size 0 0)
			(layers "F.Cu" "F.Mask" "F.Paste")
			(net "GND")
		)
	)
	(footprint ""
		(layer "F.Cu")
		(at 82.706718 -19.142202 -90)
		(property "Reference" "R3825"
			(at 0 0 270)
			(layer "F.SilkS")
			(hide yes)
			(effects
				(font
					(size 1.27 1.27)
				)
			)
		)
		(property "Value" ""
			(at 0 0 270)
			(layer "F.Fab")
			(effects
				(font
					(size 1.27 1.27)
				)
			)
		)
		(duplicate_pad_numbers_are_jumpers no)
		(fp_line
			(start -0.7874 0.4064)
			(end -0.7874 -0.4064)
			(stroke
				(width 0.1524)
				(type default)
			)
			(layer "F.SilkS")
		)
		(fp_line
			(start 0.7874 0.4064)
			(end -0.7874 0.4064)
			(stroke
				(width 0.1524)
				(type default)
			)
			(layer "F.SilkS")
		)
		(fp_line
			(start -0.7874 -0.4064)
			(end 0.7874 -0.4064)
			(stroke
				(width 0.1524)
				(type default)
			)
			(layer "F.SilkS")
		)
		(fp_line
			(start 0.7874 -0.4064)
			(end 0.7874 0.4064)
			(stroke
				(width 0.1524)
				(type default)
			)
			(layer "F.SilkS")
		)
		(fp_line
			(start -0.67945 0.3048)
			(end -0.67945 -0.305054)
			(stroke
				(width 0.1)
				(type default)
			)
			(layer "F.Fab")
		)
		(fp_line
			(start -0.12065 0.3048)
			(end -0.67945 0.3048)
			(stroke
				(width 0.1)
				(type default)
			)
			(layer "F.Fab")
		)
		(fp_line
			(start 0.120396 0.3048)
			(end 0.120396 0.2794)
			(stroke
				(width 0.1)
				(type default)
			)
			(layer "F.Fab")
		)
		(fp_line
			(start 0.67945 0.3048)
			(end 0.120396 0.3048)
			(stroke
				(width 0.1)
				(type default)
			)
			(layer "F.Fab")
		)
		(fp_line
			(start -0.12065 0.2794)
			(end -0.12065 0.3048)
			(stroke
				(width 0.1)
				(type default)
			)
			(layer "F.Fab")
		)
		(fp_line
			(start 0.120396 0.2794)
			(end -0.12065 0.2794)
			(stroke
				(width 0.1)
				(type default)
			)
			(layer "F.Fab")
		)
		(fp_line
			(start -0.12065 -0.2794)
			(end 0.12065 -0.2794)
			(stroke
				(width 0.1)
				(type default)
			)
			(layer "F.Fab")
		)
		(fp_line
			(start 0.12065 -0.2794)
			(end 0.12065 -0.3048)
			(stroke
				(width 0.1)
				(type default)
			)
			(layer "F.Fab")
		)
		(fp_line
			(start 0.12065 -0.3048)
			(end 0.67945 -0.3048)
			(stroke
				(width 0.1)
				(type default)
			)
			(layer "F.Fab")
		)
		(fp_line
			(start 0.67945 -0.3048)
			(end 0.67945 0.3048)
			(stroke
				(width 0.1)
				(type default)
			)
			(layer "F.Fab")
		)
		(fp_line
			(start -0.67945 -0.305054)
			(end -0.12065 -0.305054)
			(stroke
				(width 0.1)
				(type default)
			)
			(layer "F.Fab")
		)
		(fp_line
			(start -0.12065 -0.305054)
			(end -0.12065 -0.2794)
			(stroke
				(width 0.1)
				(type default)
			)
			(layer "F.Fab")
		)
		(pad "1" smd circle
			(at -0.40005 0 270)
			(size 0 0)
			(layers "F.Cu" "F.Mask" "F.Paste")
			(net "P3V3_AUX")
		)
		(pad "2" smd circle
			(at 0.40005 0 270)
			(size 0 0)
			(layers "F.Cu" "F.Mask" "F.Paste")
			(net "HP_LVC3_OCP_V3_2_P12V_PWRGD")
		)
	)
	(footprint ""
		(layer "F.Cu")
		(at 118.44528 -405.823166 -90)
		(property "Reference" "R2831"
			(at 0 0 270)
			(layer "F.SilkS")
			(hide yes)
			(effects
				(font
					(size 1.27 1.27)
				)
			)
		)
		(property "Value" ""
			(at 0 0 270)
			(layer "F.Fab")
			(effects
				(font
					(size 1.27 1.27)
				)
			)
		)
		(duplicate_pad_numbers_are_jumpers no)
		(fp_line
			(start -0.7874 0.4064)
			(end -0.7874 -0.4064)
			(stroke
				(width 0.1524)
				(type default)
			)
			(layer "F.SilkS")
		)
		(fp_line
			(start 0.7874 0.4064)
			(end -0.7874 0.4064)
			(stroke
				(width 0.1524)
				(type default)
			)
			(layer "F.SilkS")
		)
		(fp_line
			(start -0.7874 -0.4064)
			(end 0.7874 -0.4064)
			(stroke
				(width 0.1524)
				(type default)
			)
			(layer "F.SilkS")
		)
		(fp_line
			(start 0.7874 -0.4064)
			(end 0.7874 0.4064)
			(stroke
				(width 0.1524)
				(type default)
			)
			(layer "F.SilkS")
		)
		(fp_line
			(start -0.67945 0.3048)
			(end -0.67945 -0.305054)
			(stroke
				(width 0.1)
				(type default)
			)
			(layer "F.Fab")
		)
		(fp_line
			(start -0.12065 0.3048)
			(end -0.67945 0.3048)
			(stroke
				(width 0.1)
				(type default)
			)
			(layer "F.Fab")
		)
		(fp_line
			(start 0.120396 0.3048)
			(end 0.120396 0.2794)
			(stroke
				(width 0.1)
				(type default)
			)
			(layer "F.Fab")
		)
		(fp_line
			(start 0.67945 0.3048)
			(end 0.120396 0.3048)
			(stroke
				(width 0.1)
				(type default)
			)
			(layer "F.Fab")
		)
		(fp_line
			(start -0.12065 0.2794)
			(end -0.12065 0.3048)
			(stroke
				(width 0.1)
				(type default)
			)
			(layer "F.Fab")
		)
		(fp_line
			(start 0.120396 0.2794)
			(end -0.12065 0.2794)
			(stroke
				(width 0.1)
				(type default)
			)
			(layer "F.Fab")
		)
		(fp_line
			(start -0.12065 -0.2794)
			(end 0.12065 -0.2794)
			(stroke
				(width 0.1)
				(type default)
			)
			(layer "F.Fab")
		)
		(fp_line
			(start 0.12065 -0.2794)
			(end 0.12065 -0.3048)
			(stroke
				(width 0.1)
				(type default)
			)
			(layer "F.Fab")
		)
		(fp_line
			(start 0.12065 -0.3048)
			(end 0.67945 -0.3048)
			(stroke
				(width 0.1)
				(type default)
			)
			(layer "F.Fab")
		)
		(fp_line
			(start 0.67945 -0.3048)
			(end 0.67945 0.3048)
			(stroke
				(width 0.1)
				(type default)
			)
			(layer "F.Fab")
		)
		(fp_line
			(start -0.67945 -0.305054)
			(end -0.12065 -0.305054)
			(stroke
				(width 0.1)
				(type default)
			)
			(layer "F.Fab")
		)
		(fp_line
			(start -0.12065 -0.305054)
			(end -0.12065 -0.2794)
			(stroke
				(width 0.1)
				(type default)
			)
			(layer "F.Fab")
		)
		(pad "1" smd circle
			(at -0.40005 0 270)
			(size 0 0)
			(layers "F.Cu" "F.Mask" "F.Paste")
			(net "BIC_MONITER")
		)
		(pad "2" smd circle
			(at 0.40005 0 270)
			(size 0 0)
			(layers "F.Cu" "F.Mask" "F.Paste")
			(net "GND")
		)
	)
	(footprint ""
		(layer "F.Cu")
		(at 193.60388 -106.225848)
		(property "Reference" "R1494"
			(at 0 0 0)
			(layer "F.SilkS")
			(hide yes)
			(effects
				(font
					(size 1.27 1.27)
				)
			)
		)
		(property "Value" ""
			(at 0 0 0)
			(layer "F.Fab")
			(effects
				(font
					(size 1.27 1.27)
				)
			)
		)
		(duplicate_pad_numbers_are_jumpers no)
		(fp_line
			(start -0.7874 -0.4064)
			(end 0.7874 -0.4064)
			(stroke
				(width 0.1524)
				(type default)
			)
			(layer "F.SilkS")
		)
		(fp_line
			(start -0.7874 0.4064)
			(end -0.7874 -0.4064)
			(stroke
				(width 0.1524)
				(type default)
			)
			(layer "F.SilkS")
		)
		(fp_line
			(start 0.7874 -0.4064)
			(end 0.7874 0.4064)
			(stroke
				(width 0.1524)
				(type default)
			)
			(layer "F.SilkS")
		)
		(fp_line
			(start 0.7874 0.4064)
			(end -0.7874 0.4064)
			(stroke
				(width 0.1524)
				(type default)
			)
			(layer "F.SilkS")
		)
		(fp_line
			(start -0.67945 -0.305054)
			(end -0.12065 -0.305054)
			(stroke
				(width 0.1)
				(type default)
			)
			(layer "F.Fab")
		)
		(fp_line
			(start -0.67945 0.3048)
			(end -0.67945 -0.305054)
			(stroke
				(width 0.1)
				(type default)
			)
			(layer "F.Fab")
		)
		(fp_line
			(start -0.12065 -0.305054)
			(end -0.12065 -0.2794)
			(stroke
				(width 0.1)
				(type default)
			)
			(layer "F.Fab")
		)
		(fp_line
			(start -0.12065 -0.2794)
			(end 0.12065 -0.2794)
			(stroke
				(width 0.1)
				(type default)
			)
			(layer "F.Fab")
		)
		(fp_line
			(start -0.12065 0.2794)
			(end -0.12065 0.3048)
			(stroke
				(width 0.1)
				(type default)
			)
			(layer "F.Fab")
		)
		(fp_line
			(start -0.12065 0.3048)
			(end -0.67945 0.3048)
			(stroke
				(width 0.1)
				(type default)
			)
			(layer "F.Fab")
		)
		(fp_line
			(start 0.120396 0.2794)
			(end -0.12065 0.2794)
			(stroke
				(width 0.1)
				(type default)
			)
			(layer "F.Fab")
		)
		(fp_line
			(start 0.120396 0.3048)
			(end 0.120396 0.2794)
			(stroke
				(width 0.1)
				(type default)
			)
			(layer "F.Fab")
		)
		(fp_line
			(start 0.12065 -0.3048)
			(end 0.67945 -0.3048)
			(stroke
				(width 0.1)
				(type default)
			)
			(layer "F.Fab")
		)
		(fp_line
			(start 0.12065 -0.2794)
			(end 0.12065 -0.3048)
			(stroke
				(width 0.1)
				(type default)
			)
			(layer "F.Fab")
		)
		(fp_line
			(start 0.67945 -0.3048)
			(end 0.67945 0.3048)
			(stroke
				(width 0.1)
				(type default)
			)
			(layer "F.Fab")
		)
		(fp_line
			(start 0.67945 0.3048)
			(end 0.120396 0.3048)
			(stroke
				(width 0.1)
				(type default)
			)
			(layer "F.Fab")
		)
		(pad "1" smd circle
			(at -0.40005 0)
			(size 0 0)
			(layers "F.Cu" "F.Mask" "F.Paste")
			(net "FM_DIS_PS_PWROK_DLY")
		)
		(pad "2" smd circle
			(at 0.40005 0)
			(size 0 0)
			(layers "F.Cu" "F.Mask" "F.Paste")
			(net "GND")
		)
	)
	(footprint ""
		(layer "F.Cu")
		(at 10.19048 -258.091686)
		(property "Reference" "J23"
			(at -5.69468 -80.480408 0)
			(unlocked yes)
			(layer "F.SilkS")
			(effects
				(font
					(size 0.7874 0.5842)
					(thickness 0.1524)
				)
				(justify left)
			)
		)
		(property "Value" ""
			(at 0 0 0)
			(layer "F.Fab")
			(effects
				(font
					(size 1.27 1.27)
				)
			)
		)
		(duplicate_pad_numbers_are_jumpers no)
		(fp_line
			(start -3.24993 -81.000092)
			(end -3.24993 81.000092)
			(stroke
				(width 0.1524)
				(type default)
			)
			(layer "F.SilkS")
		)
		(fp_line
			(start -3.24993 81.000092)
			(end 3.24993 81.000092)
			(stroke
				(width 0.1524)
				(type default)
			)
			(layer "F.SilkS")
		)
		(fp_line
			(start 3.24993 -81.000092)
			(end -3.24993 -81.000092)
			(stroke
				(width 0.1524)
				(type default)
			)
			(layer "F.SilkS")
		)
		(fp_line
			(start 3.24993 -72.00011)
			(end -3.24993 -72.00011)
			(stroke
				(width 0.1524)
				(type default)
			)
			(layer "F.SilkS")
		)
		(fp_line
			(start 3.24993 72.00011)
			(end -3.24993 72.00011)
			(stroke
				(width 0.1524)
				(type default)
			)
			(layer "F.SilkS")
		)
		(fp_line
			(start 3.24993 81.000092)
			(end 3.24993 -81.000092)
			(stroke
				(width 0.1524)
				(type default)
			)
			(layer "F.SilkS")
		)
		(fp_poly
			(pts
				(xy -4.349242 -63.73495) (xy -3.467608 -63.294006) (xy -4.349242 -62.853062)
			)
			(stroke
				(width 0)
				(type default)
			)
			(fill yes)
			(layer "F.SilkS")
		)
		(fp_line
			(start -3.24993 -81.000092)
			(end -3.24993 81.000092)
			(stroke
				(width 0.1)
				(type default)
			)
			(layer "F.Fab")
		)
		(fp_line
			(start -3.24993 81.000092)
			(end 3.24993 81.000092)
			(stroke
				(width 0.1)
				(type default)
			)
			(layer "F.Fab")
		)
		(fp_line
			(start 3.24993 -81.000092)
			(end -3.24993 -81.000092)
			(stroke
				(width 0.1)
				(type default)
			)
			(layer "F.Fab")
		)
		(fp_line
			(start 3.24993 -72.00011)
			(end -3.24993 -72.00011)
			(stroke
				(width 0.1)
				(type default)
			)
			(layer "F.Fab")
		)
		(fp_line
			(start 3.24993 -71.000112)
			(end -3.24993 -71.000112)
			(stroke
				(width 0.1)
				(type default)
			)
			(layer "F.Fab")
		)
		(fp_line
			(start 3.24993 71.000112)
			(end -3.24993 71.000112)
			(stroke
				(width 0.1)
				(type default)
			)
			(layer "F.Fab")
		)
		(fp_line
			(start 3.24993 72.00011)
			(end -3.24993 72.00011)
			(stroke
				(width 0.1)
				(type default)
			)
			(layer "F.Fab")
		)
		(fp_line
			(start 3.24993 81.000092)
			(end 3.24993 -81.000092)
			(stroke
				(width 0.1)
				(type default)
			)
			(layer "F.Fab")
		)
		(fp_poly
			(pts
				(xy -4.445 -63.832994) (xy -4.445 -62.816994) (xy -3.429 -63.324994)
			)
			(stroke
				(width 0)
				(type default)
			)
			(fill yes)
			(layer "F.Fab")
		)
		(pad "1" smd rect
			(at -2.050034 -63.324994 270)
			(size 0.519938 1.4986)
			(layers "F.Cu" "F.Mask" "F.Paste")
			(net "P12V_S3_AUX_CPU1_NVDIMM")
		)
		(pad "2" smd rect
			(at -2.050034 -62.47511 270)
			(size 0.519938 1.4986)
			(layers "F.Cu" "F.Mask" "F.Paste")
			(net "TP_CHD_CPU1_DIMM1_FRU_0")
		)
		(pad "3" smd rect
			(at -2.050034 -61.624972 270)
			(size 0.519938 1.4986)
			(layers "F.Cu" "F.Mask" "F.Paste")
			(net "P3V3_AUX")
		)
		(pad "4" smd rect
			(at -2.050034 -60.775088 270)
			(size 0.519938 1.4986)
			(layers "F.Cu" "F.Mask" "F.Paste")
			(net "I3C_SPD_DDRABCD_CPU1_LVC1_SCL_6")
		)
		(pad "5" smd rect
			(at -2.050034 -59.92495 270)
			(size 0.519938 1.4986)
			(layers "F.Cu" "F.Mask" "F.Paste")
			(net "I3C_SPD_DDRABCD_CPU1_LVC1_SDA")
		)
		(pad "6" smd rect
			(at -2.050034 -59.075066 270)
			(size 0.519938 1.4986)
			(layers "F.Cu" "F.Mask" "F.Paste")
			(net "GND")
		)
		(pad "7" smd rect
			(at -2.050034 -58.224928 270)
			(size 0.519938 1.4986)
			(layers "F.Cu" "F.Mask" "F.Paste")
			(net "M_D_CPU1_SA_DQ<0>")
		)
		(pad "8" smd rect
			(at -2.050034 -57.375044 270)
			(size 0.519938 1.4986)
			(layers "F.Cu" "F.Mask" "F.Paste")
			(net "GND")
		)
		(pad "9" smd rect
			(at -2.050034 -56.524906 270)
			(size 0.519938 1.4986)
			(layers "F.Cu" "F.Mask" "F.Paste")
			(net "M_D_CPU1_SA_DQ<1>")
		)
		(pad "10" smd rect
			(at -2.050034 -55.675022 270)
			(size 0.519938 1.4986)
			(layers "F.Cu" "F.Mask" "F.Paste")
			(net "GND")
		)
		(pad "11" smd rect
			(at -2.050034 -54.824884 270)
			(size 0.519938 1.4986)
			(layers "F.Cu" "F.Mask" "F.Paste")
			(net "M_D_CPU1_SA_DQS_DP<0>")
		)
		(pad "12" smd rect
			(at -2.050034 -53.975 270)
			(size 0.519938 1.4986)
			(layers "F.Cu" "F.Mask" "F.Paste")
			(net "M_D_CPU1_SA_DQS_DN<0>")
		)
		(pad "13" smd rect
			(at -2.050034 -53.125116 270)
			(size 0.519938 1.4986)
			(layers "F.Cu" "F.Mask" "F.Paste")
			(net "GND")
		)
		(pad "14" smd rect
			(at -2.050034 -52.274978 270)
			(size 0.519938 1.4986)
			(layers "F.Cu" "F.Mask" "F.Paste")
			(net "M_D_CPU1_SA_DQ<4>")
		)
		(pad "15" smd rect
			(at -2.050034 -51.425094 270)
			(size 0.519938 1.4986)
			(layers "F.Cu" "F.Mask" "F.Paste")
			(net "GND")
		)
		(pad "16" smd rect
			(at -2.050034 -50.574956 270)
			(size 0.519938 1.4986)
			(layers "F.Cu" "F.Mask" "F.Paste")
			(net "M_D_CPU1_SA_DQ<5>")
		)
		(pad "17" smd rect
			(at -2.050034 -49.725072 270)
			(size 0.519938 1.4986)
			(layers "F.Cu" "F.Mask" "F.Paste")
			(net "GND")
		)
		(pad "18" smd rect
			(at -2.050034 -48.874934 270)
			(size 0.519938 1.4986)
			(layers "F.Cu" "F.Mask" "F.Paste")
			(net "M_D_CPU1_SA_DQ<8>")
		)
		(pad "19" smd rect
			(at -2.050034 -48.02505 270)
			(size 0.519938 1.4986)
			(layers "F.Cu" "F.Mask" "F.Paste")
			(net "GND")
		)
		(pad "20" smd rect
			(at -2.050034 -47.174912 270)
			(size 0.519938 1.4986)
			(layers "F.Cu" "F.Mask" "F.Paste")
			(net "M_D_CPU1_SA_DQ<9>")
		)
		(pad "21" smd rect
			(at -2.050034 -46.325028 270)
			(size 0.519938 1.4986)
			(layers "F.Cu" "F.Mask" "F.Paste")
			(net "GND")
		)
		(pad "22" smd rect
			(at -2.050034 -45.47489 270)
			(size 0.519938 1.4986)
			(layers "F.Cu" "F.Mask" "F.Paste")
			(net "M_D_CPU1_SA_DQS_DP<1>")
		)
		(pad "23" smd rect
			(at -2.050034 -44.625006 270)
			(size 0.519938 1.4986)
			(layers "F.Cu" "F.Mask" "F.Paste")
			(net "M_D_CPU1_SA_DQS_DN<1>")
		)
		(pad "24" smd rect
			(at -2.050034 -43.775122 270)
			(size 0.519938 1.4986)
			(layers "F.Cu" "F.Mask" "F.Paste")
			(net "GND")
		)
		(pad "25" smd rect
			(at -2.050034 -42.924984 270)
			(size 0.519938 1.4986)
			(layers "F.Cu" "F.Mask" "F.Paste")
			(net "M_D_CPU1_SA_DQ<12>")
		)
		(pad "26" smd rect
			(at -2.050034 -42.0751 270)
			(size 0.519938 1.4986)
			(layers "F.Cu" "F.Mask" "F.Paste")
			(net "GND")
		)
		(pad "27" smd rect
			(at -2.050034 -41.224962 270)
			(size 0.519938 1.4986)
			(layers "F.Cu" "F.Mask" "F.Paste")
			(net "M_D_CPU1_SA_DQ<13>")
		)
		(pad "28" smd rect
			(at -2.050034 -40.375078 270)
			(size 0.519938 1.4986)
			(layers "F.Cu" "F.Mask" "F.Paste")
			(net "GND")
		)
		(pad "29" smd rect
			(at -2.050034 -39.52494 270)
			(size 0.519938 1.4986)
			(layers "F.Cu" "F.Mask" "F.Paste")
			(net "M_D_CPU1_SA_DQ<16>")
		)
		(pad "30" smd rect
			(at -2.050034 -38.675056 270)
			(size 0.519938 1.4986)
			(layers "F.Cu" "F.Mask" "F.Paste")
			(net "GND")
		)
		(pad "31" smd rect
			(at -2.050034 -37.824918 270)
			(size 0.519938 1.4986)
			(layers "F.Cu" "F.Mask" "F.Paste")
			(net "M_D_CPU1_SA_DQ<17>")
		)
		(pad "32" smd rect
			(at -2.050034 -36.975034 270)
			(size 0.519938 1.4986)
			(layers "F.Cu" "F.Mask" "F.Paste")
			(net "GND")
		)
		(pad "33" smd rect
			(at -2.050034 -36.124896 270)
			(size 0.519938 1.4986)
			(layers "F.Cu" "F.Mask" "F.Paste")
			(net "M_D_CPU1_SA_DQS_DP<2>")
		)
		(pad "34" smd rect
			(at -2.050034 -35.275012 270)
			(size 0.519938 1.4986)
			(layers "F.Cu" "F.Mask" "F.Paste")
			(net "M_D_CPU1_SA_DQS_DN<2>")
		)
		(pad "35" smd rect
			(at -2.050034 -34.425128 270)
			(size 0.519938 1.4986)
			(layers "F.Cu" "F.Mask" "F.Paste")
			(net "GND")
		)
		(pad "36" smd rect
			(at -2.050034 -33.57499 270)
			(size 0.519938 1.4986)
			(layers "F.Cu" "F.Mask" "F.Paste")
			(net "M_D_CPU1_SA_DQ<20>")
		)
		(pad "37" smd rect
			(at -2.050034 -32.725106 270)
			(size 0.519938 1.4986)
			(layers "F.Cu" "F.Mask" "F.Paste")
			(net "GND")
		)
		(pad "38" smd rect
			(at -2.050034 -31.874968 270)
			(size 0.519938 1.4986)
			(layers "F.Cu" "F.Mask" "F.Paste")
			(net "M_D_CPU1_SA_DQ<21>")
		)
		(pad "39" smd rect
			(at -2.050034 -31.025084 270)
			(size 0.519938 1.4986)
			(layers "F.Cu" "F.Mask" "F.Paste")
			(net "GND")
		)
		(pad "40" smd rect
			(at -2.050034 -30.174946 270)
			(size 0.519938 1.4986)
			(layers "F.Cu" "F.Mask" "F.Paste")
			(net "M_D_CPU1_SA_DQ<24>")
		)
		(pad "41" smd rect
			(at -2.050034 -29.325062 270)
			(size 0.519938 1.4986)
			(layers "F.Cu" "F.Mask" "F.Paste")
			(net "GND")
		)
		(pad "42" smd rect
			(at -2.050034 -28.474924 270)
			(size 0.519938 1.4986)
			(layers "F.Cu" "F.Mask" "F.Paste")
			(net "M_D_CPU1_SA_DQ<25>")
		)
		(pad "43" smd rect
			(at -2.050034 -27.62504 270)
			(size 0.519938 1.4986)
			(layers "F.Cu" "F.Mask" "F.Paste")
			(net "GND")
		)
		(pad "44" smd rect
			(at -2.050034 -26.774902 270)
			(size 0.519938 1.4986)
			(layers "F.Cu" "F.Mask" "F.Paste")
			(net "M_D_CPU1_SA_DQS_DP<3>")
		)
		(pad "45" smd rect
			(at -2.050034 -25.925018 270)
			(size 0.519938 1.4986)
			(layers "F.Cu" "F.Mask" "F.Paste")
			(net "M_D_CPU1_SA_DQS_DN<3>")
		)
		(pad "46" smd rect
			(at -2.050034 -25.07488 270)
			(size 0.519938 1.4986)
			(layers "F.Cu" "F.Mask" "F.Paste")
			(net "GND")
		)
		(pad "47" smd rect
			(at -2.050034 -24.224996 270)
			(size 0.519938 1.4986)
			(layers "F.Cu" "F.Mask" "F.Paste")
			(net "M_D_CPU1_SA_DQ<28>")
		)
		(pad "48" smd rect
			(at -2.050034 -23.375112 270)
			(size 0.519938 1.4986)
			(layers "F.Cu" "F.Mask" "F.Paste")
			(net "GND")
		)
		(pad "49" smd rect
			(at -2.050034 -22.524974 270)
			(size 0.519938 1.4986)
			(layers "F.Cu" "F.Mask" "F.Paste")
			(net "M_D_CPU1_SA_DQ<29>")
		)
		(pad "50" smd rect
			(at -2.050034 -21.67509 270)
			(size 0.519938 1.4986)
			(layers "F.Cu" "F.Mask" "F.Paste")
			(net "GND")
		)
		(pad "51" smd rect
			(at -2.050034 -20.824952 270)
			(size 0.519938 1.4986)
			(layers "F.Cu" "F.Mask" "F.Paste")
			(net "M_D_CPU1_SA_CB<0>")
		)
		(pad "52" smd rect
			(at -2.050034 -19.975068 270)
			(size 0.519938 1.4986)
			(layers "F.Cu" "F.Mask" "F.Paste")
			(net "GND")
		)
		(pad "53" smd rect
			(at -2.050034 -19.12493 270)
			(size 0.519938 1.4986)
			(layers "F.Cu" "F.Mask" "F.Paste")
			(net "M_D_CPU1_SA_CB<1>")
		)
		(pad "54" smd rect
			(at -2.050034 -18.275046 270)
			(size 0.519938 1.4986)
			(layers "F.Cu" "F.Mask" "F.Paste")
			(net "GND")
		)
		(pad "55" smd rect
			(at -2.050034 -17.424908 270)
			(size 0.519938 1.4986)
			(layers "F.Cu" "F.Mask" "F.Paste")
			(net "M_D_CPU1_SA_DQS_DP<4>")
		)
		(pad "56" smd rect
			(at -2.050034 -16.575024 270)
			(size 0.519938 1.4986)
			(layers "F.Cu" "F.Mask" "F.Paste")
			(net "M_D_CPU1_SA_DQS_DN<4>")
		)
		(pad "57" smd rect
			(at -2.050034 -15.724886 270)
			(size 0.519938 1.4986)
			(layers "F.Cu" "F.Mask" "F.Paste")
			(net "GND")
		)
		(pad "58" smd rect
			(at -2.050034 -14.875002 270)
			(size 0.519938 1.4986)
			(layers "F.Cu" "F.Mask" "F.Paste")
			(net "M_D_CPU1_SA_CB<4>")
		)
		(pad "59" smd rect
			(at -2.050034 -14.025118 270)
			(size 0.519938 1.4986)
			(layers "F.Cu" "F.Mask" "F.Paste")
			(net "GND")
		)
		(pad "60" smd rect
			(at -2.050034 -13.17498 270)
			(size 0.519938 1.4986)
			(layers "F.Cu" "F.Mask" "F.Paste")
			(net "M_D_CPU1_SA_CB<5>")
		)
		(pad "61" smd rect
			(at -2.050034 -12.325096 270)
			(size 0.519938 1.4986)
			(layers "F.Cu" "F.Mask" "F.Paste")
			(net "GND")
		)
		(pad "62" smd rect
			(at -2.050034 -11.474958 270)
			(size 0.519938 1.4986)
			(layers "F.Cu" "F.Mask" "F.Paste")
			(net "M_D_CPU1_ALERT_N")
		)
		(pad "63" smd rect
			(at -2.050034 -10.625074 270)
			(size 0.519938 1.4986)
			(layers "F.Cu" "F.Mask" "F.Paste")
			(net "GND")
		)
		(pad "64" smd rect
			(at -2.050034 -9.774936 270)
			(size 0.519938 1.4986)
			(layers "F.Cu" "F.Mask" "F.Paste")
			(net "M_D_CPU1_SA_CS_N<0>")
		)
		(pad "65" smd rect
			(at -2.050034 -8.925052 270)
			(size 0.519938 1.4986)
			(layers "F.Cu" "F.Mask" "F.Paste")
			(net "GND")
		)
		(pad "66" smd rect
			(at -2.050034 -8.074914 270)
			(size 0.519938 1.4986)
			(layers "F.Cu" "F.Mask" "F.Paste")
			(net "M_D_CPU1_SA_CA<0>")
		)
		(pad "67" smd rect
			(at -2.050034 -7.22503 270)
			(size 0.519938 1.4986)
			(layers "F.Cu" "F.Mask" "F.Paste")
			(net "GND")
		)
		(pad "68" smd rect
			(at -2.050034 -6.374892 270)
			(size 0.519938 1.4986)
			(layers "F.Cu" "F.Mask" "F.Paste")
			(net "M_D_CPU1_SA_CA<2>")
		)
		(pad "69" smd rect
			(at -2.050034 -5.525008 270)
			(size 0.519938 1.4986)
			(layers "F.Cu" "F.Mask" "F.Paste")
			(net "GND")
		)
		(pad "70" smd rect
			(at -2.050034 -4.675124 270)
			(size 0.519938 1.4986)
			(layers "F.Cu" "F.Mask" "F.Paste")
			(net "M_D_CPU1_SA_CA<4>")
		)
		(pad "71" smd rect
			(at -2.050034 -3.824986 270)
			(size 0.519938 1.4986)
			(layers "F.Cu" "F.Mask" "F.Paste")
			(net "GND")
		)
		(pad "72" smd rect
			(at -2.050034 -2.975102 270)
			(size 0.519938 1.4986)
			(layers "F.Cu" "F.Mask" "F.Paste")
			(net "M_D_CPU1_SA_CA<6>")
		)
		(pad "73" smd rect
			(at -2.050034 -2.124964 270)
			(size 0.519938 1.4986)
			(layers "F.Cu" "F.Mask" "F.Paste")
			(net "GND")
		)
		(pad "74" smd rect
			(at -2.050034 -1.27508 270)
			(size 0.519938 1.4986)
			(layers "F.Cu" "F.Mask" "F.Paste")
			(net "M_D_CPU1_SA_PAR")
		)
		(pad "75" smd rect
			(at -2.050034 -0.424942 270)
			(size 0.519938 1.4986)
			(layers "F.Cu" "F.Mask" "F.Paste")
			(net "GND")
		)
		(pad "76" smd rect
			(at -2.050034 5.525008 270)
			(size 0.519938 1.4986)
			(layers "F.Cu" "F.Mask" "F.Paste")
			(net "M_D_CPU1_SB_CA<0>")
		)
		(pad "77" smd rect
			(at -2.050034 6.374892 270)
			(size 0.519938 1.4986)
			(layers "F.Cu" "F.Mask" "F.Paste")
			(net "GND")
		)
		(pad "78" smd rect
			(at -2.050034 7.22503 270)
			(size 0.519938 1.4986)
			(layers "F.Cu" "F.Mask" "F.Paste")
			(net "M_D_CPU1_SB_CA<2>")
		)
		(pad "79" smd rect
			(at -2.050034 8.074914 270)
			(size 0.519938 1.4986)
			(layers "F.Cu" "F.Mask" "F.Paste")
			(net "GND")
		)
		(pad "80" smd rect
			(at -2.050034 8.925052 270)
			(size 0.519938 1.4986)
			(layers "F.Cu" "F.Mask" "F.Paste")
			(net "M_D_CPU1_SB_CA<4>")
		)
		(pad "81" smd rect
			(at -2.050034 9.774936 270)
			(size 0.519938 1.4986)
			(layers "F.Cu" "F.Mask" "F.Paste")
			(net "GND")
		)
		(pad "82" smd rect
			(at -2.050034 10.625074 270)
			(size 0.519938 1.4986)
			(layers "F.Cu" "F.Mask" "F.Paste")
			(net "M_D_CPU1_SB_CA<6>")
		)
		(pad "83" smd rect
			(at -2.050034 11.474958 270)
			(size 0.519938 1.4986)
			(layers "F.Cu" "F.Mask" "F.Paste")
			(net "GND")
		)
		(pad "84" smd rect
			(at -2.050034 12.325096 270)
			(size 0.519938 1.4986)
			(layers "F.Cu" "F.Mask" "F.Paste")
			(net "M_D_CPU1_SB_CS_N<0>")
		)
		(pad "85" smd rect
			(at -2.050034 13.17498 270)
			(size 0.519938 1.4986)
			(layers "F.Cu" "F.Mask" "F.Paste")
			(net "GND")
		)
		(pad "86" smd rect
			(at -2.050034 14.025118 270)
			(size 0.519938 1.4986)
			(layers "F.Cu" "F.Mask" "F.Paste")
			(net "M_D_CPU1_SA_RSP<0>")
		)
		(pad "87" smd rect
			(at -2.050034 14.875002 270)
			(size 0.519938 1.4986)
			(layers "F.Cu" "F.Mask" "F.Paste")
			(net "M_D_CPU1_SB_RSP<0>")
		)
		(pad "88" smd rect
			(at -2.050034 15.724886 270)
			(size 0.519938 1.4986)
			(layers "F.Cu" "F.Mask" "F.Paste")
			(net "GND")
		)
		(pad "89" smd rect
			(at -2.050034 16.575024 270)
			(size 0.519938 1.4986)
			(layers "F.Cu" "F.Mask" "F.Paste")
			(net "M_D_CPU1_SB_CB<4>")
		)
		(pad "90" smd rect
			(at -2.050034 17.424908 270)
			(size 0.519938 1.4986)
			(layers "F.Cu" "F.Mask" "F.Paste")
			(net "GND")
		)
		(pad "91" smd rect
			(at -2.050034 18.275046 270)
			(size 0.519938 1.4986)
			(layers "F.Cu" "F.Mask" "F.Paste")
			(net "M_D_CPU1_SB_CB<5>")
		)
		(pad "92" smd rect
			(at -2.050034 19.12493 270)
			(size 0.519938 1.4986)
			(layers "F.Cu" "F.Mask" "F.Paste")
			(net "GND")
		)
		(pad "93" smd rect
			(at -2.050034 19.975068 270)
			(size 0.519938 1.4986)
			(layers "F.Cu" "F.Mask" "F.Paste")
			(net "M_D_CPU1_SB_DQS_DP<9>")
		)
		(pad "94" smd rect
			(at -2.050034 20.824952 270)
			(size 0.519938 1.4986)
			(layers "F.Cu" "F.Mask" "F.Paste")
			(net "M_D_CPU1_SB_DQS_DN<9>")
		)
		(pad "95" smd rect
			(at -2.050034 21.67509 270)
			(size 0.519938 1.4986)
			(layers "F.Cu" "F.Mask" "F.Paste")
			(net "GND")
		)
		(pad "96" smd rect
			(at -2.050034 22.524974 270)
			(size 0.519938 1.4986)
			(layers "F.Cu" "F.Mask" "F.Paste")
			(net "M_D_CPU1_SB_CB<0>")
		)
		(pad "97" smd rect
			(at -2.050034 23.375112 270)
			(size 0.519938 1.4986)
			(layers "F.Cu" "F.Mask" "F.Paste")
			(net "GND")
		)
		(pad "98" smd rect
			(at -2.050034 24.224996 270)
			(size 0.519938 1.4986)
			(layers "F.Cu" "F.Mask" "F.Paste")
			(net "M_D_CPU1_SB_CB<1>")
		)
		(pad "99" smd rect
			(at -2.050034 25.07488 270)
			(size 0.519938 1.4986)
			(layers "F.Cu" "F.Mask" "F.Paste")
			(net "GND")
		)
		(pad "100" smd rect
			(at -2.050034 25.925018 270)
			(size 0.519938 1.4986)
			(layers "F.Cu" "F.Mask" "F.Paste")
			(net "M_D_CPU1_SB_DQ<0>")
		)
		(pad "101" smd rect
			(at -2.050034 26.774902 270)
			(size 0.519938 1.4986)
			(layers "F.Cu" "F.Mask" "F.Paste")
			(net "GND")
		)
		(pad "102" smd rect
			(at -2.050034 27.62504 270)
			(size 0.519938 1.4986)
			(layers "F.Cu" "F.Mask" "F.Paste")
			(net "M_D_CPU1_SB_DQ<1>")
		)
		(pad "103" smd rect
			(at -2.050034 28.474924 270)
			(size 0.519938 1.4986)
			(layers "F.Cu" "F.Mask" "F.Paste")
			(net "GND")
		)
		(pad "104" smd rect
			(at -2.050034 29.325062 270)
			(size 0.519938 1.4986)
			(layers "F.Cu" "F.Mask" "F.Paste")
			(net "M_D_CPU1_SB_DQS_DP<0>")
		)
		(pad "105" smd rect
			(at -2.050034 30.174946 270)
			(size 0.519938 1.4986)
			(layers "F.Cu" "F.Mask" "F.Paste")
			(net "M_D_CPU1_SB_DQS_DN<0>")
		)
		(pad "106" smd rect
			(at -2.050034 31.025084 270)
			(size 0.519938 1.4986)
			(layers "F.Cu" "F.Mask" "F.Paste")
			(net "GND")
		)
		(pad "107" smd rect
			(at -2.050034 31.874968 270)
			(size 0.519938 1.4986)
			(layers "F.Cu" "F.Mask" "F.Paste")
			(net "M_D_CPU1_SB_DQ<4>")
		)
		(pad "108" smd rect
			(at -2.050034 32.725106 270)
			(size 0.519938 1.4986)
			(layers "F.Cu" "F.Mask" "F.Paste")
			(net "GND")
		)
		(pad "109" smd rect
			(at -2.050034 33.57499 270)
			(size 0.519938 1.4986)
			(layers "F.Cu" "F.Mask" "F.Paste")
			(net "M_D_CPU1_SB_DQ<5>")
		)
		(pad "110" smd rect
			(at -2.050034 34.425128 270)
			(size 0.519938 1.4986)
			(layers "F.Cu" "F.Mask" "F.Paste")
			(net "GND")
		)
		(pad "111" smd rect
			(at -2.050034 35.275012 270)
			(size 0.519938 1.4986)
			(layers "F.Cu" "F.Mask" "F.Paste")
			(net "M_D_CPU1_SB_DQ<8>")
		)
		(pad "112" smd rect
			(at -2.050034 36.124896 270)
			(size 0.519938 1.4986)
			(layers "F.Cu" "F.Mask" "F.Paste")
			(net "GND")
		)
		(pad "113" smd rect
			(at -2.050034 36.975034 270)
			(size 0.519938 1.4986)
			(layers "F.Cu" "F.Mask" "F.Paste")
			(net "M_D_CPU1_SB_DQ<9>")
		)
		(pad "114" smd rect
			(at -2.050034 37.824918 270)
			(size 0.519938 1.4986)
			(layers "F.Cu" "F.Mask" "F.Paste")
			(net "GND")
		)
		(pad "115" smd rect
			(at -2.050034 38.675056 270)
			(size 0.519938 1.4986)
			(layers "F.Cu" "F.Mask" "F.Paste")
			(net "M_D_CPU1_SB_DQS_DP<1>")
		)
		(pad "116" smd rect
			(at -2.050034 39.52494 270)
			(size 0.519938 1.4986)
			(layers "F.Cu" "F.Mask" "F.Paste")
			(net "M_D_CPU1_SB_DQS_DN<1>")
		)
		(pad "117" smd rect
			(at -2.050034 40.375078 270)
			(size 0.519938 1.4986)
			(layers "F.Cu" "F.Mask" "F.Paste")
			(net "GND")
		)
		(pad "118" smd rect
			(at -2.050034 41.224962 270)
			(size 0.519938 1.4986)
			(layers "F.Cu" "F.Mask" "F.Paste")
			(net "M_D_CPU1_SB_DQ<12>")
		)
		(pad "119" smd rect
			(at -2.050034 42.0751 270)
			(size 0.519938 1.4986)
			(layers "F.Cu" "F.Mask" "F.Paste")
			(net "GND")
		)
		(pad "120" smd rect
			(at -2.050034 42.924984 270)
			(size 0.519938 1.4986)
			(layers "F.Cu" "F.Mask" "F.Paste")
			(net "M_D_CPU1_SB_DQ<13>")
		)
		(pad "121" smd rect
			(at -2.050034 43.775122 270)
			(size 0.519938 1.4986)
			(layers "F.Cu" "F.Mask" "F.Paste")
			(net "GND")
		)
		(pad "122" smd rect
			(at -2.050034 44.625006 270)
			(size 0.519938 1.4986)
			(layers "F.Cu" "F.Mask" "F.Paste")
			(net "M_D_CPU1_SB_DQ<16>")
		)
		(pad "123" smd rect
			(at -2.050034 45.47489 270)
			(size 0.519938 1.4986)
			(layers "F.Cu" "F.Mask" "F.Paste")
			(net "GND")
		)
		(pad "124" smd rect
			(at -2.050034 46.325028 270)
			(size 0.519938 1.4986)
			(layers "F.Cu" "F.Mask" "F.Paste")
			(net "M_D_CPU1_SB_DQ<17>")
		)
		(pad "125" smd rect
			(at -2.050034 47.174912 270)
			(size 0.519938 1.4986)
			(layers "F.Cu" "F.Mask" "F.Paste")
			(net "GND")
		)
		(pad "126" smd rect
			(at -2.050034 48.02505 270)
			(size 0.519938 1.4986)
			(layers "F.Cu" "F.Mask" "F.Paste")
			(net "M_D_CPU1_SB_DQS_DP<2>")
		)
		(pad "127" smd rect
			(at -2.050034 48.874934 270)
			(size 0.519938 1.4986)
			(layers "F.Cu" "F.Mask" "F.Paste")
			(net "M_D_CPU1_SB_DQS_DN<2>")
		)
		(pad "128" smd rect
			(at -2.050034 49.725072 270)
			(size 0.519938 1.4986)
			(layers "F.Cu" "F.Mask" "F.Paste")
			(net "GND")
		)
		(pad "129" smd rect
			(at -2.050034 50.574956 270)
			(size 0.519938 1.4986)
			(layers "F.Cu" "F.Mask" "F.Paste")
			(net "M_D_CPU1_SB_DQ<20>")
		)
		(pad "130" smd rect
			(at -2.050034 51.425094 270)
			(size 0.519938 1.4986)
			(layers "F.Cu" "F.Mask" "F.Paste")
			(net "GND")
		)
		(pad "131" smd rect
			(at -2.050034 52.274978 270)
			(size 0.519938 1.4986)
			(layers "F.Cu" "F.Mask" "F.Paste")
			(net "M_D_CPU1_SB_DQ<21>")
		)
		(pad "132" smd rect
			(at -2.050034 53.125116 270)
			(size 0.519938 1.4986)
			(layers "F.Cu" "F.Mask" "F.Paste")
			(net "GND")
		)
		(pad "133" smd rect
			(at -2.050034 53.975 270)
			(size 0.519938 1.4986)
			(layers "F.Cu" "F.Mask" "F.Paste")
			(net "M_D_CPU1_SB_DQ<24>")
		)
		(pad "134" smd rect
			(at -2.050034 54.824884 270)
			(size 0.519938 1.4986)
			(layers "F.Cu" "F.Mask" "F.Paste")
			(net "GND")
		)
		(pad "135" smd rect
			(at -2.050034 55.675022 270)
			(size 0.519938 1.4986)
			(layers "F.Cu" "F.Mask" "F.Paste")
			(net "M_D_CPU1_SB_DQ<25>")
		)
		(pad "136" smd rect
			(at -2.050034 56.524906 270)
			(size 0.519938 1.4986)
			(layers "F.Cu" "F.Mask" "F.Paste")
			(net "GND")
		)
		(pad "137" smd rect
			(at -2.050034 57.375044 270)
			(size 0.519938 1.4986)
			(layers "F.Cu" "F.Mask" "F.Paste")
			(net "M_D_CPU1_SB_DQS_DP<3>")
		)
		(pad "138" smd rect
			(at -2.050034 58.224928 270)
			(size 0.519938 1.4986)
			(layers "F.Cu" "F.Mask" "F.Paste")
			(net "M_D_CPU1_SB_DQS_DN<3>")
		)
		(pad "139" smd rect
			(at -2.050034 59.075066 270)
			(size 0.519938 1.4986)
			(layers "F.Cu" "F.Mask" "F.Paste")
			(net "GND")
		)
		(pad "140" smd rect
			(at -2.050034 59.92495 270)
			(size 0.519938 1.4986)
			(layers "F.Cu" "F.Mask" "F.Paste")
			(net "M_D_CPU1_SB_DQ<28>")
		)
		(pad "141" smd rect
			(at -2.050034 60.775088 270)
			(size 0.519938 1.4986)
			(layers "F.Cu" "F.Mask" "F.Paste")
			(net "GND")
		)
		(pad "142" smd rect
			(at -2.050034 61.624972 270)
			(size 0.519938 1.4986)
			(layers "F.Cu" "F.Mask" "F.Paste")
			(net "M_D_CPU1_SB_DQ<29>")
		)
		(pad "143" smd rect
			(at -2.050034 62.47511 270)
			(size 0.519938 1.4986)
			(layers "F.Cu" "F.Mask" "F.Paste")
			(net "GND")
		)
		(pad "144" smd rect
			(at -2.050034 63.324994 270)
			(size 0.519938 1.4986)
			(layers "F.Cu" "F.Mask" "F.Paste")
			(net "TP_CHD_CPU1_DIMM1_FRU_1")
		)
		(pad "145" smd rect
			(at 2.050034 -63.324994 270)
			(size 0.519938 1.4986)
			(layers "F.Cu" "F.Mask" "F.Paste")
			(net "P12V_S3_AUX_CPU1_NVDIMM")
		)
		(pad "146" smd rect
			(at 2.050034 -62.47511 270)
			(size 0.519938 1.4986)
			(layers "F.Cu" "F.Mask" "F.Paste")
			(net "P12V_S3_AUX_CPU1_NVDIMM")
		)
		(pad "147" smd rect
			(at 2.050034 -61.624972 270)
			(size 0.519938 1.4986)
			(layers "F.Cu" "F.Mask" "F.Paste")
			(net "PWRGD_CHD_CPU1_DIMM1")
		)
		(pad "148" smd rect
			(at 2.050034 -60.775088 270)
			(size 0.519938 1.4986)
			(layers "F.Cu" "F.Mask" "F.Paste")
			(net "PD_CHD_CPU1_DIMM1_SAA")
		)
		(pad "149" smd rect
			(at 2.050034 -59.92495 270)
			(size 0.519938 1.4986)
			(layers "F.Cu" "F.Mask" "F.Paste")
			(net "TP_CHD_CPU1_DIMM1_FRU_2")
		)
		(pad "150" smd rect
			(at 2.050034 -59.075066 270)
			(size 0.519938 1.4986)
			(layers "F.Cu" "F.Mask" "F.Paste")
			(net "TP_CHD_CPU1_DIMM1_FRU_3")
		)
		(pad "151" smd rect
			(at 2.050034 -58.224928 270)
			(size 0.519938 1.4986)
			(layers "F.Cu" "F.Mask" "F.Paste")
			(net "GND")
		)
		(pad "152" smd rect
			(at 2.050034 -57.375044 270)
			(size 0.519938 1.4986)
			(layers "F.Cu" "F.Mask" "F.Paste")
			(net "M_D_CPU1_SA_DQ<2>")
		)
		(pad "153" smd rect
			(at 2.050034 -56.524906 270)
			(size 0.519938 1.4986)
			(layers "F.Cu" "F.Mask" "F.Paste")
			(net "GND")
		)
		(pad "154" smd rect
			(at 2.050034 -55.675022 270)
			(size 0.519938 1.4986)
			(layers "F.Cu" "F.Mask" "F.Paste")
			(net "M_D_CPU1_SA_DQ<3>")
		)
		(pad "155" smd rect
			(at 2.050034 -54.824884 270)
			(size 0.519938 1.4986)
			(layers "F.Cu" "F.Mask" "F.Paste")
			(net "GND")
		)
		(pad "156" smd rect
			(at 2.050034 -53.975 270)
			(size 0.519938 1.4986)
			(layers "F.Cu" "F.Mask" "F.Paste")
			(net "M_D_CPU1_SA_DQS_DN<5>")
		)
		(pad "157" smd rect
			(at 2.050034 -53.125116 270)
			(size 0.519938 1.4986)
			(layers "F.Cu" "F.Mask" "F.Paste")
			(net "M_D_CPU1_SA_DQS_DP<5>")
		)
		(pad "158" smd rect
			(at 2.050034 -52.274978 270)
			(size 0.519938 1.4986)
			(layers "F.Cu" "F.Mask" "F.Paste")
			(net "GND")
		)
		(pad "159" smd rect
			(at 2.050034 -51.425094 270)
			(size 0.519938 1.4986)
			(layers "F.Cu" "F.Mask" "F.Paste")
			(net "M_D_CPU1_SA_DQ<6>")
		)
		(pad "160" smd rect
			(at 2.050034 -50.574956 270)
			(size 0.519938 1.4986)
			(layers "F.Cu" "F.Mask" "F.Paste")
			(net "GND")
		)
		(pad "161" smd rect
			(at 2.050034 -49.725072 270)
			(size 0.519938 1.4986)
			(layers "F.Cu" "F.Mask" "F.Paste")
			(net "M_D_CPU1_SA_DQ<7>")
		)
		(pad "162" smd rect
			(at 2.050034 -48.874934 270)
			(size 0.519938 1.4986)
			(layers "F.Cu" "F.Mask" "F.Paste")
			(net "GND")
		)
		(pad "163" smd rect
			(at 2.050034 -48.02505 270)
			(size 0.519938 1.4986)
			(layers "F.Cu" "F.Mask" "F.Paste")
			(net "M_D_CPU1_SA_DQ<10>")
		)
		(pad "164" smd rect
			(at 2.050034 -47.174912 270)
			(size 0.519938 1.4986)
			(layers "F.Cu" "F.Mask" "F.Paste")
			(net "GND")
		)
		(pad "165" smd rect
			(at 2.050034 -46.325028 270)
			(size 0.519938 1.4986)
			(layers "F.Cu" "F.Mask" "F.Paste")
			(net "M_D_CPU1_SA_DQ<11>")
		)
		(pad "166" smd rect
			(at 2.050034 -45.47489 270)
			(size 0.519938 1.4986)
			(layers "F.Cu" "F.Mask" "F.Paste")
			(net "GND")
		)
		(pad "167" smd rect
			(at 2.050034 -44.625006 270)
			(size 0.519938 1.4986)
			(layers "F.Cu" "F.Mask" "F.Paste")
			(net "M_D_CPU1_SA_DQS_DN<6>")
		)
		(pad "168" smd rect
			(at 2.050034 -43.775122 270)
			(size 0.519938 1.4986)
			(layers "F.Cu" "F.Mask" "F.Paste")
			(net "M_D_CPU1_SA_DQS_DP<6>")
		)
		(pad "169" smd rect
			(at 2.050034 -42.924984 270)
			(size 0.519938 1.4986)
			(layers "F.Cu" "F.Mask" "F.Paste")
			(net "GND")
		)
		(pad "170" smd rect
			(at 2.050034 -42.0751 270)
			(size 0.519938 1.4986)
			(layers "F.Cu" "F.Mask" "F.Paste")
			(net "M_D_CPU1_SA_DQ<14>")
		)
		(pad "171" smd rect
			(at 2.050034 -41.224962 270)
			(size 0.519938 1.4986)
			(layers "F.Cu" "F.Mask" "F.Paste")
			(net "GND")
		)
		(pad "172" smd rect
			(at 2.050034 -40.375078 270)
			(size 0.519938 1.4986)
			(layers "F.Cu" "F.Mask" "F.Paste")
			(net "M_D_CPU1_SA_DQ<15>")
		)
		(pad "173" smd rect
			(at 2.050034 -39.52494 270)
			(size 0.519938 1.4986)
			(layers "F.Cu" "F.Mask" "F.Paste")
			(net "GND")
		)
		(pad "174" smd rect
			(at 2.050034 -38.675056 270)
			(size 0.519938 1.4986)
			(layers "F.Cu" "F.Mask" "F.Paste")
			(net "M_D_CPU1_SA_DQ<18>")
		)
		(pad "175" smd rect
			(at 2.050034 -37.824918 270)
			(size 0.519938 1.4986)
			(layers "F.Cu" "F.Mask" "F.Paste")
			(net "GND")
		)
		(pad "176" smd rect
			(at 2.050034 -36.975034 270)
			(size 0.519938 1.4986)
			(layers "F.Cu" "F.Mask" "F.Paste")
			(net "M_D_CPU1_SA_DQ<19>")
		)
		(pad "177" smd rect
			(at 2.050034 -36.124896 270)
			(size 0.519938 1.4986)
			(layers "F.Cu" "F.Mask" "F.Paste")
			(net "GND")
		)
		(pad "178" smd rect
			(at 2.050034 -35.275012 270)
			(size 0.519938 1.4986)
			(layers "F.Cu" "F.Mask" "F.Paste")
			(net "M_D_CPU1_SA_DQS_DN<7>")
		)
		(pad "179" smd rect
			(at 2.050034 -34.425128 270)
			(size 0.519938 1.4986)
			(layers "F.Cu" "F.Mask" "F.Paste")
			(net "M_D_CPU1_SA_DQS_DP<7>")
		)
		(pad "180" smd rect
			(at 2.050034 -33.57499 270)
			(size 0.519938 1.4986)
			(layers "F.Cu" "F.Mask" "F.Paste")
			(net "GND")
		)
		(pad "181" smd rect
			(at 2.050034 -32.725106 270)
			(size 0.519938 1.4986)
			(layers "F.Cu" "F.Mask" "F.Paste")
			(net "M_D_CPU1_SA_DQ<22>")
		)
		(pad "182" smd rect
			(at 2.050034 -31.874968 270)
			(size 0.519938 1.4986)
			(layers "F.Cu" "F.Mask" "F.Paste")
			(net "GND")
		)
		(pad "183" smd rect
			(at 2.050034 -31.025084 270)
			(size 0.519938 1.4986)
			(layers "F.Cu" "F.Mask" "F.Paste")
			(net "M_D_CPU1_SA_DQ<23>")
		)
		(pad "184" smd rect
			(at 2.050034 -30.174946 270)
			(size 0.519938 1.4986)
			(layers "F.Cu" "F.Mask" "F.Paste")
			(net "GND")
		)
		(pad "185" smd rect
			(at 2.050034 -29.325062 270)
			(size 0.519938 1.4986)
			(layers "F.Cu" "F.Mask" "F.Paste")
			(net "M_D_CPU1_SA_DQ<26>")
		)
		(pad "186" smd rect
			(at 2.050034 -28.474924 270)
			(size 0.519938 1.4986)
			(layers "F.Cu" "F.Mask" "F.Paste")
			(net "GND")
		)
		(pad "187" smd rect
			(at 2.050034 -27.62504 270)
			(size 0.519938 1.4986)
			(layers "F.Cu" "F.Mask" "F.Paste")
			(net "M_D_CPU1_SA_DQ<27>")
		)
		(pad "188" smd rect
			(at 2.050034 -26.774902 270)
			(size 0.519938 1.4986)
			(layers "F.Cu" "F.Mask" "F.Paste")
			(net "GND")
		)
		(pad "189" smd rect
			(at 2.050034 -25.925018 270)
			(size 0.519938 1.4986)
			(layers "F.Cu" "F.Mask" "F.Paste")
			(net "M_D_CPU1_SA_DQS_DN<8>")
		)
		(pad "190" smd rect
			(at 2.050034 -25.07488 270)
			(size 0.519938 1.4986)
			(layers "F.Cu" "F.Mask" "F.Paste")
			(net "M_D_CPU1_SA_DQS_DP<8>")
		)
		(pad "191" smd rect
			(at 2.050034 -24.224996 270)
			(size 0.519938 1.4986)
			(layers "F.Cu" "F.Mask" "F.Paste")
			(net "GND")
		)
		(pad "192" smd rect
			(at 2.050034 -23.375112 270)
			(size 0.519938 1.4986)
			(layers "F.Cu" "F.Mask" "F.Paste")
			(net "M_D_CPU1_SA_DQ<30>")
		)
		(pad "193" smd rect
			(at 2.050034 -22.524974 270)
			(size 0.519938 1.4986)
			(layers "F.Cu" "F.Mask" "F.Paste")
			(net "GND")
		)
		(pad "194" smd rect
			(at 2.050034 -21.67509 270)
			(size 0.519938 1.4986)
			(layers "F.Cu" "F.Mask" "F.Paste")
			(net "M_D_CPU1_SA_DQ<31>")
		)
		(pad "195" smd rect
			(at 2.050034 -20.824952 270)
			(size 0.519938 1.4986)
			(layers "F.Cu" "F.Mask" "F.Paste")
			(net "GND")
		)
		(pad "196" smd rect
			(at 2.050034 -19.975068 270)
			(size 0.519938 1.4986)
			(layers "F.Cu" "F.Mask" "F.Paste")
			(net "M_D_CPU1_SA_CB<2>")
		)
		(pad "197" smd rect
			(at 2.050034 -19.12493 270)
			(size 0.519938 1.4986)
			(layers "F.Cu" "F.Mask" "F.Paste")
			(net "GND")
		)
		(pad "198" smd rect
			(at 2.050034 -18.275046 270)
			(size 0.519938 1.4986)
			(layers "F.Cu" "F.Mask" "F.Paste")
			(net "M_D_CPU1_SA_CB<3>")
		)
		(pad "199" smd rect
			(at 2.050034 -17.424908 270)
			(size 0.519938 1.4986)
			(layers "F.Cu" "F.Mask" "F.Paste")
			(net "GND")
		)
		(pad "200" smd rect
			(at 2.050034 -16.575024 270)
			(size 0.519938 1.4986)
			(layers "F.Cu" "F.Mask" "F.Paste")
			(net "M_D_CPU1_SA_DQS_DN<9>")
		)
		(pad "201" smd rect
			(at 2.050034 -15.724886 270)
			(size 0.519938 1.4986)
			(layers "F.Cu" "F.Mask" "F.Paste")
			(net "M_D_CPU1_SA_DQS_DP<9>")
		)
		(pad "202" smd rect
			(at 2.050034 -14.875002 270)
			(size 0.519938 1.4986)
			(layers "F.Cu" "F.Mask" "F.Paste")
			(net "GND")
		)
		(pad "203" smd rect
			(at 2.050034 -14.025118 270)
			(size 0.519938 1.4986)
			(layers "F.Cu" "F.Mask" "F.Paste")
			(net "M_D_CPU1_SA_CB<6>")
		)
		(pad "204" smd rect
			(at 2.050034 -13.17498 270)
			(size 0.519938 1.4986)
			(layers "F.Cu" "F.Mask" "F.Paste")
			(net "GND")
		)
		(pad "205" smd rect
			(at 2.050034 -12.325096 270)
			(size 0.519938 1.4986)
			(layers "F.Cu" "F.Mask" "F.Paste")
			(net "M_D_CPU1_SA_CB<7>")
		)
		(pad "206" smd rect
			(at 2.050034 -11.474958 270)
			(size 0.519938 1.4986)
			(layers "F.Cu" "F.Mask" "F.Paste")
			(net "GND")
		)
		(pad "207" smd rect
			(at 2.050034 -10.625074 270)
			(size 0.519938 1.4986)
			(layers "F.Cu" "F.Mask" "F.Paste")
			(net "RST_M_CD_CPU1_FPGA_N")
		)
		(pad "208" smd rect
			(at 2.050034 -9.774936 270)
			(size 0.519938 1.4986)
			(layers "F.Cu" "F.Mask" "F.Paste")
			(net "GND")
		)
		(pad "209" smd rect
			(at 2.050034 -8.925052 270)
			(size 0.519938 1.4986)
			(layers "F.Cu" "F.Mask" "F.Paste")
			(net "M_D_CPU1_SA_CS_N<1>")
		)
		(pad "210" smd rect
			(at 2.050034 -8.074914 270)
			(size 0.519938 1.4986)
			(layers "F.Cu" "F.Mask" "F.Paste")
			(net "GND")
		)
		(pad "211" smd rect
			(at 2.050034 -7.22503 270)
			(size 0.519938 1.4986)
			(layers "F.Cu" "F.Mask" "F.Paste")
			(net "M_D_CPU1_SA_CA<1>")
		)
		(pad "212" smd rect
			(at 2.050034 -6.374892 270)
			(size 0.519938 1.4986)
			(layers "F.Cu" "F.Mask" "F.Paste")
			(net "GND")
		)
		(pad "213" smd rect
			(at 2.050034 -5.525008 270)
			(size 0.519938 1.4986)
			(layers "F.Cu" "F.Mask" "F.Paste")
			(net "M_D_CPU1_SA_CA<3>")
		)
		(pad "214" smd rect
			(at 2.050034 -4.675124 270)
			(size 0.519938 1.4986)
			(layers "F.Cu" "F.Mask" "F.Paste")
			(net "GND")
		)
		(pad "215" smd rect
			(at 2.050034 -3.824986 270)
			(size 0.519938 1.4986)
			(layers "F.Cu" "F.Mask" "F.Paste")
			(net "M_D_CPU1_SA_CA<5>")
		)
		(pad "216" smd rect
			(at 2.050034 -2.975102 270)
			(size 0.519938 1.4986)
			(layers "F.Cu" "F.Mask" "F.Paste")
			(net "GND")
		)
		(pad "217" smd rect
			(at 2.050034 -2.124964 270)
			(size 0.519938 1.4986)
			(layers "F.Cu" "F.Mask" "F.Paste")
			(net "M_D_CPU1_CLK_DP<0>")
		)
		(pad "218" smd rect
			(at 2.050034 -1.27508 270)
			(size 0.519938 1.4986)
			(layers "F.Cu" "F.Mask" "F.Paste")
			(net "M_D_CPU1_CLK_DN<0>")
		)
		(pad "219" smd rect
			(at 2.050034 -0.424942 270)
			(size 0.519938 1.4986)
			(layers "F.Cu" "F.Mask" "F.Paste")
			(net "GND")
		)
		(pad "220" smd rect
			(at 2.050034 5.525008 270)
			(size 0.519938 1.4986)
			(layers "F.Cu" "F.Mask" "F.Paste")
			(net "TP_CHD_CPU1_DIMM1_FRU_4")
		)
		(pad "221" smd rect
			(at 2.050034 6.374892 270)
			(size 0.519938 1.4986)
			(layers "F.Cu" "F.Mask" "F.Paste")
			(net "M_D_CPU1_SB_CA<1>")
		)
		(pad "222" smd rect
			(at 2.050034 7.22503 270)
			(size 0.519938 1.4986)
			(layers "F.Cu" "F.Mask" "F.Paste")
			(net "GND")
		)
		(pad "223" smd rect
			(at 2.050034 8.074914 270)
			(size 0.519938 1.4986)
			(layers "F.Cu" "F.Mask" "F.Paste")
			(net "M_D_CPU1_SB_CA<3>")
		)
		(pad "224" smd rect
			(at 2.050034 8.925052 270)
			(size 0.519938 1.4986)
			(layers "F.Cu" "F.Mask" "F.Paste")
			(net "GND")
		)
		(pad "225" smd rect
			(at 2.050034 9.774936 270)
			(size 0.519938 1.4986)
			(layers "F.Cu" "F.Mask" "F.Paste")
			(net "M_D_CPU1_SB_CA<5>")
		)
		(pad "226" smd rect
			(at 2.050034 10.625074 270)
			(size 0.519938 1.4986)
			(layers "F.Cu" "F.Mask" "F.Paste")
			(net "GND")
		)
		(pad "227" smd rect
			(at 2.050034 11.474958 270)
			(size 0.519938 1.4986)
			(layers "F.Cu" "F.Mask" "F.Paste")
			(net "M_D_CPU1_SB_PAR")
		)
		(pad "228" smd rect
			(at 2.050034 12.325096 270)
			(size 0.519938 1.4986)
			(layers "F.Cu" "F.Mask" "F.Paste")
			(net "GND")
		)
		(pad "229" smd rect
			(at 2.050034 13.17498 270)
			(size 0.519938 1.4986)
			(layers "F.Cu" "F.Mask" "F.Paste")
			(net "M_D_CPU1_SB_CS_N<1>")
		)
		(pad "230" smd rect
			(at 2.050034 14.025118 270)
			(size 0.519938 1.4986)
			(layers "F.Cu" "F.Mask" "F.Paste")
			(net "GND")
		)
		(pad "231" smd rect
			(at 2.050034 14.875002 270)
			(size 0.519938 1.4986)
			(layers "F.Cu" "F.Mask" "F.Paste")
			(net "TP_CHD_CPU1_DIMM1_FRU_5")
		)
		(pad "232" smd rect
			(at 2.050034 15.724886 270)
			(size 0.519938 1.4986)
			(layers "F.Cu" "F.Mask" "F.Paste")
			(net "TP_CHD_CPU1_DIMM1_FRU_6")
		)
		(pad "233" smd rect
			(at 2.050034 16.575024 270)
			(size 0.519938 1.4986)
			(layers "F.Cu" "F.Mask" "F.Paste")
			(net "GND")
		)
		(pad "234" smd rect
			(at 2.050034 17.424908 270)
			(size 0.519938 1.4986)
			(layers "F.Cu" "F.Mask" "F.Paste")
			(net "M_D_CPU1_SB_CB<6>")
		)
		(pad "235" smd rect
			(at 2.050034 18.275046 270)
			(size 0.519938 1.4986)
			(layers "F.Cu" "F.Mask" "F.Paste")
			(net "GND")
		)
		(pad "236" smd rect
			(at 2.050034 19.12493 270)
			(size 0.519938 1.4986)
			(layers "F.Cu" "F.Mask" "F.Paste")
			(net "M_D_CPU1_SB_CB<7>")
		)
		(pad "237" smd rect
			(at 2.050034 19.975068 270)
			(size 0.519938 1.4986)
			(layers "F.Cu" "F.Mask" "F.Paste")
			(net "GND")
		)
		(pad "238" smd rect
			(at 2.050034 20.824952 270)
			(size 0.519938 1.4986)
			(layers "F.Cu" "F.Mask" "F.Paste")
			(net "M_D_CPU1_SB_DQS_DN<4>")
		)
		(pad "239" smd rect
			(at 2.050034 21.67509 270)
			(size 0.519938 1.4986)
			(layers "F.Cu" "F.Mask" "F.Paste")
			(net "M_D_CPU1_SB_DQS_DP<4>")
		)
		(pad "240" smd rect
			(at 2.050034 22.524974 270)
			(size 0.519938 1.4986)
			(layers "F.Cu" "F.Mask" "F.Paste")
			(net "GND")
		)
		(pad "241" smd rect
			(at 2.050034 23.375112 270)
			(size 0.519938 1.4986)
			(layers "F.Cu" "F.Mask" "F.Paste")
			(net "M_D_CPU1_SB_CB<2>")
		)
		(pad "242" smd rect
			(at 2.050034 24.224996 270)
			(size 0.519938 1.4986)
			(layers "F.Cu" "F.Mask" "F.Paste")
			(net "GND")
		)
		(pad "243" smd rect
			(at 2.050034 25.07488 270)
			(size 0.519938 1.4986)
			(layers "F.Cu" "F.Mask" "F.Paste")
			(net "M_D_CPU1_SB_CB<3>")
		)
		(pad "244" smd rect
			(at 2.050034 25.925018 270)
			(size 0.519938 1.4986)
			(layers "F.Cu" "F.Mask" "F.Paste")
			(net "GND")
		)
		(pad "245" smd rect
			(at 2.050034 26.774902 270)
			(size 0.519938 1.4986)
			(layers "F.Cu" "F.Mask" "F.Paste")
			(net "M_D_CPU1_SB_DQ<2>")
		)
		(pad "246" smd rect
			(at 2.050034 27.62504 270)
			(size 0.519938 1.4986)
			(layers "F.Cu" "F.Mask" "F.Paste")
			(net "GND")
		)
		(pad "247" smd rect
			(at 2.050034 28.474924 270)
			(size 0.519938 1.4986)
			(layers "F.Cu" "F.Mask" "F.Paste")
			(net "M_D_CPU1_SB_DQ<3>")
		)
		(pad "248" smd rect
			(at 2.050034 29.325062 270)
			(size 0.519938 1.4986)
			(layers "F.Cu" "F.Mask" "F.Paste")
			(net "GND")
		)
		(pad "249" smd rect
			(at 2.050034 30.174946 270)
			(size 0.519938 1.4986)
			(layers "F.Cu" "F.Mask" "F.Paste")
			(net "M_D_CPU1_SB_DQS_DN<5>")
		)
		(pad "250" smd rect
			(at 2.050034 31.025084 270)
			(size 0.519938 1.4986)
			(layers "F.Cu" "F.Mask" "F.Paste")
			(net "M_D_CPU1_SB_DQS_DP<5>")
		)
		(pad "251" smd rect
			(at 2.050034 31.874968 270)
			(size 0.519938 1.4986)
			(layers "F.Cu" "F.Mask" "F.Paste")
			(net "GND")
		)
		(pad "252" smd rect
			(at 2.050034 32.725106 270)
			(size 0.519938 1.4986)
			(layers "F.Cu" "F.Mask" "F.Paste")
			(net "M_D_CPU1_SB_DQ<6>")
		)
		(pad "253" smd rect
			(at 2.050034 33.57499 270)
			(size 0.519938 1.4986)
			(layers "F.Cu" "F.Mask" "F.Paste")
			(net "GND")
		)
		(pad "254" smd rect
			(at 2.050034 34.425128 270)
			(size 0.519938 1.4986)
			(layers "F.Cu" "F.Mask" "F.Paste")
			(net "M_D_CPU1_SB_DQ<7>")
		)
		(pad "255" smd rect
			(at 2.050034 35.275012 270)
			(size 0.519938 1.4986)
			(layers "F.Cu" "F.Mask" "F.Paste")
			(net "GND")
		)
		(pad "256" smd rect
			(at 2.050034 36.124896 270)
			(size 0.519938 1.4986)
			(layers "F.Cu" "F.Mask" "F.Paste")
			(net "M_D_CPU1_SB_DQ<10>")
		)
		(pad "257" smd rect
			(at 2.050034 36.975034 270)
			(size 0.519938 1.4986)
			(layers "F.Cu" "F.Mask" "F.Paste")
			(net "GND")
		)
		(pad "258" smd rect
			(at 2.050034 37.824918 270)
			(size 0.519938 1.4986)
			(layers "F.Cu" "F.Mask" "F.Paste")
			(net "M_D_CPU1_SB_DQ<11>")
		)
		(pad "259" smd rect
			(at 2.050034 38.675056 270)
			(size 0.519938 1.4986)
			(layers "F.Cu" "F.Mask" "F.Paste")
			(net "GND")
		)
		(pad "260" smd rect
			(at 2.050034 39.52494 270)
			(size 0.519938 1.4986)
			(layers "F.Cu" "F.Mask" "F.Paste")
			(net "M_D_CPU1_SB_DQS_DN<6>")
		)
		(pad "261" smd rect
			(at 2.050034 40.375078 270)
			(size 0.519938 1.4986)
			(layers "F.Cu" "F.Mask" "F.Paste")
			(net "M_D_CPU1_SB_DQS_DP<6>")
		)
		(pad "262" smd rect
			(at 2.050034 41.224962 270)
			(size 0.519938 1.4986)
			(layers "F.Cu" "F.Mask" "F.Paste")
			(net "GND")
		)
		(pad "263" smd rect
			(at 2.050034 42.0751 270)
			(size 0.519938 1.4986)
			(layers "F.Cu" "F.Mask" "F.Paste")
			(net "M_D_CPU1_SB_DQ<14>")
		)
		(pad "264" smd rect
			(at 2.050034 42.924984 270)
			(size 0.519938 1.4986)
			(layers "F.Cu" "F.Mask" "F.Paste")
			(net "GND")
		)
		(pad "265" smd rect
			(at 2.050034 43.775122 270)
			(size 0.519938 1.4986)
			(layers "F.Cu" "F.Mask" "F.Paste")
			(net "M_D_CPU1_SB_DQ<15>")
		)
		(pad "266" smd rect
			(at 2.050034 44.625006 270)
			(size 0.519938 1.4986)
			(layers "F.Cu" "F.Mask" "F.Paste")
			(net "GND")
		)
		(pad "267" smd rect
			(at 2.050034 45.47489 270)
			(size 0.519938 1.4986)
			(layers "F.Cu" "F.Mask" "F.Paste")
			(net "M_D_CPU1_SB_DQ<18>")
		)
		(pad "268" smd rect
			(at 2.050034 46.325028 270)
			(size 0.519938 1.4986)
			(layers "F.Cu" "F.Mask" "F.Paste")
			(net "GND")
		)
		(pad "269" smd rect
			(at 2.050034 47.174912 270)
			(size 0.519938 1.4986)
			(layers "F.Cu" "F.Mask" "F.Paste")
			(net "M_D_CPU1_SB_DQ<19>")
		)
		(pad "270" smd rect
			(at 2.050034 48.02505 270)
			(size 0.519938 1.4986)
			(layers "F.Cu" "F.Mask" "F.Paste")
			(net "GND")
		)
		(pad "271" smd rect
			(at 2.050034 48.874934 270)
			(size 0.519938 1.4986)
			(layers "F.Cu" "F.Mask" "F.Paste")
			(net "M_D_CPU1_SB_DQS_DN<7>")
		)
		(pad "272" smd rect
			(at 2.050034 49.725072 270)
			(size 0.519938 1.4986)
			(layers "F.Cu" "F.Mask" "F.Paste")
			(net "M_D_CPU1_SB_DQS_DP<7>")
		)
		(pad "273" smd rect
			(at 2.050034 50.574956 270)
			(size 0.519938 1.4986)
			(layers "F.Cu" "F.Mask" "F.Paste")
			(net "GND")
		)
		(pad "274" smd rect
			(at 2.050034 51.425094 270)
			(size 0.519938 1.4986)
			(layers "F.Cu" "F.Mask" "F.Paste")
			(net "M_D_CPU1_SB_DQ<22>")
		)
		(pad "275" smd rect
			(at 2.050034 52.274978 270)
			(size 0.519938 1.4986)
			(layers "F.Cu" "F.Mask" "F.Paste")
			(net "GND")
		)
		(pad "276" smd rect
			(at 2.050034 53.125116 270)
			(size 0.519938 1.4986)
			(layers "F.Cu" "F.Mask" "F.Paste")
			(net "M_D_CPU1_SB_DQ<23>")
		)
		(pad "277" smd rect
			(at 2.050034 53.975 270)
			(size 0.519938 1.4986)
			(layers "F.Cu" "F.Mask" "F.Paste")
			(net "GND")
		)
		(pad "278" smd rect
			(at 2.050034 54.824884 270)
			(size 0.519938 1.4986)
			(layers "F.Cu" "F.Mask" "F.Paste")
			(net "M_D_CPU1_SB_DQ<26>")
		)
		(pad "279" smd rect
			(at 2.050034 55.675022 270)
			(size 0.519938 1.4986)
			(layers "F.Cu" "F.Mask" "F.Paste")
			(net "GND")
		)
		(pad "280" smd rect
			(at 2.050034 56.524906 270)
			(size 0.519938 1.4986)
			(layers "F.Cu" "F.Mask" "F.Paste")
			(net "M_D_CPU1_SB_DQ<27>")
		)
		(pad "281" smd rect
			(at 2.050034 57.375044 270)
			(size 0.519938 1.4986)
			(layers "F.Cu" "F.Mask" "F.Paste")
			(net "GND")
		)
		(pad "282" smd rect
			(at 2.050034 58.224928 270)
			(size 0.519938 1.4986)
			(layers "F.Cu" "F.Mask" "F.Paste")
			(net "M_D_CPU1_SB_DQS_DN<8>")
		)
		(pad "283" smd rect
			(at 2.050034 59.075066 270)
			(size 0.519938 1.4986)
			(layers "F.Cu" "F.Mask" "F.Paste")
			(net "M_D_CPU1_SB_DQS_DP<8>")
		)
		(pad "284" smd rect
			(at 2.050034 59.92495 270)
			(size 0.519938 1.4986)
			(layers "F.Cu" "F.Mask" "F.Paste")
			(net "GND")
		)
		(pad "285" smd rect
			(at 2.050034 60.775088 270)
			(size 0.519938 1.4986)
			(layers "F.Cu" "F.Mask" "F.Paste")
			(net "M_D_CPU1_SB_DQ<30>")
		)
		(pad "286" smd rect
			(at 2.050034 61.624972 270)
			(size 0.519938 1.4986)
			(layers "F.Cu" "F.Mask" "F.Paste")
			(net "GND")
		)
		(pad "287" smd rect
			(at 2.050034 62.47511 270)
			(size 0.519938 1.4986)
			(layers "F.Cu" "F.Mask" "F.Paste")
			(net "M_D_CPU1_SB_DQ<31>")
		)
		(pad "288" smd rect
			(at 2.050034 63.324994 270)
			(size 0.519938 1.4986)
			(layers "F.Cu" "F.Mask" "F.Paste")
			(net "GND")
		)
		(pad "G1" thru_hole oval
			(at 0 -68.97497)
			(size 2.8194 1.5748)
			(drill oval 2.4384 1.1938)
			(layers "*.Cu" "*.Mask")
			(remove_unused_layers no)
			(net "GND")
			(clearance 0.127)
			(thermal_gap 0.127)
		)
		(pad "G2" thru_hole oval
			(at 0 3.875024)
			(size 2.8194 1.5748)
			(drill oval 2.4384 1.1938)
			(layers "*.Cu" "*.Mask")
			(remove_unused_layers no)
			(net "GND")
			(clearance 0.127)
			(thermal_gap 0.127)
		)
		(pad "G3" thru_hole oval
			(at 0 68.97497)
			(size 2.8194 1.5748)
			(drill oval 2.4384 1.1938)
			(layers "*.Cu" "*.Mask")
			(remove_unused_layers no)
			(net "GND")
			(clearance 0.127)
			(thermal_gap 0.127)
		)
	)
	(footprint ""
		(layer "F.Cu")
		(at 44.668694 -16.099536 90)
		(property "Reference" "C826"
			(at 0 0 90)
			(layer "F.SilkS")
			(hide yes)
			(effects
				(font
					(size 1.27 1.27)
				)
			)
		)
		(property "Value" ""
			(at 0 0 90)
			(layer "F.Fab")
			(effects
				(font
					(size 1.27 1.27)
				)
			)
		)
		(duplicate_pad_numbers_are_jumpers no)
		(fp_line
			(start 0.299974 -0.150114)
			(end 0.299974 0.150114)
			(stroke
				(width 0.1)
				(type default)
			)
			(layer "F.Fab")
		)
		(fp_line
			(start -0.299974 -0.150114)
			(end 0.299974 -0.150114)
			(stroke
				(width 0.1)
				(type default)
			)
			(layer "F.Fab")
		)
		(fp_line
			(start 0.299974 0.150114)
			(end -0.299974 0.150114)
			(stroke
				(width 0.1)
				(type default)
			)
			(layer "F.Fab")
		)
		(fp_line
			(start -0.299974 0.150114)
			(end -0.299974 -0.150114)
			(stroke
				(width 0.1)
				(type default)
			)
			(layer "F.Fab")
		)
		(pad "1" smd rect
			(at -0.2667 0 90)
			(size 0.3048 0.381)
			(layers "F.Cu" "F.Mask" "F.Paste")
			(net "P5E_CPU1_PE1_TX_C_DN<5>")
		)
		(pad "2" smd rect
			(at 0.2667 0 90)
			(size 0.3048 0.381)
			(layers "F.Cu" "F.Mask" "F.Paste")
			(net "P5E_CPU1_PE1_TX_DN<5>")
		)
	)
	(footprint ""
		(layer "F.Cu")
		(at 457.687426 -103.646224)
		(property "Reference" "U212"
			(at -1.490726 -1.641094 0)
			(unlocked yes)
			(layer "F.SilkS")
			(effects
				(font
					(size 0.7874 0.5842)
					(thickness 0.1524)
				)
				(justify left)
			)
		)
		(property "Value" ""
			(at 0 0 0)
			(layer "F.Fab")
			(effects
				(font
					(size 1.27 1.27)
				)
			)
		)
		(duplicate_pad_numbers_are_jumpers no)
		(fp_line
			(start -1.38176 -1.100074)
			(end -1.38176 1.100074)
			(stroke
				(width 0.1524)
				(type default)
			)
			(layer "F.SilkS")
		)
		(fp_line
			(start -1.38176 1.100074)
			(end 1.38176 1.100074)
			(stroke
				(width 0.1524)
				(type default)
			)
			(layer "F.SilkS")
		)
		(fp_line
			(start -0.592074 -1.100074)
			(end -1.38176 -1.100074)
			(stroke
				(width 0.1524)
				(type default)
			)
			(layer "F.SilkS")
		)
		(fp_line
			(start 0 -0.508)
			(end -0.592074 -1.100074)
			(stroke
				(width 0.1524)
				(type default)
			)
			(layer "F.SilkS")
		)
		(fp_line
			(start 0.592074 -1.100074)
			(end 0 -0.508)
			(stroke
				(width 0.1524)
				(type default)
			)
			(layer "F.SilkS")
		)
		(fp_line
			(start 1.38176 -1.100074)
			(end 0.592074 -1.100074)
			(stroke
				(width 0.1524)
				(type default)
			)
			(layer "F.SilkS")
		)
		(fp_line
			(start 1.38176 1.100074)
			(end 1.38176 -1.100074)
			(stroke
				(width 0.1524)
				(type default)
			)
			(layer "F.SilkS")
		)
		(fp_poly
			(pts
				(xy -1.50241 -0.649986) (xy -1.9431 -0.429768) (xy -1.9431 -0.870204)
			)
			(stroke
				(width 0)
				(type default)
			)
			(fill yes)
			(layer "F.SilkS")
		)
		(fp_line
			(start -0.674878 -1.100074)
			(end -0.674878 1.100074)
			(stroke
				(width 0.1)
				(type default)
			)
			(layer "F.Fab")
		)
		(fp_line
			(start -0.674878 1.100074)
			(end 0.674878 1.100074)
			(stroke
				(width 0.1)
				(type default)
			)
			(layer "F.Fab")
		)
		(fp_line
			(start 0.674878 -1.100074)
			(end -0.674878 -1.100074)
			(stroke
				(width 0.1)
				(type default)
			)
			(layer "F.Fab")
		)
		(fp_line
			(start 0.674878 1.100074)
			(end 0.674878 -1.100074)
			(stroke
				(width 0.1)
				(type default)
			)
			(layer "F.Fab")
		)
		(fp_poly
			(pts
				(xy -1.9431 -0.870204) (xy -1.50241 -0.649986) (xy -1.9431 -0.429768)
			)
			(stroke
				(width 0)
				(type default)
			)
			(fill yes)
			(layer "F.Fab")
		)
		(pad "1" smd rect
			(at -0.94996 -0.649986 270)
			(size 0.4318 0.6096)
			(layers "F.Cu" "F.Mask" "F.Paste")
			(net "OCP_SFF_PRSNT2_R_N")
		)
		(pad "2" smd rect
			(at -0.94996 0 270)
			(size 0.4318 0.6096)
			(layers "F.Cu" "F.Mask" "F.Paste")
			(net "GND")
		)
		(pad "3" smd rect
			(at -0.94996 0.649986 270)
			(size 0.4318 0.6096)
			(layers "F.Cu" "F.Mask" "F.Paste")
			(net "OCP_SFF_PRSNT3_R_N")
		)
		(pad "4" smd rect
			(at 0.94996 0.649986 270)
			(size 0.4318 0.6096)
			(layers "F.Cu" "F.Mask" "F.Paste")
			(net "HP_LVC3_OCP_V3_1_PRSNT2_N_R")
		)
		(pad "5" smd rect
			(at 0.94996 0 270)
			(size 0.4318 0.6096)
			(layers "F.Cu" "F.Mask" "F.Paste")
			(net "P3V3_AUX")
		)
		(pad "6" smd rect
			(at 0.94996 -0.649986 270)
			(size 0.4318 0.6096)
			(layers "F.Cu" "F.Mask" "F.Paste")
			(net "HP_LVC3_OCP_V3_1_PRSNT2_N_R")
		)
	)
	(footprint ""
		(layer "F.Cu")
		(at 24.67356 -76.266548)
		(property "Reference" "U58"
			(at -1.1938 -2.02057 0)
			(unlocked yes)
			(layer "F.SilkS")
			(effects
				(font
					(size 0.7874 0.5842)
					(thickness 0.1524)
				)
				(justify left)
			)
		)
		(property "Value" ""
			(at 0 0 0)
			(layer "F.Fab")
			(effects
				(font
					(size 1.27 1.27)
				)
			)
		)
		(duplicate_pad_numbers_are_jumpers no)
		(fp_line
			(start -1.38176 -1.100074)
			(end -1.38176 1.100074)
			(stroke
				(width 0.1524)
				(type default)
			)
			(layer "F.SilkS")
		)
		(fp_line
			(start -1.38176 1.100074)
			(end 1.38176 1.100074)
			(stroke
				(width 0.1524)
				(type default)
			)
			(layer "F.SilkS")
		)
		(fp_line
			(start -0.592074 -1.100074)
			(end -1.38176 -1.100074)
			(stroke
				(width 0.1524)
				(type default)
			)
			(layer "F.SilkS")
		)
		(fp_line
			(start 0 -0.508)
			(end -0.592074 -1.100074)
			(stroke
				(width 0.1524)
				(type default)
			)
			(layer "F.SilkS")
		)
		(fp_line
			(start 0.592074 -1.100074)
			(end 0 -0.508)
			(stroke
				(width 0.1524)
				(type default)
			)
			(layer "F.SilkS")
		)
		(fp_line
			(start 1.38176 -1.100074)
			(end 0.592074 -1.100074)
			(stroke
				(width 0.1524)
				(type default)
			)
			(layer "F.SilkS")
		)
		(fp_line
			(start 1.38176 1.100074)
			(end 1.38176 -1.100074)
			(stroke
				(width 0.1524)
				(type default)
			)
			(layer "F.SilkS")
		)
		(fp_poly
			(pts
				(xy -1.50241 -0.649986) (xy -1.9431 -0.429768) (xy -1.9431 -0.870204)
			)
			(stroke
				(width 0)
				(type default)
			)
			(fill yes)
			(layer "F.SilkS")
		)
		(fp_line
			(start -0.674878 -1.100074)
			(end -0.674878 1.100074)
			(stroke
				(width 0.1)
				(type default)
			)
			(layer "F.Fab")
		)
		(fp_line
			(start -0.674878 1.100074)
			(end 0.674878 1.100074)
			(stroke
				(width 0.1)
				(type default)
			)
			(layer "F.Fab")
		)
		(fp_line
			(start 0.674878 -1.100074)
			(end -0.674878 -1.100074)
			(stroke
				(width 0.1)
				(type default)
			)
			(layer "F.Fab")
		)
		(fp_line
			(start 0.674878 1.100074)
			(end 0.674878 -1.100074)
			(stroke
				(width 0.1)
				(type default)
			)
			(layer "F.Fab")
		)
		(fp_poly
			(pts
				(xy -1.9431 -0.870204) (xy -1.50241 -0.649986) (xy -1.9431 -0.429768)
			)
			(stroke
				(width 0)
				(type default)
			)
			(fill yes)
			(layer "F.Fab")
		)
		(pad "1" smd rect
			(at -0.94996 -0.649986 270)
			(size 0.4318 0.6096)
			(layers "F.Cu" "F.Mask" "F.Paste")
			(net "OCP_V3_2_PRSNT0_R_N")
		)
		(pad "2" smd rect
			(at -0.94996 0 270)
			(size 0.4318 0.6096)
			(layers "F.Cu" "F.Mask" "F.Paste")
			(net "GND")
		)
		(pad "3" smd rect
			(at -0.94996 0.649986 270)
			(size 0.4318 0.6096)
			(layers "F.Cu" "F.Mask" "F.Paste")
			(net "OCP_V3_2_PRSNT1_R_N")
		)
		(pad "4" smd rect
			(at 0.94996 0.649986 270)
			(size 0.4318 0.6096)
			(layers "F.Cu" "F.Mask" "F.Paste")
			(net "HP_LVC3_OCP_V3_2_PRSNT2_N_R")
		)
		(pad "5" smd rect
			(at 0.94996 0 270)
			(size 0.4318 0.6096)
			(layers "F.Cu" "F.Mask" "F.Paste")
			(net "P3V3_AUX")
		)
		(pad "6" smd rect
			(at 0.94996 -0.649986 270)
			(size 0.4318 0.6096)
			(layers "F.Cu" "F.Mask" "F.Paste")
			(net "HP_LVC3_OCP_V3_2_PRSNT2_N_R")
		)
	)
	(footprint ""
		(layer "F.Cu")
		(at 20.190714 -110.875826 180)
		(property "Reference" "C2051"
			(at 0 0 180)
			(layer "F.SilkS")
			(hide yes)
			(effects
				(font
					(size 1.27 1.27)
				)
			)
		)
		(property "Value" ""
			(at 0 0 180)
			(layer "F.Fab")
			(effects
				(font
					(size 1.27 1.27)
				)
			)
		)
		(duplicate_pad_numbers_are_jumpers no)
		(fp_line
			(start 0.7874 0.4064)
			(end -0.7874 0.4064)
			(stroke
				(width 0.1524)
				(type default)
			)
			(layer "F.SilkS")
		)
		(fp_line
			(start 0.7874 -0.4064)
			(end 0.7874 0.4064)
			(stroke
				(width 0.1524)
				(type default)
			)
			(layer "F.SilkS")
		)
		(fp_line
			(start -0.7874 0.4064)
			(end -0.7874 -0.4064)
			(stroke
				(width 0.1524)
				(type default)
			)
			(layer "F.SilkS")
		)
		(fp_line
			(start -0.7874 -0.4064)
			(end 0.7874 -0.4064)
			(stroke
				(width 0.1524)
				(type default)
			)
			(layer "F.SilkS")
		)
		(fp_line
			(start 0.67945 0.3048)
			(end 0.120396 0.3048)
			(stroke
				(width 0.1)
				(type default)
			)
			(layer "F.Fab")
		)
		(fp_line
			(start 0.67945 -0.3048)
			(end 0.67945 0.3048)
			(stroke
				(width 0.1)
				(type default)
			)
			(layer "F.Fab")
		)
		(fp_line
			(start 0.12065 -0.2794)
			(end 0.12065 -0.3048)
			(stroke
				(width 0.1)
				(type default)
			)
			(layer "F.Fab")
		)
		(fp_line
			(start 0.12065 -0.3048)
			(end 0.67945 -0.3048)
			(stroke
				(width 0.1)
				(type default)
			)
			(layer "F.Fab")
		)
		(fp_line
			(start 0.120396 0.3048)
			(end 0.120396 0.2794)
			(stroke
				(width 0.1)
				(type default)
			)
			(layer "F.Fab")
		)
		(fp_line
			(start 0.120396 0.2794)
			(end -0.12065 0.2794)
			(stroke
				(width 0.1)
				(type default)
			)
			(layer "F.Fab")
		)
		(fp_line
			(start -0.12065 0.3048)
			(end -0.67945 0.3048)
			(stroke
				(width 0.1)
				(type default)
			)
			(layer "F.Fab")
		)
		(fp_line
			(start -0.12065 0.2794)
			(end -0.12065 0.3048)
			(stroke
				(width 0.1)
				(type default)
			)
			(layer "F.Fab")
		)
		(fp_line
			(start -0.12065 -0.2794)
			(end 0.12065 -0.2794)
			(stroke
				(width 0.1)
				(type default)
			)
			(layer "F.Fab")
		)
		(fp_line
			(start -0.12065 -0.305054)
			(end -0.12065 -0.2794)
			(stroke
				(width 0.1)
				(type default)
			)
			(layer "F.Fab")
		)
		(fp_line
			(start -0.67945 0.3048)
			(end -0.67945 -0.305054)
			(stroke
				(width 0.1)
				(type default)
			)
			(layer "F.Fab")
		)
		(fp_line
			(start -0.67945 -0.305054)
			(end -0.12065 -0.305054)
			(stroke
				(width 0.1)
				(type default)
			)
			(layer "F.Fab")
		)
		(pad "1" smd circle
			(at -0.40005 0 180)
			(size 0 0)
			(layers "F.Cu" "F.Mask" "F.Paste")
			(net "P3V3_ADC128_VCC")
		)
		(pad "2" smd circle
			(at 0.40005 0 180)
			(size 0 0)
			(layers "F.Cu" "F.Mask" "F.Paste")
			(net "GND")
		)
	)
	(footprint ""
		(layer "F.Cu")
		(at 53.278278 -408.517344 -90)
		(property "Reference" "C706"
			(at 0 0 270)
			(layer "F.SilkS")
			(hide yes)
			(effects
				(font
					(size 1.27 1.27)
				)
			)
		)
		(property "Value" ""
			(at 0 0 270)
			(layer "F.Fab")
			(effects
				(font
					(size 1.27 1.27)
				)
			)
		)
		(duplicate_pad_numbers_are_jumpers no)
		(fp_line
			(start -0.299974 0.150114)
			(end -0.299974 -0.150114)
			(stroke
				(width 0.1)
				(type default)
			)
			(layer "F.Fab")
		)
		(fp_line
			(start 0.299974 0.150114)
			(end -0.299974 0.150114)
			(stroke
				(width 0.1)
				(type default)
			)
			(layer "F.Fab")
		)
		(fp_line
			(start -0.299974 -0.150114)
			(end 0.299974 -0.150114)
			(stroke
				(width 0.1)
				(type default)
			)
			(layer "F.Fab")
		)
		(fp_line
			(start 0.299974 -0.150114)
			(end 0.299974 0.150114)
			(stroke
				(width 0.1)
				(type default)
			)
			(layer "F.Fab")
		)
		(pad "1" smd rect
			(at -0.2667 0 270)
			(size 0.3048 0.381)
			(layers "F.Cu" "F.Mask" "F.Paste")
			(net "P5E_CPU1_PE4_TX_C_DN<1>")
		)
		(pad "2" smd rect
			(at 0.2667 0 270)
			(size 0.3048 0.381)
			(layers "F.Cu" "F.Mask" "F.Paste")
			(net "P5E_CPU1_PE4_TX_DN<1>")
		)
	)
	(footprint ""
		(layer "F.Cu")
		(at 72.144382 -58.319924 180)
		(property "Reference" "PC2137"
			(at 0 0 180)
			(layer "F.SilkS")
			(hide yes)
			(effects
				(font
					(size 1.27 1.27)
				)
			)
		)
		(property "Value" ""
			(at 0 0 180)
			(layer "F.Fab")
			(effects
				(font
					(size 1.27 1.27)
				)
			)
		)
		(duplicate_pad_numbers_are_jumpers no)
		(fp_line
			(start 0.7874 0.4064)
			(end -0.7874 0.4064)
			(stroke
				(width 0.1524)
				(type default)
			)
			(layer "F.SilkS")
		)
		(fp_line
			(start 0.7874 -0.4064)
			(end 0.7874 0.4064)
			(stroke
				(width 0.1524)
				(type default)
			)
			(layer "F.SilkS")
		)
		(fp_line
			(start -0.7874 0.4064)
			(end -0.7874 -0.4064)
			(stroke
				(width 0.1524)
				(type default)
			)
			(layer "F.SilkS")
		)
		(fp_line
			(start -0.7874 -0.4064)
			(end 0.7874 -0.4064)
			(stroke
				(width 0.1524)
				(type default)
			)
			(layer "F.SilkS")
		)
		(fp_line
			(start 0.67945 0.3048)
			(end 0.120396 0.3048)
			(stroke
				(width 0.1)
				(type default)
			)
			(layer "F.Fab")
		)
		(fp_line
			(start 0.67945 -0.3048)
			(end 0.67945 0.3048)
			(stroke
				(width 0.1)
				(type default)
			)
			(layer "F.Fab")
		)
		(fp_line
			(start 0.12065 -0.2794)
			(end 0.12065 -0.3048)
			(stroke
				(width 0.1)
				(type default)
			)
			(layer "F.Fab")
		)
		(fp_line
			(start 0.12065 -0.3048)
			(end 0.67945 -0.3048)
			(stroke
				(width 0.1)
				(type default)
			)
			(layer "F.Fab")
		)
		(fp_line
			(start 0.120396 0.3048)
			(end 0.120396 0.2794)
			(stroke
				(width 0.1)
				(type default)
			)
			(layer "F.Fab")
		)
		(fp_line
			(start 0.120396 0.2794)
			(end -0.12065 0.2794)
			(stroke
				(width 0.1)
				(type default)
			)
			(layer "F.Fab")
		)
		(fp_line
			(start -0.12065 0.3048)
			(end -0.67945 0.3048)
			(stroke
				(width 0.1)
				(type default)
			)
			(layer "F.Fab")
		)
		(fp_line
			(start -0.12065 0.2794)
			(end -0.12065 0.3048)
			(stroke
				(width 0.1)
				(type default)
			)
			(layer "F.Fab")
		)
		(fp_line
			(start -0.12065 -0.2794)
			(end 0.12065 -0.2794)
			(stroke
				(width 0.1)
				(type default)
			)
			(layer "F.Fab")
		)
		(fp_line
			(start -0.12065 -0.305054)
			(end -0.12065 -0.2794)
			(stroke
				(width 0.1)
				(type default)
			)
			(layer "F.Fab")
		)
		(fp_line
			(start -0.67945 0.3048)
			(end -0.67945 -0.305054)
			(stroke
				(width 0.1)
				(type default)
			)
			(layer "F.Fab")
		)
		(fp_line
			(start -0.67945 -0.305054)
			(end -0.12065 -0.305054)
			(stroke
				(width 0.1)
				(type default)
			)
			(layer "F.Fab")
		)
		(pad "1" smd circle
			(at -0.40005 0 180)
			(size 0 0)
			(layers "F.Cu" "F.Mask" "F.Paste")
			(net "P3V3_OCP_V3_2_R")
		)
		(pad "2" smd circle
			(at 0.40005 0 180)
			(size 0 0)
			(layers "F.Cu" "F.Mask" "F.Paste")
			(net "GND")
		)
	)
	(footprint ""
		(layer "F.Cu")
		(at 20.485608 -385.066794 -90)
		(property "Reference" "R4662"
			(at 0 0 270)
			(layer "F.SilkS")
			(hide yes)
			(effects
				(font
					(size 1.27 1.27)
				)
			)
		)
		(property "Value" ""
			(at 0 0 270)
			(layer "F.Fab")
			(effects
				(font
					(size 1.27 1.27)
				)
			)
		)
		(duplicate_pad_numbers_are_jumpers no)
		(fp_line
			(start -0.7874 0.4064)
			(end -0.7874 -0.4064)
			(stroke
				(width 0.1524)
				(type default)
			)
			(layer "F.SilkS")
		)
		(fp_line
			(start 0.7874 0.4064)
			(end -0.020066 0.4064)
			(stroke
				(width 0.1524)
				(type default)
			)
			(layer "F.SilkS")
		)
		(fp_line
			(start -0.7874 -0.4064)
			(end 0.7874 -0.4064)
			(stroke
				(width 0.1524)
				(type default)
			)
			(layer "F.SilkS")
		)
		(fp_line
			(start -0.67945 0.3048)
			(end -0.67945 -0.305054)
			(stroke
				(width 0.1)
				(type default)
			)
			(layer "F.Fab")
		)
		(fp_line
			(start -0.12065 0.3048)
			(end -0.67945 0.3048)
			(stroke
				(width 0.1)
				(type default)
			)
			(layer "F.Fab")
		)
		(fp_line
			(start 0.120396 0.3048)
			(end 0.120396 0.2794)
			(stroke
				(width 0.1)
				(type default)
			)
			(layer "F.Fab")
		)
		(fp_line
			(start 0.67945 0.3048)
			(end 0.120396 0.3048)
			(stroke
				(width 0.1)
				(type default)
			)
			(layer "F.Fab")
		)
		(fp_line
			(start -0.12065 0.2794)
			(end -0.12065 0.3048)
			(stroke
				(width 0.1)
				(type default)
			)
			(layer "F.Fab")
		)
		(fp_line
			(start 0.120396 0.2794)
			(end -0.12065 0.2794)
			(stroke
				(width 0.1)
				(type default)
			)
			(layer "F.Fab")
		)
		(fp_line
			(start -0.12065 -0.2794)
			(end 0.12065 -0.2794)
			(stroke
				(width 0.1)
				(type default)
			)
			(layer "F.Fab")
		)
		(fp_line
			(start 0.12065 -0.2794)
			(end 0.12065 -0.3048)
			(stroke
				(width 0.1)
				(type default)
			)
			(layer "F.Fab")
		)
		(fp_line
			(start 0.12065 -0.3048)
			(end 0.67945 -0.3048)
			(stroke
				(width 0.1)
				(type default)
			)
			(layer "F.Fab")
		)
		(fp_line
			(start 0.67945 -0.3048)
			(end 0.67945 0.3048)
			(stroke
				(width 0.1)
				(type default)
			)
			(layer "F.Fab")
		)
		(fp_line
			(start -0.67945 -0.305054)
			(end -0.12065 -0.305054)
			(stroke
				(width 0.1)
				(type default)
			)
			(layer "F.Fab")
		)
		(fp_line
			(start -0.12065 -0.305054)
			(end -0.12065 -0.2794)
			(stroke
				(width 0.1)
				(type default)
			)
			(layer "F.Fab")
		)
		(pad "1" smd rect
			(at -0.40005 0 90)
			(size 0.4572 0.508)
			(layers "F.Cu" "F.Mask" "F.Paste")
			(net "P2E_MB_BMC_TX_C_DN<0>")
		)
		(pad "2" smd rect
			(at 0.40005 0 90)
			(size 0.4572 0.508)
			(layers "F.Cu" "F.Mask" "F.Paste")
			(net "P2E_MB_BMC_TX_C_R2_DN<0>")
		)
	)
	(footprint ""
		(layer "F.Cu")
		(at 105.3084 -251.375672 90)
		(property "Reference" "C251"
			(at 0 0 90)
			(layer "F.SilkS")
			(hide yes)
			(effects
				(font
					(size 1.27 1.27)
				)
			)
		)
		(property "Value" ""
			(at 0 0 90)
			(layer "F.Fab")
			(effects
				(font
					(size 1.27 1.27)
				)
			)
		)
		(duplicate_pad_numbers_are_jumpers no)
		(fp_line
			(start 0.7874 -0.4064)
			(end 0.7874 0.4064)
			(stroke
				(width 0.1524)
				(type default)
			)
			(layer "F.SilkS")
		)
		(fp_line
			(start -0.7874 -0.4064)
			(end 0.7874 -0.4064)
			(stroke
				(width 0.1524)
				(type default)
			)
			(layer "F.SilkS")
		)
		(fp_line
			(start 0.7874 0.4064)
			(end -0.7874 0.4064)
			(stroke
				(width 0.1524)
				(type default)
			)
			(layer "F.SilkS")
		)
		(fp_line
			(start -0.7874 0.4064)
			(end -0.7874 -0.4064)
			(stroke
				(width 0.1524)
				(type default)
			)
			(layer "F.SilkS")
		)
		(fp_line
			(start -0.12065 -0.305054)
			(end -0.12065 -0.2794)
			(stroke
				(width 0.1)
				(type default)
			)
			(layer "F.Fab")
		)
		(fp_line
			(start -0.67945 -0.305054)
			(end -0.12065 -0.305054)
			(stroke
				(width 0.1)
				(type default)
			)
			(layer "F.Fab")
		)
		(fp_line
			(start 0.67945 -0.3048)
			(end 0.67945 0.3048)
			(stroke
				(width 0.1)
				(type default)
			)
			(layer "F.Fab")
		)
		(fp_line
			(start 0.12065 -0.3048)
			(end 0.67945 -0.3048)
			(stroke
				(width 0.1)
				(type default)
			)
			(layer "F.Fab")
		)
		(fp_line
			(start 0.12065 -0.2794)
			(end 0.12065 -0.3048)
			(stroke
				(width 0.1)
				(type default)
			)
			(layer "F.Fab")
		)
		(fp_line
			(start -0.12065 -0.2794)
			(end 0.12065 -0.2794)
			(stroke
				(width 0.1)
				(type default)
			)
			(layer "F.Fab")
		)
		(fp_line
			(start 0.120396 0.2794)
			(end -0.12065 0.2794)
			(stroke
				(width 0.1)
				(type default)
			)
			(layer "F.Fab")
		)
		(fp_line
			(start -0.12065 0.2794)
			(end -0.12065 0.3048)
			(stroke
				(width 0.1)
				(type default)
			)
			(layer "F.Fab")
		)
		(fp_line
			(start 0.67945 0.3048)
			(end 0.120396 0.3048)
			(stroke
				(width 0.1)
				(type default)
			)
			(layer "F.Fab")
		)
		(fp_line
			(start 0.120396 0.3048)
			(end 0.120396 0.2794)
			(stroke
				(width 0.1)
				(type default)
			)
			(layer "F.Fab")
		)
		(fp_line
			(start -0.12065 0.3048)
			(end -0.67945 0.3048)
			(stroke
				(width 0.1)
				(type default)
			)
			(layer "F.Fab")
		)
		(fp_line
			(start -0.67945 0.3048)
			(end -0.67945 -0.305054)
			(stroke
				(width 0.1)
				(type default)
			)
			(layer "F.Fab")
		)
		(pad "1" smd circle
			(at -0.40005 0 90)
			(size 0 0)
			(layers "F.Cu" "F.Mask" "F.Paste")
			(net "PVCCIN_CPU1")
		)
		(pad "2" smd circle
			(at 0.40005 0 90)
			(size 0 0)
			(layers "F.Cu" "F.Mask" "F.Paste")
			(net "GND")
		)
	)
	(footprint ""
		(layer "F.Cu")
		(at 84.270342 -343.015062 -90)
		(property "Reference" "PC486_P1_7"
			(at 0 0 270)
			(layer "F.SilkS")
			(hide yes)
			(effects
				(font
					(size 1.27 1.27)
				)
			)
		)
		(property "Value" ""
			(at 0 0 270)
			(layer "F.Fab")
			(effects
				(font
					(size 1.27 1.27)
				)
			)
		)
		(duplicate_pad_numbers_are_jumpers no)
		(fp_line
			(start -0.7874 0.4064)
			(end -0.7874 -0.4064)
			(stroke
				(width 0.1524)
				(type default)
			)
			(layer "F.SilkS")
		)
		(fp_line
			(start 0.7874 0.4064)
			(end -0.7874 0.4064)
			(stroke
				(width 0.1524)
				(type default)
			)
			(layer "F.SilkS")
		)
		(fp_line
			(start -0.7874 -0.4064)
			(end 0.7874 -0.4064)
			(stroke
				(width 0.1524)
				(type default)
			)
			(layer "F.SilkS")
		)
		(fp_line
			(start 0.7874 -0.4064)
			(end 0.7874 0.4064)
			(stroke
				(width 0.1524)
				(type default)
			)
			(layer "F.SilkS")
		)
		(fp_line
			(start -0.67945 0.3048)
			(end -0.67945 -0.305054)
			(stroke
				(width 0.1)
				(type default)
			)
			(layer "F.Fab")
		)
		(fp_line
			(start -0.12065 0.3048)
			(end -0.67945 0.3048)
			(stroke
				(width 0.1)
				(type default)
			)
			(layer "F.Fab")
		)
		(fp_line
			(start 0.120396 0.3048)
			(end 0.120396 0.2794)
			(stroke
				(width 0.1)
				(type default)
			)
			(layer "F.Fab")
		)
		(fp_line
			(start 0.67945 0.3048)
			(end 0.120396 0.3048)
			(stroke
				(width 0.1)
				(type default)
			)
			(layer "F.Fab")
		)
		(fp_line
			(start -0.12065 0.2794)
			(end -0.12065 0.3048)
			(stroke
				(width 0.1)
				(type default)
			)
			(layer "F.Fab")
		)
		(fp_line
			(start 0.120396 0.2794)
			(end -0.12065 0.2794)
			(stroke
				(width 0.1)
				(type default)
			)
			(layer "F.Fab")
		)
		(fp_line
			(start -0.12065 -0.2794)
			(end 0.12065 -0.2794)
			(stroke
				(width 0.1)
				(type default)
			)
			(layer "F.Fab")
		)
		(fp_line
			(start 0.12065 -0.2794)
			(end 0.12065 -0.3048)
			(stroke
				(width 0.1)
				(type default)
			)
			(layer "F.Fab")
		)
		(fp_line
			(start 0.12065 -0.3048)
			(end 0.67945 -0.3048)
			(stroke
				(width 0.1)
				(type default)
			)
			(layer "F.Fab")
		)
		(fp_line
			(start 0.67945 -0.3048)
			(end 0.67945 0.3048)
			(stroke
				(width 0.1)
				(type default)
			)
			(layer "F.Fab")
		)
		(fp_line
			(start -0.67945 -0.305054)
			(end -0.12065 -0.305054)
			(stroke
				(width 0.1)
				(type default)
			)
			(layer "F.Fab")
		)
		(fp_line
			(start -0.12065 -0.305054)
			(end -0.12065 -0.2794)
			(stroke
				(width 0.1)
				(type default)
			)
			(layer "F.Fab")
		)
		(pad "1" smd circle
			(at -0.40005 0 270)
			(size 0 0)
			(layers "F.Cu" "F.Mask" "F.Paste")
			(net "SW_P12V_PVCCIN_CPU1_FLT")
		)
		(pad "2" smd circle
			(at 0.40005 0 270)
			(size 0 0)
			(layers "F.Cu" "F.Mask" "F.Paste")
			(net "GND")
		)
	)
	(footprint ""
		(layer "F.Cu")
		(at 23.10511 -179.928266)
		(property "Reference" "PU82"
			(at -4.4704 7.05358 0)
			(unlocked yes)
			(layer "F.SilkS")
			(effects
				(font
					(size 0.7874 0.5842)
					(thickness 0.1524)
				)
				(justify left)
			)
		)
		(property "Value" ""
			(at 0 0 0)
			(layer "F.Fab")
			(effects
				(font
					(size 1.27 1.27)
				)
			)
		)
		(duplicate_pad_numbers_are_jumpers no)
		(fp_line
			(start -1.050036 -1.549908)
			(end -0.503936 -1.549908)
			(stroke
				(width 0.1524)
				(type default)
			)
			(layer "F.SilkS")
		)
		(fp_line
			(start -1.050036 -1.253998)
			(end -1.050036 -1.549908)
			(stroke
				(width 0.1524)
				(type default)
			)
			(layer "F.SilkS")
		)
		(fp_line
			(start -1.050036 1.549908)
			(end -1.050036 1.253998)
			(stroke
				(width 0.1524)
				(type default)
			)
			(layer "F.SilkS")
		)
		(fp_line
			(start -0.503936 1.549908)
			(end -1.050036 1.549908)
			(stroke
				(width 0.1524)
				(type default)
			)
			(layer "F.SilkS")
		)
		(fp_line
			(start 0.503936 -1.549908)
			(end 1.050036 -1.549908)
			(stroke
				(width 0.1524)
				(type default)
			)
			(layer "F.SilkS")
		)
		(fp_line
			(start 1.050036 -1.549908)
			(end 1.050036 -1.253998)
			(stroke
				(width 0.1524)
				(type default)
			)
			(layer "F.SilkS")
		)
		(fp_line
			(start 1.050036 1.253998)
			(end 1.050036 1.549908)
			(stroke
				(width 0.1524)
				(type default)
			)
			(layer "F.SilkS")
		)
		(fp_line
			(start 1.050036 1.549908)
			(end 0.503936 1.549908)
			(stroke
				(width 0.1524)
				(type default)
			)
			(layer "F.SilkS")
		)
		(fp_poly
			(pts
				(xy -1.474724 -2.460498) (xy -1.385824 -1.613154) (xy -2.11709 -2.050288)
			)
			(stroke
				(width 0)
				(type default)
			)
			(fill yes)
			(layer "F.SilkS")
		)
		(fp_line
			(start -1.050036 -1.549908)
			(end 1.050036 -1.549908)
			(stroke
				(width 0.1)
				(type default)
			)
			(layer "F.Fab")
		)
		(fp_line
			(start -1.050036 1.549908)
			(end -1.050036 -1.549908)
			(stroke
				(width 0.1)
				(type default)
			)
			(layer "F.Fab")
		)
		(fp_line
			(start 1.050036 -1.549908)
			(end 1.050036 1.549908)
			(stroke
				(width 0.1)
				(type default)
			)
			(layer "F.Fab")
		)
		(fp_line
			(start 1.050036 1.549908)
			(end -1.050036 1.549908)
			(stroke
				(width 0.1)
				(type default)
			)
			(layer "F.Fab")
		)
		(fp_poly
			(pts
				(xy -2.2352 -0.618998) (xy -2.2352 -1.380998) (xy -1.4732 -0.999998)
			)
			(stroke
				(width 0)
				(type default)
			)
			(fill yes)
			(layer "F.Fab")
		)
		(pad "1" smd circle
			(at -0.94996 -0.999998 270)
			(size 0 0)
			(layers "F.Cu" "F.Mask" "F.Paste")
			(net "GND")
		)
		(pad "2" smd rect
			(at -0.849884 -0.499872 90)
			(size 0.254 0.9144)
			(layers "F.Cu" "F.Mask" "F.Paste")
			(net "SW_PVNN_MAIN_CPU1_SW")
		)
		(pad "3" smd rect
			(at -0.649986 0 90)
			(size 0.254 1.3208)
			(layers "F.Cu" "F.Mask" "F.Paste")
			(net "SW_P12V_PVCCINFAON_CPU1_FLT")
		)
		(pad "4" smd rect
			(at -0.849884 0.499872 90)
			(size 0.254 0.9144)
			(layers "F.Cu" "F.Mask" "F.Paste")
			(net "PVNN_MAIN_CPU1_CS")
		)
		(pad "5" smd circle
			(at -0.94996 0.999998 270)
			(size 0 0)
			(layers "F.Cu" "F.Mask" "F.Paste")
			(net "FM_PVNN_MAIN_CPU1_EN")
		)
		(pad "6" smd circle
			(at -0.249936 1.450086)
			(size 0 0)
			(layers "F.Cu" "F.Mask" "F.Paste")
			(net "PVNN_MAIN_CPU1_FB")
		)
		(pad "7" smd circle
			(at 0.249936 1.450086)
			(size 0 0)
			(layers "F.Cu" "F.Mask" "F.Paste")
			(net "GND")
		)
		(pad "8" smd circle
			(at 0.94996 0.999998 90)
			(size 0 0)
			(layers "F.Cu" "F.Mask" "F.Paste")
			(net "PVNN_MAIN_CPU1_REF")
		)
		(pad "9" smd rect
			(at 0.849884 0.499872 90)
			(size 0.254 0.9144)
			(layers "F.Cu" "F.Mask" "F.Paste")
			(net "PWRGD_PVNN_MAIN_CPU1_R")
		)
		(pad "10" smd rect
			(at 0.849884 0 90)
			(size 0.254 0.9144)
			(layers "F.Cu" "F.Mask" "F.Paste")
			(net "SW_PVNN_MAIN_CPU1_BST")
		)
		(pad "11" smd rect
			(at 0.849884 -0.499872 90)
			(size 0.254 0.9144)
			(layers "F.Cu" "F.Mask" "F.Paste")
			(net "SW_PVNN_MAIN_CPU1_SW")
		)
		(pad "12" smd circle
			(at 0.94996 -0.999998 90)
			(size 0 0)
			(layers "F.Cu" "F.Mask" "F.Paste")
			(net "PVNN_MAIN_CPU1_MODE")
		)
		(pad "13" smd circle
			(at 0.249936 -1.450086 180)
			(size 0 0)
			(layers "F.Cu" "F.Mask" "F.Paste")
			(net "PVNN_MAIN_CPU1_VCC")
		)
		(pad "14" smd circle
			(at -0.249936 -1.450086 180)
			(size 0 0)
			(layers "F.Cu" "F.Mask" "F.Paste")
			(net "GND")
		)
	)
	(footprint ""
		(layer "F.Cu")
		(at 132.382514 -402.371052 -90)
		(property "Reference" "C751"
			(at 0 0 270)
			(layer "F.SilkS")
			(hide yes)
			(effects
				(font
					(size 1.27 1.27)
				)
			)
		)
		(property "Value" ""
			(at 0 0 270)
			(layer "F.Fab")
			(effects
				(font
					(size 1.27 1.27)
				)
			)
		)
		(duplicate_pad_numbers_are_jumpers no)
		(fp_line
			(start -0.299974 0.150114)
			(end -0.299974 -0.150114)
			(stroke
				(width 0.1)
				(type default)
			)
			(layer "F.Fab")
		)
		(fp_line
			(start 0.299974 0.150114)
			(end -0.299974 0.150114)
			(stroke
				(width 0.1)
				(type default)
			)
			(layer "F.Fab")
		)
		(fp_line
			(start -0.299974 -0.150114)
			(end 0.299974 -0.150114)
			(stroke
				(width 0.1)
				(type default)
			)
			(layer "F.Fab")
		)
		(fp_line
			(start 0.299974 -0.150114)
			(end 0.299974 0.150114)
			(stroke
				(width 0.1)
				(type default)
			)
			(layer "F.Fab")
		)
		(pad "1" smd rect
			(at -0.2667 0 270)
			(size 0.3048 0.381)
			(layers "F.Cu" "F.Mask" "F.Paste")
			(net "P5E_CPU1_PE2_TX_C_DP<11>")
		)
		(pad "2" smd rect
			(at 0.2667 0 270)
			(size 0.3048 0.381)
			(layers "F.Cu" "F.Mask" "F.Paste")
			(net "P5E_CPU1_PE2_TX_DP<11>")
		)
	)
	(footprint ""
		(layer "F.Cu")
		(at 160.83788 -107.025948)
		(property "Reference" "R3043"
			(at 0 0 0)
			(layer "F.SilkS")
			(hide yes)
			(effects
				(font
					(size 1.27 1.27)
				)
			)
		)
		(property "Value" ""
			(at 0 0 0)
			(layer "F.Fab")
			(effects
				(font
					(size 1.27 1.27)
				)
			)
		)
		(duplicate_pad_numbers_are_jumpers no)
		(fp_line
			(start -0.7874 -0.4064)
			(end 0.7874 -0.4064)
			(stroke
				(width 0.1524)
				(type default)
			)
			(layer "F.SilkS")
		)
		(fp_line
			(start -0.7874 0.4064)
			(end -0.7874 -0.4064)
			(stroke
				(width 0.1524)
				(type default)
			)
			(layer "F.SilkS")
		)
		(fp_line
			(start 0.7874 -0.4064)
			(end 0.7874 0.4064)
			(stroke
				(width 0.1524)
				(type default)
			)
			(layer "F.SilkS")
		)
		(fp_line
			(start 0.7874 0.4064)
			(end -0.7874 0.4064)
			(stroke
				(width 0.1524)
				(type default)
			)
			(layer "F.SilkS")
		)
		(fp_line
			(start -0.67945 -0.305054)
			(end -0.12065 -0.305054)
			(stroke
				(width 0.1)
				(type default)
			)
			(layer "F.Fab")
		)
		(fp_line
			(start -0.67945 0.3048)
			(end -0.67945 -0.305054)
			(stroke
				(width 0.1)
				(type default)
			)
			(layer "F.Fab")
		)
		(fp_line
			(start -0.12065 -0.305054)
			(end -0.12065 -0.2794)
			(stroke
				(width 0.1)
				(type default)
			)
			(layer "F.Fab")
		)
		(fp_line
			(start -0.12065 -0.2794)
			(end 0.12065 -0.2794)
			(stroke
				(width 0.1)
				(type default)
			)
			(layer "F.Fab")
		)
		(fp_line
			(start -0.12065 0.2794)
			(end -0.12065 0.3048)
			(stroke
				(width 0.1)
				(type default)
			)
			(layer "F.Fab")
		)
		(fp_line
			(start -0.12065 0.3048)
			(end -0.67945 0.3048)
			(stroke
				(width 0.1)
				(type default)
			)
			(layer "F.Fab")
		)
		(fp_line
			(start 0.120396 0.2794)
			(end -0.12065 0.2794)
			(stroke
				(width 0.1)
				(type default)
			)
			(layer "F.Fab")
		)
		(fp_line
			(start 0.120396 0.3048)
			(end 0.120396 0.2794)
			(stroke
				(width 0.1)
				(type default)
			)
			(layer "F.Fab")
		)
		(fp_line
			(start 0.12065 -0.3048)
			(end 0.67945 -0.3048)
			(stroke
				(width 0.1)
				(type default)
			)
			(layer "F.Fab")
		)
		(fp_line
			(start 0.12065 -0.2794)
			(end 0.12065 -0.3048)
			(stroke
				(width 0.1)
				(type default)
			)
			(layer "F.Fab")
		)
		(fp_line
			(start 0.67945 -0.3048)
			(end 0.67945 0.3048)
			(stroke
				(width 0.1)
				(type default)
			)
			(layer "F.Fab")
		)
		(fp_line
			(start 0.67945 0.3048)
			(end 0.120396 0.3048)
			(stroke
				(width 0.1)
				(type default)
			)
			(layer "F.Fab")
		)
		(pad "1" smd circle
			(at -0.40005 0)
			(size 0 0)
			(layers "F.Cu" "F.Mask" "F.Paste")
			(net "IRQ_HSC_FAULT_N")
		)
		(pad "2" smd circle
			(at 0.40005 0)
			(size 0 0)
			(layers "F.Cu" "F.Mask" "F.Paste")
			(net "IRQ_HSC_FAULT_R1_N")
		)
	)
	(footprint ""
		(layer "F.Cu")
		(at 209.172556 -34.772092 90)
		(property "Reference" "U265"
			(at 3.273806 -3.826256 0)
			(unlocked yes)
			(layer "F.SilkS")
			(effects
				(font
					(size 0.7874 0.5842)
					(thickness 0.1524)
				)
			)
		)
		(property "Value" ""
			(at 0 0 90)
			(layer "F.Fab")
			(effects
				(font
					(size 1.27 1.27)
				)
			)
		)
		(duplicate_pad_numbers_are_jumpers no)
		(fp_line
			(start 1.500124 -1.500124)
			(end 1.500124 -1.004062)
			(stroke
				(width 0.1524)
				(type default)
			)
			(layer "F.SilkS")
		)
		(fp_line
			(start 1.004062 -1.500124)
			(end 1.500124 -1.500124)
			(stroke
				(width 0.1524)
				(type default)
			)
			(layer "F.SilkS")
		)
		(fp_line
			(start -1.500124 -1.500124)
			(end -1.004062 -1.500124)
			(stroke
				(width 0.1524)
				(type default)
			)
			(layer "F.SilkS")
		)
		(fp_line
			(start -1.500124 -1.004062)
			(end -1.500124 -1.500124)
			(stroke
				(width 0.1524)
				(type default)
			)
			(layer "F.SilkS")
		)
		(fp_line
			(start 1.500124 1.004062)
			(end 1.500124 1.500124)
			(stroke
				(width 0.1524)
				(type default)
			)
			(layer "F.SilkS")
		)
		(fp_line
			(start 1.500124 1.500124)
			(end 1.004062 1.500124)
			(stroke
				(width 0.1524)
				(type default)
			)
			(layer "F.SilkS")
		)
		(fp_line
			(start -1.004062 1.500124)
			(end -1.500124 1.500124)
			(stroke
				(width 0.1524)
				(type default)
			)
			(layer "F.SilkS")
		)
		(fp_line
			(start -1.500124 1.500124)
			(end -1.500124 1.004062)
			(stroke
				(width 0.1524)
				(type default)
			)
			(layer "F.SilkS")
		)
		(fp_poly
			(pts
				(xy -2.15011 -2.265934) (xy -1.790954 -1.188212) (xy -2.868422 -1.547368)
			)
			(stroke
				(width 0)
				(type default)
			)
			(fill yes)
			(layer "F.SilkS")
		)
		(fp_line
			(start 1.500124 -1.500124)
			(end 1.500124 1.500124)
			(stroke
				(width 0.1)
				(type default)
			)
			(layer "F.Fab")
		)
		(fp_line
			(start -1.500124 -1.500124)
			(end 1.500124 -1.500124)
			(stroke
				(width 0.1)
				(type default)
			)
			(layer "F.Fab")
		)
		(fp_line
			(start 1.500124 1.500124)
			(end -1.500124 1.500124)
			(stroke
				(width 0.1)
				(type default)
			)
			(layer "F.Fab")
		)
		(fp_line
			(start -1.500124 1.500124)
			(end -1.500124 -1.500124)
			(stroke
				(width 0.1)
				(type default)
			)
			(layer "F.Fab")
		)
		(fp_poly
			(pts
				(xy -2.847848 -1.258062) (xy -2.847848 -0.242062) (xy -1.831848 -0.750062)
			)
			(stroke
				(width 0)
				(type default)
			)
			(fill yes)
			(layer "F.Fab")
		)
		(pad "1" smd rect
			(at -1.400048 -0.750062)
			(size 0.2286 0.6096)
			(layers "F.Cu" "F.Mask" "F.Paste")
			(net "INA230_5_A1")
		)
		(pad "2" smd rect
			(at -1.400048 -0.249936)
			(size 0.2286 0.6096)
			(layers "F.Cu" "F.Mask" "F.Paste")
			(net "INA230_5_A0")
		)
		(pad "3" smd rect
			(at -1.400048 0.249936)
			(size 0.2286 0.6096)
			(layers "F.Cu" "F.Mask" "F.Paste")
			(net "P12V_SCM_ADC_ALERT_R")
		)
		(pad "4" smd rect
			(at -1.400048 0.750062)
			(size 0.2286 0.6096)
			(layers "F.Cu" "F.Mask" "F.Paste")
			(net "SMB_INA230_5_3V3AUX_SDA_R1")
		)
		(pad "5" smd rect
			(at -0.750062 1.400048 90)
			(size 0.2286 0.6096)
			(layers "F.Cu" "F.Mask" "F.Paste")
			(net "SMB_INA230_5_3V3AUX_SCL_R1")
		)
		(pad "6" smd rect
			(at -0.249936 1.400048 90)
			(size 0.2286 0.6096)
			(layers "F.Cu" "F.Mask" "F.Paste")
			(net "NC_INA230_5_NC0")
		)
		(pad "7" smd rect
			(at 0.249936 1.400048 90)
			(size 0.2286 0.6096)
			(layers "F.Cu" "F.Mask" "F.Paste")
			(net "NC_INA230_5_NC1")
		)
		(pad "8" smd rect
			(at 0.750062 1.400048 90)
			(size 0.2286 0.6096)
			(layers "F.Cu" "F.Mask" "F.Paste")
			(net "NC_INA230_5_NC2")
		)
		(pad "9" smd rect
			(at 1.400048 0.750062)
			(size 0.2286 0.6096)
			(layers "F.Cu" "F.Mask" "F.Paste")
			(net "P3V3_AUX")
		)
		(pad "10" smd rect
			(at 1.400048 0.249936)
			(size 0.2286 0.6096)
			(layers "F.Cu" "F.Mask" "F.Paste")
			(net "GND")
		)
		(pad "11" smd rect
			(at 1.400048 -0.249936)
			(size 0.2286 0.6096)
			(layers "F.Cu" "F.Mask" "F.Paste")
			(net "P12V_SCM_R")
		)
		(pad "12" smd rect
			(at 1.400048 -0.750062)
			(size 0.2286 0.6096)
			(layers "F.Cu" "F.Mask" "F.Paste")
			(net "VSENSE_P12V_INA230_5_INN")
		)
		(pad "13" smd rect
			(at 0.750062 -1.400048 90)
			(size 0.2286 0.6096)
			(layers "F.Cu" "F.Mask" "F.Paste")
			(net "VSENSE_P12V_INA230_5_INP")
		)
		(pad "14" smd rect
			(at 0.249936 -1.400048 90)
			(size 0.2286 0.6096)
			(layers "F.Cu" "F.Mask" "F.Paste")
			(net "NC_INA230_5_NC3")
		)
		(pad "15" smd rect
			(at -0.249936 -1.400048 90)
			(size 0.2286 0.6096)
			(layers "F.Cu" "F.Mask" "F.Paste")
			(net "NC_INA230_5_NC4")
		)
		(pad "16" smd rect
			(at -0.750062 -1.400048 90)
			(size 0.2286 0.6096)
			(layers "F.Cu" "F.Mask" "F.Paste")
			(net "NC_INA230_5_NC5")
		)
		(pad "TH" smd rect
			(at 0 0 90)
			(size 1.7018 1.7018)
			(layers "F.Cu" "F.Mask" "F.Paste")
			(net "GND")
		)
		(zone
			(layer "F.Cu")
			(hatch none 0.5)
			(connect_pads
				(clearance 0)
			)
			(min_thickness 0.25)
			(keepout
				(tracks not_allowed)
				(vias allowed)
				(pads allowed)
				(copperpour not_allowed)
				(footprints allowed)
			)
			(placement
				(enabled no)
				(sheetname "")
			)
			(fill
				(thermal_gap 0.5)
				(thermal_bridge_width 0.5)
				(island_removal_mode 0)
			)
			(polygon
				(pts
					(xy 209.147156 -33.727644) (xy 208.128108 -33.727644) (xy 208.128108 -35.81654) (xy 210.217004 -35.81654)
					(xy 210.217004 -33.727644) (xy 209.172556 -33.727644) (xy 209.172556 -33.870392) (xy 210.074256 -33.870392)
					(xy 210.074256 -35.673792) (xy 208.270856 -35.673792) (xy 208.270856 -33.870392) (xy 209.147156 -33.870392)
				)
			)
		)
	)
	(footprint ""
		(layer "F.Cu")
		(at 144.6022 -104.116378 90)
		(property "Reference" "R4055"
			(at 0 0 90)
			(layer "F.SilkS")
			(hide yes)
			(effects
				(font
					(size 1.27 1.27)
				)
			)
		)
		(property "Value" ""
			(at 0 0 90)
			(layer "F.Fab")
			(effects
				(font
					(size 1.27 1.27)
				)
			)
		)
		(duplicate_pad_numbers_are_jumpers no)
		(fp_line
			(start 0.7874 -0.4064)
			(end 0.7874 0.4064)
			(stroke
				(width 0.1524)
				(type default)
			)
			(layer "F.SilkS")
		)
		(fp_line
			(start -0.7874 -0.4064)
			(end 0.7874 -0.4064)
			(stroke
				(width 0.1524)
				(type default)
			)
			(layer "F.SilkS")
		)
		(fp_line
			(start 0.7874 0.4064)
			(end -0.7874 0.4064)
			(stroke
				(width 0.1524)
				(type default)
			)
			(layer "F.SilkS")
		)
		(fp_line
			(start -0.7874 0.4064)
			(end -0.7874 -0.4064)
			(stroke
				(width 0.1524)
				(type default)
			)
			(layer "F.SilkS")
		)
		(fp_line
			(start -0.12065 -0.305054)
			(end -0.12065 -0.2794)
			(stroke
				(width 0.1)
				(type default)
			)
			(layer "F.Fab")
		)
		(fp_line
			(start -0.67945 -0.305054)
			(end -0.12065 -0.305054)
			(stroke
				(width 0.1)
				(type default)
			)
			(layer "F.Fab")
		)
		(fp_line
			(start 0.67945 -0.3048)
			(end 0.67945 0.3048)
			(stroke
				(width 0.1)
				(type default)
			)
			(layer "F.Fab")
		)
		(fp_line
			(start 0.12065 -0.3048)
			(end 0.67945 -0.3048)
			(stroke
				(width 0.1)
				(type default)
			)
			(layer "F.Fab")
		)
		(fp_line
			(start 0.12065 -0.2794)
			(end 0.12065 -0.3048)
			(stroke
				(width 0.1)
				(type default)
			)
			(layer "F.Fab")
		)
		(fp_line
			(start -0.12065 -0.2794)
			(end 0.12065 -0.2794)
			(stroke
				(width 0.1)
				(type default)
			)
			(layer "F.Fab")
		)
		(fp_line
			(start 0.120396 0.2794)
			(end -0.12065 0.2794)
			(stroke
				(width 0.1)
				(type default)
			)
			(layer "F.Fab")
		)
		(fp_line
			(start -0.12065 0.2794)
			(end -0.12065 0.3048)
			(stroke
				(width 0.1)
				(type default)
			)
			(layer "F.Fab")
		)
		(fp_line
			(start 0.67945 0.3048)
			(end 0.120396 0.3048)
			(stroke
				(width 0.1)
				(type default)
			)
			(layer "F.Fab")
		)
		(fp_line
			(start 0.120396 0.3048)
			(end 0.120396 0.2794)
			(stroke
				(width 0.1)
				(type default)
			)
			(layer "F.Fab")
		)
		(fp_line
			(start -0.12065 0.3048)
			(end -0.67945 0.3048)
			(stroke
				(width 0.1)
				(type default)
			)
			(layer "F.Fab")
		)
		(fp_line
			(start -0.67945 0.3048)
			(end -0.67945 -0.305054)
			(stroke
				(width 0.1)
				(type default)
			)
			(layer "F.Fab")
		)
		(pad "1" smd circle
			(at -0.40005 0 90)
			(size 0 0)
			(layers "F.Cu" "F.Mask" "F.Paste")
			(net "PD_CPU1_ERRS_U306_DIR")
		)
		(pad "2" smd circle
			(at 0.40005 0 90)
			(size 0 0)
			(layers "F.Cu" "F.Mask" "F.Paste")
			(net "GND")
		)
	)
	(footprint ""
		(layer "F.Cu")
		(at 34.291524 -124.99721 90)
		(property "Reference" "R4594"
			(at 0 0 90)
			(layer "F.SilkS")
			(hide yes)
			(effects
				(font
					(size 1.27 1.27)
				)
			)
		)
		(property "Value" ""
			(at 0 0 90)
			(layer "F.Fab")
			(effects
				(font
					(size 1.27 1.27)
				)
			)
		)
		(duplicate_pad_numbers_are_jumpers no)
		(fp_line
			(start 0.7874 -0.4064)
			(end 0.7874 0.4064)
			(stroke
				(width 0.1524)
				(type default)
			)
			(layer "F.SilkS")
		)
		(fp_line
			(start -0.7874 -0.4064)
			(end 0.7874 -0.4064)
			(stroke
				(width 0.1524)
				(type default)
			)
			(layer "F.SilkS")
		)
		(fp_line
			(start 0.7874 0.4064)
			(end -0.7874 0.4064)
			(stroke
				(width 0.1524)
				(type default)
			)
			(layer "F.SilkS")
		)
		(fp_line
			(start -0.7874 0.4064)
			(end -0.7874 -0.4064)
			(stroke
				(width 0.1524)
				(type default)
			)
			(layer "F.SilkS")
		)
		(fp_line
			(start -0.12065 -0.305054)
			(end -0.12065 -0.2794)
			(stroke
				(width 0.1)
				(type default)
			)
			(layer "F.Fab")
		)
		(fp_line
			(start -0.67945 -0.305054)
			(end -0.12065 -0.305054)
			(stroke
				(width 0.1)
				(type default)
			)
			(layer "F.Fab")
		)
		(fp_line
			(start 0.67945 -0.3048)
			(end 0.67945 0.3048)
			(stroke
				(width 0.1)
				(type default)
			)
			(layer "F.Fab")
		)
		(fp_line
			(start 0.12065 -0.3048)
			(end 0.67945 -0.3048)
			(stroke
				(width 0.1)
				(type default)
			)
			(layer "F.Fab")
		)
		(fp_line
			(start 0.12065 -0.2794)
			(end 0.12065 -0.3048)
			(stroke
				(width 0.1)
				(type default)
			)
			(layer "F.Fab")
		)
		(fp_line
			(start -0.12065 -0.2794)
			(end 0.12065 -0.2794)
			(stroke
				(width 0.1)
				(type default)
			)
			(layer "F.Fab")
		)
		(fp_line
			(start 0.120396 0.2794)
			(end -0.12065 0.2794)
			(stroke
				(width 0.1)
				(type default)
			)
			(layer "F.Fab")
		)
		(fp_line
			(start -0.12065 0.2794)
			(end -0.12065 0.3048)
			(stroke
				(width 0.1)
				(type default)
			)
			(layer "F.Fab")
		)
		(fp_line
			(start 0.67945 0.3048)
			(end 0.120396 0.3048)
			(stroke
				(width 0.1)
				(type default)
			)
			(layer "F.Fab")
		)
		(fp_line
			(start 0.120396 0.3048)
			(end 0.120396 0.2794)
			(stroke
				(width 0.1)
				(type default)
			)
			(layer "F.Fab")
		)
		(fp_line
			(start -0.12065 0.3048)
			(end -0.67945 0.3048)
			(stroke
				(width 0.1)
				(type default)
			)
			(layer "F.Fab")
		)
		(fp_line
			(start -0.67945 0.3048)
			(end -0.67945 -0.305054)
			(stroke
				(width 0.1)
				(type default)
			)
			(layer "F.Fab")
		)
		(pad "1" smd circle
			(at -0.40005 0 90)
			(size 0 0)
			(layers "F.Cu" "F.Mask" "F.Paste")
			(net "SMB_VR_3V3AUX_SCL_R")
		)
		(pad "2" smd circle
			(at 0.40005 0 90)
			(size 0 0)
			(layers "F.Cu" "F.Mask" "F.Paste")
			(net "SMB_CLK_PVCCINFAON_CPU1")
		)
	)
	(footprint ""
		(layer "F.Cu")
		(at 309.522622 -44.948348 180)
		(property "Reference" "R607"
			(at 0 0 180)
			(layer "F.SilkS")
			(hide yes)
			(effects
				(font
					(size 1.27 1.27)
				)
			)
		)
		(property "Value" ""
			(at 0 0 180)
			(layer "F.Fab")
			(effects
				(font
					(size 1.27 1.27)
				)
			)
		)
		(duplicate_pad_numbers_are_jumpers no)
		(fp_line
			(start 0.7874 0.4064)
			(end -0.7874 0.4064)
			(stroke
				(width 0.1524)
				(type default)
			)
			(layer "F.SilkS")
		)
		(fp_line
			(start 0.7874 -0.4064)
			(end 0.7874 0.4064)
			(stroke
				(width 0.1524)
				(type default)
			)
			(layer "F.SilkS")
		)
		(fp_line
			(start -0.7874 0.4064)
			(end -0.7874 -0.4064)
			(stroke
				(width 0.1524)
				(type default)
			)
			(layer "F.SilkS")
		)
		(fp_line
			(start -0.7874 -0.4064)
			(end 0.7874 -0.4064)
			(stroke
				(width 0.1524)
				(type default)
			)
			(layer "F.SilkS")
		)
		(fp_line
			(start 0.67945 0.3048)
			(end 0.120396 0.3048)
			(stroke
				(width 0.1)
				(type default)
			)
			(layer "F.Fab")
		)
		(fp_line
			(start 0.67945 -0.3048)
			(end 0.67945 0.3048)
			(stroke
				(width 0.1)
				(type default)
			)
			(layer "F.Fab")
		)
		(fp_line
			(start 0.12065 -0.2794)
			(end 0.12065 -0.3048)
			(stroke
				(width 0.1)
				(type default)
			)
			(layer "F.Fab")
		)
		(fp_line
			(start 0.12065 -0.3048)
			(end 0.67945 -0.3048)
			(stroke
				(width 0.1)
				(type default)
			)
			(layer "F.Fab")
		)
		(fp_line
			(start 0.120396 0.3048)
			(end 0.120396 0.2794)
			(stroke
				(width 0.1)
				(type default)
			)
			(layer "F.Fab")
		)
		(fp_line
			(start 0.120396 0.2794)
			(end -0.12065 0.2794)
			(stroke
				(width 0.1)
				(type default)
			)
			(layer "F.Fab")
		)
		(fp_line
			(start -0.12065 0.3048)
			(end -0.67945 0.3048)
			(stroke
				(width 0.1)
				(type default)
			)
			(layer "F.Fab")
		)
		(fp_line
			(start -0.12065 0.2794)
			(end -0.12065 0.3048)
			(stroke
				(width 0.1)
				(type default)
			)
			(layer "F.Fab")
		)
		(fp_line
			(start -0.12065 -0.2794)
			(end 0.12065 -0.2794)
			(stroke
				(width 0.1)
				(type default)
			)
			(layer "F.Fab")
		)
		(fp_line
			(start -0.12065 -0.305054)
			(end -0.12065 -0.2794)
			(stroke
				(width 0.1)
				(type default)
			)
			(layer "F.Fab")
		)
		(fp_line
			(start -0.67945 0.3048)
			(end -0.67945 -0.305054)
			(stroke
				(width 0.1)
				(type default)
			)
			(layer "F.Fab")
		)
		(fp_line
			(start -0.67945 -0.305054)
			(end -0.12065 -0.305054)
			(stroke
				(width 0.1)
				(type default)
			)
			(layer "F.Fab")
		)
		(pad "1" smd circle
			(at -0.40005 0 180)
			(size 0 0)
			(layers "F.Cu" "F.Mask" "F.Paste")
			(net "P3V3_AUX")
		)
		(pad "2" smd circle
			(at 0.40005 0 180)
			(size 0 0)
			(layers "F.Cu" "F.Mask" "F.Paste")
			(net "FM_ESPI_FLASH_MODE")
		)
	)
	(footprint ""
		(layer "F.Cu")
		(at 368.72164 -403.936708 180)
		(property "Reference" "R4173"
			(at 0 0 180)
			(layer "F.SilkS")
			(hide yes)
			(effects
				(font
					(size 1.27 1.27)
				)
			)
		)
		(property "Value" ""
			(at 0 0 180)
			(layer "F.Fab")
			(effects
				(font
					(size 1.27 1.27)
				)
			)
		)
		(duplicate_pad_numbers_are_jumpers no)
		(fp_line
			(start 0.7874 0.4064)
			(end -0.7874 0.4064)
			(stroke
				(width 0.1524)
				(type default)
			)
			(layer "F.SilkS")
		)
		(fp_line
			(start 0.7874 -0.4064)
			(end 0.7874 0.4064)
			(stroke
				(width 0.1524)
				(type default)
			)
			(layer "F.SilkS")
		)
		(fp_line
			(start -0.7874 0.4064)
			(end -0.7874 -0.4064)
			(stroke
				(width 0.1524)
				(type default)
			)
			(layer "F.SilkS")
		)
		(fp_line
			(start -0.7874 -0.4064)
			(end 0.7874 -0.4064)
			(stroke
				(width 0.1524)
				(type default)
			)
			(layer "F.SilkS")
		)
		(fp_line
			(start 0.67945 0.3048)
			(end 0.120396 0.3048)
			(stroke
				(width 0.1)
				(type default)
			)
			(layer "F.Fab")
		)
		(fp_line
			(start 0.67945 -0.3048)
			(end 0.67945 0.3048)
			(stroke
				(width 0.1)
				(type default)
			)
			(layer "F.Fab")
		)
		(fp_line
			(start 0.12065 -0.2794)
			(end 0.12065 -0.3048)
			(stroke
				(width 0.1)
				(type default)
			)
			(layer "F.Fab")
		)
		(fp_line
			(start 0.12065 -0.3048)
			(end 0.67945 -0.3048)
			(stroke
				(width 0.1)
				(type default)
			)
			(layer "F.Fab")
		)
		(fp_line
			(start 0.120396 0.3048)
			(end 0.120396 0.2794)
			(stroke
				(width 0.1)
				(type default)
			)
			(layer "F.Fab")
		)
		(fp_line
			(start 0.120396 0.2794)
			(end -0.12065 0.2794)
			(stroke
				(width 0.1)
				(type default)
			)
			(layer "F.Fab")
		)
		(fp_line
			(start -0.12065 0.3048)
			(end -0.67945 0.3048)
			(stroke
				(width 0.1)
				(type default)
			)
			(layer "F.Fab")
		)
		(fp_line
			(start -0.12065 0.2794)
			(end -0.12065 0.3048)
			(stroke
				(width 0.1)
				(type default)
			)
			(layer "F.Fab")
		)
		(fp_line
			(start -0.12065 -0.2794)
			(end 0.12065 -0.2794)
			(stroke
				(width 0.1)
				(type default)
			)
			(layer "F.Fab")
		)
		(fp_line
			(start -0.12065 -0.305054)
			(end -0.12065 -0.2794)
			(stroke
				(width 0.1)
				(type default)
			)
			(layer "F.Fab")
		)
		(fp_line
			(start -0.67945 0.3048)
			(end -0.67945 -0.305054)
			(stroke
				(width 0.1)
				(type default)
			)
			(layer "F.Fab")
		)
		(fp_line
			(start -0.67945 -0.305054)
			(end -0.12065 -0.305054)
			(stroke
				(width 0.1)
				(type default)
			)
			(layer "F.Fab")
		)
		(pad "1" smd circle
			(at -0.40005 0 180)
			(size 0 0)
			(layers "F.Cu" "F.Mask" "F.Paste")
			(net "P3V3_AUX")
		)
		(pad "2" smd circle
			(at 0.40005 0 180)
			(size 0 0)
			(layers "F.Cu" "F.Mask" "F.Paste")
			(net "UART_BMC_BIC_R_BUF_RX")
		)
	)
	(footprint ""
		(layer "F.Cu")
		(at 121.043954 -402.371052 -90)
		(property "Reference" "C742"
			(at 0 0 270)
			(layer "F.SilkS")
			(hide yes)
			(effects
				(font
					(size 1.27 1.27)
				)
			)
		)
		(property "Value" ""
			(at 0 0 270)
			(layer "F.Fab")
			(effects
				(font
					(size 1.27 1.27)
				)
			)
		)
		(duplicate_pad_numbers_are_jumpers no)
		(fp_line
			(start -0.299974 0.150114)
			(end -0.299974 -0.150114)
			(stroke
				(width 0.1)
				(type default)
			)
			(layer "F.Fab")
		)
		(fp_line
			(start 0.299974 0.150114)
			(end -0.299974 0.150114)
			(stroke
				(width 0.1)
				(type default)
			)
			(layer "F.Fab")
		)
		(fp_line
			(start -0.299974 -0.150114)
			(end 0.299974 -0.150114)
			(stroke
				(width 0.1)
				(type default)
			)
			(layer "F.Fab")
		)
		(fp_line
			(start 0.299974 -0.150114)
			(end 0.299974 0.150114)
			(stroke
				(width 0.1)
				(type default)
			)
			(layer "F.Fab")
		)
		(pad "1" smd rect
			(at -0.2667 0 270)
			(size 0.3048 0.381)
			(layers "F.Cu" "F.Mask" "F.Paste")
			(net "P5E_CPU1_PE2_TX_C_DN<15>")
		)
		(pad "2" smd rect
			(at 0.2667 0 270)
			(size 0.3048 0.381)
			(layers "F.Cu" "F.Mask" "F.Paste")
			(net "P5E_CPU1_PE2_TX_DN<15>")
		)
	)
	(footprint ""
		(layer "F.Cu")
		(at 315.110622 -54.219348 180)
		(property "Reference" "R624"
			(at 0 0 180)
			(layer "F.SilkS")
			(hide yes)
			(effects
				(font
					(size 1.27 1.27)
				)
			)
		)
		(property "Value" ""
			(at 0 0 180)
			(layer "F.Fab")
			(effects
				(font
					(size 1.27 1.27)
				)
			)
		)
		(duplicate_pad_numbers_are_jumpers no)
		(fp_line
			(start 0.7874 0.4064)
			(end -0.7874 0.4064)
			(stroke
				(width 0.1524)
				(type default)
			)
			(layer "F.SilkS")
		)
		(fp_line
			(start 0.7874 -0.4064)
			(end 0.7874 0.4064)
			(stroke
				(width 0.1524)
				(type default)
			)
			(layer "F.SilkS")
		)
		(fp_line
			(start -0.7874 0.4064)
			(end -0.7874 -0.4064)
			(stroke
				(width 0.1524)
				(type default)
			)
			(layer "F.SilkS")
		)
		(fp_line
			(start -0.7874 -0.4064)
			(end 0.7874 -0.4064)
			(stroke
				(width 0.1524)
				(type default)
			)
			(layer "F.SilkS")
		)
		(fp_line
			(start 0.67945 0.3048)
			(end 0.120396 0.3048)
			(stroke
				(width 0.1)
				(type default)
			)
			(layer "F.Fab")
		)
		(fp_line
			(start 0.67945 -0.3048)
			(end 0.67945 0.3048)
			(stroke
				(width 0.1)
				(type default)
			)
			(layer "F.Fab")
		)
		(fp_line
			(start 0.12065 -0.2794)
			(end 0.12065 -0.3048)
			(stroke
				(width 0.1)
				(type default)
			)
			(layer "F.Fab")
		)
		(fp_line
			(start 0.12065 -0.3048)
			(end 0.67945 -0.3048)
			(stroke
				(width 0.1)
				(type default)
			)
			(layer "F.Fab")
		)
		(fp_line
			(start 0.120396 0.3048)
			(end 0.120396 0.2794)
			(stroke
				(width 0.1)
				(type default)
			)
			(layer "F.Fab")
		)
		(fp_line
			(start 0.120396 0.2794)
			(end -0.12065 0.2794)
			(stroke
				(width 0.1)
				(type default)
			)
			(layer "F.Fab")
		)
		(fp_line
			(start -0.12065 0.3048)
			(end -0.67945 0.3048)
			(stroke
				(width 0.1)
				(type default)
			)
			(layer "F.Fab")
		)
		(fp_line
			(start -0.12065 0.2794)
			(end -0.12065 0.3048)
			(stroke
				(width 0.1)
				(type default)
			)
			(layer "F.Fab")
		)
		(fp_line
			(start -0.12065 -0.2794)
			(end 0.12065 -0.2794)
			(stroke
				(width 0.1)
				(type default)
			)
			(layer "F.Fab")
		)
		(fp_line
			(start -0.12065 -0.305054)
			(end -0.12065 -0.2794)
			(stroke
				(width 0.1)
				(type default)
			)
			(layer "F.Fab")
		)
		(fp_line
			(start -0.67945 0.3048)
			(end -0.67945 -0.305054)
			(stroke
				(width 0.1)
				(type default)
			)
			(layer "F.Fab")
		)
		(fp_line
			(start -0.67945 -0.305054)
			(end -0.12065 -0.305054)
			(stroke
				(width 0.1)
				(type default)
			)
			(layer "F.Fab")
		)
		(pad "1" smd circle
			(at -0.40005 0 180)
			(size 0 0)
			(layers "F.Cu" "F.Mask" "F.Paste")
			(net "FM_PCH_XTALSEL")
		)
		(pad "2" smd circle
			(at 0.40005 0 180)
			(size 0 0)
			(layers "F.Cu" "F.Mask" "F.Paste")
			(net "GND")
		)
	)
	(footprint ""
		(layer "F.Cu")
		(at 444.85814 -39.512748)
		(property "Reference" "U240"
			(at -2.3876 -2.250948 0)
			(unlocked yes)
			(layer "F.SilkS")
			(effects
				(font
					(size 0.7874 0.5842)
					(thickness 0.1524)
				)
				(justify left)
			)
		)
		(property "Value" ""
			(at 0 0 0)
			(layer "F.Fab")
			(effects
				(font
					(size 1.27 1.27)
				)
			)
		)
		(duplicate_pad_numbers_are_jumpers no)
		(fp_line
			(start -1.207008 -1.549908)
			(end -1.207008 1.549908)
			(stroke
				(width 0.1524)
				(type default)
			)
			(layer "F.SilkS")
		)
		(fp_line
			(start -1.207008 1.549908)
			(end 1.207008 1.549908)
			(stroke
				(width 0.1524)
				(type default)
			)
			(layer "F.SilkS")
		)
		(fp_line
			(start -0.762508 -1.549908)
			(end -1.207008 -1.549908)
			(stroke
				(width 0.1524)
				(type default)
			)
			(layer "F.SilkS")
		)
		(fp_line
			(start 0 -0.635)
			(end -0.762508 -1.549908)
			(stroke
				(width 0.1524)
				(type default)
			)
			(layer "F.SilkS")
		)
		(fp_line
			(start 0.762508 -1.549908)
			(end 0 -0.635)
			(stroke
				(width 0.1524)
				(type default)
			)
			(layer "F.SilkS")
		)
		(fp_line
			(start 1.207008 -1.549908)
			(end 0.762508 -1.549908)
			(stroke
				(width 0.1524)
				(type default)
			)
			(layer "F.SilkS")
		)
		(fp_line
			(start 1.207008 1.549908)
			(end 1.207008 -1.549908)
			(stroke
				(width 0.1524)
				(type default)
			)
			(layer "F.SilkS")
		)
		(fp_poly
			(pts
				(xy -3.4036 -1.53289) (xy -2.3876 -1.02489) (xy -3.4036 -0.51689)
			)
			(stroke
				(width 0)
				(type default)
			)
			(fill yes)
			(layer "F.SilkS")
		)
		(fp_line
			(start -1.549908 -1.549908)
			(end -1.549908 1.549908)
			(stroke
				(width 0.1)
				(type default)
			)
			(layer "F.Fab")
		)
		(fp_line
			(start -1.549908 1.549908)
			(end 1.549908 1.549908)
			(stroke
				(width 0.1)
				(type default)
			)
			(layer "F.Fab")
		)
		(fp_line
			(start 1.549908 -1.549908)
			(end -1.549908 -1.549908)
			(stroke
				(width 0.1)
				(type default)
			)
			(layer "F.Fab")
		)
		(fp_line
			(start 1.549908 1.549908)
			(end 1.549908 -1.549908)
			(stroke
				(width 0.1)
				(type default)
			)
			(layer "F.Fab")
		)
		(fp_poly
			(pts
				(xy -3.4036 -1.53289) (xy -3.4036 -0.51689) (xy -2.3876 -1.02489)
			)
			(stroke
				(width 0)
				(type default)
			)
			(fill yes)
			(layer "F.Fab")
		)
		(pad "1" smd rect
			(at -1.774952 -1.02489 270)
			(size 0.508 0.8636)
			(layers "F.Cu" "F.Mask" "F.Paste")
			(net "OCP_SFF_PRSNT0_R_N")
		)
		(pad "2" smd rect
			(at -1.774952 -0.32512 270)
			(size 0.4064 0.8636)
			(layers "F.Cu" "F.Mask" "F.Paste")
			(net "OCP_SFF_PRSNT1_R_N")
		)
		(pad "3" smd rect
			(at -1.774952 0.32512 270)
			(size 0.4064 0.8636)
			(layers "F.Cu" "F.Mask" "F.Paste")
			(net "OCP_SFF_PRSNT23_R_N")
		)
		(pad "4" smd rect
			(at -1.774952 1.02489 270)
			(size 0.508 0.8636)
			(layers "F.Cu" "F.Mask" "F.Paste")
			(net "GND")
		)
		(pad "5" smd rect
			(at 1.774952 1.02489 270)
			(size 0.508 0.8636)
			(layers "F.Cu" "F.Mask" "F.Paste")
			(net "OCP_SFF_PRSNT2_R_N")
		)
		(pad "6" smd rect
			(at 1.774952 0.32512 270)
			(size 0.4064 0.8636)
			(layers "F.Cu" "F.Mask" "F.Paste")
			(net "OCP_SFF_PRSNT3_R_N")
		)
		(pad "7" smd rect
			(at 1.774952 -0.32512 270)
			(size 0.4064 0.8636)
			(layers "F.Cu" "F.Mask" "F.Paste")
			(net "OCP_SFF_PRSNT01_R_N")
		)
		(pad "8" smd rect
			(at 1.774952 -1.02489 270)
			(size 0.508 0.8636)
			(layers "F.Cu" "F.Mask" "F.Paste")
			(net "P3V3_AUX")
		)
	)
	(footprint ""
		(layer "F.Cu")
		(at 435.185566 -41.1226 180)
		(property "Reference" "R1320"
			(at 0 0 180)
			(layer "F.SilkS")
			(hide yes)
			(effects
				(font
					(size 1.27 1.27)
				)
			)
		)
		(property "Value" ""
			(at 0 0 180)
			(layer "F.Fab")
			(effects
				(font
					(size 1.27 1.27)
				)
			)
		)
		(duplicate_pad_numbers_are_jumpers no)
		(fp_line
			(start 0.7874 0.4064)
			(end -0.7874 0.4064)
			(stroke
				(width 0.1524)
				(type default)
			)
			(layer "F.SilkS")
		)
		(fp_line
			(start 0.7874 -0.4064)
			(end 0.7874 0.4064)
			(stroke
				(width 0.1524)
				(type default)
			)
			(layer "F.SilkS")
		)
		(fp_line
			(start -0.7874 0.4064)
			(end -0.7874 -0.4064)
			(stroke
				(width 0.1524)
				(type default)
			)
			(layer "F.SilkS")
		)
		(fp_line
			(start -0.7874 -0.4064)
			(end 0.7874 -0.4064)
			(stroke
				(width 0.1524)
				(type default)
			)
			(layer "F.SilkS")
		)
		(fp_line
			(start 0.67945 0.3048)
			(end 0.120396 0.3048)
			(stroke
				(width 0.1)
				(type default)
			)
			(layer "F.Fab")
		)
		(fp_line
			(start 0.67945 -0.3048)
			(end 0.67945 0.3048)
			(stroke
				(width 0.1)
				(type default)
			)
			(layer "F.Fab")
		)
		(fp_line
			(start 0.12065 -0.2794)
			(end 0.12065 -0.3048)
			(stroke
				(width 0.1)
				(type default)
			)
			(layer "F.Fab")
		)
		(fp_line
			(start 0.12065 -0.3048)
			(end 0.67945 -0.3048)
			(stroke
				(width 0.1)
				(type default)
			)
			(layer "F.Fab")
		)
		(fp_line
			(start 0.120396 0.3048)
			(end 0.120396 0.2794)
			(stroke
				(width 0.1)
				(type default)
			)
			(layer "F.Fab")
		)
		(fp_line
			(start 0.120396 0.2794)
			(end -0.12065 0.2794)
			(stroke
				(width 0.1)
				(type default)
			)
			(layer "F.Fab")
		)
		(fp_line
			(start -0.12065 0.3048)
			(end -0.67945 0.3048)
			(stroke
				(width 0.1)
				(type default)
			)
			(layer "F.Fab")
		)
		(fp_line
			(start -0.12065 0.2794)
			(end -0.12065 0.3048)
			(stroke
				(width 0.1)
				(type default)
			)
			(layer "F.Fab")
		)
		(fp_line
			(start -0.12065 -0.2794)
			(end 0.12065 -0.2794)
			(stroke
				(width 0.1)
				(type default)
			)
			(layer "F.Fab")
		)
		(fp_line
			(start -0.12065 -0.305054)
			(end -0.12065 -0.2794)
			(stroke
				(width 0.1)
				(type default)
			)
			(layer "F.Fab")
		)
		(fp_line
			(start -0.67945 0.3048)
			(end -0.67945 -0.305054)
			(stroke
				(width 0.1)
				(type default)
			)
			(layer "F.Fab")
		)
		(fp_line
			(start -0.67945 -0.305054)
			(end -0.12065 -0.305054)
			(stroke
				(width 0.1)
				(type default)
			)
			(layer "F.Fab")
		)
		(pad "1" smd circle
			(at -0.40005 0 180)
			(size 0 0)
			(layers "F.Cu" "F.Mask" "F.Paste")
			(net "P3V3_AUX")
		)
		(pad "2" smd circle
			(at 0.40005 0 180)
			(size 0 0)
			(layers "F.Cu" "F.Mask" "F.Paste")
			(net "PU_SWAP_OVERRIDE_N")
		)
	)
	(footprint ""
		(layer "F.Cu")
		(at 192.877186 -438.17413 -90)
		(property "Reference" "R2940"
			(at 0 0 270)
			(layer "F.SilkS")
			(hide yes)
			(effects
				(font
					(size 1.27 1.27)
				)
			)
		)
		(property "Value" ""
			(at 0 0 270)
			(layer "F.Fab")
			(effects
				(font
					(size 1.27 1.27)
				)
			)
		)
		(duplicate_pad_numbers_are_jumpers no)
		(fp_line
			(start -0.7874 0.4064)
			(end -0.7874 -0.4064)
			(stroke
				(width 0.1524)
				(type default)
			)
			(layer "F.SilkS")
		)
		(fp_line
			(start 0.7874 0.4064)
			(end -0.7874 0.4064)
			(stroke
				(width 0.1524)
				(type default)
			)
			(layer "F.SilkS")
		)
		(fp_line
			(start -0.7874 -0.4064)
			(end 0.7874 -0.4064)
			(stroke
				(width 0.1524)
				(type default)
			)
			(layer "F.SilkS")
		)
		(fp_line
			(start 0.7874 -0.4064)
			(end 0.7874 0.4064)
			(stroke
				(width 0.1524)
				(type default)
			)
			(layer "F.SilkS")
		)
		(fp_line
			(start -0.67945 0.3048)
			(end -0.67945 -0.305054)
			(stroke
				(width 0.1)
				(type default)
			)
			(layer "F.Fab")
		)
		(fp_line
			(start -0.12065 0.3048)
			(end -0.67945 0.3048)
			(stroke
				(width 0.1)
				(type default)
			)
			(layer "F.Fab")
		)
		(fp_line
			(start 0.120396 0.3048)
			(end 0.120396 0.2794)
			(stroke
				(width 0.1)
				(type default)
			)
			(layer "F.Fab")
		)
		(fp_line
			(start 0.67945 0.3048)
			(end 0.120396 0.3048)
			(stroke
				(width 0.1)
				(type default)
			)
			(layer "F.Fab")
		)
		(fp_line
			(start -0.12065 0.2794)
			(end -0.12065 0.3048)
			(stroke
				(width 0.1)
				(type default)
			)
			(layer "F.Fab")
		)
		(fp_line
			(start 0.120396 0.2794)
			(end -0.12065 0.2794)
			(stroke
				(width 0.1)
				(type default)
			)
			(layer "F.Fab")
		)
		(fp_line
			(start -0.12065 -0.2794)
			(end 0.12065 -0.2794)
			(stroke
				(width 0.1)
				(type default)
			)
			(layer "F.Fab")
		)
		(fp_line
			(start 0.12065 -0.2794)
			(end 0.12065 -0.3048)
			(stroke
				(width 0.1)
				(type default)
			)
			(layer "F.Fab")
		)
		(fp_line
			(start 0.12065 -0.3048)
			(end 0.67945 -0.3048)
			(stroke
				(width 0.1)
				(type default)
			)
			(layer "F.Fab")
		)
		(fp_line
			(start 0.67945 -0.3048)
			(end 0.67945 0.3048)
			(stroke
				(width 0.1)
				(type default)
			)
			(layer "F.Fab")
		)
		(fp_line
			(start -0.67945 -0.305054)
			(end -0.12065 -0.305054)
			(stroke
				(width 0.1)
				(type default)
			)
			(layer "F.Fab")
		)
		(fp_line
			(start -0.12065 -0.305054)
			(end -0.12065 -0.2794)
			(stroke
				(width 0.1)
				(type default)
			)
			(layer "F.Fab")
		)
		(pad "1" smd circle
			(at -0.40005 0 270)
			(size 0 0)
			(layers "F.Cu" "F.Mask" "F.Paste")
			(net "P3V3_AUX")
		)
		(pad "2" smd circle
			(at 0.40005 0 270)
			(size 0 0)
			(layers "F.Cu" "F.Mask" "F.Paste")
			(net "FM_GPU_HSC_EN")
		)
	)
	(footprint ""
		(layer "F.Cu")
		(at 12.778232 -15.320518 90)
		(property "Reference" "R3177"
			(at 0 0 90)
			(layer "F.SilkS")
			(hide yes)
			(effects
				(font
					(size 1.27 1.27)
				)
			)
		)
		(property "Value" ""
			(at 0 0 90)
			(layer "F.Fab")
			(effects
				(font
					(size 1.27 1.27)
				)
			)
		)
		(duplicate_pad_numbers_are_jumpers no)
		(fp_line
			(start 0.7874 -0.4064)
			(end 0.7874 0.4064)
			(stroke
				(width 0.1524)
				(type default)
			)
			(layer "F.SilkS")
		)
		(fp_line
			(start -0.7874 -0.4064)
			(end 0.7874 -0.4064)
			(stroke
				(width 0.1524)
				(type default)
			)
			(layer "F.SilkS")
		)
		(fp_line
			(start 0.7874 0.4064)
			(end -0.7874 0.4064)
			(stroke
				(width 0.1524)
				(type default)
			)
			(layer "F.SilkS")
		)
		(fp_line
			(start -0.7874 0.4064)
			(end -0.7874 -0.4064)
			(stroke
				(width 0.1524)
				(type default)
			)
			(layer "F.SilkS")
		)
		(fp_line
			(start -0.12065 -0.305054)
			(end -0.12065 -0.2794)
			(stroke
				(width 0.1)
				(type default)
			)
			(layer "F.Fab")
		)
		(fp_line
			(start -0.67945 -0.305054)
			(end -0.12065 -0.305054)
			(stroke
				(width 0.1)
				(type default)
			)
			(layer "F.Fab")
		)
		(fp_line
			(start 0.67945 -0.3048)
			(end 0.67945 0.3048)
			(stroke
				(width 0.1)
				(type default)
			)
			(layer "F.Fab")
		)
		(fp_line
			(start 0.12065 -0.3048)
			(end 0.67945 -0.3048)
			(stroke
				(width 0.1)
				(type default)
			)
			(layer "F.Fab")
		)
		(fp_line
			(start 0.12065 -0.2794)
			(end 0.12065 -0.3048)
			(stroke
				(width 0.1)
				(type default)
			)
			(layer "F.Fab")
		)
		(fp_line
			(start -0.12065 -0.2794)
			(end 0.12065 -0.2794)
			(stroke
				(width 0.1)
				(type default)
			)
			(layer "F.Fab")
		)
		(fp_line
			(start 0.120396 0.2794)
			(end -0.12065 0.2794)
			(stroke
				(width 0.1)
				(type default)
			)
			(layer "F.Fab")
		)
		(fp_line
			(start -0.12065 0.2794)
			(end -0.12065 0.3048)
			(stroke
				(width 0.1)
				(type default)
			)
			(layer "F.Fab")
		)
		(fp_line
			(start 0.67945 0.3048)
			(end 0.120396 0.3048)
			(stroke
				(width 0.1)
				(type default)
			)
			(layer "F.Fab")
		)
		(fp_line
			(start 0.120396 0.3048)
			(end 0.120396 0.2794)
			(stroke
				(width 0.1)
				(type default)
			)
			(layer "F.Fab")
		)
		(fp_line
			(start -0.12065 0.3048)
			(end -0.67945 0.3048)
			(stroke
				(width 0.1)
				(type default)
			)
			(layer "F.Fab")
		)
		(fp_line
			(start -0.67945 0.3048)
			(end -0.67945 -0.305054)
			(stroke
				(width 0.1)
				(type default)
			)
			(layer "F.Fab")
		)
		(pad "1" smd circle
			(at -0.40005 0 90)
			(size 0 0)
			(layers "F.Cu" "F.Mask" "F.Paste")
			(net "USB2_5_R1_DN")
		)
		(pad "2" smd circle
			(at 0.40005 0 90)
			(size 0 0)
			(layers "F.Cu" "F.Mask" "F.Paste")
			(net "USB2_5_DN")
		)
	)
	(footprint ""
		(layer "F.Cu")
		(at 15.197582 -410.802836 90)
		(property "Reference" "R2922"
			(at 0 0 90)
			(layer "F.SilkS")
			(hide yes)
			(effects
				(font
					(size 1.27 1.27)
				)
			)
		)
		(property "Value" ""
			(at 0 0 90)
			(layer "F.Fab")
			(effects
				(font
					(size 1.27 1.27)
				)
			)
		)
		(duplicate_pad_numbers_are_jumpers no)
		(fp_line
			(start 0.7874 -0.4064)
			(end 0.7874 0.4064)
			(stroke
				(width 0.1524)
				(type default)
			)
			(layer "F.SilkS")
		)
		(fp_line
			(start -0.7874 -0.4064)
			(end 0.7874 -0.4064)
			(stroke
				(width 0.1524)
				(type default)
			)
			(layer "F.SilkS")
		)
		(fp_line
			(start 0.7874 0.4064)
			(end -0.7874 0.4064)
			(stroke
				(width 0.1524)
				(type default)
			)
			(layer "F.SilkS")
		)
		(fp_line
			(start -0.7874 0.4064)
			(end -0.7874 -0.4064)
			(stroke
				(width 0.1524)
				(type default)
			)
			(layer "F.SilkS")
		)
		(fp_line
			(start -0.12065 -0.305054)
			(end -0.12065 -0.2794)
			(stroke
				(width 0.1)
				(type default)
			)
			(layer "F.Fab")
		)
		(fp_line
			(start -0.67945 -0.305054)
			(end -0.12065 -0.305054)
			(stroke
				(width 0.1)
				(type default)
			)
			(layer "F.Fab")
		)
		(fp_line
			(start 0.67945 -0.3048)
			(end 0.67945 0.3048)
			(stroke
				(width 0.1)
				(type default)
			)
			(layer "F.Fab")
		)
		(fp_line
			(start 0.12065 -0.3048)
			(end 0.67945 -0.3048)
			(stroke
				(width 0.1)
				(type default)
			)
			(layer "F.Fab")
		)
		(fp_line
			(start 0.12065 -0.2794)
			(end 0.12065 -0.3048)
			(stroke
				(width 0.1)
				(type default)
			)
			(layer "F.Fab")
		)
		(fp_line
			(start -0.12065 -0.2794)
			(end 0.12065 -0.2794)
			(stroke
				(width 0.1)
				(type default)
			)
			(layer "F.Fab")
		)
		(fp_line
			(start 0.120396 0.2794)
			(end -0.12065 0.2794)
			(stroke
				(width 0.1)
				(type default)
			)
			(layer "F.Fab")
		)
		(fp_line
			(start -0.12065 0.2794)
			(end -0.12065 0.3048)
			(stroke
				(width 0.1)
				(type default)
			)
			(layer "F.Fab")
		)
		(fp_line
			(start 0.67945 0.3048)
			(end 0.120396 0.3048)
			(stroke
				(width 0.1)
				(type default)
			)
			(layer "F.Fab")
		)
		(fp_line
			(start 0.120396 0.3048)
			(end 0.120396 0.2794)
			(stroke
				(width 0.1)
				(type default)
			)
			(layer "F.Fab")
		)
		(fp_line
			(start -0.12065 0.3048)
			(end -0.67945 0.3048)
			(stroke
				(width 0.1)
				(type default)
			)
			(layer "F.Fab")
		)
		(fp_line
			(start -0.67945 0.3048)
			(end -0.67945 -0.305054)
			(stroke
				(width 0.1)
				(type default)
			)
			(layer "F.Fab")
		)
		(pad "1" smd circle
			(at -0.40005 0 90)
			(size 0 0)
			(layers "F.Cu" "F.Mask" "F.Paste")
			(net "RST_SMB_SWITCH_N")
		)
		(pad "2" smd circle
			(at 0.40005 0 90)
			(size 0 0)
			(layers "F.Cu" "F.Mask" "F.Paste")
			(net "PU_RST_SMB_U181_N")
		)
	)
	(footprint ""
		(layer "F.Cu")
		(at 51.593496 -116.52377)
		(property "Reference" "R3705"
			(at 0 0 0)
			(layer "F.SilkS")
			(hide yes)
			(effects
				(font
					(size 1.27 1.27)
				)
			)
		)
		(property "Value" ""
			(at 0 0 0)
			(layer "F.Fab")
			(effects
				(font
					(size 1.27 1.27)
				)
			)
		)
		(duplicate_pad_numbers_are_jumpers no)
		(fp_line
			(start -0.7874 -0.4064)
			(end 0.7874 -0.4064)
			(stroke
				(width 0.1524)
				(type default)
			)
			(layer "F.SilkS")
		)
		(fp_line
			(start -0.7874 0.4064)
			(end -0.7874 -0.4064)
			(stroke
				(width 0.1524)
				(type default)
			)
			(layer "F.SilkS")
		)
		(fp_line
			(start 0.7874 -0.4064)
			(end 0.7874 0.4064)
			(stroke
				(width 0.1524)
				(type default)
			)
			(layer "F.SilkS")
		)
		(fp_line
			(start 0.7874 0.4064)
			(end -0.7874 0.4064)
			(stroke
				(width 0.1524)
				(type default)
			)
			(layer "F.SilkS")
		)
		(fp_line
			(start -0.67945 -0.305054)
			(end -0.12065 -0.305054)
			(stroke
				(width 0.1)
				(type default)
			)
			(layer "F.Fab")
		)
		(fp_line
			(start -0.67945 0.3048)
			(end -0.67945 -0.305054)
			(stroke
				(width 0.1)
				(type default)
			)
			(layer "F.Fab")
		)
		(fp_line
			(start -0.12065 -0.305054)
			(end -0.12065 -0.2794)
			(stroke
				(width 0.1)
				(type default)
			)
			(layer "F.Fab")
		)
		(fp_line
			(start -0.12065 -0.2794)
			(end 0.12065 -0.2794)
			(stroke
				(width 0.1)
				(type default)
			)
			(layer "F.Fab")
		)
		(fp_line
			(start -0.12065 0.2794)
			(end -0.12065 0.3048)
			(stroke
				(width 0.1)
				(type default)
			)
			(layer "F.Fab")
		)
		(fp_line
			(start -0.12065 0.3048)
			(end -0.67945 0.3048)
			(stroke
				(width 0.1)
				(type default)
			)
			(layer "F.Fab")
		)
		(fp_line
			(start 0.120396 0.2794)
			(end -0.12065 0.2794)
			(stroke
				(width 0.1)
				(type default)
			)
			(layer "F.Fab")
		)
		(fp_line
			(start 0.120396 0.3048)
			(end 0.120396 0.2794)
			(stroke
				(width 0.1)
				(type default)
			)
			(layer "F.Fab")
		)
		(fp_line
			(start 0.12065 -0.3048)
			(end 0.67945 -0.3048)
			(stroke
				(width 0.1)
				(type default)
			)
			(layer "F.Fab")
		)
		(fp_line
			(start 0.12065 -0.2794)
			(end 0.12065 -0.3048)
			(stroke
				(width 0.1)
				(type default)
			)
			(layer "F.Fab")
		)
		(fp_line
			(start 0.67945 -0.3048)
			(end 0.67945 0.3048)
			(stroke
				(width 0.1)
				(type default)
			)
			(layer "F.Fab")
		)
		(fp_line
			(start 0.67945 0.3048)
			(end 0.120396 0.3048)
			(stroke
				(width 0.1)
				(type default)
			)
			(layer "F.Fab")
		)
		(pad "1" smd circle
			(at -0.40005 0)
			(size 0 0)
			(layers "F.Cu" "F.Mask" "F.Paste")
			(net "P3V3_AUX")
		)
		(pad "2" smd circle
			(at 0.40005 0)
			(size 0 0)
			(layers "F.Cu" "F.Mask" "F.Paste")
			(net "RST_SMB_SWITCH_N")
		)
	)
	(footprint ""
		(layer "F.Cu")
		(at 303.08804 -362.843826 -90)
		(property "Reference" "PC605_P0_2"
			(at 0 0 270)
			(layer "F.SilkS")
			(hide yes)
			(effects
				(font
					(size 1.27 1.27)
				)
			)
		)
		(property "Value" ""
			(at 0 0 270)
			(layer "F.Fab")
			(effects
				(font
					(size 1.27 1.27)
				)
			)
		)
		(duplicate_pad_numbers_are_jumpers no)
		(fp_line
			(start -0.7874 0.4064)
			(end -0.7874 -0.4064)
			(stroke
				(width 0.1524)
				(type default)
			)
			(layer "F.SilkS")
		)
		(fp_line
			(start 0.7874 0.4064)
			(end -0.7874 0.4064)
			(stroke
				(width 0.1524)
				(type default)
			)
			(layer "F.SilkS")
		)
		(fp_line
			(start -0.7874 -0.4064)
			(end 0.7874 -0.4064)
			(stroke
				(width 0.1524)
				(type default)
			)
			(layer "F.SilkS")
		)
		(fp_line
			(start 0.7874 -0.4064)
			(end 0.7874 0.4064)
			(stroke
				(width 0.1524)
				(type default)
			)
			(layer "F.SilkS")
		)
		(fp_line
			(start -0.67945 0.3048)
			(end -0.67945 -0.305054)
			(stroke
				(width 0.1)
				(type default)
			)
			(layer "F.Fab")
		)
		(fp_line
			(start -0.12065 0.3048)
			(end -0.67945 0.3048)
			(stroke
				(width 0.1)
				(type default)
			)
			(layer "F.Fab")
		)
		(fp_line
			(start 0.120396 0.3048)
			(end 0.120396 0.2794)
			(stroke
				(width 0.1)
				(type default)
			)
			(layer "F.Fab")
		)
		(fp_line
			(start 0.67945 0.3048)
			(end 0.120396 0.3048)
			(stroke
				(width 0.1)
				(type default)
			)
			(layer "F.Fab")
		)
		(fp_line
			(start -0.12065 0.2794)
			(end -0.12065 0.3048)
			(stroke
				(width 0.1)
				(type default)
			)
			(layer "F.Fab")
		)
		(fp_line
			(start 0.120396 0.2794)
			(end -0.12065 0.2794)
			(stroke
				(width 0.1)
				(type default)
			)
			(layer "F.Fab")
		)
		(fp_line
			(start -0.12065 -0.2794)
			(end 0.12065 -0.2794)
			(stroke
				(width 0.1)
				(type default)
			)
			(layer "F.Fab")
		)
		(fp_line
			(start 0.12065 -0.2794)
			(end 0.12065 -0.3048)
			(stroke
				(width 0.1)
				(type default)
			)
			(layer "F.Fab")
		)
		(fp_line
			(start 0.12065 -0.3048)
			(end 0.67945 -0.3048)
			(stroke
				(width 0.1)
				(type default)
			)
			(layer "F.Fab")
		)
		(fp_line
			(start 0.67945 -0.3048)
			(end 0.67945 0.3048)
			(stroke
				(width 0.1)
				(type default)
			)
			(layer "F.Fab")
		)
		(fp_line
			(start -0.67945 -0.305054)
			(end -0.12065 -0.305054)
			(stroke
				(width 0.1)
				(type default)
			)
			(layer "F.Fab")
		)
		(fp_line
			(start -0.12065 -0.305054)
			(end -0.12065 -0.2794)
			(stroke
				(width 0.1)
				(type default)
			)
			(layer "F.Fab")
		)
		(pad "1" smd circle
			(at -0.40005 0 270)
			(size 0 0)
			(layers "F.Cu" "F.Mask" "F.Paste")
			(net "SW_P12V_PVCCFA_EHV_FIVRA_CPU0_L")
		)
		(pad "2" smd circle
			(at 0.40005 0 270)
			(size 0 0)
			(layers "F.Cu" "F.Mask" "F.Paste")
			(net "GND")
		)
	)
	(footprint ""
		(layer "F.Cu")
		(at 52.480972 -435.360318 180)
		(property "Reference" "R3524"
			(at 0 0 180)
			(layer "F.SilkS")
			(hide yes)
			(effects
				(font
					(size 1.27 1.27)
				)
			)
		)
		(property "Value" ""
			(at 0 0 180)
			(layer "F.Fab")
			(effects
				(font
					(size 1.27 1.27)
				)
			)
		)
		(duplicate_pad_numbers_are_jumpers no)
		(fp_line
			(start 0.7874 0.4064)
			(end -0.7874 0.4064)
			(stroke
				(width 0.1524)
				(type default)
			)
			(layer "F.SilkS")
		)
		(fp_line
			(start 0.7874 -0.4064)
			(end 0.7874 0.4064)
			(stroke
				(width 0.1524)
				(type default)
			)
			(layer "F.SilkS")
		)
		(fp_line
			(start -0.7874 0.4064)
			(end -0.7874 -0.4064)
			(stroke
				(width 0.1524)
				(type default)
			)
			(layer "F.SilkS")
		)
		(fp_line
			(start -0.7874 -0.4064)
			(end 0.7874 -0.4064)
			(stroke
				(width 0.1524)
				(type default)
			)
			(layer "F.SilkS")
		)
		(fp_line
			(start 0.67945 0.3048)
			(end 0.120396 0.3048)
			(stroke
				(width 0.1)
				(type default)
			)
			(layer "F.Fab")
		)
		(fp_line
			(start 0.67945 -0.3048)
			(end 0.67945 0.3048)
			(stroke
				(width 0.1)
				(type default)
			)
			(layer "F.Fab")
		)
		(fp_line
			(start 0.12065 -0.2794)
			(end 0.12065 -0.3048)
			(stroke
				(width 0.1)
				(type default)
			)
			(layer "F.Fab")
		)
		(fp_line
			(start 0.12065 -0.3048)
			(end 0.67945 -0.3048)
			(stroke
				(width 0.1)
				(type default)
			)
			(layer "F.Fab")
		)
		(fp_line
			(start 0.120396 0.3048)
			(end 0.120396 0.2794)
			(stroke
				(width 0.1)
				(type default)
			)
			(layer "F.Fab")
		)
		(fp_line
			(start 0.120396 0.2794)
			(end -0.12065 0.2794)
			(stroke
				(width 0.1)
				(type default)
			)
			(layer "F.Fab")
		)
		(fp_line
			(start -0.12065 0.3048)
			(end -0.67945 0.3048)
			(stroke
				(width 0.1)
				(type default)
			)
			(layer "F.Fab")
		)
		(fp_line
			(start -0.12065 0.2794)
			(end -0.12065 0.3048)
			(stroke
				(width 0.1)
				(type default)
			)
			(layer "F.Fab")
		)
		(fp_line
			(start -0.12065 -0.2794)
			(end 0.12065 -0.2794)
			(stroke
				(width 0.1)
				(type default)
			)
			(layer "F.Fab")
		)
		(fp_line
			(start -0.12065 -0.305054)
			(end -0.12065 -0.2794)
			(stroke
				(width 0.1)
				(type default)
			)
			(layer "F.Fab")
		)
		(fp_line
			(start -0.67945 0.3048)
			(end -0.67945 -0.305054)
			(stroke
				(width 0.1)
				(type default)
			)
			(layer "F.Fab")
		)
		(fp_line
			(start -0.67945 -0.305054)
			(end -0.12065 -0.305054)
			(stroke
				(width 0.1)
				(type default)
			)
			(layer "F.Fab")
		)
		(pad "1" smd circle
			(at -0.40005 0 180)
			(size 0 0)
			(layers "F.Cu" "F.Mask" "F.Paste")
			(net "P3V3_AUX")
		)
		(pad "2" smd circle
			(at 0.40005 0 180)
			(size 0 0)
			(layers "F.Cu" "F.Mask" "F.Paste")
			(net "SMB_1_BMC_GPU_BUF_R_SDA")
		)
	)
	(footprint ""
		(layer "F.Cu")
		(at 406.124664 -360.722926)
		(property "Reference" "R332"
			(at 0 0 0)
			(layer "F.SilkS")
			(hide yes)
			(effects
				(font
					(size 1.27 1.27)
				)
			)
		)
		(property "Value" ""
			(at 0 0 0)
			(layer "F.Fab")
			(effects
				(font
					(size 1.27 1.27)
				)
			)
		)
		(duplicate_pad_numbers_are_jumpers no)
		(fp_line
			(start -0.7874 -0.4064)
			(end 0.7874 -0.4064)
			(stroke
				(width 0.1524)
				(type default)
			)
			(layer "F.SilkS")
		)
		(fp_line
			(start -0.7874 0.4064)
			(end -0.7874 -0.4064)
			(stroke
				(width 0.1524)
				(type default)
			)
			(layer "F.SilkS")
		)
		(fp_line
			(start 0.7874 -0.4064)
			(end 0.7874 0.4064)
			(stroke
				(width 0.1524)
				(type default)
			)
			(layer "F.SilkS")
		)
		(fp_line
			(start 0.7874 0.4064)
			(end -0.7874 0.4064)
			(stroke
				(width 0.1524)
				(type default)
			)
			(layer "F.SilkS")
		)
		(fp_line
			(start -0.67945 -0.305054)
			(end -0.12065 -0.305054)
			(stroke
				(width 0.1)
				(type default)
			)
			(layer "F.Fab")
		)
		(fp_line
			(start -0.67945 0.3048)
			(end -0.67945 -0.305054)
			(stroke
				(width 0.1)
				(type default)
			)
			(layer "F.Fab")
		)
		(fp_line
			(start -0.12065 -0.305054)
			(end -0.12065 -0.2794)
			(stroke
				(width 0.1)
				(type default)
			)
			(layer "F.Fab")
		)
		(fp_line
			(start -0.12065 -0.2794)
			(end 0.12065 -0.2794)
			(stroke
				(width 0.1)
				(type default)
			)
			(layer "F.Fab")
		)
		(fp_line
			(start -0.12065 0.2794)
			(end -0.12065 0.3048)
			(stroke
				(width 0.1)
				(type default)
			)
			(layer "F.Fab")
		)
		(fp_line
			(start -0.12065 0.3048)
			(end -0.67945 0.3048)
			(stroke
				(width 0.1)
				(type default)
			)
			(layer "F.Fab")
		)
		(fp_line
			(start 0.120396 0.2794)
			(end -0.12065 0.2794)
			(stroke
				(width 0.1)
				(type default)
			)
			(layer "F.Fab")
		)
		(fp_line
			(start 0.120396 0.3048)
			(end 0.120396 0.2794)
			(stroke
				(width 0.1)
				(type default)
			)
			(layer "F.Fab")
		)
		(fp_line
			(start 0.12065 -0.3048)
			(end 0.67945 -0.3048)
			(stroke
				(width 0.1)
				(type default)
			)
			(layer "F.Fab")
		)
		(fp_line
			(start 0.12065 -0.2794)
			(end 0.12065 -0.3048)
			(stroke
				(width 0.1)
				(type default)
			)
			(layer "F.Fab")
		)
		(fp_line
			(start 0.67945 -0.3048)
			(end 0.67945 0.3048)
			(stroke
				(width 0.1)
				(type default)
			)
			(layer "F.Fab")
		)
		(fp_line
			(start 0.67945 0.3048)
			(end 0.120396 0.3048)
			(stroke
				(width 0.1)
				(type default)
			)
			(layer "F.Fab")
		)
		(pad "1" smd circle
			(at -0.40005 0)
			(size 0 0)
			(layers "F.Cu" "F.Mask" "F.Paste")
			(net "PD_PIROM_CPU0_ADDR2")
		)
		(pad "2" smd circle
			(at 0.40005 0)
			(size 0 0)
			(layers "F.Cu" "F.Mask" "F.Paste")
			(net "GND")
		)
	)
	(footprint ""
		(layer "F.Cu")
		(at 274.271486 -394.17117)
		(property "Reference" "PR2531"
			(at 0 0 0)
			(layer "F.SilkS")
			(hide yes)
			(effects
				(font
					(size 1.27 1.27)
				)
			)
		)
		(property "Value" ""
			(at 0 0 0)
			(layer "F.Fab")
			(effects
				(font
					(size 1.27 1.27)
				)
			)
		)
		(duplicate_pad_numbers_are_jumpers no)
		(fp_line
			(start -0.7874 -0.4064)
			(end 0.7874 -0.4064)
			(stroke
				(width 0.1524)
				(type default)
			)
			(layer "F.SilkS")
		)
		(fp_line
			(start -0.7874 0.4064)
			(end -0.7874 -0.4064)
			(stroke
				(width 0.1524)
				(type default)
			)
			(layer "F.SilkS")
		)
		(fp_line
			(start 0.7874 -0.4064)
			(end 0.7874 0.4064)
			(stroke
				(width 0.1524)
				(type default)
			)
			(layer "F.SilkS")
		)
		(fp_line
			(start 0.7874 0.4064)
			(end -0.7874 0.4064)
			(stroke
				(width 0.1524)
				(type default)
			)
			(layer "F.SilkS")
		)
		(fp_line
			(start -0.67945 -0.305054)
			(end -0.12065 -0.305054)
			(stroke
				(width 0.1)
				(type default)
			)
			(layer "F.Fab")
		)
		(fp_line
			(start -0.67945 0.3048)
			(end -0.67945 -0.305054)
			(stroke
				(width 0.1)
				(type default)
			)
			(layer "F.Fab")
		)
		(fp_line
			(start -0.12065 -0.305054)
			(end -0.12065 -0.2794)
			(stroke
				(width 0.1)
				(type default)
			)
			(layer "F.Fab")
		)
		(fp_line
			(start -0.12065 -0.2794)
			(end 0.12065 -0.2794)
			(stroke
				(width 0.1)
				(type default)
			)
			(layer "F.Fab")
		)
		(fp_line
			(start -0.12065 0.2794)
			(end -0.12065 0.3048)
			(stroke
				(width 0.1)
				(type default)
			)
			(layer "F.Fab")
		)
		(fp_line
			(start -0.12065 0.3048)
			(end -0.67945 0.3048)
			(stroke
				(width 0.1)
				(type default)
			)
			(layer "F.Fab")
		)
		(fp_line
			(start 0.120396 0.2794)
			(end -0.12065 0.2794)
			(stroke
				(width 0.1)
				(type default)
			)
			(layer "F.Fab")
		)
		(fp_line
			(start 0.120396 0.3048)
			(end 0.120396 0.2794)
			(stroke
				(width 0.1)
				(type default)
			)
			(layer "F.Fab")
		)
		(fp_line
			(start 0.12065 -0.3048)
			(end 0.67945 -0.3048)
			(stroke
				(width 0.1)
				(type default)
			)
			(layer "F.Fab")
		)
		(fp_line
			(start 0.12065 -0.2794)
			(end 0.12065 -0.3048)
			(stroke
				(width 0.1)
				(type default)
			)
			(layer "F.Fab")
		)
		(fp_line
			(start 0.67945 -0.3048)
			(end 0.67945 0.3048)
			(stroke
				(width 0.1)
				(type default)
			)
			(layer "F.Fab")
		)
		(fp_line
			(start 0.67945 0.3048)
			(end 0.120396 0.3048)
			(stroke
				(width 0.1)
				(type default)
			)
			(layer "F.Fab")
		)
		(pad "1" smd circle
			(at -0.40005 0)
			(size 0 0)
			(layers "F.Cu" "F.Mask" "F.Paste")
			(net "P12V_HSC_GATE_G4")
		)
		(pad "2" smd circle
			(at 0.40005 0)
			(size 0 0)
			(layers "F.Cu" "F.Mask" "F.Paste")
			(net "P12V_HSC_GATE2")
		)
	)
	(footprint ""
		(layer "F.Cu")
		(at 417.43757 -45.83684 180)
		(property "Reference" "C1172"
			(at 0 0 180)
			(layer "F.SilkS")
			(hide yes)
			(effects
				(font
					(size 1.27 1.27)
				)
			)
		)
		(property "Value" ""
			(at 0 0 180)
			(layer "F.Fab")
			(effects
				(font
					(size 1.27 1.27)
				)
			)
		)
		(duplicate_pad_numbers_are_jumpers no)
		(fp_line
			(start 0.7874 0.4064)
			(end -0.7874 0.4064)
			(stroke
				(width 0.1524)
				(type default)
			)
			(layer "F.SilkS")
		)
		(fp_line
			(start 0.7874 -0.4064)
			(end 0.7874 0.4064)
			(stroke
				(width 0.1524)
				(type default)
			)
			(layer "F.SilkS")
		)
		(fp_line
			(start -0.7874 0.4064)
			(end -0.7874 -0.4064)
			(stroke
				(width 0.1524)
				(type default)
			)
			(layer "F.SilkS")
		)
		(fp_line
			(start -0.7874 -0.4064)
			(end 0.7874 -0.4064)
			(stroke
				(width 0.1524)
				(type default)
			)
			(layer "F.SilkS")
		)
		(fp_line
			(start 0.67945 0.3048)
			(end 0.120396 0.3048)
			(stroke
				(width 0.1)
				(type default)
			)
			(layer "F.Fab")
		)
		(fp_line
			(start 0.67945 -0.3048)
			(end 0.67945 0.3048)
			(stroke
				(width 0.1)
				(type default)
			)
			(layer "F.Fab")
		)
		(fp_line
			(start 0.12065 -0.2794)
			(end 0.12065 -0.3048)
			(stroke
				(width 0.1)
				(type default)
			)
			(layer "F.Fab")
		)
		(fp_line
			(start 0.12065 -0.3048)
			(end 0.67945 -0.3048)
			(stroke
				(width 0.1)
				(type default)
			)
			(layer "F.Fab")
		)
		(fp_line
			(start 0.120396 0.3048)
			(end 0.120396 0.2794)
			(stroke
				(width 0.1)
				(type default)
			)
			(layer "F.Fab")
		)
		(fp_line
			(start 0.120396 0.2794)
			(end -0.12065 0.2794)
			(stroke
				(width 0.1)
				(type default)
			)
			(layer "F.Fab")
		)
		(fp_line
			(start -0.12065 0.3048)
			(end -0.67945 0.3048)
			(stroke
				(width 0.1)
				(type default)
			)
			(layer "F.Fab")
		)
		(fp_line
			(start -0.12065 0.2794)
			(end -0.12065 0.3048)
			(stroke
				(width 0.1)
				(type default)
			)
			(layer "F.Fab")
		)
		(fp_line
			(start -0.12065 -0.2794)
			(end 0.12065 -0.2794)
			(stroke
				(width 0.1)
				(type default)
			)
			(layer "F.Fab")
		)
		(fp_line
			(start -0.12065 -0.305054)
			(end -0.12065 -0.2794)
			(stroke
				(width 0.1)
				(type default)
			)
			(layer "F.Fab")
		)
		(fp_line
			(start -0.67945 0.3048)
			(end -0.67945 -0.305054)
			(stroke
				(width 0.1)
				(type default)
			)
			(layer "F.Fab")
		)
		(fp_line
			(start -0.67945 -0.305054)
			(end -0.12065 -0.305054)
			(stroke
				(width 0.1)
				(type default)
			)
			(layer "F.Fab")
		)
		(pad "1" smd circle
			(at -0.40005 0 180)
			(size 0 0)
			(layers "F.Cu" "F.Mask" "F.Paste")
			(net "P5V")
		)
		(pad "2" smd circle
			(at 0.40005 0 180)
			(size 0 0)
			(layers "F.Cu" "F.Mask" "F.Paste")
			(net "GND")
		)
	)
	(footprint ""
		(layer "F.Cu")
		(at 450.43725 -45.314362 180)
		(property "Reference" "R3500"
			(at 0 0 180)
			(layer "F.SilkS")
			(hide yes)
			(effects
				(font
					(size 1.27 1.27)
				)
			)
		)
		(property "Value" ""
			(at 0 0 180)
			(layer "F.Fab")
			(effects
				(font
					(size 1.27 1.27)
				)
			)
		)
		(duplicate_pad_numbers_are_jumpers no)
		(fp_line
			(start 0.7874 0.4064)
			(end -0.7874 0.4064)
			(stroke
				(width 0.1524)
				(type default)
			)
			(layer "F.SilkS")
		)
		(fp_line
			(start 0.7874 -0.4064)
			(end 0.7874 0.4064)
			(stroke
				(width 0.1524)
				(type default)
			)
			(layer "F.SilkS")
		)
		(fp_line
			(start -0.7874 0.4064)
			(end -0.7874 -0.4064)
			(stroke
				(width 0.1524)
				(type default)
			)
			(layer "F.SilkS")
		)
		(fp_line
			(start -0.7874 -0.4064)
			(end 0.7874 -0.4064)
			(stroke
				(width 0.1524)
				(type default)
			)
			(layer "F.SilkS")
		)
		(fp_line
			(start 0.67945 0.3048)
			(end 0.120396 0.3048)
			(stroke
				(width 0.1)
				(type default)
			)
			(layer "F.Fab")
		)
		(fp_line
			(start 0.67945 -0.3048)
			(end 0.67945 0.3048)
			(stroke
				(width 0.1)
				(type default)
			)
			(layer "F.Fab")
		)
		(fp_line
			(start 0.12065 -0.2794)
			(end 0.12065 -0.3048)
			(stroke
				(width 0.1)
				(type default)
			)
			(layer "F.Fab")
		)
		(fp_line
			(start 0.12065 -0.3048)
			(end 0.67945 -0.3048)
			(stroke
				(width 0.1)
				(type default)
			)
			(layer "F.Fab")
		)
		(fp_line
			(start 0.120396 0.3048)
			(end 0.120396 0.2794)
			(stroke
				(width 0.1)
				(type default)
			)
			(layer "F.Fab")
		)
		(fp_line
			(start 0.120396 0.2794)
			(end -0.12065 0.2794)
			(stroke
				(width 0.1)
				(type default)
			)
			(layer "F.Fab")
		)
		(fp_line
			(start -0.12065 0.3048)
			(end -0.67945 0.3048)
			(stroke
				(width 0.1)
				(type default)
			)
			(layer "F.Fab")
		)
		(fp_line
			(start -0.12065 0.2794)
			(end -0.12065 0.3048)
			(stroke
				(width 0.1)
				(type default)
			)
			(layer "F.Fab")
		)
		(fp_line
			(start -0.12065 -0.2794)
			(end 0.12065 -0.2794)
			(stroke
				(width 0.1)
				(type default)
			)
			(layer "F.Fab")
		)
		(fp_line
			(start -0.12065 -0.305054)
			(end -0.12065 -0.2794)
			(stroke
				(width 0.1)
				(type default)
			)
			(layer "F.Fab")
		)
		(fp_line
			(start -0.67945 0.3048)
			(end -0.67945 -0.305054)
			(stroke
				(width 0.1)
				(type default)
			)
			(layer "F.Fab")
		)
		(fp_line
			(start -0.67945 -0.305054)
			(end -0.12065 -0.305054)
			(stroke
				(width 0.1)
				(type default)
			)
			(layer "F.Fab")
		)
		(pad "1" smd circle
			(at -0.40005 0 180)
			(size 0 0)
			(layers "F.Cu" "F.Mask" "F.Paste")
			(net "P3V3_OCP_SFF")
		)
		(pad "2" smd circle
			(at 0.40005 0 180)
			(size 0 0)
			(layers "F.Cu" "F.Mask" "F.Paste")
			(net "SMB_OCP_SFF_3V3AUX_BUF_SCL")
		)
	)
	(footprint ""
		(layer "F.Cu")
		(at 92.7354 -39.675308)
		(property "Reference" "C1820"
			(at 0 0 0)
			(layer "F.SilkS")
			(hide yes)
			(effects
				(font
					(size 1.27 1.27)
				)
			)
		)
		(property "Value" ""
			(at 0 0 0)
			(layer "F.Fab")
			(effects
				(font
					(size 1.27 1.27)
				)
			)
		)
		(duplicate_pad_numbers_are_jumpers no)
		(fp_line
			(start -0.7874 -0.4064)
			(end 0.7874 -0.4064)
			(stroke
				(width 0.1524)
				(type default)
			)
			(layer "F.SilkS")
		)
		(fp_line
			(start -0.7874 0.4064)
			(end -0.7874 -0.4064)
			(stroke
				(width 0.1524)
				(type default)
			)
			(layer "F.SilkS")
		)
		(fp_line
			(start 0.7874 -0.4064)
			(end 0.7874 0.4064)
			(stroke
				(width 0.1524)
				(type default)
			)
			(layer "F.SilkS")
		)
		(fp_line
			(start 0.7874 0.4064)
			(end -0.7874 0.4064)
			(stroke
				(width 0.1524)
				(type default)
			)
			(layer "F.SilkS")
		)
		(fp_line
			(start -0.67945 -0.305054)
			(end -0.12065 -0.305054)
			(stroke
				(width 0.1)
				(type default)
			)
			(layer "F.Fab")
		)
		(fp_line
			(start -0.67945 0.3048)
			(end -0.67945 -0.305054)
			(stroke
				(width 0.1)
				(type default)
			)
			(layer "F.Fab")
		)
		(fp_line
			(start -0.12065 -0.305054)
			(end -0.12065 -0.2794)
			(stroke
				(width 0.1)
				(type default)
			)
			(layer "F.Fab")
		)
		(fp_line
			(start -0.12065 -0.2794)
			(end 0.12065 -0.2794)
			(stroke
				(width 0.1)
				(type default)
			)
			(layer "F.Fab")
		)
		(fp_line
			(start -0.12065 0.2794)
			(end -0.12065 0.3048)
			(stroke
				(width 0.1)
				(type default)
			)
			(layer "F.Fab")
		)
		(fp_line
			(start -0.12065 0.3048)
			(end -0.67945 0.3048)
			(stroke
				(width 0.1)
				(type default)
			)
			(layer "F.Fab")
		)
		(fp_line
			(start 0.120396 0.2794)
			(end -0.12065 0.2794)
			(stroke
				(width 0.1)
				(type default)
			)
			(layer "F.Fab")
		)
		(fp_line
			(start 0.120396 0.3048)
			(end 0.120396 0.2794)
			(stroke
				(width 0.1)
				(type default)
			)
			(layer "F.Fab")
		)
		(fp_line
			(start 0.12065 -0.3048)
			(end 0.67945 -0.3048)
			(stroke
				(width 0.1)
				(type default)
			)
			(layer "F.Fab")
		)
		(fp_line
			(start 0.12065 -0.2794)
			(end 0.12065 -0.3048)
			(stroke
				(width 0.1)
				(type default)
			)
			(layer "F.Fab")
		)
		(fp_line
			(start 0.67945 -0.3048)
			(end 0.67945 0.3048)
			(stroke
				(width 0.1)
				(type default)
			)
			(layer "F.Fab")
		)
		(fp_line
			(start 0.67945 0.3048)
			(end 0.120396 0.3048)
			(stroke
				(width 0.1)
				(type default)
			)
			(layer "F.Fab")
		)
		(pad "1" smd circle
			(at -0.40005 0)
			(size 0 0)
			(layers "F.Cu" "F.Mask" "F.Paste")
			(net "P3V3_AUX")
		)
		(pad "2" smd circle
			(at 0.40005 0)
			(size 0 0)
			(layers "F.Cu" "F.Mask" "F.Paste")
			(net "GND")
		)
	)
	(footprint ""
		(layer "F.Cu")
		(at 258.375658 -49.558956)
		(property "Reference" "PC2196"
			(at 0 0 0)
			(layer "F.SilkS")
			(hide yes)
			(effects
				(font
					(size 1.27 1.27)
				)
			)
		)
		(property "Value" ""
			(at 0 0 0)
			(layer "F.Fab")
			(effects
				(font
					(size 1.27 1.27)
				)
			)
		)
		(duplicate_pad_numbers_are_jumpers no)
		(fp_line
			(start -0.7874 -0.4064)
			(end 0.7874 -0.4064)
			(stroke
				(width 0.1524)
				(type default)
			)
			(layer "F.SilkS")
		)
		(fp_line
			(start -0.7874 0.4064)
			(end -0.7874 -0.4064)
			(stroke
				(width 0.1524)
				(type default)
			)
			(layer "F.SilkS")
		)
		(fp_line
			(start 0.7874 -0.4064)
			(end 0.7874 0.4064)
			(stroke
				(width 0.1524)
				(type default)
			)
			(layer "F.SilkS")
		)
		(fp_line
			(start 0.7874 0.4064)
			(end -0.7874 0.4064)
			(stroke
				(width 0.1524)
				(type default)
			)
			(layer "F.SilkS")
		)
		(fp_line
			(start -0.67945 -0.305054)
			(end -0.12065 -0.305054)
			(stroke
				(width 0.1)
				(type default)
			)
			(layer "F.Fab")
		)
		(fp_line
			(start -0.67945 0.3048)
			(end -0.67945 -0.305054)
			(stroke
				(width 0.1)
				(type default)
			)
			(layer "F.Fab")
		)
		(fp_line
			(start -0.12065 -0.305054)
			(end -0.12065 -0.2794)
			(stroke
				(width 0.1)
				(type default)
			)
			(layer "F.Fab")
		)
		(fp_line
			(start -0.12065 -0.2794)
			(end 0.12065 -0.2794)
			(stroke
				(width 0.1)
				(type default)
			)
			(layer "F.Fab")
		)
		(fp_line
			(start -0.12065 0.2794)
			(end -0.12065 0.3048)
			(stroke
				(width 0.1)
				(type default)
			)
			(layer "F.Fab")
		)
		(fp_line
			(start -0.12065 0.3048)
			(end -0.67945 0.3048)
			(stroke
				(width 0.1)
				(type default)
			)
			(layer "F.Fab")
		)
		(fp_line
			(start 0.120396 0.2794)
			(end -0.12065 0.2794)
			(stroke
				(width 0.1)
				(type default)
			)
			(layer "F.Fab")
		)
		(fp_line
			(start 0.120396 0.3048)
			(end 0.120396 0.2794)
			(stroke
				(width 0.1)
				(type default)
			)
			(layer "F.Fab")
		)
		(fp_line
			(start 0.12065 -0.3048)
			(end 0.67945 -0.3048)
			(stroke
				(width 0.1)
				(type default)
			)
			(layer "F.Fab")
		)
		(fp_line
			(start 0.12065 -0.2794)
			(end 0.12065 -0.3048)
			(stroke
				(width 0.1)
				(type default)
			)
			(layer "F.Fab")
		)
		(fp_line
			(start 0.67945 -0.3048)
			(end 0.67945 0.3048)
			(stroke
				(width 0.1)
				(type default)
			)
			(layer "F.Fab")
		)
		(fp_line
			(start 0.67945 0.3048)
			(end 0.120396 0.3048)
			(stroke
				(width 0.1)
				(type default)
			)
			(layer "F.Fab")
		)
		(pad "1" smd circle
			(at -0.40005 0)
			(size 0 0)
			(layers "F.Cu" "F.Mask" "F.Paste")
			(net "P12V_E1S_TIMER_0")
		)
		(pad "2" smd circle
			(at 0.40005 0)
			(size 0 0)
			(layers "F.Cu" "F.Mask" "F.Paste")
			(net "GND")
		)
	)
	(footprint ""
		(layer "F.Cu")
		(at 444.715138 -71.898002 -90)
		(property "Reference" "PC581"
			(at 0 0 270)
			(layer "F.SilkS")
			(hide yes)
			(effects
				(font
					(size 1.27 1.27)
				)
			)
		)
		(property "Value" ""
			(at 0 0 270)
			(layer "F.Fab")
			(effects
				(font
					(size 1.27 1.27)
				)
			)
		)
		(duplicate_pad_numbers_are_jumpers no)
		(fp_line
			(start -1.2954 0.5842)
			(end -1.2954 -0.5842)
			(stroke
				(width 0.1524)
				(type default)
			)
			(layer "F.SilkS")
		)
		(fp_line
			(start 1.2954 0.5842)
			(end -1.2954 0.5842)
			(stroke
				(width 0.1524)
				(type default)
			)
			(layer "F.SilkS")
		)
		(fp_line
			(start -1.2954 -0.5842)
			(end 1.2954 -0.5842)
			(stroke
				(width 0.1524)
				(type default)
			)
			(layer "F.SilkS")
		)
		(fp_line
			(start 0 -0.5842)
			(end 0 0.5842)
			(stroke
				(width 0.1524)
				(type default)
			)
			(layer "F.SilkS")
		)
		(fp_line
			(start 1.2954 -0.5842)
			(end 1.2954 0.5842)
			(stroke
				(width 0.1524)
				(type default)
			)
			(layer "F.SilkS")
		)
		(fp_line
			(start -0.8636 0.4572)
			(end -0.8636 0.4064)
			(stroke
				(width 0.1)
				(type default)
			)
			(layer "F.Fab")
		)
		(fp_line
			(start 0.8636 0.4572)
			(end -0.8636 0.4572)
			(stroke
				(width 0.1)
				(type default)
			)
			(layer "F.Fab")
		)
		(fp_line
			(start -1.1938 0.4064)
			(end -1.1938 -0.4064)
			(stroke
				(width 0.1)
				(type default)
			)
			(layer "F.Fab")
		)
		(fp_line
			(start -0.8636 0.4064)
			(end -1.1938 0.4064)
			(stroke
				(width 0.1)
				(type default)
			)
			(layer "F.Fab")
		)
		(fp_line
			(start 0.8636 0.4064)
			(end 0.8636 0.4572)
			(stroke
				(width 0.1)
				(type default)
			)
			(layer "F.Fab")
		)
		(fp_line
			(start 1.1938 0.4064)
			(end 0.8636 0.4064)
			(stroke
				(width 0.1)
				(type default)
			)
			(layer "F.Fab")
		)
		(fp_line
			(start -1.1938 -0.4064)
			(end -0.8636 -0.4064)
			(stroke
				(width 0.1)
				(type default)
			)
			(layer "F.Fab")
		)
		(fp_line
			(start -0.8636 -0.4064)
			(end -0.8636 -0.4572)
			(stroke
				(width 0.1)
				(type default)
			)
			(layer "F.Fab")
		)
		(fp_line
			(start 0.8636 -0.4064)
			(end 1.1938 -0.4064)
			(stroke
				(width 0.1)
				(type default)
			)
			(layer "F.Fab")
		)
		(fp_line
			(start 1.1938 -0.4064)
			(end 1.1938 0.4064)
			(stroke
				(width 0.1)
				(type default)
			)
			(layer "F.Fab")
		)
		(fp_line
			(start -0.8636 -0.4572)
			(end 0.8636 -0.4572)
			(stroke
				(width 0.1)
				(type default)
			)
			(layer "F.Fab")
		)
		(fp_line
			(start 0.8636 -0.4572)
			(end 0.8636 -0.4064)
			(stroke
				(width 0.1)
				(type default)
			)
			(layer "F.Fab")
		)
		(pad "1" smd rect
			(at -0.7366 0 180)
			(size 0.7112 0.8128)
			(layers "F.Cu" "F.Mask" "F.Paste")
			(net "P3V3_AUX_VDRV")
		)
		(pad "2" smd rect
			(at 0.7366 0 180)
			(size 0.7112 0.8128)
			(layers "F.Cu" "F.Mask" "F.Paste")
			(net "GND")
		)
	)
	(footprint ""
		(layer "F.Cu")
		(at 54.811168 -151.411178)
		(property "Reference" "PC445_P1_2"
			(at 0 0 0)
			(layer "F.SilkS")
			(hide yes)
			(effects
				(font
					(size 1.27 1.27)
				)
			)
		)
		(property "Value" ""
			(at 0 0 0)
			(layer "F.Fab")
			(effects
				(font
					(size 1.27 1.27)
				)
			)
		)
		(duplicate_pad_numbers_are_jumpers no)
		(fp_line
			(start -0.7874 -0.4064)
			(end 0.7874 -0.4064)
			(stroke
				(width 0.1524)
				(type default)
			)
			(layer "F.SilkS")
		)
		(fp_line
			(start -0.7874 0.4064)
			(end -0.7874 -0.4064)
			(stroke
				(width 0.1524)
				(type default)
			)
			(layer "F.SilkS")
		)
		(fp_line
			(start 0.7874 -0.4064)
			(end 0.7874 0.4064)
			(stroke
				(width 0.1524)
				(type default)
			)
			(layer "F.SilkS")
		)
		(fp_line
			(start 0.7874 0.4064)
			(end -0.7874 0.4064)
			(stroke
				(width 0.1524)
				(type default)
			)
			(layer "F.SilkS")
		)
		(fp_line
			(start -0.67945 -0.305054)
			(end -0.12065 -0.305054)
			(stroke
				(width 0.1)
				(type default)
			)
			(layer "F.Fab")
		)
		(fp_line
			(start -0.67945 0.3048)
			(end -0.67945 -0.305054)
			(stroke
				(width 0.1)
				(type default)
			)
			(layer "F.Fab")
		)
		(fp_line
			(start -0.12065 -0.305054)
			(end -0.12065 -0.2794)
			(stroke
				(width 0.1)
				(type default)
			)
			(layer "F.Fab")
		)
		(fp_line
			(start -0.12065 -0.2794)
			(end 0.12065 -0.2794)
			(stroke
				(width 0.1)
				(type default)
			)
			(layer "F.Fab")
		)
		(fp_line
			(start -0.12065 0.2794)
			(end -0.12065 0.3048)
			(stroke
				(width 0.1)
				(type default)
			)
			(layer "F.Fab")
		)
		(fp_line
			(start -0.12065 0.3048)
			(end -0.67945 0.3048)
			(stroke
				(width 0.1)
				(type default)
			)
			(layer "F.Fab")
		)
		(fp_line
			(start 0.120396 0.2794)
			(end -0.12065 0.2794)
			(stroke
				(width 0.1)
				(type default)
			)
			(layer "F.Fab")
		)
		(fp_line
			(start 0.120396 0.3048)
			(end 0.120396 0.2794)
			(stroke
				(width 0.1)
				(type default)
			)
			(layer "F.Fab")
		)
		(fp_line
			(start 0.12065 -0.3048)
			(end 0.67945 -0.3048)
			(stroke
				(width 0.1)
				(type default)
			)
			(layer "F.Fab")
		)
		(fp_line
			(start 0.12065 -0.2794)
			(end 0.12065 -0.3048)
			(stroke
				(width 0.1)
				(type default)
			)
			(layer "F.Fab")
		)
		(fp_line
			(start 0.67945 -0.3048)
			(end 0.67945 0.3048)
			(stroke
				(width 0.1)
				(type default)
			)
			(layer "F.Fab")
		)
		(fp_line
			(start 0.67945 0.3048)
			(end 0.120396 0.3048)
			(stroke
				(width 0.1)
				(type default)
			)
			(layer "F.Fab")
		)
		(pad "1" smd circle
			(at -0.40005 0)
			(size 0 0)
			(layers "F.Cu" "F.Mask" "F.Paste")
			(net "SW_P12V_PVCCINFAON_CPU1_FLT")
		)
		(pad "2" smd circle
			(at 0.40005 0)
			(size 0 0)
			(layers "F.Cu" "F.Mask" "F.Paste")
			(net "GND")
		)
	)
	(footprint ""
		(layer "F.Cu")
		(at 306.215288 -408.517344 -90)
		(property "Reference" "C903"
			(at 0 0 270)
			(layer "F.SilkS")
			(hide yes)
			(effects
				(font
					(size 1.27 1.27)
				)
			)
		)
		(property "Value" ""
			(at 0 0 270)
			(layer "F.Fab")
			(effects
				(font
					(size 1.27 1.27)
				)
			)
		)
		(duplicate_pad_numbers_are_jumpers no)
		(fp_line
			(start -0.299974 0.150114)
			(end -0.299974 -0.150114)
			(stroke
				(width 0.1)
				(type default)
			)
			(layer "F.Fab")
		)
		(fp_line
			(start 0.299974 0.150114)
			(end -0.299974 0.150114)
			(stroke
				(width 0.1)
				(type default)
			)
			(layer "F.Fab")
		)
		(fp_line
			(start -0.299974 -0.150114)
			(end 0.299974 -0.150114)
			(stroke
				(width 0.1)
				(type default)
			)
			(layer "F.Fab")
		)
		(fp_line
			(start 0.299974 -0.150114)
			(end 0.299974 0.150114)
			(stroke
				(width 0.1)
				(type default)
			)
			(layer "F.Fab")
		)
		(pad "1" smd rect
			(at -0.2667 0 270)
			(size 0.3048 0.381)
			(layers "F.Cu" "F.Mask" "F.Paste")
			(net "P5E_CPU0_PE0_TX_C_DP<15>")
		)
		(pad "2" smd rect
			(at 0.2667 0 270)
			(size 0.3048 0.381)
			(layers "F.Cu" "F.Mask" "F.Paste")
			(net "P5E_CPU0_PE0_TX_DP<15>")
		)
	)
	(footprint ""
		(layer "F.Cu")
		(at 325.077836 -345.462606 90)
		(property "Reference" "PC227"
			(at 0 0 90)
			(layer "F.SilkS")
			(hide yes)
			(effects
				(font
					(size 1.27 1.27)
				)
			)
		)
		(property "Value" ""
			(at 0 0 90)
			(layer "F.Fab")
			(effects
				(font
					(size 1.27 1.27)
				)
			)
		)
		(duplicate_pad_numbers_are_jumpers no)
		(fp_line
			(start 0.7874 -0.4064)
			(end 0.7874 0.4064)
			(stroke
				(width 0.1524)
				(type default)
			)
			(layer "F.SilkS")
		)
		(fp_line
			(start -0.7874 -0.4064)
			(end 0.7874 -0.4064)
			(stroke
				(width 0.1524)
				(type default)
			)
			(layer "F.SilkS")
		)
		(fp_line
			(start 0.7874 0.4064)
			(end -0.7874 0.4064)
			(stroke
				(width 0.1524)
				(type default)
			)
			(layer "F.SilkS")
		)
		(fp_line
			(start -0.7874 0.4064)
			(end -0.7874 -0.4064)
			(stroke
				(width 0.1524)
				(type default)
			)
			(layer "F.SilkS")
		)
		(fp_line
			(start -0.12065 -0.305054)
			(end -0.12065 -0.2794)
			(stroke
				(width 0.1)
				(type default)
			)
			(layer "F.Fab")
		)
		(fp_line
			(start -0.67945 -0.305054)
			(end -0.12065 -0.305054)
			(stroke
				(width 0.1)
				(type default)
			)
			(layer "F.Fab")
		)
		(fp_line
			(start 0.67945 -0.3048)
			(end 0.67945 0.3048)
			(stroke
				(width 0.1)
				(type default)
			)
			(layer "F.Fab")
		)
		(fp_line
			(start 0.12065 -0.3048)
			(end 0.67945 -0.3048)
			(stroke
				(width 0.1)
				(type default)
			)
			(layer "F.Fab")
		)
		(fp_line
			(start 0.12065 -0.2794)
			(end 0.12065 -0.3048)
			(stroke
				(width 0.1)
				(type default)
			)
			(layer "F.Fab")
		)
		(fp_line
			(start -0.12065 -0.2794)
			(end 0.12065 -0.2794)
			(stroke
				(width 0.1)
				(type default)
			)
			(layer "F.Fab")
		)
		(fp_line
			(start 0.120396 0.2794)
			(end -0.12065 0.2794)
			(stroke
				(width 0.1)
				(type default)
			)
			(layer "F.Fab")
		)
		(fp_line
			(start -0.12065 0.2794)
			(end -0.12065 0.3048)
			(stroke
				(width 0.1)
				(type default)
			)
			(layer "F.Fab")
		)
		(fp_line
			(start 0.67945 0.3048)
			(end 0.120396 0.3048)
			(stroke
				(width 0.1)
				(type default)
			)
			(layer "F.Fab")
		)
		(fp_line
			(start 0.120396 0.3048)
			(end 0.120396 0.2794)
			(stroke
				(width 0.1)
				(type default)
			)
			(layer "F.Fab")
		)
		(fp_line
			(start -0.12065 0.3048)
			(end -0.67945 0.3048)
			(stroke
				(width 0.1)
				(type default)
			)
			(layer "F.Fab")
		)
		(fp_line
			(start -0.67945 0.3048)
			(end -0.67945 -0.305054)
			(stroke
				(width 0.1)
				(type default)
			)
			(layer "F.Fab")
		)
		(pad "1" smd circle
			(at -0.40005 0 90)
			(size 0 0)
			(layers "F.Cu" "F.Mask" "F.Paste")
			(net "PVCCIN_CPU0_VDD7")
		)
		(pad "2" smd circle
			(at 0.40005 0 90)
			(size 0 0)
			(layers "F.Cu" "F.Mask" "F.Paste")
			(net "GND")
		)
	)
	(footprint ""
		(layer "F.Cu")
		(at 68.085716 -113.72469 180)
		(property "Reference" "R3711"
			(at 0 0 180)
			(layer "F.SilkS")
			(hide yes)
			(effects
				(font
					(size 1.27 1.27)
				)
			)
		)
		(property "Value" ""
			(at 0 0 180)
			(layer "F.Fab")
			(effects
				(font
					(size 1.27 1.27)
				)
			)
		)
		(duplicate_pad_numbers_are_jumpers no)
		(fp_line
			(start 0.7874 0.4064)
			(end -0.7874 0.4064)
			(stroke
				(width 0.1524)
				(type default)
			)
			(layer "F.SilkS")
		)
		(fp_line
			(start 0.7874 -0.4064)
			(end 0.7874 0.4064)
			(stroke
				(width 0.1524)
				(type default)
			)
			(layer "F.SilkS")
		)
		(fp_line
			(start -0.7874 0.4064)
			(end -0.7874 -0.4064)
			(stroke
				(width 0.1524)
				(type default)
			)
			(layer "F.SilkS")
		)
		(fp_line
			(start -0.7874 -0.4064)
			(end 0.7874 -0.4064)
			(stroke
				(width 0.1524)
				(type default)
			)
			(layer "F.SilkS")
		)
		(fp_line
			(start 0.67945 0.3048)
			(end 0.120396 0.3048)
			(stroke
				(width 0.1)
				(type default)
			)
			(layer "F.Fab")
		)
		(fp_line
			(start 0.67945 -0.3048)
			(end 0.67945 0.3048)
			(stroke
				(width 0.1)
				(type default)
			)
			(layer "F.Fab")
		)
		(fp_line
			(start 0.12065 -0.2794)
			(end 0.12065 -0.3048)
			(stroke
				(width 0.1)
				(type default)
			)
			(layer "F.Fab")
		)
		(fp_line
			(start 0.12065 -0.3048)
			(end 0.67945 -0.3048)
			(stroke
				(width 0.1)
				(type default)
			)
			(layer "F.Fab")
		)
		(fp_line
			(start 0.120396 0.3048)
			(end 0.120396 0.2794)
			(stroke
				(width 0.1)
				(type default)
			)
			(layer "F.Fab")
		)
		(fp_line
			(start 0.120396 0.2794)
			(end -0.12065 0.2794)
			(stroke
				(width 0.1)
				(type default)
			)
			(layer "F.Fab")
		)
		(fp_line
			(start -0.12065 0.3048)
			(end -0.67945 0.3048)
			(stroke
				(width 0.1)
				(type default)
			)
			(layer "F.Fab")
		)
		(fp_line
			(start -0.12065 0.2794)
			(end -0.12065 0.3048)
			(stroke
				(width 0.1)
				(type default)
			)
			(layer "F.Fab")
		)
		(fp_line
			(start -0.12065 -0.2794)
			(end 0.12065 -0.2794)
			(stroke
				(width 0.1)
				(type default)
			)
			(layer "F.Fab")
		)
		(fp_line
			(start -0.12065 -0.305054)
			(end -0.12065 -0.2794)
			(stroke
				(width 0.1)
				(type default)
			)
			(layer "F.Fab")
		)
		(fp_line
			(start -0.67945 0.3048)
			(end -0.67945 -0.305054)
			(stroke
				(width 0.1)
				(type default)
			)
			(layer "F.Fab")
		)
		(fp_line
			(start -0.67945 -0.305054)
			(end -0.12065 -0.305054)
			(stroke
				(width 0.1)
				(type default)
			)
			(layer "F.Fab")
		)
		(pad "1" smd circle
			(at -0.40005 0 180)
			(size 0 0)
			(layers "F.Cu" "F.Mask" "F.Paste")
			(net "SMB_VR_SENSOR_3V3AUX_SCL")
		)
		(pad "2" smd circle
			(at 0.40005 0 180)
			(size 0 0)
			(layers "F.Cu" "F.Mask" "F.Paste")
			(net "SMB_VR_SENSOR_3V3AUX_SCL_R")
		)
	)
	(footprint ""
		(layer "F.Cu")
		(at 150.761954 -402.371052 -90)
		(property "Reference" "C763"
			(at 0 0 270)
			(layer "F.SilkS")
			(hide yes)
			(effects
				(font
					(size 1.27 1.27)
				)
			)
		)
		(property "Value" ""
			(at 0 0 270)
			(layer "F.Fab")
			(effects
				(font
					(size 1.27 1.27)
				)
			)
		)
		(duplicate_pad_numbers_are_jumpers no)
		(fp_line
			(start -0.299974 0.150114)
			(end -0.299974 -0.150114)
			(stroke
				(width 0.1)
				(type default)
			)
			(layer "F.Fab")
		)
		(fp_line
			(start 0.299974 0.150114)
			(end -0.299974 0.150114)
			(stroke
				(width 0.1)
				(type default)
			)
			(layer "F.Fab")
		)
		(fp_line
			(start -0.299974 -0.150114)
			(end 0.299974 -0.150114)
			(stroke
				(width 0.1)
				(type default)
			)
			(layer "F.Fab")
		)
		(fp_line
			(start 0.299974 -0.150114)
			(end 0.299974 0.150114)
			(stroke
				(width 0.1)
				(type default)
			)
			(layer "F.Fab")
		)
		(pad "1" smd rect
			(at -0.2667 0 270)
			(size 0.3048 0.381)
			(layers "F.Cu" "F.Mask" "F.Paste")
			(net "P5E_CPU1_PE2_TX_C_DP<5>")
		)
		(pad "2" smd rect
			(at 0.2667 0 270)
			(size 0.3048 0.381)
			(layers "F.Cu" "F.Mask" "F.Paste")
			(net "P5E_CPU1_PE2_TX_DP<5>")
		)
	)
	(footprint ""
		(layer "F.Cu")
		(at 440.137804 -18.27022 180)
		(property "Reference" "C1213"
			(at 0 0 180)
			(layer "F.SilkS")
			(hide yes)
			(effects
				(font
					(size 1.27 1.27)
				)
			)
		)
		(property "Value" ""
			(at 0 0 180)
			(layer "F.Fab")
			(effects
				(font
					(size 1.27 1.27)
				)
			)
		)
		(duplicate_pad_numbers_are_jumpers no)
		(fp_line
			(start 1.524 0.762)
			(end -1.524 0.762)
			(stroke
				(width 0.1524)
				(type default)
			)
			(layer "F.SilkS")
		)
		(fp_line
			(start 1.524 -0.762)
			(end 1.524 0.762)
			(stroke
				(width 0.1524)
				(type default)
			)
			(layer "F.SilkS")
		)
		(fp_line
			(start -1.524 0.762)
			(end -1.524 -0.762)
			(stroke
				(width 0.1524)
				(type default)
			)
			(layer "F.SilkS")
		)
		(fp_line
			(start -1.524 -0.762)
			(end 1.524 -0.762)
			(stroke
				(width 0.1524)
				(type default)
			)
			(layer "F.SilkS")
		)
		(fp_line
			(start 1.1049 0.724916)
			(end 1.1049 -0.724916)
			(stroke
				(width 0.1)
				(type default)
			)
			(layer "F.Fab")
		)
		(fp_line
			(start 1.1049 -0.724916)
			(end -1.1049 -0.724916)
			(stroke
				(width 0.1)
				(type default)
			)
			(layer "F.Fab")
		)
		(fp_line
			(start -1.1049 0.724916)
			(end 1.1049 0.724916)
			(stroke
				(width 0.1)
				(type default)
			)
			(layer "F.Fab")
		)
		(fp_line
			(start -1.1049 -0.724916)
			(end -1.1049 0.724916)
			(stroke
				(width 0.1)
				(type default)
			)
			(layer "F.Fab")
		)
		(pad "1" smd rect
			(at -0.889 0)
			(size 1.016 1.27)
			(layers "F.Cu" "F.Mask" "F.Paste")
			(net "P12V_OCP_SFF")
		)
		(pad "2" smd rect
			(at 0.889 0)
			(size 1.016 1.27)
			(layers "F.Cu" "F.Mask" "F.Paste")
			(net "GND")
		)
	)
	(footprint ""
		(layer "F.Cu")
		(at 338.38007 -297.514772)
		(property "Reference" "H15"
			(at -1.83007 -5.064506 0)
			(unlocked yes)
			(layer "F.SilkS")
			(effects
				(font
					(size 0.7874 0.5842)
					(thickness 0.1524)
				)
				(justify left)
			)
		)
		(property "Value" ""
			(at 0 0 0)
			(layer "F.Fab")
			(effects
				(font
					(size 1.27 1.27)
				)
			)
		)
		(duplicate_pad_numbers_are_jumpers no)
		(fp_circle
			(center 0 0)
			(end 2.5273 0)
			(stroke
				(width 0.1524)
				(type default)
			)
			(fill no)
			(layer "F.SilkS")
		)
		(fp_circle
			(center 0 0)
			(end 2.5273 0)
			(stroke
				(width 0.1524)
				(type default)
			)
			(fill no)
			(layer "B.SilkS")
		)
		(fp_circle
			(center 0 0)
			(end 2.5273 0)
			(stroke
				(width 0.1)
				(type default)
			)
			(fill no)
			(layer "B.Fab")
		)
		(fp_circle
			(center 0 0)
			(end 2.5273 0)
			(stroke
				(width 0.1)
				(type default)
			)
			(fill no)
			(layer "F.Fab")
		)
		(pad "" np_thru_hole circle
			(at 0 0)
			(size 3.429 3.429)
			(drill 3.429)
			(layers "*.Cu" "*.Mask")
			(clearance 0.381)
			(thermal_gap 0.381)
		)
	)
	(footprint ""
		(layer "F.Cu")
		(at 312.42 -24.9936)
		(property "Reference" "R4788"
			(at 0 0 0)
			(layer "F.SilkS")
			(hide yes)
			(effects
				(font
					(size 1.27 1.27)
				)
			)
		)
		(property "Value" ""
			(at 0 0 0)
			(layer "F.Fab")
			(effects
				(font
					(size 1.27 1.27)
				)
			)
		)
		(duplicate_pad_numbers_are_jumpers no)
		(fp_line
			(start -0.7874 -0.4064)
			(end 0.7874 -0.4064)
			(stroke
				(width 0.1524)
				(type default)
			)
			(layer "F.SilkS")
		)
		(fp_line
			(start -0.7874 0.4064)
			(end -0.7874 -0.4064)
			(stroke
				(width 0.1524)
				(type default)
			)
			(layer "F.SilkS")
		)
		(fp_line
			(start 0.7874 -0.4064)
			(end 0.7874 0.4064)
			(stroke
				(width 0.1524)
				(type default)
			)
			(layer "F.SilkS")
		)
		(fp_line
			(start 0.7874 0.4064)
			(end -0.7874 0.4064)
			(stroke
				(width 0.1524)
				(type default)
			)
			(layer "F.SilkS")
		)
		(fp_line
			(start -0.67945 -0.305054)
			(end -0.12065 -0.305054)
			(stroke
				(width 0.1)
				(type default)
			)
			(layer "F.Fab")
		)
		(fp_line
			(start -0.67945 0.3048)
			(end -0.67945 -0.305054)
			(stroke
				(width 0.1)
				(type default)
			)
			(layer "F.Fab")
		)
		(fp_line
			(start -0.12065 -0.305054)
			(end -0.12065 -0.2794)
			(stroke
				(width 0.1)
				(type default)
			)
			(layer "F.Fab")
		)
		(fp_line
			(start -0.12065 -0.2794)
			(end 0.12065 -0.2794)
			(stroke
				(width 0.1)
				(type default)
			)
			(layer "F.Fab")
		)
		(fp_line
			(start -0.12065 0.2794)
			(end -0.12065 0.3048)
			(stroke
				(width 0.1)
				(type default)
			)
			(layer "F.Fab")
		)
		(fp_line
			(start -0.12065 0.3048)
			(end -0.67945 0.3048)
			(stroke
				(width 0.1)
				(type default)
			)
			(layer "F.Fab")
		)
		(fp_line
			(start 0.120396 0.2794)
			(end -0.12065 0.2794)
			(stroke
				(width 0.1)
				(type default)
			)
			(layer "F.Fab")
		)
		(fp_line
			(start 0.120396 0.3048)
			(end 0.120396 0.2794)
			(stroke
				(width 0.1)
				(type default)
			)
			(layer "F.Fab")
		)
		(fp_line
			(start 0.12065 -0.3048)
			(end 0.67945 -0.3048)
			(stroke
				(width 0.1)
				(type default)
			)
			(layer "F.Fab")
		)
		(fp_line
			(start 0.12065 -0.2794)
			(end 0.12065 -0.3048)
			(stroke
				(width 0.1)
				(type default)
			)
			(layer "F.Fab")
		)
		(fp_line
			(start 0.67945 -0.3048)
			(end 0.67945 0.3048)
			(stroke
				(width 0.1)
				(type default)
			)
			(layer "F.Fab")
		)
		(fp_line
			(start 0.67945 0.3048)
			(end 0.120396 0.3048)
			(stroke
				(width 0.1)
				(type default)
			)
			(layer "F.Fab")
		)
		(pad "1" smd circle
			(at -0.40005 0)
			(size 0 0)
			(layers "F.Cu" "F.Mask" "F.Paste")
			(net "PWRGD_DSW_PWROK_R5")
		)
		(pad "2" smd circle
			(at 0.40005 0)
			(size 0 0)
			(layers "F.Cu" "F.Mask" "F.Paste")
			(net "PWRGD_DSW_PWROK")
		)
	)
	(footprint ""
		(layer "F.Cu")
		(at 23.767034 -385.778248 -90)
		(property "Reference" "C1868"
			(at 0 0 270)
			(layer "F.SilkS")
			(hide yes)
			(effects
				(font
					(size 1.27 1.27)
				)
			)
		)
		(property "Value" ""
			(at 0 0 270)
			(layer "F.Fab")
			(effects
				(font
					(size 1.27 1.27)
				)
			)
		)
		(duplicate_pad_numbers_are_jumpers no)
		(fp_line
			(start -0.002032 0.4064)
			(end -0.7874 0.4064)
			(stroke
				(width 0.1524)
				(type default)
			)
			(layer "F.SilkS")
		)
		(fp_line
			(start -0.7874 -0.4064)
			(end 0.7874 -0.4064)
			(stroke
				(width 0.1524)
				(type default)
			)
			(layer "F.SilkS")
		)
		(fp_line
			(start 0.7874 -0.4064)
			(end 0.7874 0.4064)
			(stroke
				(width 0.1524)
				(type default)
			)
			(layer "F.SilkS")
		)
		(fp_line
			(start -0.6858 0.3048)
			(end -0.6858 -0.3048)
			(stroke
				(width 0.1)
				(type default)
			)
			(layer "F.Fab")
		)
		(fp_line
			(start -0.1016 0.3048)
			(end -0.6858 0.3048)
			(stroke
				(width 0.1)
				(type default)
			)
			(layer "F.Fab")
		)
		(fp_line
			(start 0.1016 0.3048)
			(end 0.1016 0.2794)
			(stroke
				(width 0.1)
				(type default)
			)
			(layer "F.Fab")
		)
		(fp_line
			(start 0.6858 0.3048)
			(end 0.1016 0.3048)
			(stroke
				(width 0.1)
				(type default)
			)
			(layer "F.Fab")
		)
		(fp_line
			(start -0.1016 0.2794)
			(end -0.1016 0.3048)
			(stroke
				(width 0.1)
				(type default)
			)
			(layer "F.Fab")
		)
		(fp_line
			(start 0.1016 0.2794)
			(end -0.1016 0.2794)
			(stroke
				(width 0.1)
				(type default)
			)
			(layer "F.Fab")
		)
		(fp_line
			(start -0.1016 -0.2794)
			(end 0.1016 -0.2794)
			(stroke
				(width 0.1)
				(type default)
			)
			(layer "F.Fab")
		)
		(fp_line
			(start 0.1016 -0.2794)
			(end 0.1016 -0.3048)
			(stroke
				(width 0.1)
				(type default)
			)
			(layer "F.Fab")
		)
		(fp_line
			(start -0.6858 -0.3048)
			(end -0.1016 -0.3048)
			(stroke
				(width 0.1)
				(type default)
			)
			(layer "F.Fab")
		)
		(fp_line
			(start -0.1016 -0.3048)
			(end -0.1016 -0.2794)
			(stroke
				(width 0.1)
				(type default)
			)
			(layer "F.Fab")
		)
		(fp_line
			(start 0.1016 -0.3048)
			(end 0.6858 -0.3048)
			(stroke
				(width 0.1)
				(type default)
			)
			(layer "F.Fab")
		)
		(fp_line
			(start 0.6858 -0.3048)
			(end 0.6858 0.3048)
			(stroke
				(width 0.1)
				(type default)
			)
			(layer "F.Fab")
		)
		(pad "1" smd rect
			(at -0.40005 0 90)
			(size 0.4572 0.508)
			(layers "F.Cu" "F.Mask" "F.Paste")
			(net "P2E_MB_BMC_RX_BUF_C_DP<0>")
		)
		(pad "2" smd rect
			(at 0.40005 0 90)
			(size 0.4572 0.508)
			(layers "F.Cu" "F.Mask" "F.Paste")
			(net "P2E_MB_BMC_RX_BUF_DP<0>")
		)
	)
	(footprint ""
		(layer "F.Cu")
		(at 98.525838 -315.66739 90)
		(property "Reference" "PC580"
			(at 0 0 90)
			(layer "F.SilkS")
			(hide yes)
			(effects
				(font
					(size 1.27 1.27)
				)
			)
		)
		(property "Value" ""
			(at 0 0 90)
			(layer "F.Fab")
			(effects
				(font
					(size 1.27 1.27)
				)
			)
		)
		(duplicate_pad_numbers_are_jumpers no)
		(fp_line
			(start 2.750058 0.999998)
			(end -2.750058 0.999998)
			(stroke
				(width 0.1524)
				(type default)
			)
			(layer "F.SilkS")
		)
		(fp_circle
			(center 0 0.999998)
			(end 0 3.750056)
			(stroke
				(width 0.1524)
				(type default)
			)
			(fill no)
			(layer "F.SilkS")
		)
		(fp_poly
			(pts
				(arc
					(start 2.750058 0.999998)
					(mid 0 3.750056)
					(end -2.750058 0.999998)
				)
			)
			(stroke
				(width 0)
				(type default)
			)
			(fill yes)
			(layer "F.SilkS")
		)
		(fp_circle
			(center 0 0.999998)
			(end 0 3.750056)
			(stroke
				(width 0.1)
				(type default)
			)
			(fill no)
			(layer "F.Fab")
		)
		(pad "1" thru_hole rect
			(at 0 0 90)
			(size 1.5748 1.5748)
			(drill 1.0668)
			(layers "*.Cu" "*.Mask")
			(remove_unused_layers no)
			(net "PVCCIN_CPU1")
			(clearance 0)
			(padstack
				(mode front_inner_back)
				(layer "Inner"
					(shape circle)
					(size 1.5748 1.5748)
					(clearance 0)
				)
				(layer "B.Cu"
					(shape rect)
					(size 1.5748 1.5748)
					(clearance 0)
				)
			)
		)
		(pad "2" thru_hole circle
			(at 0 1.999996 90)
			(size 1.5748 1.5748)
			(drill 1.0668)
			(layers "*.Cu" "*.Mask")
			(remove_unused_layers no)
			(net "GND")
			(clearance 0)
		)
	)
	(footprint ""
		(layer "F.Cu")
		(at 77.920088 -251.76988)
		(property "Reference" "H24"
			(at -4.47802 -1.615948 0)
			(unlocked yes)
			(layer "F.SilkS")
			(effects
				(font
					(size 0.7874 0.5842)
					(thickness 0.1524)
				)
				(justify left)
			)
		)
		(property "Value" ""
			(at 0 0 0)
			(layer "F.Fab")
			(effects
				(font
					(size 1.27 1.27)
				)
			)
		)
		(duplicate_pad_numbers_are_jumpers no)
		(fp_circle
			(center 0 0)
			(end 2.5273 0)
			(stroke
				(width 0.1524)
				(type default)
			)
			(fill no)
			(layer "F.SilkS")
		)
		(fp_circle
			(center 0 0)
			(end 2.5273 0)
			(stroke
				(width 0.1524)
				(type default)
			)
			(fill no)
			(layer "B.SilkS")
		)
		(fp_circle
			(center 0 0)
			(end 2.5273 0)
			(stroke
				(width 0.1)
				(type default)
			)
			(fill no)
			(layer "B.Fab")
		)
		(fp_circle
			(center 0 0)
			(end 2.5273 0)
			(stroke
				(width 0.1)
				(type default)
			)
			(fill no)
			(layer "F.Fab")
		)
		(pad "" np_thru_hole circle
			(at 0 0)
			(size 3.429 3.429)
			(drill 3.429)
			(layers "*.Cu" "*.Mask")
			(clearance 0.381)
			(thermal_gap 0.381)
		)
	)
	(footprint ""
		(layer "F.Cu")
		(at 106.7308 -410.6164 180)
		(property "Reference" "R4725"
			(at 0 0 180)
			(layer "F.SilkS")
			(hide yes)
			(effects
				(font
					(size 1.27 1.27)
				)
			)
		)
		(property "Value" ""
			(at 0 0 180)
			(layer "F.Fab")
			(effects
				(font
					(size 1.27 1.27)
				)
			)
		)
		(duplicate_pad_numbers_are_jumpers no)
		(fp_line
			(start 0.7874 0.4064)
			(end -0.7874 0.4064)
			(stroke
				(width 0.1524)
				(type default)
			)
			(layer "F.SilkS")
		)
		(fp_line
			(start 0.7874 -0.4064)
			(end 0.7874 0.4064)
			(stroke
				(width 0.1524)
				(type default)
			)
			(layer "F.SilkS")
		)
		(fp_line
			(start -0.7874 0.4064)
			(end -0.7874 -0.4064)
			(stroke
				(width 0.1524)
				(type default)
			)
			(layer "F.SilkS")
		)
		(fp_line
			(start -0.7874 -0.4064)
			(end 0.7874 -0.4064)
			(stroke
				(width 0.1524)
				(type default)
			)
			(layer "F.SilkS")
		)
		(fp_line
			(start 0.67945 0.3048)
			(end 0.120396 0.3048)
			(stroke
				(width 0.1)
				(type default)
			)
			(layer "F.Fab")
		)
		(fp_line
			(start 0.67945 -0.3048)
			(end 0.67945 0.3048)
			(stroke
				(width 0.1)
				(type default)
			)
			(layer "F.Fab")
		)
		(fp_line
			(start 0.12065 -0.2794)
			(end 0.12065 -0.3048)
			(stroke
				(width 0.1)
				(type default)
			)
			(layer "F.Fab")
		)
		(fp_line
			(start 0.12065 -0.3048)
			(end 0.67945 -0.3048)
			(stroke
				(width 0.1)
				(type default)
			)
			(layer "F.Fab")
		)
		(fp_line
			(start 0.120396 0.3048)
			(end 0.120396 0.2794)
			(stroke
				(width 0.1)
				(type default)
			)
			(layer "F.Fab")
		)
		(fp_line
			(start 0.120396 0.2794)
			(end -0.12065 0.2794)
			(stroke
				(width 0.1)
				(type default)
			)
			(layer "F.Fab")
		)
		(fp_line
			(start -0.12065 0.3048)
			(end -0.67945 0.3048)
			(stroke
				(width 0.1)
				(type default)
			)
			(layer "F.Fab")
		)
		(fp_line
			(start -0.12065 0.2794)
			(end -0.12065 0.3048)
			(stroke
				(width 0.1)
				(type default)
			)
			(layer "F.Fab")
		)
		(fp_line
			(start -0.12065 -0.2794)
			(end 0.12065 -0.2794)
			(stroke
				(width 0.1)
				(type default)
			)
			(layer "F.Fab")
		)
		(fp_line
			(start -0.12065 -0.305054)
			(end -0.12065 -0.2794)
			(stroke
				(width 0.1)
				(type default)
			)
			(layer "F.Fab")
		)
		(fp_line
			(start -0.67945 0.3048)
			(end -0.67945 -0.305054)
			(stroke
				(width 0.1)
				(type default)
			)
			(layer "F.Fab")
		)
		(fp_line
			(start -0.67945 -0.305054)
			(end -0.12065 -0.305054)
			(stroke
				(width 0.1)
				(type default)
			)
			(layer "F.Fab")
		)
		(pad "1" smd circle
			(at -0.40005 0 180)
			(size 0 0)
			(layers "F.Cu" "F.Mask" "F.Paste")
			(net "P3V3_AUX")
		)
		(pad "2" smd circle
			(at 0.40005 0 180)
			(size 0 0)
			(layers "F.Cu" "F.Mask" "F.Paste")
			(net "PRSNT_SWB")
		)
	)
	(footprint ""
		(layer "F.Cu")
		(at 346.995496 -26.804366 -90)
		(property "Reference" "R1024"
			(at 0 0 270)
			(layer "F.SilkS")
			(hide yes)
			(effects
				(font
					(size 1.27 1.27)
				)
			)
		)
		(property "Value" ""
			(at 0 0 270)
			(layer "F.Fab")
			(effects
				(font
					(size 1.27 1.27)
				)
			)
		)
		(duplicate_pad_numbers_are_jumpers no)
		(fp_line
			(start -0.7874 0.4064)
			(end -0.7874 -0.4064)
			(stroke
				(width 0.1524)
				(type default)
			)
			(layer "F.SilkS")
		)
		(fp_line
			(start 0.7874 0.4064)
			(end -0.7874 0.4064)
			(stroke
				(width 0.1524)
				(type default)
			)
			(layer "F.SilkS")
		)
		(fp_line
			(start -0.7874 -0.4064)
			(end 0.7874 -0.4064)
			(stroke
				(width 0.1524)
				(type default)
			)
			(layer "F.SilkS")
		)
		(fp_line
			(start 0.7874 -0.4064)
			(end 0.7874 0.4064)
			(stroke
				(width 0.1524)
				(type default)
			)
			(layer "F.SilkS")
		)
		(fp_line
			(start -0.67945 0.3048)
			(end -0.67945 -0.305054)
			(stroke
				(width 0.1)
				(type default)
			)
			(layer "F.Fab")
		)
		(fp_line
			(start -0.12065 0.3048)
			(end -0.67945 0.3048)
			(stroke
				(width 0.1)
				(type default)
			)
			(layer "F.Fab")
		)
		(fp_line
			(start 0.120396 0.3048)
			(end 0.120396 0.2794)
			(stroke
				(width 0.1)
				(type default)
			)
			(layer "F.Fab")
		)
		(fp_line
			(start 0.67945 0.3048)
			(end 0.120396 0.3048)
			(stroke
				(width 0.1)
				(type default)
			)
			(layer "F.Fab")
		)
		(fp_line
			(start -0.12065 0.2794)
			(end -0.12065 0.3048)
			(stroke
				(width 0.1)
				(type default)
			)
			(layer "F.Fab")
		)
		(fp_line
			(start 0.120396 0.2794)
			(end -0.12065 0.2794)
			(stroke
				(width 0.1)
				(type default)
			)
			(layer "F.Fab")
		)
		(fp_line
			(start -0.12065 -0.2794)
			(end 0.12065 -0.2794)
			(stroke
				(width 0.1)
				(type default)
			)
			(layer "F.Fab")
		)
		(fp_line
			(start 0.12065 -0.2794)
			(end 0.12065 -0.3048)
			(stroke
				(width 0.1)
				(type default)
			)
			(layer "F.Fab")
		)
		(fp_line
			(start 0.12065 -0.3048)
			(end 0.67945 -0.3048)
			(stroke
				(width 0.1)
				(type default)
			)
			(layer "F.Fab")
		)
		(fp_line
			(start 0.67945 -0.3048)
			(end 0.67945 0.3048)
			(stroke
				(width 0.1)
				(type default)
			)
			(layer "F.Fab")
		)
		(fp_line
			(start -0.67945 -0.305054)
			(end -0.12065 -0.305054)
			(stroke
				(width 0.1)
				(type default)
			)
			(layer "F.Fab")
		)
		(fp_line
			(start -0.12065 -0.305054)
			(end -0.12065 -0.2794)
			(stroke
				(width 0.1)
				(type default)
			)
			(layer "F.Fab")
		)
		(pad "1" smd circle
			(at -0.40005 0 270)
			(size 0 0)
			(layers "F.Cu" "F.Mask" "F.Paste")
			(net "JTAG_DBP_TCK_PCH")
		)
		(pad "2" smd circle
			(at 0.40005 0 270)
			(size 0 0)
			(layers "F.Cu" "F.Mask" "F.Paste")
			(net "GND")
		)
	)
	(footprint ""
		(layer "F.Cu")
		(at 93.100398 -408.517344 -90)
		(property "Reference" "C681"
			(at 0 0 270)
			(layer "F.SilkS")
			(hide yes)
			(effects
				(font
					(size 1.27 1.27)
				)
			)
		)
		(property "Value" ""
			(at 0 0 270)
			(layer "F.Fab")
			(effects
				(font
					(size 1.27 1.27)
				)
			)
		)
		(duplicate_pad_numbers_are_jumpers no)
		(fp_line
			(start -0.299974 0.150114)
			(end -0.299974 -0.150114)
			(stroke
				(width 0.1)
				(type default)
			)
			(layer "F.Fab")
		)
		(fp_line
			(start 0.299974 0.150114)
			(end -0.299974 0.150114)
			(stroke
				(width 0.1)
				(type default)
			)
			(layer "F.Fab")
		)
		(fp_line
			(start -0.299974 -0.150114)
			(end 0.299974 -0.150114)
			(stroke
				(width 0.1)
				(type default)
			)
			(layer "F.Fab")
		)
		(fp_line
			(start 0.299974 -0.150114)
			(end 0.299974 0.150114)
			(stroke
				(width 0.1)
				(type default)
			)
			(layer "F.Fab")
		)
		(pad "1" smd rect
			(at -0.2667 0 270)
			(size 0.3048 0.381)
			(layers "F.Cu" "F.Mask" "F.Paste")
			(net "P5E_CPU1_PE4_TX_C_DP<14>")
		)
		(pad "2" smd rect
			(at 0.2667 0 270)
			(size 0.3048 0.381)
			(layers "F.Cu" "F.Mask" "F.Paste")
			(net "P5E_CPU1_PE4_TX_DP<14>")
		)
	)
	(footprint ""
		(layer "F.Cu")
		(at 364.50143 -252.956314 -90)
		(property "Reference" "C1016"
			(at 0 0 270)
			(layer "F.SilkS")
			(hide yes)
			(effects
				(font
					(size 1.27 1.27)
				)
			)
		)
		(property "Value" ""
			(at 0 0 270)
			(layer "F.Fab")
			(effects
				(font
					(size 1.27 1.27)
				)
			)
		)
		(duplicate_pad_numbers_are_jumpers no)
		(fp_line
			(start -0.7874 0.4064)
			(end -0.7874 -0.4064)
			(stroke
				(width 0.1524)
				(type default)
			)
			(layer "F.SilkS")
		)
		(fp_line
			(start 0.7874 0.4064)
			(end -0.7874 0.4064)
			(stroke
				(width 0.1524)
				(type default)
			)
			(layer "F.SilkS")
		)
		(fp_line
			(start -0.7874 -0.4064)
			(end 0.7874 -0.4064)
			(stroke
				(width 0.1524)
				(type default)
			)
			(layer "F.SilkS")
		)
		(fp_line
			(start 0.7874 -0.4064)
			(end 0.7874 0.4064)
			(stroke
				(width 0.1524)
				(type default)
			)
			(layer "F.SilkS")
		)
		(fp_line
			(start -0.67945 0.3048)
			(end -0.67945 -0.305054)
			(stroke
				(width 0.1)
				(type default)
			)
			(layer "F.Fab")
		)
		(fp_line
			(start -0.12065 0.3048)
			(end -0.67945 0.3048)
			(stroke
				(width 0.1)
				(type default)
			)
			(layer "F.Fab")
		)
		(fp_line
			(start 0.120396 0.3048)
			(end 0.120396 0.2794)
			(stroke
				(width 0.1)
				(type default)
			)
			(layer "F.Fab")
		)
		(fp_line
			(start 0.67945 0.3048)
			(end 0.120396 0.3048)
			(stroke
				(width 0.1)
				(type default)
			)
			(layer "F.Fab")
		)
		(fp_line
			(start -0.12065 0.2794)
			(end -0.12065 0.3048)
			(stroke
				(width 0.1)
				(type default)
			)
			(layer "F.Fab")
		)
		(fp_line
			(start 0.120396 0.2794)
			(end -0.12065 0.2794)
			(stroke
				(width 0.1)
				(type default)
			)
			(layer "F.Fab")
		)
		(fp_line
			(start -0.12065 -0.2794)
			(end 0.12065 -0.2794)
			(stroke
				(width 0.1)
				(type default)
			)
			(layer "F.Fab")
		)
		(fp_line
			(start 0.12065 -0.2794)
			(end 0.12065 -0.3048)
			(stroke
				(width 0.1)
				(type default)
			)
			(layer "F.Fab")
		)
		(fp_line
			(start 0.12065 -0.3048)
			(end 0.67945 -0.3048)
			(stroke
				(width 0.1)
				(type default)
			)
			(layer "F.Fab")
		)
		(fp_line
			(start 0.67945 -0.3048)
			(end 0.67945 0.3048)
			(stroke
				(width 0.1)
				(type default)
			)
			(layer "F.Fab")
		)
		(fp_line
			(start -0.67945 -0.305054)
			(end -0.12065 -0.305054)
			(stroke
				(width 0.1)
				(type default)
			)
			(layer "F.Fab")
		)
		(fp_line
			(start -0.12065 -0.305054)
			(end -0.12065 -0.2794)
			(stroke
				(width 0.1)
				(type default)
			)
			(layer "F.Fab")
		)
		(pad "1" smd circle
			(at -0.40005 0 270)
			(size 0 0)
			(layers "F.Cu" "F.Mask" "F.Paste")
			(net "PVCCIN_CPU0")
		)
		(pad "2" smd circle
			(at 0.40005 0 270)
			(size 0 0)
			(layers "F.Cu" "F.Mask" "F.Paste")
			(net "GND")
		)
	)
	(footprint ""
		(layer "F.Cu")
		(at 45.136308 -353.61626 -90)
		(property "Reference" "PC1196_P1_4"
			(at 0 0 270)
			(layer "F.SilkS")
			(hide yes)
			(effects
				(font
					(size 1.27 1.27)
				)
			)
		)
		(property "Value" ""
			(at 0 0 270)
			(layer "F.Fab")
			(effects
				(font
					(size 1.27 1.27)
				)
			)
		)
		(duplicate_pad_numbers_are_jumpers no)
		(fp_line
			(start -0.7874 0.4064)
			(end -0.7874 -0.4064)
			(stroke
				(width 0.1524)
				(type default)
			)
			(layer "F.SilkS")
		)
		(fp_line
			(start 0.7874 0.4064)
			(end -0.7874 0.4064)
			(stroke
				(width 0.1524)
				(type default)
			)
			(layer "F.SilkS")
		)
		(fp_line
			(start -0.7874 -0.4064)
			(end 0.7874 -0.4064)
			(stroke
				(width 0.1524)
				(type default)
			)
			(layer "F.SilkS")
		)
		(fp_line
			(start 0.7874 -0.4064)
			(end 0.7874 0.4064)
			(stroke
				(width 0.1524)
				(type default)
			)
			(layer "F.SilkS")
		)
		(fp_line
			(start -0.67945 0.3048)
			(end -0.67945 -0.305054)
			(stroke
				(width 0.1)
				(type default)
			)
			(layer "F.Fab")
		)
		(fp_line
			(start -0.12065 0.3048)
			(end -0.67945 0.3048)
			(stroke
				(width 0.1)
				(type default)
			)
			(layer "F.Fab")
		)
		(fp_line
			(start 0.120396 0.3048)
			(end 0.120396 0.2794)
			(stroke
				(width 0.1)
				(type default)
			)
			(layer "F.Fab")
		)
		(fp_line
			(start 0.67945 0.3048)
			(end 0.120396 0.3048)
			(stroke
				(width 0.1)
				(type default)
			)
			(layer "F.Fab")
		)
		(fp_line
			(start -0.12065 0.2794)
			(end -0.12065 0.3048)
			(stroke
				(width 0.1)
				(type default)
			)
			(layer "F.Fab")
		)
		(fp_line
			(start 0.120396 0.2794)
			(end -0.12065 0.2794)
			(stroke
				(width 0.1)
				(type default)
			)
			(layer "F.Fab")
		)
		(fp_line
			(start -0.12065 -0.2794)
			(end 0.12065 -0.2794)
			(stroke
				(width 0.1)
				(type default)
			)
			(layer "F.Fab")
		)
		(fp_line
			(start 0.12065 -0.2794)
			(end 0.12065 -0.3048)
			(stroke
				(width 0.1)
				(type default)
			)
			(layer "F.Fab")
		)
		(fp_line
			(start 0.12065 -0.3048)
			(end 0.67945 -0.3048)
			(stroke
				(width 0.1)
				(type default)
			)
			(layer "F.Fab")
		)
		(fp_line
			(start 0.67945 -0.3048)
			(end 0.67945 0.3048)
			(stroke
				(width 0.1)
				(type default)
			)
			(layer "F.Fab")
		)
		(fp_line
			(start -0.67945 -0.305054)
			(end -0.12065 -0.305054)
			(stroke
				(width 0.1)
				(type default)
			)
			(layer "F.Fab")
		)
		(fp_line
			(start -0.12065 -0.305054)
			(end -0.12065 -0.2794)
			(stroke
				(width 0.1)
				(type default)
			)
			(layer "F.Fab")
		)
		(pad "1" smd circle
			(at -0.40005 0 270)
			(size 0 0)
			(layers "F.Cu" "F.Mask" "F.Paste")
			(net "SW_P12V_PVCCFA_EHV_FIVRA_CPU1_L")
		)
		(pad "2" smd circle
			(at 0.40005 0 270)
			(size 0 0)
			(layers "F.Cu" "F.Mask" "F.Paste")
			(net "GND")
		)
	)
	(footprint ""
		(layer "F.Cu")
		(at 151.5872 -127.897128 90)
		(property "Reference" "C1825"
			(at 0 0 90)
			(layer "F.SilkS")
			(hide yes)
			(effects
				(font
					(size 1.27 1.27)
				)
			)
		)
		(property "Value" ""
			(at 0 0 90)
			(layer "F.Fab")
			(effects
				(font
					(size 1.27 1.27)
				)
			)
		)
		(duplicate_pad_numbers_are_jumpers no)
		(fp_line
			(start 0.7874 -0.4064)
			(end 0.7874 0.4064)
			(stroke
				(width 0.1524)
				(type default)
			)
			(layer "F.SilkS")
		)
		(fp_line
			(start -0.7874 -0.4064)
			(end 0.7874 -0.4064)
			(stroke
				(width 0.1524)
				(type default)
			)
			(layer "F.SilkS")
		)
		(fp_line
			(start 0.7874 0.4064)
			(end -0.7874 0.4064)
			(stroke
				(width 0.1524)
				(type default)
			)
			(layer "F.SilkS")
		)
		(fp_line
			(start -0.7874 0.4064)
			(end -0.7874 -0.4064)
			(stroke
				(width 0.1524)
				(type default)
			)
			(layer "F.SilkS")
		)
		(fp_line
			(start -0.12065 -0.305054)
			(end -0.12065 -0.2794)
			(stroke
				(width 0.1)
				(type default)
			)
			(layer "F.Fab")
		)
		(fp_line
			(start -0.67945 -0.305054)
			(end -0.12065 -0.305054)
			(stroke
				(width 0.1)
				(type default)
			)
			(layer "F.Fab")
		)
		(fp_line
			(start 0.67945 -0.3048)
			(end 0.67945 0.3048)
			(stroke
				(width 0.1)
				(type default)
			)
			(layer "F.Fab")
		)
		(fp_line
			(start 0.12065 -0.3048)
			(end 0.67945 -0.3048)
			(stroke
				(width 0.1)
				(type default)
			)
			(layer "F.Fab")
		)
		(fp_line
			(start 0.12065 -0.2794)
			(end 0.12065 -0.3048)
			(stroke
				(width 0.1)
				(type default)
			)
			(layer "F.Fab")
		)
		(fp_line
			(start -0.12065 -0.2794)
			(end 0.12065 -0.2794)
			(stroke
				(width 0.1)
				(type default)
			)
			(layer "F.Fab")
		)
		(fp_line
			(start 0.120396 0.2794)
			(end -0.12065 0.2794)
			(stroke
				(width 0.1)
				(type default)
			)
			(layer "F.Fab")
		)
		(fp_line
			(start -0.12065 0.2794)
			(end -0.12065 0.3048)
			(stroke
				(width 0.1)
				(type default)
			)
			(layer "F.Fab")
		)
		(fp_line
			(start 0.67945 0.3048)
			(end 0.120396 0.3048)
			(stroke
				(width 0.1)
				(type default)
			)
			(layer "F.Fab")
		)
		(fp_line
			(start 0.120396 0.3048)
			(end 0.120396 0.2794)
			(stroke
				(width 0.1)
				(type default)
			)
			(layer "F.Fab")
		)
		(fp_line
			(start -0.12065 0.3048)
			(end -0.67945 0.3048)
			(stroke
				(width 0.1)
				(type default)
			)
			(layer "F.Fab")
		)
		(fp_line
			(start -0.67945 0.3048)
			(end -0.67945 -0.305054)
			(stroke
				(width 0.1)
				(type default)
			)
			(layer "F.Fab")
		)
		(pad "1" smd circle
			(at -0.40005 0 90)
			(size 0 0)
			(layers "F.Cu" "F.Mask" "F.Paste")
			(net "P3V3_AUX")
		)
		(pad "2" smd circle
			(at 0.40005 0 90)
			(size 0 0)
			(layers "F.Cu" "F.Mask" "F.Paste")
			(net "GND")
		)
	)
	(footprint ""
		(layer "F.Cu")
		(at 66.022982 -36.906708 90)
		(property "Reference" "R4059"
			(at 0 0 90)
			(layer "F.SilkS")
			(hide yes)
			(effects
				(font
					(size 1.27 1.27)
				)
			)
		)
		(property "Value" ""
			(at 0 0 90)
			(layer "F.Fab")
			(effects
				(font
					(size 1.27 1.27)
				)
			)
		)
		(duplicate_pad_numbers_are_jumpers no)
		(fp_line
			(start 0.7874 -0.4064)
			(end 0.7874 0.4064)
			(stroke
				(width 0.1524)
				(type default)
			)
			(layer "F.SilkS")
		)
		(fp_line
			(start -0.7874 -0.4064)
			(end 0.7874 -0.4064)
			(stroke
				(width 0.1524)
				(type default)
			)
			(layer "F.SilkS")
		)
		(fp_line
			(start 0.7874 0.4064)
			(end -0.7874 0.4064)
			(stroke
				(width 0.1524)
				(type default)
			)
			(layer "F.SilkS")
		)
		(fp_line
			(start -0.7874 0.4064)
			(end -0.7874 -0.4064)
			(stroke
				(width 0.1524)
				(type default)
			)
			(layer "F.SilkS")
		)
		(fp_line
			(start -0.12065 -0.305054)
			(end -0.12065 -0.2794)
			(stroke
				(width 0.1)
				(type default)
			)
			(layer "F.Fab")
		)
		(fp_line
			(start -0.67945 -0.305054)
			(end -0.12065 -0.305054)
			(stroke
				(width 0.1)
				(type default)
			)
			(layer "F.Fab")
		)
		(fp_line
			(start 0.67945 -0.3048)
			(end 0.67945 0.3048)
			(stroke
				(width 0.1)
				(type default)
			)
			(layer "F.Fab")
		)
		(fp_line
			(start 0.12065 -0.3048)
			(end 0.67945 -0.3048)
			(stroke
				(width 0.1)
				(type default)
			)
			(layer "F.Fab")
		)
		(fp_line
			(start 0.12065 -0.2794)
			(end 0.12065 -0.3048)
			(stroke
				(width 0.1)
				(type default)
			)
			(layer "F.Fab")
		)
		(fp_line
			(start -0.12065 -0.2794)
			(end 0.12065 -0.2794)
			(stroke
				(width 0.1)
				(type default)
			)
			(layer "F.Fab")
		)
		(fp_line
			(start 0.120396 0.2794)
			(end -0.12065 0.2794)
			(stroke
				(width 0.1)
				(type default)
			)
			(layer "F.Fab")
		)
		(fp_line
			(start -0.12065 0.2794)
			(end -0.12065 0.3048)
			(stroke
				(width 0.1)
				(type default)
			)
			(layer "F.Fab")
		)
		(fp_line
			(start 0.67945 0.3048)
			(end 0.120396 0.3048)
			(stroke
				(width 0.1)
				(type default)
			)
			(layer "F.Fab")
		)
		(fp_line
			(start 0.120396 0.3048)
			(end 0.120396 0.2794)
			(stroke
				(width 0.1)
				(type default)
			)
			(layer "F.Fab")
		)
		(fp_line
			(start -0.12065 0.3048)
			(end -0.67945 0.3048)
			(stroke
				(width 0.1)
				(type default)
			)
			(layer "F.Fab")
		)
		(fp_line
			(start -0.67945 0.3048)
			(end -0.67945 -0.305054)
			(stroke
				(width 0.1)
				(type default)
			)
			(layer "F.Fab")
		)
		(pad "1" smd circle
			(at -0.40005 0 90)
			(size 0 0)
			(layers "F.Cu" "F.Mask" "F.Paste")
			(net "HP_LVC3_OCP_V3_2_EN")
		)
		(pad "2" smd circle
			(at 0.40005 0 90)
			(size 0 0)
			(layers "F.Cu" "F.Mask" "F.Paste")
			(net "P12V_OCP_EN_2_R")
		)
	)
	(footprint ""
		(layer "F.Cu")
		(at 64.185038 -402.371052 -90)
		(property "Reference" "C721"
			(at 0 0 270)
			(layer "F.SilkS")
			(hide yes)
			(effects
				(font
					(size 1.27 1.27)
				)
			)
		)
		(property "Value" ""
			(at 0 0 270)
			(layer "F.Fab")
			(effects
				(font
					(size 1.27 1.27)
				)
			)
		)
		(duplicate_pad_numbers_are_jumpers no)
		(fp_line
			(start -0.299974 0.150114)
			(end -0.299974 -0.150114)
			(stroke
				(width 0.1)
				(type default)
			)
			(layer "F.Fab")
		)
		(fp_line
			(start 0.299974 0.150114)
			(end -0.299974 0.150114)
			(stroke
				(width 0.1)
				(type default)
			)
			(layer "F.Fab")
		)
		(fp_line
			(start -0.299974 -0.150114)
			(end 0.299974 -0.150114)
			(stroke
				(width 0.1)
				(type default)
			)
			(layer "F.Fab")
		)
		(fp_line
			(start 0.299974 -0.150114)
			(end 0.299974 0.150114)
			(stroke
				(width 0.1)
				(type default)
			)
			(layer "F.Fab")
		)
		(pad "1" smd rect
			(at -0.2667 0 270)
			(size 0.3048 0.381)
			(layers "F.Cu" "F.Mask" "F.Paste")
			(net "P5E_CPU1_PE0_TX_C_DP<10>")
		)
		(pad "2" smd rect
			(at 0.2667 0 270)
			(size 0.3048 0.381)
			(layers "F.Cu" "F.Mask" "F.Paste")
			(net "P5E_CPU1_PE0_TX_DP<10>")
		)
	)
	(footprint ""
		(layer "F.Cu")
		(at 421.15359 -163.477194 -90)
		(property "Reference" "PR2718"
			(at 0 0 270)
			(layer "F.SilkS")
			(hide yes)
			(effects
				(font
					(size 1.27 1.27)
				)
			)
		)
		(property "Value" ""
			(at 0 0 270)
			(layer "F.Fab")
			(effects
				(font
					(size 1.27 1.27)
				)
			)
		)
		(duplicate_pad_numbers_are_jumpers no)
		(fp_line
			(start -0.7874 0.4064)
			(end -0.7874 -0.4064)
			(stroke
				(width 0.1524)
				(type default)
			)
			(layer "F.SilkS")
		)
		(fp_line
			(start 0.7874 0.4064)
			(end -0.7874 0.4064)
			(stroke
				(width 0.1524)
				(type default)
			)
			(layer "F.SilkS")
		)
		(fp_line
			(start -0.7874 -0.4064)
			(end 0.7874 -0.4064)
			(stroke
				(width 0.1524)
				(type default)
			)
			(layer "F.SilkS")
		)
		(fp_line
			(start 0.7874 -0.4064)
			(end 0.7874 0.4064)
			(stroke
				(width 0.1524)
				(type default)
			)
			(layer "F.SilkS")
		)
		(fp_line
			(start -0.67945 0.3048)
			(end -0.67945 -0.305054)
			(stroke
				(width 0.1)
				(type default)
			)
			(layer "F.Fab")
		)
		(fp_line
			(start -0.12065 0.3048)
			(end -0.67945 0.3048)
			(stroke
				(width 0.1)
				(type default)
			)
			(layer "F.Fab")
		)
		(fp_line
			(start 0.120396 0.3048)
			(end 0.120396 0.2794)
			(stroke
				(width 0.1)
				(type default)
			)
			(layer "F.Fab")
		)
		(fp_line
			(start 0.67945 0.3048)
			(end 0.120396 0.3048)
			(stroke
				(width 0.1)
				(type default)
			)
			(layer "F.Fab")
		)
		(fp_line
			(start -0.12065 0.2794)
			(end -0.12065 0.3048)
			(stroke
				(width 0.1)
				(type default)
			)
			(layer "F.Fab")
		)
		(fp_line
			(start 0.120396 0.2794)
			(end -0.12065 0.2794)
			(stroke
				(width 0.1)
				(type default)
			)
			(layer "F.Fab")
		)
		(fp_line
			(start -0.12065 -0.2794)
			(end 0.12065 -0.2794)
			(stroke
				(width 0.1)
				(type default)
			)
			(layer "F.Fab")
		)
		(fp_line
			(start 0.12065 -0.2794)
			(end 0.12065 -0.3048)
			(stroke
				(width 0.1)
				(type default)
			)
			(layer "F.Fab")
		)
		(fp_line
			(start 0.12065 -0.3048)
			(end 0.67945 -0.3048)
			(stroke
				(width 0.1)
				(type default)
			)
			(layer "F.Fab")
		)
		(fp_line
			(start 0.67945 -0.3048)
			(end 0.67945 0.3048)
			(stroke
				(width 0.1)
				(type default)
			)
			(layer "F.Fab")
		)
		(fp_line
			(start -0.67945 -0.305054)
			(end -0.12065 -0.305054)
			(stroke
				(width 0.1)
				(type default)
			)
			(layer "F.Fab")
		)
		(fp_line
			(start -0.12065 -0.305054)
			(end -0.12065 -0.2794)
			(stroke
				(width 0.1)
				(type default)
			)
			(layer "F.Fab")
		)
		(pad "1" smd circle
			(at -0.40005 0 270)
			(size 0 0)
			(layers "F.Cu" "F.Mask" "F.Paste")
			(net "PVCCD_HV_CPU0_LSET1")
		)
		(pad "2" smd circle
			(at 0.40005 0 270)
			(size 0 0)
			(layers "F.Cu" "F.Mask" "F.Paste")
			(net "GND")
		)
	)
	(footprint ""
		(layer "F.Cu")
		(at 119.508016 -255.0541 90)
		(property "Reference" "C268"
			(at 0 0 90)
			(layer "F.SilkS")
			(hide yes)
			(effects
				(font
					(size 1.27 1.27)
				)
			)
		)
		(property "Value" ""
			(at 0 0 90)
			(layer "F.Fab")
			(effects
				(font
					(size 1.27 1.27)
				)
			)
		)
		(duplicate_pad_numbers_are_jumpers no)
		(fp_line
			(start 0.7874 -0.4064)
			(end 0.7874 0.4064)
			(stroke
				(width 0.1524)
				(type default)
			)
			(layer "F.SilkS")
		)
		(fp_line
			(start -0.7874 -0.4064)
			(end 0.7874 -0.4064)
			(stroke
				(width 0.1524)
				(type default)
			)
			(layer "F.SilkS")
		)
		(fp_line
			(start 0.7874 0.4064)
			(end -0.7874 0.4064)
			(stroke
				(width 0.1524)
				(type default)
			)
			(layer "F.SilkS")
		)
		(fp_line
			(start -0.7874 0.4064)
			(end -0.7874 -0.4064)
			(stroke
				(width 0.1524)
				(type default)
			)
			(layer "F.SilkS")
		)
		(fp_line
			(start -0.12065 -0.305054)
			(end -0.12065 -0.2794)
			(stroke
				(width 0.1)
				(type default)
			)
			(layer "F.Fab")
		)
		(fp_line
			(start -0.67945 -0.305054)
			(end -0.12065 -0.305054)
			(stroke
				(width 0.1)
				(type default)
			)
			(layer "F.Fab")
		)
		(fp_line
			(start 0.67945 -0.3048)
			(end 0.67945 0.3048)
			(stroke
				(width 0.1)
				(type default)
			)
			(layer "F.Fab")
		)
		(fp_line
			(start 0.12065 -0.3048)
			(end 0.67945 -0.3048)
			(stroke
				(width 0.1)
				(type default)
			)
			(layer "F.Fab")
		)
		(fp_line
			(start 0.12065 -0.2794)
			(end 0.12065 -0.3048)
			(stroke
				(width 0.1)
				(type default)
			)
			(layer "F.Fab")
		)
		(fp_line
			(start -0.12065 -0.2794)
			(end 0.12065 -0.2794)
			(stroke
				(width 0.1)
				(type default)
			)
			(layer "F.Fab")
		)
		(fp_line
			(start 0.120396 0.2794)
			(end -0.12065 0.2794)
			(stroke
				(width 0.1)
				(type default)
			)
			(layer "F.Fab")
		)
		(fp_line
			(start -0.12065 0.2794)
			(end -0.12065 0.3048)
			(stroke
				(width 0.1)
				(type default)
			)
			(layer "F.Fab")
		)
		(fp_line
			(start 0.67945 0.3048)
			(end 0.120396 0.3048)
			(stroke
				(width 0.1)
				(type default)
			)
			(layer "F.Fab")
		)
		(fp_line
			(start 0.120396 0.3048)
			(end 0.120396 0.2794)
			(stroke
				(width 0.1)
				(type default)
			)
			(layer "F.Fab")
		)
		(fp_line
			(start -0.12065 0.3048)
			(end -0.67945 0.3048)
			(stroke
				(width 0.1)
				(type default)
			)
			(layer "F.Fab")
		)
		(fp_line
			(start -0.67945 0.3048)
			(end -0.67945 -0.305054)
			(stroke
				(width 0.1)
				(type default)
			)
			(layer "F.Fab")
		)
		(pad "1" smd circle
			(at -0.40005 0 90)
			(size 0 0)
			(layers "F.Cu" "F.Mask" "F.Paste")
			(net "PVCCIN_CPU1")
		)
		(pad "2" smd circle
			(at 0.40005 0 90)
			(size 0 0)
			(layers "F.Cu" "F.Mask" "F.Paste")
			(net "GND")
		)
	)
	(footprint ""
		(layer "F.Cu")
		(at 382.968754 -347.509846 -90)
		(property "Reference" "PC1344"
			(at 0 0 270)
			(layer "F.SilkS")
			(hide yes)
			(effects
				(font
					(size 1.27 1.27)
				)
			)
		)
		(property "Value" ""
			(at 0 0 270)
			(layer "F.Fab")
			(effects
				(font
					(size 1.27 1.27)
				)
			)
		)
		(duplicate_pad_numbers_are_jumpers no)
		(fp_line
			(start -0.7874 0.4064)
			(end -0.7874 -0.4064)
			(stroke
				(width 0.1524)
				(type default)
			)
			(layer "F.SilkS")
		)
		(fp_line
			(start 0.7874 0.4064)
			(end -0.7874 0.4064)
			(stroke
				(width 0.1524)
				(type default)
			)
			(layer "F.SilkS")
		)
		(fp_line
			(start -0.7874 -0.4064)
			(end 0.7874 -0.4064)
			(stroke
				(width 0.1524)
				(type default)
			)
			(layer "F.SilkS")
		)
		(fp_line
			(start 0.7874 -0.4064)
			(end 0.7874 0.4064)
			(stroke
				(width 0.1524)
				(type default)
			)
			(layer "F.SilkS")
		)
		(fp_line
			(start -0.67945 0.3048)
			(end -0.67945 -0.305054)
			(stroke
				(width 0.1)
				(type default)
			)
			(layer "F.Fab")
		)
		(fp_line
			(start -0.12065 0.3048)
			(end -0.67945 0.3048)
			(stroke
				(width 0.1)
				(type default)
			)
			(layer "F.Fab")
		)
		(fp_line
			(start 0.120396 0.3048)
			(end 0.120396 0.2794)
			(stroke
				(width 0.1)
				(type default)
			)
			(layer "F.Fab")
		)
		(fp_line
			(start 0.67945 0.3048)
			(end 0.120396 0.3048)
			(stroke
				(width 0.1)
				(type default)
			)
			(layer "F.Fab")
		)
		(fp_line
			(start -0.12065 0.2794)
			(end -0.12065 0.3048)
			(stroke
				(width 0.1)
				(type default)
			)
			(layer "F.Fab")
		)
		(fp_line
			(start 0.120396 0.2794)
			(end -0.12065 0.2794)
			(stroke
				(width 0.1)
				(type default)
			)
			(layer "F.Fab")
		)
		(fp_line
			(start -0.12065 -0.2794)
			(end 0.12065 -0.2794)
			(stroke
				(width 0.1)
				(type default)
			)
			(layer "F.Fab")
		)
		(fp_line
			(start 0.12065 -0.2794)
			(end 0.12065 -0.3048)
			(stroke
				(width 0.1)
				(type default)
			)
			(layer "F.Fab")
		)
		(fp_line
			(start 0.12065 -0.3048)
			(end 0.67945 -0.3048)
			(stroke
				(width 0.1)
				(type default)
			)
			(layer "F.Fab")
		)
		(fp_line
			(start 0.67945 -0.3048)
			(end 0.67945 0.3048)
			(stroke
				(width 0.1)
				(type default)
			)
			(layer "F.Fab")
		)
		(fp_line
			(start -0.67945 -0.305054)
			(end -0.12065 -0.305054)
			(stroke
				(width 0.1)
				(type default)
			)
			(layer "F.Fab")
		)
		(fp_line
			(start -0.12065 -0.305054)
			(end -0.12065 -0.2794)
			(stroke
				(width 0.1)
				(type default)
			)
			(layer "F.Fab")
		)
		(pad "1" smd circle
			(at -0.40005 0 270)
			(size 0 0)
			(layers "F.Cu" "F.Mask" "F.Paste")
			(net "GND")
		)
		(pad "2" smd circle
			(at 0.40005 0 270)
			(size 0 0)
			(layers "F.Cu" "F.Mask" "F.Paste")
			(net "PVCCIN_CPU0_VREF")
		)
	)
	(footprint ""
		(layer "F.Cu")
		(at 307.14188 -49.621948 180)
		(property "Reference" "R497"
			(at 0 0 180)
			(layer "F.SilkS")
			(hide yes)
			(effects
				(font
					(size 1.27 1.27)
				)
			)
		)
		(property "Value" ""
			(at 0 0 180)
			(layer "F.Fab")
			(effects
				(font
					(size 1.27 1.27)
				)
			)
		)
		(duplicate_pad_numbers_are_jumpers no)
		(fp_line
			(start 0.7874 0.4064)
			(end -0.7874 0.4064)
			(stroke
				(width 0.1524)
				(type default)
			)
			(layer "F.SilkS")
		)
		(fp_line
			(start 0.7874 -0.4064)
			(end 0.7874 0.4064)
			(stroke
				(width 0.1524)
				(type default)
			)
			(layer "F.SilkS")
		)
		(fp_line
			(start -0.7874 0.4064)
			(end -0.7874 -0.4064)
			(stroke
				(width 0.1524)
				(type default)
			)
			(layer "F.SilkS")
		)
		(fp_line
			(start -0.7874 -0.4064)
			(end 0.7874 -0.4064)
			(stroke
				(width 0.1524)
				(type default)
			)
			(layer "F.SilkS")
		)
		(fp_line
			(start 0.67945 0.3048)
			(end 0.120396 0.3048)
			(stroke
				(width 0.1)
				(type default)
			)
			(layer "F.Fab")
		)
		(fp_line
			(start 0.67945 -0.3048)
			(end 0.67945 0.3048)
			(stroke
				(width 0.1)
				(type default)
			)
			(layer "F.Fab")
		)
		(fp_line
			(start 0.12065 -0.2794)
			(end 0.12065 -0.3048)
			(stroke
				(width 0.1)
				(type default)
			)
			(layer "F.Fab")
		)
		(fp_line
			(start 0.12065 -0.3048)
			(end 0.67945 -0.3048)
			(stroke
				(width 0.1)
				(type default)
			)
			(layer "F.Fab")
		)
		(fp_line
			(start 0.120396 0.3048)
			(end 0.120396 0.2794)
			(stroke
				(width 0.1)
				(type default)
			)
			(layer "F.Fab")
		)
		(fp_line
			(start 0.120396 0.2794)
			(end -0.12065 0.2794)
			(stroke
				(width 0.1)
				(type default)
			)
			(layer "F.Fab")
		)
		(fp_line
			(start -0.12065 0.3048)
			(end -0.67945 0.3048)
			(stroke
				(width 0.1)
				(type default)
			)
			(layer "F.Fab")
		)
		(fp_line
			(start -0.12065 0.2794)
			(end -0.12065 0.3048)
			(stroke
				(width 0.1)
				(type default)
			)
			(layer "F.Fab")
		)
		(fp_line
			(start -0.12065 -0.2794)
			(end 0.12065 -0.2794)
			(stroke
				(width 0.1)
				(type default)
			)
			(layer "F.Fab")
		)
		(fp_line
			(start -0.12065 -0.305054)
			(end -0.12065 -0.2794)
			(stroke
				(width 0.1)
				(type default)
			)
			(layer "F.Fab")
		)
		(fp_line
			(start -0.67945 0.3048)
			(end -0.67945 -0.305054)
			(stroke
				(width 0.1)
				(type default)
			)
			(layer "F.Fab")
		)
		(fp_line
			(start -0.67945 -0.305054)
			(end -0.12065 -0.305054)
			(stroke
				(width 0.1)
				(type default)
			)
			(layer "F.Fab")
		)
		(pad "1" smd circle
			(at -0.40005 0 180)
			(size 0 0)
			(layers "F.Cu" "F.Mask" "F.Paste")
			(net "PD_RCOMP_1P8_3P3")
		)
		(pad "2" smd circle
			(at 0.40005 0 180)
			(size 0 0)
			(layers "F.Cu" "F.Mask" "F.Paste")
			(net "GND")
		)
	)
	(footprint ""
		(layer "F.Cu")
		(at 244.750844 -407.411936 -90)
		(property "Reference" "PR4"
			(at 0 0 270)
			(layer "F.SilkS")
			(hide yes)
			(effects
				(font
					(size 1.27 1.27)
				)
			)
		)
		(property "Value" ""
			(at 0 0 270)
			(layer "F.Fab")
			(effects
				(font
					(size 1.27 1.27)
				)
			)
		)
		(duplicate_pad_numbers_are_jumpers no)
		(fp_line
			(start -3.9878 3.5814)
			(end -3.9878 -3.5814)
			(stroke
				(width 0.1524)
				(type default)
			)
			(layer "F.SilkS")
		)
		(fp_line
			(start 3.9878 3.5814)
			(end -3.9878 3.5814)
			(stroke
				(width 0.1524)
				(type default)
			)
			(layer "F.SilkS")
		)
		(fp_line
			(start -3.9878 -3.5814)
			(end 3.9878 -3.5814)
			(stroke
				(width 0.1524)
				(type default)
			)
			(layer "F.SilkS")
		)
		(fp_line
			(start 3.9878 -3.5814)
			(end 3.9878 3.5814)
			(stroke
				(width 0.1524)
				(type default)
			)
			(layer "F.SilkS")
		)
		(fp_line
			(start -3.5306 3.353054)
			(end -3.5306 -3.353054)
			(stroke
				(width 0.1)
				(type default)
			)
			(layer "F.Fab")
		)
		(fp_line
			(start 3.5306 3.353054)
			(end -3.5306 3.353054)
			(stroke
				(width 0.1)
				(type default)
			)
			(layer "F.Fab")
		)
		(fp_line
			(start -3.5306 -3.353054)
			(end 3.5306 -3.353054)
			(stroke
				(width 0.1)
				(type default)
			)
			(layer "F.Fab")
		)
		(fp_line
			(start 3.5306 -3.353054)
			(end 3.5306 3.353054)
			(stroke
				(width 0.1)
				(type default)
			)
			(layer "F.Fab")
		)
		(pad "1A" smd rect
			(at -2.249932 0 90)
			(size 3.2004 6.858)
			(layers "F.Cu" "F.Mask" "F.Paste")
			(net "P12V_PSU")
		)
		(pad "1B" smd rect
			(at -0.776732 0 270)
			(size 0.254 0.508)
			(layers "F.Cu" "F.Mask" "F.Paste")
			(net "P12V_HSC_SENSE2_R1_P")
		)
		(pad "2A" smd rect
			(at 2.249932 0 90)
			(size 3.2004 6.858)
			(layers "F.Cu" "F.Mask" "F.Paste")
			(net "P12V_MAIN_R")
		)
		(pad "2B" smd rect
			(at 0.776732 0 270)
			(size 0.254 0.508)
			(layers "F.Cu" "F.Mask" "F.Paste")
			(net "P12V_HSC_SENSE2_R1_N")
		)
	)
	(footprint ""
		(layer "F.Cu")
		(at 143.764 -25.110948 180)
		(property "Reference" "R4628"
			(at 0 0 180)
			(layer "F.SilkS")
			(hide yes)
			(effects
				(font
					(size 1.27 1.27)
				)
			)
		)
		(property "Value" ""
			(at 0 0 180)
			(layer "F.Fab")
			(effects
				(font
					(size 1.27 1.27)
				)
			)
		)
		(duplicate_pad_numbers_are_jumpers no)
		(fp_line
			(start 0.7874 0.4064)
			(end -0.7874 0.4064)
			(stroke
				(width 0.1524)
				(type default)
			)
			(layer "F.SilkS")
		)
		(fp_line
			(start 0.7874 -0.4064)
			(end 0.7874 0.4064)
			(stroke
				(width 0.1524)
				(type default)
			)
			(layer "F.SilkS")
		)
		(fp_line
			(start -0.7874 0.4064)
			(end -0.7874 -0.4064)
			(stroke
				(width 0.1524)
				(type default)
			)
			(layer "F.SilkS")
		)
		(fp_line
			(start -0.7874 -0.4064)
			(end 0.7874 -0.4064)
			(stroke
				(width 0.1524)
				(type default)
			)
			(layer "F.SilkS")
		)
		(fp_line
			(start 0.67945 0.3048)
			(end 0.120396 0.3048)
			(stroke
				(width 0.1)
				(type default)
			)
			(layer "F.Fab")
		)
		(fp_line
			(start 0.67945 -0.3048)
			(end 0.67945 0.3048)
			(stroke
				(width 0.1)
				(type default)
			)
			(layer "F.Fab")
		)
		(fp_line
			(start 0.12065 -0.2794)
			(end 0.12065 -0.3048)
			(stroke
				(width 0.1)
				(type default)
			)
			(layer "F.Fab")
		)
		(fp_line
			(start 0.12065 -0.3048)
			(end 0.67945 -0.3048)
			(stroke
				(width 0.1)
				(type default)
			)
			(layer "F.Fab")
		)
		(fp_line
			(start 0.120396 0.3048)
			(end 0.120396 0.2794)
			(stroke
				(width 0.1)
				(type default)
			)
			(layer "F.Fab")
		)
		(fp_line
			(start 0.120396 0.2794)
			(end -0.12065 0.2794)
			(stroke
				(width 0.1)
				(type default)
			)
			(layer "F.Fab")
		)
		(fp_line
			(start -0.12065 0.3048)
			(end -0.67945 0.3048)
			(stroke
				(width 0.1)
				(type default)
			)
			(layer "F.Fab")
		)
		(fp_line
			(start -0.12065 0.2794)
			(end -0.12065 0.3048)
			(stroke
				(width 0.1)
				(type default)
			)
			(layer "F.Fab")
		)
		(fp_line
			(start -0.12065 -0.2794)
			(end 0.12065 -0.2794)
			(stroke
				(width 0.1)
				(type default)
			)
			(layer "F.Fab")
		)
		(fp_line
			(start -0.12065 -0.305054)
			(end -0.12065 -0.2794)
			(stroke
				(width 0.1)
				(type default)
			)
			(layer "F.Fab")
		)
		(fp_line
			(start -0.67945 0.3048)
			(end -0.67945 -0.305054)
			(stroke
				(width 0.1)
				(type default)
			)
			(layer "F.Fab")
		)
		(fp_line
			(start -0.67945 -0.305054)
			(end -0.12065 -0.305054)
			(stroke
				(width 0.1)
				(type default)
			)
			(layer "F.Fab")
		)
		(pad "1" smd circle
			(at -0.40005 0 180)
			(size 0 0)
			(layers "F.Cu" "F.Mask" "F.Paste")
			(net "JTAG_BMC_TMS")
		)
		(pad "2" smd circle
			(at 0.40005 0 180)
			(size 0 0)
			(layers "F.Cu" "F.Mask" "F.Paste")
			(net "JTAG_BMC_TMS_R")
		)
	)
	(footprint ""
		(layer "F.Cu")
		(at 145.46326 -338.393532 90)
		(property "Reference" "PL106"
			(at -4.419854 0.37338 0)
			(unlocked yes)
			(layer "F.SilkS")
			(effects
				(font
					(size 0.7874 0.5842)
					(thickness 0.1524)
				)
				(justify left)
			)
		)
		(property "Value" ""
			(at 0 0 90)
			(layer "F.Fab")
			(effects
				(font
					(size 1.27 1.27)
				)
			)
		)
		(duplicate_pad_numbers_are_jumpers no)
		(fp_line
			(start 3.24993 -3.24993)
			(end 3.24993 -2.2352)
			(stroke
				(width 0.1524)
				(type default)
			)
			(layer "F.SilkS")
		)
		(fp_line
			(start -3.24993 -3.24993)
			(end 3.24993 -3.24993)
			(stroke
				(width 0.1524)
				(type default)
			)
			(layer "F.SilkS")
		)
		(fp_line
			(start -3.24993 -2.2352)
			(end -3.24993 -3.24993)
			(stroke
				(width 0.1524)
				(type default)
			)
			(layer "F.SilkS")
		)
		(fp_line
			(start 3.24993 2.2352)
			(end 3.24993 3.24993)
			(stroke
				(width 0.1524)
				(type default)
			)
			(layer "F.SilkS")
		)
		(fp_line
			(start 3.24993 3.24993)
			(end -3.24993 3.24993)
			(stroke
				(width 0.1524)
				(type default)
			)
			(layer "F.SilkS")
		)
		(fp_line
			(start -3.24993 3.24993)
			(end -3.24993 2.2352)
			(stroke
				(width 0.1524)
				(type default)
			)
			(layer "F.SilkS")
		)
		(fp_line
			(start 3.24993 -3.24993)
			(end 3.24993 3.24993)
			(stroke
				(width 0.1)
				(type default)
			)
			(layer "F.Fab")
		)
		(fp_line
			(start -3.24993 -3.24993)
			(end 3.24993 -3.24993)
			(stroke
				(width 0.1)
				(type default)
			)
			(layer "F.Fab")
		)
		(fp_line
			(start 3.24993 3.24993)
			(end -3.24993 3.24993)
			(stroke
				(width 0.1)
				(type default)
			)
			(layer "F.Fab")
		)
		(fp_line
			(start -3.24993 3.24993)
			(end -3.24993 -3.24993)
			(stroke
				(width 0.1)
				(type default)
			)
			(layer "F.Fab")
		)
		(pad "1" smd rect
			(at -2.29997 0 90)
			(size 2.0066 4.2164)
			(layers "F.Cu" "F.Mask" "F.Paste")
			(net "IND_P1_CPL8")
		)
		(pad "2" smd rect
			(at 2.29997 0 90)
			(size 2.0066 4.2164)
			(layers "F.Cu" "F.Mask" "F.Paste")
			(net "GND")
		)
	)
	(footprint ""
		(layer "F.Cu")
		(at 109.580934 -392.12774)
		(property "Reference" "R3460"
			(at 0 0 0)
			(layer "F.SilkS")
			(hide yes)
			(effects
				(font
					(size 1.27 1.27)
				)
			)
		)
		(property "Value" ""
			(at 0 0 0)
			(layer "F.Fab")
			(effects
				(font
					(size 1.27 1.27)
				)
			)
		)
		(duplicate_pad_numbers_are_jumpers no)
		(fp_line
			(start -0.7874 -0.4064)
			(end 0.7874 -0.4064)
			(stroke
				(width 0.1524)
				(type default)
			)
			(layer "F.SilkS")
		)
		(fp_line
			(start -0.7874 0.4064)
			(end -0.7874 -0.4064)
			(stroke
				(width 0.1524)
				(type default)
			)
			(layer "F.SilkS")
		)
		(fp_line
			(start 0.7874 -0.4064)
			(end 0.7874 0.4064)
			(stroke
				(width 0.1524)
				(type default)
			)
			(layer "F.SilkS")
		)
		(fp_line
			(start 0.7874 0.4064)
			(end -0.7874 0.4064)
			(stroke
				(width 0.1524)
				(type default)
			)
			(layer "F.SilkS")
		)
		(fp_line
			(start -0.67945 -0.305054)
			(end -0.12065 -0.305054)
			(stroke
				(width 0.1)
				(type default)
			)
			(layer "F.Fab")
		)
		(fp_line
			(start -0.67945 0.3048)
			(end -0.67945 -0.305054)
			(stroke
				(width 0.1)
				(type default)
			)
			(layer "F.Fab")
		)
		(fp_line
			(start -0.12065 -0.305054)
			(end -0.12065 -0.2794)
			(stroke
				(width 0.1)
				(type default)
			)
			(layer "F.Fab")
		)
		(fp_line
			(start -0.12065 -0.2794)
			(end 0.12065 -0.2794)
			(stroke
				(width 0.1)
				(type default)
			)
			(layer "F.Fab")
		)
		(fp_line
			(start -0.12065 0.2794)
			(end -0.12065 0.3048)
			(stroke
				(width 0.1)
				(type default)
			)
			(layer "F.Fab")
		)
		(fp_line
			(start -0.12065 0.3048)
			(end -0.67945 0.3048)
			(stroke
				(width 0.1)
				(type default)
			)
			(layer "F.Fab")
		)
		(fp_line
			(start 0.120396 0.2794)
			(end -0.12065 0.2794)
			(stroke
				(width 0.1)
				(type default)
			)
			(layer "F.Fab")
		)
		(fp_line
			(start 0.120396 0.3048)
			(end 0.120396 0.2794)
			(stroke
				(width 0.1)
				(type default)
			)
			(layer "F.Fab")
		)
		(fp_line
			(start 0.12065 -0.3048)
			(end 0.67945 -0.3048)
			(stroke
				(width 0.1)
				(type default)
			)
			(layer "F.Fab")
		)
		(fp_line
			(start 0.12065 -0.2794)
			(end 0.12065 -0.3048)
			(stroke
				(width 0.1)
				(type default)
			)
			(layer "F.Fab")
		)
		(fp_line
			(start 0.67945 -0.3048)
			(end 0.67945 0.3048)
			(stroke
				(width 0.1)
				(type default)
			)
			(layer "F.Fab")
		)
		(fp_line
			(start 0.67945 0.3048)
			(end 0.120396 0.3048)
			(stroke
				(width 0.1)
				(type default)
			)
			(layer "F.Fab")
		)
		(pad "1" smd circle
			(at -0.40005 0)
			(size 0 0)
			(layers "F.Cu" "F.Mask" "F.Paste")
			(net "GPU_NVS_PWR_BRAKE_N")
		)
		(pad "2" smd circle
			(at 0.40005 0)
			(size 0 0)
			(layers "F.Cu" "F.Mask" "F.Paste")
			(net "GND")
		)
	)
	(footprint ""
		(layer "F.Cu")
		(at 21.456396 -386.484876 -90)
		(property "Reference" "R3291"
			(at 0 0 270)
			(layer "F.SilkS")
			(hide yes)
			(effects
				(font
					(size 1.27 1.27)
				)
			)
		)
		(property "Value" ""
			(at 0 0 270)
			(layer "F.Fab")
			(effects
				(font
					(size 1.27 1.27)
				)
			)
		)
		(duplicate_pad_numbers_are_jumpers no)
		(fp_line
			(start -0.7874 0.4064)
			(end -0.7874 -0.4064)
			(stroke
				(width 0.1524)
				(type default)
			)
			(layer "F.SilkS")
		)
		(fp_line
			(start 0.7874 0.4064)
			(end -0.7874 0.4064)
			(stroke
				(width 0.1524)
				(type default)
			)
			(layer "F.SilkS")
		)
		(fp_line
			(start -0.7874 -0.4064)
			(end 0.7874 -0.4064)
			(stroke
				(width 0.1524)
				(type default)
			)
			(layer "F.SilkS")
		)
		(fp_line
			(start 0.7874 -0.4064)
			(end 0.7874 0.4064)
			(stroke
				(width 0.1524)
				(type default)
			)
			(layer "F.SilkS")
		)
		(fp_line
			(start -0.67945 0.3048)
			(end -0.67945 -0.305054)
			(stroke
				(width 0.1)
				(type default)
			)
			(layer "F.Fab")
		)
		(fp_line
			(start -0.12065 0.3048)
			(end -0.67945 0.3048)
			(stroke
				(width 0.1)
				(type default)
			)
			(layer "F.Fab")
		)
		(fp_line
			(start 0.120396 0.3048)
			(end 0.120396 0.2794)
			(stroke
				(width 0.1)
				(type default)
			)
			(layer "F.Fab")
		)
		(fp_line
			(start 0.67945 0.3048)
			(end 0.120396 0.3048)
			(stroke
				(width 0.1)
				(type default)
			)
			(layer "F.Fab")
		)
		(fp_line
			(start -0.12065 0.2794)
			(end -0.12065 0.3048)
			(stroke
				(width 0.1)
				(type default)
			)
			(layer "F.Fab")
		)
		(fp_line
			(start 0.120396 0.2794)
			(end -0.12065 0.2794)
			(stroke
				(width 0.1)
				(type default)
			)
			(layer "F.Fab")
		)
		(fp_line
			(start -0.12065 -0.2794)
			(end 0.12065 -0.2794)
			(stroke
				(width 0.1)
				(type default)
			)
			(layer "F.Fab")
		)
		(fp_line
			(start 0.12065 -0.2794)
			(end 0.12065 -0.3048)
			(stroke
				(width 0.1)
				(type default)
			)
			(layer "F.Fab")
		)
		(fp_line
			(start 0.12065 -0.3048)
			(end 0.67945 -0.3048)
			(stroke
				(width 0.1)
				(type default)
			)
			(layer "F.Fab")
		)
		(fp_line
			(start 0.67945 -0.3048)
			(end 0.67945 0.3048)
			(stroke
				(width 0.1)
				(type default)
			)
			(layer "F.Fab")
		)
		(fp_line
			(start -0.67945 -0.305054)
			(end -0.12065 -0.305054)
			(stroke
				(width 0.1)
				(type default)
			)
			(layer "F.Fab")
		)
		(fp_line
			(start -0.12065 -0.305054)
			(end -0.12065 -0.2794)
			(stroke
				(width 0.1)
				(type default)
			)
			(layer "F.Fab")
		)
		(pad "1" smd circle
			(at -0.40005 0 270)
			(size 0 0)
			(layers "F.Cu" "F.Mask" "F.Paste")
			(net "PU_TEST")
		)
		(pad "2" smd circle
			(at 0.40005 0 270)
			(size 0 0)
			(layers "F.Cu" "F.Mask" "F.Paste")
			(net "GND")
		)
	)
	(footprint ""
		(layer "F.Cu")
		(at 93.193362 -339.51545 -90)
		(property "Reference" "PC505_P1_6"
			(at 0 0 270)
			(layer "F.SilkS")
			(hide yes)
			(effects
				(font
					(size 1.27 1.27)
				)
			)
		)
		(property "Value" ""
			(at 0 0 270)
			(layer "F.Fab")
			(effects
				(font
					(size 1.27 1.27)
				)
			)
		)
		(duplicate_pad_numbers_are_jumpers no)
		(fp_line
			(start -0.7874 0.4064)
			(end -0.7874 -0.4064)
			(stroke
				(width 0.1524)
				(type default)
			)
			(layer "F.SilkS")
		)
		(fp_line
			(start 0.7874 0.4064)
			(end -0.7874 0.4064)
			(stroke
				(width 0.1524)
				(type default)
			)
			(layer "F.SilkS")
		)
		(fp_line
			(start -0.7874 -0.4064)
			(end 0.7874 -0.4064)
			(stroke
				(width 0.1524)
				(type default)
			)
			(layer "F.SilkS")
		)
		(fp_line
			(start 0.7874 -0.4064)
			(end 0.7874 0.4064)
			(stroke
				(width 0.1524)
				(type default)
			)
			(layer "F.SilkS")
		)
		(fp_line
			(start -0.67945 0.3048)
			(end -0.67945 -0.305054)
			(stroke
				(width 0.1)
				(type default)
			)
			(layer "F.Fab")
		)
		(fp_line
			(start -0.12065 0.3048)
			(end -0.67945 0.3048)
			(stroke
				(width 0.1)
				(type default)
			)
			(layer "F.Fab")
		)
		(fp_line
			(start 0.120396 0.3048)
			(end 0.120396 0.2794)
			(stroke
				(width 0.1)
				(type default)
			)
			(layer "F.Fab")
		)
		(fp_line
			(start 0.67945 0.3048)
			(end 0.120396 0.3048)
			(stroke
				(width 0.1)
				(type default)
			)
			(layer "F.Fab")
		)
		(fp_line
			(start -0.12065 0.2794)
			(end -0.12065 0.3048)
			(stroke
				(width 0.1)
				(type default)
			)
			(layer "F.Fab")
		)
		(fp_line
			(start 0.120396 0.2794)
			(end -0.12065 0.2794)
			(stroke
				(width 0.1)
				(type default)
			)
			(layer "F.Fab")
		)
		(fp_line
			(start -0.12065 -0.2794)
			(end 0.12065 -0.2794)
			(stroke
				(width 0.1)
				(type default)
			)
			(layer "F.Fab")
		)
		(fp_line
			(start 0.12065 -0.2794)
			(end 0.12065 -0.3048)
			(stroke
				(width 0.1)
				(type default)
			)
			(layer "F.Fab")
		)
		(fp_line
			(start 0.12065 -0.3048)
			(end 0.67945 -0.3048)
			(stroke
				(width 0.1)
				(type default)
			)
			(layer "F.Fab")
		)
		(fp_line
			(start 0.67945 -0.3048)
			(end 0.67945 0.3048)
			(stroke
				(width 0.1)
				(type default)
			)
			(layer "F.Fab")
		)
		(fp_line
			(start -0.67945 -0.305054)
			(end -0.12065 -0.305054)
			(stroke
				(width 0.1)
				(type default)
			)
			(layer "F.Fab")
		)
		(fp_line
			(start -0.12065 -0.305054)
			(end -0.12065 -0.2794)
			(stroke
				(width 0.1)
				(type default)
			)
			(layer "F.Fab")
		)
		(pad "1" smd circle
			(at -0.40005 0 270)
			(size 0 0)
			(layers "F.Cu" "F.Mask" "F.Paste")
			(net "SW_P12V_PVCCIN_CPU1_FLT")
		)
		(pad "2" smd circle
			(at 0.40005 0 270)
			(size 0 0)
			(layers "F.Cu" "F.Mask" "F.Paste")
			(net "GND")
		)
	)
	(footprint ""
		(layer "F.Cu")
		(at 307.6956 -28.7528 180)
		(property "Reference" "C2387"
			(at 0 0 180)
			(layer "F.SilkS")
			(hide yes)
			(effects
				(font
					(size 1.27 1.27)
				)
			)
		)
		(property "Value" ""
			(at 0 0 180)
			(layer "F.Fab")
			(effects
				(font
					(size 1.27 1.27)
				)
			)
		)
		(duplicate_pad_numbers_are_jumpers no)
		(fp_line
			(start 0.7874 0.4064)
			(end -0.7874 0.4064)
			(stroke
				(width 0.1524)
				(type default)
			)
			(layer "F.SilkS")
		)
		(fp_line
			(start 0.7874 -0.4064)
			(end 0.7874 0.4064)
			(stroke
				(width 0.1524)
				(type default)
			)
			(layer "F.SilkS")
		)
		(fp_line
			(start -0.7874 0.4064)
			(end -0.7874 -0.4064)
			(stroke
				(width 0.1524)
				(type default)
			)
			(layer "F.SilkS")
		)
		(fp_line
			(start -0.7874 -0.4064)
			(end 0.7874 -0.4064)
			(stroke
				(width 0.1524)
				(type default)
			)
			(layer "F.SilkS")
		)
		(fp_line
			(start 0.67945 0.3048)
			(end 0.120396 0.3048)
			(stroke
				(width 0.1)
				(type default)
			)
			(layer "F.Fab")
		)
		(fp_line
			(start 0.67945 -0.3048)
			(end 0.67945 0.3048)
			(stroke
				(width 0.1)
				(type default)
			)
			(layer "F.Fab")
		)
		(fp_line
			(start 0.12065 -0.2794)
			(end 0.12065 -0.3048)
			(stroke
				(width 0.1)
				(type default)
			)
			(layer "F.Fab")
		)
		(fp_line
			(start 0.12065 -0.3048)
			(end 0.67945 -0.3048)
			(stroke
				(width 0.1)
				(type default)
			)
			(layer "F.Fab")
		)
		(fp_line
			(start 0.120396 0.3048)
			(end 0.120396 0.2794)
			(stroke
				(width 0.1)
				(type default)
			)
			(layer "F.Fab")
		)
		(fp_line
			(start 0.120396 0.2794)
			(end -0.12065 0.2794)
			(stroke
				(width 0.1)
				(type default)
			)
			(layer "F.Fab")
		)
		(fp_line
			(start -0.12065 0.3048)
			(end -0.67945 0.3048)
			(stroke
				(width 0.1)
				(type default)
			)
			(layer "F.Fab")
		)
		(fp_line
			(start -0.12065 0.2794)
			(end -0.12065 0.3048)
			(stroke
				(width 0.1)
				(type default)
			)
			(layer "F.Fab")
		)
		(fp_line
			(start -0.12065 -0.2794)
			(end 0.12065 -0.2794)
			(stroke
				(width 0.1)
				(type default)
			)
			(layer "F.Fab")
		)
		(fp_line
			(start -0.12065 -0.305054)
			(end -0.12065 -0.2794)
			(stroke
				(width 0.1)
				(type default)
			)
			(layer "F.Fab")
		)
		(fp_line
			(start -0.67945 0.3048)
			(end -0.67945 -0.305054)
			(stroke
				(width 0.1)
				(type default)
			)
			(layer "F.Fab")
		)
		(fp_line
			(start -0.67945 -0.305054)
			(end -0.12065 -0.305054)
			(stroke
				(width 0.1)
				(type default)
			)
			(layer "F.Fab")
		)
		(pad "1" smd circle
			(at -0.40005 0 180)
			(size 0 0)
			(layers "F.Cu" "F.Mask" "F.Paste")
			(net "P12V_AUX")
		)
		(pad "2" smd circle
			(at 0.40005 0 180)
			(size 0 0)
			(layers "F.Cu" "F.Mask" "F.Paste")
			(net "GND")
		)
	)
	(footprint ""
		(layer "F.Cu")
		(at 101.380036 -360.929174 -90)
		(property "Reference" "R308"
			(at 0 0 270)
			(layer "F.SilkS")
			(hide yes)
			(effects
				(font
					(size 1.27 1.27)
				)
			)
		)
		(property "Value" ""
			(at 0 0 270)
			(layer "F.Fab")
			(effects
				(font
					(size 1.27 1.27)
				)
			)
		)
		(duplicate_pad_numbers_are_jumpers no)
		(fp_line
			(start -0.7874 0.4064)
			(end -0.7874 -0.4064)
			(stroke
				(width 0.1524)
				(type default)
			)
			(layer "F.SilkS")
		)
		(fp_line
			(start 0.7874 0.4064)
			(end -0.7874 0.4064)
			(stroke
				(width 0.1524)
				(type default)
			)
			(layer "F.SilkS")
		)
		(fp_line
			(start -0.7874 -0.4064)
			(end 0.7874 -0.4064)
			(stroke
				(width 0.1524)
				(type default)
			)
			(layer "F.SilkS")
		)
		(fp_line
			(start 0.7874 -0.4064)
			(end 0.7874 0.4064)
			(stroke
				(width 0.1524)
				(type default)
			)
			(layer "F.SilkS")
		)
		(fp_line
			(start -0.67945 0.3048)
			(end -0.67945 -0.305054)
			(stroke
				(width 0.1)
				(type default)
			)
			(layer "F.Fab")
		)
		(fp_line
			(start -0.12065 0.3048)
			(end -0.67945 0.3048)
			(stroke
				(width 0.1)
				(type default)
			)
			(layer "F.Fab")
		)
		(fp_line
			(start 0.120396 0.3048)
			(end 0.120396 0.2794)
			(stroke
				(width 0.1)
				(type default)
			)
			(layer "F.Fab")
		)
		(fp_line
			(start 0.67945 0.3048)
			(end 0.120396 0.3048)
			(stroke
				(width 0.1)
				(type default)
			)
			(layer "F.Fab")
		)
		(fp_line
			(start -0.12065 0.2794)
			(end -0.12065 0.3048)
			(stroke
				(width 0.1)
				(type default)
			)
			(layer "F.Fab")
		)
		(fp_line
			(start 0.120396 0.2794)
			(end -0.12065 0.2794)
			(stroke
				(width 0.1)
				(type default)
			)
			(layer "F.Fab")
		)
		(fp_line
			(start -0.12065 -0.2794)
			(end 0.12065 -0.2794)
			(stroke
				(width 0.1)
				(type default)
			)
			(layer "F.Fab")
		)
		(fp_line
			(start 0.12065 -0.2794)
			(end 0.12065 -0.3048)
			(stroke
				(width 0.1)
				(type default)
			)
			(layer "F.Fab")
		)
		(fp_line
			(start 0.12065 -0.3048)
			(end 0.67945 -0.3048)
			(stroke
				(width 0.1)
				(type default)
			)
			(layer "F.Fab")
		)
		(fp_line
			(start 0.67945 -0.3048)
			(end 0.67945 0.3048)
			(stroke
				(width 0.1)
				(type default)
			)
			(layer "F.Fab")
		)
		(fp_line
			(start -0.67945 -0.305054)
			(end -0.12065 -0.305054)
			(stroke
				(width 0.1)
				(type default)
			)
			(layer "F.Fab")
		)
		(fp_line
			(start -0.12065 -0.305054)
			(end -0.12065 -0.2794)
			(stroke
				(width 0.1)
				(type default)
			)
			(layer "F.Fab")
		)
		(pad "1" smd circle
			(at -0.40005 0 270)
			(size 0 0)
			(layers "F.Cu" "F.Mask" "F.Paste")
			(net "PWRGD_PVCCIN_CPU1")
		)
		(pad "2" smd circle
			(at 0.40005 0 270)
			(size 0 0)
			(layers "F.Cu" "F.Mask" "F.Paste")
			(net "PWRGD_PVCCIN_CPU1_R")
		)
	)
	(footprint ""
		(layer "F.Cu")
		(at 185.346086 -353.650296 -90)
		(property "Reference" "PC1195_P1_3"
			(at 0 0 270)
			(layer "F.SilkS")
			(hide yes)
			(effects
				(font
					(size 1.27 1.27)
				)
			)
		)
		(property "Value" ""
			(at 0 0 270)
			(layer "F.Fab")
			(effects
				(font
					(size 1.27 1.27)
				)
			)
		)
		(duplicate_pad_numbers_are_jumpers no)
		(fp_line
			(start -0.7874 0.4064)
			(end -0.7874 -0.4064)
			(stroke
				(width 0.1524)
				(type default)
			)
			(layer "F.SilkS")
		)
		(fp_line
			(start 0.7874 0.4064)
			(end -0.7874 0.4064)
			(stroke
				(width 0.1524)
				(type default)
			)
			(layer "F.SilkS")
		)
		(fp_line
			(start -0.7874 -0.4064)
			(end 0.7874 -0.4064)
			(stroke
				(width 0.1524)
				(type default)
			)
			(layer "F.SilkS")
		)
		(fp_line
			(start 0.7874 -0.4064)
			(end 0.7874 0.4064)
			(stroke
				(width 0.1524)
				(type default)
			)
			(layer "F.SilkS")
		)
		(fp_line
			(start -0.67945 0.3048)
			(end -0.67945 -0.305054)
			(stroke
				(width 0.1)
				(type default)
			)
			(layer "F.Fab")
		)
		(fp_line
			(start -0.12065 0.3048)
			(end -0.67945 0.3048)
			(stroke
				(width 0.1)
				(type default)
			)
			(layer "F.Fab")
		)
		(fp_line
			(start 0.120396 0.3048)
			(end 0.120396 0.2794)
			(stroke
				(width 0.1)
				(type default)
			)
			(layer "F.Fab")
		)
		(fp_line
			(start 0.67945 0.3048)
			(end 0.120396 0.3048)
			(stroke
				(width 0.1)
				(type default)
			)
			(layer "F.Fab")
		)
		(fp_line
			(start -0.12065 0.2794)
			(end -0.12065 0.3048)
			(stroke
				(width 0.1)
				(type default)
			)
			(layer "F.Fab")
		)
		(fp_line
			(start 0.120396 0.2794)
			(end -0.12065 0.2794)
			(stroke
				(width 0.1)
				(type default)
			)
			(layer "F.Fab")
		)
		(fp_line
			(start -0.12065 -0.2794)
			(end 0.12065 -0.2794)
			(stroke
				(width 0.1)
				(type default)
			)
			(layer "F.Fab")
		)
		(fp_line
			(start 0.12065 -0.2794)
			(end 0.12065 -0.3048)
			(stroke
				(width 0.1)
				(type default)
			)
			(layer "F.Fab")
		)
		(fp_line
			(start 0.12065 -0.3048)
			(end 0.67945 -0.3048)
			(stroke
				(width 0.1)
				(type default)
			)
			(layer "F.Fab")
		)
		(fp_line
			(start 0.67945 -0.3048)
			(end 0.67945 0.3048)
			(stroke
				(width 0.1)
				(type default)
			)
			(layer "F.Fab")
		)
		(fp_line
			(start -0.67945 -0.305054)
			(end -0.12065 -0.305054)
			(stroke
				(width 0.1)
				(type default)
			)
			(layer "F.Fab")
		)
		(fp_line
			(start -0.12065 -0.305054)
			(end -0.12065 -0.2794)
			(stroke
				(width 0.1)
				(type default)
			)
			(layer "F.Fab")
		)
		(pad "1" smd circle
			(at -0.40005 0 270)
			(size 0 0)
			(layers "F.Cu" "F.Mask" "F.Paste")
			(net "SW_P12V_PVCCFA_EHV_FIVRA_CPU1_R")
		)
		(pad "2" smd circle
			(at 0.40005 0 270)
			(size 0 0)
			(layers "F.Cu" "F.Mask" "F.Paste")
			(net "GND")
		)
	)
	(footprint ""
		(layer "F.Cu")
		(at 121.251472 -357.11638 90)
		(property "Reference" "PC1266"
			(at 0 0 90)
			(layer "F.SilkS")
			(hide yes)
			(effects
				(font
					(size 1.27 1.27)
				)
			)
		)
		(property "Value" ""
			(at 0 0 90)
			(layer "F.Fab")
			(effects
				(font
					(size 1.27 1.27)
				)
			)
		)
		(duplicate_pad_numbers_are_jumpers no)
		(fp_line
			(start 0.7874 -0.4064)
			(end 0.7874 0.4064)
			(stroke
				(width 0.1524)
				(type default)
			)
			(layer "F.SilkS")
		)
		(fp_line
			(start -0.7874 -0.4064)
			(end 0.7874 -0.4064)
			(stroke
				(width 0.1524)
				(type default)
			)
			(layer "F.SilkS")
		)
		(fp_line
			(start 0.7874 0.4064)
			(end -0.7874 0.4064)
			(stroke
				(width 0.1524)
				(type default)
			)
			(layer "F.SilkS")
		)
		(fp_line
			(start -0.7874 0.4064)
			(end -0.7874 -0.4064)
			(stroke
				(width 0.1524)
				(type default)
			)
			(layer "F.SilkS")
		)
		(fp_line
			(start -0.12065 -0.305054)
			(end -0.12065 -0.2794)
			(stroke
				(width 0.1)
				(type default)
			)
			(layer "F.Fab")
		)
		(fp_line
			(start -0.67945 -0.305054)
			(end -0.12065 -0.305054)
			(stroke
				(width 0.1)
				(type default)
			)
			(layer "F.Fab")
		)
		(fp_line
			(start 0.67945 -0.3048)
			(end 0.67945 0.3048)
			(stroke
				(width 0.1)
				(type default)
			)
			(layer "F.Fab")
		)
		(fp_line
			(start 0.12065 -0.3048)
			(end 0.67945 -0.3048)
			(stroke
				(width 0.1)
				(type default)
			)
			(layer "F.Fab")
		)
		(fp_line
			(start 0.12065 -0.2794)
			(end 0.12065 -0.3048)
			(stroke
				(width 0.1)
				(type default)
			)
			(layer "F.Fab")
		)
		(fp_line
			(start -0.12065 -0.2794)
			(end 0.12065 -0.2794)
			(stroke
				(width 0.1)
				(type default)
			)
			(layer "F.Fab")
		)
		(fp_line
			(start 0.120396 0.2794)
			(end -0.12065 0.2794)
			(stroke
				(width 0.1)
				(type default)
			)
			(layer "F.Fab")
		)
		(fp_line
			(start -0.12065 0.2794)
			(end -0.12065 0.3048)
			(stroke
				(width 0.1)
				(type default)
			)
			(layer "F.Fab")
		)
		(fp_line
			(start 0.67945 0.3048)
			(end 0.120396 0.3048)
			(stroke
				(width 0.1)
				(type default)
			)
			(layer "F.Fab")
		)
		(fp_line
			(start 0.120396 0.3048)
			(end 0.120396 0.2794)
			(stroke
				(width 0.1)
				(type default)
			)
			(layer "F.Fab")
		)
		(fp_line
			(start -0.12065 0.3048)
			(end -0.67945 0.3048)
			(stroke
				(width 0.1)
				(type default)
			)
			(layer "F.Fab")
		)
		(fp_line
			(start -0.67945 0.3048)
			(end -0.67945 -0.305054)
			(stroke
				(width 0.1)
				(type default)
			)
			(layer "F.Fab")
		)
		(pad "1" smd circle
			(at -0.40005 0 90)
			(size 0 0)
			(layers "F.Cu" "F.Mask" "F.Paste")
			(net "PVPP_HBM_CPU1_FB")
		)
		(pad "2" smd circle
			(at 0.40005 0 90)
			(size 0 0)
			(layers "F.Cu" "F.Mask" "F.Paste")
			(net "SH_PVPP_HBM_CPU1_P")
		)
	)
	(footprint ""
		(layer "F.Cu")
		(at 378.099574 -4.696206 180)
		(property "Reference" "J63"
			(at -4.451096 -1.140206 90)
			(unlocked yes)
			(layer "F.SilkS")
			(effects
				(font
					(size 0.7874 0.5842)
					(thickness 0.1524)
				)
				(justify left)
			)
		)
		(property "Value" ""
			(at 0 0 180)
			(layer "F.Fab")
			(effects
				(font
					(size 1.27 1.27)
				)
			)
		)
		(duplicate_pad_numbers_are_jumpers no)
		(fp_line
			(start 1.2192 2.1082)
			(end -1.2192 2.1082)
			(stroke
				(width 0.1524)
				(type default)
			)
			(layer "F.SilkS")
		)
		(fp_line
			(start 1.2192 -2.1082)
			(end 1.2192 2.1082)
			(stroke
				(width 0.1524)
				(type default)
			)
			(layer "F.SilkS")
		)
		(fp_line
			(start -1.2192 2.1082)
			(end -1.2192 -2.1082)
			(stroke
				(width 0.1524)
				(type default)
			)
			(layer "F.SilkS")
		)
		(fp_line
			(start -1.2192 -2.1082)
			(end 1.2192 -2.1082)
			(stroke
				(width 0.1524)
				(type default)
			)
			(layer "F.SilkS")
		)
		(pad "" np_thru_hole circle
			(at -2.8829 -1.27 90)
			(size 1.0414 1.0414)
			(drill 1.0414)
			(layers "*.Cu" "*.Mask")
			(clearance 0.381)
			(thermal_gap 0.381)
		)
		(pad "" np_thru_hole circle
			(at -2.8829 1.27 90)
			(size 1.0414 1.0414)
			(drill 1.0414)
			(layers "*.Cu" "*.Mask")
			(clearance 0.381)
			(thermal_gap 0.381)
		)
		(pad "" np_thru_hole circle
			(at 3.4671 -1.27 90)
			(size 1.0414 1.0414)
			(drill 1.0414)
			(layers "*.Cu" "*.Mask")
			(clearance 0.381)
			(thermal_gap 0.381)
		)
		(pad "" np_thru_hole circle
			(at 3.4671 1.27 90)
			(size 1.0414 1.0414)
			(drill 1.0414)
			(layers "*.Cu" "*.Mask")
			(clearance 0.381)
			(thermal_gap 0.381)
		)
		(pad "1" smd rect
			(at 0.8255 -0.249936 90)
			(size 0.3048 0.508)
			(layers "F.Cu" "F.Mask" "F.Paste")
			(net "DELTA_L_85_5INCH_TOP_DP")
		)
		(pad "2" smd rect
			(at 0.8255 0.249936 90)
			(size 0.3048 0.508)
			(layers "F.Cu" "F.Mask" "F.Paste")
			(net "DELTA_L_85_5INCH_TOP_DN")
		)
		(pad "3" smd circle
			(at 0 0 180)
			(size 0 0)
			(layers "F.Cu" "F.Mask" "F.Paste")
			(net "DELTA_L_GND_1")
		)
		(zone
			(layer "F.Cu")
			(hatch none 0.5)
			(connect_pads
				(clearance 0)
			)
			(min_thickness 0.25)
			(keepout
				(tracks not_allowed)
				(vias allowed)
				(pads allowed)
				(copperpour not_allowed)
				(footprints allowed)
			)
			(placement
				(enabled no)
				(sheetname "")
			)
			(fill
				(thermal_gap 0.5)
				(thermal_bridge_width 0.5)
				(island_removal_mode 0)
			)
			(polygon
				(pts
					(xy 376.981974 -4.147566) (xy 376.981974 -4.24307) (xy 377.578874 -4.24307) (xy 377.578874 -4.64947)
					(xy 376.981974 -4.64947) (xy 376.981974 -4.742942) (xy 377.578874 -4.742942) (xy 377.578874 -5.149342)
					(xy 376.981974 -5.149342) (xy 376.981974 -5.244846) (xy 377.680474 -5.244846) (xy 377.680474 -4.147566)
				)
			)
		)
		(zone
			(layers "F.Cu" "B.Cu" "In1.Cu" "In2.Cu" "In3.Cu" "In4.Cu" "In5.Cu" "In6.Cu"
				"In7.Cu" "In8.Cu" "In9.Cu" "In10.Cu" "In11.Cu" "In12.Cu" "In13.Cu" "In14.Cu"
				"In15.Cu" "In16.Cu"
			)
			(hatch none 0.5)
			(connect_pads
				(clearance 0)
			)
			(min_thickness 0.25)
			(keepout
				(tracks not_allowed)
				(vias allowed)
				(pads allowed)
				(copperpour not_allowed)
				(footprints allowed)
			)
			(placement
				(enabled no)
				(sheetname "")
			)
			(fill
				(thermal_gap 0.5)
				(thermal_bridge_width 0.5)
				(island_removal_mode 0)
			)
			(polygon
				(pts
					(arc
						(start 375.559574 -5.966206)
						(mid 373.705374 -5.966206)
						(end 375.559574 -5.966206)
					)
				)
			)
		)
		(zone
			(layers "F.Cu" "B.Cu" "In1.Cu" "In2.Cu" "In3.Cu" "In4.Cu" "In5.Cu" "In6.Cu"
				"In7.Cu" "In8.Cu" "In9.Cu" "In10.Cu" "In11.Cu" "In12.Cu" "In13.Cu" "In14.Cu"
				"In15.Cu" "In16.Cu"
			)
			(hatch none 0.5)
			(connect_pads
				(clearance 0)
			)
			(min_thickness 0.25)
			(keepout
				(tracks not_allowed)
				(vias allowed)
				(pads allowed)
				(copperpour not_allowed)
				(footprints allowed)
			)
			(placement
				(enabled no)
				(sheetname "")
			)
			(fill
				(thermal_gap 0.5)
				(thermal_bridge_width 0.5)
				(island_removal_mode 0)
			)
			(polygon
				(pts
					(arc
						(start 375.559574 -3.426206)
						(mid 373.705374 -3.426206)
						(end 375.559574 -3.426206)
					)
				)
			)
		)
		(zone
			(layers "F.Cu" "B.Cu" "In1.Cu" "In2.Cu" "In3.Cu" "In4.Cu" "In5.Cu" "In6.Cu"
				"In7.Cu" "In8.Cu" "In9.Cu" "In10.Cu" "In11.Cu" "In12.Cu" "In13.Cu" "In14.Cu"
				"In15.Cu" "In16.Cu"
			)
			(hatch none 0.5)
			(connect_pads
				(clearance 0)
			)
			(min_thickness 0.25)
			(keepout
				(tracks not_allowed)
				(vias allowed)
				(pads allowed)
				(copperpour not_allowed)
				(footprints allowed)
			)
			(placement
				(enabled no)
				(sheetname "")
			)
			(fill
				(thermal_gap 0.5)
				(thermal_bridge_width 0.5)
				(island_removal_mode 0)
			)
			(polygon
				(pts
					(arc
						(start 381.909574 -5.966206)
						(mid 380.055374 -5.966206)
						(end 381.909574 -5.966206)
					)
				)
			)
		)
		(zone
			(layers "F.Cu" "B.Cu" "In1.Cu" "In2.Cu" "In3.Cu" "In4.Cu" "In5.Cu" "In6.Cu"
				"In7.Cu" "In8.Cu" "In9.Cu" "In10.Cu" "In11.Cu" "In12.Cu" "In13.Cu" "In14.Cu"
				"In15.Cu" "In16.Cu"
			)
			(hatch none 0.5)
			(connect_pads
				(clearance 0)
			)
			(min_thickness 0.25)
			(keepout
				(tracks not_allowed)
				(vias allowed)
				(pads allowed)
				(copperpour not_allowed)
				(footprints allowed)
			)
			(placement
				(enabled no)
				(sheetname "")
			)
			(fill
				(thermal_gap 0.5)
				(thermal_bridge_width 0.5)
				(island_removal_mode 0)
			)
			(polygon
				(pts
					(arc
						(start 381.909574 -3.426206)
						(mid 380.055374 -3.426206)
						(end 381.909574 -3.426206)
					)
				)
			)
		)
	)
	(footprint ""
		(layer "F.Cu")
		(at 31.29788 -431.891948)
		(property "Reference" "R3515"
			(at 0 0 0)
			(layer "F.SilkS")
			(hide yes)
			(effects
				(font
					(size 1.27 1.27)
				)
			)
		)
		(property "Value" ""
			(at 0 0 0)
			(layer "F.Fab")
			(effects
				(font
					(size 1.27 1.27)
				)
			)
		)
		(duplicate_pad_numbers_are_jumpers no)
		(fp_line
			(start -0.7874 -0.4064)
			(end 0.7874 -0.4064)
			(stroke
				(width 0.1524)
				(type default)
			)
			(layer "F.SilkS")
		)
		(fp_line
			(start -0.7874 0.4064)
			(end -0.7874 -0.4064)
			(stroke
				(width 0.1524)
				(type default)
			)
			(layer "F.SilkS")
		)
		(fp_line
			(start 0.7874 -0.4064)
			(end 0.7874 0.4064)
			(stroke
				(width 0.1524)
				(type default)
			)
			(layer "F.SilkS")
		)
		(fp_line
			(start 0.7874 0.4064)
			(end -0.7874 0.4064)
			(stroke
				(width 0.1524)
				(type default)
			)
			(layer "F.SilkS")
		)
		(fp_line
			(start -0.67945 -0.305054)
			(end -0.12065 -0.305054)
			(stroke
				(width 0.1)
				(type default)
			)
			(layer "F.Fab")
		)
		(fp_line
			(start -0.67945 0.3048)
			(end -0.67945 -0.305054)
			(stroke
				(width 0.1)
				(type default)
			)
			(layer "F.Fab")
		)
		(fp_line
			(start -0.12065 -0.305054)
			(end -0.12065 -0.2794)
			(stroke
				(width 0.1)
				(type default)
			)
			(layer "F.Fab")
		)
		(fp_line
			(start -0.12065 -0.2794)
			(end 0.12065 -0.2794)
			(stroke
				(width 0.1)
				(type default)
			)
			(layer "F.Fab")
		)
		(fp_line
			(start -0.12065 0.2794)
			(end -0.12065 0.3048)
			(stroke
				(width 0.1)
				(type default)
			)
			(layer "F.Fab")
		)
		(fp_line
			(start -0.12065 0.3048)
			(end -0.67945 0.3048)
			(stroke
				(width 0.1)
				(type default)
			)
			(layer "F.Fab")
		)
		(fp_line
			(start 0.120396 0.2794)
			(end -0.12065 0.2794)
			(stroke
				(width 0.1)
				(type default)
			)
			(layer "F.Fab")
		)
		(fp_line
			(start 0.120396 0.3048)
			(end 0.120396 0.2794)
			(stroke
				(width 0.1)
				(type default)
			)
			(layer "F.Fab")
		)
		(fp_line
			(start 0.12065 -0.3048)
			(end 0.67945 -0.3048)
			(stroke
				(width 0.1)
				(type default)
			)
			(layer "F.Fab")
		)
		(fp_line
			(start 0.12065 -0.2794)
			(end 0.12065 -0.3048)
			(stroke
				(width 0.1)
				(type default)
			)
			(layer "F.Fab")
		)
		(fp_line
			(start 0.67945 -0.3048)
			(end 0.67945 0.3048)
			(stroke
				(width 0.1)
				(type default)
			)
			(layer "F.Fab")
		)
		(fp_line
			(start 0.67945 0.3048)
			(end 0.120396 0.3048)
			(stroke
				(width 0.1)
				(type default)
			)
			(layer "F.Fab")
		)
		(pad "1" smd circle
			(at -0.40005 0)
			(size 0 0)
			(layers "F.Cu" "F.Mask" "F.Paste")
			(net "FM_SWB_PWR_EN_R1_BUF")
		)
		(pad "2" smd circle
			(at 0.40005 0)
			(size 0 0)
			(layers "F.Cu" "F.Mask" "F.Paste")
			(net "FM_SWB_PWR_EN_R_BUF")
		)
	)
	(footprint ""
		(layer "F.Cu")
		(at 20.8026 -410.7942 90)
		(property "Reference" "R4734"
			(at 0 0 90)
			(layer "F.SilkS")
			(hide yes)
			(effects
				(font
					(size 1.27 1.27)
				)
			)
		)
		(property "Value" ""
			(at 0 0 90)
			(layer "F.Fab")
			(effects
				(font
					(size 1.27 1.27)
				)
			)
		)
		(duplicate_pad_numbers_are_jumpers no)
		(fp_line
			(start 0.7874 -0.4064)
			(end 0.7874 0.4064)
			(stroke
				(width 0.1524)
				(type default)
			)
			(layer "F.SilkS")
		)
		(fp_line
			(start -0.7874 -0.4064)
			(end 0.7874 -0.4064)
			(stroke
				(width 0.1524)
				(type default)
			)
			(layer "F.SilkS")
		)
		(fp_line
			(start 0.7874 0.4064)
			(end -0.7874 0.4064)
			(stroke
				(width 0.1524)
				(type default)
			)
			(layer "F.SilkS")
		)
		(fp_line
			(start -0.7874 0.4064)
			(end -0.7874 -0.4064)
			(stroke
				(width 0.1524)
				(type default)
			)
			(layer "F.SilkS")
		)
		(fp_line
			(start -0.12065 -0.305054)
			(end -0.12065 -0.2794)
			(stroke
				(width 0.1)
				(type default)
			)
			(layer "F.Fab")
		)
		(fp_line
			(start -0.67945 -0.305054)
			(end -0.12065 -0.305054)
			(stroke
				(width 0.1)
				(type default)
			)
			(layer "F.Fab")
		)
		(fp_line
			(start 0.67945 -0.3048)
			(end 0.67945 0.3048)
			(stroke
				(width 0.1)
				(type default)
			)
			(layer "F.Fab")
		)
		(fp_line
			(start 0.12065 -0.3048)
			(end 0.67945 -0.3048)
			(stroke
				(width 0.1)
				(type default)
			)
			(layer "F.Fab")
		)
		(fp_line
			(start 0.12065 -0.2794)
			(end 0.12065 -0.3048)
			(stroke
				(width 0.1)
				(type default)
			)
			(layer "F.Fab")
		)
		(fp_line
			(start -0.12065 -0.2794)
			(end 0.12065 -0.2794)
			(stroke
				(width 0.1)
				(type default)
			)
			(layer "F.Fab")
		)
		(fp_line
			(start 0.120396 0.2794)
			(end -0.12065 0.2794)
			(stroke
				(width 0.1)
				(type default)
			)
			(layer "F.Fab")
		)
		(fp_line
			(start -0.12065 0.2794)
			(end -0.12065 0.3048)
			(stroke
				(width 0.1)
				(type default)
			)
			(layer "F.Fab")
		)
		(fp_line
			(start 0.67945 0.3048)
			(end 0.120396 0.3048)
			(stroke
				(width 0.1)
				(type default)
			)
			(layer "F.Fab")
		)
		(fp_line
			(start 0.120396 0.3048)
			(end 0.120396 0.2794)
			(stroke
				(width 0.1)
				(type default)
			)
			(layer "F.Fab")
		)
		(fp_line
			(start -0.12065 0.3048)
			(end -0.67945 0.3048)
			(stroke
				(width 0.1)
				(type default)
			)
			(layer "F.Fab")
		)
		(fp_line
			(start -0.67945 0.3048)
			(end -0.67945 -0.305054)
			(stroke
				(width 0.1)
				(type default)
			)
			(layer "F.Fab")
		)
		(pad "1" smd circle
			(at -0.40005 0 90)
			(size 0 0)
			(layers "F.Cu" "F.Mask" "F.Paste")
			(net "PRSNT_CABLE_GPU_B3_ISO_N")
		)
		(pad "2" smd circle
			(at 0.40005 0 90)
			(size 0 0)
			(layers "F.Cu" "F.Mask" "F.Paste")
			(net "PRSNT_CABLE_GPU_B3_ISO_R1_N")
		)
	)
	(footprint ""
		(layer "F.Cu")
		(at 104.13492 -354.445062 -90)
		(property "Reference" "C2446"
			(at 0 0 270)
			(layer "F.SilkS")
			(hide yes)
			(effects
				(font
					(size 1.27 1.27)
				)
			)
		)
		(property "Value" ""
			(at 0 0 270)
			(layer "F.Fab")
			(effects
				(font
					(size 1.27 1.27)
				)
			)
		)
		(duplicate_pad_numbers_are_jumpers no)
		(fp_line
			(start -0.7874 0.4064)
			(end -0.7874 -0.4064)
			(stroke
				(width 0.1524)
				(type default)
			)
			(layer "F.SilkS")
		)
		(fp_line
			(start 0.7874 0.4064)
			(end -0.7874 0.4064)
			(stroke
				(width 0.1524)
				(type default)
			)
			(layer "F.SilkS")
		)
		(fp_line
			(start -0.7874 -0.4064)
			(end 0.7874 -0.4064)
			(stroke
				(width 0.1524)
				(type default)
			)
			(layer "F.SilkS")
		)
		(fp_line
			(start 0.7874 -0.4064)
			(end 0.7874 0.4064)
			(stroke
				(width 0.1524)
				(type default)
			)
			(layer "F.SilkS")
		)
		(fp_line
			(start -0.67945 0.3048)
			(end -0.67945 -0.305054)
			(stroke
				(width 0.1)
				(type default)
			)
			(layer "F.Fab")
		)
		(fp_line
			(start -0.12065 0.3048)
			(end -0.67945 0.3048)
			(stroke
				(width 0.1)
				(type default)
			)
			(layer "F.Fab")
		)
		(fp_line
			(start 0.120396 0.3048)
			(end 0.120396 0.2794)
			(stroke
				(width 0.1)
				(type default)
			)
			(layer "F.Fab")
		)
		(fp_line
			(start 0.67945 0.3048)
			(end 0.120396 0.3048)
			(stroke
				(width 0.1)
				(type default)
			)
			(layer "F.Fab")
		)
		(fp_line
			(start -0.12065 0.2794)
			(end -0.12065 0.3048)
			(stroke
				(width 0.1)
				(type default)
			)
			(layer "F.Fab")
		)
		(fp_line
			(start 0.120396 0.2794)
			(end -0.12065 0.2794)
			(stroke
				(width 0.1)
				(type default)
			)
			(layer "F.Fab")
		)
		(fp_line
			(start -0.12065 -0.2794)
			(end 0.12065 -0.2794)
			(stroke
				(width 0.1)
				(type default)
			)
			(layer "F.Fab")
		)
		(fp_line
			(start 0.12065 -0.2794)
			(end 0.12065 -0.3048)
			(stroke
				(width 0.1)
				(type default)
			)
			(layer "F.Fab")
		)
		(fp_line
			(start 0.12065 -0.3048)
			(end 0.67945 -0.3048)
			(stroke
				(width 0.1)
				(type default)
			)
			(layer "F.Fab")
		)
		(fp_line
			(start 0.67945 -0.3048)
			(end 0.67945 0.3048)
			(stroke
				(width 0.1)
				(type default)
			)
			(layer "F.Fab")
		)
		(fp_line
			(start -0.67945 -0.305054)
			(end -0.12065 -0.305054)
			(stroke
				(width 0.1)
				(type default)
			)
			(layer "F.Fab")
		)
		(fp_line
			(start -0.12065 -0.305054)
			(end -0.12065 -0.2794)
			(stroke
				(width 0.1)
				(type default)
			)
			(layer "F.Fab")
		)
		(pad "1" smd circle
			(at -0.40005 0 270)
			(size 0 0)
			(layers "F.Cu" "F.Mask" "F.Paste")
			(net "PVCCFA_EHV_FIVRA_CPU1_EN_R")
		)
		(pad "2" smd circle
			(at 0.40005 0 270)
			(size 0 0)
			(layers "F.Cu" "F.Mask" "F.Paste")
			(net "GND")
		)
	)
	(footprint ""
		(layer "F.Cu")
		(at 211.210906 -16.343122 -90)
		(property "Reference" "R1141"
			(at 0 0 270)
			(layer "F.SilkS")
			(hide yes)
			(effects
				(font
					(size 1.27 1.27)
				)
			)
		)
		(property "Value" ""
			(at 0 0 270)
			(layer "F.Fab")
			(effects
				(font
					(size 1.27 1.27)
				)
			)
		)
		(duplicate_pad_numbers_are_jumpers no)
		(fp_line
			(start -0.7874 0.4064)
			(end -0.7874 -0.4064)
			(stroke
				(width 0.1524)
				(type default)
			)
			(layer "F.SilkS")
		)
		(fp_line
			(start 0.7874 0.4064)
			(end -0.7874 0.4064)
			(stroke
				(width 0.1524)
				(type default)
			)
			(layer "F.SilkS")
		)
		(fp_line
			(start -0.7874 -0.4064)
			(end 0.7874 -0.4064)
			(stroke
				(width 0.1524)
				(type default)
			)
			(layer "F.SilkS")
		)
		(fp_line
			(start 0.7874 -0.4064)
			(end 0.7874 0.4064)
			(stroke
				(width 0.1524)
				(type default)
			)
			(layer "F.SilkS")
		)
		(fp_line
			(start -0.67945 0.3048)
			(end -0.67945 -0.305054)
			(stroke
				(width 0.1)
				(type default)
			)
			(layer "F.Fab")
		)
		(fp_line
			(start -0.12065 0.3048)
			(end -0.67945 0.3048)
			(stroke
				(width 0.1)
				(type default)
			)
			(layer "F.Fab")
		)
		(fp_line
			(start 0.120396 0.3048)
			(end 0.120396 0.2794)
			(stroke
				(width 0.1)
				(type default)
			)
			(layer "F.Fab")
		)
		(fp_line
			(start 0.67945 0.3048)
			(end 0.120396 0.3048)
			(stroke
				(width 0.1)
				(type default)
			)
			(layer "F.Fab")
		)
		(fp_line
			(start -0.12065 0.2794)
			(end -0.12065 0.3048)
			(stroke
				(width 0.1)
				(type default)
			)
			(layer "F.Fab")
		)
		(fp_line
			(start 0.120396 0.2794)
			(end -0.12065 0.2794)
			(stroke
				(width 0.1)
				(type default)
			)
			(layer "F.Fab")
		)
		(fp_line
			(start -0.12065 -0.2794)
			(end 0.12065 -0.2794)
			(stroke
				(width 0.1)
				(type default)
			)
			(layer "F.Fab")
		)
		(fp_line
			(start 0.12065 -0.2794)
			(end 0.12065 -0.3048)
			(stroke
				(width 0.1)
				(type default)
			)
			(layer "F.Fab")
		)
		(fp_line
			(start 0.12065 -0.3048)
			(end 0.67945 -0.3048)
			(stroke
				(width 0.1)
				(type default)
			)
			(layer "F.Fab")
		)
		(fp_line
			(start 0.67945 -0.3048)
			(end 0.67945 0.3048)
			(stroke
				(width 0.1)
				(type default)
			)
			(layer "F.Fab")
		)
		(fp_line
			(start -0.67945 -0.305054)
			(end -0.12065 -0.305054)
			(stroke
				(width 0.1)
				(type default)
			)
			(layer "F.Fab")
		)
		(fp_line
			(start -0.12065 -0.305054)
			(end -0.12065 -0.2794)
			(stroke
				(width 0.1)
				(type default)
			)
			(layer "F.Fab")
		)
		(pad "1" smd circle
			(at -0.40005 0 270)
			(size 0 0)
			(layers "F.Cu" "F.Mask" "F.Paste")
			(net "CLK_50M_NCSI_OCP_1")
		)
		(pad "2" smd circle
			(at 0.40005 0 270)
			(size 0 0)
			(layers "F.Cu" "F.Mask" "F.Paste")
			(net "CLK_50M_NCSI_OCP_SFF")
		)
	)
	(footprint ""
		(layer "F.Cu")
		(at 114.70132 -409.428442)
		(property "Reference" "R4494"
			(at 0 0 0)
			(layer "F.SilkS")
			(hide yes)
			(effects
				(font
					(size 1.27 1.27)
				)
			)
		)
		(property "Value" ""
			(at 0 0 0)
			(layer "F.Fab")
			(effects
				(font
					(size 1.27 1.27)
				)
			)
		)
		(duplicate_pad_numbers_are_jumpers no)
		(fp_line
			(start -0.7874 -0.4064)
			(end 0.7874 -0.4064)
			(stroke
				(width 0.1524)
				(type default)
			)
			(layer "F.SilkS")
		)
		(fp_line
			(start -0.7874 0.4064)
			(end -0.7874 -0.4064)
			(stroke
				(width 0.1524)
				(type default)
			)
			(layer "F.SilkS")
		)
		(fp_line
			(start 0.7874 -0.4064)
			(end 0.7874 0.4064)
			(stroke
				(width 0.1524)
				(type default)
			)
			(layer "F.SilkS")
		)
		(fp_line
			(start 0.7874 0.4064)
			(end -0.7874 0.4064)
			(stroke
				(width 0.1524)
				(type default)
			)
			(layer "F.SilkS")
		)
		(fp_line
			(start -0.67945 -0.305054)
			(end -0.12065 -0.305054)
			(stroke
				(width 0.1)
				(type default)
			)
			(layer "F.Fab")
		)
		(fp_line
			(start -0.67945 0.3048)
			(end -0.67945 -0.305054)
			(stroke
				(width 0.1)
				(type default)
			)
			(layer "F.Fab")
		)
		(fp_line
			(start -0.12065 -0.305054)
			(end -0.12065 -0.2794)
			(stroke
				(width 0.1)
				(type default)
			)
			(layer "F.Fab")
		)
		(fp_line
			(start -0.12065 -0.2794)
			(end 0.12065 -0.2794)
			(stroke
				(width 0.1)
				(type default)
			)
			(layer "F.Fab")
		)
		(fp_line
			(start -0.12065 0.2794)
			(end -0.12065 0.3048)
			(stroke
				(width 0.1)
				(type default)
			)
			(layer "F.Fab")
		)
		(fp_line
			(start -0.12065 0.3048)
			(end -0.67945 0.3048)
			(stroke
				(width 0.1)
				(type default)
			)
			(layer "F.Fab")
		)
		(fp_line
			(start 0.120396 0.2794)
			(end -0.12065 0.2794)
			(stroke
				(width 0.1)
				(type default)
			)
			(layer "F.Fab")
		)
		(fp_line
			(start 0.120396 0.3048)
			(end 0.120396 0.2794)
			(stroke
				(width 0.1)
				(type default)
			)
			(layer "F.Fab")
		)
		(fp_line
			(start 0.12065 -0.3048)
			(end 0.67945 -0.3048)
			(stroke
				(width 0.1)
				(type default)
			)
			(layer "F.Fab")
		)
		(fp_line
			(start 0.12065 -0.2794)
			(end 0.12065 -0.3048)
			(stroke
				(width 0.1)
				(type default)
			)
			(layer "F.Fab")
		)
		(fp_line
			(start 0.67945 -0.3048)
			(end 0.67945 0.3048)
			(stroke
				(width 0.1)
				(type default)
			)
			(layer "F.Fab")
		)
		(fp_line
			(start 0.67945 0.3048)
			(end 0.120396 0.3048)
			(stroke
				(width 0.1)
				(type default)
			)
			(layer "F.Fab")
		)
		(pad "1" smd circle
			(at -0.40005 0)
			(size 0 0)
			(layers "F.Cu" "F.Mask" "F.Paste")
			(net "FM_9ZXL045_3_OE_N")
		)
		(pad "2" smd circle
			(at 0.40005 0)
			(size 0 0)
			(layers "F.Cu" "F.Mask" "F.Paste")
			(net "P3V3")
		)
	)
	(footprint ""
		(layer "F.Cu")
		(at 47.159418 -178.060604 90)
		(property "Reference" "PC432"
			(at 0 0 90)
			(layer "F.SilkS")
			(hide yes)
			(effects
				(font
					(size 1.27 1.27)
				)
			)
		)
		(property "Value" ""
			(at 0 0 90)
			(layer "F.Fab")
			(effects
				(font
					(size 1.27 1.27)
				)
			)
		)
		(duplicate_pad_numbers_are_jumpers no)
		(fp_line
			(start 1.524 -0.762)
			(end 1.524 0.762)
			(stroke
				(width 0.1524)
				(type default)
			)
			(layer "F.SilkS")
		)
		(fp_line
			(start -1.524 -0.762)
			(end 1.524 -0.762)
			(stroke
				(width 0.1524)
				(type default)
			)
			(layer "F.SilkS")
		)
		(fp_line
			(start 1.524 0.762)
			(end -1.524 0.762)
			(stroke
				(width 0.1524)
				(type default)
			)
			(layer "F.SilkS")
		)
		(fp_line
			(start -1.524 0.762)
			(end -1.524 -0.762)
			(stroke
				(width 0.1524)
				(type default)
			)
			(layer "F.SilkS")
		)
		(fp_line
			(start 1.1049 -0.724916)
			(end -1.1049 -0.724916)
			(stroke
				(width 0.1)
				(type default)
			)
			(layer "F.Fab")
		)
		(fp_line
			(start -1.1049 -0.724916)
			(end -1.1049 0.724916)
			(stroke
				(width 0.1)
				(type default)
			)
			(layer "F.Fab")
		)
		(fp_line
			(start 1.1049 0.724916)
			(end 1.1049 -0.724916)
			(stroke
				(width 0.1)
				(type default)
			)
			(layer "F.Fab")
		)
		(fp_line
			(start -1.1049 0.724916)
			(end 1.1049 0.724916)
			(stroke
				(width 0.1)
				(type default)
			)
			(layer "F.Fab")
		)
		(pad "1" smd rect
			(at -0.889 0 270)
			(size 1.016 1.27)
			(layers "F.Cu" "F.Mask" "F.Paste")
			(net "SW_P12V_PVCCINFAON_CPU1_FLT")
		)
		(pad "2" smd rect
			(at 0.889 0 270)
			(size 1.016 1.27)
			(layers "F.Cu" "F.Mask" "F.Paste")
			(net "GND")
		)
	)
	(footprint ""
		(layer "F.Cu")
		(at 173.810168 -358.15778 -90)
		(property "Reference" "PC401"
			(at 0 0 270)
			(layer "F.SilkS")
			(hide yes)
			(effects
				(font
					(size 1.27 1.27)
				)
			)
		)
		(property "Value" ""
			(at 0 0 270)
			(layer "F.Fab")
			(effects
				(font
					(size 1.27 1.27)
				)
			)
		)
		(duplicate_pad_numbers_are_jumpers no)
		(fp_line
			(start -0.7874 0.4064)
			(end -0.7874 -0.4064)
			(stroke
				(width 0.1524)
				(type default)
			)
			(layer "F.SilkS")
		)
		(fp_line
			(start 0.7874 0.4064)
			(end -0.7874 0.4064)
			(stroke
				(width 0.1524)
				(type default)
			)
			(layer "F.SilkS")
		)
		(fp_line
			(start -0.7874 -0.4064)
			(end 0.7874 -0.4064)
			(stroke
				(width 0.1524)
				(type default)
			)
			(layer "F.SilkS")
		)
		(fp_line
			(start 0.7874 -0.4064)
			(end 0.7874 0.4064)
			(stroke
				(width 0.1524)
				(type default)
			)
			(layer "F.SilkS")
		)
		(fp_line
			(start -0.67945 0.3048)
			(end -0.67945 -0.305054)
			(stroke
				(width 0.1)
				(type default)
			)
			(layer "F.Fab")
		)
		(fp_line
			(start -0.12065 0.3048)
			(end -0.67945 0.3048)
			(stroke
				(width 0.1)
				(type default)
			)
			(layer "F.Fab")
		)
		(fp_line
			(start 0.120396 0.3048)
			(end 0.120396 0.2794)
			(stroke
				(width 0.1)
				(type default)
			)
			(layer "F.Fab")
		)
		(fp_line
			(start 0.67945 0.3048)
			(end 0.120396 0.3048)
			(stroke
				(width 0.1)
				(type default)
			)
			(layer "F.Fab")
		)
		(fp_line
			(start -0.12065 0.2794)
			(end -0.12065 0.3048)
			(stroke
				(width 0.1)
				(type default)
			)
			(layer "F.Fab")
		)
		(fp_line
			(start 0.120396 0.2794)
			(end -0.12065 0.2794)
			(stroke
				(width 0.1)
				(type default)
			)
			(layer "F.Fab")
		)
		(fp_line
			(start -0.12065 -0.2794)
			(end 0.12065 -0.2794)
			(stroke
				(width 0.1)
				(type default)
			)
			(layer "F.Fab")
		)
		(fp_line
			(start 0.12065 -0.2794)
			(end 0.12065 -0.3048)
			(stroke
				(width 0.1)
				(type default)
			)
			(layer "F.Fab")
		)
		(fp_line
			(start 0.12065 -0.3048)
			(end 0.67945 -0.3048)
			(stroke
				(width 0.1)
				(type default)
			)
			(layer "F.Fab")
		)
		(fp_line
			(start 0.67945 -0.3048)
			(end 0.67945 0.3048)
			(stroke
				(width 0.1)
				(type default)
			)
			(layer "F.Fab")
		)
		(fp_line
			(start -0.67945 -0.305054)
			(end -0.12065 -0.305054)
			(stroke
				(width 0.1)
				(type default)
			)
			(layer "F.Fab")
		)
		(fp_line
			(start -0.12065 -0.305054)
			(end -0.12065 -0.2794)
			(stroke
				(width 0.1)
				(type default)
			)
			(layer "F.Fab")
		)
		(pad "1" smd circle
			(at -0.40005 0 270)
			(size 0 0)
			(layers "F.Cu" "F.Mask" "F.Paste")
			(net "SW_PVCCFA_EHV_FIVRA_CPU1_BOOT1_")
		)
		(pad "2" smd circle
			(at 0.40005 0 270)
			(size 0 0)
			(layers "F.Cu" "F.Mask" "F.Paste")
			(net "SW_PVCCFA_EHV_FIVRA_CPU1_BOOTR1")
		)
	)
	(footprint ""
		(layer "F.Cu")
		(at 31.937452 -162.586162 180)
		(property "Reference" "PR202"
			(at 0 0 180)
			(layer "F.SilkS")
			(hide yes)
			(effects
				(font
					(size 1.27 1.27)
				)
			)
		)
		(property "Value" ""
			(at 0 0 180)
			(layer "F.Fab")
			(effects
				(font
					(size 1.27 1.27)
				)
			)
		)
		(duplicate_pad_numbers_are_jumpers no)
		(fp_line
			(start 0.7874 0.4064)
			(end -0.7874 0.4064)
			(stroke
				(width 0.1524)
				(type default)
			)
			(layer "F.SilkS")
		)
		(fp_line
			(start 0.7874 -0.4064)
			(end 0.7874 0.4064)
			(stroke
				(width 0.1524)
				(type default)
			)
			(layer "F.SilkS")
		)
		(fp_line
			(start -0.7874 0.4064)
			(end -0.7874 -0.4064)
			(stroke
				(width 0.1524)
				(type default)
			)
			(layer "F.SilkS")
		)
		(fp_line
			(start -0.7874 -0.4064)
			(end 0.7874 -0.4064)
			(stroke
				(width 0.1524)
				(type default)
			)
			(layer "F.SilkS")
		)
		(fp_line
			(start 0.67945 0.3048)
			(end 0.120396 0.3048)
			(stroke
				(width 0.1)
				(type default)
			)
			(layer "F.Fab")
		)
		(fp_line
			(start 0.67945 -0.3048)
			(end 0.67945 0.3048)
			(stroke
				(width 0.1)
				(type default)
			)
			(layer "F.Fab")
		)
		(fp_line
			(start 0.12065 -0.2794)
			(end 0.12065 -0.3048)
			(stroke
				(width 0.1)
				(type default)
			)
			(layer "F.Fab")
		)
		(fp_line
			(start 0.12065 -0.3048)
			(end 0.67945 -0.3048)
			(stroke
				(width 0.1)
				(type default)
			)
			(layer "F.Fab")
		)
		(fp_line
			(start 0.120396 0.3048)
			(end 0.120396 0.2794)
			(stroke
				(width 0.1)
				(type default)
			)
			(layer "F.Fab")
		)
		(fp_line
			(start 0.120396 0.2794)
			(end -0.12065 0.2794)
			(stroke
				(width 0.1)
				(type default)
			)
			(layer "F.Fab")
		)
		(fp_line
			(start -0.12065 0.3048)
			(end -0.67945 0.3048)
			(stroke
				(width 0.1)
				(type default)
			)
			(layer "F.Fab")
		)
		(fp_line
			(start -0.12065 0.2794)
			(end -0.12065 0.3048)
			(stroke
				(width 0.1)
				(type default)
			)
			(layer "F.Fab")
		)
		(fp_line
			(start -0.12065 -0.2794)
			(end 0.12065 -0.2794)
			(stroke
				(width 0.1)
				(type default)
			)
			(layer "F.Fab")
		)
		(fp_line
			(start -0.12065 -0.305054)
			(end -0.12065 -0.2794)
			(stroke
				(width 0.1)
				(type default)
			)
			(layer "F.Fab")
		)
		(fp_line
			(start -0.67945 0.3048)
			(end -0.67945 -0.305054)
			(stroke
				(width 0.1)
				(type default)
			)
			(layer "F.Fab")
		)
		(fp_line
			(start -0.67945 -0.305054)
			(end -0.12065 -0.305054)
			(stroke
				(width 0.1)
				(type default)
			)
			(layer "F.Fab")
		)
		(pad "1" smd circle
			(at -0.40005 0 180)
			(size 0 0)
			(layers "F.Cu" "F.Mask" "F.Paste")
			(net "PVCCD_HV_CPU1_VREF")
		)
		(pad "2" smd circle
			(at 0.40005 0 180)
			(size 0 0)
			(layers "F.Cu" "F.Mask" "F.Paste")
			(net "PVCCD_HV_CPU1_ADDR")
		)
	)
	(footprint ""
		(layer "F.Cu")
		(at 33.472374 -393.17549 180)
		(property "Reference" "R4657"
			(at 0 0 180)
			(layer "F.SilkS")
			(hide yes)
			(effects
				(font
					(size 1.27 1.27)
				)
			)
		)
		(property "Value" ""
			(at 0 0 180)
			(layer "F.Fab")
			(effects
				(font
					(size 1.27 1.27)
				)
			)
		)
		(duplicate_pad_numbers_are_jumpers no)
		(fp_line
			(start 0.7874 0.4064)
			(end -0.7874 0.4064)
			(stroke
				(width 0.1524)
				(type default)
			)
			(layer "F.SilkS")
		)
		(fp_line
			(start 0.7874 -0.4064)
			(end 0.7874 0.4064)
			(stroke
				(width 0.1524)
				(type default)
			)
			(layer "F.SilkS")
		)
		(fp_line
			(start -0.7874 0.4064)
			(end -0.7874 -0.4064)
			(stroke
				(width 0.1524)
				(type default)
			)
			(layer "F.SilkS")
		)
		(fp_line
			(start -0.7874 -0.4064)
			(end 0.7874 -0.4064)
			(stroke
				(width 0.1524)
				(type default)
			)
			(layer "F.SilkS")
		)
		(fp_line
			(start 0.67945 0.3048)
			(end 0.120396 0.3048)
			(stroke
				(width 0.1)
				(type default)
			)
			(layer "F.Fab")
		)
		(fp_line
			(start 0.67945 -0.3048)
			(end 0.67945 0.3048)
			(stroke
				(width 0.1)
				(type default)
			)
			(layer "F.Fab")
		)
		(fp_line
			(start 0.12065 -0.2794)
			(end 0.12065 -0.3048)
			(stroke
				(width 0.1)
				(type default)
			)
			(layer "F.Fab")
		)
		(fp_line
			(start 0.12065 -0.3048)
			(end 0.67945 -0.3048)
			(stroke
				(width 0.1)
				(type default)
			)
			(layer "F.Fab")
		)
		(fp_line
			(start 0.120396 0.3048)
			(end 0.120396 0.2794)
			(stroke
				(width 0.1)
				(type default)
			)
			(layer "F.Fab")
		)
		(fp_line
			(start 0.120396 0.2794)
			(end -0.12065 0.2794)
			(stroke
				(width 0.1)
				(type default)
			)
			(layer "F.Fab")
		)
		(fp_line
			(start -0.12065 0.3048)
			(end -0.67945 0.3048)
			(stroke
				(width 0.1)
				(type default)
			)
			(layer "F.Fab")
		)
		(fp_line
			(start -0.12065 0.2794)
			(end -0.12065 0.3048)
			(stroke
				(width 0.1)
				(type default)
			)
			(layer "F.Fab")
		)
		(fp_line
			(start -0.12065 -0.2794)
			(end 0.12065 -0.2794)
			(stroke
				(width 0.1)
				(type default)
			)
			(layer "F.Fab")
		)
		(fp_line
			(start -0.12065 -0.305054)
			(end -0.12065 -0.2794)
			(stroke
				(width 0.1)
				(type default)
			)
			(layer "F.Fab")
		)
		(fp_line
			(start -0.67945 0.3048)
			(end -0.67945 -0.305054)
			(stroke
				(width 0.1)
				(type default)
			)
			(layer "F.Fab")
		)
		(fp_line
			(start -0.67945 -0.305054)
			(end -0.12065 -0.305054)
			(stroke
				(width 0.1)
				(type default)
			)
			(layer "F.Fab")
		)
		(pad "1" smd circle
			(at -0.40005 0 180)
			(size 0 0)
			(layers "F.Cu" "F.Mask" "F.Paste")
			(net "FM_P2E_BUF2_SD_TH")
		)
		(pad "2" smd circle
			(at 0.40005 0 180)
			(size 0 0)
			(layers "F.Cu" "F.Mask" "F.Paste")
			(net "GND")
		)
	)
	(footprint ""
		(layer "F.Cu")
		(at 157.226 -126.365 -90)
		(property "Reference" "R4639"
			(at 0 0 270)
			(layer "F.SilkS")
			(hide yes)
			(effects
				(font
					(size 1.27 1.27)
				)
			)
		)
		(property "Value" ""
			(at 0 0 270)
			(layer "F.Fab")
			(effects
				(font
					(size 1.27 1.27)
				)
			)
		)
		(duplicate_pad_numbers_are_jumpers no)
		(fp_line
			(start -2.234946 0.9271)
			(end -2.234946 -0.9271)
			(stroke
				(width 0.1524)
				(type default)
			)
			(layer "F.SilkS")
		)
		(fp_line
			(start 2.234946 0.9271)
			(end -2.234946 0.9271)
			(stroke
				(width 0.1524)
				(type default)
			)
			(layer "F.SilkS")
		)
		(fp_line
			(start -2.234946 -0.9271)
			(end 2.234946 -0.9271)
			(stroke
				(width 0.1524)
				(type default)
			)
			(layer "F.SilkS")
		)
		(fp_line
			(start 2.234946 -0.9271)
			(end 2.234946 0.9271)
			(stroke
				(width 0.1524)
				(type default)
			)
			(layer "F.SilkS")
		)
		(fp_line
			(start -1.575054 0.824992)
			(end 1.575054 0.824992)
			(stroke
				(width 0.1)
				(type default)
			)
			(layer "F.Fab")
		)
		(fp_line
			(start 1.575054 0.824992)
			(end 1.575054 -0.824992)
			(stroke
				(width 0.1)
				(type default)
			)
			(layer "F.Fab")
		)
		(fp_line
			(start -1.575054 -0.824992)
			(end -1.575054 0.824992)
			(stroke
				(width 0.1)
				(type default)
			)
			(layer "F.Fab")
		)
		(fp_line
			(start 1.575054 -0.824992)
			(end -1.575054 -0.824992)
			(stroke
				(width 0.1)
				(type default)
			)
			(layer "F.Fab")
		)
		(pad "1" smd rect
			(at -1.599946 0 270)
			(size 1.016 1.6002)
			(layers "F.Cu" "F.Mask" "F.Paste")
			(net "P5V")
		)
		(pad "2" smd rect
			(at 1.599946 0 270)
			(size 1.016 1.6002)
			(layers "F.Cu" "F.Mask" "F.Paste")
			(net "VR_P5V_EN_D")
		)
	)
	(footprint ""
		(layer "F.Cu")
		(at 85.919818 -53.880258 -90)
		(property "Reference" "PC2151"
			(at 0 0 270)
			(layer "F.SilkS")
			(hide yes)
			(effects
				(font
					(size 1.27 1.27)
				)
			)
		)
		(property "Value" ""
			(at 0 0 270)
			(layer "F.Fab")
			(effects
				(font
					(size 1.27 1.27)
				)
			)
		)
		(duplicate_pad_numbers_are_jumpers no)
		(fp_line
			(start -0.7874 0.4064)
			(end -0.7874 -0.4064)
			(stroke
				(width 0.1524)
				(type default)
			)
			(layer "F.SilkS")
		)
		(fp_line
			(start 0.7874 0.4064)
			(end -0.7874 0.4064)
			(stroke
				(width 0.1524)
				(type default)
			)
			(layer "F.SilkS")
		)
		(fp_line
			(start -0.7874 -0.4064)
			(end 0.7874 -0.4064)
			(stroke
				(width 0.1524)
				(type default)
			)
			(layer "F.SilkS")
		)
		(fp_line
			(start 0.7874 -0.4064)
			(end 0.7874 0.4064)
			(stroke
				(width 0.1524)
				(type default)
			)
			(layer "F.SilkS")
		)
		(fp_line
			(start -0.67945 0.3048)
			(end -0.67945 -0.305054)
			(stroke
				(width 0.1)
				(type default)
			)
			(layer "F.Fab")
		)
		(fp_line
			(start -0.12065 0.3048)
			(end -0.67945 0.3048)
			(stroke
				(width 0.1)
				(type default)
			)
			(layer "F.Fab")
		)
		(fp_line
			(start 0.120396 0.3048)
			(end 0.120396 0.2794)
			(stroke
				(width 0.1)
				(type default)
			)
			(layer "F.Fab")
		)
		(fp_line
			(start 0.67945 0.3048)
			(end 0.120396 0.3048)
			(stroke
				(width 0.1)
				(type default)
			)
			(layer "F.Fab")
		)
		(fp_line
			(start -0.12065 0.2794)
			(end -0.12065 0.3048)
			(stroke
				(width 0.1)
				(type default)
			)
			(layer "F.Fab")
		)
		(fp_line
			(start 0.120396 0.2794)
			(end -0.12065 0.2794)
			(stroke
				(width 0.1)
				(type default)
			)
			(layer "F.Fab")
		)
		(fp_line
			(start -0.12065 -0.2794)
			(end 0.12065 -0.2794)
			(stroke
				(width 0.1)
				(type default)
			)
			(layer "F.Fab")
		)
		(fp_line
			(start 0.12065 -0.2794)
			(end 0.12065 -0.3048)
			(stroke
				(width 0.1)
				(type default)
			)
			(layer "F.Fab")
		)
		(fp_line
			(start 0.12065 -0.3048)
			(end 0.67945 -0.3048)
			(stroke
				(width 0.1)
				(type default)
			)
			(layer "F.Fab")
		)
		(fp_line
			(start 0.67945 -0.3048)
			(end 0.67945 0.3048)
			(stroke
				(width 0.1)
				(type default)
			)
			(layer "F.Fab")
		)
		(fp_line
			(start -0.67945 -0.305054)
			(end -0.12065 -0.305054)
			(stroke
				(width 0.1)
				(type default)
			)
			(layer "F.Fab")
		)
		(fp_line
			(start -0.12065 -0.305054)
			(end -0.12065 -0.2794)
			(stroke
				(width 0.1)
				(type default)
			)
			(layer "F.Fab")
		)
		(pad "1" smd circle
			(at -0.40005 0 270)
			(size 0 0)
			(layers "F.Cu" "F.Mask" "F.Paste")
			(net "P3V3_OCP_GATE_2")
		)
		(pad "2" smd circle
			(at 0.40005 0 270)
			(size 0 0)
			(layers "F.Cu" "F.Mask" "F.Paste")
			(net "GND")
		)
	)
	(footprint ""
		(layer "F.Cu")
		(at 353.246944 -241.976656 -90)
		(property "Reference" "C1015"
			(at 0 0 270)
			(layer "F.SilkS")
			(hide yes)
			(effects
				(font
					(size 1.27 1.27)
				)
			)
		)
		(property "Value" ""
			(at 0 0 270)
			(layer "F.Fab")
			(effects
				(font
					(size 1.27 1.27)
				)
			)
		)
		(duplicate_pad_numbers_are_jumpers no)
		(fp_line
			(start -0.7874 0.4064)
			(end -0.7874 -0.4064)
			(stroke
				(width 0.1524)
				(type default)
			)
			(layer "F.SilkS")
		)
		(fp_line
			(start 0.7874 0.4064)
			(end -0.7874 0.4064)
			(stroke
				(width 0.1524)
				(type default)
			)
			(layer "F.SilkS")
		)
		(fp_line
			(start -0.7874 -0.4064)
			(end 0.7874 -0.4064)
			(stroke
				(width 0.1524)
				(type default)
			)
			(layer "F.SilkS")
		)
		(fp_line
			(start 0.7874 -0.4064)
			(end 0.7874 0.4064)
			(stroke
				(width 0.1524)
				(type default)
			)
			(layer "F.SilkS")
		)
		(fp_line
			(start -0.67945 0.3048)
			(end -0.67945 -0.305054)
			(stroke
				(width 0.1)
				(type default)
			)
			(layer "F.Fab")
		)
		(fp_line
			(start -0.12065 0.3048)
			(end -0.67945 0.3048)
			(stroke
				(width 0.1)
				(type default)
			)
			(layer "F.Fab")
		)
		(fp_line
			(start 0.120396 0.3048)
			(end 0.120396 0.2794)
			(stroke
				(width 0.1)
				(type default)
			)
			(layer "F.Fab")
		)
		(fp_line
			(start 0.67945 0.3048)
			(end 0.120396 0.3048)
			(stroke
				(width 0.1)
				(type default)
			)
			(layer "F.Fab")
		)
		(fp_line
			(start -0.12065 0.2794)
			(end -0.12065 0.3048)
			(stroke
				(width 0.1)
				(type default)
			)
			(layer "F.Fab")
		)
		(fp_line
			(start 0.120396 0.2794)
			(end -0.12065 0.2794)
			(stroke
				(width 0.1)
				(type default)
			)
			(layer "F.Fab")
		)
		(fp_line
			(start -0.12065 -0.2794)
			(end 0.12065 -0.2794)
			(stroke
				(width 0.1)
				(type default)
			)
			(layer "F.Fab")
		)
		(fp_line
			(start 0.12065 -0.2794)
			(end 0.12065 -0.3048)
			(stroke
				(width 0.1)
				(type default)
			)
			(layer "F.Fab")
		)
		(fp_line
			(start 0.12065 -0.3048)
			(end 0.67945 -0.3048)
			(stroke
				(width 0.1)
				(type default)
			)
			(layer "F.Fab")
		)
		(fp_line
			(start 0.67945 -0.3048)
			(end 0.67945 0.3048)
			(stroke
				(width 0.1)
				(type default)
			)
			(layer "F.Fab")
		)
		(fp_line
			(start -0.67945 -0.305054)
			(end -0.12065 -0.305054)
			(stroke
				(width 0.1)
				(type default)
			)
			(layer "F.Fab")
		)
		(fp_line
			(start -0.12065 -0.305054)
			(end -0.12065 -0.2794)
			(stroke
				(width 0.1)
				(type default)
			)
			(layer "F.Fab")
		)
		(pad "1" smd circle
			(at -0.40005 0 270)
			(size 0 0)
			(layers "F.Cu" "F.Mask" "F.Paste")
			(net "PVCCIN_CPU0")
		)
		(pad "2" smd circle
			(at 0.40005 0 270)
			(size 0 0)
			(layers "F.Cu" "F.Mask" "F.Paste")
			(net "GND")
		)
	)
	(footprint ""
		(layer "F.Cu")
		(at 309.57774 -430.73701 -90)
		(property "Reference" "C2266"
			(at 0 0 270)
			(layer "F.SilkS")
			(hide yes)
			(effects
				(font
					(size 1.27 1.27)
				)
			)
		)
		(property "Value" ""
			(at 0 0 270)
			(layer "F.Fab")
			(effects
				(font
					(size 1.27 1.27)
				)
			)
		)
		(duplicate_pad_numbers_are_jumpers no)
		(fp_line
			(start -0.7874 0.4064)
			(end -0.7874 -0.4064)
			(stroke
				(width 0.1524)
				(type default)
			)
			(layer "F.SilkS")
		)
		(fp_line
			(start 0.7874 0.4064)
			(end -0.7874 0.4064)
			(stroke
				(width 0.1524)
				(type default)
			)
			(layer "F.SilkS")
		)
		(fp_line
			(start -0.7874 -0.4064)
			(end 0.7874 -0.4064)
			(stroke
				(width 0.1524)
				(type default)
			)
			(layer "F.SilkS")
		)
		(fp_line
			(start 0.7874 -0.4064)
			(end 0.7874 0.4064)
			(stroke
				(width 0.1524)
				(type default)
			)
			(layer "F.SilkS")
		)
		(fp_line
			(start -0.67945 0.3048)
			(end -0.67945 -0.305054)
			(stroke
				(width 0.1)
				(type default)
			)
			(layer "F.Fab")
		)
		(fp_line
			(start -0.12065 0.3048)
			(end -0.67945 0.3048)
			(stroke
				(width 0.1)
				(type default)
			)
			(layer "F.Fab")
		)
		(fp_line
			(start 0.120396 0.3048)
			(end 0.120396 0.2794)
			(stroke
				(width 0.1)
				(type default)
			)
			(layer "F.Fab")
		)
		(fp_line
			(start 0.67945 0.3048)
			(end 0.120396 0.3048)
			(stroke
				(width 0.1)
				(type default)
			)
			(layer "F.Fab")
		)
		(fp_line
			(start -0.12065 0.2794)
			(end -0.12065 0.3048)
			(stroke
				(width 0.1)
				(type default)
			)
			(layer "F.Fab")
		)
		(fp_line
			(start 0.120396 0.2794)
			(end -0.12065 0.2794)
			(stroke
				(width 0.1)
				(type default)
			)
			(layer "F.Fab")
		)
		(fp_line
			(start -0.12065 -0.2794)
			(end 0.12065 -0.2794)
			(stroke
				(width 0.1)
				(type default)
			)
			(layer "F.Fab")
		)
		(fp_line
			(start 0.12065 -0.2794)
			(end 0.12065 -0.3048)
			(stroke
				(width 0.1)
				(type default)
			)
			(layer "F.Fab")
		)
		(fp_line
			(start 0.12065 -0.3048)
			(end 0.67945 -0.3048)
			(stroke
				(width 0.1)
				(type default)
			)
			(layer "F.Fab")
		)
		(fp_line
			(start 0.67945 -0.3048)
			(end 0.67945 0.3048)
			(stroke
				(width 0.1)
				(type default)
			)
			(layer "F.Fab")
		)
		(fp_line
			(start -0.67945 -0.305054)
			(end -0.12065 -0.305054)
			(stroke
				(width 0.1)
				(type default)
			)
			(layer "F.Fab")
		)
		(fp_line
			(start -0.12065 -0.305054)
			(end -0.12065 -0.2794)
			(stroke
				(width 0.1)
				(type default)
			)
			(layer "F.Fab")
		)
		(pad "1" smd circle
			(at -0.40005 0 270)
			(size 0 0)
			(layers "F.Cu" "F.Mask" "F.Paste")
			(net "GPU_3V3IO_RSVD1_FFU_ISO")
		)
		(pad "2" smd circle
			(at 0.40005 0 270)
			(size 0 0)
			(layers "F.Cu" "F.Mask" "F.Paste")
			(net "GND")
		)
	)
	(footprint ""
		(layer "F.Cu")
		(at 152.96388 -130.774948)
		(property "Reference" "R3207"
			(at 0 0 0)
			(layer "F.SilkS")
			(hide yes)
			(effects
				(font
					(size 1.27 1.27)
				)
			)
		)
		(property "Value" ""
			(at 0 0 0)
			(layer "F.Fab")
			(effects
				(font
					(size 1.27 1.27)
				)
			)
		)
		(duplicate_pad_numbers_are_jumpers no)
		(fp_line
			(start -0.7874 -0.4064)
			(end 0.7874 -0.4064)
			(stroke
				(width 0.1524)
				(type default)
			)
			(layer "F.SilkS")
		)
		(fp_line
			(start -0.7874 0.4064)
			(end -0.7874 -0.4064)
			(stroke
				(width 0.1524)
				(type default)
			)
			(layer "F.SilkS")
		)
		(fp_line
			(start 0.7874 -0.4064)
			(end 0.7874 0.4064)
			(stroke
				(width 0.1524)
				(type default)
			)
			(layer "F.SilkS")
		)
		(fp_line
			(start 0.7874 0.4064)
			(end -0.7874 0.4064)
			(stroke
				(width 0.1524)
				(type default)
			)
			(layer "F.SilkS")
		)
		(fp_line
			(start -0.67945 -0.305054)
			(end -0.12065 -0.305054)
			(stroke
				(width 0.1)
				(type default)
			)
			(layer "F.Fab")
		)
		(fp_line
			(start -0.67945 0.3048)
			(end -0.67945 -0.305054)
			(stroke
				(width 0.1)
				(type default)
			)
			(layer "F.Fab")
		)
		(fp_line
			(start -0.12065 -0.305054)
			(end -0.12065 -0.2794)
			(stroke
				(width 0.1)
				(type default)
			)
			(layer "F.Fab")
		)
		(fp_line
			(start -0.12065 -0.2794)
			(end 0.12065 -0.2794)
			(stroke
				(width 0.1)
				(type default)
			)
			(layer "F.Fab")
		)
		(fp_line
			(start -0.12065 0.2794)
			(end -0.12065 0.3048)
			(stroke
				(width 0.1)
				(type default)
			)
			(layer "F.Fab")
		)
		(fp_line
			(start -0.12065 0.3048)
			(end -0.67945 0.3048)
			(stroke
				(width 0.1)
				(type default)
			)
			(layer "F.Fab")
		)
		(fp_line
			(start 0.120396 0.2794)
			(end -0.12065 0.2794)
			(stroke
				(width 0.1)
				(type default)
			)
			(layer "F.Fab")
		)
		(fp_line
			(start 0.120396 0.3048)
			(end 0.120396 0.2794)
			(stroke
				(width 0.1)
				(type default)
			)
			(layer "F.Fab")
		)
		(fp_line
			(start 0.12065 -0.3048)
			(end 0.67945 -0.3048)
			(stroke
				(width 0.1)
				(type default)
			)
			(layer "F.Fab")
		)
		(fp_line
			(start 0.12065 -0.2794)
			(end 0.12065 -0.3048)
			(stroke
				(width 0.1)
				(type default)
			)
			(layer "F.Fab")
		)
		(fp_line
			(start 0.67945 -0.3048)
			(end 0.67945 0.3048)
			(stroke
				(width 0.1)
				(type default)
			)
			(layer "F.Fab")
		)
		(fp_line
			(start 0.67945 0.3048)
			(end 0.120396 0.3048)
			(stroke
				(width 0.1)
				(type default)
			)
			(layer "F.Fab")
		)
		(pad "1" smd circle
			(at -0.40005 0)
			(size 0 0)
			(layers "F.Cu" "F.Mask" "F.Paste")
			(net "FB_BMC_ISOLATE1")
		)
		(pad "2" smd circle
			(at 0.40005 0)
			(size 0 0)
			(layers "F.Cu" "F.Mask" "F.Paste")
			(net "GND")
		)
	)
	(footprint ""
		(layer "F.Cu")
		(at 120.36044 -425.059348)
		(property "Reference" "R2937"
			(at 0 0 0)
			(layer "F.SilkS")
			(hide yes)
			(effects
				(font
					(size 1.27 1.27)
				)
			)
		)
		(property "Value" ""
			(at 0 0 0)
			(layer "F.Fab")
			(effects
				(font
					(size 1.27 1.27)
				)
			)
		)
		(duplicate_pad_numbers_are_jumpers no)
		(fp_line
			(start -0.7874 -0.4064)
			(end 0.7874 -0.4064)
			(stroke
				(width 0.1524)
				(type default)
			)
			(layer "F.SilkS")
		)
		(fp_line
			(start -0.7874 0.4064)
			(end -0.7874 -0.4064)
			(stroke
				(width 0.1524)
				(type default)
			)
			(layer "F.SilkS")
		)
		(fp_line
			(start 0.7874 -0.4064)
			(end 0.7874 0.4064)
			(stroke
				(width 0.1524)
				(type default)
			)
			(layer "F.SilkS")
		)
		(fp_line
			(start 0.7874 0.4064)
			(end -0.7874 0.4064)
			(stroke
				(width 0.1524)
				(type default)
			)
			(layer "F.SilkS")
		)
		(fp_line
			(start -0.67945 -0.305054)
			(end -0.12065 -0.305054)
			(stroke
				(width 0.1)
				(type default)
			)
			(layer "F.Fab")
		)
		(fp_line
			(start -0.67945 0.3048)
			(end -0.67945 -0.305054)
			(stroke
				(width 0.1)
				(type default)
			)
			(layer "F.Fab")
		)
		(fp_line
			(start -0.12065 -0.305054)
			(end -0.12065 -0.2794)
			(stroke
				(width 0.1)
				(type default)
			)
			(layer "F.Fab")
		)
		(fp_line
			(start -0.12065 -0.2794)
			(end 0.12065 -0.2794)
			(stroke
				(width 0.1)
				(type default)
			)
			(layer "F.Fab")
		)
		(fp_line
			(start -0.12065 0.2794)
			(end -0.12065 0.3048)
			(stroke
				(width 0.1)
				(type default)
			)
			(layer "F.Fab")
		)
		(fp_line
			(start -0.12065 0.3048)
			(end -0.67945 0.3048)
			(stroke
				(width 0.1)
				(type default)
			)
			(layer "F.Fab")
		)
		(fp_line
			(start 0.120396 0.2794)
			(end -0.12065 0.2794)
			(stroke
				(width 0.1)
				(type default)
			)
			(layer "F.Fab")
		)
		(fp_line
			(start 0.120396 0.3048)
			(end 0.120396 0.2794)
			(stroke
				(width 0.1)
				(type default)
			)
			(layer "F.Fab")
		)
		(fp_line
			(start 0.12065 -0.3048)
			(end 0.67945 -0.3048)
			(stroke
				(width 0.1)
				(type default)
			)
			(layer "F.Fab")
		)
		(fp_line
			(start 0.12065 -0.2794)
			(end 0.12065 -0.3048)
			(stroke
				(width 0.1)
				(type default)
			)
			(layer "F.Fab")
		)
		(fp_line
			(start 0.67945 -0.3048)
			(end 0.67945 0.3048)
			(stroke
				(width 0.1)
				(type default)
			)
			(layer "F.Fab")
		)
		(fp_line
			(start 0.67945 0.3048)
			(end 0.120396 0.3048)
			(stroke
				(width 0.1)
				(type default)
			)
			(layer "F.Fab")
		)
		(pad "1" smd circle
			(at -0.40005 0)
			(size 0 0)
			(layers "F.Cu" "F.Mask" "F.Paste")
			(net "FM_GPU_PWR_EN_R")
		)
		(pad "2" smd circle
			(at 0.40005 0)
			(size 0 0)
			(layers "F.Cu" "F.Mask" "F.Paste")
			(net "GND")
		)
	)
	(footprint ""
		(layer "F.Cu")
		(at 134.93496 -206.024734)
		(property "Reference" "H18"
			(at -1.17602 3.913632 0)
			(unlocked yes)
			(layer "F.SilkS")
			(effects
				(font
					(size 0.7874 0.5842)
					(thickness 0.1524)
				)
				(justify left)
			)
		)
		(property "Value" ""
			(at 0 0 0)
			(layer "F.Fab")
			(effects
				(font
					(size 1.27 1.27)
				)
			)
		)
		(duplicate_pad_numbers_are_jumpers no)
		(fp_circle
			(center 0 0)
			(end 2.5273 0)
			(stroke
				(width 0.1524)
				(type default)
			)
			(fill no)
			(layer "F.SilkS")
		)
		(fp_circle
			(center 0 0)
			(end 2.5273 0)
			(stroke
				(width 0.1524)
				(type default)
			)
			(fill no)
			(layer "B.SilkS")
		)
		(fp_circle
			(center 0 0)
			(end 2.5273 0)
			(stroke
				(width 0.1)
				(type default)
			)
			(fill no)
			(layer "B.Fab")
		)
		(fp_circle
			(center 0 0)
			(end 2.5273 0)
			(stroke
				(width 0.1)
				(type default)
			)
			(fill no)
			(layer "F.Fab")
		)
		(pad "" np_thru_hole circle
			(at 0 0)
			(size 3.429 3.429)
			(drill 3.429)
			(layers "*.Cu" "*.Mask")
			(clearance 0.381)
			(thermal_gap 0.381)
		)
	)
	(footprint ""
		(layer "F.Cu")
		(at 164.52088 -41.112948)
		(property "Reference" "R3301"
			(at 0 0 0)
			(layer "F.SilkS")
			(hide yes)
			(effects
				(font
					(size 1.27 1.27)
				)
			)
		)
		(property "Value" ""
			(at 0 0 0)
			(layer "F.Fab")
			(effects
				(font
					(size 1.27 1.27)
				)
			)
		)
		(duplicate_pad_numbers_are_jumpers no)
		(fp_line
			(start -0.7874 -0.4064)
			(end 0.7874 -0.4064)
			(stroke
				(width 0.1524)
				(type default)
			)
			(layer "F.SilkS")
		)
		(fp_line
			(start -0.7874 0.4064)
			(end -0.7874 -0.4064)
			(stroke
				(width 0.1524)
				(type default)
			)
			(layer "F.SilkS")
		)
		(fp_line
			(start 0.7874 -0.4064)
			(end 0.7874 0.4064)
			(stroke
				(width 0.1524)
				(type default)
			)
			(layer "F.SilkS")
		)
		(fp_line
			(start 0.7874 0.4064)
			(end -0.7874 0.4064)
			(stroke
				(width 0.1524)
				(type default)
			)
			(layer "F.SilkS")
		)
		(fp_line
			(start -0.67945 -0.305054)
			(end -0.12065 -0.305054)
			(stroke
				(width 0.1)
				(type default)
			)
			(layer "F.Fab")
		)
		(fp_line
			(start -0.67945 0.3048)
			(end -0.67945 -0.305054)
			(stroke
				(width 0.1)
				(type default)
			)
			(layer "F.Fab")
		)
		(fp_line
			(start -0.12065 -0.305054)
			(end -0.12065 -0.2794)
			(stroke
				(width 0.1)
				(type default)
			)
			(layer "F.Fab")
		)
		(fp_line
			(start -0.12065 -0.2794)
			(end 0.12065 -0.2794)
			(stroke
				(width 0.1)
				(type default)
			)
			(layer "F.Fab")
		)
		(fp_line
			(start -0.12065 0.2794)
			(end -0.12065 0.3048)
			(stroke
				(width 0.1)
				(type default)
			)
			(layer "F.Fab")
		)
		(fp_line
			(start -0.12065 0.3048)
			(end -0.67945 0.3048)
			(stroke
				(width 0.1)
				(type default)
			)
			(layer "F.Fab")
		)
		(fp_line
			(start 0.120396 0.2794)
			(end -0.12065 0.2794)
			(stroke
				(width 0.1)
				(type default)
			)
			(layer "F.Fab")
		)
		(fp_line
			(start 0.120396 0.3048)
			(end 0.120396 0.2794)
			(stroke
				(width 0.1)
				(type default)
			)
			(layer "F.Fab")
		)
		(fp_line
			(start 0.12065 -0.3048)
			(end 0.67945 -0.3048)
			(stroke
				(width 0.1)
				(type default)
			)
			(layer "F.Fab")
		)
		(fp_line
			(start 0.12065 -0.2794)
			(end 0.12065 -0.3048)
			(stroke
				(width 0.1)
				(type default)
			)
			(layer "F.Fab")
		)
		(fp_line
			(start 0.67945 -0.3048)
			(end 0.67945 0.3048)
			(stroke
				(width 0.1)
				(type default)
			)
			(layer "F.Fab")
		)
		(fp_line
			(start 0.67945 0.3048)
			(end 0.120396 0.3048)
			(stroke
				(width 0.1)
				(type default)
			)
			(layer "F.Fab")
		)
		(pad "1" smd circle
			(at -0.40005 0)
			(size 0 0)
			(layers "F.Cu" "F.Mask" "F.Paste")
			(net "IRQ_LVC3_WAKE_N")
		)
		(pad "2" smd circle
			(at 0.40005 0)
			(size 0 0)
			(layers "F.Cu" "F.Mask" "F.Paste")
			(net "M2_0_PEWAKE_N")
		)
	)
	(footprint ""
		(layer "F.Cu")
		(at 40.627554 -108.047282)
		(property "Reference" "R3683"
			(at 0 0 0)
			(layer "F.SilkS")
			(hide yes)
			(effects
				(font
					(size 1.27 1.27)
				)
			)
		)
		(property "Value" ""
			(at 0 0 0)
			(layer "F.Fab")
			(effects
				(font
					(size 1.27 1.27)
				)
			)
		)
		(duplicate_pad_numbers_are_jumpers no)
		(fp_line
			(start -0.7874 -0.4064)
			(end 0.7874 -0.4064)
			(stroke
				(width 0.1524)
				(type default)
			)
			(layer "F.SilkS")
		)
		(fp_line
			(start -0.7874 0.4064)
			(end -0.7874 -0.4064)
			(stroke
				(width 0.1524)
				(type default)
			)
			(layer "F.SilkS")
		)
		(fp_line
			(start 0.7874 -0.4064)
			(end 0.7874 0.4064)
			(stroke
				(width 0.1524)
				(type default)
			)
			(layer "F.SilkS")
		)
		(fp_line
			(start 0.7874 0.4064)
			(end -0.7874 0.4064)
			(stroke
				(width 0.1524)
				(type default)
			)
			(layer "F.SilkS")
		)
		(fp_line
			(start -0.67945 -0.305054)
			(end -0.12065 -0.305054)
			(stroke
				(width 0.1)
				(type default)
			)
			(layer "F.Fab")
		)
		(fp_line
			(start -0.67945 0.3048)
			(end -0.67945 -0.305054)
			(stroke
				(width 0.1)
				(type default)
			)
			(layer "F.Fab")
		)
		(fp_line
			(start -0.12065 -0.305054)
			(end -0.12065 -0.2794)
			(stroke
				(width 0.1)
				(type default)
			)
			(layer "F.Fab")
		)
		(fp_line
			(start -0.12065 -0.2794)
			(end 0.12065 -0.2794)
			(stroke
				(width 0.1)
				(type default)
			)
			(layer "F.Fab")
		)
		(fp_line
			(start -0.12065 0.2794)
			(end -0.12065 0.3048)
			(stroke
				(width 0.1)
				(type default)
			)
			(layer "F.Fab")
		)
		(fp_line
			(start -0.12065 0.3048)
			(end -0.67945 0.3048)
			(stroke
				(width 0.1)
				(type default)
			)
			(layer "F.Fab")
		)
		(fp_line
			(start 0.120396 0.2794)
			(end -0.12065 0.2794)
			(stroke
				(width 0.1)
				(type default)
			)
			(layer "F.Fab")
		)
		(fp_line
			(start 0.120396 0.3048)
			(end 0.120396 0.2794)
			(stroke
				(width 0.1)
				(type default)
			)
			(layer "F.Fab")
		)
		(fp_line
			(start 0.12065 -0.3048)
			(end 0.67945 -0.3048)
			(stroke
				(width 0.1)
				(type default)
			)
			(layer "F.Fab")
		)
		(fp_line
			(start 0.12065 -0.2794)
			(end 0.12065 -0.3048)
			(stroke
				(width 0.1)
				(type default)
			)
			(layer "F.Fab")
		)
		(fp_line
			(start 0.67945 -0.3048)
			(end 0.67945 0.3048)
			(stroke
				(width 0.1)
				(type default)
			)
			(layer "F.Fab")
		)
		(fp_line
			(start 0.67945 0.3048)
			(end 0.120396 0.3048)
			(stroke
				(width 0.1)
				(type default)
			)
			(layer "F.Fab")
		)
		(pad "1" smd rect
			(at -0.40005 0 180)
			(size 0.4572 0.508)
			(layers "F.Cu" "F.Mask" "F.Paste")
			(net "P3V3_ADC")
		)
		(pad "2" smd rect
			(at 0.40005 0 180)
			(size 0.4572 0.508)
			(layers "F.Cu" "F.Mask" "F.Paste")
			(net "P3V3_ADC_MAM")
		)
	)
	(footprint ""
		(layer "F.Cu")
		(at 218.205304 -59.453272 180)
		(property "Reference" "PC2220"
			(at 0 0 180)
			(layer "F.SilkS")
			(hide yes)
			(effects
				(font
					(size 1.27 1.27)
				)
			)
		)
		(property "Value" ""
			(at 0 0 180)
			(layer "F.Fab")
			(effects
				(font
					(size 1.27 1.27)
				)
			)
		)
		(duplicate_pad_numbers_are_jumpers no)
		(fp_line
			(start 1.524 0.762)
			(end -1.524 0.762)
			(stroke
				(width 0.1524)
				(type default)
			)
			(layer "F.SilkS")
		)
		(fp_line
			(start 1.524 -0.762)
			(end 1.524 0.762)
			(stroke
				(width 0.1524)
				(type default)
			)
			(layer "F.SilkS")
		)
		(fp_line
			(start -1.524 0.762)
			(end -1.524 -0.762)
			(stroke
				(width 0.1524)
				(type default)
			)
			(layer "F.SilkS")
		)
		(fp_line
			(start -1.524 -0.762)
			(end 1.524 -0.762)
			(stroke
				(width 0.1524)
				(type default)
			)
			(layer "F.SilkS")
		)
		(fp_line
			(start 1.1049 0.724916)
			(end 1.1049 -0.724916)
			(stroke
				(width 0.1)
				(type default)
			)
			(layer "F.Fab")
		)
		(fp_line
			(start 1.1049 -0.724916)
			(end -1.1049 -0.724916)
			(stroke
				(width 0.1)
				(type default)
			)
			(layer "F.Fab")
		)
		(fp_line
			(start -1.1049 0.724916)
			(end 1.1049 0.724916)
			(stroke
				(width 0.1)
				(type default)
			)
			(layer "F.Fab")
		)
		(fp_line
			(start -1.1049 -0.724916)
			(end -1.1049 0.724916)
			(stroke
				(width 0.1)
				(type default)
			)
			(layer "F.Fab")
		)
		(pad "1" smd rect
			(at -0.889 0)
			(size 1.016 1.27)
			(layers "F.Cu" "F.Mask" "F.Paste")
			(net "P3V3_E1S_0_R")
		)
		(pad "2" smd rect
			(at 0.889 0)
			(size 1.016 1.27)
			(layers "F.Cu" "F.Mask" "F.Paste")
			(net "GND")
		)
	)
	(footprint ""
		(layer "F.Cu")
		(at 176.059338 -414.697418)
		(property "Reference" "R3431"
			(at 0 0 0)
			(layer "F.SilkS")
			(hide yes)
			(effects
				(font
					(size 1.27 1.27)
				)
			)
		)
		(property "Value" ""
			(at 0 0 0)
			(layer "F.Fab")
			(effects
				(font
					(size 1.27 1.27)
				)
			)
		)
		(duplicate_pad_numbers_are_jumpers no)
		(fp_line
			(start -0.7874 -0.4064)
			(end 0.7874 -0.4064)
			(stroke
				(width 0.1524)
				(type default)
			)
			(layer "F.SilkS")
		)
		(fp_line
			(start -0.7874 0.4064)
			(end -0.7874 -0.4064)
			(stroke
				(width 0.1524)
				(type default)
			)
			(layer "F.SilkS")
		)
		(fp_line
			(start 0.7874 -0.4064)
			(end 0.7874 0.4064)
			(stroke
				(width 0.1524)
				(type default)
			)
			(layer "F.SilkS")
		)
		(fp_line
			(start 0.7874 0.4064)
			(end -0.7874 0.4064)
			(stroke
				(width 0.1524)
				(type default)
			)
			(layer "F.SilkS")
		)
		(fp_line
			(start -0.67945 -0.305054)
			(end -0.12065 -0.305054)
			(stroke
				(width 0.1)
				(type default)
			)
			(layer "F.Fab")
		)
		(fp_line
			(start -0.67945 0.3048)
			(end -0.67945 -0.305054)
			(stroke
				(width 0.1)
				(type default)
			)
			(layer "F.Fab")
		)
		(fp_line
			(start -0.12065 -0.305054)
			(end -0.12065 -0.2794)
			(stroke
				(width 0.1)
				(type default)
			)
			(layer "F.Fab")
		)
		(fp_line
			(start -0.12065 -0.2794)
			(end 0.12065 -0.2794)
			(stroke
				(width 0.1)
				(type default)
			)
			(layer "F.Fab")
		)
		(fp_line
			(start -0.12065 0.2794)
			(end -0.12065 0.3048)
			(stroke
				(width 0.1)
				(type default)
			)
			(layer "F.Fab")
		)
		(fp_line
			(start -0.12065 0.3048)
			(end -0.67945 0.3048)
			(stroke
				(width 0.1)
				(type default)
			)
			(layer "F.Fab")
		)
		(fp_line
			(start 0.120396 0.2794)
			(end -0.12065 0.2794)
			(stroke
				(width 0.1)
				(type default)
			)
			(layer "F.Fab")
		)
		(fp_line
			(start 0.120396 0.3048)
			(end 0.120396 0.2794)
			(stroke
				(width 0.1)
				(type default)
			)
			(layer "F.Fab")
		)
		(fp_line
			(start 0.12065 -0.3048)
			(end 0.67945 -0.3048)
			(stroke
				(width 0.1)
				(type default)
			)
			(layer "F.Fab")
		)
		(fp_line
			(start 0.12065 -0.2794)
			(end 0.12065 -0.3048)
			(stroke
				(width 0.1)
				(type default)
			)
			(layer "F.Fab")
		)
		(fp_line
			(start 0.67945 -0.3048)
			(end 0.67945 0.3048)
			(stroke
				(width 0.1)
				(type default)
			)
			(layer "F.Fab")
		)
		(fp_line
			(start 0.67945 0.3048)
			(end 0.120396 0.3048)
			(stroke
				(width 0.1)
				(type default)
			)
			(layer "F.Fab")
		)
		(pad "1" smd circle
			(at -0.40005 0)
			(size 0 0)
			(layers "F.Cu" "F.Mask" "F.Paste")
			(net "GPU_HMC_PRSNT_N")
		)
		(pad "2" smd circle
			(at 0.40005 0)
			(size 0 0)
			(layers "F.Cu" "F.Mask" "F.Paste")
			(net "GND")
		)
	)
	(footprint ""
		(layer "F.Cu")
		(at 88.690958 -402.371052 -90)
		(property "Reference" "C737"
			(at 0 0 270)
			(layer "F.SilkS")
			(hide yes)
			(effects
				(font
					(size 1.27 1.27)
				)
			)
		)
		(property "Value" ""
			(at 0 0 270)
			(layer "F.Fab")
			(effects
				(font
					(size 1.27 1.27)
				)
			)
		)
		(duplicate_pad_numbers_are_jumpers no)
		(fp_line
			(start -0.299974 0.150114)
			(end -0.299974 -0.150114)
			(stroke
				(width 0.1)
				(type default)
			)
			(layer "F.Fab")
		)
		(fp_line
			(start 0.299974 0.150114)
			(end -0.299974 0.150114)
			(stroke
				(width 0.1)
				(type default)
			)
			(layer "F.Fab")
		)
		(fp_line
			(start -0.299974 -0.150114)
			(end 0.299974 -0.150114)
			(stroke
				(width 0.1)
				(type default)
			)
			(layer "F.Fab")
		)
		(fp_line
			(start 0.299974 -0.150114)
			(end 0.299974 0.150114)
			(stroke
				(width 0.1)
				(type default)
			)
			(layer "F.Fab")
		)
		(pad "1" smd rect
			(at -0.2667 0 270)
			(size 0.3048 0.381)
			(layers "F.Cu" "F.Mask" "F.Paste")
			(net "P5E_CPU1_PE0_TX_C_DP<2>")
		)
		(pad "2" smd rect
			(at 0.2667 0 270)
			(size 0.3048 0.381)
			(layers "F.Cu" "F.Mask" "F.Paste")
			(net "P5E_CPU1_PE0_TX_DP<2>")
		)
	)
	(footprint ""
		(layer "F.Cu")
		(at 433.33289 -135.029702 180)
		(property "Reference" "R2398"
			(at 0 0 180)
			(layer "F.SilkS")
			(hide yes)
			(effects
				(font
					(size 1.27 1.27)
				)
			)
		)
		(property "Value" ""
			(at 0 0 180)
			(layer "F.Fab")
			(effects
				(font
					(size 1.27 1.27)
				)
			)
		)
		(duplicate_pad_numbers_are_jumpers no)
		(fp_line
			(start 0.7874 0.4064)
			(end -0.7874 0.4064)
			(stroke
				(width 0.1524)
				(type default)
			)
			(layer "F.SilkS")
		)
		(fp_line
			(start 0.7874 -0.4064)
			(end 0.7874 0.4064)
			(stroke
				(width 0.1524)
				(type default)
			)
			(layer "F.SilkS")
		)
		(fp_line
			(start -0.7874 0.4064)
			(end -0.7874 -0.4064)
			(stroke
				(width 0.1524)
				(type default)
			)
			(layer "F.SilkS")
		)
		(fp_line
			(start -0.7874 -0.4064)
			(end 0.7874 -0.4064)
			(stroke
				(width 0.1524)
				(type default)
			)
			(layer "F.SilkS")
		)
		(fp_line
			(start 0.67945 0.3048)
			(end 0.120396 0.3048)
			(stroke
				(width 0.1)
				(type default)
			)
			(layer "F.Fab")
		)
		(fp_line
			(start 0.67945 -0.3048)
			(end 0.67945 0.3048)
			(stroke
				(width 0.1)
				(type default)
			)
			(layer "F.Fab")
		)
		(fp_line
			(start 0.12065 -0.2794)
			(end 0.12065 -0.3048)
			(stroke
				(width 0.1)
				(type default)
			)
			(layer "F.Fab")
		)
		(fp_line
			(start 0.12065 -0.3048)
			(end 0.67945 -0.3048)
			(stroke
				(width 0.1)
				(type default)
			)
			(layer "F.Fab")
		)
		(fp_line
			(start 0.120396 0.3048)
			(end 0.120396 0.2794)
			(stroke
				(width 0.1)
				(type default)
			)
			(layer "F.Fab")
		)
		(fp_line
			(start 0.120396 0.2794)
			(end -0.12065 0.2794)
			(stroke
				(width 0.1)
				(type default)
			)
			(layer "F.Fab")
		)
		(fp_line
			(start -0.12065 0.3048)
			(end -0.67945 0.3048)
			(stroke
				(width 0.1)
				(type default)
			)
			(layer "F.Fab")
		)
		(fp_line
			(start -0.12065 0.2794)
			(end -0.12065 0.3048)
			(stroke
				(width 0.1)
				(type default)
			)
			(layer "F.Fab")
		)
		(fp_line
			(start -0.12065 -0.2794)
			(end 0.12065 -0.2794)
			(stroke
				(width 0.1)
				(type default)
			)
			(layer "F.Fab")
		)
		(fp_line
			(start -0.12065 -0.305054)
			(end -0.12065 -0.2794)
			(stroke
				(width 0.1)
				(type default)
			)
			(layer "F.Fab")
		)
		(fp_line
			(start -0.67945 0.3048)
			(end -0.67945 -0.305054)
			(stroke
				(width 0.1)
				(type default)
			)
			(layer "F.Fab")
		)
		(fp_line
			(start -0.67945 -0.305054)
			(end -0.12065 -0.305054)
			(stroke
				(width 0.1)
				(type default)
			)
			(layer "F.Fab")
		)
		(pad "1" smd circle
			(at -0.40005 0 180)
			(size 0 0)
			(layers "F.Cu" "F.Mask" "F.Paste")
			(net "P3V3_AUX")
		)
		(pad "2" smd circle
			(at 0.40005 0 180)
			(size 0 0)
			(layers "F.Cu" "F.Mask" "F.Paste")
			(net "IRQ_PVCCFA_CPU0_VRHOT_R_N")
		)
	)
	(footprint ""
		(layer "F.Cu")
		(at 464.01355 -45.669708)
		(property "Reference" "U82"
			(at -0.0127 1.719072 0)
			(unlocked yes)
			(layer "F.SilkS")
			(effects
				(font
					(size 0.7874 0.5842)
					(thickness 0.1524)
				)
				(justify left)
			)
		)
		(property "Value" ""
			(at 0 0 0)
			(layer "F.Fab")
			(effects
				(font
					(size 1.27 1.27)
				)
			)
		)
		(duplicate_pad_numbers_are_jumpers no)
		(fp_line
			(start -1.400048 1.100074)
			(end -1.400048 -1.100074)
			(stroke
				(width 0.1524)
				(type default)
			)
			(layer "F.SilkS")
		)
		(fp_line
			(start 1.400048 -1.100074)
			(end -1.400048 -1.100074)
			(stroke
				(width 0.1524)
				(type default)
			)
			(layer "F.SilkS")
		)
		(fp_line
			(start 1.400048 -1.100074)
			(end 1.400048 1.100074)
			(stroke
				(width 0.1524)
				(type default)
			)
			(layer "F.SilkS")
		)
		(fp_line
			(start 1.400048 1.100074)
			(end -1.400048 1.100074)
			(stroke
				(width 0.1524)
				(type default)
			)
			(layer "F.SilkS")
		)
		(fp_poly
			(pts
				(xy -2.606548 -0.141986) (xy -2.606548 -1.157986) (xy -1.590548 -0.649986)
			)
			(stroke
				(width 0)
				(type default)
			)
			(fill yes)
			(layer "F.SilkS")
		)
		(fp_line
			(start -0.674878 -1.100074)
			(end 0.674878 -1.100074)
			(stroke
				(width 0.1)
				(type default)
			)
			(layer "F.Fab")
		)
		(fp_line
			(start -0.674878 1.100074)
			(end -0.674878 -1.100074)
			(stroke
				(width 0.1)
				(type default)
			)
			(layer "F.Fab")
		)
		(fp_line
			(start 0.674878 -1.100074)
			(end 0.674878 1.100074)
			(stroke
				(width 0.1)
				(type default)
			)
			(layer "F.Fab")
		)
		(fp_line
			(start 0.674878 1.100074)
			(end -0.674878 1.100074)
			(stroke
				(width 0.1)
				(type default)
			)
			(layer "F.Fab")
		)
		(fp_poly
			(pts
				(xy -1.590548 -0.649986) (xy -2.606548 -1.157986) (xy -2.606548 -0.141986)
			)
			(stroke
				(width 0)
				(type default)
			)
			(fill yes)
			(layer "F.Fab")
		)
		(pad "1" smd rect
			(at -0.94996 -0.649986 270)
			(size 0.4318 0.6096)
			(layers "F.Cu" "F.Mask" "F.Paste")
			(net "PU_OCP_SFF_WAKE_OE")
		)
		(pad "2" smd rect
			(at -0.94996 0 270)
			(size 0.4318 0.6096)
			(layers "F.Cu" "F.Mask" "F.Paste")
			(net "IRQ_LVC3_OCP_SFF_WAKE_N")
		)
		(pad "3" smd rect
			(at -0.94996 0.649986 270)
			(size 0.4318 0.6096)
			(layers "F.Cu" "F.Mask" "F.Paste")
			(net "GND")
		)
		(pad "4" smd rect
			(at 0.94996 0.649986 270)
			(size 0.4318 0.6096)
			(layers "F.Cu" "F.Mask" "F.Paste")
			(net "OCP_SFF_WAKE_BUFF_N")
		)
		(pad "5" smd rect
			(at 0.94996 -0.649986 270)
			(size 0.4318 0.6096)
			(layers "F.Cu" "F.Mask" "F.Paste")
			(net "P3V3_AUX")
		)
	)
	(footprint ""
		(layer "F.Cu")
		(at 116.71808 -397.747998 -90)
		(property "Reference" "Q75"
			(at 0.64516 -1.48082 0)
			(unlocked yes)
			(layer "F.SilkS")
			(effects
				(font
					(size 0.7874 0.5842)
					(thickness 0.1524)
				)
				(justify left)
			)
		)
		(property "Value" ""
			(at 0 0 270)
			(layer "F.Fab")
			(effects
				(font
					(size 1.27 1.27)
				)
			)
		)
		(duplicate_pad_numbers_are_jumpers no)
		(fp_line
			(start -1.332738 1.100074)
			(end -1.332738 -1.100074)
			(stroke
				(width 0.1524)
				(type default)
			)
			(layer "F.SilkS")
		)
		(fp_line
			(start 1.332738 1.100074)
			(end -1.332738 1.100074)
			(stroke
				(width 0.1524)
				(type default)
			)
			(layer "F.SilkS")
		)
		(fp_line
			(start 0 -0.541274)
			(end 0.4826 -1.100074)
			(stroke
				(width 0.1524)
				(type default)
			)
			(layer "F.SilkS")
		)
		(fp_line
			(start -1.332738 -1.100074)
			(end -0.4826 -1.100074)
			(stroke
				(width 0.1524)
				(type default)
			)
			(layer "F.SilkS")
		)
		(fp_line
			(start -0.4826 -1.100074)
			(end 0 -0.541274)
			(stroke
				(width 0.1524)
				(type default)
			)
			(layer "F.SilkS")
		)
		(fp_line
			(start 0.4826 -1.100074)
			(end 1.332738 -1.100074)
			(stroke
				(width 0.1524)
				(type default)
			)
			(layer "F.SilkS")
		)
		(fp_line
			(start 1.332738 -1.100074)
			(end 1.332738 1.100074)
			(stroke
				(width 0.1524)
				(type default)
			)
			(layer "F.SilkS")
		)
		(fp_poly
			(pts
				(xy -0.801116 -2.02311) (xy -1.152144 -1.321054) (xy -1.503172 -2.02311)
			)
			(stroke
				(width 0)
				(type default)
			)
			(fill yes)
			(layer "F.SilkS")
		)
		(fp_line
			(start -0.674878 1.100074)
			(end -0.674878 -1.100074)
			(stroke
				(width 0.1)
				(type default)
			)
			(layer "F.Fab")
		)
		(fp_line
			(start 0.674878 1.100074)
			(end -0.674878 1.100074)
			(stroke
				(width 0.1)
				(type default)
			)
			(layer "F.Fab")
		)
		(fp_line
			(start -0.674878 -1.100074)
			(end 0.674878 -1.100074)
			(stroke
				(width 0.1)
				(type default)
			)
			(layer "F.Fab")
		)
		(fp_line
			(start 0.674878 -1.100074)
			(end 0.674878 1.100074)
			(stroke
				(width 0.1)
				(type default)
			)
			(layer "F.Fab")
		)
		(fp_poly
			(pts
				(xy -2.2352 -0.298958) (xy -2.2352 -1.001014) (xy -1.533144 -0.649986)
			)
			(stroke
				(width 0)
				(type default)
			)
			(fill yes)
			(layer "F.Fab")
		)
		(pad "1" smd rect
			(at -0.94996 -0.649986)
			(size 0.4318 0.508)
			(layers "F.Cu" "F.Mask" "F.Paste")
			(net "GND")
		)
		(pad "2" smd rect
			(at -0.94996 0)
			(size 0.4318 0.508)
			(layers "F.Cu" "F.Mask" "F.Paste")
			(net "FM_SMB_1_ALERT_GPU_N")
		)
		(pad "3" smd rect
			(at -0.94996 0.649986)
			(size 0.4318 0.508)
			(layers "F.Cu" "F.Mask" "F.Paste")
			(net "FM_SMB_1_ALERT_GPU_ISO_N")
		)
		(pad "4" smd rect
			(at 0.94996 0.649986)
			(size 0.4318 0.508)
			(layers "F.Cu" "F.Mask" "F.Paste")
			(net "GND")
		)
		(pad "5" smd rect
			(at 0.94996 0)
			(size 0.4318 0.508)
			(layers "F.Cu" "F.Mask" "F.Paste")
			(net "FM_SMB_1_ALERT_GPU")
		)
		(pad "6" smd rect
			(at 0.94996 -0.649986)
			(size 0.4318 0.508)
			(layers "F.Cu" "F.Mask" "F.Paste")
			(net "FM_SMB_1_ALERT_GPU")
		)
	)
	(footprint ""
		(layer "F.Cu")
		(at 424.557444 -367.231676)
		(property "Reference" "PR1298"
			(at 0 0 0)
			(layer "F.SilkS")
			(hide yes)
			(effects
				(font
					(size 1.27 1.27)
				)
			)
		)
		(property "Value" ""
			(at 0 0 0)
			(layer "F.Fab")
			(effects
				(font
					(size 1.27 1.27)
				)
			)
		)
		(duplicate_pad_numbers_are_jumpers no)
		(fp_line
			(start -0.7874 -0.4064)
			(end 0.7874 -0.4064)
			(stroke
				(width 0.1524)
				(type default)
			)
			(layer "F.SilkS")
		)
		(fp_line
			(start -0.7874 0.4064)
			(end -0.7874 -0.4064)
			(stroke
				(width 0.1524)
				(type default)
			)
			(layer "F.SilkS")
		)
		(fp_line
			(start 0.7874 -0.4064)
			(end 0.7874 0.4064)
			(stroke
				(width 0.1524)
				(type default)
			)
			(layer "F.SilkS")
		)
		(fp_line
			(start 0.7874 0.4064)
			(end -0.7874 0.4064)
			(stroke
				(width 0.1524)
				(type default)
			)
			(layer "F.SilkS")
		)
		(fp_line
			(start -0.67945 -0.305054)
			(end -0.12065 -0.305054)
			(stroke
				(width 0.1)
				(type default)
			)
			(layer "F.Fab")
		)
		(fp_line
			(start -0.67945 0.3048)
			(end -0.67945 -0.305054)
			(stroke
				(width 0.1)
				(type default)
			)
			(layer "F.Fab")
		)
		(fp_line
			(start -0.12065 -0.305054)
			(end -0.12065 -0.2794)
			(stroke
				(width 0.1)
				(type default)
			)
			(layer "F.Fab")
		)
		(fp_line
			(start -0.12065 -0.2794)
			(end 0.12065 -0.2794)
			(stroke
				(width 0.1)
				(type default)
			)
			(layer "F.Fab")
		)
		(fp_line
			(start -0.12065 0.2794)
			(end -0.12065 0.3048)
			(stroke
				(width 0.1)
				(type default)
			)
			(layer "F.Fab")
		)
		(fp_line
			(start -0.12065 0.3048)
			(end -0.67945 0.3048)
			(stroke
				(width 0.1)
				(type default)
			)
			(layer "F.Fab")
		)
		(fp_line
			(start 0.120396 0.2794)
			(end -0.12065 0.2794)
			(stroke
				(width 0.1)
				(type default)
			)
			(layer "F.Fab")
		)
		(fp_line
			(start 0.120396 0.3048)
			(end 0.120396 0.2794)
			(stroke
				(width 0.1)
				(type default)
			)
			(layer "F.Fab")
		)
		(fp_line
			(start 0.12065 -0.3048)
			(end 0.67945 -0.3048)
			(stroke
				(width 0.1)
				(type default)
			)
			(layer "F.Fab")
		)
		(fp_line
			(start 0.12065 -0.2794)
			(end 0.12065 -0.3048)
			(stroke
				(width 0.1)
				(type default)
			)
			(layer "F.Fab")
		)
		(fp_line
			(start 0.67945 -0.3048)
			(end 0.67945 0.3048)
			(stroke
				(width 0.1)
				(type default)
			)
			(layer "F.Fab")
		)
		(fp_line
			(start 0.67945 0.3048)
			(end 0.120396 0.3048)
			(stroke
				(width 0.1)
				(type default)
			)
			(layer "F.Fab")
		)
		(pad "1" smd circle
			(at -0.40005 0)
			(size 0 0)
			(layers "F.Cu" "F.Mask" "F.Paste")
			(net "PVCCFA_EHV_FIVRA_CPU0_LSET3")
		)
		(pad "2" smd circle
			(at 0.40005 0)
			(size 0 0)
			(layers "F.Cu" "F.Mask" "F.Paste")
			(net "GND")
		)
	)
	(footprint ""
		(layer "F.Cu")
		(at 175.595534 -353.62261 -90)
		(property "Reference" "PC399_P1_1"
			(at 0 0 270)
			(layer "F.SilkS")
			(hide yes)
			(effects
				(font
					(size 1.27 1.27)
				)
			)
		)
		(property "Value" ""
			(at 0 0 270)
			(layer "F.Fab")
			(effects
				(font
					(size 1.27 1.27)
				)
			)
		)
		(duplicate_pad_numbers_are_jumpers no)
		(fp_line
			(start -0.7874 0.4064)
			(end -0.7874 -0.4064)
			(stroke
				(width 0.1524)
				(type default)
			)
			(layer "F.SilkS")
		)
		(fp_line
			(start 0.7874 0.4064)
			(end -0.7874 0.4064)
			(stroke
				(width 0.1524)
				(type default)
			)
			(layer "F.SilkS")
		)
		(fp_line
			(start -0.7874 -0.4064)
			(end 0.7874 -0.4064)
			(stroke
				(width 0.1524)
				(type default)
			)
			(layer "F.SilkS")
		)
		(fp_line
			(start 0.7874 -0.4064)
			(end 0.7874 0.4064)
			(stroke
				(width 0.1524)
				(type default)
			)
			(layer "F.SilkS")
		)
		(fp_line
			(start -0.67945 0.3048)
			(end -0.67945 -0.305054)
			(stroke
				(width 0.1)
				(type default)
			)
			(layer "F.Fab")
		)
		(fp_line
			(start -0.12065 0.3048)
			(end -0.67945 0.3048)
			(stroke
				(width 0.1)
				(type default)
			)
			(layer "F.Fab")
		)
		(fp_line
			(start 0.120396 0.3048)
			(end 0.120396 0.2794)
			(stroke
				(width 0.1)
				(type default)
			)
			(layer "F.Fab")
		)
		(fp_line
			(start 0.67945 0.3048)
			(end 0.120396 0.3048)
			(stroke
				(width 0.1)
				(type default)
			)
			(layer "F.Fab")
		)
		(fp_line
			(start -0.12065 0.2794)
			(end -0.12065 0.3048)
			(stroke
				(width 0.1)
				(type default)
			)
			(layer "F.Fab")
		)
		(fp_line
			(start 0.120396 0.2794)
			(end -0.12065 0.2794)
			(stroke
				(width 0.1)
				(type default)
			)
			(layer "F.Fab")
		)
		(fp_line
			(start -0.12065 -0.2794)
			(end 0.12065 -0.2794)
			(stroke
				(width 0.1)
				(type default)
			)
			(layer "F.Fab")
		)
		(fp_line
			(start 0.12065 -0.2794)
			(end 0.12065 -0.3048)
			(stroke
				(width 0.1)
				(type default)
			)
			(layer "F.Fab")
		)
		(fp_line
			(start 0.12065 -0.3048)
			(end 0.67945 -0.3048)
			(stroke
				(width 0.1)
				(type default)
			)
			(layer "F.Fab")
		)
		(fp_line
			(start 0.67945 -0.3048)
			(end 0.67945 0.3048)
			(stroke
				(width 0.1)
				(type default)
			)
			(layer "F.Fab")
		)
		(fp_line
			(start -0.67945 -0.305054)
			(end -0.12065 -0.305054)
			(stroke
				(width 0.1)
				(type default)
			)
			(layer "F.Fab")
		)
		(fp_line
			(start -0.12065 -0.305054)
			(end -0.12065 -0.2794)
			(stroke
				(width 0.1)
				(type default)
			)
			(layer "F.Fab")
		)
		(pad "1" smd circle
			(at -0.40005 0 270)
			(size 0 0)
			(layers "F.Cu" "F.Mask" "F.Paste")
			(net "SW_P12V_PVCCFA_EHV_FIVRA_CPU1_R")
		)
		(pad "2" smd circle
			(at 0.40005 0 270)
			(size 0 0)
			(layers "F.Cu" "F.Mask" "F.Paste")
			(net "GND")
		)
	)
	(footprint ""
		(layer "F.Cu")
		(at 385.716272 -58.703464 180)
		(property "Reference" "R1472"
			(at 0 0 180)
			(layer "F.SilkS")
			(hide yes)
			(effects
				(font
					(size 1.27 1.27)
				)
			)
		)
		(property "Value" ""
			(at 0 0 180)
			(layer "F.Fab")
			(effects
				(font
					(size 1.27 1.27)
				)
			)
		)
		(duplicate_pad_numbers_are_jumpers no)
		(fp_line
			(start 0.7874 0.4064)
			(end -0.7874 0.4064)
			(stroke
				(width 0.1524)
				(type default)
			)
			(layer "F.SilkS")
		)
		(fp_line
			(start 0.7874 -0.4064)
			(end 0.7874 0.4064)
			(stroke
				(width 0.1524)
				(type default)
			)
			(layer "F.SilkS")
		)
		(fp_line
			(start -0.7874 0.4064)
			(end -0.7874 -0.4064)
			(stroke
				(width 0.1524)
				(type default)
			)
			(layer "F.SilkS")
		)
		(fp_line
			(start -0.7874 -0.4064)
			(end 0.7874 -0.4064)
			(stroke
				(width 0.1524)
				(type default)
			)
			(layer "F.SilkS")
		)
		(fp_line
			(start 0.67945 0.3048)
			(end 0.120396 0.3048)
			(stroke
				(width 0.1)
				(type default)
			)
			(layer "F.Fab")
		)
		(fp_line
			(start 0.67945 -0.3048)
			(end 0.67945 0.3048)
			(stroke
				(width 0.1)
				(type default)
			)
			(layer "F.Fab")
		)
		(fp_line
			(start 0.12065 -0.2794)
			(end 0.12065 -0.3048)
			(stroke
				(width 0.1)
				(type default)
			)
			(layer "F.Fab")
		)
		(fp_line
			(start 0.12065 -0.3048)
			(end 0.67945 -0.3048)
			(stroke
				(width 0.1)
				(type default)
			)
			(layer "F.Fab")
		)
		(fp_line
			(start 0.120396 0.3048)
			(end 0.120396 0.2794)
			(stroke
				(width 0.1)
				(type default)
			)
			(layer "F.Fab")
		)
		(fp_line
			(start 0.120396 0.2794)
			(end -0.12065 0.2794)
			(stroke
				(width 0.1)
				(type default)
			)
			(layer "F.Fab")
		)
		(fp_line
			(start -0.12065 0.3048)
			(end -0.67945 0.3048)
			(stroke
				(width 0.1)
				(type default)
			)
			(layer "F.Fab")
		)
		(fp_line
			(start -0.12065 0.2794)
			(end -0.12065 0.3048)
			(stroke
				(width 0.1)
				(type default)
			)
			(layer "F.Fab")
		)
		(fp_line
			(start -0.12065 -0.2794)
			(end 0.12065 -0.2794)
			(stroke
				(width 0.1)
				(type default)
			)
			(layer "F.Fab")
		)
		(fp_line
			(start -0.12065 -0.305054)
			(end -0.12065 -0.2794)
			(stroke
				(width 0.1)
				(type default)
			)
			(layer "F.Fab")
		)
		(fp_line
			(start -0.67945 0.3048)
			(end -0.67945 -0.305054)
			(stroke
				(width 0.1)
				(type default)
			)
			(layer "F.Fab")
		)
		(fp_line
			(start -0.67945 -0.305054)
			(end -0.12065 -0.305054)
			(stroke
				(width 0.1)
				(type default)
			)
			(layer "F.Fab")
		)
		(pad "1" smd circle
			(at -0.40005 0 180)
			(size 0 0)
			(layers "F.Cu" "F.Mask" "F.Paste")
			(net "JTAG_DBP_PRESENT_R_N")
		)
		(pad "2" smd circle
			(at 0.40005 0 180)
			(size 0 0)
			(layers "F.Cu" "F.Mask" "F.Paste")
			(net "FM_BMC_DBP_PRESENT_R_N")
		)
	)
	(footprint ""
		(layer "F.Cu")
		(at 72.460358 -402.371052 -90)
		(property "Reference" "C726"
			(at 0 0 270)
			(layer "F.SilkS")
			(hide yes)
			(effects
				(font
					(size 1.27 1.27)
				)
			)
		)
		(property "Value" ""
			(at 0 0 270)
			(layer "F.Fab")
			(effects
				(font
					(size 1.27 1.27)
				)
			)
		)
		(duplicate_pad_numbers_are_jumpers no)
		(fp_line
			(start -0.299974 0.150114)
			(end -0.299974 -0.150114)
			(stroke
				(width 0.1)
				(type default)
			)
			(layer "F.Fab")
		)
		(fp_line
			(start 0.299974 0.150114)
			(end -0.299974 0.150114)
			(stroke
				(width 0.1)
				(type default)
			)
			(layer "F.Fab")
		)
		(fp_line
			(start -0.299974 -0.150114)
			(end 0.299974 -0.150114)
			(stroke
				(width 0.1)
				(type default)
			)
			(layer "F.Fab")
		)
		(fp_line
			(start 0.299974 -0.150114)
			(end 0.299974 0.150114)
			(stroke
				(width 0.1)
				(type default)
			)
			(layer "F.Fab")
		)
		(pad "1" smd rect
			(at -0.2667 0 270)
			(size 0.3048 0.381)
			(layers "F.Cu" "F.Mask" "F.Paste")
			(net "P5E_CPU1_PE0_TX_C_DN<7>")
		)
		(pad "2" smd rect
			(at 0.2667 0 270)
			(size 0.3048 0.381)
			(layers "F.Cu" "F.Mask" "F.Paste")
			(net "P5E_CPU1_PE0_TX_DN<7>")
		)
	)
	(footprint ""
		(layer "F.Cu")
		(at 420.591488 -165.018974 180)
		(property "Reference" "PC1354"
			(at 0 0 180)
			(layer "F.SilkS")
			(hide yes)
			(effects
				(font
					(size 1.27 1.27)
				)
			)
		)
		(property "Value" ""
			(at 0 0 180)
			(layer "F.Fab")
			(effects
				(font
					(size 1.27 1.27)
				)
			)
		)
		(duplicate_pad_numbers_are_jumpers no)
		(fp_line
			(start 0.7874 0.4064)
			(end -0.7874 0.4064)
			(stroke
				(width 0.1524)
				(type default)
			)
			(layer "F.SilkS")
		)
		(fp_line
			(start 0.7874 -0.4064)
			(end 0.7874 0.4064)
			(stroke
				(width 0.1524)
				(type default)
			)
			(layer "F.SilkS")
		)
		(fp_line
			(start -0.7874 0.4064)
			(end -0.7874 -0.4064)
			(stroke
				(width 0.1524)
				(type default)
			)
			(layer "F.SilkS")
		)
		(fp_line
			(start -0.7874 -0.4064)
			(end 0.7874 -0.4064)
			(stroke
				(width 0.1524)
				(type default)
			)
			(layer "F.SilkS")
		)
		(fp_line
			(start 0.67945 0.3048)
			(end 0.120396 0.3048)
			(stroke
				(width 0.1)
				(type default)
			)
			(layer "F.Fab")
		)
		(fp_line
			(start 0.67945 -0.3048)
			(end 0.67945 0.3048)
			(stroke
				(width 0.1)
				(type default)
			)
			(layer "F.Fab")
		)
		(fp_line
			(start 0.12065 -0.2794)
			(end 0.12065 -0.3048)
			(stroke
				(width 0.1)
				(type default)
			)
			(layer "F.Fab")
		)
		(fp_line
			(start 0.12065 -0.3048)
			(end 0.67945 -0.3048)
			(stroke
				(width 0.1)
				(type default)
			)
			(layer "F.Fab")
		)
		(fp_line
			(start 0.120396 0.3048)
			(end 0.120396 0.2794)
			(stroke
				(width 0.1)
				(type default)
			)
			(layer "F.Fab")
		)
		(fp_line
			(start 0.120396 0.2794)
			(end -0.12065 0.2794)
			(stroke
				(width 0.1)
				(type default)
			)
			(layer "F.Fab")
		)
		(fp_line
			(start -0.12065 0.3048)
			(end -0.67945 0.3048)
			(stroke
				(width 0.1)
				(type default)
			)
			(layer "F.Fab")
		)
		(fp_line
			(start -0.12065 0.2794)
			(end -0.12065 0.3048)
			(stroke
				(width 0.1)
				(type default)
			)
			(layer "F.Fab")
		)
		(fp_line
			(start -0.12065 -0.2794)
			(end 0.12065 -0.2794)
			(stroke
				(width 0.1)
				(type default)
			)
			(layer "F.Fab")
		)
		(fp_line
			(start -0.12065 -0.305054)
			(end -0.12065 -0.2794)
			(stroke
				(width 0.1)
				(type default)
			)
			(layer "F.Fab")
		)
		(fp_line
			(start -0.67945 0.3048)
			(end -0.67945 -0.305054)
			(stroke
				(width 0.1)
				(type default)
			)
			(layer "F.Fab")
		)
		(fp_line
			(start -0.67945 -0.305054)
			(end -0.12065 -0.305054)
			(stroke
				(width 0.1)
				(type default)
			)
			(layer "F.Fab")
		)
		(pad "1" smd circle
			(at -0.40005 0 180)
			(size 0 0)
			(layers "F.Cu" "F.Mask" "F.Paste")
			(net "GND")
		)
		(pad "2" smd circle
			(at 0.40005 0 180)
			(size 0 0)
			(layers "F.Cu" "F.Mask" "F.Paste")
			(net "PVCCD_HV_CPU0_VREF")
		)
	)
	(footprint ""
		(layer "F.Cu")
		(at 294.045894 -413.05988)
		(property "Reference" "R4692"
			(at 0 0 0)
			(layer "F.SilkS")
			(hide yes)
			(effects
				(font
					(size 1.27 1.27)
				)
			)
		)
		(property "Value" ""
			(at 0 0 0)
			(layer "F.Fab")
			(effects
				(font
					(size 1.27 1.27)
				)
			)
		)
		(duplicate_pad_numbers_are_jumpers no)
		(fp_line
			(start -0.7874 -0.4064)
			(end 0.7874 -0.4064)
			(stroke
				(width 0.1524)
				(type default)
			)
			(layer "F.SilkS")
		)
		(fp_line
			(start -0.7874 0.4064)
			(end -0.7874 -0.4064)
			(stroke
				(width 0.1524)
				(type default)
			)
			(layer "F.SilkS")
		)
		(fp_line
			(start 0.7874 -0.4064)
			(end 0.7874 0.4064)
			(stroke
				(width 0.1524)
				(type default)
			)
			(layer "F.SilkS")
		)
		(fp_line
			(start 0.7874 0.4064)
			(end -0.7874 0.4064)
			(stroke
				(width 0.1524)
				(type default)
			)
			(layer "F.SilkS")
		)
		(fp_line
			(start -0.67945 -0.305054)
			(end -0.12065 -0.305054)
			(stroke
				(width 0.1)
				(type default)
			)
			(layer "F.Fab")
		)
		(fp_line
			(start -0.67945 0.3048)
			(end -0.67945 -0.305054)
			(stroke
				(width 0.1)
				(type default)
			)
			(layer "F.Fab")
		)
		(fp_line
			(start -0.12065 -0.305054)
			(end -0.12065 -0.2794)
			(stroke
				(width 0.1)
				(type default)
			)
			(layer "F.Fab")
		)
		(fp_line
			(start -0.12065 -0.2794)
			(end 0.12065 -0.2794)
			(stroke
				(width 0.1)
				(type default)
			)
			(layer "F.Fab")
		)
		(fp_line
			(start -0.12065 0.2794)
			(end -0.12065 0.3048)
			(stroke
				(width 0.1)
				(type default)
			)
			(layer "F.Fab")
		)
		(fp_line
			(start -0.12065 0.3048)
			(end -0.67945 0.3048)
			(stroke
				(width 0.1)
				(type default)
			)
			(layer "F.Fab")
		)
		(fp_line
			(start 0.120396 0.2794)
			(end -0.12065 0.2794)
			(stroke
				(width 0.1)
				(type default)
			)
			(layer "F.Fab")
		)
		(fp_line
			(start 0.120396 0.3048)
			(end 0.120396 0.2794)
			(stroke
				(width 0.1)
				(type default)
			)
			(layer "F.Fab")
		)
		(fp_line
			(start 0.12065 -0.3048)
			(end 0.67945 -0.3048)
			(stroke
				(width 0.1)
				(type default)
			)
			(layer "F.Fab")
		)
		(fp_line
			(start 0.12065 -0.2794)
			(end 0.12065 -0.3048)
			(stroke
				(width 0.1)
				(type default)
			)
			(layer "F.Fab")
		)
		(fp_line
			(start 0.67945 -0.3048)
			(end 0.67945 0.3048)
			(stroke
				(width 0.1)
				(type default)
			)
			(layer "F.Fab")
		)
		(fp_line
			(start 0.67945 0.3048)
			(end 0.120396 0.3048)
			(stroke
				(width 0.1)
				(type default)
			)
			(layer "F.Fab")
		)
		(pad "1" smd circle
			(at -0.40005 0)
			(size 0 0)
			(layers "F.Cu" "F.Mask" "F.Paste")
			(net "P3V3_AUX")
		)
		(pad "2" smd circle
			(at 0.40005 0)
			(size 0 0)
			(layers "F.Cu" "F.Mask" "F.Paste")
			(net "TP_HSC_TYPE_ADC_ALERT")
		)
	)
	(footprint ""
		(layer "F.Cu")
		(at 82.564478 -402.371052 -90)
		(property "Reference" "C733"
			(at 0 0 270)
			(layer "F.SilkS")
			(hide yes)
			(effects
				(font
					(size 1.27 1.27)
				)
			)
		)
		(property "Value" ""
			(at 0 0 270)
			(layer "F.Fab")
			(effects
				(font
					(size 1.27 1.27)
				)
			)
		)
		(duplicate_pad_numbers_are_jumpers no)
		(fp_line
			(start -0.299974 0.150114)
			(end -0.299974 -0.150114)
			(stroke
				(width 0.1)
				(type default)
			)
			(layer "F.Fab")
		)
		(fp_line
			(start 0.299974 0.150114)
			(end -0.299974 0.150114)
			(stroke
				(width 0.1)
				(type default)
			)
			(layer "F.Fab")
		)
		(fp_line
			(start -0.299974 -0.150114)
			(end 0.299974 -0.150114)
			(stroke
				(width 0.1)
				(type default)
			)
			(layer "F.Fab")
		)
		(fp_line
			(start 0.299974 -0.150114)
			(end 0.299974 0.150114)
			(stroke
				(width 0.1)
				(type default)
			)
			(layer "F.Fab")
		)
		(pad "1" smd rect
			(at -0.2667 0 270)
			(size 0.3048 0.381)
			(layers "F.Cu" "F.Mask" "F.Paste")
			(net "P5E_CPU1_PE0_TX_C_DP<4>")
		)
		(pad "2" smd rect
			(at 0.2667 0 270)
			(size 0.3048 0.381)
			(layers "F.Cu" "F.Mask" "F.Paste")
			(net "P5E_CPU1_PE0_TX_DP<4>")
		)
	)
	(footprint ""
		(layer "F.Cu")
		(at 50.437542 -149.575266)
		(property "Reference" "PC447"
			(at 0 0 0)
			(layer "F.SilkS")
			(hide yes)
			(effects
				(font
					(size 1.27 1.27)
				)
			)
		)
		(property "Value" ""
			(at 0 0 0)
			(layer "F.Fab")
			(effects
				(font
					(size 1.27 1.27)
				)
			)
		)
		(duplicate_pad_numbers_are_jumpers no)
		(fp_line
			(start -0.7874 -0.4064)
			(end 0.7874 -0.4064)
			(stroke
				(width 0.1524)
				(type default)
			)
			(layer "F.SilkS")
		)
		(fp_line
			(start -0.7874 0.4064)
			(end -0.7874 -0.4064)
			(stroke
				(width 0.1524)
				(type default)
			)
			(layer "F.SilkS")
		)
		(fp_line
			(start 0.7874 -0.4064)
			(end 0.7874 0.4064)
			(stroke
				(width 0.1524)
				(type default)
			)
			(layer "F.SilkS")
		)
		(fp_line
			(start 0.7874 0.4064)
			(end -0.7874 0.4064)
			(stroke
				(width 0.1524)
				(type default)
			)
			(layer "F.SilkS")
		)
		(fp_line
			(start -0.67945 -0.305054)
			(end -0.12065 -0.305054)
			(stroke
				(width 0.1)
				(type default)
			)
			(layer "F.Fab")
		)
		(fp_line
			(start -0.67945 0.3048)
			(end -0.67945 -0.305054)
			(stroke
				(width 0.1)
				(type default)
			)
			(layer "F.Fab")
		)
		(fp_line
			(start -0.12065 -0.305054)
			(end -0.12065 -0.2794)
			(stroke
				(width 0.1)
				(type default)
			)
			(layer "F.Fab")
		)
		(fp_line
			(start -0.12065 -0.2794)
			(end 0.12065 -0.2794)
			(stroke
				(width 0.1)
				(type default)
			)
			(layer "F.Fab")
		)
		(fp_line
			(start -0.12065 0.2794)
			(end -0.12065 0.3048)
			(stroke
				(width 0.1)
				(type default)
			)
			(layer "F.Fab")
		)
		(fp_line
			(start -0.12065 0.3048)
			(end -0.67945 0.3048)
			(stroke
				(width 0.1)
				(type default)
			)
			(layer "F.Fab")
		)
		(fp_line
			(start 0.120396 0.2794)
			(end -0.12065 0.2794)
			(stroke
				(width 0.1)
				(type default)
			)
			(layer "F.Fab")
		)
		(fp_line
			(start 0.120396 0.3048)
			(end 0.120396 0.2794)
			(stroke
				(width 0.1)
				(type default)
			)
			(layer "F.Fab")
		)
		(fp_line
			(start 0.12065 -0.3048)
			(end 0.67945 -0.3048)
			(stroke
				(width 0.1)
				(type default)
			)
			(layer "F.Fab")
		)
		(fp_line
			(start 0.12065 -0.2794)
			(end 0.12065 -0.3048)
			(stroke
				(width 0.1)
				(type default)
			)
			(layer "F.Fab")
		)
		(fp_line
			(start 0.67945 -0.3048)
			(end 0.67945 0.3048)
			(stroke
				(width 0.1)
				(type default)
			)
			(layer "F.Fab")
		)
		(fp_line
			(start 0.67945 0.3048)
			(end 0.120396 0.3048)
			(stroke
				(width 0.1)
				(type default)
			)
			(layer "F.Fab")
		)
		(pad "1" smd circle
			(at -0.40005 0)
			(size 0 0)
			(layers "F.Cu" "F.Mask" "F.Paste")
			(net "SW_PVCCINFAON_CPU1_BOOT2_R")
		)
		(pad "2" smd circle
			(at 0.40005 0)
			(size 0 0)
			(layers "F.Cu" "F.Mask" "F.Paste")
			(net "SW_PVCCINFAON_CPU1_BOOTR2")
		)
	)
	(footprint ""
		(layer "F.Cu")
		(at 278.246078 -417.2839 -90)
		(property "Reference" "R4673"
			(at 0 0 270)
			(layer "F.SilkS")
			(hide yes)
			(effects
				(font
					(size 1.27 1.27)
				)
			)
		)
		(property "Value" ""
			(at 0 0 270)
			(layer "F.Fab")
			(effects
				(font
					(size 1.27 1.27)
				)
			)
		)
		(duplicate_pad_numbers_are_jumpers no)
		(fp_line
			(start -0.7874 0.4064)
			(end -0.7874 -0.4064)
			(stroke
				(width 0.1524)
				(type default)
			)
			(layer "F.SilkS")
		)
		(fp_line
			(start 0.7874 0.4064)
			(end -0.7874 0.4064)
			(stroke
				(width 0.1524)
				(type default)
			)
			(layer "F.SilkS")
		)
		(fp_line
			(start -0.7874 -0.4064)
			(end 0.7874 -0.4064)
			(stroke
				(width 0.1524)
				(type default)
			)
			(layer "F.SilkS")
		)
		(fp_line
			(start 0.7874 -0.4064)
			(end 0.7874 0.4064)
			(stroke
				(width 0.1524)
				(type default)
			)
			(layer "F.SilkS")
		)
		(fp_line
			(start -0.67945 0.3048)
			(end -0.67945 -0.305054)
			(stroke
				(width 0.1)
				(type default)
			)
			(layer "F.Fab")
		)
		(fp_line
			(start -0.12065 0.3048)
			(end -0.67945 0.3048)
			(stroke
				(width 0.1)
				(type default)
			)
			(layer "F.Fab")
		)
		(fp_line
			(start 0.120396 0.3048)
			(end 0.120396 0.2794)
			(stroke
				(width 0.1)
				(type default)
			)
			(layer "F.Fab")
		)
		(fp_line
			(start 0.67945 0.3048)
			(end 0.120396 0.3048)
			(stroke
				(width 0.1)
				(type default)
			)
			(layer "F.Fab")
		)
		(fp_line
			(start -0.12065 0.2794)
			(end -0.12065 0.3048)
			(stroke
				(width 0.1)
				(type default)
			)
			(layer "F.Fab")
		)
		(fp_line
			(start 0.120396 0.2794)
			(end -0.12065 0.2794)
			(stroke
				(width 0.1)
				(type default)
			)
			(layer "F.Fab")
		)
		(fp_line
			(start -0.12065 -0.2794)
			(end 0.12065 -0.2794)
			(stroke
				(width 0.1)
				(type default)
			)
			(layer "F.Fab")
		)
		(fp_line
			(start 0.12065 -0.2794)
			(end 0.12065 -0.3048)
			(stroke
				(width 0.1)
				(type default)
			)
			(layer "F.Fab")
		)
		(fp_line
			(start 0.12065 -0.3048)
			(end 0.67945 -0.3048)
			(stroke
				(width 0.1)
				(type default)
			)
			(layer "F.Fab")
		)
		(fp_line
			(start 0.67945 -0.3048)
			(end 0.67945 0.3048)
			(stroke
				(width 0.1)
				(type default)
			)
			(layer "F.Fab")
		)
		(fp_line
			(start -0.67945 -0.305054)
			(end -0.12065 -0.305054)
			(stroke
				(width 0.1)
				(type default)
			)
			(layer "F.Fab")
		)
		(fp_line
			(start -0.12065 -0.305054)
			(end -0.12065 -0.2794)
			(stroke
				(width 0.1)
				(type default)
			)
			(layer "F.Fab")
		)
		(pad "1" smd circle
			(at -0.40005 0 270)
			(size 0 0)
			(layers "F.Cu" "F.Mask" "F.Paste")
			(net "A_HSC_LOW_GATE")
		)
		(pad "2" smd circle
			(at 0.40005 0 270)
			(size 0 0)
			(layers "F.Cu" "F.Mask" "F.Paste")
			(net "GND")
		)
	)
	(footprint ""
		(layer "F.Cu")
		(at 374.16359 -66.898012)
		(property "Reference" "R755"
			(at 0 0 0)
			(layer "F.SilkS")
			(hide yes)
			(effects
				(font
					(size 1.27 1.27)
				)
			)
		)
		(property "Value" ""
			(at 0 0 0)
			(layer "F.Fab")
			(effects
				(font
					(size 1.27 1.27)
				)
			)
		)
		(duplicate_pad_numbers_are_jumpers no)
		(fp_line
			(start -0.7874 -0.4064)
			(end 0.7874 -0.4064)
			(stroke
				(width 0.1524)
				(type default)
			)
			(layer "F.SilkS")
		)
		(fp_line
			(start -0.7874 0.4064)
			(end -0.7874 -0.4064)
			(stroke
				(width 0.1524)
				(type default)
			)
			(layer "F.SilkS")
		)
		(fp_line
			(start 0.7874 -0.4064)
			(end 0.7874 0.4064)
			(stroke
				(width 0.1524)
				(type default)
			)
			(layer "F.SilkS")
		)
		(fp_line
			(start 0.7874 0.4064)
			(end -0.7874 0.4064)
			(stroke
				(width 0.1524)
				(type default)
			)
			(layer "F.SilkS")
		)
		(fp_line
			(start -0.67945 -0.305054)
			(end -0.12065 -0.305054)
			(stroke
				(width 0.1)
				(type default)
			)
			(layer "F.Fab")
		)
		(fp_line
			(start -0.67945 0.3048)
			(end -0.67945 -0.305054)
			(stroke
				(width 0.1)
				(type default)
			)
			(layer "F.Fab")
		)
		(fp_line
			(start -0.12065 -0.305054)
			(end -0.12065 -0.2794)
			(stroke
				(width 0.1)
				(type default)
			)
			(layer "F.Fab")
		)
		(fp_line
			(start -0.12065 -0.2794)
			(end 0.12065 -0.2794)
			(stroke
				(width 0.1)
				(type default)
			)
			(layer "F.Fab")
		)
		(fp_line
			(start -0.12065 0.2794)
			(end -0.12065 0.3048)
			(stroke
				(width 0.1)
				(type default)
			)
			(layer "F.Fab")
		)
		(fp_line
			(start -0.12065 0.3048)
			(end -0.67945 0.3048)
			(stroke
				(width 0.1)
				(type default)
			)
			(layer "F.Fab")
		)
		(fp_line
			(start 0.120396 0.2794)
			(end -0.12065 0.2794)
			(stroke
				(width 0.1)
				(type default)
			)
			(layer "F.Fab")
		)
		(fp_line
			(start 0.120396 0.3048)
			(end 0.120396 0.2794)
			(stroke
				(width 0.1)
				(type default)
			)
			(layer "F.Fab")
		)
		(fp_line
			(start 0.12065 -0.3048)
			(end 0.67945 -0.3048)
			(stroke
				(width 0.1)
				(type default)
			)
			(layer "F.Fab")
		)
		(fp_line
			(start 0.12065 -0.2794)
			(end 0.12065 -0.3048)
			(stroke
				(width 0.1)
				(type default)
			)
			(layer "F.Fab")
		)
		(fp_line
			(start 0.67945 -0.3048)
			(end 0.67945 0.3048)
			(stroke
				(width 0.1)
				(type default)
			)
			(layer "F.Fab")
		)
		(fp_line
			(start 0.67945 0.3048)
			(end 0.120396 0.3048)
			(stroke
				(width 0.1)
				(type default)
			)
			(layer "F.Fab")
		)
		(pad "1" smd circle
			(at -0.40005 0)
			(size 0 0)
			(layers "F.Cu" "F.Mask" "F.Paste")
			(net "JTAG_DBP_PREQ_N")
		)
		(pad "2" smd circle
			(at 0.40005 0)
			(size 0 0)
			(layers "F.Cu" "F.Mask" "F.Paste")
			(net "H_DBP_PREQ_N_PCH")
		)
	)
	(footprint ""
		(layer "F.Cu")
		(at 152.09393 -36.741608 -90)
		(property "Reference" "C2327"
			(at 0 0 270)
			(layer "F.SilkS")
			(hide yes)
			(effects
				(font
					(size 1.27 1.27)
				)
			)
		)
		(property "Value" ""
			(at 0 0 270)
			(layer "F.Fab")
			(effects
				(font
					(size 1.27 1.27)
				)
			)
		)
		(duplicate_pad_numbers_are_jumpers no)
		(fp_line
			(start -0.7874 0.4064)
			(end -0.7874 -0.4064)
			(stroke
				(width 0.1524)
				(type default)
			)
			(layer "F.SilkS")
		)
		(fp_line
			(start 0.7874 0.4064)
			(end -0.7874 0.4064)
			(stroke
				(width 0.1524)
				(type default)
			)
			(layer "F.SilkS")
		)
		(fp_line
			(start -0.7874 -0.4064)
			(end 0.7874 -0.4064)
			(stroke
				(width 0.1524)
				(type default)
			)
			(layer "F.SilkS")
		)
		(fp_line
			(start 0.7874 -0.4064)
			(end 0.7874 0.4064)
			(stroke
				(width 0.1524)
				(type default)
			)
			(layer "F.SilkS")
		)
		(fp_line
			(start -0.67945 0.3048)
			(end -0.67945 -0.305054)
			(stroke
				(width 0.1)
				(type default)
			)
			(layer "F.Fab")
		)
		(fp_line
			(start -0.12065 0.3048)
			(end -0.67945 0.3048)
			(stroke
				(width 0.1)
				(type default)
			)
			(layer "F.Fab")
		)
		(fp_line
			(start 0.120396 0.3048)
			(end 0.120396 0.2794)
			(stroke
				(width 0.1)
				(type default)
			)
			(layer "F.Fab")
		)
		(fp_line
			(start 0.67945 0.3048)
			(end 0.120396 0.3048)
			(stroke
				(width 0.1)
				(type default)
			)
			(layer "F.Fab")
		)
		(fp_line
			(start -0.12065 0.2794)
			(end -0.12065 0.3048)
			(stroke
				(width 0.1)
				(type default)
			)
			(layer "F.Fab")
		)
		(fp_line
			(start 0.120396 0.2794)
			(end -0.12065 0.2794)
			(stroke
				(width 0.1)
				(type default)
			)
			(layer "F.Fab")
		)
		(fp_line
			(start -0.12065 -0.2794)
			(end 0.12065 -0.2794)
			(stroke
				(width 0.1)
				(type default)
			)
			(layer "F.Fab")
		)
		(fp_line
			(start 0.12065 -0.2794)
			(end 0.12065 -0.3048)
			(stroke
				(width 0.1)
				(type default)
			)
			(layer "F.Fab")
		)
		(fp_line
			(start 0.12065 -0.3048)
			(end 0.67945 -0.3048)
			(stroke
				(width 0.1)
				(type default)
			)
			(layer "F.Fab")
		)
		(fp_line
			(start 0.67945 -0.3048)
			(end 0.67945 0.3048)
			(stroke
				(width 0.1)
				(type default)
			)
			(layer "F.Fab")
		)
		(fp_line
			(start -0.67945 -0.305054)
			(end -0.12065 -0.305054)
			(stroke
				(width 0.1)
				(type default)
			)
			(layer "F.Fab")
		)
		(fp_line
			(start -0.12065 -0.305054)
			(end -0.12065 -0.2794)
			(stroke
				(width 0.1)
				(type default)
			)
			(layer "F.Fab")
		)
		(pad "1" smd circle
			(at -0.40005 0 270)
			(size 0 0)
			(layers "F.Cu" "F.Mask" "F.Paste")
			(net "USB_HUB_2_XTAL_OUT")
		)
		(pad "2" smd circle
			(at 0.40005 0 270)
			(size 0 0)
			(layers "F.Cu" "F.Mask" "F.Paste")
			(net "GND")
		)
	)
	(footprint ""
		(layer "F.Cu")
		(at 167.386 -23.713948 -90)
		(property "Reference" "R148"
			(at 0 0 270)
			(layer "F.SilkS")
			(hide yes)
			(effects
				(font
					(size 1.27 1.27)
				)
			)
		)
		(property "Value" ""
			(at 0 0 270)
			(layer "F.Fab")
			(effects
				(font
					(size 1.27 1.27)
				)
			)
		)
		(duplicate_pad_numbers_are_jumpers no)
		(fp_line
			(start -0.7874 0.4064)
			(end -0.7874 -0.4064)
			(stroke
				(width 0.1524)
				(type default)
			)
			(layer "F.SilkS")
		)
		(fp_line
			(start 0.7874 0.4064)
			(end -0.7874 0.4064)
			(stroke
				(width 0.1524)
				(type default)
			)
			(layer "F.SilkS")
		)
		(fp_line
			(start -0.7874 -0.4064)
			(end 0.7874 -0.4064)
			(stroke
				(width 0.1524)
				(type default)
			)
			(layer "F.SilkS")
		)
		(fp_line
			(start 0.7874 -0.4064)
			(end 0.7874 0.4064)
			(stroke
				(width 0.1524)
				(type default)
			)
			(layer "F.SilkS")
		)
		(fp_line
			(start -0.67945 0.3048)
			(end -0.67945 -0.305054)
			(stroke
				(width 0.1)
				(type default)
			)
			(layer "F.Fab")
		)
		(fp_line
			(start -0.12065 0.3048)
			(end -0.67945 0.3048)
			(stroke
				(width 0.1)
				(type default)
			)
			(layer "F.Fab")
		)
		(fp_line
			(start 0.120396 0.3048)
			(end 0.120396 0.2794)
			(stroke
				(width 0.1)
				(type default)
			)
			(layer "F.Fab")
		)
		(fp_line
			(start 0.67945 0.3048)
			(end 0.120396 0.3048)
			(stroke
				(width 0.1)
				(type default)
			)
			(layer "F.Fab")
		)
		(fp_line
			(start -0.12065 0.2794)
			(end -0.12065 0.3048)
			(stroke
				(width 0.1)
				(type default)
			)
			(layer "F.Fab")
		)
		(fp_line
			(start 0.120396 0.2794)
			(end -0.12065 0.2794)
			(stroke
				(width 0.1)
				(type default)
			)
			(layer "F.Fab")
		)
		(fp_line
			(start -0.12065 -0.2794)
			(end 0.12065 -0.2794)
			(stroke
				(width 0.1)
				(type default)
			)
			(layer "F.Fab")
		)
		(fp_line
			(start 0.12065 -0.2794)
			(end 0.12065 -0.3048)
			(stroke
				(width 0.1)
				(type default)
			)
			(layer "F.Fab")
		)
		(fp_line
			(start 0.12065 -0.3048)
			(end 0.67945 -0.3048)
			(stroke
				(width 0.1)
				(type default)
			)
			(layer "F.Fab")
		)
		(fp_line
			(start 0.67945 -0.3048)
			(end 0.67945 0.3048)
			(stroke
				(width 0.1)
				(type default)
			)
			(layer "F.Fab")
		)
		(fp_line
			(start -0.67945 -0.305054)
			(end -0.12065 -0.305054)
			(stroke
				(width 0.1)
				(type default)
			)
			(layer "F.Fab")
		)
		(fp_line
			(start -0.12065 -0.305054)
			(end -0.12065 -0.2794)
			(stroke
				(width 0.1)
				(type default)
			)
			(layer "F.Fab")
		)
		(pad "1" smd circle
			(at -0.40005 0 270)
			(size 0 0)
			(layers "F.Cu" "F.Mask" "F.Paste")
			(net "PECI_BMC_R")
		)
		(pad "2" smd circle
			(at 0.40005 0 270)
			(size 0 0)
			(layers "F.Cu" "F.Mask" "F.Paste")
			(net "GND")
		)
	)
	(footprint ""
		(layer "F.Cu")
		(at 427.176438 -181.53507 90)
		(property "Reference" "PC1273"
			(at 0 0 90)
			(layer "F.SilkS")
			(hide yes)
			(effects
				(font
					(size 1.27 1.27)
				)
			)
		)
		(property "Value" ""
			(at 0 0 90)
			(layer "F.Fab")
			(effects
				(font
					(size 1.27 1.27)
				)
			)
		)
		(duplicate_pad_numbers_are_jumpers no)
		(fp_line
			(start 1.524 -0.762)
			(end 1.524 0.762)
			(stroke
				(width 0.1524)
				(type default)
			)
			(layer "F.SilkS")
		)
		(fp_line
			(start -1.524 -0.762)
			(end 1.524 -0.762)
			(stroke
				(width 0.1524)
				(type default)
			)
			(layer "F.SilkS")
		)
		(fp_line
			(start 1.524 0.762)
			(end -1.524 0.762)
			(stroke
				(width 0.1524)
				(type default)
			)
			(layer "F.SilkS")
		)
		(fp_line
			(start -1.524 0.762)
			(end -1.524 -0.762)
			(stroke
				(width 0.1524)
				(type default)
			)
			(layer "F.SilkS")
		)
		(fp_line
			(start 1.1049 -0.724916)
			(end -1.1049 -0.724916)
			(stroke
				(width 0.1)
				(type default)
			)
			(layer "F.Fab")
		)
		(fp_line
			(start -1.1049 -0.724916)
			(end -1.1049 0.724916)
			(stroke
				(width 0.1)
				(type default)
			)
			(layer "F.Fab")
		)
		(fp_line
			(start 1.1049 0.724916)
			(end 1.1049 -0.724916)
			(stroke
				(width 0.1)
				(type default)
			)
			(layer "F.Fab")
		)
		(fp_line
			(start -1.1049 0.724916)
			(end 1.1049 0.724916)
			(stroke
				(width 0.1)
				(type default)
			)
			(layer "F.Fab")
		)
		(pad "1" smd rect
			(at -0.889 0 270)
			(size 1.016 1.27)
			(layers "F.Cu" "F.Mask" "F.Paste")
			(net "SW_P12V_PVCCINFAON_CPU0_FLT")
		)
		(pad "2" smd rect
			(at 0.889 0 270)
			(size 1.016 1.27)
			(layers "F.Cu" "F.Mask" "F.Paste")
			(net "GND")
		)
	)
	(footprint ""
		(layer "F.Cu")
		(at 172.36948 -424.398948)
		(property "Reference" "U195"
			(at -1.41478 -2.86639 0)
			(unlocked yes)
			(layer "F.SilkS")
			(effects
				(font
					(size 0.7874 0.5842)
					(thickness 0.1524)
				)
				(justify left)
			)
		)
		(property "Value" ""
			(at 0 0 0)
			(layer "F.Fab")
			(effects
				(font
					(size 1.27 1.27)
				)
			)
		)
		(duplicate_pad_numbers_are_jumpers no)
		(fp_line
			(start -1.3462 -1.100074)
			(end -0.670052 -1.100074)
			(stroke
				(width 0.1524)
				(type default)
			)
			(layer "F.SilkS")
		)
		(fp_line
			(start -1.3462 1.100074)
			(end -1.3462 -1.100074)
			(stroke
				(width 0.1524)
				(type default)
			)
			(layer "F.SilkS")
		)
		(fp_line
			(start -0.670052 -1.100074)
			(end 0 -0.381)
			(stroke
				(width 0.1524)
				(type default)
			)
			(layer "F.SilkS")
		)
		(fp_line
			(start 0 -0.381)
			(end 0.670052 -1.100074)
			(stroke
				(width 0.1524)
				(type default)
			)
			(layer "F.SilkS")
		)
		(fp_line
			(start 0.670052 -1.100074)
			(end 1.3462 -1.100074)
			(stroke
				(width 0.1524)
				(type default)
			)
			(layer "F.SilkS")
		)
		(fp_line
			(start 1.3462 -1.100074)
			(end 1.3462 1.100074)
			(stroke
				(width 0.1524)
				(type default)
			)
			(layer "F.SilkS")
		)
		(fp_line
			(start 1.3462 1.100074)
			(end -1.3462 1.100074)
			(stroke
				(width 0.1524)
				(type default)
			)
			(layer "F.SilkS")
		)
		(fp_poly
			(pts
				(xy -1.049274 -1.31826) (xy -1.430274 -2.08026) (xy -0.668274 -2.08026)
			)
			(stroke
				(width 0)
				(type default)
			)
			(fill yes)
			(layer "F.SilkS")
		)
		(fp_line
			(start -1.100074 -0.8001)
			(end -0.670052 -0.8001)
			(stroke
				(width 0.1)
				(type default)
			)
			(layer "F.Fab")
		)
		(fp_line
			(start -1.100074 0.8001)
			(end -1.100074 -0.8001)
			(stroke
				(width 0.1)
				(type default)
			)
			(layer "F.Fab")
		)
		(fp_line
			(start -0.670052 -1.100074)
			(end 0.670052 -1.100074)
			(stroke
				(width 0.1)
				(type default)
			)
			(layer "F.Fab")
		)
		(fp_line
			(start -0.670052 -0.8001)
			(end -0.670052 -1.100074)
			(stroke
				(width 0.1)
				(type default)
			)
			(layer "F.Fab")
		)
		(fp_line
			(start -0.670052 0.8001)
			(end -1.100074 0.8001)
			(stroke
				(width 0.1)
				(type default)
			)
			(layer "F.Fab")
		)
		(fp_line
			(start -0.670052 0.8001)
			(end -0.670052 -0.8001)
			(stroke
				(width 0.1)
				(type default)
			)
			(layer "F.Fab")
		)
		(fp_line
			(start -0.670052 1.100074)
			(end -0.670052 0.8001)
			(stroke
				(width 0.1)
				(type default)
			)
			(layer "F.Fab")
		)
		(fp_line
			(start 0.670052 -1.100074)
			(end 0.670052 -0.8001)
			(stroke
				(width 0.1)
				(type default)
			)
			(layer "F.Fab")
		)
		(fp_line
			(start 0.670052 -0.8001)
			(end 0.670052 0.8001)
			(stroke
				(width 0.1)
				(type default)
			)
			(layer "F.Fab")
		)
		(fp_line
			(start 0.670052 -0.8001)
			(end 1.100074 -0.8001)
			(stroke
				(width 0.1)
				(type default)
			)
			(layer "F.Fab")
		)
		(fp_line
			(start 0.670052 0.8001)
			(end 0.670052 1.100074)
			(stroke
				(width 0.1)
				(type default)
			)
			(layer "F.Fab")
		)
		(fp_line
			(start 0.670052 1.100074)
			(end -0.670052 1.100074)
			(stroke
				(width 0.1)
				(type default)
			)
			(layer "F.Fab")
		)
		(fp_line
			(start 1.100074 -0.8001)
			(end 1.100074 0.8001)
			(stroke
				(width 0.1)
				(type default)
			)
			(layer "F.Fab")
		)
		(fp_line
			(start 1.100074 0.8001)
			(end 0.670052 0.8001)
			(stroke
				(width 0.1)
				(type default)
			)
			(layer "F.Fab")
		)
		(fp_poly
			(pts
				(xy -1.524 -0.649986) (xy -2.286 -1.030986) (xy -2.286 -0.268986)
			)
			(stroke
				(width 0)
				(type default)
			)
			(fill yes)
			(layer "F.Fab")
		)
		(pad "1" smd rect
			(at -0.94996 -0.649986 270)
			(size 0.4064 0.508)
			(layers "F.Cu" "F.Mask" "F.Paste")
			(net "BMC_MONITER_R")
		)
		(pad "2" smd rect
			(at -0.94996 0 270)
			(size 0.4064 0.508)
			(layers "F.Cu" "F.Mask" "F.Paste")
			(net "GND")
		)
		(pad "3" smd rect
			(at -0.94996 0.649986 270)
			(size 0.4064 0.508)
			(layers "F.Cu" "F.Mask" "F.Paste")
			(net "RST_SWB_BIC_R_N")
		)
		(pad "4" smd rect
			(at 0.94996 0.649986 270)
			(size 0.4064 0.508)
			(layers "F.Cu" "F.Mask" "F.Paste")
			(net "RST_SWB_BIC_BUF_R_N")
		)
		(pad "5" smd rect
			(at 0.94996 0 270)
			(size 0.4064 0.508)
			(layers "F.Cu" "F.Mask" "F.Paste")
			(net "P3V3_AUX")
		)
		(pad "6" smd rect
			(at 0.94996 -0.649986 270)
			(size 0.4064 0.508)
			(layers "F.Cu" "F.Mask" "F.Paste")
			(net "BMC_MONITER_BUF_R")
		)
	)
	(footprint ""
		(layer "F.Cu")
		(at 460.092044 -76.57211 90)
		(property "Reference" "PC2262"
			(at 0 0 90)
			(layer "F.SilkS")
			(hide yes)
			(effects
				(font
					(size 1.27 1.27)
				)
			)
		)
		(property "Value" ""
			(at 0 0 90)
			(layer "F.Fab")
			(effects
				(font
					(size 1.27 1.27)
				)
			)
		)
		(duplicate_pad_numbers_are_jumpers no)
		(fp_line
			(start 1.524 -0.762)
			(end 1.524 0.762)
			(stroke
				(width 0.1524)
				(type default)
			)
			(layer "F.SilkS")
		)
		(fp_line
			(start -1.524 -0.762)
			(end 1.524 -0.762)
			(stroke
				(width 0.1524)
				(type default)
			)
			(layer "F.SilkS")
		)
		(fp_line
			(start 1.524 0.762)
			(end -1.524 0.762)
			(stroke
				(width 0.1524)
				(type default)
			)
			(layer "F.SilkS")
		)
		(fp_line
			(start -1.524 0.762)
			(end -1.524 -0.762)
			(stroke
				(width 0.1524)
				(type default)
			)
			(layer "F.SilkS")
		)
		(fp_line
			(start 1.1049 -0.724916)
			(end -1.1049 -0.724916)
			(stroke
				(width 0.1)
				(type default)
			)
			(layer "F.Fab")
		)
		(fp_line
			(start -1.1049 -0.724916)
			(end -1.1049 0.724916)
			(stroke
				(width 0.1)
				(type default)
			)
			(layer "F.Fab")
		)
		(fp_line
			(start 1.1049 0.724916)
			(end 1.1049 -0.724916)
			(stroke
				(width 0.1)
				(type default)
			)
			(layer "F.Fab")
		)
		(fp_line
			(start -1.1049 0.724916)
			(end 1.1049 0.724916)
			(stroke
				(width 0.1)
				(type default)
			)
			(layer "F.Fab")
		)
		(pad "1" smd rect
			(at -0.889 0 270)
			(size 1.016 1.27)
			(layers "F.Cu" "F.Mask" "F.Paste")
			(net "SW_P3V3_AUX_FLT")
		)
		(pad "2" smd rect
			(at 0.889 0 270)
			(size 1.016 1.27)
			(layers "F.Cu" "F.Mask" "F.Paste")
			(net "GND")
		)
	)
	(footprint ""
		(layer "F.Cu")
		(at 293.265098 -408.7749)
		(property "Reference" "U345"
			(at -0.37084 2.595372 0)
			(unlocked yes)
			(layer "F.SilkS")
			(effects
				(font
					(size 0.7874 0.5842)
					(thickness 0.1524)
				)
				(justify left)
			)
		)
		(property "Value" ""
			(at 0 0 0)
			(layer "F.Fab")
			(effects
				(font
					(size 1.27 1.27)
				)
			)
		)
		(duplicate_pad_numbers_are_jumpers no)
		(fp_line
			(start -1.448308 -1.549908)
			(end -0.774954 -1.549908)
			(stroke
				(width 0.1524)
				(type default)
			)
			(layer "F.SilkS")
		)
		(fp_line
			(start -1.448308 1.549908)
			(end -1.448308 -1.549908)
			(stroke
				(width 0.1524)
				(type default)
			)
			(layer "F.SilkS")
		)
		(fp_line
			(start -0.774954 -1.549908)
			(end 0 -0.533908)
			(stroke
				(width 0.1524)
				(type default)
			)
			(layer "F.SilkS")
		)
		(fp_line
			(start 0 -0.533908)
			(end 0.774954 -1.549908)
			(stroke
				(width 0.1524)
				(type default)
			)
			(layer "F.SilkS")
		)
		(fp_line
			(start 1.448308 -1.549908)
			(end 1.448308 1.549908)
			(stroke
				(width 0.1524)
				(type default)
			)
			(layer "F.SilkS")
		)
		(fp_line
			(start 1.448308 1.549908)
			(end -1.448308 1.549908)
			(stroke
				(width 0.1524)
				(type default)
			)
			(layer "F.SilkS")
		)
		(fp_rect
			(start -1.549908 -1.549908)
			(end -0.787908 -1.880108)
			(stroke
				(width 0)
				(type default)
			)
			(fill yes)
			(layer "F.SilkS")
		)
		(fp_line
			(start -1.549908 -1.549908)
			(end 1.549908 -1.549908)
			(stroke
				(width 0.1)
				(type default)
			)
			(layer "F.Fab")
		)
		(fp_line
			(start -1.549908 1.549908)
			(end -1.549908 -1.549908)
			(stroke
				(width 0.1)
				(type default)
			)
			(layer "F.Fab")
		)
		(fp_line
			(start 1.549908 -1.549908)
			(end 1.549908 1.549908)
			(stroke
				(width 0.1)
				(type default)
			)
			(layer "F.Fab")
		)
		(fp_line
			(start 1.549908 1.549908)
			(end -1.549908 1.549908)
			(stroke
				(width 0.1)
				(type default)
			)
			(layer "F.Fab")
		)
		(fp_rect
			(start -1.549908 -1.549908)
			(end -0.787908 -1.880108)
			(stroke
				(width 0)
				(type default)
			)
			(fill yes)
			(layer "F.Fab")
		)
		(pad "1" smd rect
			(at -2.350008 -0.975106 270)
			(size 0.4318 1.4986)
			(layers "F.Cu" "F.Mask" "F.Paste")
			(net "P3V3_AUX")
		)
		(pad "2" smd rect
			(at -2.350008 -0.32512 270)
			(size 0.4318 1.4986)
			(layers "F.Cu" "F.Mask" "F.Paste")
			(net "P12V_HSC_TEMP_D+")
		)
		(pad "3" smd rect
			(at -2.350008 0.32512 270)
			(size 0.4318 1.4986)
			(layers "F.Cu" "F.Mask" "F.Paste")
			(net "P12V_HSC_TEMP_D-")
		)
		(pad "4" smd rect
			(at -2.350008 0.975106 270)
			(size 0.4318 1.4986)
			(layers "F.Cu" "F.Mask" "F.Paste")
			(net "P12V_HSC_T_CRIT_N")
		)
		(pad "5" smd rect
			(at 2.350008 0.975106 270)
			(size 0.4318 1.4986)
			(layers "F.Cu" "F.Mask" "F.Paste")
			(net "GND")
		)
		(pad "6" smd rect
			(at 2.350008 0.32512 270)
			(size 0.4318 1.4986)
			(layers "F.Cu" "F.Mask" "F.Paste")
			(net "P12V_HSC_TEMP_ALERT_N")
		)
		(pad "7" smd rect
			(at 2.350008 -0.32512 270)
			(size 0.4318 1.4986)
			(layers "F.Cu" "F.Mask" "F.Paste")
			(net "P12V_HSC_TEMP_SDA")
		)
		(pad "8" smd rect
			(at 2.350008 -0.975106 270)
			(size 0.4318 1.4986)
			(layers "F.Cu" "F.Mask" "F.Paste")
			(net "P12V_HSC_TEMP_SCL")
		)
	)
	(footprint ""
		(layer "F.Cu")
		(at 220.087444 -98.164904 180)
		(property "Reference" "R2221"
			(at 0 0 180)
			(layer "F.SilkS")
			(hide yes)
			(effects
				(font
					(size 1.27 1.27)
				)
			)
		)
		(property "Value" ""
			(at 0 0 180)
			(layer "F.Fab")
			(effects
				(font
					(size 1.27 1.27)
				)
			)
		)
		(duplicate_pad_numbers_are_jumpers no)
		(fp_line
			(start 0.7874 0.4064)
			(end -0.7874 0.4064)
			(stroke
				(width 0.1524)
				(type default)
			)
			(layer "F.SilkS")
		)
		(fp_line
			(start 0.7874 -0.4064)
			(end 0.7874 0.4064)
			(stroke
				(width 0.1524)
				(type default)
			)
			(layer "F.SilkS")
		)
		(fp_line
			(start -0.7874 0.4064)
			(end -0.7874 -0.4064)
			(stroke
				(width 0.1524)
				(type default)
			)
			(layer "F.SilkS")
		)
		(fp_line
			(start -0.7874 -0.4064)
			(end 0.7874 -0.4064)
			(stroke
				(width 0.1524)
				(type default)
			)
			(layer "F.SilkS")
		)
		(fp_line
			(start 0.67945 0.3048)
			(end 0.120396 0.3048)
			(stroke
				(width 0.1)
				(type default)
			)
			(layer "F.Fab")
		)
		(fp_line
			(start 0.67945 -0.3048)
			(end 0.67945 0.3048)
			(stroke
				(width 0.1)
				(type default)
			)
			(layer "F.Fab")
		)
		(fp_line
			(start 0.12065 -0.2794)
			(end 0.12065 -0.3048)
			(stroke
				(width 0.1)
				(type default)
			)
			(layer "F.Fab")
		)
		(fp_line
			(start 0.12065 -0.3048)
			(end 0.67945 -0.3048)
			(stroke
				(width 0.1)
				(type default)
			)
			(layer "F.Fab")
		)
		(fp_line
			(start 0.120396 0.3048)
			(end 0.120396 0.2794)
			(stroke
				(width 0.1)
				(type default)
			)
			(layer "F.Fab")
		)
		(fp_line
			(start 0.120396 0.2794)
			(end -0.12065 0.2794)
			(stroke
				(width 0.1)
				(type default)
			)
			(layer "F.Fab")
		)
		(fp_line
			(start -0.12065 0.3048)
			(end -0.67945 0.3048)
			(stroke
				(width 0.1)
				(type default)
			)
			(layer "F.Fab")
		)
		(fp_line
			(start -0.12065 0.2794)
			(end -0.12065 0.3048)
			(stroke
				(width 0.1)
				(type default)
			)
			(layer "F.Fab")
		)
		(fp_line
			(start -0.12065 -0.2794)
			(end 0.12065 -0.2794)
			(stroke
				(width 0.1)
				(type default)
			)
			(layer "F.Fab")
		)
		(fp_line
			(start -0.12065 -0.305054)
			(end -0.12065 -0.2794)
			(stroke
				(width 0.1)
				(type default)
			)
			(layer "F.Fab")
		)
		(fp_line
			(start -0.67945 0.3048)
			(end -0.67945 -0.305054)
			(stroke
				(width 0.1)
				(type default)
			)
			(layer "F.Fab")
		)
		(fp_line
			(start -0.67945 -0.305054)
			(end -0.12065 -0.305054)
			(stroke
				(width 0.1)
				(type default)
			)
			(layer "F.Fab")
		)
		(pad "1" smd circle
			(at -0.40005 0 180)
			(size 0 0)
			(layers "F.Cu" "F.Mask" "F.Paste")
			(net "P12V_AUX")
		)
		(pad "2" smd circle
			(at 0.40005 0 180)
			(size 0 0)
			(layers "F.Cu" "F.Mask" "F.Paste")
			(net "A_P12V_STBY_FP_TRIGGER")
		)
	)
	(footprint ""
		(layer "F.Cu")
		(at 366.48263 -238.162338 90)
		(property "Reference" "C412"
			(at 0 0 90)
			(layer "F.SilkS")
			(hide yes)
			(effects
				(font
					(size 1.27 1.27)
				)
			)
		)
		(property "Value" ""
			(at 0 0 90)
			(layer "F.Fab")
			(effects
				(font
					(size 1.27 1.27)
				)
			)
		)
		(duplicate_pad_numbers_are_jumpers no)
		(fp_line
			(start 0.7874 -0.4064)
			(end 0.7874 0.4064)
			(stroke
				(width 0.1524)
				(type default)
			)
			(layer "F.SilkS")
		)
		(fp_line
			(start -0.7874 -0.4064)
			(end 0.7874 -0.4064)
			(stroke
				(width 0.1524)
				(type default)
			)
			(layer "F.SilkS")
		)
		(fp_line
			(start 0.7874 0.4064)
			(end -0.7874 0.4064)
			(stroke
				(width 0.1524)
				(type default)
			)
			(layer "F.SilkS")
		)
		(fp_line
			(start -0.7874 0.4064)
			(end -0.7874 -0.4064)
			(stroke
				(width 0.1524)
				(type default)
			)
			(layer "F.SilkS")
		)
		(fp_line
			(start -0.12065 -0.305054)
			(end -0.12065 -0.2794)
			(stroke
				(width 0.1)
				(type default)
			)
			(layer "F.Fab")
		)
		(fp_line
			(start -0.67945 -0.305054)
			(end -0.12065 -0.305054)
			(stroke
				(width 0.1)
				(type default)
			)
			(layer "F.Fab")
		)
		(fp_line
			(start 0.67945 -0.3048)
			(end 0.67945 0.3048)
			(stroke
				(width 0.1)
				(type default)
			)
			(layer "F.Fab")
		)
		(fp_line
			(start 0.12065 -0.3048)
			(end 0.67945 -0.3048)
			(stroke
				(width 0.1)
				(type default)
			)
			(layer "F.Fab")
		)
		(fp_line
			(start 0.12065 -0.2794)
			(end 0.12065 -0.3048)
			(stroke
				(width 0.1)
				(type default)
			)
			(layer "F.Fab")
		)
		(fp_line
			(start -0.12065 -0.2794)
			(end 0.12065 -0.2794)
			(stroke
				(width 0.1)
				(type default)
			)
			(layer "F.Fab")
		)
		(fp_line
			(start 0.120396 0.2794)
			(end -0.12065 0.2794)
			(stroke
				(width 0.1)
				(type default)
			)
			(layer "F.Fab")
		)
		(fp_line
			(start -0.12065 0.2794)
			(end -0.12065 0.3048)
			(stroke
				(width 0.1)
				(type default)
			)
			(layer "F.Fab")
		)
		(fp_line
			(start 0.67945 0.3048)
			(end 0.120396 0.3048)
			(stroke
				(width 0.1)
				(type default)
			)
			(layer "F.Fab")
		)
		(fp_line
			(start 0.120396 0.3048)
			(end 0.120396 0.2794)
			(stroke
				(width 0.1)
				(type default)
			)
			(layer "F.Fab")
		)
		(fp_line
			(start -0.12065 0.3048)
			(end -0.67945 0.3048)
			(stroke
				(width 0.1)
				(type default)
			)
			(layer "F.Fab")
		)
		(fp_line
			(start -0.67945 0.3048)
			(end -0.67945 -0.305054)
			(stroke
				(width 0.1)
				(type default)
			)
			(layer "F.Fab")
		)
		(pad "1" smd circle
			(at -0.40005 0 90)
			(size 0 0)
			(layers "F.Cu" "F.Mask" "F.Paste")
			(net "PVCCINFAON_CPU0")
		)
		(pad "2" smd circle
			(at 0.40005 0 90)
			(size 0 0)
			(layers "F.Cu" "F.Mask" "F.Paste")
			(net "GND")
		)
	)
	(footprint ""
		(layer "F.Cu")
		(at 430.600104 -130.329178 180)
		(property "Reference" "R2391"
			(at 0 0 180)
			(layer "F.SilkS")
			(hide yes)
			(effects
				(font
					(size 1.27 1.27)
				)
			)
		)
		(property "Value" ""
			(at 0 0 180)
			(layer "F.Fab")
			(effects
				(font
					(size 1.27 1.27)
				)
			)
		)
		(duplicate_pad_numbers_are_jumpers no)
		(fp_line
			(start 0.7874 0.4064)
			(end -0.7874 0.4064)
			(stroke
				(width 0.1524)
				(type default)
			)
			(layer "F.SilkS")
		)
		(fp_line
			(start 0.7874 -0.4064)
			(end 0.7874 0.4064)
			(stroke
				(width 0.1524)
				(type default)
			)
			(layer "F.SilkS")
		)
		(fp_line
			(start -0.7874 0.4064)
			(end -0.7874 -0.4064)
			(stroke
				(width 0.1524)
				(type default)
			)
			(layer "F.SilkS")
		)
		(fp_line
			(start -0.7874 -0.4064)
			(end 0.7874 -0.4064)
			(stroke
				(width 0.1524)
				(type default)
			)
			(layer "F.SilkS")
		)
		(fp_line
			(start 0.67945 0.3048)
			(end 0.120396 0.3048)
			(stroke
				(width 0.1)
				(type default)
			)
			(layer "F.Fab")
		)
		(fp_line
			(start 0.67945 -0.3048)
			(end 0.67945 0.3048)
			(stroke
				(width 0.1)
				(type default)
			)
			(layer "F.Fab")
		)
		(fp_line
			(start 0.12065 -0.2794)
			(end 0.12065 -0.3048)
			(stroke
				(width 0.1)
				(type default)
			)
			(layer "F.Fab")
		)
		(fp_line
			(start 0.12065 -0.3048)
			(end 0.67945 -0.3048)
			(stroke
				(width 0.1)
				(type default)
			)
			(layer "F.Fab")
		)
		(fp_line
			(start 0.120396 0.3048)
			(end 0.120396 0.2794)
			(stroke
				(width 0.1)
				(type default)
			)
			(layer "F.Fab")
		)
		(fp_line
			(start 0.120396 0.2794)
			(end -0.12065 0.2794)
			(stroke
				(width 0.1)
				(type default)
			)
			(layer "F.Fab")
		)
		(fp_line
			(start -0.12065 0.3048)
			(end -0.67945 0.3048)
			(stroke
				(width 0.1)
				(type default)
			)
			(layer "F.Fab")
		)
		(fp_line
			(start -0.12065 0.2794)
			(end -0.12065 0.3048)
			(stroke
				(width 0.1)
				(type default)
			)
			(layer "F.Fab")
		)
		(fp_line
			(start -0.12065 -0.2794)
			(end 0.12065 -0.2794)
			(stroke
				(width 0.1)
				(type default)
			)
			(layer "F.Fab")
		)
		(fp_line
			(start -0.12065 -0.305054)
			(end -0.12065 -0.2794)
			(stroke
				(width 0.1)
				(type default)
			)
			(layer "F.Fab")
		)
		(fp_line
			(start -0.67945 0.3048)
			(end -0.67945 -0.305054)
			(stroke
				(width 0.1)
				(type default)
			)
			(layer "F.Fab")
		)
		(fp_line
			(start -0.67945 -0.305054)
			(end -0.12065 -0.305054)
			(stroke
				(width 0.1)
				(type default)
			)
			(layer "F.Fab")
		)
		(pad "1" smd circle
			(at -0.40005 0 180)
			(size 0 0)
			(layers "F.Cu" "F.Mask" "F.Paste")
			(net "SMB_VR_3V3AUX_SDA_R2")
		)
		(pad "2" smd circle
			(at 0.40005 0 180)
			(size 0 0)
			(layers "F.Cu" "F.Mask" "F.Paste")
			(net "SMB_DIO_PVCCINFAON_CPU0")
		)
	)
	(footprint ""
		(layer "F.Cu")
		(at 370.021358 -107.333034 90)
		(property "Reference" "R1832"
			(at 0 0 90)
			(layer "F.SilkS")
			(hide yes)
			(effects
				(font
					(size 1.27 1.27)
				)
			)
		)
		(property "Value" ""
			(at 0 0 90)
			(layer "F.Fab")
			(effects
				(font
					(size 1.27 1.27)
				)
			)
		)
		(duplicate_pad_numbers_are_jumpers no)
		(fp_line
			(start 0.7874 -0.4064)
			(end 0.7874 0.4064)
			(stroke
				(width 0.1524)
				(type default)
			)
			(layer "F.SilkS")
		)
		(fp_line
			(start -0.7874 -0.4064)
			(end 0.7874 -0.4064)
			(stroke
				(width 0.1524)
				(type default)
			)
			(layer "F.SilkS")
		)
		(fp_line
			(start 0.7874 0.4064)
			(end -0.7874 0.4064)
			(stroke
				(width 0.1524)
				(type default)
			)
			(layer "F.SilkS")
		)
		(fp_line
			(start -0.7874 0.4064)
			(end -0.7874 -0.4064)
			(stroke
				(width 0.1524)
				(type default)
			)
			(layer "F.SilkS")
		)
		(fp_line
			(start -0.12065 -0.305054)
			(end -0.12065 -0.2794)
			(stroke
				(width 0.1)
				(type default)
			)
			(layer "F.Fab")
		)
		(fp_line
			(start -0.67945 -0.305054)
			(end -0.12065 -0.305054)
			(stroke
				(width 0.1)
				(type default)
			)
			(layer "F.Fab")
		)
		(fp_line
			(start 0.67945 -0.3048)
			(end 0.67945 0.3048)
			(stroke
				(width 0.1)
				(type default)
			)
			(layer "F.Fab")
		)
		(fp_line
			(start 0.12065 -0.3048)
			(end 0.67945 -0.3048)
			(stroke
				(width 0.1)
				(type default)
			)
			(layer "F.Fab")
		)
		(fp_line
			(start 0.12065 -0.2794)
			(end 0.12065 -0.3048)
			(stroke
				(width 0.1)
				(type default)
			)
			(layer "F.Fab")
		)
		(fp_line
			(start -0.12065 -0.2794)
			(end 0.12065 -0.2794)
			(stroke
				(width 0.1)
				(type default)
			)
			(layer "F.Fab")
		)
		(fp_line
			(start 0.120396 0.2794)
			(end -0.12065 0.2794)
			(stroke
				(width 0.1)
				(type default)
			)
			(layer "F.Fab")
		)
		(fp_line
			(start -0.12065 0.2794)
			(end -0.12065 0.3048)
			(stroke
				(width 0.1)
				(type default)
			)
			(layer "F.Fab")
		)
		(fp_line
			(start 0.67945 0.3048)
			(end 0.120396 0.3048)
			(stroke
				(width 0.1)
				(type default)
			)
			(layer "F.Fab")
		)
		(fp_line
			(start 0.120396 0.3048)
			(end 0.120396 0.2794)
			(stroke
				(width 0.1)
				(type default)
			)
			(layer "F.Fab")
		)
		(fp_line
			(start -0.12065 0.3048)
			(end -0.67945 0.3048)
			(stroke
				(width 0.1)
				(type default)
			)
			(layer "F.Fab")
		)
		(fp_line
			(start -0.67945 0.3048)
			(end -0.67945 -0.305054)
			(stroke
				(width 0.1)
				(type default)
			)
			(layer "F.Fab")
		)
		(pad "1" smd circle
			(at -0.40005 0 90)
			(size 0 0)
			(layers "F.Cu" "F.Mask" "F.Paste")
			(net "JTAG_BMC_DBP_PREQ_N")
		)
		(pad "2" smd circle
			(at 0.40005 0 90)
			(size 0 0)
			(layers "F.Cu" "F.Mask" "F.Paste")
			(net "JTAG_DBP_BMC_PREQ_R_N")
		)
	)
	(footprint ""
		(layer "F.Cu")
		(at 328.647044 -342.976962)
		(property "Reference" "PU7_P0_7"
			(at -10.682224 -1.070356 0)
			(unlocked yes)
			(layer "F.SilkS")
			(effects
				(font
					(size 0.7874 0.5842)
					(thickness 0.1524)
				)
				(justify left)
			)
		)
		(property "Value" ""
			(at 0 0 0)
			(layer "F.Fab")
			(effects
				(font
					(size 1.27 1.27)
				)
			)
		)
		(duplicate_pad_numbers_are_jumpers no)
		(fp_line
			(start -2.500122 -2.999994)
			(end -2.24409 -2.999994)
			(stroke
				(width 0.1524)
				(type default)
			)
			(layer "F.SilkS")
		)
		(fp_line
			(start -2.500122 -2.529078)
			(end -2.500122 -2.999994)
			(stroke
				(width 0.1524)
				(type default)
			)
			(layer "F.SilkS")
		)
		(fp_line
			(start -2.500122 0.6604)
			(end -2.500122 0.229108)
			(stroke
				(width 0.1524)
				(type default)
			)
			(layer "F.SilkS")
		)
		(fp_line
			(start -2.500122 2.999994)
			(end -2.500122 2.339594)
			(stroke
				(width 0.1524)
				(type default)
			)
			(layer "F.SilkS")
		)
		(fp_line
			(start -2.2987 2.999994)
			(end -2.500122 2.999994)
			(stroke
				(width 0.1524)
				(type default)
			)
			(layer "F.SilkS")
		)
		(fp_line
			(start 2.31394 -2.999994)
			(end 2.500122 -2.999994)
			(stroke
				(width 0.1524)
				(type default)
			)
			(layer "F.SilkS")
		)
		(fp_line
			(start 2.500122 -2.999994)
			(end 2.500122 -2.44348)
			(stroke
				(width 0.1524)
				(type default)
			)
			(layer "F.SilkS")
		)
		(fp_line
			(start 2.500122 2.339594)
			(end 2.500122 2.999994)
			(stroke
				(width 0.1524)
				(type default)
			)
			(layer "F.SilkS")
		)
		(fp_line
			(start 2.500122 2.999994)
			(end 2.2987 2.999994)
			(stroke
				(width 0.1524)
				(type default)
			)
			(layer "F.SilkS")
		)
		(fp_poly
			(pts
				(xy -2.176272 -3.637534) (xy -2.684272 -2.621534) (xy -3.192272 -3.637534)
			)
			(stroke
				(width 0)
				(type default)
			)
			(fill yes)
			(layer "F.SilkS")
		)
		(fp_line
			(start -2.500122 -2.999994)
			(end 2.500122 -2.999994)
			(stroke
				(width 0.1)
				(type default)
			)
			(layer "F.Fab")
		)
		(fp_line
			(start -2.500122 2.999994)
			(end -2.500122 -2.999994)
			(stroke
				(width 0.1)
				(type default)
			)
			(layer "F.Fab")
		)
		(fp_line
			(start 2.500122 -2.999994)
			(end 2.500122 2.999994)
			(stroke
				(width 0.1)
				(type default)
			)
			(layer "F.Fab")
		)
		(fp_line
			(start 2.500122 2.999994)
			(end -2.500122 2.999994)
			(stroke
				(width 0.1)
				(type default)
			)
			(layer "F.Fab")
		)
		(fp_poly
			(pts
				(xy -4.218432 -2.783078) (xy -4.218432 -1.767078) (xy -3.202432 -2.275078)
			)
			(stroke
				(width 0)
				(type default)
			)
			(fill yes)
			(layer "F.Fab")
		)
		(pad "1" smd rect
			(at -2.400046 -2.275078 90)
			(size 0.2286 0.6096)
			(layers "F.Cu" "F.Mask" "F.Paste")
			(net "PVCCIN_CPU0_VOS7")
		)
		(pad "2" smd rect
			(at -2.400046 -1.82499 90)
			(size 0.2286 0.6096)
			(layers "F.Cu" "F.Mask" "F.Paste")
			(net "GND")
		)
		(pad "3" smd rect
			(at -2.400046 -1.374902 90)
			(size 0.2286 0.6096)
			(layers "F.Cu" "F.Mask" "F.Paste")
			(net "PVCCIN_CPU0_VDD7")
		)
		(pad "4" smd rect
			(at -2.400046 -0.925068 90)
			(size 0.2286 0.6096)
			(layers "F.Cu" "F.Mask" "F.Paste")
			(net "PVCCIN_CPU0_PVCC")
		)
		(pad "5" smd rect
			(at -2.400046 -0.47498 90)
			(size 0.2286 0.6096)
			(layers "F.Cu" "F.Mask" "F.Paste")
			(net "GND")
		)
		(pad "6" smd rect
			(at -2.400046 -0.024892 90)
			(size 0.2286 0.6096)
			(layers "F.Cu" "F.Mask" "F.Paste")
			(net "Net_8562")
		)
		(pad "7_9-20_24" smd circle
			(at 0 1.150112 90)
			(size 0 0)
			(layers "F.Cu" "F.Mask" "F.Paste")
			(net "GND")
		)
		(pad "10_19" smd rect
			(at 0 2.899918 90)
			(size 0.6096 4.318)
			(layers "F.Cu" "F.Mask" "F.Paste")
			(net "SW_PVCCIN_CPU0_SW7")
		)
		(pad "25_29" smd rect
			(at 1.549908 -1.279906 270)
			(size 2.0574 2.3114)
			(layers "F.Cu" "F.Mask" "F.Paste")
			(net "SW_P12V_PVCCIN_CPU0_FLT")
		)
		(pad "30" smd rect
			(at 2.05994 -2.899918)
			(size 0.2286 0.6096)
			(layers "F.Cu" "F.Mask" "F.Paste")
			(net "SW_P12V_PVCCIN_CPU0_FLT")
		)
		(pad "31" smd rect
			(at 1.610106 -2.899918)
			(size 0.2286 0.6096)
			(layers "F.Cu" "F.Mask" "F.Paste")
			(net "Net_8563")
		)
		(pad "32" smd rect
			(at 1.160018 -2.899918)
			(size 0.2286 0.6096)
			(layers "F.Cu" "F.Mask" "F.Paste")
			(net "SW_PVCCIN_CPU0_BOOTR7")
		)
		(pad "33" smd rect
			(at 0.70993 -2.899918)
			(size 0.2286 0.6096)
			(layers "F.Cu" "F.Mask" "F.Paste")
			(net "SW_PVCCIN_CPU0_BOOT7")
		)
		(pad "34" smd rect
			(at 0.260096 -2.899918)
			(size 0.2286 0.6096)
			(layers "F.Cu" "F.Mask" "F.Paste")
			(net "PVCCIN_CPU0_PWM7")
		)
		(pad "35" smd rect
			(at -0.189992 -2.899918)
			(size 0.2286 0.6096)
			(layers "F.Cu" "F.Mask" "F.Paste")
			(net "PVCCIN_CPU0_VDD7")
		)
		(pad "36" smd rect
			(at -0.64008 -2.899918)
			(size 0.2286 0.6096)
			(layers "F.Cu" "F.Mask" "F.Paste")
			(net "PVCCIN_CPU0_ATSEN")
		)
		(pad "37" smd rect
			(at -1.089914 -2.899918)
			(size 0.2286 0.6096)
			(layers "F.Cu" "F.Mask" "F.Paste")
			(net "PVCCIN_CPU0_LSET7")
		)
		(pad "38" smd rect
			(at -1.540002 -2.899918)
			(size 0.2286 0.6096)
			(layers "F.Cu" "F.Mask" "F.Paste")
			(net "PVCCIN_CPU0_IMON7")
		)
		(pad "39" smd rect
			(at -1.99009 -2.899918)
			(size 0.2286 0.6096)
			(layers "F.Cu" "F.Mask" "F.Paste")
			(net "PVCCIN_CPU0_VREF")
		)
		(pad "40" smd rect
			(at -0.87503 -1.27508)
			(size 1.7526 1.9558)
			(layers "F.Cu" "F.Mask" "F.Paste")
			(net "GND")
		)
		(pad "41" smd rect
			(at -1.525016 0.249936 270)
			(size 0.3048 0.4572)
			(layers "F.Cu" "F.Mask" "F.Paste")
			(net "Net_8561")
		)
		(zone
			(layer "F.Cu")
			(hatch none 0.5)
			(connect_pads
				(clearance 0)
			)
			(min_thickness 0.25)
			(keepout
				(tracks not_allowed)
				(vias allowed)
				(pads allowed)
				(copperpour not_allowed)
				(footprints allowed)
			)
			(placement
				(enabled no)
				(sheetname "")
			)
			(fill
				(thermal_gap 0.5)
				(thermal_bridge_width 0.5)
				(island_removal_mode 0)
			)
			(polygon
				(pts
					(xy 326.602598 -344.658188) (xy 326.844914 -344.658188) (xy 326.844914 -343.624408) (xy 326.602598 -343.624408)
				)
			)
		)
		(zone
			(layer "F.Cu")
			(hatch none 0.5)
			(connect_pads
				(clearance 0)
			)
			(min_thickness 0.25)
			(keepout
				(tracks not_allowed)
				(vias allowed)
				(pads allowed)
				(copperpour not_allowed)
				(footprints allowed)
			)
			(placement
				(enabled no)
				(sheetname "")
			)
			(fill
				(thermal_gap 0.5)
				(thermal_bridge_width 0.5)
				(island_removal_mode 0)
			)
			(polygon
				(pts
					(xy 326.146922 -339.976968) (xy 326.146922 -340.655148) (xy 331.10678 -340.655148) (xy 331.10678 -339.976968)
					(xy 330.856844 -339.976968) (xy 330.856844 -340.432644) (xy 326.437244 -340.432644) (xy 326.437244 -339.976968)
				)
			)
		)
	)
	(footprint ""
		(layer "F.Cu")
		(at 193.089022 -24.091392 -90)
		(property "Reference" "R4015"
			(at 0 0 270)
			(layer "F.SilkS")
			(hide yes)
			(effects
				(font
					(size 1.27 1.27)
				)
			)
		)
		(property "Value" ""
			(at 0 0 270)
			(layer "F.Fab")
			(effects
				(font
					(size 1.27 1.27)
				)
			)
		)
		(duplicate_pad_numbers_are_jumpers no)
		(fp_line
			(start -0.7874 0.4064)
			(end -0.7874 -0.4064)
			(stroke
				(width 0.1524)
				(type default)
			)
			(layer "F.SilkS")
		)
		(fp_line
			(start 0.7874 0.4064)
			(end -0.7874 0.4064)
			(stroke
				(width 0.1524)
				(type default)
			)
			(layer "F.SilkS")
		)
		(fp_line
			(start -0.7874 -0.4064)
			(end 0.7874 -0.4064)
			(stroke
				(width 0.1524)
				(type default)
			)
			(layer "F.SilkS")
		)
		(fp_line
			(start 0.7874 -0.4064)
			(end 0.7874 0.4064)
			(stroke
				(width 0.1524)
				(type default)
			)
			(layer "F.SilkS")
		)
		(fp_line
			(start -0.67945 0.3048)
			(end -0.67945 -0.305054)
			(stroke
				(width 0.1)
				(type default)
			)
			(layer "F.Fab")
		)
		(fp_line
			(start -0.12065 0.3048)
			(end -0.67945 0.3048)
			(stroke
				(width 0.1)
				(type default)
			)
			(layer "F.Fab")
		)
		(fp_line
			(start 0.120396 0.3048)
			(end 0.120396 0.2794)
			(stroke
				(width 0.1)
				(type default)
			)
			(layer "F.Fab")
		)
		(fp_line
			(start 0.67945 0.3048)
			(end 0.120396 0.3048)
			(stroke
				(width 0.1)
				(type default)
			)
			(layer "F.Fab")
		)
		(fp_line
			(start -0.12065 0.2794)
			(end -0.12065 0.3048)
			(stroke
				(width 0.1)
				(type default)
			)
			(layer "F.Fab")
		)
		(fp_line
			(start 0.120396 0.2794)
			(end -0.12065 0.2794)
			(stroke
				(width 0.1)
				(type default)
			)
			(layer "F.Fab")
		)
		(fp_line
			(start -0.12065 -0.2794)
			(end 0.12065 -0.2794)
			(stroke
				(width 0.1)
				(type default)
			)
			(layer "F.Fab")
		)
		(fp_line
			(start 0.12065 -0.2794)
			(end 0.12065 -0.3048)
			(stroke
				(width 0.1)
				(type default)
			)
			(layer "F.Fab")
		)
		(fp_line
			(start 0.12065 -0.3048)
			(end 0.67945 -0.3048)
			(stroke
				(width 0.1)
				(type default)
			)
			(layer "F.Fab")
		)
		(fp_line
			(start 0.67945 -0.3048)
			(end 0.67945 0.3048)
			(stroke
				(width 0.1)
				(type default)
			)
			(layer "F.Fab")
		)
		(fp_line
			(start -0.67945 -0.305054)
			(end -0.12065 -0.305054)
			(stroke
				(width 0.1)
				(type default)
			)
			(layer "F.Fab")
		)
		(fp_line
			(start -0.12065 -0.305054)
			(end -0.12065 -0.2794)
			(stroke
				(width 0.1)
				(type default)
			)
			(layer "F.Fab")
		)
		(pad "1" smd circle
			(at -0.40005 0 270)
			(size 0 0)
			(layers "F.Cu" "F.Mask" "F.Paste")
			(net "P3V3_AUX")
		)
		(pad "2" smd circle
			(at 0.40005 0 270)
			(size 0 0)
			(layers "F.Cu" "F.Mask" "F.Paste")
			(net "HP_LVC3_SCM_HSC_PWRGD")
		)
	)
	(footprint ""
		(layer "F.Cu")
		(at 337.650328 -402.371052 -90)
		(property "Reference" "C1557"
			(at 0 0 270)
			(layer "F.SilkS")
			(hide yes)
			(effects
				(font
					(size 1.27 1.27)
				)
			)
		)
		(property "Value" ""
			(at 0 0 270)
			(layer "F.Fab")
			(effects
				(font
					(size 1.27 1.27)
				)
			)
		)
		(duplicate_pad_numbers_are_jumpers no)
		(fp_line
			(start -0.299974 0.150114)
			(end -0.299974 -0.150114)
			(stroke
				(width 0.1)
				(type default)
			)
			(layer "F.Fab")
		)
		(fp_line
			(start 0.299974 0.150114)
			(end -0.299974 0.150114)
			(stroke
				(width 0.1)
				(type default)
			)
			(layer "F.Fab")
		)
		(fp_line
			(start -0.299974 -0.150114)
			(end 0.299974 -0.150114)
			(stroke
				(width 0.1)
				(type default)
			)
			(layer "F.Fab")
		)
		(fp_line
			(start 0.299974 -0.150114)
			(end 0.299974 0.150114)
			(stroke
				(width 0.1)
				(type default)
			)
			(layer "F.Fab")
		)
		(pad "1" smd rect
			(at -0.2667 0 270)
			(size 0.3048 0.381)
			(layers "F.Cu" "F.Mask" "F.Paste")
			(net "P5E_CPU0_PE4_TX_C_DP<11>")
		)
		(pad "2" smd rect
			(at 0.2667 0 270)
			(size 0.3048 0.381)
			(layers "F.Cu" "F.Mask" "F.Paste")
			(net "P5E_CPU0_PE4_TX_DP<11>")
		)
	)
	(footprint ""
		(layer "F.Cu")
		(at 72.766174 -65.082674 -90)
		(property "Reference" "R3081"
			(at 0 0 270)
			(layer "F.SilkS")
			(hide yes)
			(effects
				(font
					(size 1.27 1.27)
				)
			)
		)
		(property "Value" ""
			(at 0 0 270)
			(layer "F.Fab")
			(effects
				(font
					(size 1.27 1.27)
				)
			)
		)
		(duplicate_pad_numbers_are_jumpers no)
		(fp_line
			(start -0.7874 0.4064)
			(end -0.7874 -0.4064)
			(stroke
				(width 0.1524)
				(type default)
			)
			(layer "F.SilkS")
		)
		(fp_line
			(start 0.7874 0.4064)
			(end -0.7874 0.4064)
			(stroke
				(width 0.1524)
				(type default)
			)
			(layer "F.SilkS")
		)
		(fp_line
			(start -0.7874 -0.4064)
			(end 0.7874 -0.4064)
			(stroke
				(width 0.1524)
				(type default)
			)
			(layer "F.SilkS")
		)
		(fp_line
			(start 0.7874 -0.4064)
			(end 0.7874 0.4064)
			(stroke
				(width 0.1524)
				(type default)
			)
			(layer "F.SilkS")
		)
		(fp_line
			(start -0.67945 0.3048)
			(end -0.67945 -0.305054)
			(stroke
				(width 0.1)
				(type default)
			)
			(layer "F.Fab")
		)
		(fp_line
			(start -0.12065 0.3048)
			(end -0.67945 0.3048)
			(stroke
				(width 0.1)
				(type default)
			)
			(layer "F.Fab")
		)
		(fp_line
			(start 0.120396 0.3048)
			(end 0.120396 0.2794)
			(stroke
				(width 0.1)
				(type default)
			)
			(layer "F.Fab")
		)
		(fp_line
			(start 0.67945 0.3048)
			(end 0.120396 0.3048)
			(stroke
				(width 0.1)
				(type default)
			)
			(layer "F.Fab")
		)
		(fp_line
			(start -0.12065 0.2794)
			(end -0.12065 0.3048)
			(stroke
				(width 0.1)
				(type default)
			)
			(layer "F.Fab")
		)
		(fp_line
			(start 0.120396 0.2794)
			(end -0.12065 0.2794)
			(stroke
				(width 0.1)
				(type default)
			)
			(layer "F.Fab")
		)
		(fp_line
			(start -0.12065 -0.2794)
			(end 0.12065 -0.2794)
			(stroke
				(width 0.1)
				(type default)
			)
			(layer "F.Fab")
		)
		(fp_line
			(start 0.12065 -0.2794)
			(end 0.12065 -0.3048)
			(stroke
				(width 0.1)
				(type default)
			)
			(layer "F.Fab")
		)
		(fp_line
			(start 0.12065 -0.3048)
			(end 0.67945 -0.3048)
			(stroke
				(width 0.1)
				(type default)
			)
			(layer "F.Fab")
		)
		(fp_line
			(start 0.67945 -0.3048)
			(end 0.67945 0.3048)
			(stroke
				(width 0.1)
				(type default)
			)
			(layer "F.Fab")
		)
		(fp_line
			(start -0.67945 -0.305054)
			(end -0.12065 -0.305054)
			(stroke
				(width 0.1)
				(type default)
			)
			(layer "F.Fab")
		)
		(fp_line
			(start -0.12065 -0.305054)
			(end -0.12065 -0.2794)
			(stroke
				(width 0.1)
				(type default)
			)
			(layer "F.Fab")
		)
		(pad "1" smd circle
			(at -0.40005 0 270)
			(size 0 0)
			(layers "F.Cu" "F.Mask" "F.Paste")
			(net "LED_RST_PLD_CPU0_DRAM_GH_N")
		)
		(pad "2" smd circle
			(at 0.40005 0 270)
			(size 0 0)
			(layers "F.Cu" "F.Mask" "F.Paste")
			(net "P3V3_AUX")
		)
	)
	(footprint ""
		(layer "F.Cu")
		(at 96.983296 -70.78599)
		(property "Reference" "D86"
			(at -48.854106 50.178462 90)
			(unlocked yes)
			(layer "F.SilkS")
			(effects
				(font
					(size 0.635 0.4064)
					(thickness 0.1524)
				)
				(justify left)
			)
		)
		(property "Value" ""
			(at 0 0 0)
			(layer "F.Fab")
			(effects
				(font
					(size 1.27 1.27)
				)
			)
		)
		(duplicate_pad_numbers_are_jumpers no)
		(fp_line
			(start -0.90678 0.4826)
			(end -0.90678 -0.4699)
			(stroke
				(width 0.1524)
				(type default)
			)
			(layer "F.SilkS")
		)
		(fp_line
			(start -0.89408 -0.4826)
			(end 0.90678 -0.4826)
			(stroke
				(width 0.1524)
				(type default)
			)
			(layer "F.SilkS")
		)
		(fp_line
			(start -0.79248 -0.4826)
			(end 1.03378 -0.4826)
			(stroke
				(width 0.1524)
				(type default)
			)
			(layer "F.SilkS")
		)
		(fp_line
			(start -0.64008 -0.4826)
			(end 1.16078 -0.4826)
			(stroke
				(width 0.1524)
				(type default)
			)
			(layer "F.SilkS")
		)
		(fp_line
			(start 0.90678 -0.4826)
			(end 0.90678 0.4826)
			(stroke
				(width 0.1524)
				(type default)
			)
			(layer "F.SilkS")
		)
		(fp_line
			(start 0.90678 0.4826)
			(end -0.90678 0.4826)
			(stroke
				(width 0.1524)
				(type default)
			)
			(layer "F.SilkS")
		)
		(fp_line
			(start 1.03378 -0.4826)
			(end 1.03378 0.4826)
			(stroke
				(width 0.1524)
				(type default)
			)
			(layer "F.SilkS")
		)
		(fp_line
			(start 1.03378 0.4826)
			(end -0.79248 0.4826)
			(stroke
				(width 0.1524)
				(type default)
			)
			(layer "F.SilkS")
		)
		(fp_line
			(start 1.16078 -0.4826)
			(end 1.16078 0.4826)
			(stroke
				(width 0.1524)
				(type default)
			)
			(layer "F.SilkS")
		)
		(fp_line
			(start 1.16078 0.4826)
			(end -0.64008 0.4826)
			(stroke
				(width 0.1524)
				(type default)
			)
			(layer "F.SilkS")
		)
		(fp_line
			(start -0.499872 -0.249936)
			(end 0.499872 -0.249936)
			(stroke
				(width 0.1)
				(type default)
			)
			(layer "F.Fab")
		)
		(fp_line
			(start -0.499872 0.249936)
			(end -0.499872 -0.249936)
			(stroke
				(width 0.1)
				(type default)
			)
			(layer "F.Fab")
		)
		(fp_line
			(start 0.499872 -0.249936)
			(end 0.499872 0.249936)
			(stroke
				(width 0.1)
				(type default)
			)
			(layer "F.Fab")
		)
		(fp_line
			(start 0.499872 0.249936)
			(end -0.499872 0.249936)
			(stroke
				(width 0.1)
				(type default)
			)
			(layer "F.Fab")
		)
		(pad "A" smd rect
			(at -0.47498 0)
			(size 0.6096 0.7112)
			(layers "F.Cu" "F.Mask" "F.Paste")
			(net "LED_PWRGD_PVCCIN_CPU1")
		)
		(pad "C" smd rect
			(at 0.47498 0)
			(size 0.6096 0.7112)
			(layers "F.Cu" "F.Mask" "F.Paste")
			(net "LED_PWRGD_PVCCIN_CPU1_D")
		)
	)
	(footprint ""
		(layer "F.Cu")
		(at 83.4898 -35.651948 90)
		(property "Reference" "R4615"
			(at 0 0 90)
			(layer "F.SilkS")
			(hide yes)
			(effects
				(font
					(size 1.27 1.27)
				)
			)
		)
		(property "Value" ""
			(at 0 0 90)
			(layer "F.Fab")
			(effects
				(font
					(size 1.27 1.27)
				)
			)
		)
		(duplicate_pad_numbers_are_jumpers no)
		(fp_line
			(start 0.7874 -0.4064)
			(end 0.7874 0.4064)
			(stroke
				(width 0.1524)
				(type default)
			)
			(layer "F.SilkS")
		)
		(fp_line
			(start -0.7874 -0.4064)
			(end 0.7874 -0.4064)
			(stroke
				(width 0.1524)
				(type default)
			)
			(layer "F.SilkS")
		)
		(fp_line
			(start 0.7874 0.4064)
			(end -0.7874 0.4064)
			(stroke
				(width 0.1524)
				(type default)
			)
			(layer "F.SilkS")
		)
		(fp_line
			(start -0.7874 0.4064)
			(end -0.7874 -0.4064)
			(stroke
				(width 0.1524)
				(type default)
			)
			(layer "F.SilkS")
		)
		(fp_line
			(start -0.12065 -0.305054)
			(end -0.12065 -0.2794)
			(stroke
				(width 0.1)
				(type default)
			)
			(layer "F.Fab")
		)
		(fp_line
			(start -0.67945 -0.305054)
			(end -0.12065 -0.305054)
			(stroke
				(width 0.1)
				(type default)
			)
			(layer "F.Fab")
		)
		(fp_line
			(start 0.67945 -0.3048)
			(end 0.67945 0.3048)
			(stroke
				(width 0.1)
				(type default)
			)
			(layer "F.Fab")
		)
		(fp_line
			(start 0.12065 -0.3048)
			(end 0.67945 -0.3048)
			(stroke
				(width 0.1)
				(type default)
			)
			(layer "F.Fab")
		)
		(fp_line
			(start 0.12065 -0.2794)
			(end 0.12065 -0.3048)
			(stroke
				(width 0.1)
				(type default)
			)
			(layer "F.Fab")
		)
		(fp_line
			(start -0.12065 -0.2794)
			(end 0.12065 -0.2794)
			(stroke
				(width 0.1)
				(type default)
			)
			(layer "F.Fab")
		)
		(fp_line
			(start 0.120396 0.2794)
			(end -0.12065 0.2794)
			(stroke
				(width 0.1)
				(type default)
			)
			(layer "F.Fab")
		)
		(fp_line
			(start -0.12065 0.2794)
			(end -0.12065 0.3048)
			(stroke
				(width 0.1)
				(type default)
			)
			(layer "F.Fab")
		)
		(fp_line
			(start 0.67945 0.3048)
			(end 0.120396 0.3048)
			(stroke
				(width 0.1)
				(type default)
			)
			(layer "F.Fab")
		)
		(fp_line
			(start 0.120396 0.3048)
			(end 0.120396 0.2794)
			(stroke
				(width 0.1)
				(type default)
			)
			(layer "F.Fab")
		)
		(fp_line
			(start -0.12065 0.3048)
			(end -0.67945 0.3048)
			(stroke
				(width 0.1)
				(type default)
			)
			(layer "F.Fab")
		)
		(fp_line
			(start -0.67945 0.3048)
			(end -0.67945 -0.305054)
			(stroke
				(width 0.1)
				(type default)
			)
			(layer "F.Fab")
		)
		(pad "1" smd circle
			(at -0.40005 0 90)
			(size 0 0)
			(layers "F.Cu" "F.Mask" "F.Paste")
			(net "OCP_V3_2_P3V3_PWRGD")
		)
		(pad "2" smd circle
			(at 0.40005 0 90)
			(size 0 0)
			(layers "F.Cu" "F.Mask" "F.Paste")
			(net "HP_OCP_V3_2_RST_R")
		)
	)
	(footprint ""
		(layer "F.Cu")
		(at 27.58313 -174.11446)
		(property "Reference" "PR4699"
			(at 0 0 0)
			(layer "F.SilkS")
			(hide yes)
			(effects
				(font
					(size 1.27 1.27)
				)
			)
		)
		(property "Value" ""
			(at 0 0 0)
			(layer "F.Fab")
			(effects
				(font
					(size 1.27 1.27)
				)
			)
		)
		(duplicate_pad_numbers_are_jumpers no)
		(fp_line
			(start -0.7874 -0.4064)
			(end 0.7874 -0.4064)
			(stroke
				(width 0.1524)
				(type default)
			)
			(layer "F.SilkS")
		)
		(fp_line
			(start -0.7874 0.4064)
			(end -0.7874 -0.4064)
			(stroke
				(width 0.1524)
				(type default)
			)
			(layer "F.SilkS")
		)
		(fp_line
			(start 0.7874 -0.4064)
			(end 0.7874 0.4064)
			(stroke
				(width 0.1524)
				(type default)
			)
			(layer "F.SilkS")
		)
		(fp_line
			(start 0.7874 0.4064)
			(end -0.7874 0.4064)
			(stroke
				(width 0.1524)
				(type default)
			)
			(layer "F.SilkS")
		)
		(fp_line
			(start -0.67945 -0.305054)
			(end -0.12065 -0.305054)
			(stroke
				(width 0.1)
				(type default)
			)
			(layer "F.Fab")
		)
		(fp_line
			(start -0.67945 0.3048)
			(end -0.67945 -0.305054)
			(stroke
				(width 0.1)
				(type default)
			)
			(layer "F.Fab")
		)
		(fp_line
			(start -0.12065 -0.305054)
			(end -0.12065 -0.2794)
			(stroke
				(width 0.1)
				(type default)
			)
			(layer "F.Fab")
		)
		(fp_line
			(start -0.12065 -0.2794)
			(end 0.12065 -0.2794)
			(stroke
				(width 0.1)
				(type default)
			)
			(layer "F.Fab")
		)
		(fp_line
			(start -0.12065 0.2794)
			(end -0.12065 0.3048)
			(stroke
				(width 0.1)
				(type default)
			)
			(layer "F.Fab")
		)
		(fp_line
			(start -0.12065 0.3048)
			(end -0.67945 0.3048)
			(stroke
				(width 0.1)
				(type default)
			)
			(layer "F.Fab")
		)
		(fp_line
			(start 0.120396 0.2794)
			(end -0.12065 0.2794)
			(stroke
				(width 0.1)
				(type default)
			)
			(layer "F.Fab")
		)
		(fp_line
			(start 0.120396 0.3048)
			(end 0.120396 0.2794)
			(stroke
				(width 0.1)
				(type default)
			)
			(layer "F.Fab")
		)
		(fp_line
			(start 0.12065 -0.3048)
			(end 0.67945 -0.3048)
			(stroke
				(width 0.1)
				(type default)
			)
			(layer "F.Fab")
		)
		(fp_line
			(start 0.12065 -0.2794)
			(end 0.12065 -0.3048)
			(stroke
				(width 0.1)
				(type default)
			)
			(layer "F.Fab")
		)
		(fp_line
			(start 0.67945 -0.3048)
			(end 0.67945 0.3048)
			(stroke
				(width 0.1)
				(type default)
			)
			(layer "F.Fab")
		)
		(fp_line
			(start 0.67945 0.3048)
			(end 0.120396 0.3048)
			(stroke
				(width 0.1)
				(type default)
			)
			(layer "F.Fab")
		)
		(pad "1" smd circle
			(at -0.40005 0)
			(size 0 0)
			(layers "F.Cu" "F.Mask" "F.Paste")
			(net "PVNN_MAIN_CPU1_FB_RC")
		)
		(pad "2" smd circle
			(at 0.40005 0)
			(size 0 0)
			(layers "F.Cu" "F.Mask" "F.Paste")
			(net "PVNN_MAIN_CPU1")
		)
	)
	(footprint ""
		(layer "F.Cu")
		(at 179.12588 -126.964948 -90)
		(property "Reference" "R273"
			(at 0 0 270)
			(layer "F.SilkS")
			(hide yes)
			(effects
				(font
					(size 1.27 1.27)
				)
			)
		)
		(property "Value" ""
			(at 0 0 270)
			(layer "F.Fab")
			(effects
				(font
					(size 1.27 1.27)
				)
			)
		)
		(duplicate_pad_numbers_are_jumpers no)
		(fp_line
			(start -0.7874 0.4064)
			(end -0.7874 -0.4064)
			(stroke
				(width 0.1524)
				(type default)
			)
			(layer "F.SilkS")
		)
		(fp_line
			(start 0.7874 0.4064)
			(end -0.7874 0.4064)
			(stroke
				(width 0.1524)
				(type default)
			)
			(layer "F.SilkS")
		)
		(fp_line
			(start -0.7874 -0.4064)
			(end 0.7874 -0.4064)
			(stroke
				(width 0.1524)
				(type default)
			)
			(layer "F.SilkS")
		)
		(fp_line
			(start 0.7874 -0.4064)
			(end 0.7874 0.4064)
			(stroke
				(width 0.1524)
				(type default)
			)
			(layer "F.SilkS")
		)
		(fp_line
			(start -0.67945 0.3048)
			(end -0.67945 -0.305054)
			(stroke
				(width 0.1)
				(type default)
			)
			(layer "F.Fab")
		)
		(fp_line
			(start -0.12065 0.3048)
			(end -0.67945 0.3048)
			(stroke
				(width 0.1)
				(type default)
			)
			(layer "F.Fab")
		)
		(fp_line
			(start 0.120396 0.3048)
			(end 0.120396 0.2794)
			(stroke
				(width 0.1)
				(type default)
			)
			(layer "F.Fab")
		)
		(fp_line
			(start 0.67945 0.3048)
			(end 0.120396 0.3048)
			(stroke
				(width 0.1)
				(type default)
			)
			(layer "F.Fab")
		)
		(fp_line
			(start -0.12065 0.2794)
			(end -0.12065 0.3048)
			(stroke
				(width 0.1)
				(type default)
			)
			(layer "F.Fab")
		)
		(fp_line
			(start 0.120396 0.2794)
			(end -0.12065 0.2794)
			(stroke
				(width 0.1)
				(type default)
			)
			(layer "F.Fab")
		)
		(fp_line
			(start -0.12065 -0.2794)
			(end 0.12065 -0.2794)
			(stroke
				(width 0.1)
				(type default)
			)
			(layer "F.Fab")
		)
		(fp_line
			(start 0.12065 -0.2794)
			(end 0.12065 -0.3048)
			(stroke
				(width 0.1)
				(type default)
			)
			(layer "F.Fab")
		)
		(fp_line
			(start 0.12065 -0.3048)
			(end 0.67945 -0.3048)
			(stroke
				(width 0.1)
				(type default)
			)
			(layer "F.Fab")
		)
		(fp_line
			(start 0.67945 -0.3048)
			(end 0.67945 0.3048)
			(stroke
				(width 0.1)
				(type default)
			)
			(layer "F.Fab")
		)
		(fp_line
			(start -0.67945 -0.305054)
			(end -0.12065 -0.305054)
			(stroke
				(width 0.1)
				(type default)
			)
			(layer "F.Fab")
		)
		(fp_line
			(start -0.12065 -0.305054)
			(end -0.12065 -0.2794)
			(stroke
				(width 0.1)
				(type default)
			)
			(layer "F.Fab")
		)
		(pad "1" smd circle
			(at -0.40005 0 270)
			(size 0 0)
			(layers "F.Cu" "F.Mask" "F.Paste")
			(net "P3V3_AUX")
		)
		(pad "2" smd circle
			(at 0.40005 0 270)
			(size 0 0)
			(layers "F.Cu" "F.Mask" "F.Paste")
			(net "FM_CPU1_PROC_ID0")
		)
	)
	(footprint ""
		(layer "F.Cu")
		(at 112.26546 -413.408368 180)
		(property "Reference" "U314"
			(at 3.34772 6.20903 0)
			(unlocked yes)
			(layer "F.SilkS")
			(effects
				(font
					(size 0.7874 0.5842)
					(thickness 0.1524)
				)
			)
		)
		(property "Value" ""
			(at 0 0 180)
			(layer "F.Fab")
			(effects
				(font
					(size 1.27 1.27)
				)
			)
		)
		(duplicate_pad_numbers_are_jumpers no)
		(fp_line
			(start 2.500122 2.500122)
			(end 2.500122 2.01676)
			(stroke
				(width 0.1524)
				(type default)
			)
			(layer "F.SilkS")
		)
		(fp_line
			(start 2.500122 -2.01676)
			(end 2.500122 -2.500122)
			(stroke
				(width 0.1524)
				(type default)
			)
			(layer "F.SilkS")
		)
		(fp_line
			(start 2.500122 -2.500122)
			(end 2.01676 -2.500122)
			(stroke
				(width 0.1524)
				(type default)
			)
			(layer "F.SilkS")
		)
		(fp_line
			(start 2.01676 2.500122)
			(end 2.500122 2.500122)
			(stroke
				(width 0.1524)
				(type default)
			)
			(layer "F.SilkS")
		)
		(fp_line
			(start -2.01676 -2.500122)
			(end -2.500122 -2.500122)
			(stroke
				(width 0.1524)
				(type default)
			)
			(layer "F.SilkS")
		)
		(fp_line
			(start -2.500122 2.500122)
			(end -2.01676 2.500122)
			(stroke
				(width 0.1524)
				(type default)
			)
			(layer "F.SilkS")
		)
		(fp_line
			(start -2.500122 2.01676)
			(end -2.500122 2.500122)
			(stroke
				(width 0.1524)
				(type default)
			)
			(layer "F.SilkS")
		)
		(fp_line
			(start -2.500122 -2.500122)
			(end -2.500122 -2.01676)
			(stroke
				(width 0.1524)
				(type default)
			)
			(layer "F.SilkS")
		)
		(fp_poly
			(pts
				(xy -4.209542 -1.276858) (xy -4.209542 -2.472182) (xy -3.014218 -1.87452)
			)
			(stroke
				(width 0)
				(type default)
			)
			(fill yes)
			(layer "F.SilkS")
		)
		(fp_line
			(start 2.500122 2.500122)
			(end 2.500122 -2.500122)
			(stroke
				(width 0.1)
				(type default)
			)
			(layer "F.Fab")
		)
		(fp_line
			(start 2.500122 -2.500122)
			(end -2.500122 -2.500122)
			(stroke
				(width 0.1)
				(type default)
			)
			(layer "F.Fab")
		)
		(fp_line
			(start -2.500122 2.500122)
			(end 2.500122 2.500122)
			(stroke
				(width 0.1)
				(type default)
			)
			(layer "F.Fab")
		)
		(fp_line
			(start -2.500122 -2.500122)
			(end -2.500122 2.500122)
			(stroke
				(width 0.1)
				(type default)
			)
			(layer "F.Fab")
		)
		(fp_poly
			(pts
				(xy -3.044698 -1.75006) (xy -4.240022 -1.152398) (xy -4.240022 -2.347722)
			)
			(stroke
				(width 0)
				(type default)
			)
			(fill yes)
			(layer "F.Fab")
		)
		(pad "1" smd rect
			(at -2.3749 -1.75006 90)
			(size 0.254 0.5588)
			(layers "F.Cu" "F.Mask" "F.Paste")
			(net "FM_9ZXL045_DEV_EN")
		)
		(pad "2" smd rect
			(at -2.3749 -1.249934 90)
			(size 0.254 0.5588)
			(layers "F.Cu" "F.Mask" "F.Paste")
			(net "P3V3_9ZXL045_VDDR")
		)
		(pad "3" smd rect
			(at -2.3749 -0.750062 90)
			(size 0.254 0.5588)
			(layers "F.Cu" "F.Mask" "F.Paste")
			(net "CLK_100M_GPU_SWB_REF_DP")
		)
		(pad "4" smd rect
			(at -2.3749 -0.249936 90)
			(size 0.254 0.5588)
			(layers "F.Cu" "F.Mask" "F.Paste")
			(net "CLK_100M_GPU_SWB_REF_DN")
		)
		(pad "5" smd rect
			(at -2.3749 0.249936 90)
			(size 0.254 0.5588)
			(layers "F.Cu" "F.Mask" "F.Paste")
			(net "CLK_9ZXL045_SADR0")
		)
		(pad "6" smd rect
			(at -2.3749 0.750062 90)
			(size 0.254 0.5588)
			(layers "F.Cu" "F.Mask" "F.Paste")
			(net "SMB_HOST_9ZXL045_3V3AUX_SDA")
		)
		(pad "7" smd rect
			(at -2.3749 1.249934 90)
			(size 0.254 0.5588)
			(layers "F.Cu" "F.Mask" "F.Paste")
			(net "SMB_HOST_9ZXL045_3V3AUX_SCL")
		)
		(pad "8" smd rect
			(at -2.3749 1.75006 90)
			(size 0.254 0.5588)
			(layers "F.Cu" "F.Mask" "F.Paste")
			(net "NC_U314_FBOUT_N")
		)
		(pad "9" smd rect
			(at -1.75006 2.3749 180)
			(size 0.254 0.5588)
			(layers "F.Cu" "F.Mask" "F.Paste")
			(net "NC_U314_FBOUT")
		)
		(pad "10" smd rect
			(at -1.249934 2.3749 180)
			(size 0.254 0.5588)
			(layers "F.Cu" "F.Mask" "F.Paste")
			(net "NC_U314_NC0")
		)
		(pad "11" smd rect
			(at -0.750062 2.3749 180)
			(size 0.254 0.5588)
			(layers "F.Cu" "F.Mask" "F.Paste")
			(net "NC_U314_NC1")
		)
		(pad "12" smd rect
			(at -0.249936 2.3749 180)
			(size 0.254 0.5588)
			(layers "F.Cu" "F.Mask" "F.Paste")
			(net "P3V3_9ZXL045_VDD")
		)
		(pad "13" smd rect
			(at 0.249936 2.3749 180)
			(size 0.254 0.5588)
			(layers "F.Cu" "F.Mask" "F.Paste")
			(net "CLK_100M_SWB_R_DP")
		)
		(pad "14" smd rect
			(at 0.750062 2.3749 180)
			(size 0.254 0.5588)
			(layers "F.Cu" "F.Mask" "F.Paste")
			(net "CLK_100M_SWB_R_DN")
		)
		(pad "15" smd rect
			(at 1.249934 2.3749 180)
			(size 0.254 0.5588)
			(layers "F.Cu" "F.Mask" "F.Paste")
			(net "FM_9ZXL045_0_OE_N")
		)
		(pad "16" smd rect
			(at 1.75006 2.3749 180)
			(size 0.254 0.5588)
			(layers "F.Cu" "F.Mask" "F.Paste")
			(net "P3V3_9ZXL045_VDD")
		)
		(pad "17" smd rect
			(at 2.3749 1.75006 270)
			(size 0.254 0.5588)
			(layers "F.Cu" "F.Mask" "F.Paste")
			(net "NC_U314_NC2")
		)
		(pad "18" smd rect
			(at 2.3749 1.249934 270)
			(size 0.254 0.5588)
			(layers "F.Cu" "F.Mask" "F.Paste")
			(net "FM_9ZXL045_1_OE_N")
		)
		(pad "19" smd rect
			(at 2.3749 0.750062 270)
			(size 0.254 0.5588)
			(layers "F.Cu" "F.Mask" "F.Paste")
			(net "CLK_100M_GPU_1_R_DP")
		)
		(pad "20" smd rect
			(at 2.3749 0.249936 270)
			(size 0.254 0.5588)
			(layers "F.Cu" "F.Mask" "F.Paste")
			(net "CLK_100M_GPU_1_R_DN")
		)
		(pad "21" smd rect
			(at 2.3749 -0.249936 270)
			(size 0.254 0.5588)
			(layers "F.Cu" "F.Mask" "F.Paste")
			(net "P3V3_9ZXL045_VDD")
		)
		(pad "22" smd rect
			(at 2.3749 -0.750062 270)
			(size 0.254 0.5588)
			(layers "F.Cu" "F.Mask" "F.Paste")
			(net "CLK_100M_GPU_2_R_DP")
		)
		(pad "23" smd rect
			(at 2.3749 -1.249934 270)
			(size 0.254 0.5588)
			(layers "F.Cu" "F.Mask" "F.Paste")
			(net "CLK_100M_GPU_2_R_DN")
		)
		(pad "24" smd rect
			(at 2.3749 -1.75006 270)
			(size 0.254 0.5588)
			(layers "F.Cu" "F.Mask" "F.Paste")
			(net "FM_9ZXL045_2_OE_N")
		)
		(pad "25" smd rect
			(at 1.75006 -2.3749)
			(size 0.254 0.5588)
			(layers "F.Cu" "F.Mask" "F.Paste")
			(net "P3V3_9ZXL045_VDD")
		)
		(pad "26" smd rect
			(at 1.249934 -2.3749)
			(size 0.254 0.5588)
			(layers "F.Cu" "F.Mask" "F.Paste")
			(net "FM_9ZXL045_3_OE_N")
		)
		(pad "27" smd rect
			(at 0.750062 -2.3749)
			(size 0.254 0.5588)
			(layers "F.Cu" "F.Mask" "F.Paste")
			(net "TP_CLK_100M_BUF_DIF3_DP")
		)
		(pad "28" smd rect
			(at 0.249936 -2.3749)
			(size 0.254 0.5588)
			(layers "F.Cu" "F.Mask" "F.Paste")
			(net "TP_CLK_100M_BUF_DIF3_DN")
		)
		(pad "29" smd rect
			(at -0.249936 -2.3749)
			(size 0.254 0.5588)
			(layers "F.Cu" "F.Mask" "F.Paste")
			(net "P3V3_9ZXL045_VDD")
		)
		(pad "30" smd rect
			(at -0.750062 -2.3749)
			(size 0.254 0.5588)
			(layers "F.Cu" "F.Mask" "F.Paste")
			(net "NC_U314_NC3")
		)
		(pad "31" smd rect
			(at -1.249934 -2.3749)
			(size 0.254 0.5588)
			(layers "F.Cu" "F.Mask" "F.Paste")
			(net "P3V3_9ZXL045_VDDA")
		)
		(pad "32" smd rect
			(at -1.75006 -2.3749)
			(size 0.254 0.5588)
			(layers "F.Cu" "F.Mask" "F.Paste")
			(net "CLK_9ZXL045_HIBW")
		)
		(pad "33" smd rect
			(at 0 0 180)
			(size 3.1496 3.1496)
			(layers "F.Cu" "F.Mask" "F.Paste")
			(net "GND")
		)
		(zone
			(layer "F.Cu")
			(hatch none 0.5)
			(connect_pads
				(clearance 0)
			)
			(min_thickness 0.25)
			(keepout
				(tracks not_allowed)
				(vias allowed)
				(pads allowed)
				(copperpour not_allowed)
				(footprints allowed)
			)
			(placement
				(enabled no)
				(sheetname "")
			)
			(fill
				(thermal_gap 0.5)
				(thermal_bridge_width 0.5)
				(island_removal_mode 0)
			)
			(polygon
				(pts
					(xy 114.31016 -415.453068) (xy 114.31016 -412.183834) (xy 113.89106 -412.183834) (xy 113.89106 -415.033968)
					(xy 110.63986 -415.033968) (xy 110.63986 -411.782768) (xy 113.89106 -411.782768) (xy 113.89106 -412.158434)
					(xy 114.31016 -412.158434) (xy 114.31016 -411.363668) (xy 110.22076 -411.363668) (xy 110.22076 -415.453068)
				)
			)
		)
	)
	(footprint ""
		(layer "F.Cu")
		(at 273.801078 -422.6433)
		(property "Reference" "R4652"
			(at 0 0 0)
			(layer "F.SilkS")
			(hide yes)
			(effects
				(font
					(size 1.27 1.27)
				)
			)
		)
		(property "Value" ""
			(at 0 0 0)
			(layer "F.Fab")
			(effects
				(font
					(size 1.27 1.27)
				)
			)
		)
		(duplicate_pad_numbers_are_jumpers no)
		(fp_line
			(start -0.7874 -0.4064)
			(end 0.7874 -0.4064)
			(stroke
				(width 0.1524)
				(type default)
			)
			(layer "F.SilkS")
		)
		(fp_line
			(start -0.7874 0.4064)
			(end -0.7874 -0.4064)
			(stroke
				(width 0.1524)
				(type default)
			)
			(layer "F.SilkS")
		)
		(fp_line
			(start 0.7874 -0.4064)
			(end 0.7874 0.4064)
			(stroke
				(width 0.1524)
				(type default)
			)
			(layer "F.SilkS")
		)
		(fp_line
			(start 0.7874 0.4064)
			(end -0.7874 0.4064)
			(stroke
				(width 0.1524)
				(type default)
			)
			(layer "F.SilkS")
		)
		(fp_line
			(start -0.67945 -0.305054)
			(end -0.12065 -0.305054)
			(stroke
				(width 0.1)
				(type default)
			)
			(layer "F.Fab")
		)
		(fp_line
			(start -0.67945 0.3048)
			(end -0.67945 -0.305054)
			(stroke
				(width 0.1)
				(type default)
			)
			(layer "F.Fab")
		)
		(fp_line
			(start -0.12065 -0.305054)
			(end -0.12065 -0.2794)
			(stroke
				(width 0.1)
				(type default)
			)
			(layer "F.Fab")
		)
		(fp_line
			(start -0.12065 -0.2794)
			(end 0.12065 -0.2794)
			(stroke
				(width 0.1)
				(type default)
			)
			(layer "F.Fab")
		)
		(fp_line
			(start -0.12065 0.2794)
			(end -0.12065 0.3048)
			(stroke
				(width 0.1)
				(type default)
			)
			(layer "F.Fab")
		)
		(fp_line
			(start -0.12065 0.3048)
			(end -0.67945 0.3048)
			(stroke
				(width 0.1)
				(type default)
			)
			(layer "F.Fab")
		)
		(fp_line
			(start 0.120396 0.2794)
			(end -0.12065 0.2794)
			(stroke
				(width 0.1)
				(type default)
			)
			(layer "F.Fab")
		)
		(fp_line
			(start 0.120396 0.3048)
			(end 0.120396 0.2794)
			(stroke
				(width 0.1)
				(type default)
			)
			(layer "F.Fab")
		)
		(fp_line
			(start 0.12065 -0.3048)
			(end 0.67945 -0.3048)
			(stroke
				(width 0.1)
				(type default)
			)
			(layer "F.Fab")
		)
		(fp_line
			(start 0.12065 -0.2794)
			(end 0.12065 -0.3048)
			(stroke
				(width 0.1)
				(type default)
			)
			(layer "F.Fab")
		)
		(fp_line
			(start 0.67945 -0.3048)
			(end 0.67945 0.3048)
			(stroke
				(width 0.1)
				(type default)
			)
			(layer "F.Fab")
		)
		(fp_line
			(start 0.67945 0.3048)
			(end 0.120396 0.3048)
			(stroke
				(width 0.1)
				(type default)
			)
			(layer "F.Fab")
		)
		(pad "1" smd circle
			(at -0.40005 0)
			(size 0 0)
			(layers "F.Cu" "F.Mask" "F.Paste")
			(net "A_HSC_LOW_DRAIN")
		)
		(pad "2" smd circle
			(at 0.40005 0)
			(size 0 0)
			(layers "F.Cu" "F.Mask" "F.Paste")
			(net "HSC_D_OC")
		)
	)
	(footprint ""
		(layer "F.Cu")
		(at 355.228144 -241.976656 -90)
		(property "Reference" "C1023"
			(at 0 0 270)
			(layer "F.SilkS")
			(hide yes)
			(effects
				(font
					(size 1.27 1.27)
				)
			)
		)
		(property "Value" ""
			(at 0 0 270)
			(layer "F.Fab")
			(effects
				(font
					(size 1.27 1.27)
				)
			)
		)
		(duplicate_pad_numbers_are_jumpers no)
		(fp_line
			(start -0.7874 0.4064)
			(end -0.7874 -0.4064)
			(stroke
				(width 0.1524)
				(type default)
			)
			(layer "F.SilkS")
		)
		(fp_line
			(start 0.7874 0.4064)
			(end -0.7874 0.4064)
			(stroke
				(width 0.1524)
				(type default)
			)
			(layer "F.SilkS")
		)
		(fp_line
			(start -0.7874 -0.4064)
			(end 0.7874 -0.4064)
			(stroke
				(width 0.1524)
				(type default)
			)
			(layer "F.SilkS")
		)
		(fp_line
			(start 0.7874 -0.4064)
			(end 0.7874 0.4064)
			(stroke
				(width 0.1524)
				(type default)
			)
			(layer "F.SilkS")
		)
		(fp_line
			(start -0.67945 0.3048)
			(end -0.67945 -0.305054)
			(stroke
				(width 0.1)
				(type default)
			)
			(layer "F.Fab")
		)
		(fp_line
			(start -0.12065 0.3048)
			(end -0.67945 0.3048)
			(stroke
				(width 0.1)
				(type default)
			)
			(layer "F.Fab")
		)
		(fp_line
			(start 0.120396 0.3048)
			(end 0.120396 0.2794)
			(stroke
				(width 0.1)
				(type default)
			)
			(layer "F.Fab")
		)
		(fp_line
			(start 0.67945 0.3048)
			(end 0.120396 0.3048)
			(stroke
				(width 0.1)
				(type default)
			)
			(layer "F.Fab")
		)
		(fp_line
			(start -0.12065 0.2794)
			(end -0.12065 0.3048)
			(stroke
				(width 0.1)
				(type default)
			)
			(layer "F.Fab")
		)
		(fp_line
			(start 0.120396 0.2794)
			(end -0.12065 0.2794)
			(stroke
				(width 0.1)
				(type default)
			)
			(layer "F.Fab")
		)
		(fp_line
			(start -0.12065 -0.2794)
			(end 0.12065 -0.2794)
			(stroke
				(width 0.1)
				(type default)
			)
			(layer "F.Fab")
		)
		(fp_line
			(start 0.12065 -0.2794)
			(end 0.12065 -0.3048)
			(stroke
				(width 0.1)
				(type default)
			)
			(layer "F.Fab")
		)
		(fp_line
			(start 0.12065 -0.3048)
			(end 0.67945 -0.3048)
			(stroke
				(width 0.1)
				(type default)
			)
			(layer "F.Fab")
		)
		(fp_line
			(start 0.67945 -0.3048)
			(end 0.67945 0.3048)
			(stroke
				(width 0.1)
				(type default)
			)
			(layer "F.Fab")
		)
		(fp_line
			(start -0.67945 -0.305054)
			(end -0.12065 -0.305054)
			(stroke
				(width 0.1)
				(type default)
			)
			(layer "F.Fab")
		)
		(fp_line
			(start -0.12065 -0.305054)
			(end -0.12065 -0.2794)
			(stroke
				(width 0.1)
				(type default)
			)
			(layer "F.Fab")
		)
		(pad "1" smd circle
			(at -0.40005 0 270)
			(size 0 0)
			(layers "F.Cu" "F.Mask" "F.Paste")
			(net "PVCCIN_CPU0")
		)
		(pad "2" smd circle
			(at 0.40005 0 270)
			(size 0 0)
			(layers "F.Cu" "F.Mask" "F.Paste")
			(net "GND")
		)
	)
	(footprint ""
		(layer "F.Cu")
		(at 200.58888 -108.422948 90)
		(property "Reference" "R1841"
			(at 0 0 90)
			(layer "F.SilkS")
			(hide yes)
			(effects
				(font
					(size 1.27 1.27)
				)
			)
		)
		(property "Value" ""
			(at 0 0 90)
			(layer "F.Fab")
			(effects
				(font
					(size 1.27 1.27)
				)
			)
		)
		(duplicate_pad_numbers_are_jumpers no)
		(fp_line
			(start 0.7874 -0.4064)
			(end 0.7874 0.4064)
			(stroke
				(width 0.1524)
				(type default)
			)
			(layer "F.SilkS")
		)
		(fp_line
			(start -0.7874 -0.4064)
			(end 0.7874 -0.4064)
			(stroke
				(width 0.1524)
				(type default)
			)
			(layer "F.SilkS")
		)
		(fp_line
			(start 0.7874 0.4064)
			(end -0.7874 0.4064)
			(stroke
				(width 0.1524)
				(type default)
			)
			(layer "F.SilkS")
		)
		(fp_line
			(start -0.7874 0.4064)
			(end -0.7874 -0.4064)
			(stroke
				(width 0.1524)
				(type default)
			)
			(layer "F.SilkS")
		)
		(fp_line
			(start -0.12065 -0.305054)
			(end -0.12065 -0.2794)
			(stroke
				(width 0.1)
				(type default)
			)
			(layer "F.Fab")
		)
		(fp_line
			(start -0.67945 -0.305054)
			(end -0.12065 -0.305054)
			(stroke
				(width 0.1)
				(type default)
			)
			(layer "F.Fab")
		)
		(fp_line
			(start 0.67945 -0.3048)
			(end 0.67945 0.3048)
			(stroke
				(width 0.1)
				(type default)
			)
			(layer "F.Fab")
		)
		(fp_line
			(start 0.12065 -0.3048)
			(end 0.67945 -0.3048)
			(stroke
				(width 0.1)
				(type default)
			)
			(layer "F.Fab")
		)
		(fp_line
			(start 0.12065 -0.2794)
			(end 0.12065 -0.3048)
			(stroke
				(width 0.1)
				(type default)
			)
			(layer "F.Fab")
		)
		(fp_line
			(start -0.12065 -0.2794)
			(end 0.12065 -0.2794)
			(stroke
				(width 0.1)
				(type default)
			)
			(layer "F.Fab")
		)
		(fp_line
			(start 0.120396 0.2794)
			(end -0.12065 0.2794)
			(stroke
				(width 0.1)
				(type default)
			)
			(layer "F.Fab")
		)
		(fp_line
			(start -0.12065 0.2794)
			(end -0.12065 0.3048)
			(stroke
				(width 0.1)
				(type default)
			)
			(layer "F.Fab")
		)
		(fp_line
			(start 0.67945 0.3048)
			(end 0.120396 0.3048)
			(stroke
				(width 0.1)
				(type default)
			)
			(layer "F.Fab")
		)
		(fp_line
			(start 0.120396 0.3048)
			(end 0.120396 0.2794)
			(stroke
				(width 0.1)
				(type default)
			)
			(layer "F.Fab")
		)
		(fp_line
			(start -0.12065 0.3048)
			(end -0.67945 0.3048)
			(stroke
				(width 0.1)
				(type default)
			)
			(layer "F.Fab")
		)
		(fp_line
			(start -0.67945 0.3048)
			(end -0.67945 -0.305054)
			(stroke
				(width 0.1)
				(type default)
			)
			(layer "F.Fab")
		)
		(pad "1" smd circle
			(at -0.40005 0 90)
			(size 0 0)
			(layers "F.Cu" "F.Mask" "F.Paste")
			(net "P3V3_AUX")
		)
		(pad "2" smd circle
			(at 0.40005 0 90)
			(size 0 0)
			(layers "F.Cu" "F.Mask" "F.Paste")
			(net "FM_CPU_RMCA_CATERR_LVT3_R_N")
		)
	)
	(footprint ""
		(layer "F.Cu")
		(at 162.563302 -23.38959)
		(property "Reference" "R4149"
			(at 0 0 0)
			(layer "F.SilkS")
			(hide yes)
			(effects
				(font
					(size 1.27 1.27)
				)
			)
		)
		(property "Value" ""
			(at 0 0 0)
			(layer "F.Fab")
			(effects
				(font
					(size 1.27 1.27)
				)
			)
		)
		(duplicate_pad_numbers_are_jumpers no)
		(fp_line
			(start -0.7874 -0.4064)
			(end 0.7874 -0.4064)
			(stroke
				(width 0.1524)
				(type default)
			)
			(layer "F.SilkS")
		)
		(fp_line
			(start -0.7874 0.4064)
			(end -0.7874 -0.4064)
			(stroke
				(width 0.1524)
				(type default)
			)
			(layer "F.SilkS")
		)
		(fp_line
			(start 0.7874 -0.4064)
			(end 0.7874 0.4064)
			(stroke
				(width 0.1524)
				(type default)
			)
			(layer "F.SilkS")
		)
		(fp_line
			(start 0.7874 0.4064)
			(end -0.7874 0.4064)
			(stroke
				(width 0.1524)
				(type default)
			)
			(layer "F.SilkS")
		)
		(fp_line
			(start -0.67945 -0.305054)
			(end -0.12065 -0.305054)
			(stroke
				(width 0.1)
				(type default)
			)
			(layer "F.Fab")
		)
		(fp_line
			(start -0.67945 0.3048)
			(end -0.67945 -0.305054)
			(stroke
				(width 0.1)
				(type default)
			)
			(layer "F.Fab")
		)
		(fp_line
			(start -0.12065 -0.305054)
			(end -0.12065 -0.2794)
			(stroke
				(width 0.1)
				(type default)
			)
			(layer "F.Fab")
		)
		(fp_line
			(start -0.12065 -0.2794)
			(end 0.12065 -0.2794)
			(stroke
				(width 0.1)
				(type default)
			)
			(layer "F.Fab")
		)
		(fp_line
			(start -0.12065 0.2794)
			(end -0.12065 0.3048)
			(stroke
				(width 0.1)
				(type default)
			)
			(layer "F.Fab")
		)
		(fp_line
			(start -0.12065 0.3048)
			(end -0.67945 0.3048)
			(stroke
				(width 0.1)
				(type default)
			)
			(layer "F.Fab")
		)
		(fp_line
			(start 0.120396 0.2794)
			(end -0.12065 0.2794)
			(stroke
				(width 0.1)
				(type default)
			)
			(layer "F.Fab")
		)
		(fp_line
			(start 0.120396 0.3048)
			(end 0.120396 0.2794)
			(stroke
				(width 0.1)
				(type default)
			)
			(layer "F.Fab")
		)
		(fp_line
			(start 0.12065 -0.3048)
			(end 0.67945 -0.3048)
			(stroke
				(width 0.1)
				(type default)
			)
			(layer "F.Fab")
		)
		(fp_line
			(start 0.12065 -0.2794)
			(end 0.12065 -0.3048)
			(stroke
				(width 0.1)
				(type default)
			)
			(layer "F.Fab")
		)
		(fp_line
			(start 0.67945 -0.3048)
			(end 0.67945 0.3048)
			(stroke
				(width 0.1)
				(type default)
			)
			(layer "F.Fab")
		)
		(fp_line
			(start 0.67945 0.3048)
			(end 0.120396 0.3048)
			(stroke
				(width 0.1)
				(type default)
			)
			(layer "F.Fab")
		)
		(pad "1" smd circle
			(at -0.40005 0)
			(size 0 0)
			(layers "F.Cu" "F.Mask" "F.Paste")
			(net "SMB_1_PLD_3V3AUX_SCL")
		)
		(pad "2" smd circle
			(at 0.40005 0)
			(size 0 0)
			(layers "F.Cu" "F.Mask" "F.Paste")
			(net "SMB_1_PLD_3V3AUX_SCL_R1")
		)
	)
	(footprint ""
		(layer "F.Cu")
		(at 62.47257 -37.307266 180)
		(property "Reference" "Q118"
			(at 0.51435 -2.215388 0)
			(unlocked yes)
			(layer "F.SilkS")
			(effects
				(font
					(size 0.7874 0.5842)
					(thickness 0.1524)
				)
				(justify left)
			)
		)
		(property "Value" ""
			(at 0 0 180)
			(layer "F.Fab")
			(effects
				(font
					(size 1.27 1.27)
				)
			)
		)
		(duplicate_pad_numbers_are_jumpers no)
		(fp_line
			(start 1.332738 1.100074)
			(end -1.332738 1.100074)
			(stroke
				(width 0.1524)
				(type default)
			)
			(layer "F.SilkS")
		)
		(fp_line
			(start 1.332738 -1.100074)
			(end 1.332738 1.100074)
			(stroke
				(width 0.1524)
				(type default)
			)
			(layer "F.SilkS")
		)
		(fp_line
			(start 0.4826 -1.100074)
			(end 1.332738 -1.100074)
			(stroke
				(width 0.1524)
				(type default)
			)
			(layer "F.SilkS")
		)
		(fp_line
			(start 0 -0.541274)
			(end 0.4826 -1.100074)
			(stroke
				(width 0.1524)
				(type default)
			)
			(layer "F.SilkS")
		)
		(fp_line
			(start -0.4826 -1.100074)
			(end 0 -0.541274)
			(stroke
				(width 0.1524)
				(type default)
			)
			(layer "F.SilkS")
		)
		(fp_line
			(start -1.332738 1.100074)
			(end -1.332738 -1.100074)
			(stroke
				(width 0.1524)
				(type default)
			)
			(layer "F.SilkS")
		)
		(fp_line
			(start -1.332738 -1.100074)
			(end -0.4826 -1.100074)
			(stroke
				(width 0.1524)
				(type default)
			)
			(layer "F.SilkS")
		)
		(fp_poly
			(pts
				(xy -2.7432 -1.011174) (xy -2.041144 -0.660146) (xy -2.7432 -0.309118)
			)
			(stroke
				(width 0)
				(type default)
			)
			(fill yes)
			(layer "F.SilkS")
		)
		(fp_line
			(start 0.674878 1.100074)
			(end -0.674878 1.100074)
			(stroke
				(width 0.1)
				(type default)
			)
			(layer "F.Fab")
		)
		(fp_line
			(start 0.674878 -1.100074)
			(end 0.674878 1.100074)
			(stroke
				(width 0.1)
				(type default)
			)
			(layer "F.Fab")
		)
		(fp_line
			(start -0.674878 1.100074)
			(end -0.674878 -1.100074)
			(stroke
				(width 0.1)
				(type default)
			)
			(layer "F.Fab")
		)
		(fp_line
			(start -0.674878 -1.100074)
			(end 0.674878 -1.100074)
			(stroke
				(width 0.1)
				(type default)
			)
			(layer "F.Fab")
		)
		(fp_poly
			(pts
				(xy -2.2352 -0.298958) (xy -2.2352 -1.001014) (xy -1.533144 -0.649986)
			)
			(stroke
				(width 0)
				(type default)
			)
			(fill yes)
			(layer "F.Fab")
		)
		(pad "1" smd rect
			(at -0.94996 -0.649986 270)
			(size 0.4318 0.508)
			(layers "F.Cu" "F.Mask" "F.Paste")
			(net "GND")
		)
		(pad "2" smd rect
			(at -0.94996 0 270)
			(size 0.4318 0.508)
			(layers "F.Cu" "F.Mask" "F.Paste")
			(net "P12V_OCP_EN_2_R")
		)
		(pad "3" smd rect
			(at -0.94996 0.649986 270)
			(size 0.4318 0.508)
			(layers "F.Cu" "F.Mask" "F.Paste")
			(net "P12V_OCP_UV_2_R")
		)
		(pad "4" smd rect
			(at 0.94996 0.649986 270)
			(size 0.4318 0.508)
			(layers "F.Cu" "F.Mask" "F.Paste")
			(net "GND")
		)
		(pad "5" smd rect
			(at 0.94996 0 270)
			(size 0.4318 0.508)
			(layers "F.Cu" "F.Mask" "F.Paste")
			(net "P12V_OCP_2_EN_G")
		)
		(pad "6" smd rect
			(at 0.94996 -0.649986 270)
			(size 0.4318 0.508)
			(layers "F.Cu" "F.Mask" "F.Paste")
			(net "P12V_OCP_2_EN_G")
		)
	)
	(footprint ""
		(layer "F.Cu")
		(at 303.780444 -438.109106 -90)
		(property "Reference" "R4137"
			(at 0 0 270)
			(layer "F.SilkS")
			(hide yes)
			(effects
				(font
					(size 1.27 1.27)
				)
			)
		)
		(property "Value" ""
			(at 0 0 270)
			(layer "F.Fab")
			(effects
				(font
					(size 1.27 1.27)
				)
			)
		)
		(duplicate_pad_numbers_are_jumpers no)
		(fp_line
			(start -0.7874 0.4064)
			(end -0.7874 -0.4064)
			(stroke
				(width 0.1524)
				(type default)
			)
			(layer "F.SilkS")
		)
		(fp_line
			(start 0.7874 0.4064)
			(end -0.7874 0.4064)
			(stroke
				(width 0.1524)
				(type default)
			)
			(layer "F.SilkS")
		)
		(fp_line
			(start -0.7874 -0.4064)
			(end 0.7874 -0.4064)
			(stroke
				(width 0.1524)
				(type default)
			)
			(layer "F.SilkS")
		)
		(fp_line
			(start 0.7874 -0.4064)
			(end 0.7874 0.4064)
			(stroke
				(width 0.1524)
				(type default)
			)
			(layer "F.SilkS")
		)
		(fp_line
			(start -0.67945 0.3048)
			(end -0.67945 -0.305054)
			(stroke
				(width 0.1)
				(type default)
			)
			(layer "F.Fab")
		)
		(fp_line
			(start -0.12065 0.3048)
			(end -0.67945 0.3048)
			(stroke
				(width 0.1)
				(type default)
			)
			(layer "F.Fab")
		)
		(fp_line
			(start 0.120396 0.3048)
			(end 0.120396 0.2794)
			(stroke
				(width 0.1)
				(type default)
			)
			(layer "F.Fab")
		)
		(fp_line
			(start 0.67945 0.3048)
			(end 0.120396 0.3048)
			(stroke
				(width 0.1)
				(type default)
			)
			(layer "F.Fab")
		)
		(fp_line
			(start -0.12065 0.2794)
			(end -0.12065 0.3048)
			(stroke
				(width 0.1)
				(type default)
			)
			(layer "F.Fab")
		)
		(fp_line
			(start 0.120396 0.2794)
			(end -0.12065 0.2794)
			(stroke
				(width 0.1)
				(type default)
			)
			(layer "F.Fab")
		)
		(fp_line
			(start -0.12065 -0.2794)
			(end 0.12065 -0.2794)
			(stroke
				(width 0.1)
				(type default)
			)
			(layer "F.Fab")
		)
		(fp_line
			(start 0.12065 -0.2794)
			(end 0.12065 -0.3048)
			(stroke
				(width 0.1)
				(type default)
			)
			(layer "F.Fab")
		)
		(fp_line
			(start 0.12065 -0.3048)
			(end 0.67945 -0.3048)
			(stroke
				(width 0.1)
				(type default)
			)
			(layer "F.Fab")
		)
		(fp_line
			(start 0.67945 -0.3048)
			(end 0.67945 0.3048)
			(stroke
				(width 0.1)
				(type default)
			)
			(layer "F.Fab")
		)
		(fp_line
			(start -0.67945 -0.305054)
			(end -0.12065 -0.305054)
			(stroke
				(width 0.1)
				(type default)
			)
			(layer "F.Fab")
		)
		(fp_line
			(start -0.12065 -0.305054)
			(end -0.12065 -0.2794)
			(stroke
				(width 0.1)
				(type default)
			)
			(layer "F.Fab")
		)
		(pad "1" smd circle
			(at -0.40005 0 270)
			(size 0 0)
			(layers "F.Cu" "F.Mask" "F.Paste")
			(net "P3V3_AUX")
		)
		(pad "2" smd circle
			(at 0.40005 0 270)
			(size 0 0)
			(layers "F.Cu" "F.Mask" "F.Paste")
			(net "GPU_3V3IO_RSVD3_FFU_N")
		)
	)
	(footprint ""
		(layer "F.Cu")
		(at 113.16208 -395.207998 -90)
		(property "Reference" "Q74"
			(at 0.98806 -4.43484 0)
			(unlocked yes)
			(layer "F.SilkS")
			(effects
				(font
					(size 0.7874 0.5842)
					(thickness 0.1524)
				)
				(justify left)
			)
		)
		(property "Value" ""
			(at 0 0 270)
			(layer "F.Fab")
			(effects
				(font
					(size 1.27 1.27)
				)
			)
		)
		(duplicate_pad_numbers_are_jumpers no)
		(fp_line
			(start -1.332738 1.100074)
			(end -1.332738 -1.100074)
			(stroke
				(width 0.1524)
				(type default)
			)
			(layer "F.SilkS")
		)
		(fp_line
			(start 1.332738 1.100074)
			(end -1.332738 1.100074)
			(stroke
				(width 0.1524)
				(type default)
			)
			(layer "F.SilkS")
		)
		(fp_line
			(start 0 -0.541274)
			(end 0.4826 -1.100074)
			(stroke
				(width 0.1524)
				(type default)
			)
			(layer "F.SilkS")
		)
		(fp_line
			(start -1.332738 -1.100074)
			(end -0.4826 -1.100074)
			(stroke
				(width 0.1524)
				(type default)
			)
			(layer "F.SilkS")
		)
		(fp_line
			(start -0.4826 -1.100074)
			(end 0 -0.541274)
			(stroke
				(width 0.1524)
				(type default)
			)
			(layer "F.SilkS")
		)
		(fp_line
			(start 0.4826 -1.100074)
			(end 1.332738 -1.100074)
			(stroke
				(width 0.1524)
				(type default)
			)
			(layer "F.SilkS")
		)
		(fp_line
			(start 1.332738 -1.100074)
			(end 1.332738 1.100074)
			(stroke
				(width 0.1524)
				(type default)
			)
			(layer "F.SilkS")
		)
		(fp_poly
			(pts
				(xy -0.661416 -2.06121) (xy -1.012444 -1.359154) (xy -1.363472 -2.06121)
			)
			(stroke
				(width 0)
				(type default)
			)
			(fill yes)
			(layer "F.SilkS")
		)
		(fp_line
			(start -0.674878 1.100074)
			(end -0.674878 -1.100074)
			(stroke
				(width 0.1)
				(type default)
			)
			(layer "F.Fab")
		)
		(fp_line
			(start 0.674878 1.100074)
			(end -0.674878 1.100074)
			(stroke
				(width 0.1)
				(type default)
			)
			(layer "F.Fab")
		)
		(fp_line
			(start -0.674878 -1.100074)
			(end 0.674878 -1.100074)
			(stroke
				(width 0.1)
				(type default)
			)
			(layer "F.Fab")
		)
		(fp_line
			(start 0.674878 -1.100074)
			(end 0.674878 1.100074)
			(stroke
				(width 0.1)
				(type default)
			)
			(layer "F.Fab")
		)
		(fp_poly
			(pts
				(xy -2.2352 -0.298958) (xy -2.2352 -1.001014) (xy -1.533144 -0.649986)
			)
			(stroke
				(width 0)
				(type default)
			)
			(fill yes)
			(layer "F.Fab")
		)
		(pad "1" smd rect
			(at -0.94996 -0.649986)
			(size 0.4318 0.508)
			(layers "F.Cu" "F.Mask" "F.Paste")
			(net "GND")
		)
		(pad "2" smd rect
			(at -0.94996 0)
			(size 0.4318 0.508)
			(layers "F.Cu" "F.Mask" "F.Paste")
			(net "FM_SMB_2_ALERT_GPU_N")
		)
		(pad "3" smd rect
			(at -0.94996 0.649986)
			(size 0.4318 0.508)
			(layers "F.Cu" "F.Mask" "F.Paste")
			(net "FM_SMB_2_ALERT_GPU_ISO_N")
		)
		(pad "4" smd rect
			(at 0.94996 0.649986)
			(size 0.4318 0.508)
			(layers "F.Cu" "F.Mask" "F.Paste")
			(net "GND")
		)
		(pad "5" smd rect
			(at 0.94996 0)
			(size 0.4318 0.508)
			(layers "F.Cu" "F.Mask" "F.Paste")
			(net "FM_SMB_2_ALERT_GPU")
		)
		(pad "6" smd rect
			(at 0.94996 -0.649986)
			(size 0.4318 0.508)
			(layers "F.Cu" "F.Mask" "F.Paste")
			(net "FM_SMB_2_ALERT_GPU")
		)
	)
	(footprint ""
		(layer "F.Cu")
		(at 121.52884 -366.796066 -90)
		(property "Reference" "PC1267"
			(at 0 0 270)
			(layer "F.SilkS")
			(hide yes)
			(effects
				(font
					(size 1.27 1.27)
				)
			)
		)
		(property "Value" ""
			(at 0 0 270)
			(layer "F.Fab")
			(effects
				(font
					(size 1.27 1.27)
				)
			)
		)
		(duplicate_pad_numbers_are_jumpers no)
		(fp_line
			(start -0.7874 0.4064)
			(end -0.7874 -0.4064)
			(stroke
				(width 0.1524)
				(type default)
			)
			(layer "F.SilkS")
		)
		(fp_line
			(start 0.7874 0.4064)
			(end -0.7874 0.4064)
			(stroke
				(width 0.1524)
				(type default)
			)
			(layer "F.SilkS")
		)
		(fp_line
			(start -0.7874 -0.4064)
			(end 0.7874 -0.4064)
			(stroke
				(width 0.1524)
				(type default)
			)
			(layer "F.SilkS")
		)
		(fp_line
			(start 0.7874 -0.4064)
			(end 0.7874 0.4064)
			(stroke
				(width 0.1524)
				(type default)
			)
			(layer "F.SilkS")
		)
		(fp_line
			(start -0.67945 0.3048)
			(end -0.67945 -0.305054)
			(stroke
				(width 0.1)
				(type default)
			)
			(layer "F.Fab")
		)
		(fp_line
			(start -0.12065 0.3048)
			(end -0.67945 0.3048)
			(stroke
				(width 0.1)
				(type default)
			)
			(layer "F.Fab")
		)
		(fp_line
			(start 0.120396 0.3048)
			(end 0.120396 0.2794)
			(stroke
				(width 0.1)
				(type default)
			)
			(layer "F.Fab")
		)
		(fp_line
			(start 0.67945 0.3048)
			(end 0.120396 0.3048)
			(stroke
				(width 0.1)
				(type default)
			)
			(layer "F.Fab")
		)
		(fp_line
			(start -0.12065 0.2794)
			(end -0.12065 0.3048)
			(stroke
				(width 0.1)
				(type default)
			)
			(layer "F.Fab")
		)
		(fp_line
			(start 0.120396 0.2794)
			(end -0.12065 0.2794)
			(stroke
				(width 0.1)
				(type default)
			)
			(layer "F.Fab")
		)
		(fp_line
			(start -0.12065 -0.2794)
			(end 0.12065 -0.2794)
			(stroke
				(width 0.1)
				(type default)
			)
			(layer "F.Fab")
		)
		(fp_line
			(start 0.12065 -0.2794)
			(end 0.12065 -0.3048)
			(stroke
				(width 0.1)
				(type default)
			)
			(layer "F.Fab")
		)
		(fp_line
			(start 0.12065 -0.3048)
			(end 0.67945 -0.3048)
			(stroke
				(width 0.1)
				(type default)
			)
			(layer "F.Fab")
		)
		(fp_line
			(start 0.67945 -0.3048)
			(end 0.67945 0.3048)
			(stroke
				(width 0.1)
				(type default)
			)
			(layer "F.Fab")
		)
		(fp_line
			(start -0.67945 -0.305054)
			(end -0.12065 -0.305054)
			(stroke
				(width 0.1)
				(type default)
			)
			(layer "F.Fab")
		)
		(fp_line
			(start -0.12065 -0.305054)
			(end -0.12065 -0.2794)
			(stroke
				(width 0.1)
				(type default)
			)
			(layer "F.Fab")
		)
		(pad "1" smd circle
			(at -0.40005 0 270)
			(size 0 0)
			(layers "F.Cu" "F.Mask" "F.Paste")
			(net "PVPP_HBM_CPU1")
		)
		(pad "2" smd circle
			(at 0.40005 0 270)
			(size 0 0)
			(layers "F.Cu" "F.Mask" "F.Paste")
			(net "GND")
		)
	)
	(footprint ""
		(layer "F.Cu")
		(at 394.899896 -56.999886)
		(property "Reference" "J42"
			(at 4.46278 8.605012 0)
			(unlocked yes)
			(layer "F.SilkS")
			(effects
				(font
					(size 0.7874 0.5842)
					(thickness 0.1524)
				)
				(justify left)
			)
		)
		(property "Value" ""
			(at 0 0 0)
			(layer "F.Fab")
			(effects
				(font
					(size 1.27 1.27)
				)
			)
		)
		(duplicate_pad_numbers_are_jumpers no)
		(fp_line
			(start -3.620008 -10.655046)
			(end 2.032 -10.655046)
			(stroke
				(width 0.1524)
				(type default)
			)
			(layer "F.SilkS")
		)
		(fp_line
			(start -3.620008 -7.5184)
			(end -3.620008 -10.655046)
			(stroke
				(width 0.1524)
				(type default)
			)
			(layer "F.SilkS")
		)
		(fp_line
			(start -3.620008 10.655046)
			(end -3.620008 7.5184)
			(stroke
				(width 0.1524)
				(type default)
			)
			(layer "F.SilkS")
		)
		(fp_line
			(start 2.032 10.655046)
			(end -3.620008 10.655046)
			(stroke
				(width 0.1524)
				(type default)
			)
			(layer "F.SilkS")
		)
		(fp_line
			(start 3.302 -10.655046)
			(end 3.620008 -10.655046)
			(stroke
				(width 0.1524)
				(type default)
			)
			(layer "F.SilkS")
		)
		(fp_line
			(start 3.620008 -10.655046)
			(end 3.620008 -7.5184)
			(stroke
				(width 0.1524)
				(type default)
			)
			(layer "F.SilkS")
		)
		(fp_line
			(start 3.620008 7.5184)
			(end 3.620008 10.655046)
			(stroke
				(width 0.1524)
				(type default)
			)
			(layer "F.SilkS")
		)
		(fp_line
			(start 3.620008 10.655046)
			(end 3.302 10.655046)
			(stroke
				(width 0.1524)
				(type default)
			)
			(layer "F.SilkS")
		)
		(fp_poly
			(pts
				(xy -4.1656 -7.249922) (xy -5.08 -6.805422) (xy -5.08 -7.669022)
			)
			(stroke
				(width 0)
				(type default)
			)
			(fill yes)
			(layer "F.SilkS")
		)
		(fp_line
			(start -3.620008 -10.655046)
			(end 3.620008 -10.655046)
			(stroke
				(width 0.1)
				(type default)
			)
			(layer "F.Fab")
		)
		(fp_line
			(start -3.620008 10.655046)
			(end -3.620008 -10.655046)
			(stroke
				(width 0.1)
				(type default)
			)
			(layer "F.Fab")
		)
		(fp_line
			(start 3.620008 -10.655046)
			(end 3.620008 10.655046)
			(stroke
				(width 0.1)
				(type default)
			)
			(layer "F.Fab")
		)
		(fp_line
			(start 3.620008 10.655046)
			(end -3.620008 10.655046)
			(stroke
				(width 0.1)
				(type default)
			)
			(layer "F.Fab")
		)
		(fp_poly
			(pts
				(xy -4.1656 -7.249922) (xy -5.08 -7.669022) (xy -5.08 -6.805422)
			)
			(stroke
				(width 0)
				(type default)
			)
			(fill yes)
			(layer "F.Fab")
		)
		(fp_text user "59"
			(at -5.816092 8.908034 0)
			(unlocked yes)
			(layer "F.SilkS")
			(effects
				(font
					(size 0.7874 0.5842)
					(thickness 0.1524)
				)
				(justify left)
			)
		)
		(fp_text user "60"
			(at 4.475988 6.535674 0)
			(unlocked yes)
			(layer "F.SilkS")
			(effects
				(font
					(size 0.7874 0.5842)
					(thickness 0.1524)
				)
				(justify left)
			)
		)
		(fp_text user "2"
			(at 4.504944 -7.675626 0)
			(unlocked yes)
			(layer "F.SilkS")
			(effects
				(font
					(size 0.7874 0.5842)
					(thickness 0.1524)
				)
				(justify left)
			)
		)
		(fp_text user "59"
			(at -4.683252 6.589522 270)
			(unlocked yes)
			(layer "F.Fab")
			(effects
				(font
					(size 0.7874 0.5842)
					(thickness 0.1524)
				)
				(justify left)
			)
		)
		(fp_text user "2"
			(at 4.613148 -7.592822 270)
			(unlocked yes)
			(layer "F.Fab")
			(effects
				(font
					(size 0.7874 0.5842)
					(thickness 0.1524)
				)
				(justify left)
			)
		)
		(fp_text user "60"
			(at 4.613148 6.513322 270)
			(unlocked yes)
			(layer "F.Fab")
			(effects
				(font
					(size 0.7874 0.5842)
					(thickness 0.1524)
				)
				(justify left)
			)
		)
		(pad "" np_thru_hole circle
			(at 2.670048 -10.065004 270)
			(size 1.0414 1.0414)
			(drill 1.0414)
			(layers "*.Cu" "*.Mask")
			(clearance 0.381)
			(thermal_gap 0.381)
		)
		(pad "" np_thru_hole circle
			(at 2.670048 10.065004 270)
			(size 1.0414 1.0414)
			(drill 1.0414)
			(layers "*.Cu" "*.Mask")
			(clearance 0.381)
			(thermal_gap 0.381)
		)
		(pad "1" smd rect
			(at -2.86512 -7.249922 270)
			(size 0.2794 2.286)
			(layers "F.Cu" "F.Mask" "F.Paste")
			(net "P1V05_PCH_AUX")
		)
		(pad "2" smd rect
			(at 2.86512 -7.249922 270)
			(size 0.2794 2.286)
			(layers "F.Cu" "F.Mask" "F.Paste")
			(net "JTAG_DBP_TMS_R")
		)
		(pad "3" smd rect
			(at -2.86512 -6.75005 270)
			(size 0.2794 2.286)
			(layers "F.Cu" "F.Mask" "F.Paste")
			(net "JTAG_DBP_CPU_GTL_TCK_R")
		)
		(pad "4" smd rect
			(at 2.86512 -6.75005 270)
			(size 0.2794 2.286)
			(layers "F.Cu" "F.Mask" "F.Paste")
			(net "JTAG_DBP_TDO_R")
		)
		(pad "5" smd rect
			(at -2.86512 -6.249924 270)
			(size 0.2794 2.286)
			(layers "F.Cu" "F.Mask" "F.Paste")
			(net "JTAG_DBP_TDI_R")
		)
		(pad "6" smd rect
			(at 2.86512 -6.249924 270)
			(size 0.2794 2.286)
			(layers "F.Cu" "F.Mask" "F.Paste")
			(net "JTAG_RST_DBP_RST_CO_N")
		)
		(pad "7" smd rect
			(at -2.86512 -5.750052 270)
			(size 0.2794 2.286)
			(layers "F.Cu" "F.Mask" "F.Paste")
			(net "JTAG_DBP_PMODE")
		)
		(pad "8" smd rect
			(at 2.86512 -5.750052 270)
			(size 0.2794 2.286)
			(layers "F.Cu" "F.Mask" "F.Paste")
			(net "PD_TRST_P3")
		)
		(pad "9" smd rect
			(at -2.86512 -5.249926 270)
			(size 0.2794 2.286)
			(layers "F.Cu" "F.Mask" "F.Paste")
			(net "NC_MIPI60_P9")
		)
		(pad "10" smd rect
			(at 2.86512 -5.249926 270)
			(size 0.2794 2.286)
			(layers "F.Cu" "F.Mask" "F.Paste")
			(net "JTAG_DBP_PREQ_N_R")
		)
		(pad "11" smd rect
			(at -2.86512 -4.750054 270)
			(size 0.2794 2.286)
			(layers "F.Cu" "F.Mask" "F.Paste")
			(net "JTAG_DBP_PRDY_R1_N")
		)
		(pad "12" smd rect
			(at 2.86512 -4.750054 270)
			(size 0.2794 2.286)
			(layers "F.Cu" "F.Mask" "F.Paste")
			(net "P1V8_PCH_AUX")
		)
		(pad "13" smd rect
			(at -2.86512 -4.249928 270)
			(size 0.2794 2.286)
			(layers "F.Cu" "F.Mask" "F.Paste")
			(net "JTAG_TRC_PCH_PTI0_CLK")
		)
		(pad "14" smd rect
			(at 2.86512 -4.249928 270)
			(size 0.2794 2.286)
			(layers "F.Cu" "F.Mask" "F.Paste")
			(net "GND")
		)
		(pad "15" smd rect
			(at -2.86512 -3.750056 270)
			(size 0.2794 2.286)
			(layers "F.Cu" "F.Mask" "F.Paste")
			(net "JTAG_DBP_PCH_DEBUG_CONSENT_N")
		)
		(pad "16" smd rect
			(at 2.86512 -3.750056 270)
			(size 0.2794 2.286)
			(layers "F.Cu" "F.Mask" "F.Paste")
			(net "GND")
		)
		(pad "17" smd rect
			(at -2.86512 -3.24993 270)
			(size 0.2794 2.286)
			(layers "F.Cu" "F.Mask" "F.Paste")
			(net "JTAG_DBP_PRESENT_R_N")
		)
		(pad "18" smd rect
			(at 2.86512 -3.24993 270)
			(size 0.2794 2.286)
			(layers "F.Cu" "F.Mask" "F.Paste")
			(net "NC_DBP_P18")
		)
		(pad "19" smd rect
			(at -2.86512 -2.750058 270)
			(size 0.2794 2.286)
			(layers "F.Cu" "F.Mask" "F.Paste")
			(net "JTAG_TRC_PCH_PTI<0>")
		)
		(pad "20" smd rect
			(at 2.86512 -2.750058 270)
			(size 0.2794 2.286)
			(layers "F.Cu" "F.Mask" "F.Paste")
			(net "NC_DBP_P20")
		)
		(pad "21" smd rect
			(at -2.86512 -2.249932 270)
			(size 0.2794 2.286)
			(layers "F.Cu" "F.Mask" "F.Paste")
			(net "JTAG_TRC_PCH_PTI<1>")
		)
		(pad "22" smd rect
			(at 2.86512 -2.249932 270)
			(size 0.2794 2.286)
			(layers "F.Cu" "F.Mask" "F.Paste")
			(net "NC_DBP_P22")
		)
		(pad "23" smd rect
			(at -2.86512 -1.75006 270)
			(size 0.2794 2.286)
			(layers "F.Cu" "F.Mask" "F.Paste")
			(net "JTAG_TRC_PCH_PTI<2>")
		)
		(pad "24" smd rect
			(at 2.86512 -1.75006 270)
			(size 0.2794 2.286)
			(layers "F.Cu" "F.Mask" "F.Paste")
			(net "NC_DBP_P24")
		)
		(pad "25" smd rect
			(at -2.86512 -1.249934 270)
			(size 0.2794 2.286)
			(layers "F.Cu" "F.Mask" "F.Paste")
			(net "JTAG_TRC_PCH_PTI<3>")
		)
		(pad "26" smd rect
			(at 2.86512 -1.249934 270)
			(size 0.2794 2.286)
			(layers "F.Cu" "F.Mask" "F.Paste")
			(net "NC_DBP_P26")
		)
		(pad "27" smd rect
			(at -2.86512 -0.750062 270)
			(size 0.2794 2.286)
			(layers "F.Cu" "F.Mask" "F.Paste")
			(net "JTAG_TRC_PCH_PTI<4>")
		)
		(pad "28" smd rect
			(at 2.86512 -0.750062 270)
			(size 0.2794 2.286)
			(layers "F.Cu" "F.Mask" "F.Paste")
			(net "NC_DBP_P28")
		)
		(pad "29" smd rect
			(at -2.86512 -0.249936 270)
			(size 0.2794 2.286)
			(layers "F.Cu" "F.Mask" "F.Paste")
			(net "JTAG_TRC_PCH_PTI<5>")
		)
		(pad "30" smd rect
			(at 2.86512 -0.249936 270)
			(size 0.2794 2.286)
			(layers "F.Cu" "F.Mask" "F.Paste")
			(net "NC_DBP_P30")
		)
		(pad "31" smd rect
			(at -2.86512 0.249936 270)
			(size 0.2794 2.286)
			(layers "F.Cu" "F.Mask" "F.Paste")
			(net "JTAG_TRC_PCH_PTI<6>")
		)
		(pad "32" smd rect
			(at 2.86512 0.249936 270)
			(size 0.2794 2.286)
			(layers "F.Cu" "F.Mask" "F.Paste")
			(net "NC_DBP_P32")
		)
		(pad "33" smd rect
			(at -2.86512 0.750062 270)
			(size 0.2794 2.286)
			(layers "F.Cu" "F.Mask" "F.Paste")
			(net "JTAG_TRC_PCH_PTI<7>")
		)
		(pad "34" smd rect
			(at 2.86512 0.750062 270)
			(size 0.2794 2.286)
			(layers "F.Cu" "F.Mask" "F.Paste")
			(net "NC_DBP_P34")
		)
		(pad "35" smd rect
			(at -2.86512 1.249934 270)
			(size 0.2794 2.286)
			(layers "F.Cu" "F.Mask" "F.Paste")
			(net "JTAG_TRC_PCH_PTI<8>")
		)
		(pad "36" smd rect
			(at 2.86512 1.249934 270)
			(size 0.2794 2.286)
			(layers "F.Cu" "F.Mask" "F.Paste")
			(net "JTAG_DBP_BOOT_HALT_N")
		)
		(pad "37" smd rect
			(at -2.86512 1.75006 270)
			(size 0.2794 2.286)
			(layers "F.Cu" "F.Mask" "F.Paste")
			(net "JTAG_TRC_PCH_PTI<9>")
		)
		(pad "38" smd rect
			(at 2.86512 1.75006 270)
			(size 0.2794 2.286)
			(layers "F.Cu" "F.Mask" "F.Paste")
			(net "FM_CPU_FBRK_DEBUG_N")
		)
		(pad "39" smd rect
			(at -2.86512 2.249932 270)
			(size 0.2794 2.286)
			(layers "F.Cu" "F.Mask" "F.Paste")
			(net "JTAG_TRC_PCH_PTI<10>")
		)
		(pad "40" smd rect
			(at 2.86512 2.249932 270)
			(size 0.2794 2.286)
			(layers "F.Cu" "F.Mask" "F.Paste")
			(net "JTAG_DBP_POWER_BTN_N")
		)
		(pad "41" smd rect
			(at -2.86512 2.750058 270)
			(size 0.2794 2.286)
			(layers "F.Cu" "F.Mask" "F.Paste")
			(net "JTAG_TRC_PCH_PTI<11>")
		)
		(pad "42" smd rect
			(at 2.86512 2.750058 270)
			(size 0.2794 2.286)
			(layers "F.Cu" "F.Mask" "F.Paste")
			(net "JTAG_RST_DBP_RSMRST_N")
		)
		(pad "43" smd rect
			(at -2.86512 3.24993 270)
			(size 0.2794 2.286)
			(layers "F.Cu" "F.Mask" "F.Paste")
			(net "JTAG_TRC_PCH_PTI<12>")
		)
		(pad "44" smd rect
			(at 2.86512 3.24993 270)
			(size 0.2794 2.286)
			(layers "F.Cu" "F.Mask" "F.Paste")
			(net "NC_DBP_P44")
		)
		(pad "45" smd rect
			(at -2.86512 3.750056 270)
			(size 0.2794 2.286)
			(layers "F.Cu" "F.Mask" "F.Paste")
			(net "JTAG_TRC_PCH_PTI<13>")
		)
		(pad "46" smd rect
			(at 2.86512 3.750056 270)
			(size 0.2794 2.286)
			(layers "F.Cu" "F.Mask" "F.Paste")
			(net "NC_DBP_P46")
		)
		(pad "47" smd rect
			(at -2.86512 4.249928 270)
			(size 0.2794 2.286)
			(layers "F.Cu" "F.Mask" "F.Paste")
			(net "JTAG_TRC_PCH_PTI<14>")
		)
		(pad "48" smd rect
			(at 2.86512 4.249928 270)
			(size 0.2794 2.286)
			(layers "F.Cu" "F.Mask" "F.Paste")
			(net "SMB_HOST_3V3AUX_XDP_R_SCL")
		)
		(pad "49" smd rect
			(at -2.86512 4.750054 270)
			(size 0.2794 2.286)
			(layers "F.Cu" "F.Mask" "F.Paste")
			(net "JTAG_TRC_PCH_PTI<15>")
		)
		(pad "50" smd rect
			(at 2.86512 4.750054 270)
			(size 0.2794 2.286)
			(layers "F.Cu" "F.Mask" "F.Paste")
			(net "SMB_HOST_3V3AUX_XDP_R_SDA")
		)
		(pad "51" smd rect
			(at -2.86512 5.249926 270)
			(size 0.2794 2.286)
			(layers "F.Cu" "F.Mask" "F.Paste")
			(net "JTAG_DBP_TCK_R_TCK")
		)
		(pad "52" smd rect
			(at 2.86512 5.249926 270)
			(size 0.2794 2.286)
			(layers "F.Cu" "F.Mask" "F.Paste")
			(net "P3V3_AUX")
		)
		(pad "53" smd rect
			(at -2.86512 5.750052 270)
			(size 0.2794 2.286)
			(layers "F.Cu" "F.Mask" "F.Paste")
			(net "JTAG_DBP_CPU_HOOK9_MBP3_GTL_N")
		)
		(pad "54" smd rect
			(at 2.86512 5.750052 270)
			(size 0.2794 2.286)
			(layers "F.Cu" "F.Mask" "F.Paste")
			(net "NC_DBP_P54")
		)
		(pad "55" smd rect
			(at -2.86512 6.249924 270)
			(size 0.2794 2.286)
			(layers "F.Cu" "F.Mask" "F.Paste")
			(net "JTAG_DBP_CPU_HOOK8_MBP2_GTL_N")
		)
		(pad "56" smd rect
			(at 2.86512 6.249924 270)
			(size 0.2794 2.286)
			(layers "F.Cu" "F.Mask" "F.Paste")
			(net "NC_DBP_P56")
		)
		(pad "57" smd rect
			(at -2.86512 6.75005 270)
			(size 0.2794 2.286)
			(layers "F.Cu" "F.Mask" "F.Paste")
			(net "GND")
		)
		(pad "58" smd rect
			(at 2.86512 6.75005 270)
			(size 0.2794 2.286)
			(layers "F.Cu" "F.Mask" "F.Paste")
			(net "GND")
		)
		(pad "59" smd rect
			(at -2.86512 7.249922 270)
			(size 0.2794 2.286)
			(layers "F.Cu" "F.Mask" "F.Paste")
			(net "JTAG_TRC_PCH_PTI1_CLK")
		)
		(pad "60" smd rect
			(at 2.86512 7.249922 270)
			(size 0.2794 2.286)
			(layers "F.Cu" "F.Mask" "F.Paste")
			(net "GND")
		)
		(pad "G1" smd rect
			(at 0 -8.065008)
			(size 0.4318 2.54)
			(layers "F.Cu" "F.Mask" "F.Paste")
			(net "GND")
		)
		(pad "G2" smd rect
			(at 0 -3.175)
			(size 0.4318 4.699)
			(layers "F.Cu" "F.Mask" "F.Paste")
			(net "GND")
		)
		(pad "G3" smd rect
			(at 0 3.175)
			(size 0.4318 4.699)
			(layers "F.Cu" "F.Mask" "F.Paste")
			(net "GND")
		)
		(pad "G4" smd rect
			(at 0 8.065008)
			(size 0.4318 2.54)
			(layers "F.Cu" "F.Mask" "F.Paste")
			(net "GND")
		)
		(zone
			(layers "F.Cu" "B.Cu" "In1.Cu" "In2.Cu" "In3.Cu" "In4.Cu" "In5.Cu" "In6.Cu"
				"In7.Cu" "In8.Cu" "In9.Cu" "In10.Cu" "In11.Cu" "In12.Cu" "In13.Cu" "In14.Cu"
				"In15.Cu" "In16.Cu"
			)
			(hatch none 0.5)
			(connect_pads
				(clearance 0)
			)
			(min_thickness 0.25)
			(keepout
				(tracks not_allowed)
				(vias allowed)
				(pads allowed)
				(copperpour not_allowed)
				(footprints allowed)
			)
			(placement
				(enabled no)
				(sheetname "")
			)
			(fill
				(thermal_gap 0.5)
				(thermal_bridge_width 0.5)
				(island_removal_mode 0)
			)
			(polygon
				(pts
					(arc
						(start 398.497044 -67.06489)
						(mid 396.642844 -67.06489)
						(end 398.497044 -67.06489)
					)
				)
			)
		)
		(zone
			(layers "F.Cu" "B.Cu" "In1.Cu" "In2.Cu" "In3.Cu" "In4.Cu" "In5.Cu" "In6.Cu"
				"In7.Cu" "In8.Cu" "In9.Cu" "In10.Cu" "In11.Cu" "In12.Cu" "In13.Cu" "In14.Cu"
				"In15.Cu" "In16.Cu"
			)
			(hatch none 0.5)
			(connect_pads
				(clearance 0)
			)
			(min_thickness 0.25)
			(keepout
				(tracks not_allowed)
				(vias allowed)
				(pads allowed)
				(copperpour not_allowed)
				(footprints allowed)
			)
			(placement
				(enabled no)
				(sheetname "")
			)
			(fill
				(thermal_gap 0.5)
				(thermal_bridge_width 0.5)
				(island_removal_mode 0)
			)
			(polygon
				(pts
					(arc
						(start 398.497044 -46.934882)
						(mid 396.642844 -46.934882)
						(end 398.497044 -46.934882)
					)
				)
			)
		)
	)
	(footprint ""
		(layer "F.Cu")
		(at 73.496678 -29.845762 90)
		(property "Reference" "PC2165"
			(at 0 0 90)
			(layer "F.SilkS")
			(hide yes)
			(effects
				(font
					(size 1.27 1.27)
				)
			)
		)
		(property "Value" ""
			(at 0 0 90)
			(layer "F.Fab")
			(effects
				(font
					(size 1.27 1.27)
				)
			)
		)
		(duplicate_pad_numbers_are_jumpers no)
		(fp_line
			(start 0.7874 -0.4064)
			(end 0.7874 0.4064)
			(stroke
				(width 0.1524)
				(type default)
			)
			(layer "F.SilkS")
		)
		(fp_line
			(start -0.7874 -0.4064)
			(end 0.7874 -0.4064)
			(stroke
				(width 0.1524)
				(type default)
			)
			(layer "F.SilkS")
		)
		(fp_line
			(start 0.7874 0.4064)
			(end -0.7874 0.4064)
			(stroke
				(width 0.1524)
				(type default)
			)
			(layer "F.SilkS")
		)
		(fp_line
			(start -0.7874 0.4064)
			(end -0.7874 -0.4064)
			(stroke
				(width 0.1524)
				(type default)
			)
			(layer "F.SilkS")
		)
		(fp_line
			(start -0.12065 -0.305054)
			(end -0.12065 -0.2794)
			(stroke
				(width 0.1)
				(type default)
			)
			(layer "F.Fab")
		)
		(fp_line
			(start -0.67945 -0.305054)
			(end -0.12065 -0.305054)
			(stroke
				(width 0.1)
				(type default)
			)
			(layer "F.Fab")
		)
		(fp_line
			(start 0.67945 -0.3048)
			(end 0.67945 0.3048)
			(stroke
				(width 0.1)
				(type default)
			)
			(layer "F.Fab")
		)
		(fp_line
			(start 0.12065 -0.3048)
			(end 0.67945 -0.3048)
			(stroke
				(width 0.1)
				(type default)
			)
			(layer "F.Fab")
		)
		(fp_line
			(start 0.12065 -0.2794)
			(end 0.12065 -0.3048)
			(stroke
				(width 0.1)
				(type default)
			)
			(layer "F.Fab")
		)
		(fp_line
			(start -0.12065 -0.2794)
			(end 0.12065 -0.2794)
			(stroke
				(width 0.1)
				(type default)
			)
			(layer "F.Fab")
		)
		(fp_line
			(start 0.120396 0.2794)
			(end -0.12065 0.2794)
			(stroke
				(width 0.1)
				(type default)
			)
			(layer "F.Fab")
		)
		(fp_line
			(start -0.12065 0.2794)
			(end -0.12065 0.3048)
			(stroke
				(width 0.1)
				(type default)
			)
			(layer "F.Fab")
		)
		(fp_line
			(start 0.67945 0.3048)
			(end 0.120396 0.3048)
			(stroke
				(width 0.1)
				(type default)
			)
			(layer "F.Fab")
		)
		(fp_line
			(start 0.120396 0.3048)
			(end 0.120396 0.2794)
			(stroke
				(width 0.1)
				(type default)
			)
			(layer "F.Fab")
		)
		(fp_line
			(start -0.12065 0.3048)
			(end -0.67945 0.3048)
			(stroke
				(width 0.1)
				(type default)
			)
			(layer "F.Fab")
		)
		(fp_line
			(start -0.67945 0.3048)
			(end -0.67945 -0.305054)
			(stroke
				(width 0.1)
				(type default)
			)
			(layer "F.Fab")
		)
		(pad "1" smd circle
			(at -0.40005 0 90)
			(size 0 0)
			(layers "F.Cu" "F.Mask" "F.Paste")
			(net "P12V_AUX")
		)
		(pad "2" smd circle
			(at 0.40005 0 90)
			(size 0 0)
			(layers "F.Cu" "F.Mask" "F.Paste")
			(net "GND")
		)
	)
	(footprint ""
		(layer "F.Cu")
		(at 249.81535 -73.290684)
		(property "Reference" "PL110"
			(at -2.3876 -2.969768 0)
			(unlocked yes)
			(layer "F.SilkS")
			(effects
				(font
					(size 0.7874 0.5842)
					(thickness 0.1524)
				)
				(justify left)
			)
		)
		(property "Value" ""
			(at 0 0 0)
			(layer "F.Fab")
			(effects
				(font
					(size 1.27 1.27)
				)
			)
		)
		(duplicate_pad_numbers_are_jumpers no)
		(fp_line
			(start -2.249932 -2.249932)
			(end 2.249932 -2.249932)
			(stroke
				(width 0.1524)
				(type default)
			)
			(layer "F.SilkS")
		)
		(fp_line
			(start -2.249932 -1.3843)
			(end -2.249932 -2.249932)
			(stroke
				(width 0.1524)
				(type default)
			)
			(layer "F.SilkS")
		)
		(fp_line
			(start -2.249932 2.249932)
			(end -2.249932 1.3843)
			(stroke
				(width 0.1524)
				(type default)
			)
			(layer "F.SilkS")
		)
		(fp_line
			(start 2.249932 -2.249932)
			(end 2.249932 -1.3843)
			(stroke
				(width 0.1524)
				(type default)
			)
			(layer "F.SilkS")
		)
		(fp_line
			(start 2.249932 1.3843)
			(end 2.249932 2.249932)
			(stroke
				(width 0.1524)
				(type default)
			)
			(layer "F.SilkS")
		)
		(fp_line
			(start 2.249932 2.249932)
			(end -2.249932 2.249932)
			(stroke
				(width 0.1524)
				(type default)
			)
			(layer "F.SilkS")
		)
		(fp_line
			(start -2.249932 -2.249932)
			(end 2.249932 -2.249932)
			(stroke
				(width 0.1)
				(type default)
			)
			(layer "F.Fab")
		)
		(fp_line
			(start -2.249932 2.249932)
			(end -2.249932 -2.249932)
			(stroke
				(width 0.1)
				(type default)
			)
			(layer "F.Fab")
		)
		(fp_line
			(start 2.249932 -2.249932)
			(end 2.249932 2.249932)
			(stroke
				(width 0.1)
				(type default)
			)
			(layer "F.Fab")
		)
		(fp_line
			(start 2.249932 2.249932)
			(end -2.249932 2.249932)
			(stroke
				(width 0.1)
				(type default)
			)
			(layer "F.Fab")
		)
		(pad "1" smd rect
			(at -1.82499 0)
			(size 1.0668 2.5146)
			(layers "F.Cu" "F.Mask" "F.Paste")
			(net "P12V_AUX")
		)
		(pad "2" smd rect
			(at 1.82499 0)
			(size 1.0668 2.5146)
			(layers "F.Cu" "F.Mask" "F.Paste")
			(net "SW_P12V_AUX_P1V05_PCH_AUX_FLT")
		)
	)
	(footprint ""
		(layer "F.Cu")
		(at 24.050752 -404.842218 180)
		(property "Reference" "C1974"
			(at 0 0 180)
			(layer "F.SilkS")
			(hide yes)
			(effects
				(font
					(size 1.27 1.27)
				)
			)
		)
		(property "Value" ""
			(at 0 0 180)
			(layer "F.Fab")
			(effects
				(font
					(size 1.27 1.27)
				)
			)
		)
		(duplicate_pad_numbers_are_jumpers no)
		(fp_line
			(start 0.7874 0.4064)
			(end -0.7874 0.4064)
			(stroke
				(width 0.1524)
				(type default)
			)
			(layer "F.SilkS")
		)
		(fp_line
			(start 0.7874 -0.4064)
			(end 0.7874 0.4064)
			(stroke
				(width 0.1524)
				(type default)
			)
			(layer "F.SilkS")
		)
		(fp_line
			(start -0.7874 0.4064)
			(end -0.7874 -0.4064)
			(stroke
				(width 0.1524)
				(type default)
			)
			(layer "F.SilkS")
		)
		(fp_line
			(start -0.7874 -0.4064)
			(end 0.7874 -0.4064)
			(stroke
				(width 0.1524)
				(type default)
			)
			(layer "F.SilkS")
		)
		(fp_line
			(start 0.67945 0.3048)
			(end 0.120396 0.3048)
			(stroke
				(width 0.1)
				(type default)
			)
			(layer "F.Fab")
		)
		(fp_line
			(start 0.67945 -0.3048)
			(end 0.67945 0.3048)
			(stroke
				(width 0.1)
				(type default)
			)
			(layer "F.Fab")
		)
		(fp_line
			(start 0.12065 -0.2794)
			(end 0.12065 -0.3048)
			(stroke
				(width 0.1)
				(type default)
			)
			(layer "F.Fab")
		)
		(fp_line
			(start 0.12065 -0.3048)
			(end 0.67945 -0.3048)
			(stroke
				(width 0.1)
				(type default)
			)
			(layer "F.Fab")
		)
		(fp_line
			(start 0.120396 0.3048)
			(end 0.120396 0.2794)
			(stroke
				(width 0.1)
				(type default)
			)
			(layer "F.Fab")
		)
		(fp_line
			(start 0.120396 0.2794)
			(end -0.12065 0.2794)
			(stroke
				(width 0.1)
				(type default)
			)
			(layer "F.Fab")
		)
		(fp_line
			(start -0.12065 0.3048)
			(end -0.67945 0.3048)
			(stroke
				(width 0.1)
				(type default)
			)
			(layer "F.Fab")
		)
		(fp_line
			(start -0.12065 0.2794)
			(end -0.12065 0.3048)
			(stroke
				(width 0.1)
				(type default)
			)
			(layer "F.Fab")
		)
		(fp_line
			(start -0.12065 -0.2794)
			(end 0.12065 -0.2794)
			(stroke
				(width 0.1)
				(type default)
			)
			(layer "F.Fab")
		)
		(fp_line
			(start -0.12065 -0.305054)
			(end -0.12065 -0.2794)
			(stroke
				(width 0.1)
				(type default)
			)
			(layer "F.Fab")
		)
		(fp_line
			(start -0.67945 0.3048)
			(end -0.67945 -0.305054)
			(stroke
				(width 0.1)
				(type default)
			)
			(layer "F.Fab")
		)
		(fp_line
			(start -0.67945 -0.305054)
			(end -0.12065 -0.305054)
			(stroke
				(width 0.1)
				(type default)
			)
			(layer "F.Fab")
		)
		(pad "1" smd circle
			(at -0.40005 0 180)
			(size 0 0)
			(layers "F.Cu" "F.Mask" "F.Paste")
			(net "GPU_FPGA_THERM_OVERT_ISO_N")
		)
		(pad "2" smd circle
			(at 0.40005 0 180)
			(size 0 0)
			(layers "F.Cu" "F.Mask" "F.Paste")
			(net "GND")
		)
	)
	(footprint ""
		(layer "F.Cu")
		(at 427.452028 -159.516318)
		(property "Reference" "PC208"
			(at 0 0 0)
			(layer "F.SilkS")
			(hide yes)
			(effects
				(font
					(size 1.27 1.27)
				)
			)
		)
		(property "Value" ""
			(at 0 0 0)
			(layer "F.Fab")
			(effects
				(font
					(size 1.27 1.27)
				)
			)
		)
		(duplicate_pad_numbers_are_jumpers no)
		(fp_line
			(start -3.400044 1.249934)
			(end 3.400044 1.249934)
			(stroke
				(width 0.1524)
				(type default)
			)
			(layer "F.SilkS")
		)
		(fp_circle
			(center 0 1.249934)
			(end 3.400044 1.249934)
			(stroke
				(width 0.1524)
				(type default)
			)
			(fill no)
			(layer "F.SilkS")
		)
		(fp_poly
			(pts
				(arc
					(start -3.400044 1.249934)
					(mid 0 4.649978)
					(end 3.400044 1.249934)
				)
			)
			(stroke
				(width 0)
				(type default)
			)
			(fill yes)
			(layer "F.SilkS")
		)
		(fp_circle
			(center 0 1.249934)
			(end 3.400044 1.249934)
			(stroke
				(width 0.1)
				(type default)
			)
			(fill no)
			(layer "F.Fab")
		)
		(pad "1" thru_hole rect
			(at 0 0)
			(size 1.524 1.524)
			(drill 1.016)
			(layers "*.Cu" "*.Mask")
			(remove_unused_layers no)
			(net "SW_P12V_PVCCINFAON_CPU0_FLT")
			(clearance 0)
			(padstack
				(mode front_inner_back)
				(layer "Inner"
					(shape circle)
					(size 1.524 1.524)
					(clearance 0)
				)
				(layer "B.Cu"
					(shape rect)
					(size 1.524 1.524)
					(clearance 0)
				)
			)
		)
		(pad "2" thru_hole circle
			(at 0 2.500122)
			(size 1.524 1.524)
			(drill 1.016)
			(layers "*.Cu" "*.Mask")
			(remove_unused_layers no)
			(net "GND")
			(clearance 0)
		)
	)
	(footprint ""
		(layer "F.Cu")
		(at 268.668246 -130.536696 180)
		(property "Reference" "U315"
			(at 1.132332 2.691892 0)
			(unlocked yes)
			(layer "F.SilkS")
			(effects
				(font
					(size 0.7874 0.5842)
					(thickness 0.1524)
				)
				(justify left)
			)
		)
		(property "Value" ""
			(at 0 0 180)
			(layer "F.Fab")
			(effects
				(font
					(size 1.27 1.27)
				)
			)
		)
		(duplicate_pad_numbers_are_jumpers no)
		(fp_line
			(start 1.463548 1.549908)
			(end -1.463548 1.549908)
			(stroke
				(width 0.1524)
				(type default)
			)
			(layer "F.SilkS")
		)
		(fp_line
			(start 1.463548 -1.549908)
			(end 1.463548 1.549908)
			(stroke
				(width 0.1524)
				(type default)
			)
			(layer "F.SilkS")
		)
		(fp_line
			(start 0.762 -1.549908)
			(end 1.463548 -1.549908)
			(stroke
				(width 0.1524)
				(type default)
			)
			(layer "F.SilkS")
		)
		(fp_line
			(start 0 -0.762)
			(end 0.762 -1.549908)
			(stroke
				(width 0.1524)
				(type default)
			)
			(layer "F.SilkS")
		)
		(fp_line
			(start -0.787908 -1.549908)
			(end 0 -0.762)
			(stroke
				(width 0.1524)
				(type default)
			)
			(layer "F.SilkS")
		)
		(fp_line
			(start -1.463548 1.549908)
			(end -1.463548 -1.549908)
			(stroke
				(width 0.1524)
				(type default)
			)
			(layer "F.SilkS")
		)
		(fp_line
			(start -1.463548 -1.549908)
			(end -0.787908 -1.549908)
			(stroke
				(width 0.1524)
				(type default)
			)
			(layer "F.SilkS")
		)
		(fp_poly
			(pts
				(xy -2.86004 -1.050036) (xy -3.4798 -0.740156) (xy -3.4798 -1.359916)
			)
			(stroke
				(width 0)
				(type default)
			)
			(fill yes)
			(layer "F.SilkS")
		)
		(fp_line
			(start 1.549908 1.549908)
			(end -1.549908 1.549908)
			(stroke
				(width 0.1)
				(type default)
			)
			(layer "F.Fab")
		)
		(fp_line
			(start 1.549908 -1.549908)
			(end 1.549908 1.549908)
			(stroke
				(width 0.1)
				(type default)
			)
			(layer "F.Fab")
		)
		(fp_line
			(start -1.549908 1.549908)
			(end -1.549908 -1.549908)
			(stroke
				(width 0.1)
				(type default)
			)
			(layer "F.Fab")
		)
		(fp_line
			(start -1.549908 -1.549908)
			(end 1.549908 -1.549908)
			(stroke
				(width 0.1)
				(type default)
			)
			(layer "F.Fab")
		)
		(fp_poly
			(pts
				(xy -3.4798 -1.359916) (xy -2.86004 -1.050036) (xy -3.4798 -0.740156)
			)
			(stroke
				(width 0)
				(type default)
			)
			(fill yes)
			(layer "F.Fab")
		)
		(pad "1" smd rect
			(at -2.175002 -1.050036 270)
			(size 0.6096 1.1684)
			(layers "F.Cu" "F.Mask" "F.Paste")
			(net "P3V3_AUX")
		)
		(pad "2" smd rect
			(at -2.175002 -0.32512 270)
			(size 0.4318 1.1684)
			(layers "F.Cu" "F.Mask" "F.Paste")
			(net "SMB_HOST_CLK_BUF_3V3AUX_SCL")
		)
		(pad "3" smd rect
			(at -2.175002 0.32512 270)
			(size 0.4318 1.1684)
			(layers "F.Cu" "F.Mask" "F.Paste")
			(net "SMB_HOST_CLK_BUF_3V3AUX_SDA")
		)
		(pad "4" smd rect
			(at -2.175002 1.050036 270)
			(size 0.6096 1.1684)
			(layers "F.Cu" "F.Mask" "F.Paste")
			(net "GND")
		)
		(pad "5" smd rect
			(at 2.175002 1.050036 270)
			(size 0.6096 1.1684)
			(layers "F.Cu" "F.Mask" "F.Paste")
			(net "PU_CLK_BUF_ISO_EN")
		)
		(pad "6" smd rect
			(at 2.175002 0.32512 270)
			(size 0.4318 1.1684)
			(layers "F.Cu" "F.Mask" "F.Paste")
			(net "SMB_HOST_CLK_BUF_ISO_3V3AUX_S_2")
		)
		(pad "7" smd rect
			(at 2.175002 -0.32512 270)
			(size 0.4318 1.1684)
			(layers "F.Cu" "F.Mask" "F.Paste")
			(net "SMB_HOST_CLK_BUF_ISO_3V3AUX_S_1")
		)
		(pad "8" smd rect
			(at 2.175002 -1.050036 270)
			(size 0.6096 1.1684)
			(layers "F.Cu" "F.Mask" "F.Paste")
			(net "P3V3")
		)
	)
	(footprint ""
		(layer "F.Cu")
		(at 131.466844 -128.516126 180)
		(property "Reference" "R2984"
			(at 0 0 180)
			(layer "F.SilkS")
			(hide yes)
			(effects
				(font
					(size 1.27 1.27)
				)
			)
		)
		(property "Value" ""
			(at 0 0 180)
			(layer "F.Fab")
			(effects
				(font
					(size 1.27 1.27)
				)
			)
		)
		(duplicate_pad_numbers_are_jumpers no)
		(fp_line
			(start 0.7874 0.4064)
			(end -0.7874 0.4064)
			(stroke
				(width 0.1524)
				(type default)
			)
			(layer "F.SilkS")
		)
		(fp_line
			(start 0.7874 -0.4064)
			(end 0.7874 0.4064)
			(stroke
				(width 0.1524)
				(type default)
			)
			(layer "F.SilkS")
		)
		(fp_line
			(start -0.7874 0.4064)
			(end -0.7874 -0.4064)
			(stroke
				(width 0.1524)
				(type default)
			)
			(layer "F.SilkS")
		)
		(fp_line
			(start -0.7874 -0.4064)
			(end 0.7874 -0.4064)
			(stroke
				(width 0.1524)
				(type default)
			)
			(layer "F.SilkS")
		)
		(fp_line
			(start 0.67945 0.3048)
			(end 0.120396 0.3048)
			(stroke
				(width 0.1)
				(type default)
			)
			(layer "F.Fab")
		)
		(fp_line
			(start 0.67945 -0.3048)
			(end 0.67945 0.3048)
			(stroke
				(width 0.1)
				(type default)
			)
			(layer "F.Fab")
		)
		(fp_line
			(start 0.12065 -0.2794)
			(end 0.12065 -0.3048)
			(stroke
				(width 0.1)
				(type default)
			)
			(layer "F.Fab")
		)
		(fp_line
			(start 0.12065 -0.3048)
			(end 0.67945 -0.3048)
			(stroke
				(width 0.1)
				(type default)
			)
			(layer "F.Fab")
		)
		(fp_line
			(start 0.120396 0.3048)
			(end 0.120396 0.2794)
			(stroke
				(width 0.1)
				(type default)
			)
			(layer "F.Fab")
		)
		(fp_line
			(start 0.120396 0.2794)
			(end -0.12065 0.2794)
			(stroke
				(width 0.1)
				(type default)
			)
			(layer "F.Fab")
		)
		(fp_line
			(start -0.12065 0.3048)
			(end -0.67945 0.3048)
			(stroke
				(width 0.1)
				(type default)
			)
			(layer "F.Fab")
		)
		(fp_line
			(start -0.12065 0.2794)
			(end -0.12065 0.3048)
			(stroke
				(width 0.1)
				(type default)
			)
			(layer "F.Fab")
		)
		(fp_line
			(start -0.12065 -0.2794)
			(end 0.12065 -0.2794)
			(stroke
				(width 0.1)
				(type default)
			)
			(layer "F.Fab")
		)
		(fp_line
			(start -0.12065 -0.305054)
			(end -0.12065 -0.2794)
			(stroke
				(width 0.1)
				(type default)
			)
			(layer "F.Fab")
		)
		(fp_line
			(start -0.67945 0.3048)
			(end -0.67945 -0.305054)
			(stroke
				(width 0.1)
				(type default)
			)
			(layer "F.Fab")
		)
		(fp_line
			(start -0.67945 -0.305054)
			(end -0.12065 -0.305054)
			(stroke
				(width 0.1)
				(type default)
			)
			(layer "F.Fab")
		)
		(pad "1" smd circle
			(at -0.40005 0 180)
			(size 0 0)
			(layers "F.Cu" "F.Mask" "F.Paste")
			(net "P3V3_AUX")
		)
		(pad "2" smd circle
			(at 0.40005 0 180)
			(size 0 0)
			(layers "F.Cu" "F.Mask" "F.Paste")
			(net "SMB_BMC_SWB_SCL")
		)
	)
	(footprint ""
		(layer "F.Cu")
		(at 124.64288 -92.674948 -90)
		(property "Reference" "R4396"
			(at 0 0 270)
			(layer "F.SilkS")
			(hide yes)
			(effects
				(font
					(size 1.27 1.27)
				)
			)
		)
		(property "Value" ""
			(at 0 0 270)
			(layer "F.Fab")
			(effects
				(font
					(size 1.27 1.27)
				)
			)
		)
		(duplicate_pad_numbers_are_jumpers no)
		(fp_line
			(start -0.7874 0.4064)
			(end -0.7874 -0.4064)
			(stroke
				(width 0.1524)
				(type default)
			)
			(layer "F.SilkS")
		)
		(fp_line
			(start 0.7874 0.4064)
			(end -0.7874 0.4064)
			(stroke
				(width 0.1524)
				(type default)
			)
			(layer "F.SilkS")
		)
		(fp_line
			(start -0.7874 -0.4064)
			(end 0.7874 -0.4064)
			(stroke
				(width 0.1524)
				(type default)
			)
			(layer "F.SilkS")
		)
		(fp_line
			(start 0.7874 -0.4064)
			(end 0.7874 0.4064)
			(stroke
				(width 0.1524)
				(type default)
			)
			(layer "F.SilkS")
		)
		(fp_line
			(start -0.67945 0.3048)
			(end -0.67945 -0.305054)
			(stroke
				(width 0.1)
				(type default)
			)
			(layer "F.Fab")
		)
		(fp_line
			(start -0.12065 0.3048)
			(end -0.67945 0.3048)
			(stroke
				(width 0.1)
				(type default)
			)
			(layer "F.Fab")
		)
		(fp_line
			(start 0.120396 0.3048)
			(end 0.120396 0.2794)
			(stroke
				(width 0.1)
				(type default)
			)
			(layer "F.Fab")
		)
		(fp_line
			(start 0.67945 0.3048)
			(end 0.120396 0.3048)
			(stroke
				(width 0.1)
				(type default)
			)
			(layer "F.Fab")
		)
		(fp_line
			(start -0.12065 0.2794)
			(end -0.12065 0.3048)
			(stroke
				(width 0.1)
				(type default)
			)
			(layer "F.Fab")
		)
		(fp_line
			(start 0.120396 0.2794)
			(end -0.12065 0.2794)
			(stroke
				(width 0.1)
				(type default)
			)
			(layer "F.Fab")
		)
		(fp_line
			(start -0.12065 -0.2794)
			(end 0.12065 -0.2794)
			(stroke
				(width 0.1)
				(type default)
			)
			(layer "F.Fab")
		)
		(fp_line
			(start 0.12065 -0.2794)
			(end 0.12065 -0.3048)
			(stroke
				(width 0.1)
				(type default)
			)
			(layer "F.Fab")
		)
		(fp_line
			(start 0.12065 -0.3048)
			(end 0.67945 -0.3048)
			(stroke
				(width 0.1)
				(type default)
			)
			(layer "F.Fab")
		)
		(fp_line
			(start 0.67945 -0.3048)
			(end 0.67945 0.3048)
			(stroke
				(width 0.1)
				(type default)
			)
			(layer "F.Fab")
		)
		(fp_line
			(start -0.67945 -0.305054)
			(end -0.12065 -0.305054)
			(stroke
				(width 0.1)
				(type default)
			)
			(layer "F.Fab")
		)
		(fp_line
			(start -0.12065 -0.305054)
			(end -0.12065 -0.2794)
			(stroke
				(width 0.1)
				(type default)
			)
			(layer "F.Fab")
		)
		(pad "1" smd circle
			(at -0.40005 0 270)
			(size 0 0)
			(layers "F.Cu" "F.Mask" "F.Paste")
			(net "PVNN_TERM_CPU1")
		)
		(pad "2" smd circle
			(at 0.40005 0 270)
			(size 0 0)
			(layers "F.Cu" "F.Mask" "F.Paste")
			(net "H_CPU1_THERMTRIP_LVC1_R_N")
		)
	)
	(footprint ""
		(layer "F.Cu")
		(at 28.532328 -99.586034)
		(property "Reference" "R3863"
			(at 0 0 0)
			(layer "F.SilkS")
			(hide yes)
			(effects
				(font
					(size 1.27 1.27)
				)
			)
		)
		(property "Value" ""
			(at 0 0 0)
			(layer "F.Fab")
			(effects
				(font
					(size 1.27 1.27)
				)
			)
		)
		(duplicate_pad_numbers_are_jumpers no)
		(fp_line
			(start -0.7874 -0.4064)
			(end 0.7874 -0.4064)
			(stroke
				(width 0.1524)
				(type default)
			)
			(layer "F.SilkS")
		)
		(fp_line
			(start -0.7874 0.4064)
			(end -0.7874 -0.4064)
			(stroke
				(width 0.1524)
				(type default)
			)
			(layer "F.SilkS")
		)
		(fp_line
			(start 0.7874 -0.4064)
			(end 0.7874 0.4064)
			(stroke
				(width 0.1524)
				(type default)
			)
			(layer "F.SilkS")
		)
		(fp_line
			(start 0.7874 0.4064)
			(end -0.7874 0.4064)
			(stroke
				(width 0.1524)
				(type default)
			)
			(layer "F.SilkS")
		)
		(fp_line
			(start -0.67945 -0.305054)
			(end -0.12065 -0.305054)
			(stroke
				(width 0.1)
				(type default)
			)
			(layer "F.Fab")
		)
		(fp_line
			(start -0.67945 0.3048)
			(end -0.67945 -0.305054)
			(stroke
				(width 0.1)
				(type default)
			)
			(layer "F.Fab")
		)
		(fp_line
			(start -0.12065 -0.305054)
			(end -0.12065 -0.2794)
			(stroke
				(width 0.1)
				(type default)
			)
			(layer "F.Fab")
		)
		(fp_line
			(start -0.12065 -0.2794)
			(end 0.12065 -0.2794)
			(stroke
				(width 0.1)
				(type default)
			)
			(layer "F.Fab")
		)
		(fp_line
			(start -0.12065 0.2794)
			(end -0.12065 0.3048)
			(stroke
				(width 0.1)
				(type default)
			)
			(layer "F.Fab")
		)
		(fp_line
			(start -0.12065 0.3048)
			(end -0.67945 0.3048)
			(stroke
				(width 0.1)
				(type default)
			)
			(layer "F.Fab")
		)
		(fp_line
			(start 0.120396 0.2794)
			(end -0.12065 0.2794)
			(stroke
				(width 0.1)
				(type default)
			)
			(layer "F.Fab")
		)
		(fp_line
			(start 0.120396 0.3048)
			(end 0.120396 0.2794)
			(stroke
				(width 0.1)
				(type default)
			)
			(layer "F.Fab")
		)
		(fp_line
			(start 0.12065 -0.3048)
			(end 0.67945 -0.3048)
			(stroke
				(width 0.1)
				(type default)
			)
			(layer "F.Fab")
		)
		(fp_line
			(start 0.12065 -0.2794)
			(end 0.12065 -0.3048)
			(stroke
				(width 0.1)
				(type default)
			)
			(layer "F.Fab")
		)
		(fp_line
			(start 0.67945 -0.3048)
			(end 0.67945 0.3048)
			(stroke
				(width 0.1)
				(type default)
			)
			(layer "F.Fab")
		)
		(fp_line
			(start 0.67945 0.3048)
			(end 0.120396 0.3048)
			(stroke
				(width 0.1)
				(type default)
			)
			(layer "F.Fab")
		)
		(pad "1" smd rect
			(at -0.40005 0 180)
			(size 0.4572 0.508)
			(layers "F.Cu" "F.Mask" "F.Paste")
			(net "P12V_OCP_SFF_ISENSE_MAM_MAM")
		)
		(pad "2" smd rect
			(at 0.40005 0 180)
			(size 0.4572 0.508)
			(layers "F.Cu" "F.Mask" "F.Paste")
			(net "P12V_OCP_SFF_ISENSE_MAM")
		)
	)
	(footprint ""
		(layer "F.Cu")
		(at 90.086688 -65.193672 -90)
		(property "Reference" "R3069"
			(at 0 0 270)
			(layer "F.SilkS")
			(hide yes)
			(effects
				(font
					(size 1.27 1.27)
				)
			)
		)
		(property "Value" ""
			(at 0 0 270)
			(layer "F.Fab")
			(effects
				(font
					(size 1.27 1.27)
				)
			)
		)
		(duplicate_pad_numbers_are_jumpers no)
		(fp_line
			(start -0.7874 0.4064)
			(end -0.7874 -0.4064)
			(stroke
				(width 0.1524)
				(type default)
			)
			(layer "F.SilkS")
		)
		(fp_line
			(start 0.7874 0.4064)
			(end -0.7874 0.4064)
			(stroke
				(width 0.1524)
				(type default)
			)
			(layer "F.SilkS")
		)
		(fp_line
			(start -0.7874 -0.4064)
			(end 0.7874 -0.4064)
			(stroke
				(width 0.1524)
				(type default)
			)
			(layer "F.SilkS")
		)
		(fp_line
			(start 0.7874 -0.4064)
			(end 0.7874 0.4064)
			(stroke
				(width 0.1524)
				(type default)
			)
			(layer "F.SilkS")
		)
		(fp_line
			(start -0.67945 0.3048)
			(end -0.67945 -0.305054)
			(stroke
				(width 0.1)
				(type default)
			)
			(layer "F.Fab")
		)
		(fp_line
			(start -0.12065 0.3048)
			(end -0.67945 0.3048)
			(stroke
				(width 0.1)
				(type default)
			)
			(layer "F.Fab")
		)
		(fp_line
			(start 0.120396 0.3048)
			(end 0.120396 0.2794)
			(stroke
				(width 0.1)
				(type default)
			)
			(layer "F.Fab")
		)
		(fp_line
			(start 0.67945 0.3048)
			(end 0.120396 0.3048)
			(stroke
				(width 0.1)
				(type default)
			)
			(layer "F.Fab")
		)
		(fp_line
			(start -0.12065 0.2794)
			(end -0.12065 0.3048)
			(stroke
				(width 0.1)
				(type default)
			)
			(layer "F.Fab")
		)
		(fp_line
			(start 0.120396 0.2794)
			(end -0.12065 0.2794)
			(stroke
				(width 0.1)
				(type default)
			)
			(layer "F.Fab")
		)
		(fp_line
			(start -0.12065 -0.2794)
			(end 0.12065 -0.2794)
			(stroke
				(width 0.1)
				(type default)
			)
			(layer "F.Fab")
		)
		(fp_line
			(start 0.12065 -0.2794)
			(end 0.12065 -0.3048)
			(stroke
				(width 0.1)
				(type default)
			)
			(layer "F.Fab")
		)
		(fp_line
			(start 0.12065 -0.3048)
			(end 0.67945 -0.3048)
			(stroke
				(width 0.1)
				(type default)
			)
			(layer "F.Fab")
		)
		(fp_line
			(start 0.67945 -0.3048)
			(end 0.67945 0.3048)
			(stroke
				(width 0.1)
				(type default)
			)
			(layer "F.Fab")
		)
		(fp_line
			(start -0.67945 -0.305054)
			(end -0.12065 -0.305054)
			(stroke
				(width 0.1)
				(type default)
			)
			(layer "F.Fab")
		)
		(fp_line
			(start -0.12065 -0.305054)
			(end -0.12065 -0.2794)
			(stroke
				(width 0.1)
				(type default)
			)
			(layer "F.Fab")
		)
		(pad "1" smd circle
			(at -0.40005 0 270)
			(size 0 0)
			(layers "F.Cu" "F.Mask" "F.Paste")
			(net "LED_PWRGD_SYS_PWROK_R")
		)
		(pad "2" smd circle
			(at 0.40005 0 270)
			(size 0 0)
			(layers "F.Cu" "F.Mask" "F.Paste")
			(net "P3V3_AUX")
		)
	)
	(footprint ""
		(layer "F.Cu")
		(at 148.197824 -52.420012)
		(property "Reference" "R3623"
			(at 0 0 0)
			(layer "F.SilkS")
			(hide yes)
			(effects
				(font
					(size 1.27 1.27)
				)
			)
		)
		(property "Value" ""
			(at 0 0 0)
			(layer "F.Fab")
			(effects
				(font
					(size 1.27 1.27)
				)
			)
		)
		(duplicate_pad_numbers_are_jumpers no)
		(fp_line
			(start -0.7874 -0.4064)
			(end 0.7874 -0.4064)
			(stroke
				(width 0.1524)
				(type default)
			)
			(layer "F.SilkS")
		)
		(fp_line
			(start -0.7874 0.4064)
			(end -0.7874 -0.4064)
			(stroke
				(width 0.1524)
				(type default)
			)
			(layer "F.SilkS")
		)
		(fp_line
			(start 0.7874 -0.4064)
			(end 0.7874 0.4064)
			(stroke
				(width 0.1524)
				(type default)
			)
			(layer "F.SilkS")
		)
		(fp_line
			(start 0.7874 0.4064)
			(end -0.7874 0.4064)
			(stroke
				(width 0.1524)
				(type default)
			)
			(layer "F.SilkS")
		)
		(fp_line
			(start -0.67945 -0.305054)
			(end -0.12065 -0.305054)
			(stroke
				(width 0.1)
				(type default)
			)
			(layer "F.Fab")
		)
		(fp_line
			(start -0.67945 0.3048)
			(end -0.67945 -0.305054)
			(stroke
				(width 0.1)
				(type default)
			)
			(layer "F.Fab")
		)
		(fp_line
			(start -0.12065 -0.305054)
			(end -0.12065 -0.2794)
			(stroke
				(width 0.1)
				(type default)
			)
			(layer "F.Fab")
		)
		(fp_line
			(start -0.12065 -0.2794)
			(end 0.12065 -0.2794)
			(stroke
				(width 0.1)
				(type default)
			)
			(layer "F.Fab")
		)
		(fp_line
			(start -0.12065 0.2794)
			(end -0.12065 0.3048)
			(stroke
				(width 0.1)
				(type default)
			)
			(layer "F.Fab")
		)
		(fp_line
			(start -0.12065 0.3048)
			(end -0.67945 0.3048)
			(stroke
				(width 0.1)
				(type default)
			)
			(layer "F.Fab")
		)
		(fp_line
			(start 0.120396 0.2794)
			(end -0.12065 0.2794)
			(stroke
				(width 0.1)
				(type default)
			)
			(layer "F.Fab")
		)
		(fp_line
			(start 0.120396 0.3048)
			(end 0.120396 0.2794)
			(stroke
				(width 0.1)
				(type default)
			)
			(layer "F.Fab")
		)
		(fp_line
			(start 0.12065 -0.3048)
			(end 0.67945 -0.3048)
			(stroke
				(width 0.1)
				(type default)
			)
			(layer "F.Fab")
		)
		(fp_line
			(start 0.12065 -0.2794)
			(end 0.12065 -0.3048)
			(stroke
				(width 0.1)
				(type default)
			)
			(layer "F.Fab")
		)
		(fp_line
			(start 0.67945 -0.3048)
			(end 0.67945 0.3048)
			(stroke
				(width 0.1)
				(type default)
			)
			(layer "F.Fab")
		)
		(fp_line
			(start 0.67945 0.3048)
			(end 0.120396 0.3048)
			(stroke
				(width 0.1)
				(type default)
			)
			(layer "F.Fab")
		)
		(pad "1" smd circle
			(at -0.40005 0)
			(size 0 0)
			(layers "F.Cu" "F.Mask" "F.Paste")
			(net "P3V3_AUX")
		)
		(pad "2" smd circle
			(at 0.40005 0)
			(size 0 0)
			(layers "F.Cu" "F.Mask" "F.Paste")
			(net "INA230_4_A1")
		)
	)
	(footprint ""
		(layer "F.Cu")
		(at 19.769582 -423.629836 -90)
		(property "Reference" "R3499"
			(at 0 0 270)
			(layer "F.SilkS")
			(hide yes)
			(effects
				(font
					(size 1.27 1.27)
				)
			)
		)
		(property "Value" ""
			(at 0 0 270)
			(layer "F.Fab")
			(effects
				(font
					(size 1.27 1.27)
				)
			)
		)
		(duplicate_pad_numbers_are_jumpers no)
		(fp_line
			(start -0.7874 0.4064)
			(end -0.7874 -0.4064)
			(stroke
				(width 0.1524)
				(type default)
			)
			(layer "F.SilkS")
		)
		(fp_line
			(start 0.7874 0.4064)
			(end -0.7874 0.4064)
			(stroke
				(width 0.1524)
				(type default)
			)
			(layer "F.SilkS")
		)
		(fp_line
			(start -0.7874 -0.4064)
			(end 0.7874 -0.4064)
			(stroke
				(width 0.1524)
				(type default)
			)
			(layer "F.SilkS")
		)
		(fp_line
			(start 0.7874 -0.4064)
			(end 0.7874 0.4064)
			(stroke
				(width 0.1524)
				(type default)
			)
			(layer "F.SilkS")
		)
		(fp_line
			(start -0.67945 0.3048)
			(end -0.67945 -0.305054)
			(stroke
				(width 0.1)
				(type default)
			)
			(layer "F.Fab")
		)
		(fp_line
			(start -0.12065 0.3048)
			(end -0.67945 0.3048)
			(stroke
				(width 0.1)
				(type default)
			)
			(layer "F.Fab")
		)
		(fp_line
			(start 0.120396 0.3048)
			(end 0.120396 0.2794)
			(stroke
				(width 0.1)
				(type default)
			)
			(layer "F.Fab")
		)
		(fp_line
			(start 0.67945 0.3048)
			(end 0.120396 0.3048)
			(stroke
				(width 0.1)
				(type default)
			)
			(layer "F.Fab")
		)
		(fp_line
			(start -0.12065 0.2794)
			(end -0.12065 0.3048)
			(stroke
				(width 0.1)
				(type default)
			)
			(layer "F.Fab")
		)
		(fp_line
			(start 0.120396 0.2794)
			(end -0.12065 0.2794)
			(stroke
				(width 0.1)
				(type default)
			)
			(layer "F.Fab")
		)
		(fp_line
			(start -0.12065 -0.2794)
			(end 0.12065 -0.2794)
			(stroke
				(width 0.1)
				(type default)
			)
			(layer "F.Fab")
		)
		(fp_line
			(start 0.12065 -0.2794)
			(end 0.12065 -0.3048)
			(stroke
				(width 0.1)
				(type default)
			)
			(layer "F.Fab")
		)
		(fp_line
			(start 0.12065 -0.3048)
			(end 0.67945 -0.3048)
			(stroke
				(width 0.1)
				(type default)
			)
			(layer "F.Fab")
		)
		(fp_line
			(start 0.67945 -0.3048)
			(end 0.67945 0.3048)
			(stroke
				(width 0.1)
				(type default)
			)
			(layer "F.Fab")
		)
		(fp_line
			(start -0.67945 -0.305054)
			(end -0.12065 -0.305054)
			(stroke
				(width 0.1)
				(type default)
			)
			(layer "F.Fab")
		)
		(fp_line
			(start -0.12065 -0.305054)
			(end -0.12065 -0.2794)
			(stroke
				(width 0.1)
				(type default)
			)
			(layer "F.Fab")
		)
		(pad "1" smd circle
			(at -0.40005 0 270)
			(size 0 0)
			(layers "F.Cu" "F.Mask" "F.Paste")
			(net "GPU_BASE_ID1")
		)
		(pad "2" smd circle
			(at 0.40005 0 270)
			(size 0 0)
			(layers "F.Cu" "F.Mask" "F.Paste")
			(net "GPU_BASE_ID1_R")
		)
	)
	(footprint ""
		(layer "F.Cu")
		(at 377.541282 -59.295792 180)
		(property "Reference" "R747"
			(at 0 0 180)
			(layer "F.SilkS")
			(hide yes)
			(effects
				(font
					(size 1.27 1.27)
				)
			)
		)
		(property "Value" ""
			(at 0 0 180)
			(layer "F.Fab")
			(effects
				(font
					(size 1.27 1.27)
				)
			)
		)
		(duplicate_pad_numbers_are_jumpers no)
		(fp_line
			(start 0.7874 0.4064)
			(end -0.7874 0.4064)
			(stroke
				(width 0.1524)
				(type default)
			)
			(layer "F.SilkS")
		)
		(fp_line
			(start 0.7874 -0.4064)
			(end 0.7874 0.4064)
			(stroke
				(width 0.1524)
				(type default)
			)
			(layer "F.SilkS")
		)
		(fp_line
			(start -0.7874 0.4064)
			(end -0.7874 -0.4064)
			(stroke
				(width 0.1524)
				(type default)
			)
			(layer "F.SilkS")
		)
		(fp_line
			(start -0.7874 -0.4064)
			(end 0.7874 -0.4064)
			(stroke
				(width 0.1524)
				(type default)
			)
			(layer "F.SilkS")
		)
		(fp_line
			(start 0.67945 0.3048)
			(end 0.120396 0.3048)
			(stroke
				(width 0.1)
				(type default)
			)
			(layer "F.Fab")
		)
		(fp_line
			(start 0.67945 -0.3048)
			(end 0.67945 0.3048)
			(stroke
				(width 0.1)
				(type default)
			)
			(layer "F.Fab")
		)
		(fp_line
			(start 0.12065 -0.2794)
			(end 0.12065 -0.3048)
			(stroke
				(width 0.1)
				(type default)
			)
			(layer "F.Fab")
		)
		(fp_line
			(start 0.12065 -0.3048)
			(end 0.67945 -0.3048)
			(stroke
				(width 0.1)
				(type default)
			)
			(layer "F.Fab")
		)
		(fp_line
			(start 0.120396 0.3048)
			(end 0.120396 0.2794)
			(stroke
				(width 0.1)
				(type default)
			)
			(layer "F.Fab")
		)
		(fp_line
			(start 0.120396 0.2794)
			(end -0.12065 0.2794)
			(stroke
				(width 0.1)
				(type default)
			)
			(layer "F.Fab")
		)
		(fp_line
			(start -0.12065 0.3048)
			(end -0.67945 0.3048)
			(stroke
				(width 0.1)
				(type default)
			)
			(layer "F.Fab")
		)
		(fp_line
			(start -0.12065 0.2794)
			(end -0.12065 0.3048)
			(stroke
				(width 0.1)
				(type default)
			)
			(layer "F.Fab")
		)
		(fp_line
			(start -0.12065 -0.2794)
			(end 0.12065 -0.2794)
			(stroke
				(width 0.1)
				(type default)
			)
			(layer "F.Fab")
		)
		(fp_line
			(start -0.12065 -0.305054)
			(end -0.12065 -0.2794)
			(stroke
				(width 0.1)
				(type default)
			)
			(layer "F.Fab")
		)
		(fp_line
			(start -0.67945 0.3048)
			(end -0.67945 -0.305054)
			(stroke
				(width 0.1)
				(type default)
			)
			(layer "F.Fab")
		)
		(fp_line
			(start -0.67945 -0.305054)
			(end -0.12065 -0.305054)
			(stroke
				(width 0.1)
				(type default)
			)
			(layer "F.Fab")
		)
		(pad "1" smd circle
			(at -0.40005 0 180)
			(size 0 0)
			(layers "F.Cu" "F.Mask" "F.Paste")
			(net "P1V05_PCH_AUX")
		)
		(pad "2" smd circle
			(at 0.40005 0 180)
			(size 0 0)
			(layers "F.Cu" "F.Mask" "F.Paste")
			(net "JTAG_DBP_TDO_PCH")
		)
	)
	(footprint ""
		(layer "F.Cu")
		(at 232.176066 -402.722842 180)
		(property "Reference" "PU297"
			(at 0.384556 7.701788 0)
			(unlocked yes)
			(layer "F.SilkS")
			(effects
				(font
					(size 0.7874 0.5842)
					(thickness 0.1524)
				)
			)
		)
		(property "Value" ""
			(at 0 0 180)
			(layer "F.Fab")
			(effects
				(font
					(size 1.27 1.27)
				)
			)
		)
		(duplicate_pad_numbers_are_jumpers no)
		(fp_line
			(start 2.567686 2.567686)
			(end 2.567686 -2.567686)
			(stroke
				(width 0.1524)
				(type default)
			)
			(layer "F.SilkS")
		)
		(fp_line
			(start 2.567686 -2.567686)
			(end -2.567686 -2.567686)
			(stroke
				(width 0.1524)
				(type default)
			)
			(layer "F.SilkS")
		)
		(fp_line
			(start -2.567686 2.567686)
			(end 2.567686 2.567686)
			(stroke
				(width 0.1524)
				(type default)
			)
			(layer "F.SilkS")
		)
		(fp_line
			(start -2.567686 -2.567686)
			(end -2.567686 2.567686)
			(stroke
				(width 0.1524)
				(type default)
			)
			(layer "F.SilkS")
		)
		(fp_poly
			(pts
				(xy -3.429 -3.101594) (xy -3.06959 -2.024126) (xy -4.147312 -2.383282)
			)
			(stroke
				(width 0)
				(type default)
			)
			(fill yes)
			(layer "F.SilkS")
		)
		(fp_line
			(start 2.549906 2.549906)
			(end 2.549906 -2.549906)
			(stroke
				(width 0.1)
				(type default)
			)
			(layer "F.Fab")
		)
		(fp_line
			(start 2.549906 -2.549906)
			(end -2.549906 -2.549906)
			(stroke
				(width 0.1)
				(type default)
			)
			(layer "F.Fab")
		)
		(fp_line
			(start -2.549906 2.549906)
			(end 2.549906 2.549906)
			(stroke
				(width 0.1)
				(type default)
			)
			(layer "F.Fab")
		)
		(fp_line
			(start -2.549906 -2.549906)
			(end -2.549906 2.549906)
			(stroke
				(width 0.1)
				(type default)
			)
			(layer "F.Fab")
		)
		(fp_poly
			(pts
				(xy -3.806698 -2.25806) (xy -3.806698 -1.24206) (xy -2.790698 -1.75006)
			)
			(stroke
				(width 0)
				(type default)
			)
			(fill yes)
			(layer "F.Fab")
		)
		(pad "1" smd rect
			(at -2.250186 -1.75006 270)
			(size 0.254 0.3556)
			(layers "F.Cu" "F.Mask" "F.Paste")
			(net "P12V_AUX")
		)
		(pad "2" smd rect
			(at -2.237486 -1.249934 270)
			(size 0.254 0.381)
			(layers "F.Cu" "F.Mask" "F.Paste")
			(net "P12V_AUX")
		)
		(pad "3" smd rect
			(at -2.237486 -0.750062 270)
			(size 0.254 0.381)
			(layers "F.Cu" "F.Mask" "F.Paste")
			(net "HSC_D_OC_4")
		)
		(pad "4" smd rect
			(at -2.237486 -0.249936 270)
			(size 0.254 0.381)
			(layers "F.Cu" "F.Mask" "F.Paste")
			(net "HSC_ON")
		)
		(pad "5" smd rect
			(at -2.237486 0.249936 270)
			(size 0.254 0.381)
			(layers "F.Cu" "F.Mask" "F.Paste")
			(net "HSC_FAULT")
		)
		(pad "6" smd rect
			(at -2.237486 0.750062 270)
			(size 0.254 0.381)
			(layers "F.Cu" "F.Mask" "F.Paste")
			(net "HSC_FLT_TYPE_4")
		)
		(pad "7" smd rect
			(at -2.237486 1.249934 270)
			(size 0.254 0.381)
			(layers "F.Cu" "F.Mask" "F.Paste")
			(net "HSC_NC1_4")
		)
		(pad "8" smd rect
			(at -2.250186 1.75006 270)
			(size 0.254 0.3556)
			(layers "F.Cu" "F.Mask" "F.Paste")
			(net "HSC_MODE_4")
		)
		(pad "9" smd rect
			(at -1.75006 2.250186 180)
			(size 0.254 0.3556)
			(layers "F.Cu" "F.Mask" "F.Paste")
			(net "P12V_PSU")
		)
		(pad "10" smd rect
			(at -1.249934 2.237486 180)
			(size 0.254 0.381)
			(layers "F.Cu" "F.Mask" "F.Paste")
			(net "P12V_PSU")
		)
		(pad "11" smd rect
			(at -0.750062 2.237486 180)
			(size 0.254 0.381)
			(layers "F.Cu" "F.Mask" "F.Paste")
			(net "P12V_PSU")
		)
		(pad "12" smd rect
			(at -0.249936 2.237486 180)
			(size 0.254 0.381)
			(layers "F.Cu" "F.Mask" "F.Paste")
			(net "P12V_PSU")
		)
		(pad "13" smd rect
			(at 0.249936 2.237486 180)
			(size 0.254 0.381)
			(layers "F.Cu" "F.Mask" "F.Paste")
			(net "P12V_PSU")
		)
		(pad "14" smd rect
			(at 0.750062 2.237486 180)
			(size 0.254 0.381)
			(layers "F.Cu" "F.Mask" "F.Paste")
			(net "P12V_PSU")
		)
		(pad "15" smd rect
			(at 1.249934 2.237486 180)
			(size 0.254 0.381)
			(layers "F.Cu" "F.Mask" "F.Paste")
			(net "P12V_PSU")
		)
		(pad "16" smd rect
			(at 1.75006 2.250186 180)
			(size 0.254 0.3556)
			(layers "F.Cu" "F.Mask" "F.Paste")
			(net "P12V_PSU")
		)
		(pad "17" smd rect
			(at 2.250186 1.75006 270)
			(size 0.254 0.3556)
			(layers "F.Cu" "F.Mask" "F.Paste")
			(net "HSC_SCREF_4")
		)
		(pad "18" smd rect
			(at 2.237486 1.249934 270)
			(size 0.254 0.381)
			(layers "F.Cu" "F.Mask" "F.Paste")
			(net "HSC_VTEMP")
		)
		(pad "19" smd rect
			(at 2.237486 0.750062 270)
			(size 0.254 0.381)
			(layers "F.Cu" "F.Mask" "F.Paste")
			(net "HSC_SS")
		)
		(pad "20" smd rect
			(at 2.237486 0.249936 270)
			(size 0.254 0.381)
			(layers "F.Cu" "F.Mask" "F.Paste")
			(net "AGND_HSC")
		)
		(pad "21" smd rect
			(at 2.237486 -0.249936 270)
			(size 0.254 0.381)
			(layers "F.Cu" "F.Mask" "F.Paste")
			(net "HSC_VDD_R_4")
		)
		(pad "22" smd rect
			(at 2.237486 -0.750062 270)
			(size 0.254 0.381)
			(layers "F.Cu" "F.Mask" "F.Paste")
			(net "HSC_IMON")
		)
		(pad "23" smd rect
			(at 2.237486 -1.249934 270)
			(size 0.254 0.381)
			(layers "F.Cu" "F.Mask" "F.Paste")
			(net "HSC_CS_4")
		)
		(pad "24" smd rect
			(at 2.250186 -1.75006 270)
			(size 0.254 0.3556)
			(layers "F.Cu" "F.Mask" "F.Paste")
			(net "HSC_OCREF")
		)
		(pad "25" smd rect
			(at 1.75006 -2.250186 180)
			(size 0.254 0.3556)
			(layers "F.Cu" "F.Mask" "F.Paste")
			(net "P12V_AUX")
		)
		(pad "26" smd rect
			(at 1.249934 -2.237486 180)
			(size 0.254 0.381)
			(layers "F.Cu" "F.Mask" "F.Paste")
			(net "P12V_AUX")
		)
		(pad "27" smd rect
			(at 0.750062 -2.237486 180)
			(size 0.254 0.381)
			(layers "F.Cu" "F.Mask" "F.Paste")
			(net "P12V_AUX")
		)
		(pad "28" smd rect
			(at 0.249936 -2.237486 180)
			(size 0.254 0.381)
			(layers "F.Cu" "F.Mask" "F.Paste")
			(net "P12V_AUX")
		)
		(pad "29" smd rect
			(at -0.249936 -2.237486 180)
			(size 0.254 0.381)
			(layers "F.Cu" "F.Mask" "F.Paste")
			(net "P12V_AUX")
		)
		(pad "30" smd rect
			(at -0.750062 -2.237486 180)
			(size 0.254 0.381)
			(layers "F.Cu" "F.Mask" "F.Paste")
			(net "P12V_AUX")
		)
		(pad "31" smd rect
			(at -1.249934 -2.237486 180)
			(size 0.254 0.381)
			(layers "F.Cu" "F.Mask" "F.Paste")
			(net "P12V_AUX")
		)
		(pad "32" smd rect
			(at -1.75006 -2.250186 180)
			(size 0.254 0.3556)
			(layers "F.Cu" "F.Mask" "F.Paste")
			(net "P12V_AUX")
		)
		(pad "33" smd rect
			(at 0 0 180)
			(size 3.4036 3.4036)
			(layers "F.Cu" "F.Mask" "F.Paste")
			(net "P12V_PSU")
		)
		(zone
			(layer "F.Cu")
			(hatch none 0.5)
			(connect_pads
				(clearance 0)
			)
			(min_thickness 0.25)
			(keepout
				(tracks not_allowed)
				(vias allowed)
				(pads allowed)
				(copperpour not_allowed)
				(footprints allowed)
			)
			(placement
				(enabled no)
				(sheetname "")
			)
			(fill
				(thermal_gap 0.5)
				(thermal_bridge_width 0.5)
				(island_removal_mode 0)
			)
			(polygon
				(pts
					(xy 234.197652 -401.275042) (xy 234.197652 -400.825208) (xy 234.0737 -400.701256) (xy 233.623866 -400.701256)
					(xy 233.623866 -400.726656) (xy 230.728266 -400.726656) (xy 230.728266 -400.701256) (xy 230.15448 -400.701256)
					(xy 230.15448 -401.275042) (xy 230.17988 -401.275042) (xy 230.17988 -404.170642) (xy 230.15448 -404.170642)
					(xy 230.15448 -404.475442) (xy 230.423466 -404.475442) (xy 230.423466 -400.970242) (xy 233.928666 -400.970242)
					(xy 233.928666 -403.230842) (xy 234.172252 -403.230842) (xy 234.172252 -401.275042)
				)
			)
		)
	)
	(footprint ""
		(layer "F.Cu")
		(at 185.22188 -126.964948 -90)
		(property "Reference" "R270"
			(at 0 0 270)
			(layer "F.SilkS")
			(hide yes)
			(effects
				(font
					(size 1.27 1.27)
				)
			)
		)
		(property "Value" ""
			(at 0 0 270)
			(layer "F.Fab")
			(effects
				(font
					(size 1.27 1.27)
				)
			)
		)
		(duplicate_pad_numbers_are_jumpers no)
		(fp_line
			(start -0.7874 0.4064)
			(end -0.7874 -0.4064)
			(stroke
				(width 0.1524)
				(type default)
			)
			(layer "F.SilkS")
		)
		(fp_line
			(start 0.7874 0.4064)
			(end -0.7874 0.4064)
			(stroke
				(width 0.1524)
				(type default)
			)
			(layer "F.SilkS")
		)
		(fp_line
			(start -0.7874 -0.4064)
			(end 0.7874 -0.4064)
			(stroke
				(width 0.1524)
				(type default)
			)
			(layer "F.SilkS")
		)
		(fp_line
			(start 0.7874 -0.4064)
			(end 0.7874 0.4064)
			(stroke
				(width 0.1524)
				(type default)
			)
			(layer "F.SilkS")
		)
		(fp_line
			(start -0.67945 0.3048)
			(end -0.67945 -0.305054)
			(stroke
				(width 0.1)
				(type default)
			)
			(layer "F.Fab")
		)
		(fp_line
			(start -0.12065 0.3048)
			(end -0.67945 0.3048)
			(stroke
				(width 0.1)
				(type default)
			)
			(layer "F.Fab")
		)
		(fp_line
			(start 0.120396 0.3048)
			(end 0.120396 0.2794)
			(stroke
				(width 0.1)
				(type default)
			)
			(layer "F.Fab")
		)
		(fp_line
			(start 0.67945 0.3048)
			(end 0.120396 0.3048)
			(stroke
				(width 0.1)
				(type default)
			)
			(layer "F.Fab")
		)
		(fp_line
			(start -0.12065 0.2794)
			(end -0.12065 0.3048)
			(stroke
				(width 0.1)
				(type default)
			)
			(layer "F.Fab")
		)
		(fp_line
			(start 0.120396 0.2794)
			(end -0.12065 0.2794)
			(stroke
				(width 0.1)
				(type default)
			)
			(layer "F.Fab")
		)
		(fp_line
			(start -0.12065 -0.2794)
			(end 0.12065 -0.2794)
			(stroke
				(width 0.1)
				(type default)
			)
			(layer "F.Fab")
		)
		(fp_line
			(start 0.12065 -0.2794)
			(end 0.12065 -0.3048)
			(stroke
				(width 0.1)
				(type default)
			)
			(layer "F.Fab")
		)
		(fp_line
			(start 0.12065 -0.3048)
			(end 0.67945 -0.3048)
			(stroke
				(width 0.1)
				(type default)
			)
			(layer "F.Fab")
		)
		(fp_line
			(start 0.67945 -0.3048)
			(end 0.67945 0.3048)
			(stroke
				(width 0.1)
				(type default)
			)
			(layer "F.Fab")
		)
		(fp_line
			(start -0.67945 -0.305054)
			(end -0.12065 -0.305054)
			(stroke
				(width 0.1)
				(type default)
			)
			(layer "F.Fab")
		)
		(fp_line
			(start -0.12065 -0.305054)
			(end -0.12065 -0.2794)
			(stroke
				(width 0.1)
				(type default)
			)
			(layer "F.Fab")
		)
		(pad "1" smd circle
			(at -0.40005 0 270)
			(size 0 0)
			(layers "F.Cu" "F.Mask" "F.Paste")
			(net "P3V3_AUX")
		)
		(pad "2" smd circle
			(at 0.40005 0 270)
			(size 0 0)
			(layers "F.Cu" "F.Mask" "F.Paste")
			(net "FM_CPU1_PKGID0")
		)
	)
	(footprint ""
		(layer "F.Cu")
		(at 40.306498 -182.28564 180)
		(property "Reference" "C1404"
			(at 0 0 180)
			(layer "F.SilkS")
			(hide yes)
			(effects
				(font
					(size 1.27 1.27)
				)
			)
		)
		(property "Value" ""
			(at 0 0 180)
			(layer "F.Fab")
			(effects
				(font
					(size 1.27 1.27)
				)
			)
		)
		(duplicate_pad_numbers_are_jumpers no)
		(fp_line
			(start 1.524 0.762)
			(end -1.524 0.762)
			(stroke
				(width 0.1524)
				(type default)
			)
			(layer "F.SilkS")
		)
		(fp_line
			(start 1.524 -0.762)
			(end 1.524 0.762)
			(stroke
				(width 0.1524)
				(type default)
			)
			(layer "F.SilkS")
		)
		(fp_line
			(start -1.524 0.762)
			(end -1.524 -0.762)
			(stroke
				(width 0.1524)
				(type default)
			)
			(layer "F.SilkS")
		)
		(fp_line
			(start -1.524 -0.762)
			(end 1.524 -0.762)
			(stroke
				(width 0.1524)
				(type default)
			)
			(layer "F.SilkS")
		)
		(fp_line
			(start 1.1049 0.724916)
			(end 1.1049 -0.724916)
			(stroke
				(width 0.1)
				(type default)
			)
			(layer "F.Fab")
		)
		(fp_line
			(start 1.1049 -0.724916)
			(end -1.1049 -0.724916)
			(stroke
				(width 0.1)
				(type default)
			)
			(layer "F.Fab")
		)
		(fp_line
			(start -1.1049 0.724916)
			(end 1.1049 0.724916)
			(stroke
				(width 0.1)
				(type default)
			)
			(layer "F.Fab")
		)
		(fp_line
			(start -1.1049 -0.724916)
			(end -1.1049 0.724916)
			(stroke
				(width 0.1)
				(type default)
			)
			(layer "F.Fab")
		)
		(pad "1" smd rect
			(at -0.889 0)
			(size 1.016 1.27)
			(layers "F.Cu" "F.Mask" "F.Paste")
			(net "PVNN_MAIN_CPU1")
		)
		(pad "2" smd rect
			(at 0.889 0)
			(size 1.016 1.27)
			(layers "F.Cu" "F.Mask" "F.Paste")
			(net "GND")
		)
	)
	(footprint ""
		(layer "F.Cu")
		(at 111.25708 -397.874998 90)
		(property "Reference" "C1804"
			(at 0 0 90)
			(layer "F.SilkS")
			(hide yes)
			(effects
				(font
					(size 1.27 1.27)
				)
			)
		)
		(property "Value" ""
			(at 0 0 90)
			(layer "F.Fab")
			(effects
				(font
					(size 1.27 1.27)
				)
			)
		)
		(duplicate_pad_numbers_are_jumpers no)
		(fp_line
			(start 0.7874 -0.4064)
			(end 0.7874 0.4064)
			(stroke
				(width 0.1524)
				(type default)
			)
			(layer "F.SilkS")
		)
		(fp_line
			(start -0.7874 -0.4064)
			(end 0.7874 -0.4064)
			(stroke
				(width 0.1524)
				(type default)
			)
			(layer "F.SilkS")
		)
		(fp_line
			(start 0.7874 0.4064)
			(end -0.7874 0.4064)
			(stroke
				(width 0.1524)
				(type default)
			)
			(layer "F.SilkS")
		)
		(fp_line
			(start -0.7874 0.4064)
			(end -0.7874 -0.4064)
			(stroke
				(width 0.1524)
				(type default)
			)
			(layer "F.SilkS")
		)
		(fp_line
			(start -0.12065 -0.305054)
			(end -0.12065 -0.2794)
			(stroke
				(width 0.1)
				(type default)
			)
			(layer "F.Fab")
		)
		(fp_line
			(start -0.67945 -0.305054)
			(end -0.12065 -0.305054)
			(stroke
				(width 0.1)
				(type default)
			)
			(layer "F.Fab")
		)
		(fp_line
			(start 0.67945 -0.3048)
			(end 0.67945 0.3048)
			(stroke
				(width 0.1)
				(type default)
			)
			(layer "F.Fab")
		)
		(fp_line
			(start 0.12065 -0.3048)
			(end 0.67945 -0.3048)
			(stroke
				(width 0.1)
				(type default)
			)
			(layer "F.Fab")
		)
		(fp_line
			(start 0.12065 -0.2794)
			(end 0.12065 -0.3048)
			(stroke
				(width 0.1)
				(type default)
			)
			(layer "F.Fab")
		)
		(fp_line
			(start -0.12065 -0.2794)
			(end 0.12065 -0.2794)
			(stroke
				(width 0.1)
				(type default)
			)
			(layer "F.Fab")
		)
		(fp_line
			(start 0.120396 0.2794)
			(end -0.12065 0.2794)
			(stroke
				(width 0.1)
				(type default)
			)
			(layer "F.Fab")
		)
		(fp_line
			(start -0.12065 0.2794)
			(end -0.12065 0.3048)
			(stroke
				(width 0.1)
				(type default)
			)
			(layer "F.Fab")
		)
		(fp_line
			(start 0.67945 0.3048)
			(end 0.120396 0.3048)
			(stroke
				(width 0.1)
				(type default)
			)
			(layer "F.Fab")
		)
		(fp_line
			(start 0.120396 0.3048)
			(end 0.120396 0.2794)
			(stroke
				(width 0.1)
				(type default)
			)
			(layer "F.Fab")
		)
		(fp_line
			(start -0.12065 0.3048)
			(end -0.67945 0.3048)
			(stroke
				(width 0.1)
				(type default)
			)
			(layer "F.Fab")
		)
		(fp_line
			(start -0.67945 0.3048)
			(end -0.67945 -0.305054)
			(stroke
				(width 0.1)
				(type default)
			)
			(layer "F.Fab")
		)
		(pad "1" smd circle
			(at -0.40005 0 90)
			(size 0 0)
			(layers "F.Cu" "F.Mask" "F.Paste")
			(net "FM_SMB_2_ALERT_GPU_ISO_N")
		)
		(pad "2" smd circle
			(at 0.40005 0 90)
			(size 0 0)
			(layers "F.Cu" "F.Mask" "F.Paste")
			(net "GND")
		)
	)
	(footprint ""
		(layer "F.Cu")
		(at 60.25388 -16.220948 -90)
		(property "Reference" "R3172"
			(at 0 0 270)
			(layer "F.SilkS")
			(hide yes)
			(effects
				(font
					(size 1.27 1.27)
				)
			)
		)
		(property "Value" ""
			(at 0 0 270)
			(layer "F.Fab")
			(effects
				(font
					(size 1.27 1.27)
				)
			)
		)
		(duplicate_pad_numbers_are_jumpers no)
		(fp_line
			(start -0.7874 0.4064)
			(end -0.7874 -0.4064)
			(stroke
				(width 0.1524)
				(type default)
			)
			(layer "F.SilkS")
		)
		(fp_line
			(start 0.7874 0.4064)
			(end -0.7874 0.4064)
			(stroke
				(width 0.1524)
				(type default)
			)
			(layer "F.SilkS")
		)
		(fp_line
			(start -0.7874 -0.4064)
			(end 0.7874 -0.4064)
			(stroke
				(width 0.1524)
				(type default)
			)
			(layer "F.SilkS")
		)
		(fp_line
			(start 0.7874 -0.4064)
			(end 0.7874 0.4064)
			(stroke
				(width 0.1524)
				(type default)
			)
			(layer "F.SilkS")
		)
		(fp_line
			(start -0.67945 0.3048)
			(end -0.67945 -0.305054)
			(stroke
				(width 0.1)
				(type default)
			)
			(layer "F.Fab")
		)
		(fp_line
			(start -0.12065 0.3048)
			(end -0.67945 0.3048)
			(stroke
				(width 0.1)
				(type default)
			)
			(layer "F.Fab")
		)
		(fp_line
			(start 0.120396 0.3048)
			(end 0.120396 0.2794)
			(stroke
				(width 0.1)
				(type default)
			)
			(layer "F.Fab")
		)
		(fp_line
			(start 0.67945 0.3048)
			(end 0.120396 0.3048)
			(stroke
				(width 0.1)
				(type default)
			)
			(layer "F.Fab")
		)
		(fp_line
			(start -0.12065 0.2794)
			(end -0.12065 0.3048)
			(stroke
				(width 0.1)
				(type default)
			)
			(layer "F.Fab")
		)
		(fp_line
			(start 0.120396 0.2794)
			(end -0.12065 0.2794)
			(stroke
				(width 0.1)
				(type default)
			)
			(layer "F.Fab")
		)
		(fp_line
			(start -0.12065 -0.2794)
			(end 0.12065 -0.2794)
			(stroke
				(width 0.1)
				(type default)
			)
			(layer "F.Fab")
		)
		(fp_line
			(start 0.12065 -0.2794)
			(end 0.12065 -0.3048)
			(stroke
				(width 0.1)
				(type default)
			)
			(layer "F.Fab")
		)
		(fp_line
			(start 0.12065 -0.3048)
			(end 0.67945 -0.3048)
			(stroke
				(width 0.1)
				(type default)
			)
			(layer "F.Fab")
		)
		(fp_line
			(start 0.67945 -0.3048)
			(end 0.67945 0.3048)
			(stroke
				(width 0.1)
				(type default)
			)
			(layer "F.Fab")
		)
		(fp_line
			(start -0.67945 -0.305054)
			(end -0.12065 -0.305054)
			(stroke
				(width 0.1)
				(type default)
			)
			(layer "F.Fab")
		)
		(fp_line
			(start -0.12065 -0.305054)
			(end -0.12065 -0.2794)
			(stroke
				(width 0.1)
				(type default)
			)
			(layer "F.Fab")
		)
		(pad "1" smd circle
			(at -0.40005 0 270)
			(size 0 0)
			(layers "F.Cu" "F.Mask" "F.Paste")
			(net "OCP_V3_2_AUX_PWR_EN")
		)
		(pad "2" smd circle
			(at 0.40005 0 270)
			(size 0 0)
			(layers "F.Cu" "F.Mask" "F.Paste")
			(net "OCP_V3_2_AUX_PWR_EN_R")
		)
	)
	(footprint ""
		(layer "F.Cu")
		(at 82.322924 -152.621742 90)
		(property "Reference" "C537"
			(at 0 0 90)
			(layer "F.SilkS")
			(hide yes)
			(effects
				(font
					(size 1.27 1.27)
				)
			)
		)
		(property "Value" ""
			(at 0 0 90)
			(layer "F.Fab")
			(effects
				(font
					(size 1.27 1.27)
				)
			)
		)
		(duplicate_pad_numbers_are_jumpers no)
		(fp_line
			(start 0.7874 -0.4064)
			(end 0.7874 0.4064)
			(stroke
				(width 0.1524)
				(type default)
			)
			(layer "F.SilkS")
		)
		(fp_line
			(start -0.7874 -0.4064)
			(end 0.7874 -0.4064)
			(stroke
				(width 0.1524)
				(type default)
			)
			(layer "F.SilkS")
		)
		(fp_line
			(start 0.7874 0.4064)
			(end -0.7874 0.4064)
			(stroke
				(width 0.1524)
				(type default)
			)
			(layer "F.SilkS")
		)
		(fp_line
			(start -0.7874 0.4064)
			(end -0.7874 -0.4064)
			(stroke
				(width 0.1524)
				(type default)
			)
			(layer "F.SilkS")
		)
		(fp_line
			(start -0.12065 -0.305054)
			(end -0.12065 -0.2794)
			(stroke
				(width 0.1)
				(type default)
			)
			(layer "F.Fab")
		)
		(fp_line
			(start -0.67945 -0.305054)
			(end -0.12065 -0.305054)
			(stroke
				(width 0.1)
				(type default)
			)
			(layer "F.Fab")
		)
		(fp_line
			(start 0.67945 -0.3048)
			(end 0.67945 0.3048)
			(stroke
				(width 0.1)
				(type default)
			)
			(layer "F.Fab")
		)
		(fp_line
			(start 0.12065 -0.3048)
			(end 0.67945 -0.3048)
			(stroke
				(width 0.1)
				(type default)
			)
			(layer "F.Fab")
		)
		(fp_line
			(start 0.12065 -0.2794)
			(end 0.12065 -0.3048)
			(stroke
				(width 0.1)
				(type default)
			)
			(layer "F.Fab")
		)
		(fp_line
			(start -0.12065 -0.2794)
			(end 0.12065 -0.2794)
			(stroke
				(width 0.1)
				(type default)
			)
			(layer "F.Fab")
		)
		(fp_line
			(start 0.120396 0.2794)
			(end -0.12065 0.2794)
			(stroke
				(width 0.1)
				(type default)
			)
			(layer "F.Fab")
		)
		(fp_line
			(start -0.12065 0.2794)
			(end -0.12065 0.3048)
			(stroke
				(width 0.1)
				(type default)
			)
			(layer "F.Fab")
		)
		(fp_line
			(start 0.67945 0.3048)
			(end 0.120396 0.3048)
			(stroke
				(width 0.1)
				(type default)
			)
			(layer "F.Fab")
		)
		(fp_line
			(start 0.120396 0.3048)
			(end 0.120396 0.2794)
			(stroke
				(width 0.1)
				(type default)
			)
			(layer "F.Fab")
		)
		(fp_line
			(start -0.12065 0.3048)
			(end -0.67945 0.3048)
			(stroke
				(width 0.1)
				(type default)
			)
			(layer "F.Fab")
		)
		(fp_line
			(start -0.67945 0.3048)
			(end -0.67945 -0.305054)
			(stroke
				(width 0.1)
				(type default)
			)
			(layer "F.Fab")
		)
		(pad "1" smd circle
			(at -0.40005 0 90)
			(size 0 0)
			(layers "F.Cu" "F.Mask" "F.Paste")
			(net "P3V3_AUX")
		)
		(pad "2" smd circle
			(at 0.40005 0 90)
			(size 0 0)
			(layers "F.Cu" "F.Mask" "F.Paste")
			(net "GND")
		)
	)
	(footprint ""
		(layer "F.Cu")
		(at 406.124664 -363.008926 180)
		(property "Reference" "R335"
			(at 0 0 180)
			(layer "F.SilkS")
			(hide yes)
			(effects
				(font
					(size 1.27 1.27)
				)
			)
		)
		(property "Value" ""
			(at 0 0 180)
			(layer "F.Fab")
			(effects
				(font
					(size 1.27 1.27)
				)
			)
		)
		(duplicate_pad_numbers_are_jumpers no)
		(fp_line
			(start 0.7874 0.4064)
			(end -0.7874 0.4064)
			(stroke
				(width 0.1524)
				(type default)
			)
			(layer "F.SilkS")
		)
		(fp_line
			(start 0.7874 -0.4064)
			(end 0.7874 0.4064)
			(stroke
				(width 0.1524)
				(type default)
			)
			(layer "F.SilkS")
		)
		(fp_line
			(start -0.7874 0.4064)
			(end -0.7874 -0.4064)
			(stroke
				(width 0.1524)
				(type default)
			)
			(layer "F.SilkS")
		)
		(fp_line
			(start -0.7874 -0.4064)
			(end 0.7874 -0.4064)
			(stroke
				(width 0.1524)
				(type default)
			)
			(layer "F.SilkS")
		)
		(fp_line
			(start 0.67945 0.3048)
			(end 0.120396 0.3048)
			(stroke
				(width 0.1)
				(type default)
			)
			(layer "F.Fab")
		)
		(fp_line
			(start 0.67945 -0.3048)
			(end 0.67945 0.3048)
			(stroke
				(width 0.1)
				(type default)
			)
			(layer "F.Fab")
		)
		(fp_line
			(start 0.12065 -0.2794)
			(end 0.12065 -0.3048)
			(stroke
				(width 0.1)
				(type default)
			)
			(layer "F.Fab")
		)
		(fp_line
			(start 0.12065 -0.3048)
			(end 0.67945 -0.3048)
			(stroke
				(width 0.1)
				(type default)
			)
			(layer "F.Fab")
		)
		(fp_line
			(start 0.120396 0.3048)
			(end 0.120396 0.2794)
			(stroke
				(width 0.1)
				(type default)
			)
			(layer "F.Fab")
		)
		(fp_line
			(start 0.120396 0.2794)
			(end -0.12065 0.2794)
			(stroke
				(width 0.1)
				(type default)
			)
			(layer "F.Fab")
		)
		(fp_line
			(start -0.12065 0.3048)
			(end -0.67945 0.3048)
			(stroke
				(width 0.1)
				(type default)
			)
			(layer "F.Fab")
		)
		(fp_line
			(start -0.12065 0.2794)
			(end -0.12065 0.3048)
			(stroke
				(width 0.1)
				(type default)
			)
			(layer "F.Fab")
		)
		(fp_line
			(start -0.12065 -0.2794)
			(end 0.12065 -0.2794)
			(stroke
				(width 0.1)
				(type default)
			)
			(layer "F.Fab")
		)
		(fp_line
			(start -0.12065 -0.305054)
			(end -0.12065 -0.2794)
			(stroke
				(width 0.1)
				(type default)
			)
			(layer "F.Fab")
		)
		(fp_line
			(start -0.67945 0.3048)
			(end -0.67945 -0.305054)
			(stroke
				(width 0.1)
				(type default)
			)
			(layer "F.Fab")
		)
		(fp_line
			(start -0.67945 -0.305054)
			(end -0.12065 -0.305054)
			(stroke
				(width 0.1)
				(type default)
			)
			(layer "F.Fab")
		)
		(pad "1" smd circle
			(at -0.40005 0 180)
			(size 0 0)
			(layers "F.Cu" "F.Mask" "F.Paste")
			(net "P3V3_AUX")
		)
		(pad "2" smd circle
			(at 0.40005 0 180)
			(size 0 0)
			(layers "F.Cu" "F.Mask" "F.Paste")
			(net "PD_PIROM_CPU0_ADDR0")
		)
	)
	(footprint ""
		(layer "F.Cu")
		(at 118.542816 -251.375672 90)
		(property "Reference" "C263"
			(at 0 0 90)
			(layer "F.SilkS")
			(hide yes)
			(effects
				(font
					(size 1.27 1.27)
				)
			)
		)
		(property "Value" ""
			(at 0 0 90)
			(layer "F.Fab")
			(effects
				(font
					(size 1.27 1.27)
				)
			)
		)
		(duplicate_pad_numbers_are_jumpers no)
		(fp_line
			(start 0.7874 -0.4064)
			(end 0.7874 0.4064)
			(stroke
				(width 0.1524)
				(type default)
			)
			(layer "F.SilkS")
		)
		(fp_line
			(start -0.7874 -0.4064)
			(end 0.7874 -0.4064)
			(stroke
				(width 0.1524)
				(type default)
			)
			(layer "F.SilkS")
		)
		(fp_line
			(start 0.7874 0.4064)
			(end -0.7874 0.4064)
			(stroke
				(width 0.1524)
				(type default)
			)
			(layer "F.SilkS")
		)
		(fp_line
			(start -0.7874 0.4064)
			(end -0.7874 -0.4064)
			(stroke
				(width 0.1524)
				(type default)
			)
			(layer "F.SilkS")
		)
		(fp_line
			(start -0.12065 -0.305054)
			(end -0.12065 -0.2794)
			(stroke
				(width 0.1)
				(type default)
			)
			(layer "F.Fab")
		)
		(fp_line
			(start -0.67945 -0.305054)
			(end -0.12065 -0.305054)
			(stroke
				(width 0.1)
				(type default)
			)
			(layer "F.Fab")
		)
		(fp_line
			(start 0.67945 -0.3048)
			(end 0.67945 0.3048)
			(stroke
				(width 0.1)
				(type default)
			)
			(layer "F.Fab")
		)
		(fp_line
			(start 0.12065 -0.3048)
			(end 0.67945 -0.3048)
			(stroke
				(width 0.1)
				(type default)
			)
			(layer "F.Fab")
		)
		(fp_line
			(start 0.12065 -0.2794)
			(end 0.12065 -0.3048)
			(stroke
				(width 0.1)
				(type default)
			)
			(layer "F.Fab")
		)
		(fp_line
			(start -0.12065 -0.2794)
			(end 0.12065 -0.2794)
			(stroke
				(width 0.1)
				(type default)
			)
			(layer "F.Fab")
		)
		(fp_line
			(start 0.120396 0.2794)
			(end -0.12065 0.2794)
			(stroke
				(width 0.1)
				(type default)
			)
			(layer "F.Fab")
		)
		(fp_line
			(start -0.12065 0.2794)
			(end -0.12065 0.3048)
			(stroke
				(width 0.1)
				(type default)
			)
			(layer "F.Fab")
		)
		(fp_line
			(start 0.67945 0.3048)
			(end 0.120396 0.3048)
			(stroke
				(width 0.1)
				(type default)
			)
			(layer "F.Fab")
		)
		(fp_line
			(start 0.120396 0.3048)
			(end 0.120396 0.2794)
			(stroke
				(width 0.1)
				(type default)
			)
			(layer "F.Fab")
		)
		(fp_line
			(start -0.12065 0.3048)
			(end -0.67945 0.3048)
			(stroke
				(width 0.1)
				(type default)
			)
			(layer "F.Fab")
		)
		(fp_line
			(start -0.67945 0.3048)
			(end -0.67945 -0.305054)
			(stroke
				(width 0.1)
				(type default)
			)
			(layer "F.Fab")
		)
		(pad "1" smd circle
			(at -0.40005 0 90)
			(size 0 0)
			(layers "F.Cu" "F.Mask" "F.Paste")
			(net "PVCCIN_CPU1")
		)
		(pad "2" smd circle
			(at 0.40005 0 90)
			(size 0 0)
			(layers "F.Cu" "F.Mask" "F.Paste")
			(net "GND")
		)
	)
	(footprint ""
		(layer "F.Cu")
		(at 201.02068 -102.235)
		(property "Reference" "R4712"
			(at 0 0 0)
			(layer "F.SilkS")
			(hide yes)
			(effects
				(font
					(size 1.27 1.27)
				)
			)
		)
		(property "Value" ""
			(at 0 0 0)
			(layer "F.Fab")
			(effects
				(font
					(size 1.27 1.27)
				)
			)
		)
		(duplicate_pad_numbers_are_jumpers no)
		(fp_line
			(start -0.7874 -0.4064)
			(end 0.7874 -0.4064)
			(stroke
				(width 0.1524)
				(type default)
			)
			(layer "F.SilkS")
		)
		(fp_line
			(start -0.7874 0.4064)
			(end -0.7874 -0.4064)
			(stroke
				(width 0.1524)
				(type default)
			)
			(layer "F.SilkS")
		)
		(fp_line
			(start 0.7874 -0.4064)
			(end 0.7874 0.4064)
			(stroke
				(width 0.1524)
				(type default)
			)
			(layer "F.SilkS")
		)
		(fp_line
			(start 0.7874 0.4064)
			(end -0.7874 0.4064)
			(stroke
				(width 0.1524)
				(type default)
			)
			(layer "F.SilkS")
		)
		(fp_line
			(start -0.67945 -0.305054)
			(end -0.12065 -0.305054)
			(stroke
				(width 0.1)
				(type default)
			)
			(layer "F.Fab")
		)
		(fp_line
			(start -0.67945 0.3048)
			(end -0.67945 -0.305054)
			(stroke
				(width 0.1)
				(type default)
			)
			(layer "F.Fab")
		)
		(fp_line
			(start -0.12065 -0.305054)
			(end -0.12065 -0.2794)
			(stroke
				(width 0.1)
				(type default)
			)
			(layer "F.Fab")
		)
		(fp_line
			(start -0.12065 -0.2794)
			(end 0.12065 -0.2794)
			(stroke
				(width 0.1)
				(type default)
			)
			(layer "F.Fab")
		)
		(fp_line
			(start -0.12065 0.2794)
			(end -0.12065 0.3048)
			(stroke
				(width 0.1)
				(type default)
			)
			(layer "F.Fab")
		)
		(fp_line
			(start -0.12065 0.3048)
			(end -0.67945 0.3048)
			(stroke
				(width 0.1)
				(type default)
			)
			(layer "F.Fab")
		)
		(fp_line
			(start 0.120396 0.2794)
			(end -0.12065 0.2794)
			(stroke
				(width 0.1)
				(type default)
			)
			(layer "F.Fab")
		)
		(fp_line
			(start 0.120396 0.3048)
			(end 0.120396 0.2794)
			(stroke
				(width 0.1)
				(type default)
			)
			(layer "F.Fab")
		)
		(fp_line
			(start 0.12065 -0.3048)
			(end 0.67945 -0.3048)
			(stroke
				(width 0.1)
				(type default)
			)
			(layer "F.Fab")
		)
		(fp_line
			(start 0.12065 -0.2794)
			(end 0.12065 -0.3048)
			(stroke
				(width 0.1)
				(type default)
			)
			(layer "F.Fab")
		)
		(fp_line
			(start 0.67945 -0.3048)
			(end 0.67945 0.3048)
			(stroke
				(width 0.1)
				(type default)
			)
			(layer "F.Fab")
		)
		(fp_line
			(start 0.67945 0.3048)
			(end 0.120396 0.3048)
			(stroke
				(width 0.1)
				(type default)
			)
			(layer "F.Fab")
		)
		(pad "1" smd circle
			(at -0.40005 0)
			(size 0 0)
			(layers "F.Cu" "F.Mask" "F.Paste")
			(net "RST_PFR_OVR_RTC")
		)
		(pad "2" smd circle
			(at 0.40005 0)
			(size 0 0)
			(layers "F.Cu" "F.Mask" "F.Paste")
			(net "GND")
		)
	)
	(footprint ""
		(layer "F.Cu")
		(at 197.19036 -118.074948)
		(property "Reference" "R1469"
			(at 0 0 0)
			(layer "F.SilkS")
			(hide yes)
			(effects
				(font
					(size 1.27 1.27)
				)
			)
		)
		(property "Value" ""
			(at 0 0 0)
			(layer "F.Fab")
			(effects
				(font
					(size 1.27 1.27)
				)
			)
		)
		(duplicate_pad_numbers_are_jumpers no)
		(fp_line
			(start -0.7874 -0.4064)
			(end 0.7874 -0.4064)
			(stroke
				(width 0.1524)
				(type default)
			)
			(layer "F.SilkS")
		)
		(fp_line
			(start -0.7874 0.4064)
			(end -0.7874 -0.4064)
			(stroke
				(width 0.1524)
				(type default)
			)
			(layer "F.SilkS")
		)
		(fp_line
			(start 0.7874 -0.4064)
			(end 0.7874 0.4064)
			(stroke
				(width 0.1524)
				(type default)
			)
			(layer "F.SilkS")
		)
		(fp_line
			(start 0.7874 0.4064)
			(end -0.7874 0.4064)
			(stroke
				(width 0.1524)
				(type default)
			)
			(layer "F.SilkS")
		)
		(fp_line
			(start -0.67945 -0.305054)
			(end -0.12065 -0.305054)
			(stroke
				(width 0.1)
				(type default)
			)
			(layer "F.Fab")
		)
		(fp_line
			(start -0.67945 0.3048)
			(end -0.67945 -0.305054)
			(stroke
				(width 0.1)
				(type default)
			)
			(layer "F.Fab")
		)
		(fp_line
			(start -0.12065 -0.305054)
			(end -0.12065 -0.2794)
			(stroke
				(width 0.1)
				(type default)
			)
			(layer "F.Fab")
		)
		(fp_line
			(start -0.12065 -0.2794)
			(end 0.12065 -0.2794)
			(stroke
				(width 0.1)
				(type default)
			)
			(layer "F.Fab")
		)
		(fp_line
			(start -0.12065 0.2794)
			(end -0.12065 0.3048)
			(stroke
				(width 0.1)
				(type default)
			)
			(layer "F.Fab")
		)
		(fp_line
			(start -0.12065 0.3048)
			(end -0.67945 0.3048)
			(stroke
				(width 0.1)
				(type default)
			)
			(layer "F.Fab")
		)
		(fp_line
			(start 0.120396 0.2794)
			(end -0.12065 0.2794)
			(stroke
				(width 0.1)
				(type default)
			)
			(layer "F.Fab")
		)
		(fp_line
			(start 0.120396 0.3048)
			(end 0.120396 0.2794)
			(stroke
				(width 0.1)
				(type default)
			)
			(layer "F.Fab")
		)
		(fp_line
			(start 0.12065 -0.3048)
			(end 0.67945 -0.3048)
			(stroke
				(width 0.1)
				(type default)
			)
			(layer "F.Fab")
		)
		(fp_line
			(start 0.12065 -0.2794)
			(end 0.12065 -0.3048)
			(stroke
				(width 0.1)
				(type default)
			)
			(layer "F.Fab")
		)
		(fp_line
			(start 0.67945 -0.3048)
			(end 0.67945 0.3048)
			(stroke
				(width 0.1)
				(type default)
			)
			(layer "F.Fab")
		)
		(fp_line
			(start 0.67945 0.3048)
			(end 0.120396 0.3048)
			(stroke
				(width 0.1)
				(type default)
			)
			(layer "F.Fab")
		)
		(pad "1" smd circle
			(at -0.40005 0)
			(size 0 0)
			(layers "F.Cu" "F.Mask" "F.Paste")
			(net "RST_PLTRST_PLD_B_N")
		)
		(pad "2" smd circle
			(at 0.40005 0)
			(size 0 0)
			(layers "F.Cu" "F.Mask" "F.Paste")
			(net "RST_PLTRST_B_N")
		)
	)
	(footprint ""
		(layer "F.Cu")
		(at 263.805924 -75.61834 90)
		(property "Reference" "PR1327"
			(at 0 0 90)
			(layer "F.SilkS")
			(hide yes)
			(effects
				(font
					(size 1.27 1.27)
				)
			)
		)
		(property "Value" ""
			(at 0 0 90)
			(layer "F.Fab")
			(effects
				(font
					(size 1.27 1.27)
				)
			)
		)
		(duplicate_pad_numbers_are_jumpers no)
		(fp_line
			(start 0.7874 -0.4064)
			(end 0.7874 0.4064)
			(stroke
				(width 0.1524)
				(type default)
			)
			(layer "F.SilkS")
		)
		(fp_line
			(start -0.7874 -0.4064)
			(end 0.7874 -0.4064)
			(stroke
				(width 0.1524)
				(type default)
			)
			(layer "F.SilkS")
		)
		(fp_line
			(start 0.7874 0.4064)
			(end -0.7874 0.4064)
			(stroke
				(width 0.1524)
				(type default)
			)
			(layer "F.SilkS")
		)
		(fp_line
			(start -0.7874 0.4064)
			(end -0.7874 -0.4064)
			(stroke
				(width 0.1524)
				(type default)
			)
			(layer "F.SilkS")
		)
		(fp_line
			(start -0.12065 -0.305054)
			(end -0.12065 -0.2794)
			(stroke
				(width 0.1)
				(type default)
			)
			(layer "F.Fab")
		)
		(fp_line
			(start -0.67945 -0.305054)
			(end -0.12065 -0.305054)
			(stroke
				(width 0.1)
				(type default)
			)
			(layer "F.Fab")
		)
		(fp_line
			(start 0.67945 -0.3048)
			(end 0.67945 0.3048)
			(stroke
				(width 0.1)
				(type default)
			)
			(layer "F.Fab")
		)
		(fp_line
			(start 0.12065 -0.3048)
			(end 0.67945 -0.3048)
			(stroke
				(width 0.1)
				(type default)
			)
			(layer "F.Fab")
		)
		(fp_line
			(start 0.12065 -0.2794)
			(end 0.12065 -0.3048)
			(stroke
				(width 0.1)
				(type default)
			)
			(layer "F.Fab")
		)
		(fp_line
			(start -0.12065 -0.2794)
			(end 0.12065 -0.2794)
			(stroke
				(width 0.1)
				(type default)
			)
			(layer "F.Fab")
		)
		(fp_line
			(start 0.120396 0.2794)
			(end -0.12065 0.2794)
			(stroke
				(width 0.1)
				(type default)
			)
			(layer "F.Fab")
		)
		(fp_line
			(start -0.12065 0.2794)
			(end -0.12065 0.3048)
			(stroke
				(width 0.1)
				(type default)
			)
			(layer "F.Fab")
		)
		(fp_line
			(start 0.67945 0.3048)
			(end 0.120396 0.3048)
			(stroke
				(width 0.1)
				(type default)
			)
			(layer "F.Fab")
		)
		(fp_line
			(start 0.120396 0.3048)
			(end 0.120396 0.2794)
			(stroke
				(width 0.1)
				(type default)
			)
			(layer "F.Fab")
		)
		(fp_line
			(start -0.12065 0.3048)
			(end -0.67945 0.3048)
			(stroke
				(width 0.1)
				(type default)
			)
			(layer "F.Fab")
		)
		(fp_line
			(start -0.67945 0.3048)
			(end -0.67945 -0.305054)
			(stroke
				(width 0.1)
				(type default)
			)
			(layer "F.Fab")
		)
		(pad "1" smd circle
			(at -0.40005 0 90)
			(size 0 0)
			(layers "F.Cu" "F.Mask" "F.Paste")
			(net "P1V05_PCH_AUX_CS")
		)
		(pad "2" smd circle
			(at 0.40005 0 90)
			(size 0 0)
			(layers "F.Cu" "F.Mask" "F.Paste")
			(net "GND")
		)
	)
	(footprint ""
		(layer "F.Cu")
		(at 339.298534 0.383794)
		(property "Reference" "J71"
			(at -4.245864 1.013206 90)
			(unlocked yes)
			(layer "F.SilkS")
			(effects
				(font
					(size 0.7874 0.5842)
					(thickness 0.1524)
				)
				(justify left)
			)
		)
		(property "Value" ""
			(at 0 0 0)
			(layer "F.Fab")
			(effects
				(font
					(size 1.27 1.27)
				)
			)
		)
		(duplicate_pad_numbers_are_jumpers no)
		(fp_line
			(start -1.2192 -2.1082)
			(end 1.2192 -2.1082)
			(stroke
				(width 0.1524)
				(type default)
			)
			(layer "F.SilkS")
		)
		(fp_line
			(start -1.2192 2.1082)
			(end -1.2192 -2.1082)
			(stroke
				(width 0.1524)
				(type default)
			)
			(layer "F.SilkS")
		)
		(fp_line
			(start 1.2192 -2.1082)
			(end 1.2192 2.1082)
			(stroke
				(width 0.1524)
				(type default)
			)
			(layer "F.SilkS")
		)
		(fp_line
			(start 1.2192 2.1082)
			(end -1.2192 2.1082)
			(stroke
				(width 0.1524)
				(type default)
			)
			(layer "F.SilkS")
		)
		(pad "" np_thru_hole circle
			(at -2.8829 -1.27 270)
			(size 1.0414 1.0414)
			(drill 1.0414)
			(layers "*.Cu" "*.Mask")
			(clearance 0.381)
			(thermal_gap 0.381)
		)
		(pad "" np_thru_hole circle
			(at -2.8829 1.27 270)
			(size 1.0414 1.0414)
			(drill 1.0414)
			(layers "*.Cu" "*.Mask")
			(clearance 0.381)
			(thermal_gap 0.381)
		)
		(pad "" np_thru_hole circle
			(at 3.4671 -1.27 270)
			(size 1.0414 1.0414)
			(drill 1.0414)
			(layers "*.Cu" "*.Mask")
			(clearance 0.381)
			(thermal_gap 0.381)
		)
		(pad "" np_thru_hole circle
			(at 3.4671 1.27 270)
			(size 1.0414 1.0414)
			(drill 1.0414)
			(layers "*.Cu" "*.Mask")
			(clearance 0.381)
			(thermal_gap 0.381)
		)
		(pad "1" smd rect
			(at 0.8255 -0.249936 270)
			(size 0.3048 0.508)
			(layers "F.Cu" "F.Mask" "F.Paste")
			(net "DELTA_L_85_5INCH_IN1_DN")
		)
		(pad "2" smd rect
			(at 0.8255 0.249936 270)
			(size 0.3048 0.508)
			(layers "F.Cu" "F.Mask" "F.Paste")
			(net "DELTA_L_85_5INCH_IN1_DP")
		)
		(pad "3" smd circle
			(at 0 0)
			(size 0 0)
			(layers "F.Cu" "F.Mask" "F.Paste")
			(net "DELTA_L_GND_1")
		)
		(zone
			(layer "F.Cu")
			(hatch none 0.5)
			(connect_pads
				(clearance 0)
			)
			(min_thickness 0.25)
			(keepout
				(tracks not_allowed)
				(vias allowed)
				(pads allowed)
				(copperpour not_allowed)
				(footprints allowed)
			)
			(placement
				(enabled no)
				(sheetname "")
			)
			(fill
				(thermal_gap 0.5)
				(thermal_bridge_width 0.5)
				(island_removal_mode 0)
			)
			(polygon
				(pts
					(xy 340.416134 -0.164846) (xy 340.416134 -0.069342) (xy 339.819234 -0.069342) (xy 339.819234 0.337058)
					(xy 340.416134 0.337058) (xy 340.416134 0.43053) (xy 339.819234 0.43053) (xy 339.819234 0.83693)
					(xy 340.416134 0.83693) (xy 340.416134 0.932434) (xy 339.717634 0.932434) (xy 339.717634 -0.164846)
				)
			)
		)
		(zone
			(layers "F.Cu" "B.Cu" "In1.Cu" "In2.Cu" "In3.Cu" "In4.Cu" "In5.Cu" "In6.Cu"
				"In7.Cu" "In8.Cu" "In9.Cu" "In10.Cu" "In11.Cu" "In12.Cu" "In13.Cu" "In14.Cu"
				"In15.Cu" "In16.Cu"
			)
			(hatch none 0.5)
			(connect_pads
				(clearance 0)
			)
			(min_thickness 0.25)
			(keepout
				(tracks not_allowed)
				(vias allowed)
				(pads allowed)
				(copperpour not_allowed)
				(footprints allowed)
			)
			(placement
				(enabled no)
				(sheetname "")
			)
			(fill
				(thermal_gap 0.5)
				(thermal_bridge_width 0.5)
				(island_removal_mode 0)
			)
			(polygon
				(pts
					(arc
						(start 337.342734 -0.886206)
						(mid 335.488534 -0.886206)
						(end 337.342734 -0.886206)
					)
				)
			)
		)
		(zone
			(layers "F.Cu" "B.Cu" "In1.Cu" "In2.Cu" "In3.Cu" "In4.Cu" "In5.Cu" "In6.Cu"
				"In7.Cu" "In8.Cu" "In9.Cu" "In10.Cu" "In11.Cu" "In12.Cu" "In13.Cu" "In14.Cu"
				"In15.Cu" "In16.Cu"
			)
			(hatch none 0.5)
			(connect_pads
				(clearance 0)
			)
			(min_thickness 0.25)
			(keepout
				(tracks not_allowed)
				(vias allowed)
				(pads allowed)
				(copperpour not_allowed)
				(footprints allowed)
			)
			(placement
				(enabled no)
				(sheetname "")
			)
			(fill
				(thermal_gap 0.5)
				(thermal_bridge_width 0.5)
				(island_removal_mode 0)
			)
			(polygon
				(pts
					(arc
						(start 337.342734 1.653794)
						(mid 335.488534 1.653794)
						(end 337.342734 1.653794)
					)
				)
			)
		)
		(zone
			(layers "F.Cu" "B.Cu" "In1.Cu" "In2.Cu" "In3.Cu" "In4.Cu" "In5.Cu" "In6.Cu"
				"In7.Cu" "In8.Cu" "In9.Cu" "In10.Cu" "In11.Cu" "In12.Cu" "In13.Cu" "In14.Cu"
				"In15.Cu" "In16.Cu"
			)
			(hatch none 0.5)
			(connect_pads
				(clearance 0)
			)
			(min_thickness 0.25)
			(keepout
				(tracks not_allowed)
				(vias allowed)
				(pads allowed)
				(copperpour not_allowed)
				(footprints allowed)
			)
			(placement
				(enabled no)
				(sheetname "")
			)
			(fill
				(thermal_gap 0.5)
				(thermal_bridge_width 0.5)
				(island_removal_mode 0)
			)
			(polygon
				(pts
					(arc
						(start 343.692734 -0.886206)
						(mid 341.838534 -0.886206)
						(end 343.692734 -0.886206)
					)
				)
			)
		)
		(zone
			(layers "F.Cu" "B.Cu" "In1.Cu" "In2.Cu" "In3.Cu" "In4.Cu" "In5.Cu" "In6.Cu"
				"In7.Cu" "In8.Cu" "In9.Cu" "In10.Cu" "In11.Cu" "In12.Cu" "In13.Cu" "In14.Cu"
				"In15.Cu" "In16.Cu"
			)
			(hatch none 0.5)
			(connect_pads
				(clearance 0)
			)
			(min_thickness 0.25)
			(keepout
				(tracks not_allowed)
				(vias allowed)
				(pads allowed)
				(copperpour not_allowed)
				(footprints allowed)
			)
			(placement
				(enabled no)
				(sheetname "")
			)
			(fill
				(thermal_gap 0.5)
				(thermal_bridge_width 0.5)
				(island_removal_mode 0)
			)
			(polygon
				(pts
					(arc
						(start 343.692734 1.653794)
						(mid 341.838534 1.653794)
						(end 343.692734 1.653794)
					)
				)
			)
		)
	)
	(footprint ""
		(layer "F.Cu")
		(at 284.63494 -409.52928)
		(property "Reference" "R4892"
			(at 0 0 0)
			(layer "F.SilkS")
			(hide yes)
			(effects
				(font
					(size 1.27 1.27)
				)
			)
		)
		(property "Value" ""
			(at 0 0 0)
			(layer "F.Fab")
			(effects
				(font
					(size 1.27 1.27)
				)
			)
		)
		(duplicate_pad_numbers_are_jumpers no)
		(fp_line
			(start -0.7874 -0.4064)
			(end 0.7874 -0.4064)
			(stroke
				(width 0.1524)
				(type default)
			)
			(layer "F.SilkS")
		)
		(fp_line
			(start -0.7874 0.4064)
			(end -0.7874 -0.4064)
			(stroke
				(width 0.1524)
				(type default)
			)
			(layer "F.SilkS")
		)
		(fp_line
			(start 0.7874 -0.4064)
			(end 0.7874 0.4064)
			(stroke
				(width 0.1524)
				(type default)
			)
			(layer "F.SilkS")
		)
		(fp_line
			(start 0.7874 0.4064)
			(end -0.7874 0.4064)
			(stroke
				(width 0.1524)
				(type default)
			)
			(layer "F.SilkS")
		)
		(fp_line
			(start -0.67945 -0.305054)
			(end -0.12065 -0.305054)
			(stroke
				(width 0.1)
				(type default)
			)
			(layer "F.Fab")
		)
		(fp_line
			(start -0.67945 0.3048)
			(end -0.67945 -0.305054)
			(stroke
				(width 0.1)
				(type default)
			)
			(layer "F.Fab")
		)
		(fp_line
			(start -0.12065 -0.305054)
			(end -0.12065 -0.2794)
			(stroke
				(width 0.1)
				(type default)
			)
			(layer "F.Fab")
		)
		(fp_line
			(start -0.12065 -0.2794)
			(end 0.12065 -0.2794)
			(stroke
				(width 0.1)
				(type default)
			)
			(layer "F.Fab")
		)
		(fp_line
			(start -0.12065 0.2794)
			(end -0.12065 0.3048)
			(stroke
				(width 0.1)
				(type default)
			)
			(layer "F.Fab")
		)
		(fp_line
			(start -0.12065 0.3048)
			(end -0.67945 0.3048)
			(stroke
				(width 0.1)
				(type default)
			)
			(layer "F.Fab")
		)
		(fp_line
			(start 0.120396 0.2794)
			(end -0.12065 0.2794)
			(stroke
				(width 0.1)
				(type default)
			)
			(layer "F.Fab")
		)
		(fp_line
			(start 0.120396 0.3048)
			(end 0.120396 0.2794)
			(stroke
				(width 0.1)
				(type default)
			)
			(layer "F.Fab")
		)
		(fp_line
			(start 0.12065 -0.3048)
			(end 0.67945 -0.3048)
			(stroke
				(width 0.1)
				(type default)
			)
			(layer "F.Fab")
		)
		(fp_line
			(start 0.12065 -0.2794)
			(end 0.12065 -0.3048)
			(stroke
				(width 0.1)
				(type default)
			)
			(layer "F.Fab")
		)
		(fp_line
			(start 0.67945 -0.3048)
			(end 0.67945 0.3048)
			(stroke
				(width 0.1)
				(type default)
			)
			(layer "F.Fab")
		)
		(fp_line
			(start 0.67945 0.3048)
			(end 0.120396 0.3048)
			(stroke
				(width 0.1)
				(type default)
			)
			(layer "F.Fab")
		)
		(pad "1" smd circle
			(at -0.40005 0)
			(size 0 0)
			(layers "F.Cu" "F.Mask" "F.Paste")
			(net "P12V_HSC_TEMP_R")
		)
		(pad "2" smd circle
			(at 0.40005 0)
			(size 0 0)
			(layers "F.Cu" "F.Mask" "F.Paste")
			(net "P12V_HSC_TEMP_D+")
		)
	)
	(footprint ""
		(layer "F.Cu")
		(at 418.485828 -165.760654)
		(property "Reference" "PC633"
			(at 0 0 0)
			(layer "F.SilkS")
			(hide yes)
			(effects
				(font
					(size 1.27 1.27)
				)
			)
		)
		(property "Value" ""
			(at 0 0 0)
			(layer "F.Fab")
			(effects
				(font
					(size 1.27 1.27)
				)
			)
		)
		(duplicate_pad_numbers_are_jumpers no)
		(fp_line
			(start -0.7874 -0.4064)
			(end 0.7874 -0.4064)
			(stroke
				(width 0.1524)
				(type default)
			)
			(layer "F.SilkS")
		)
		(fp_line
			(start -0.7874 0.4064)
			(end -0.7874 -0.4064)
			(stroke
				(width 0.1524)
				(type default)
			)
			(layer "F.SilkS")
		)
		(fp_line
			(start 0.7874 -0.4064)
			(end 0.7874 0.4064)
			(stroke
				(width 0.1524)
				(type default)
			)
			(layer "F.SilkS")
		)
		(fp_line
			(start 0.7874 0.4064)
			(end -0.7874 0.4064)
			(stroke
				(width 0.1524)
				(type default)
			)
			(layer "F.SilkS")
		)
		(fp_line
			(start -0.67945 -0.305054)
			(end -0.12065 -0.305054)
			(stroke
				(width 0.1)
				(type default)
			)
			(layer "F.Fab")
		)
		(fp_line
			(start -0.67945 0.3048)
			(end -0.67945 -0.305054)
			(stroke
				(width 0.1)
				(type default)
			)
			(layer "F.Fab")
		)
		(fp_line
			(start -0.12065 -0.305054)
			(end -0.12065 -0.2794)
			(stroke
				(width 0.1)
				(type default)
			)
			(layer "F.Fab")
		)
		(fp_line
			(start -0.12065 -0.2794)
			(end 0.12065 -0.2794)
			(stroke
				(width 0.1)
				(type default)
			)
			(layer "F.Fab")
		)
		(fp_line
			(start -0.12065 0.2794)
			(end -0.12065 0.3048)
			(stroke
				(width 0.1)
				(type default)
			)
			(layer "F.Fab")
		)
		(fp_line
			(start -0.12065 0.3048)
			(end -0.67945 0.3048)
			(stroke
				(width 0.1)
				(type default)
			)
			(layer "F.Fab")
		)
		(fp_line
			(start 0.120396 0.2794)
			(end -0.12065 0.2794)
			(stroke
				(width 0.1)
				(type default)
			)
			(layer "F.Fab")
		)
		(fp_line
			(start 0.120396 0.3048)
			(end 0.120396 0.2794)
			(stroke
				(width 0.1)
				(type default)
			)
			(layer "F.Fab")
		)
		(fp_line
			(start 0.12065 -0.3048)
			(end 0.67945 -0.3048)
			(stroke
				(width 0.1)
				(type default)
			)
			(layer "F.Fab")
		)
		(fp_line
			(start 0.12065 -0.2794)
			(end 0.12065 -0.3048)
			(stroke
				(width 0.1)
				(type default)
			)
			(layer "F.Fab")
		)
		(fp_line
			(start 0.67945 -0.3048)
			(end 0.67945 0.3048)
			(stroke
				(width 0.1)
				(type default)
			)
			(layer "F.Fab")
		)
		(fp_line
			(start 0.67945 0.3048)
			(end 0.120396 0.3048)
			(stroke
				(width 0.1)
				(type default)
			)
			(layer "F.Fab")
		)
		(pad "1" smd circle
			(at -0.40005 0)
			(size 0 0)
			(layers "F.Cu" "F.Mask" "F.Paste")
			(net "PVCCD_HV_CPU0_VDD1")
		)
		(pad "2" smd circle
			(at 0.40005 0)
			(size 0 0)
			(layers "F.Cu" "F.Mask" "F.Paste")
			(net "GND")
		)
	)
	(footprint ""
		(layer "F.Cu")
		(at 437.875172 -29.684218 180)
		(property "Reference" "PR3839"
			(at 0 0 180)
			(layer "F.SilkS")
			(hide yes)
			(effects
				(font
					(size 1.27 1.27)
				)
			)
		)
		(property "Value" ""
			(at 0 0 180)
			(layer "F.Fab")
			(effects
				(font
					(size 1.27 1.27)
				)
			)
		)
		(duplicate_pad_numbers_are_jumpers no)
		(fp_line
			(start 0.7874 0.4064)
			(end -0.7874 0.4064)
			(stroke
				(width 0.1524)
				(type default)
			)
			(layer "F.SilkS")
		)
		(fp_line
			(start 0.7874 -0.4064)
			(end 0.7874 0.4064)
			(stroke
				(width 0.1524)
				(type default)
			)
			(layer "F.SilkS")
		)
		(fp_line
			(start -0.7874 0.4064)
			(end -0.7874 -0.4064)
			(stroke
				(width 0.1524)
				(type default)
			)
			(layer "F.SilkS")
		)
		(fp_line
			(start -0.7874 -0.4064)
			(end 0.7874 -0.4064)
			(stroke
				(width 0.1524)
				(type default)
			)
			(layer "F.SilkS")
		)
		(fp_line
			(start 0.67945 0.3048)
			(end 0.120396 0.3048)
			(stroke
				(width 0.1)
				(type default)
			)
			(layer "F.Fab")
		)
		(fp_line
			(start 0.67945 -0.3048)
			(end 0.67945 0.3048)
			(stroke
				(width 0.1)
				(type default)
			)
			(layer "F.Fab")
		)
		(fp_line
			(start 0.12065 -0.2794)
			(end 0.12065 -0.3048)
			(stroke
				(width 0.1)
				(type default)
			)
			(layer "F.Fab")
		)
		(fp_line
			(start 0.12065 -0.3048)
			(end 0.67945 -0.3048)
			(stroke
				(width 0.1)
				(type default)
			)
			(layer "F.Fab")
		)
		(fp_line
			(start 0.120396 0.3048)
			(end 0.120396 0.2794)
			(stroke
				(width 0.1)
				(type default)
			)
			(layer "F.Fab")
		)
		(fp_line
			(start 0.120396 0.2794)
			(end -0.12065 0.2794)
			(stroke
				(width 0.1)
				(type default)
			)
			(layer "F.Fab")
		)
		(fp_line
			(start -0.12065 0.3048)
			(end -0.67945 0.3048)
			(stroke
				(width 0.1)
				(type default)
			)
			(layer "F.Fab")
		)
		(fp_line
			(start -0.12065 0.2794)
			(end -0.12065 0.3048)
			(stroke
				(width 0.1)
				(type default)
			)
			(layer "F.Fab")
		)
		(fp_line
			(start -0.12065 -0.2794)
			(end 0.12065 -0.2794)
			(stroke
				(width 0.1)
				(type default)
			)
			(layer "F.Fab")
		)
		(fp_line
			(start -0.12065 -0.305054)
			(end -0.12065 -0.2794)
			(stroke
				(width 0.1)
				(type default)
			)
			(layer "F.Fab")
		)
		(fp_line
			(start -0.67945 0.3048)
			(end -0.67945 -0.305054)
			(stroke
				(width 0.1)
				(type default)
			)
			(layer "F.Fab")
		)
		(fp_line
			(start -0.67945 -0.305054)
			(end -0.12065 -0.305054)
			(stroke
				(width 0.1)
				(type default)
			)
			(layer "F.Fab")
		)
		(pad "1" smd circle
			(at -0.40005 0 180)
			(size 0 0)
			(layers "F.Cu" "F.Mask" "F.Paste")
			(net "P12V_OCP_FLTB_1")
		)
		(pad "2" smd circle
			(at 0.40005 0 180)
			(size 0 0)
			(layers "F.Cu" "F.Mask" "F.Paste")
			(net "P3V3_AUX")
		)
	)
	(footprint ""
		(layer "F.Cu")
		(at 317.396622 -51.196748)
		(property "Reference" "R3041"
			(at 0 0 0)
			(layer "F.SilkS")
			(hide yes)
			(effects
				(font
					(size 1.27 1.27)
				)
			)
		)
		(property "Value" ""
			(at 0 0 0)
			(layer "F.Fab")
			(effects
				(font
					(size 1.27 1.27)
				)
			)
		)
		(duplicate_pad_numbers_are_jumpers no)
		(fp_line
			(start -0.7874 -0.4064)
			(end 0.7874 -0.4064)
			(stroke
				(width 0.1524)
				(type default)
			)
			(layer "F.SilkS")
		)
		(fp_line
			(start -0.7874 0.4064)
			(end -0.7874 -0.4064)
			(stroke
				(width 0.1524)
				(type default)
			)
			(layer "F.SilkS")
		)
		(fp_line
			(start 0.7874 -0.4064)
			(end 0.7874 0.4064)
			(stroke
				(width 0.1524)
				(type default)
			)
			(layer "F.SilkS")
		)
		(fp_line
			(start 0.7874 0.4064)
			(end -0.7874 0.4064)
			(stroke
				(width 0.1524)
				(type default)
			)
			(layer "F.SilkS")
		)
		(fp_line
			(start -0.67945 -0.305054)
			(end -0.12065 -0.305054)
			(stroke
				(width 0.1)
				(type default)
			)
			(layer "F.Fab")
		)
		(fp_line
			(start -0.67945 0.3048)
			(end -0.67945 -0.305054)
			(stroke
				(width 0.1)
				(type default)
			)
			(layer "F.Fab")
		)
		(fp_line
			(start -0.12065 -0.305054)
			(end -0.12065 -0.2794)
			(stroke
				(width 0.1)
				(type default)
			)
			(layer "F.Fab")
		)
		(fp_line
			(start -0.12065 -0.2794)
			(end 0.12065 -0.2794)
			(stroke
				(width 0.1)
				(type default)
			)
			(layer "F.Fab")
		)
		(fp_line
			(start -0.12065 0.2794)
			(end -0.12065 0.3048)
			(stroke
				(width 0.1)
				(type default)
			)
			(layer "F.Fab")
		)
		(fp_line
			(start -0.12065 0.3048)
			(end -0.67945 0.3048)
			(stroke
				(width 0.1)
				(type default)
			)
			(layer "F.Fab")
		)
		(fp_line
			(start 0.120396 0.2794)
			(end -0.12065 0.2794)
			(stroke
				(width 0.1)
				(type default)
			)
			(layer "F.Fab")
		)
		(fp_line
			(start 0.120396 0.3048)
			(end 0.120396 0.2794)
			(stroke
				(width 0.1)
				(type default)
			)
			(layer "F.Fab")
		)
		(fp_line
			(start 0.12065 -0.3048)
			(end 0.67945 -0.3048)
			(stroke
				(width 0.1)
				(type default)
			)
			(layer "F.Fab")
		)
		(fp_line
			(start 0.12065 -0.2794)
			(end 0.12065 -0.3048)
			(stroke
				(width 0.1)
				(type default)
			)
			(layer "F.Fab")
		)
		(fp_line
			(start 0.67945 -0.3048)
			(end 0.67945 0.3048)
			(stroke
				(width 0.1)
				(type default)
			)
			(layer "F.Fab")
		)
		(fp_line
			(start 0.67945 0.3048)
			(end 0.120396 0.3048)
			(stroke
				(width 0.1)
				(type default)
			)
			(layer "F.Fab")
		)
		(pad "1" smd circle
			(at -0.40005 0)
			(size 0 0)
			(layers "F.Cu" "F.Mask" "F.Paste")
			(net "P3V3_AUX")
		)
		(pad "2" smd circle
			(at 0.40005 0)
			(size 0 0)
			(layers "F.Cu" "F.Mask" "F.Paste")
			(net "FM_PCH_GLB_RST_WARN_N")
		)
	)
	(footprint ""
		(layer "F.Cu")
		(at 77.916278 -30.112462 -90)
		(property "Reference" "PD107"
			(at 0.280924 -1.999742 0)
			(unlocked yes)
			(layer "F.SilkS")
			(effects
				(font
					(size 0.7874 0.5842)
					(thickness 0.1524)
				)
				(justify left)
			)
		)
		(property "Value" ""
			(at 0 0 270)
			(layer "F.Fab")
			(effects
				(font
					(size 1.27 1.27)
				)
			)
		)
		(duplicate_pad_numbers_are_jumpers no)
		(fp_line
			(start -2.250186 0.999998)
			(end 2.631186 0.999998)
			(stroke
				(width 0.1524)
				(type default)
			)
			(layer "F.SilkS")
		)
		(fp_line
			(start 2.631186 0.999998)
			(end 2.631186 -0.999998)
			(stroke
				(width 0.1524)
				(type default)
			)
			(layer "F.SilkS")
		)
		(fp_line
			(start -0.381 0.3302)
			(end -0.381 -0.4318)
			(stroke
				(width 0.1524)
				(type default)
			)
			(layer "F.SilkS")
		)
		(fp_line
			(start -0.381 -0.0508)
			(end -0.6604 -0.0508)
			(stroke
				(width 0.1524)
				(type default)
			)
			(layer "F.SilkS")
		)
		(fp_line
			(start 0.381 -0.0508)
			(end -0.381 0.3302)
			(stroke
				(width 0.1524)
				(type default)
			)
			(layer "F.SilkS")
		)
		(fp_line
			(start 0.381 -0.0508)
			(end 0.635 -0.0508)
			(stroke
				(width 0.1524)
				(type default)
			)
			(layer "F.SilkS")
		)
		(fp_line
			(start -0.381 -0.4318)
			(end 0.381 -0.0508)
			(stroke
				(width 0.1524)
				(type default)
			)
			(layer "F.SilkS")
		)
		(fp_line
			(start 0.381 -0.4318)
			(end 0.381 0.3302)
			(stroke
				(width 0.1524)
				(type default)
			)
			(layer "F.SilkS")
		)
		(fp_line
			(start -2.250186 -0.999998)
			(end -2.250186 0.999998)
			(stroke
				(width 0.1524)
				(type default)
			)
			(layer "F.SilkS")
		)
		(fp_line
			(start 2.631186 -0.999998)
			(end -2.250186 -0.999998)
			(stroke
				(width 0.1524)
				(type default)
			)
			(layer "F.SilkS")
		)
		(fp_rect
			(start 2.6162 1.016)
			(end 2.1844 -0.9652)
			(stroke
				(width 0)
				(type default)
			)
			(fill yes)
			(layer "F.SilkS")
		)
		(fp_line
			(start -1.450086 0.999998)
			(end 1.450086 0.999998)
			(stroke
				(width 0.1)
				(type default)
			)
			(layer "F.Fab")
		)
		(fp_line
			(start 1.450086 0.999998)
			(end 1.450086 -0.999998)
			(stroke
				(width 0.1)
				(type default)
			)
			(layer "F.Fab")
		)
		(fp_line
			(start -1.450086 -0.999998)
			(end -1.450086 0.999998)
			(stroke
				(width 0.1)
				(type default)
			)
			(layer "F.Fab")
		)
		(fp_line
			(start 1.450086 -0.999998)
			(end -1.450086 -0.999998)
			(stroke
				(width 0.1)
				(type default)
			)
			(layer "F.Fab")
		)
		(fp_text user "+"
			(at -4.134866 -0.205232 270)
			(unlocked yes)
			(layer "F.SilkS")
			(effects
				(font
					(size 1.905 1.4224)
					(thickness 0.1524)
				)
				(justify left)
			)
		)
		(fp_text user "-"
			(at 2.4384 -0.22225 270)
			(unlocked yes)
			(layer "F.SilkS")
			(effects
				(font
					(size 1.905 1.4224)
					(thickness 0.1524)
				)
				(justify left)
			)
		)
		(fp_text user "+"
			(at -3.4798 -0.22225 270)
			(unlocked yes)
			(layer "F.Fab")
			(effects
				(font
					(size 1.905 1.4224)
					(thickness 0.1524)
				)
				(justify left)
			)
		)
		(fp_text user "-"
			(at 2.4384 -0.22225 270)
			(unlocked yes)
			(layer "F.Fab")
			(effects
				(font
					(size 1.905 1.4224)
					(thickness 0.1524)
				)
				(justify left)
			)
		)
		(pad "A" smd rect
			(at -1.450086 0 270)
			(size 1.3208 1.4224)
			(layers "F.Cu" "F.Mask" "F.Paste")
			(net "GND")
		)
		(pad "C" smd rect
			(at 1.450086 0 270)
			(size 1.3208 1.4224)
			(layers "F.Cu" "F.Mask" "F.Paste")
			(net "P12V_AUX")
		)
	)
	(footprint ""
		(layer "F.Cu")
		(at 226.733608 -407.871422 180)
		(property "Reference" "PR3982"
			(at 0 0 180)
			(layer "F.SilkS")
			(hide yes)
			(effects
				(font
					(size 1.27 1.27)
				)
			)
		)
		(property "Value" ""
			(at 0 0 180)
			(layer "F.Fab")
			(effects
				(font
					(size 1.27 1.27)
				)
			)
		)
		(duplicate_pad_numbers_are_jumpers no)
		(fp_line
			(start 0.7874 0.4064)
			(end -0.7874 0.4064)
			(stroke
				(width 0.1524)
				(type default)
			)
			(layer "F.SilkS")
		)
		(fp_line
			(start 0.7874 -0.4064)
			(end 0.7874 0.4064)
			(stroke
				(width 0.1524)
				(type default)
			)
			(layer "F.SilkS")
		)
		(fp_line
			(start -0.7874 0.4064)
			(end -0.7874 -0.4064)
			(stroke
				(width 0.1524)
				(type default)
			)
			(layer "F.SilkS")
		)
		(fp_line
			(start -0.7874 -0.4064)
			(end 0.7874 -0.4064)
			(stroke
				(width 0.1524)
				(type default)
			)
			(layer "F.SilkS")
		)
		(fp_line
			(start 0.67945 0.3048)
			(end 0.120396 0.3048)
			(stroke
				(width 0.1)
				(type default)
			)
			(layer "F.Fab")
		)
		(fp_line
			(start 0.67945 -0.3048)
			(end 0.67945 0.3048)
			(stroke
				(width 0.1)
				(type default)
			)
			(layer "F.Fab")
		)
		(fp_line
			(start 0.12065 -0.2794)
			(end 0.12065 -0.3048)
			(stroke
				(width 0.1)
				(type default)
			)
			(layer "F.Fab")
		)
		(fp_line
			(start 0.12065 -0.3048)
			(end 0.67945 -0.3048)
			(stroke
				(width 0.1)
				(type default)
			)
			(layer "F.Fab")
		)
		(fp_line
			(start 0.120396 0.3048)
			(end 0.120396 0.2794)
			(stroke
				(width 0.1)
				(type default)
			)
			(layer "F.Fab")
		)
		(fp_line
			(start 0.120396 0.2794)
			(end -0.12065 0.2794)
			(stroke
				(width 0.1)
				(type default)
			)
			(layer "F.Fab")
		)
		(fp_line
			(start -0.12065 0.3048)
			(end -0.67945 0.3048)
			(stroke
				(width 0.1)
				(type default)
			)
			(layer "F.Fab")
		)
		(fp_line
			(start -0.12065 0.2794)
			(end -0.12065 0.3048)
			(stroke
				(width 0.1)
				(type default)
			)
			(layer "F.Fab")
		)
		(fp_line
			(start -0.12065 -0.2794)
			(end 0.12065 -0.2794)
			(stroke
				(width 0.1)
				(type default)
			)
			(layer "F.Fab")
		)
		(fp_line
			(start -0.12065 -0.305054)
			(end -0.12065 -0.2794)
			(stroke
				(width 0.1)
				(type default)
			)
			(layer "F.Fab")
		)
		(fp_line
			(start -0.67945 0.3048)
			(end -0.67945 -0.305054)
			(stroke
				(width 0.1)
				(type default)
			)
			(layer "F.Fab")
		)
		(fp_line
			(start -0.67945 -0.305054)
			(end -0.12065 -0.305054)
			(stroke
				(width 0.1)
				(type default)
			)
			(layer "F.Fab")
		)
		(pad "1" smd circle
			(at -0.40005 0 180)
			(size 0 0)
			(layers "F.Cu" "F.Mask" "F.Paste")
			(net "AGND_HSC")
		)
		(pad "2" smd circle
			(at 0.40005 0 180)
			(size 0 0)
			(layers "F.Cu" "F.Mask" "F.Paste")
			(net "HSC_MODE_3")
		)
	)
	(footprint ""
		(layer "F.Cu")
		(at 180.64988 -126.964948 -90)
		(property "Reference" "R271"
			(at 0 0 270)
			(layer "F.SilkS")
			(hide yes)
			(effects
				(font
					(size 1.27 1.27)
				)
			)
		)
		(property "Value" ""
			(at 0 0 270)
			(layer "F.Fab")
			(effects
				(font
					(size 1.27 1.27)
				)
			)
		)
		(duplicate_pad_numbers_are_jumpers no)
		(fp_line
			(start -0.7874 0.4064)
			(end -0.7874 -0.4064)
			(stroke
				(width 0.1524)
				(type default)
			)
			(layer "F.SilkS")
		)
		(fp_line
			(start 0.7874 0.4064)
			(end -0.7874 0.4064)
			(stroke
				(width 0.1524)
				(type default)
			)
			(layer "F.SilkS")
		)
		(fp_line
			(start -0.7874 -0.4064)
			(end 0.7874 -0.4064)
			(stroke
				(width 0.1524)
				(type default)
			)
			(layer "F.SilkS")
		)
		(fp_line
			(start 0.7874 -0.4064)
			(end 0.7874 0.4064)
			(stroke
				(width 0.1524)
				(type default)
			)
			(layer "F.SilkS")
		)
		(fp_line
			(start -0.67945 0.3048)
			(end -0.67945 -0.305054)
			(stroke
				(width 0.1)
				(type default)
			)
			(layer "F.Fab")
		)
		(fp_line
			(start -0.12065 0.3048)
			(end -0.67945 0.3048)
			(stroke
				(width 0.1)
				(type default)
			)
			(layer "F.Fab")
		)
		(fp_line
			(start 0.120396 0.3048)
			(end 0.120396 0.2794)
			(stroke
				(width 0.1)
				(type default)
			)
			(layer "F.Fab")
		)
		(fp_line
			(start 0.67945 0.3048)
			(end 0.120396 0.3048)
			(stroke
				(width 0.1)
				(type default)
			)
			(layer "F.Fab")
		)
		(fp_line
			(start -0.12065 0.2794)
			(end -0.12065 0.3048)
			(stroke
				(width 0.1)
				(type default)
			)
			(layer "F.Fab")
		)
		(fp_line
			(start 0.120396 0.2794)
			(end -0.12065 0.2794)
			(stroke
				(width 0.1)
				(type default)
			)
			(layer "F.Fab")
		)
		(fp_line
			(start -0.12065 -0.2794)
			(end 0.12065 -0.2794)
			(stroke
				(width 0.1)
				(type default)
			)
			(layer "F.Fab")
		)
		(fp_line
			(start 0.12065 -0.2794)
			(end 0.12065 -0.3048)
			(stroke
				(width 0.1)
				(type default)
			)
			(layer "F.Fab")
		)
		(fp_line
			(start 0.12065 -0.3048)
			(end 0.67945 -0.3048)
			(stroke
				(width 0.1)
				(type default)
			)
			(layer "F.Fab")
		)
		(fp_line
			(start 0.67945 -0.3048)
			(end 0.67945 0.3048)
			(stroke
				(width 0.1)
				(type default)
			)
			(layer "F.Fab")
		)
		(fp_line
			(start -0.67945 -0.305054)
			(end -0.12065 -0.305054)
			(stroke
				(width 0.1)
				(type default)
			)
			(layer "F.Fab")
		)
		(fp_line
			(start -0.12065 -0.305054)
			(end -0.12065 -0.2794)
			(stroke
				(width 0.1)
				(type default)
			)
			(layer "F.Fab")
		)
		(pad "1" smd circle
			(at -0.40005 0 270)
			(size 0 0)
			(layers "F.Cu" "F.Mask" "F.Paste")
			(net "P3V3_AUX")
		)
		(pad "2" smd circle
			(at 0.40005 0 270)
			(size 0 0)
			(layers "F.Cu" "F.Mask" "F.Paste")
			(net "FM_CPU1_PKGID1")
		)
	)
	(footprint ""
		(layer "F.Cu")
		(at 437.93537 -174.805594)
		(property "Reference" "PR4683"
			(at 0 0 0)
			(layer "F.SilkS")
			(hide yes)
			(effects
				(font
					(size 1.27 1.27)
				)
			)
		)
		(property "Value" ""
			(at 0 0 0)
			(layer "F.Fab")
			(effects
				(font
					(size 1.27 1.27)
				)
			)
		)
		(duplicate_pad_numbers_are_jumpers no)
		(fp_line
			(start -0.7874 -0.4064)
			(end 0.7874 -0.4064)
			(stroke
				(width 0.1524)
				(type default)
			)
			(layer "F.SilkS")
		)
		(fp_line
			(start -0.7874 0.4064)
			(end -0.7874 -0.4064)
			(stroke
				(width 0.1524)
				(type default)
			)
			(layer "F.SilkS")
		)
		(fp_line
			(start 0.7874 -0.4064)
			(end 0.7874 0.4064)
			(stroke
				(width 0.1524)
				(type default)
			)
			(layer "F.SilkS")
		)
		(fp_line
			(start 0.7874 0.4064)
			(end -0.7874 0.4064)
			(stroke
				(width 0.1524)
				(type default)
			)
			(layer "F.SilkS")
		)
		(fp_line
			(start -0.67945 -0.305054)
			(end -0.12065 -0.305054)
			(stroke
				(width 0.1)
				(type default)
			)
			(layer "F.Fab")
		)
		(fp_line
			(start -0.67945 0.3048)
			(end -0.67945 -0.305054)
			(stroke
				(width 0.1)
				(type default)
			)
			(layer "F.Fab")
		)
		(fp_line
			(start -0.12065 -0.305054)
			(end -0.12065 -0.2794)
			(stroke
				(width 0.1)
				(type default)
			)
			(layer "F.Fab")
		)
		(fp_line
			(start -0.12065 -0.2794)
			(end 0.12065 -0.2794)
			(stroke
				(width 0.1)
				(type default)
			)
			(layer "F.Fab")
		)
		(fp_line
			(start -0.12065 0.2794)
			(end -0.12065 0.3048)
			(stroke
				(width 0.1)
				(type default)
			)
			(layer "F.Fab")
		)
		(fp_line
			(start -0.12065 0.3048)
			(end -0.67945 0.3048)
			(stroke
				(width 0.1)
				(type default)
			)
			(layer "F.Fab")
		)
		(fp_line
			(start 0.120396 0.2794)
			(end -0.12065 0.2794)
			(stroke
				(width 0.1)
				(type default)
			)
			(layer "F.Fab")
		)
		(fp_line
			(start 0.120396 0.3048)
			(end 0.120396 0.2794)
			(stroke
				(width 0.1)
				(type default)
			)
			(layer "F.Fab")
		)
		(fp_line
			(start 0.12065 -0.3048)
			(end 0.67945 -0.3048)
			(stroke
				(width 0.1)
				(type default)
			)
			(layer "F.Fab")
		)
		(fp_line
			(start 0.12065 -0.2794)
			(end 0.12065 -0.3048)
			(stroke
				(width 0.1)
				(type default)
			)
			(layer "F.Fab")
		)
		(fp_line
			(start 0.67945 -0.3048)
			(end 0.67945 0.3048)
			(stroke
				(width 0.1)
				(type default)
			)
			(layer "F.Fab")
		)
		(fp_line
			(start 0.67945 0.3048)
			(end 0.120396 0.3048)
			(stroke
				(width 0.1)
				(type default)
			)
			(layer "F.Fab")
		)
		(pad "1" smd circle
			(at -0.40005 0)
			(size 0 0)
			(layers "F.Cu" "F.Mask" "F.Paste")
			(net "PVNN_MAIN_CPU0_FB_RC")
		)
		(pad "2" smd circle
			(at 0.40005 0)
			(size 0 0)
			(layers "F.Cu" "F.Mask" "F.Paste")
			(net "PVNN_MAIN_CPU0")
		)
	)
	(footprint ""
		(layer "F.Cu")
		(at 25.632156 -180.529738 90)
		(property "Reference" "PC1283"
			(at 0 0 90)
			(layer "F.SilkS")
			(hide yes)
			(effects
				(font
					(size 1.27 1.27)
				)
			)
		)
		(property "Value" ""
			(at 0 0 90)
			(layer "F.Fab")
			(effects
				(font
					(size 1.27 1.27)
				)
			)
		)
		(duplicate_pad_numbers_are_jumpers no)
		(fp_line
			(start 0.7874 -0.4064)
			(end 0.7874 0.4064)
			(stroke
				(width 0.1524)
				(type default)
			)
			(layer "F.SilkS")
		)
		(fp_line
			(start -0.7874 -0.4064)
			(end 0.7874 -0.4064)
			(stroke
				(width 0.1524)
				(type default)
			)
			(layer "F.SilkS")
		)
		(fp_line
			(start 0.7874 0.4064)
			(end -0.7874 0.4064)
			(stroke
				(width 0.1524)
				(type default)
			)
			(layer "F.SilkS")
		)
		(fp_line
			(start -0.7874 0.4064)
			(end -0.7874 -0.4064)
			(stroke
				(width 0.1524)
				(type default)
			)
			(layer "F.SilkS")
		)
		(fp_line
			(start -0.12065 -0.305054)
			(end -0.12065 -0.2794)
			(stroke
				(width 0.1)
				(type default)
			)
			(layer "F.Fab")
		)
		(fp_line
			(start -0.67945 -0.305054)
			(end -0.12065 -0.305054)
			(stroke
				(width 0.1)
				(type default)
			)
			(layer "F.Fab")
		)
		(fp_line
			(start 0.67945 -0.3048)
			(end 0.67945 0.3048)
			(stroke
				(width 0.1)
				(type default)
			)
			(layer "F.Fab")
		)
		(fp_line
			(start 0.12065 -0.3048)
			(end 0.67945 -0.3048)
			(stroke
				(width 0.1)
				(type default)
			)
			(layer "F.Fab")
		)
		(fp_line
			(start 0.12065 -0.2794)
			(end 0.12065 -0.3048)
			(stroke
				(width 0.1)
				(type default)
			)
			(layer "F.Fab")
		)
		(fp_line
			(start -0.12065 -0.2794)
			(end 0.12065 -0.2794)
			(stroke
				(width 0.1)
				(type default)
			)
			(layer "F.Fab")
		)
		(fp_line
			(start 0.120396 0.2794)
			(end -0.12065 0.2794)
			(stroke
				(width 0.1)
				(type default)
			)
			(layer "F.Fab")
		)
		(fp_line
			(start -0.12065 0.2794)
			(end -0.12065 0.3048)
			(stroke
				(width 0.1)
				(type default)
			)
			(layer "F.Fab")
		)
		(fp_line
			(start 0.67945 0.3048)
			(end 0.120396 0.3048)
			(stroke
				(width 0.1)
				(type default)
			)
			(layer "F.Fab")
		)
		(fp_line
			(start 0.120396 0.3048)
			(end 0.120396 0.2794)
			(stroke
				(width 0.1)
				(type default)
			)
			(layer "F.Fab")
		)
		(fp_line
			(start -0.12065 0.3048)
			(end -0.67945 0.3048)
			(stroke
				(width 0.1)
				(type default)
			)
			(layer "F.Fab")
		)
		(fp_line
			(start -0.67945 0.3048)
			(end -0.67945 -0.305054)
			(stroke
				(width 0.1)
				(type default)
			)
			(layer "F.Fab")
		)
		(pad "1" smd circle
			(at -0.40005 0 90)
			(size 0 0)
			(layers "F.Cu" "F.Mask" "F.Paste")
			(net "SW_PVNN_MAIN_CPU1_BST_R")
		)
		(pad "2" smd circle
			(at 0.40005 0 90)
			(size 0 0)
			(layers "F.Cu" "F.Mask" "F.Paste")
			(net "SW_PVNN_MAIN_CPU1_SW")
		)
	)
	(footprint ""
		(layer "F.Cu")
		(at 177.694082 -28.937712 -90)
		(property "Reference" "PU299"
			(at -3.695446 10.633202 0)
			(unlocked yes)
			(layer "F.SilkS")
			(effects
				(font
					(size 0.7874 0.5842)
					(thickness 0.1524)
				)
				(justify left)
			)
		)
		(property "Value" ""
			(at 0 0 270)
			(layer "F.Fab")
			(effects
				(font
					(size 1.27 1.27)
				)
			)
		)
		(duplicate_pad_numbers_are_jumpers no)
		(fp_line
			(start -1.549908 2.549906)
			(end -0.753872 2.549906)
			(stroke
				(width 0.1524)
				(type default)
			)
			(layer "F.SilkS")
		)
		(fp_line
			(start -0.245872 2.549906)
			(end 0.245872 2.549906)
			(stroke
				(width 0.1524)
				(type default)
			)
			(layer "F.SilkS")
		)
		(fp_line
			(start 0.753872 2.549906)
			(end 1.549908 2.549906)
			(stroke
				(width 0.1524)
				(type default)
			)
			(layer "F.SilkS")
		)
		(fp_line
			(start 1.549908 2.549906)
			(end 1.549908 2.253996)
			(stroke
				(width 0.1524)
				(type default)
			)
			(layer "F.SilkS")
		)
		(fp_line
			(start -1.549908 2.253996)
			(end -1.549908 2.549906)
			(stroke
				(width 0.1524)
				(type default)
			)
			(layer "F.SilkS")
		)
		(fp_line
			(start 1.549908 -2.253996)
			(end 1.549908 -2.549906)
			(stroke
				(width 0.1524)
				(type default)
			)
			(layer "F.SilkS")
		)
		(fp_line
			(start -1.549908 -2.549906)
			(end -1.549908 -2.251964)
			(stroke
				(width 0.1524)
				(type default)
			)
			(layer "F.SilkS")
		)
		(fp_line
			(start -0.752094 -2.549906)
			(end -1.549908 -2.549906)
			(stroke
				(width 0.1524)
				(type default)
			)
			(layer "F.SilkS")
		)
		(fp_line
			(start 0.2413 -2.549906)
			(end -0.2413 -2.549906)
			(stroke
				(width 0.1524)
				(type default)
			)
			(layer "F.SilkS")
		)
		(fp_line
			(start 1.549908 -2.549906)
			(end 0.752094 -2.549906)
			(stroke
				(width 0.1524)
				(type default)
			)
			(layer "F.SilkS")
		)
		(fp_poly
			(pts
				(xy -2.7432 -1.574292) (xy -2.7432 -2.4257) (xy -1.891538 -1.999996)
			)
			(stroke
				(width 0)
				(type default)
			)
			(fill yes)
			(layer "F.SilkS")
		)
		(fp_line
			(start -1.549908 2.549906)
			(end 1.549908 2.549906)
			(stroke
				(width 0.1)
				(type default)
			)
			(layer "F.Fab")
		)
		(fp_line
			(start 1.549908 2.549906)
			(end 1.549908 -2.549906)
			(stroke
				(width 0.1)
				(type default)
			)
			(layer "F.Fab")
		)
		(fp_line
			(start -1.549908 -2.549906)
			(end -1.549908 2.549906)
			(stroke
				(width 0.1)
				(type default)
			)
			(layer "F.Fab")
		)
		(fp_line
			(start 1.549908 -2.549906)
			(end -1.549908 -2.549906)
			(stroke
				(width 0.1)
				(type default)
			)
			(layer "F.Fab")
		)
		(fp_poly
			(pts
				(xy -1.891538 -1.999996) (xy -2.7432 -1.574292) (xy -2.7432 -2.4257)
			)
			(stroke
				(width 0)
				(type default)
			)
			(fill yes)
			(layer "F.Fab")
		)
		(fp_text user "11"
			(at 2.959354 5.367782 0)
			(unlocked yes)
			(layer "F.SilkS")
			(effects
				(font
					(size 0.635 0.4064)
					(thickness 0.1524)
				)
			)
		)
		(fp_text user "10"
			(at -2.087626 2.863342 0)
			(unlocked yes)
			(layer "F.SilkS")
			(effects
				(font
					(size 0.635 0.4064)
					(thickness 0.1524)
				)
			)
		)
		(fp_text user "9"
			(at -2.478786 1.346962 180)
			(unlocked yes)
			(layer "F.SilkS")
			(effects
				(font
					(size 0.635 0.4064)
					(thickness 0.1524)
				)
			)
		)
		(fp_text user "12"
			(at 3.713734 0.864362 0)
			(unlocked yes)
			(layer "F.SilkS")
			(effects
				(font
					(size 0.635 0.4064)
					(thickness 0.1524)
				)
			)
		)
		(fp_text user "20"
			(at 1.641094 -4.164838 0)
			(unlocked yes)
			(layer "F.SilkS")
			(effects
				(font
					(size 0.635 0.4064)
					(thickness 0.1524)
				)
			)
		)
		(fp_text user "21_22"
			(at -1.886966 -4.454398 0)
			(unlocked yes)
			(layer "F.SilkS")
			(effects
				(font
					(size 0.635 0.4064)
					(thickness 0.1524)
				)
			)
		)
		(fp_text user "11"
			(at 1.1938 3.329432 270)
			(unlocked yes)
			(layer "F.Fab")
			(effects
				(font
					(size 0.635 0.4064)
					(thickness 0.1524)
				)
			)
		)
		(fp_text user "10"
			(at -1.4224 3.253232 270)
			(unlocked yes)
			(layer "F.Fab")
			(effects
				(font
					(size 0.635 0.4064)
					(thickness 0.1524)
				)
			)
		)
		(fp_text user "12"
			(at 2.207768 2.7178 180)
			(unlocked yes)
			(layer "F.Fab")
			(effects
				(font
					(size 0.635 0.4064)
					(thickness 0.1524)
				)
			)
		)
		(fp_text user "9"
			(at -2.338832 2.5908 180)
			(unlocked yes)
			(layer "F.Fab")
			(effects
				(font
					(size 0.635 0.4064)
					(thickness 0.1524)
				)
			)
		)
		(fp_text user "20"
			(at 2.055368 -2.7686 180)
			(unlocked yes)
			(layer "F.Fab")
			(effects
				(font
					(size 0.635 0.4064)
					(thickness 0.1524)
				)
			)
		)
		(fp_text user "21_22"
			(at -0.0762 -3.401568 270)
			(unlocked yes)
			(layer "F.Fab")
			(effects
				(font
					(size 0.635 0.4064)
					(thickness 0.1524)
				)
			)
		)
		(pad "1" smd circle
			(at -1.374902 -1.999996 180)
			(size 0 0)
			(layers "F.Cu" "F.Mask" "F.Paste")
			(net "P12V_SCM_EN_R2")
		)
		(pad "2" smd rect
			(at -1.400048 -1.500124 180)
			(size 0.254 0.8128)
			(layers "F.Cu" "F.Mask" "F.Paste")
			(net "GND")
		)
		(pad "3" smd rect
			(at -1.400048 -0.999998 180)
			(size 0.254 0.8128)
			(layers "F.Cu" "F.Mask" "F.Paste")
			(net "GND")
		)
		(pad "4" smd rect
			(at -1.400048 -0.499872 180)
			(size 0.254 0.8128)
			(layers "F.Cu" "F.Mask" "F.Paste")
			(net "P12V_SCM_TIMER")
		)
		(pad "5" smd rect
			(at -1.400048 0 180)
			(size 0.254 0.8128)
			(layers "F.Cu" "F.Mask" "F.Paste")
			(net "P12V_SCM_ISET")
		)
		(pad "6" smd rect
			(at -1.400048 0.499872 180)
			(size 0.254 0.8128)
			(layers "F.Cu" "F.Mask" "F.Paste")
			(net "P12V_SCM_SS")
		)
		(pad "7" smd rect
			(at -1.400048 0.999998 180)
			(size 0.254 0.8128)
			(layers "F.Cu" "F.Mask" "F.Paste")
			(net "GND")
		)
		(pad "8" smd rect
			(at -1.400048 1.500124 180)
			(size 0.254 0.8128)
			(layers "F.Cu" "F.Mask" "F.Paste")
			(net "P12V_SCM_IMON")
		)
		(pad "9" smd rect
			(at -1.400048 1.999996 180)
			(size 0.254 0.8128)
			(layers "F.Cu" "F.Mask" "F.Paste")
			(net "P12V_SCM_FLTB_N")
		)
		(pad "10" smd rect
			(at -0.499872 2.400046 270)
			(size 0.254 0.8128)
			(layers "F.Cu" "F.Mask" "F.Paste")
			(net "HP_LVC3_SCM_HSC_PWRGD_R")
		)
		(pad "11" smd rect
			(at 0.499872 2.400046 270)
			(size 0.254 0.8128)
			(layers "F.Cu" "F.Mask" "F.Paste")
			(net "P12V_SCM_OV_FB")
		)
		(pad "12" smd rect
			(at 1.400048 1.999996 180)
			(size 0.254 0.8128)
			(layers "F.Cu" "F.Mask" "F.Paste")
			(net "P12V_SCM_AVIN_PD")
		)
		(pad "13" smd rect
			(at 1.400048 1.500124 180)
			(size 0.254 0.8128)
			(layers "F.Cu" "F.Mask" "F.Paste")
			(net "P12V_SCM_R")
		)
		(pad "14" smd rect
			(at 1.400048 0.999998 180)
			(size 0.254 0.8128)
			(layers "F.Cu" "F.Mask" "F.Paste")
			(net "P12V_SCM_R")
		)
		(pad "15" smd rect
			(at 1.400048 0.499872 180)
			(size 0.254 0.8128)
			(layers "F.Cu" "F.Mask" "F.Paste")
			(net "P12V_SCM_R")
		)
		(pad "16" smd rect
			(at 1.400048 0 180)
			(size 0.254 0.8128)
			(layers "F.Cu" "F.Mask" "F.Paste")
			(net "P12V_SCM_R")
		)
		(pad "17" smd rect
			(at 1.400048 -0.499872 180)
			(size 0.254 0.8128)
			(layers "F.Cu" "F.Mask" "F.Paste")
			(net "P12V_SCM_R")
		)
		(pad "18" smd rect
			(at 1.400048 -0.999998 180)
			(size 0.254 0.8128)
			(layers "F.Cu" "F.Mask" "F.Paste")
			(net "P12V_SCM_R")
		)
		(pad "19" smd rect
			(at 1.400048 -1.500124 180)
			(size 0.254 0.8128)
			(layers "F.Cu" "F.Mask" "F.Paste")
			(net "P12V_SCM_R")
		)
		(pad "20" smd rect
			(at 1.400048 -1.999996 180)
			(size 0.254 0.8128)
			(layers "F.Cu" "F.Mask" "F.Paste")
			(net "P12V_SCM_R")
		)
		(pad "21_22" smd circle
			(at 0.499872 -2.337562 180)
			(size 0 0)
			(layers "F.Cu" "F.Mask" "F.Paste")
			(net "P12V_AUX")
		)
		(pad "23" smd rect
			(at 0 -1.100074 180)
			(size 0.254 1.27)
			(layers "F.Cu" "F.Mask" "F.Paste")
			(net "P12V_AUX")
		)
		(pad "24" smd rect
			(at 0 -0.199898 180)
			(size 0.254 1.27)
			(layers "F.Cu" "F.Mask" "F.Paste")
			(net "P12V_AUX")
		)
		(pad "25" smd rect
			(at 0 0.700024 180)
			(size 0.254 1.27)
			(layers "F.Cu" "F.Mask" "F.Paste")
			(net "P12V_AUX")
		)
		(pad "26" smd rect
			(at 0 1.599946 180)
			(size 0.254 1.27)
			(layers "F.Cu" "F.Mask" "F.Paste")
			(net "P12V_AUX")
		)
	)
	(footprint ""
		(layer "F.Cu")
		(at 14.064996 -99.136454 -90)
		(property "Reference" "U268"
			(at -3.321558 -3.514598 0)
			(unlocked yes)
			(layer "F.SilkS")
			(effects
				(font
					(size 0.7874 0.5842)
					(thickness 0.1524)
				)
				(justify left)
			)
		)
		(property "Value" ""
			(at 0 0 270)
			(layer "F.Fab")
			(effects
				(font
					(size 1.27 1.27)
				)
			)
		)
		(duplicate_pad_numbers_are_jumpers no)
		(fp_line
			(start -0.508 2.921)
			(end -0.508 3.683)
			(stroke
				(width 0.1524)
				(type default)
			)
			(layer "F.SilkS")
		)
		(fp_line
			(start -2.500122 2.500122)
			(end -2.500122 1.778)
			(stroke
				(width 0.1524)
				(type default)
			)
			(layer "F.SilkS")
		)
		(fp_line
			(start -1.778 2.500122)
			(end -2.500122 2.500122)
			(stroke
				(width 0.1524)
				(type default)
			)
			(layer "F.SilkS")
		)
		(fp_line
			(start 2.500122 2.500122)
			(end 1.778 2.500122)
			(stroke
				(width 0.1524)
				(type default)
			)
			(layer "F.SilkS")
		)
		(fp_line
			(start 2.500122 1.778)
			(end 2.500122 2.500122)
			(stroke
				(width 0.1524)
				(type default)
			)
			(layer "F.SilkS")
		)
		(fp_line
			(start 2.921 1.524)
			(end 3.302 1.524)
			(stroke
				(width 0.1524)
				(type default)
			)
			(layer "F.SilkS")
		)
		(fp_line
			(start -2.921 0.508)
			(end -3.302 0.508)
			(stroke
				(width 0.1524)
				(type default)
			)
			(layer "F.SilkS")
		)
		(fp_line
			(start 2.921 -1.016)
			(end 3.683 -1.016)
			(stroke
				(width 0.1524)
				(type default)
			)
			(layer "F.SilkS")
		)
		(fp_line
			(start -2.500122 -1.778)
			(end -2.500122 -2.500122)
			(stroke
				(width 0.1524)
				(type default)
			)
			(layer "F.SilkS")
		)
		(fp_line
			(start -2.500122 -2.500122)
			(end -1.778 -2.500122)
			(stroke
				(width 0.1524)
				(type default)
			)
			(layer "F.SilkS")
		)
		(fp_line
			(start 1.778 -2.500122)
			(end 2.500122 -2.500122)
			(stroke
				(width 0.1524)
				(type default)
			)
			(layer "F.SilkS")
		)
		(fp_line
			(start 2.500122 -2.500122)
			(end 2.500122 -1.778)
			(stroke
				(width 0.1524)
				(type default)
			)
			(layer "F.SilkS")
		)
		(fp_line
			(start 0 -2.921)
			(end 0 -3.302)
			(stroke
				(width 0.1524)
				(type default)
			)
			(layer "F.SilkS")
		)
		(fp_poly
			(pts
				(xy -2.65938 -1.724152) (xy -3.578352 -2.030222) (xy -2.965704 -2.64287)
			)
			(stroke
				(width 0)
				(type default)
			)
			(fill yes)
			(layer "F.SilkS")
		)
		(fp_line
			(start -0.508 2.921)
			(end -0.508 3.683)
			(stroke
				(width 0.1)
				(type default)
			)
			(layer "F.Fab")
		)
		(fp_line
			(start -2.500122 2.500122)
			(end -2.500122 -2.500122)
			(stroke
				(width 0.1)
				(type default)
			)
			(layer "F.Fab")
		)
		(fp_line
			(start 2.500122 2.500122)
			(end -2.500122 2.500122)
			(stroke
				(width 0.1)
				(type default)
			)
			(layer "F.Fab")
		)
		(fp_line
			(start 2.921 1.524)
			(end 3.302 1.524)
			(stroke
				(width 0.1)
				(type default)
			)
			(layer "F.Fab")
		)
		(fp_line
			(start -2.921 0.508)
			(end -3.302 0.508)
			(stroke
				(width 0.1)
				(type default)
			)
			(layer "F.Fab")
		)
		(fp_line
			(start 2.921 -1.016)
			(end 3.683 -1.016)
			(stroke
				(width 0.1)
				(type default)
			)
			(layer "F.Fab")
		)
		(fp_line
			(start -2.500122 -2.500122)
			(end 2.500122 -2.500122)
			(stroke
				(width 0.1)
				(type default)
			)
			(layer "F.Fab")
		)
		(fp_line
			(start 2.500122 -2.500122)
			(end 2.500122 2.500122)
			(stroke
				(width 0.1)
				(type default)
			)
			(layer "F.Fab")
		)
		(fp_line
			(start 0 -2.921)
			(end 0 -3.302)
			(stroke
				(width 0.1)
				(type default)
			)
			(layer "F.Fab")
		)
		(fp_poly
			(pts
				(xy -3.7592 -1.933194) (xy -2.892806 -1.500124) (xy -3.7592 -1.0668)
			)
			(stroke
				(width 0)
				(type default)
			)
			(fill yes)
			(layer "F.Fab")
		)
		(fp_text user "15"
			(at 4.098036 4.054856 0)
			(unlocked yes)
			(layer "F.SilkS")
			(effects
				(font
					(size 0.635 0.4064)
					(thickness 0.1524)
				)
			)
		)
		(fp_text user "14"
			(at 1.484376 3.513836 0)
			(unlocked yes)
			(layer "F.SilkS")
			(effects
				(font
					(size 0.635 0.4064)
					(thickness 0.1524)
				)
			)
		)
		(fp_text user "8"
			(at -2.064004 2.993136 0)
			(unlocked yes)
			(layer "F.SilkS")
			(effects
				(font
					(size 0.635 0.4064)
					(thickness 0.1524)
				)
			)
		)
		(fp_text user "7"
			(at -3.147568 1.8034 0)
			(unlocked yes)
			(layer "F.SilkS")
			(effects
				(font
					(size 0.635 0.4064)
					(thickness 0.1524)
				)
			)
		)
		(fp_text user "28"
			(at -1.304544 -3.471164 0)
			(unlocked yes)
			(layer "F.SilkS")
			(effects
				(font
					(size 0.635 0.4064)
					(thickness 0.1524)
				)
			)
		)
		(fp_text user "21"
			(at 4.557776 -3.974084 0)
			(unlocked yes)
			(layer "F.SilkS")
			(effects
				(font
					(size 0.635 0.4064)
					(thickness 0.1524)
				)
			)
		)
		(fp_text user "22"
			(at 3.315716 -4.591304 0)
			(unlocked yes)
			(layer "F.SilkS")
			(effects
				(font
					(size 0.635 0.4064)
					(thickness 0.1524)
				)
			)
		)
		(fp_text user "8"
			(at -1.8796 3.253232 270)
			(unlocked yes)
			(layer "F.Fab")
			(effects
				(font
					(size 0.635 0.4064)
					(thickness 0.1524)
				)
			)
		)
		(fp_text user "14"
			(at 2.1336 3.253232 270)
			(unlocked yes)
			(layer "F.Fab")
			(effects
				(font
					(size 0.635 0.4064)
					(thickness 0.1524)
				)
			)
		)
		(fp_text user "15"
			(at 3.253232 2.2352 0)
			(unlocked yes)
			(layer "F.Fab")
			(effects
				(font
					(size 0.635 0.4064)
					(thickness 0.1524)
				)
			)
		)
		(fp_text user "7"
			(at -3.147568 1.8034 0)
			(unlocked yes)
			(layer "F.Fab")
			(effects
				(font
					(size 0.635 0.4064)
					(thickness 0.1524)
				)
			)
		)
		(fp_text user "21"
			(at 3.227832 -2.2606 0)
			(unlocked yes)
			(layer "F.Fab")
			(effects
				(font
					(size 0.635 0.4064)
					(thickness 0.1524)
				)
			)
		)
		(fp_text user "28"
			(at -2.2098 -3.172968 270)
			(unlocked yes)
			(layer "F.Fab")
			(effects
				(font
					(size 0.635 0.4064)
					(thickness 0.1524)
				)
			)
		)
		(fp_text user "22"
			(at 2.2352 -3.172968 270)
			(unlocked yes)
			(layer "F.Fab")
			(effects
				(font
					(size 0.635 0.4064)
					(thickness 0.1524)
				)
			)
		)
		(pad "1" smd rect
			(at -2.412492 -1.500124)
			(size 0.254 0.7366)
			(layers "F.Cu" "F.Mask" "F.Paste")
			(net "USB2_P0_R_DN")
		)
		(pad "2" smd rect
			(at -2.412492 -0.999998)
			(size 0.254 0.7366)
			(layers "F.Cu" "F.Mask" "F.Paste")
			(net "USB2_P0_R_DP")
		)
		(pad "3" smd rect
			(at -2.412492 -0.499872)
			(size 0.254 0.7366)
			(layers "F.Cu" "F.Mask" "F.Paste")
			(net "USB2_HUB_SWB_DN")
		)
		(pad "4" smd rect
			(at -2.412492 0)
			(size 0.254 0.7366)
			(layers "F.Cu" "F.Mask" "F.Paste")
			(net "USB2_HUB_SWB_DP")
		)
		(pad "5" smd rect
			(at -2.412492 0.499872)
			(size 0.254 0.7366)
			(layers "F.Cu" "F.Mask" "F.Paste")
			(net "P3V3_AUX_USB_HUB")
		)
		(pad "6" smd rect
			(at -2.412492 0.999998)
			(size 0.254 0.7366)
			(layers "F.Cu" "F.Mask" "F.Paste")
			(net "NC_USB_HUB_DM2")
		)
		(pad "7" smd rect
			(at -2.412492 1.500124)
			(size 0.254 0.7366)
			(layers "F.Cu" "F.Mask" "F.Paste")
			(net "NC_USB_HUB_DP2")
		)
		(pad "8" smd rect
			(at -1.500124 2.412492 270)
			(size 0.254 0.7366)
			(layers "F.Cu" "F.Mask" "F.Paste")
			(net "USB_HUB_RREF")
		)
		(pad "9" smd rect
			(at -0.999998 2.412492 270)
			(size 0.254 0.7366)
			(layers "F.Cu" "F.Mask" "F.Paste")
			(net "P3V3_AUX_USB_HUB")
		)
		(pad "10" smd rect
			(at -0.499872 2.412492 270)
			(size 0.254 0.7366)
			(layers "F.Cu" "F.Mask" "F.Paste")
			(net "USB_HUB_XTAL_IN")
		)
		(pad "11" smd rect
			(at 0 2.412492 270)
			(size 0.254 0.7366)
			(layers "F.Cu" "F.Mask" "F.Paste")
			(net "USB_HUB_XTAL_OUT")
		)
		(pad "12" smd rect
			(at 0.499872 2.412492 270)
			(size 0.254 0.7366)
			(layers "F.Cu" "F.Mask" "F.Paste")
			(net "NC_USB_HUB_DM3")
		)
		(pad "13" smd rect
			(at 0.999998 2.412492 270)
			(size 0.254 0.7366)
			(layers "F.Cu" "F.Mask" "F.Paste")
			(net "NC_USB_HUB_DP3")
		)
		(pad "14" smd rect
			(at 1.500124 2.412492 270)
			(size 0.254 0.7366)
			(layers "F.Cu" "F.Mask" "F.Paste")
			(net "P3V3_AUX_USB_HUB")
		)
		(pad "15" smd rect
			(at 2.412492 1.500124)
			(size 0.254 0.7366)
			(layers "F.Cu" "F.Mask" "F.Paste")
			(net "NC_USB_HUB_DM4")
		)
		(pad "16" smd rect
			(at 2.412492 0.999998)
			(size 0.254 0.7366)
			(layers "F.Cu" "F.Mask" "F.Paste")
			(net "NC_USB_HUB_DP4")
		)
		(pad "17" smd rect
			(at 2.412492 0.499872)
			(size 0.254 0.7366)
			(layers "F.Cu" "F.Mask" "F.Paste")
			(net "RST_USB_HUB_R_N")
		)
		(pad "18" smd rect
			(at 2.412492 0)
			(size 0.254 0.7366)
			(layers "F.Cu" "F.Mask" "F.Paste")
			(net "USB_HUB_TEST")
		)
		(pad "19" smd rect
			(at 2.412492 -0.499872)
			(size 0.254 0.7366)
			(layers "F.Cu" "F.Mask" "F.Paste")
			(net "USB_HUB_OVCUR4")
		)
		(pad "20" smd rect
			(at 2.412492 -0.999998)
			(size 0.254 0.7366)
			(layers "F.Cu" "F.Mask" "F.Paste")
			(net "USB_HUB_OVCUR3")
		)
		(pad "21" smd rect
			(at 2.412492 -1.500124)
			(size 0.254 0.7366)
			(layers "F.Cu" "F.Mask" "F.Paste")
			(net "USB_HUB_DVDD")
		)
		(pad "22" smd rect
			(at 1.500124 -2.412492 270)
			(size 0.254 0.7366)
			(layers "F.Cu" "F.Mask" "F.Paste")
			(net "USB_HUB_PSELF")
		)
		(pad "23" smd rect
			(at 0.999998 -2.412492 270)
			(size 0.254 0.7366)
			(layers "F.Cu" "F.Mask" "F.Paste")
			(net "USB_HUB_PGANG")
		)
		(pad "24" smd rect
			(at 0.499872 -2.412492 270)
			(size 0.254 0.7366)
			(layers "F.Cu" "F.Mask" "F.Paste")
			(net "USB_HUB_OVCUR2")
		)
		(pad "25" smd rect
			(at 0 -2.412492 270)
			(size 0.254 0.7366)
			(layers "F.Cu" "F.Mask" "F.Paste")
			(net "USB_HUB_OVCUR1")
		)
		(pad "26" smd rect
			(at -0.499872 -2.412492 270)
			(size 0.254 0.7366)
			(layers "F.Cu" "F.Mask" "F.Paste")
			(net "NC_USB_HUB_SDA")
		)
		(pad "27" smd rect
			(at -0.999998 -2.412492 270)
			(size 0.254 0.7366)
			(layers "F.Cu" "F.Mask" "F.Paste")
			(net "P3V3_AUX_USB_HUB")
		)
		(pad "28" smd rect
			(at -1.500124 -2.412492 270)
			(size 0.254 0.7366)
			(layers "F.Cu" "F.Mask" "F.Paste")
			(net "P3V3_AUX_USB_HUB")
		)
		(pad "TH" smd rect
			(at 0 0 270)
			(size 3.556 3.556)
			(layers "F.Cu" "F.Mask" "F.Paste")
			(net "GND")
		)
		(zone
			(layer "F.Cu")
			(hatch none 0.5)
			(connect_pads
				(clearance 0)
			)
			(min_thickness 0.25)
			(keepout
				(tracks not_allowed)
				(vias allowed)
				(pads allowed)
				(copperpour not_allowed)
				(footprints allowed)
			)
			(placement
				(enabled no)
				(sheetname "")
			)
			(fill
				(thermal_gap 0.5)
				(thermal_bridge_width 0.5)
				(island_removal_mode 0)
			)
			(polygon
				(pts
					(xy 16.046196 -98.196654) (xy 15.893796 -98.196654) (xy 15.893796 -100.965254) (xy 12.236196 -100.965254)
					(xy 12.236196 -97.307654) (xy 15.893796 -97.307654) (xy 15.893796 -98.171254) (xy 16.046196 -98.171254)
					(xy 16.046196 -97.155254) (xy 12.083796 -97.155254) (xy 12.083796 -101.117654) (xy 16.046196 -101.117654)
				)
			)
		)
	)
	(footprint ""
		(layer "F.Cu")
		(at 420.52494 -105.207308)
		(property "Reference" "PU205"
			(at -5.1562 -1.20523 0)
			(unlocked yes)
			(layer "F.SilkS")
			(effects
				(font
					(size 0.7874 0.5842)
					(thickness 0.1524)
				)
			)
		)
		(property "Value" ""
			(at 0 0 0)
			(layer "F.Fab")
			(effects
				(font
					(size 1.27 1.27)
				)
			)
		)
		(duplicate_pad_numbers_are_jumpers no)
		(fp_line
			(start -1.239774 -1.495298)
			(end 1.239774 -1.495298)
			(stroke
				(width 0.1524)
				(type default)
			)
			(layer "F.SilkS")
		)
		(fp_line
			(start -1.239774 1.495298)
			(end -1.239774 -1.495298)
			(stroke
				(width 0.1524)
				(type default)
			)
			(layer "F.SilkS")
		)
		(fp_line
			(start 1.239774 -1.495298)
			(end 1.239774 1.495298)
			(stroke
				(width 0.1524)
				(type default)
			)
			(layer "F.SilkS")
		)
		(fp_line
			(start 1.239774 1.495298)
			(end -1.239774 1.495298)
			(stroke
				(width 0.1524)
				(type default)
			)
			(layer "F.SilkS")
		)
		(fp_poly
			(pts
				(xy -1.887474 -1.720596) (xy -1.528318 -0.643128) (xy -2.60604 -1.002284)
			)
			(stroke
				(width 0)
				(type default)
			)
			(fill yes)
			(layer "F.SilkS")
		)
		(fp_line
			(start -0.8001 -1.050036)
			(end 0.8001 -1.050036)
			(stroke
				(width 0.1)
				(type default)
			)
			(layer "F.Fab")
		)
		(fp_line
			(start -0.8001 1.050036)
			(end -0.8001 -1.050036)
			(stroke
				(width 0.1)
				(type default)
			)
			(layer "F.Fab")
		)
		(fp_line
			(start 0.8001 -1.050036)
			(end 0.8001 1.050036)
			(stroke
				(width 0.1)
				(type default)
			)
			(layer "F.Fab")
		)
		(fp_line
			(start 0.8001 1.050036)
			(end -0.8001 1.050036)
			(stroke
				(width 0.1)
				(type default)
			)
			(layer "F.Fab")
		)
		(fp_poly
			(pts
				(xy -2.458974 -0.508) (xy -2.458974 0.508) (xy -1.442974 0)
			)
			(stroke
				(width 0)
				(type default)
			)
			(fill yes)
			(layer "F.Fab")
		)
		(pad "1_2" smd circle
			(at -0.374904 0 90)
			(size 0 0)
			(layers "F.Cu" "F.Mask" "F.Paste")
			(net "P3V3_AUX")
		)
		(pad "3" smd rect
			(at -0.499872 0.999998)
			(size 0.254 0.7112)
			(layers "F.Cu" "F.Mask" "F.Paste")
			(net "GND")
		)
		(pad "4" smd rect
			(at 0 0.999998)
			(size 0.254 0.7112)
			(layers "F.Cu" "F.Mask" "F.Paste")
			(net "P3V3_OCP_ILIMIT_1")
		)
		(pad "5" smd rect
			(at 0.499872 0.999998)
			(size 0.254 0.7112)
			(layers "F.Cu" "F.Mask" "F.Paste")
			(net "P3V3_OCP_MODE_1")
		)
		(pad "6_7" smd circle
			(at 0.374904 0 270)
			(size 0 0)
			(layers "F.Cu" "F.Mask" "F.Paste")
			(net "P3V3_OCP_SFF_R")
		)
		(pad "8" smd rect
			(at 0.499872 -0.999998)
			(size 0.254 0.7112)
			(layers "F.Cu" "F.Mask" "F.Paste")
			(net "P3V3_OCP_GATE_1")
		)
		(pad "9" smd rect
			(at 0 -0.999998)
			(size 0.254 0.7112)
			(layers "F.Cu" "F.Mask" "F.Paste")
			(net "P3V3_OCP_EN_1_R2")
		)
		(pad "10" smd rect
			(at -0.499872 -0.999998)
			(size 0.254 0.7112)
			(layers "F.Cu" "F.Mask" "F.Paste")
			(net "P3V3_OCP_DVDT_1")
		)
	)
	(footprint ""
		(layer "F.Cu")
		(at 121.784364 -355.69779)
		(property "Reference" "R2583"
			(at 0 0 0)
			(layer "F.SilkS")
			(hide yes)
			(effects
				(font
					(size 1.27 1.27)
				)
			)
		)
		(property "Value" ""
			(at 0 0 0)
			(layer "F.Fab")
			(effects
				(font
					(size 1.27 1.27)
				)
			)
		)
		(duplicate_pad_numbers_are_jumpers no)
		(fp_line
			(start -0.7874 -0.4064)
			(end 0.7874 -0.4064)
			(stroke
				(width 0.1524)
				(type default)
			)
			(layer "F.SilkS")
		)
		(fp_line
			(start -0.7874 0.4064)
			(end -0.7874 -0.4064)
			(stroke
				(width 0.1524)
				(type default)
			)
			(layer "F.SilkS")
		)
		(fp_line
			(start 0.7874 -0.4064)
			(end 0.7874 0.4064)
			(stroke
				(width 0.1524)
				(type default)
			)
			(layer "F.SilkS")
		)
		(fp_line
			(start 0.7874 0.4064)
			(end -0.7874 0.4064)
			(stroke
				(width 0.1524)
				(type default)
			)
			(layer "F.SilkS")
		)
		(fp_line
			(start -0.67945 -0.305054)
			(end -0.12065 -0.305054)
			(stroke
				(width 0.1)
				(type default)
			)
			(layer "F.Fab")
		)
		(fp_line
			(start -0.67945 0.3048)
			(end -0.67945 -0.305054)
			(stroke
				(width 0.1)
				(type default)
			)
			(layer "F.Fab")
		)
		(fp_line
			(start -0.12065 -0.305054)
			(end -0.12065 -0.2794)
			(stroke
				(width 0.1)
				(type default)
			)
			(layer "F.Fab")
		)
		(fp_line
			(start -0.12065 -0.2794)
			(end 0.12065 -0.2794)
			(stroke
				(width 0.1)
				(type default)
			)
			(layer "F.Fab")
		)
		(fp_line
			(start -0.12065 0.2794)
			(end -0.12065 0.3048)
			(stroke
				(width 0.1)
				(type default)
			)
			(layer "F.Fab")
		)
		(fp_line
			(start -0.12065 0.3048)
			(end -0.67945 0.3048)
			(stroke
				(width 0.1)
				(type default)
			)
			(layer "F.Fab")
		)
		(fp_line
			(start 0.120396 0.2794)
			(end -0.12065 0.2794)
			(stroke
				(width 0.1)
				(type default)
			)
			(layer "F.Fab")
		)
		(fp_line
			(start 0.120396 0.3048)
			(end 0.120396 0.2794)
			(stroke
				(width 0.1)
				(type default)
			)
			(layer "F.Fab")
		)
		(fp_line
			(start 0.12065 -0.3048)
			(end 0.67945 -0.3048)
			(stroke
				(width 0.1)
				(type default)
			)
			(layer "F.Fab")
		)
		(fp_line
			(start 0.12065 -0.2794)
			(end 0.12065 -0.3048)
			(stroke
				(width 0.1)
				(type default)
			)
			(layer "F.Fab")
		)
		(fp_line
			(start 0.67945 -0.3048)
			(end 0.67945 0.3048)
			(stroke
				(width 0.1)
				(type default)
			)
			(layer "F.Fab")
		)
		(fp_line
			(start 0.67945 0.3048)
			(end 0.120396 0.3048)
			(stroke
				(width 0.1)
				(type default)
			)
			(layer "F.Fab")
		)
		(pad "1" smd circle
			(at -0.40005 0)
			(size 0 0)
			(layers "F.Cu" "F.Mask" "F.Paste")
			(net "P3V3_AUX")
		)
		(pad "2" smd circle
			(at 0.40005 0)
			(size 0 0)
			(layers "F.Cu" "F.Mask" "F.Paste")
			(net "PWRGD_PVPP_HBM_CPU1_R")
		)
	)
	(footprint ""
		(layer "F.Cu")
		(at 73.506076 -174.008034 180)
		(property "Reference" "PR569"
			(at 0 0 180)
			(layer "F.SilkS")
			(hide yes)
			(effects
				(font
					(size 1.27 1.27)
				)
			)
		)
		(property "Value" ""
			(at 0 0 180)
			(layer "F.Fab")
			(effects
				(font
					(size 1.27 1.27)
				)
			)
		)
		(duplicate_pad_numbers_are_jumpers no)
		(fp_line
			(start 0.7874 0.4064)
			(end -0.7874 0.4064)
			(stroke
				(width 0.1524)
				(type default)
			)
			(layer "F.SilkS")
		)
		(fp_line
			(start 0.7874 -0.4064)
			(end 0.7874 0.4064)
			(stroke
				(width 0.1524)
				(type default)
			)
			(layer "F.SilkS")
		)
		(fp_line
			(start -0.7874 0.4064)
			(end -0.7874 -0.4064)
			(stroke
				(width 0.1524)
				(type default)
			)
			(layer "F.SilkS")
		)
		(fp_line
			(start -0.7874 -0.4064)
			(end 0.7874 -0.4064)
			(stroke
				(width 0.1524)
				(type default)
			)
			(layer "F.SilkS")
		)
		(fp_line
			(start 0.67945 0.3048)
			(end 0.120396 0.3048)
			(stroke
				(width 0.1)
				(type default)
			)
			(layer "F.Fab")
		)
		(fp_line
			(start 0.67945 -0.3048)
			(end 0.67945 0.3048)
			(stroke
				(width 0.1)
				(type default)
			)
			(layer "F.Fab")
		)
		(fp_line
			(start 0.12065 -0.2794)
			(end 0.12065 -0.3048)
			(stroke
				(width 0.1)
				(type default)
			)
			(layer "F.Fab")
		)
		(fp_line
			(start 0.12065 -0.3048)
			(end 0.67945 -0.3048)
			(stroke
				(width 0.1)
				(type default)
			)
			(layer "F.Fab")
		)
		(fp_line
			(start 0.120396 0.3048)
			(end 0.120396 0.2794)
			(stroke
				(width 0.1)
				(type default)
			)
			(layer "F.Fab")
		)
		(fp_line
			(start 0.120396 0.2794)
			(end -0.12065 0.2794)
			(stroke
				(width 0.1)
				(type default)
			)
			(layer "F.Fab")
		)
		(fp_line
			(start -0.12065 0.3048)
			(end -0.67945 0.3048)
			(stroke
				(width 0.1)
				(type default)
			)
			(layer "F.Fab")
		)
		(fp_line
			(start -0.12065 0.2794)
			(end -0.12065 0.3048)
			(stroke
				(width 0.1)
				(type default)
			)
			(layer "F.Fab")
		)
		(fp_line
			(start -0.12065 -0.2794)
			(end 0.12065 -0.2794)
			(stroke
				(width 0.1)
				(type default)
			)
			(layer "F.Fab")
		)
		(fp_line
			(start -0.12065 -0.305054)
			(end -0.12065 -0.2794)
			(stroke
				(width 0.1)
				(type default)
			)
			(layer "F.Fab")
		)
		(fp_line
			(start -0.67945 0.3048)
			(end -0.67945 -0.305054)
			(stroke
				(width 0.1)
				(type default)
			)
			(layer "F.Fab")
		)
		(fp_line
			(start -0.67945 -0.305054)
			(end -0.12065 -0.305054)
			(stroke
				(width 0.1)
				(type default)
			)
			(layer "F.Fab")
		)
		(pad "1" smd circle
			(at -0.40005 0 180)
			(size 0 0)
			(layers "F.Cu" "F.Mask" "F.Paste")
			(net "VSENSE_PVCCFA_EHV_CPU1_DP")
		)
		(pad "2" smd circle
			(at 0.40005 0 180)
			(size 0 0)
			(layers "F.Cu" "F.Mask" "F.Paste")
			(net "PVCCFA_EHV_CPU1")
		)
	)
	(footprint ""
		(layer "F.Cu")
		(at 20.190714 -106.761026)
		(property "Reference" "R3667"
			(at 0 0 0)
			(layer "F.SilkS")
			(hide yes)
			(effects
				(font
					(size 1.27 1.27)
				)
			)
		)
		(property "Value" ""
			(at 0 0 0)
			(layer "F.Fab")
			(effects
				(font
					(size 1.27 1.27)
				)
			)
		)
		(duplicate_pad_numbers_are_jumpers no)
		(fp_line
			(start -0.7874 -0.4064)
			(end 0.7874 -0.4064)
			(stroke
				(width 0.1524)
				(type default)
			)
			(layer "F.SilkS")
		)
		(fp_line
			(start -0.7874 0.4064)
			(end -0.7874 -0.4064)
			(stroke
				(width 0.1524)
				(type default)
			)
			(layer "F.SilkS")
		)
		(fp_line
			(start 0.7874 -0.4064)
			(end 0.7874 0.4064)
			(stroke
				(width 0.1524)
				(type default)
			)
			(layer "F.SilkS")
		)
		(fp_line
			(start 0.7874 0.4064)
			(end -0.7874 0.4064)
			(stroke
				(width 0.1524)
				(type default)
			)
			(layer "F.SilkS")
		)
		(fp_line
			(start -0.67945 -0.305054)
			(end -0.12065 -0.305054)
			(stroke
				(width 0.1)
				(type default)
			)
			(layer "F.Fab")
		)
		(fp_line
			(start -0.67945 0.3048)
			(end -0.67945 -0.305054)
			(stroke
				(width 0.1)
				(type default)
			)
			(layer "F.Fab")
		)
		(fp_line
			(start -0.12065 -0.305054)
			(end -0.12065 -0.2794)
			(stroke
				(width 0.1)
				(type default)
			)
			(layer "F.Fab")
		)
		(fp_line
			(start -0.12065 -0.2794)
			(end 0.12065 -0.2794)
			(stroke
				(width 0.1)
				(type default)
			)
			(layer "F.Fab")
		)
		(fp_line
			(start -0.12065 0.2794)
			(end -0.12065 0.3048)
			(stroke
				(width 0.1)
				(type default)
			)
			(layer "F.Fab")
		)
		(fp_line
			(start -0.12065 0.3048)
			(end -0.67945 0.3048)
			(stroke
				(width 0.1)
				(type default)
			)
			(layer "F.Fab")
		)
		(fp_line
			(start 0.120396 0.2794)
			(end -0.12065 0.2794)
			(stroke
				(width 0.1)
				(type default)
			)
			(layer "F.Fab")
		)
		(fp_line
			(start 0.120396 0.3048)
			(end 0.120396 0.2794)
			(stroke
				(width 0.1)
				(type default)
			)
			(layer "F.Fab")
		)
		(fp_line
			(start 0.12065 -0.3048)
			(end 0.67945 -0.3048)
			(stroke
				(width 0.1)
				(type default)
			)
			(layer "F.Fab")
		)
		(fp_line
			(start 0.12065 -0.2794)
			(end 0.12065 -0.3048)
			(stroke
				(width 0.1)
				(type default)
			)
			(layer "F.Fab")
		)
		(fp_line
			(start 0.67945 -0.3048)
			(end 0.67945 0.3048)
			(stroke
				(width 0.1)
				(type default)
			)
			(layer "F.Fab")
		)
		(fp_line
			(start 0.67945 0.3048)
			(end 0.120396 0.3048)
			(stroke
				(width 0.1)
				(type default)
			)
			(layer "F.Fab")
		)
		(pad "1" smd circle
			(at -0.40005 0)
			(size 0 0)
			(layers "F.Cu" "F.Mask" "F.Paste")
			(net "P3V3_AUX")
		)
		(pad "2" smd circle
			(at 0.40005 0)
			(size 0 0)
			(layers "F.Cu" "F.Mask" "F.Paste")
			(net "ADC128_A1")
		)
	)
	(footprint ""
		(layer "F.Cu")
		(at 364.978442 -393.33805)
		(property "Reference" "Q136"
			(at -1.4224 -1.768348 0)
			(unlocked yes)
			(layer "F.SilkS")
			(effects
				(font
					(size 0.7874 0.5842)
					(thickness 0.1524)
				)
				(justify left)
			)
		)
		(property "Value" ""
			(at 0 0 0)
			(layer "F.Fab")
			(effects
				(font
					(size 1.27 1.27)
				)
			)
		)
		(duplicate_pad_numbers_are_jumpers no)
		(fp_line
			(start -1.332738 -1.100074)
			(end -0.4826 -1.100074)
			(stroke
				(width 0.1524)
				(type default)
			)
			(layer "F.SilkS")
		)
		(fp_line
			(start -1.332738 1.100074)
			(end -1.332738 -1.100074)
			(stroke
				(width 0.1524)
				(type default)
			)
			(layer "F.SilkS")
		)
		(fp_line
			(start -0.4826 -1.100074)
			(end 0 -0.541274)
			(stroke
				(width 0.1524)
				(type default)
			)
			(layer "F.SilkS")
		)
		(fp_line
			(start 0 -0.541274)
			(end 0.4826 -1.100074)
			(stroke
				(width 0.1524)
				(type default)
			)
			(layer "F.SilkS")
		)
		(fp_line
			(start 0.4826 -1.100074)
			(end 1.332738 -1.100074)
			(stroke
				(width 0.1524)
				(type default)
			)
			(layer "F.SilkS")
		)
		(fp_line
			(start 1.332738 -1.100074)
			(end 1.332738 1.100074)
			(stroke
				(width 0.1524)
				(type default)
			)
			(layer "F.SilkS")
		)
		(fp_line
			(start 1.332738 1.100074)
			(end -1.332738 1.100074)
			(stroke
				(width 0.1524)
				(type default)
			)
			(layer "F.SilkS")
		)
		(fp_poly
			(pts
				(xy -2.2352 -1.001014) (xy -1.533144 -0.649986) (xy -2.2352 -0.298958)
			)
			(stroke
				(width 0)
				(type default)
			)
			(fill yes)
			(layer "F.SilkS")
		)
		(fp_line
			(start -0.674878 -1.100074)
			(end 0.674878 -1.100074)
			(stroke
				(width 0.1)
				(type default)
			)
			(layer "F.Fab")
		)
		(fp_line
			(start -0.674878 1.100074)
			(end -0.674878 -1.100074)
			(stroke
				(width 0.1)
				(type default)
			)
			(layer "F.Fab")
		)
		(fp_line
			(start 0.674878 -1.100074)
			(end 0.674878 1.100074)
			(stroke
				(width 0.1)
				(type default)
			)
			(layer "F.Fab")
		)
		(fp_line
			(start 0.674878 1.100074)
			(end -0.674878 1.100074)
			(stroke
				(width 0.1)
				(type default)
			)
			(layer "F.Fab")
		)
		(fp_poly
			(pts
				(xy -2.2352 -0.298958) (xy -2.2352 -1.001014) (xy -1.533144 -0.649986)
			)
			(stroke
				(width 0)
				(type default)
			)
			(fill yes)
			(layer "F.Fab")
		)
		(pad "1" smd rect
			(at -0.94996 -0.649986 90)
			(size 0.4318 0.508)
			(layers "F.Cu" "F.Mask" "F.Paste")
			(net "GND")
		)
		(pad "2" smd rect
			(at -0.94996 0 90)
			(size 0.4318 0.508)
			(layers "F.Cu" "F.Mask" "F.Paste")
			(net "GPU_3V3IO_RSVD4")
		)
		(pad "3" smd rect
			(at -0.94996 0.649986 90)
			(size 0.4318 0.508)
			(layers "F.Cu" "F.Mask" "F.Paste")
			(net "GPU_3V3IO_RSVD4_ISO")
		)
		(pad "4" smd rect
			(at 0.94996 0.649986 90)
			(size 0.4318 0.508)
			(layers "F.Cu" "F.Mask" "F.Paste")
			(net "GND")
		)
		(pad "5" smd rect
			(at 0.94996 0 90)
			(size 0.4318 0.508)
			(layers "F.Cu" "F.Mask" "F.Paste")
			(net "GPU_3V3IO_RSVD4_N")
		)
		(pad "6" smd rect
			(at 0.94996 -0.649986 90)
			(size 0.4318 0.508)
			(layers "F.Cu" "F.Mask" "F.Paste")
			(net "GPU_3V3IO_RSVD4_N")
		)
	)
	(footprint ""
		(layer "F.Cu")
		(at 21.7932 -410.7942 90)
		(property "Reference" "R4735"
			(at 0 0 90)
			(layer "F.SilkS")
			(hide yes)
			(effects
				(font
					(size 1.27 1.27)
				)
			)
		)
		(property "Value" ""
			(at 0 0 90)
			(layer "F.Fab")
			(effects
				(font
					(size 1.27 1.27)
				)
			)
		)
		(duplicate_pad_numbers_are_jumpers no)
		(fp_line
			(start 0.7874 -0.4064)
			(end 0.7874 0.4064)
			(stroke
				(width 0.1524)
				(type default)
			)
			(layer "F.SilkS")
		)
		(fp_line
			(start -0.7874 -0.4064)
			(end 0.7874 -0.4064)
			(stroke
				(width 0.1524)
				(type default)
			)
			(layer "F.SilkS")
		)
		(fp_line
			(start 0.7874 0.4064)
			(end -0.7874 0.4064)
			(stroke
				(width 0.1524)
				(type default)
			)
			(layer "F.SilkS")
		)
		(fp_line
			(start -0.7874 0.4064)
			(end -0.7874 -0.4064)
			(stroke
				(width 0.1524)
				(type default)
			)
			(layer "F.SilkS")
		)
		(fp_line
			(start -0.12065 -0.305054)
			(end -0.12065 -0.2794)
			(stroke
				(width 0.1)
				(type default)
			)
			(layer "F.Fab")
		)
		(fp_line
			(start -0.67945 -0.305054)
			(end -0.12065 -0.305054)
			(stroke
				(width 0.1)
				(type default)
			)
			(layer "F.Fab")
		)
		(fp_line
			(start 0.67945 -0.3048)
			(end 0.67945 0.3048)
			(stroke
				(width 0.1)
				(type default)
			)
			(layer "F.Fab")
		)
		(fp_line
			(start 0.12065 -0.3048)
			(end 0.67945 -0.3048)
			(stroke
				(width 0.1)
				(type default)
			)
			(layer "F.Fab")
		)
		(fp_line
			(start 0.12065 -0.2794)
			(end 0.12065 -0.3048)
			(stroke
				(width 0.1)
				(type default)
			)
			(layer "F.Fab")
		)
		(fp_line
			(start -0.12065 -0.2794)
			(end 0.12065 -0.2794)
			(stroke
				(width 0.1)
				(type default)
			)
			(layer "F.Fab")
		)
		(fp_line
			(start 0.120396 0.2794)
			(end -0.12065 0.2794)
			(stroke
				(width 0.1)
				(type default)
			)
			(layer "F.Fab")
		)
		(fp_line
			(start -0.12065 0.2794)
			(end -0.12065 0.3048)
			(stroke
				(width 0.1)
				(type default)
			)
			(layer "F.Fab")
		)
		(fp_line
			(start 0.67945 0.3048)
			(end 0.120396 0.3048)
			(stroke
				(width 0.1)
				(type default)
			)
			(layer "F.Fab")
		)
		(fp_line
			(start 0.120396 0.3048)
			(end 0.120396 0.2794)
			(stroke
				(width 0.1)
				(type default)
			)
			(layer "F.Fab")
		)
		(fp_line
			(start -0.12065 0.3048)
			(end -0.67945 0.3048)
			(stroke
				(width 0.1)
				(type default)
			)
			(layer "F.Fab")
		)
		(fp_line
			(start -0.67945 0.3048)
			(end -0.67945 -0.305054)
			(stroke
				(width 0.1)
				(type default)
			)
			(layer "F.Fab")
		)
		(pad "1" smd circle
			(at -0.40005 0 90)
			(size 0 0)
			(layers "F.Cu" "F.Mask" "F.Paste")
			(net "PRSNT_CABLE_SWB_B2_ISO_N")
		)
		(pad "2" smd circle
			(at 0.40005 0 90)
			(size 0 0)
			(layers "F.Cu" "F.Mask" "F.Paste")
			(net "PRSNT_CABLE_SWB_B2_ISO_R_N")
		)
	)
	(footprint ""
		(layer "F.Cu")
		(at 370.17833 -338.17814 90)
		(property "Reference" "PR1768"
			(at 0 0 90)
			(layer "F.SilkS")
			(hide yes)
			(effects
				(font
					(size 1.27 1.27)
				)
			)
		)
		(property "Value" ""
			(at 0 0 90)
			(layer "F.Fab")
			(effects
				(font
					(size 1.27 1.27)
				)
			)
		)
		(duplicate_pad_numbers_are_jumpers no)
		(fp_line
			(start 0.7874 -0.4064)
			(end 0.7874 0.4064)
			(stroke
				(width 0.1524)
				(type default)
			)
			(layer "F.SilkS")
		)
		(fp_line
			(start -0.7874 -0.4064)
			(end 0.7874 -0.4064)
			(stroke
				(width 0.1524)
				(type default)
			)
			(layer "F.SilkS")
		)
		(fp_line
			(start 0.7874 0.4064)
			(end -0.7874 0.4064)
			(stroke
				(width 0.1524)
				(type default)
			)
			(layer "F.SilkS")
		)
		(fp_line
			(start -0.7874 0.4064)
			(end -0.7874 -0.4064)
			(stroke
				(width 0.1524)
				(type default)
			)
			(layer "F.SilkS")
		)
		(fp_line
			(start -0.12065 -0.305054)
			(end -0.12065 -0.2794)
			(stroke
				(width 0.1)
				(type default)
			)
			(layer "F.Fab")
		)
		(fp_line
			(start -0.67945 -0.305054)
			(end -0.12065 -0.305054)
			(stroke
				(width 0.1)
				(type default)
			)
			(layer "F.Fab")
		)
		(fp_line
			(start 0.67945 -0.3048)
			(end 0.67945 0.3048)
			(stroke
				(width 0.1)
				(type default)
			)
			(layer "F.Fab")
		)
		(fp_line
			(start 0.12065 -0.3048)
			(end 0.67945 -0.3048)
			(stroke
				(width 0.1)
				(type default)
			)
			(layer "F.Fab")
		)
		(fp_line
			(start 0.12065 -0.2794)
			(end 0.12065 -0.3048)
			(stroke
				(width 0.1)
				(type default)
			)
			(layer "F.Fab")
		)
		(fp_line
			(start -0.12065 -0.2794)
			(end 0.12065 -0.2794)
			(stroke
				(width 0.1)
				(type default)
			)
			(layer "F.Fab")
		)
		(fp_line
			(start 0.120396 0.2794)
			(end -0.12065 0.2794)
			(stroke
				(width 0.1)
				(type default)
			)
			(layer "F.Fab")
		)
		(fp_line
			(start -0.12065 0.2794)
			(end -0.12065 0.3048)
			(stroke
				(width 0.1)
				(type default)
			)
			(layer "F.Fab")
		)
		(fp_line
			(start 0.67945 0.3048)
			(end 0.120396 0.3048)
			(stroke
				(width 0.1)
				(type default)
			)
			(layer "F.Fab")
		)
		(fp_line
			(start 0.120396 0.3048)
			(end 0.120396 0.2794)
			(stroke
				(width 0.1)
				(type default)
			)
			(layer "F.Fab")
		)
		(fp_line
			(start -0.12065 0.3048)
			(end -0.67945 0.3048)
			(stroke
				(width 0.1)
				(type default)
			)
			(layer "F.Fab")
		)
		(fp_line
			(start -0.67945 0.3048)
			(end -0.67945 -0.305054)
			(stroke
				(width 0.1)
				(type default)
			)
			(layer "F.Fab")
		)
		(pad "1" smd circle
			(at -0.40005 0 90)
			(size 0 0)
			(layers "F.Cu" "F.Mask" "F.Paste")
			(net "SW_PVCCIN_CPU0_BOOT4")
		)
		(pad "2" smd circle
			(at 0.40005 0 90)
			(size 0 0)
			(layers "F.Cu" "F.Mask" "F.Paste")
			(net "SW_PVCCIN_CPU0_BOOT4_R")
		)
	)
	(footprint ""
		(layer "F.Cu")
		(at 31.5341 -170.0276)
		(property "Reference" "PC2368"
			(at 0 0 0)
			(layer "F.SilkS")
			(hide yes)
			(effects
				(font
					(size 1.27 1.27)
				)
			)
		)
		(property "Value" ""
			(at 0 0 0)
			(layer "F.Fab")
			(effects
				(font
					(size 1.27 1.27)
				)
			)
		)
		(duplicate_pad_numbers_are_jumpers no)
		(fp_line
			(start -0.7874 -0.4064)
			(end 0.7874 -0.4064)
			(stroke
				(width 0.1524)
				(type default)
			)
			(layer "F.SilkS")
		)
		(fp_line
			(start -0.7874 0.4064)
			(end -0.7874 -0.4064)
			(stroke
				(width 0.1524)
				(type default)
			)
			(layer "F.SilkS")
		)
		(fp_line
			(start 0.7874 -0.4064)
			(end 0.7874 0.4064)
			(stroke
				(width 0.1524)
				(type default)
			)
			(layer "F.SilkS")
		)
		(fp_line
			(start 0.7874 0.4064)
			(end -0.7874 0.4064)
			(stroke
				(width 0.1524)
				(type default)
			)
			(layer "F.SilkS")
		)
		(fp_line
			(start -0.67945 -0.305054)
			(end -0.12065 -0.305054)
			(stroke
				(width 0.1)
				(type default)
			)
			(layer "F.Fab")
		)
		(fp_line
			(start -0.67945 0.3048)
			(end -0.67945 -0.305054)
			(stroke
				(width 0.1)
				(type default)
			)
			(layer "F.Fab")
		)
		(fp_line
			(start -0.12065 -0.305054)
			(end -0.12065 -0.2794)
			(stroke
				(width 0.1)
				(type default)
			)
			(layer "F.Fab")
		)
		(fp_line
			(start -0.12065 -0.2794)
			(end 0.12065 -0.2794)
			(stroke
				(width 0.1)
				(type default)
			)
			(layer "F.Fab")
		)
		(fp_line
			(start -0.12065 0.2794)
			(end -0.12065 0.3048)
			(stroke
				(width 0.1)
				(type default)
			)
			(layer "F.Fab")
		)
		(fp_line
			(start -0.12065 0.3048)
			(end -0.67945 0.3048)
			(stroke
				(width 0.1)
				(type default)
			)
			(layer "F.Fab")
		)
		(fp_line
			(start 0.120396 0.2794)
			(end -0.12065 0.2794)
			(stroke
				(width 0.1)
				(type default)
			)
			(layer "F.Fab")
		)
		(fp_line
			(start 0.120396 0.3048)
			(end 0.120396 0.2794)
			(stroke
				(width 0.1)
				(type default)
			)
			(layer "F.Fab")
		)
		(fp_line
			(start 0.12065 -0.3048)
			(end 0.67945 -0.3048)
			(stroke
				(width 0.1)
				(type default)
			)
			(layer "F.Fab")
		)
		(fp_line
			(start 0.12065 -0.2794)
			(end 0.12065 -0.3048)
			(stroke
				(width 0.1)
				(type default)
			)
			(layer "F.Fab")
		)
		(fp_line
			(start 0.67945 -0.3048)
			(end 0.67945 0.3048)
			(stroke
				(width 0.1)
				(type default)
			)
			(layer "F.Fab")
		)
		(fp_line
			(start 0.67945 0.3048)
			(end 0.120396 0.3048)
			(stroke
				(width 0.1)
				(type default)
			)
			(layer "F.Fab")
		)
		(pad "1" smd circle
			(at -0.40005 0)
			(size 0 0)
			(layers "F.Cu" "F.Mask" "F.Paste")
			(net "PVCCD_HV_CPU1_VCC")
		)
		(pad "2" smd circle
			(at 0.40005 0)
			(size 0 0)
			(layers "F.Cu" "F.Mask" "F.Paste")
			(net "GND")
		)
	)
	(footprint ""
		(layer "F.Cu")
		(at 61.845698 -26.99004 90)
		(property "Reference" "PR3852"
			(at 0 0 90)
			(layer "F.SilkS")
			(hide yes)
			(effects
				(font
					(size 1.27 1.27)
				)
			)
		)
		(property "Value" ""
			(at 0 0 90)
			(layer "F.Fab")
			(effects
				(font
					(size 1.27 1.27)
				)
			)
		)
		(duplicate_pad_numbers_are_jumpers no)
		(fp_line
			(start 0.7874 -0.4064)
			(end 0.7874 0.4064)
			(stroke
				(width 0.1524)
				(type default)
			)
			(layer "F.SilkS")
		)
		(fp_line
			(start -0.7874 -0.4064)
			(end 0.7874 -0.4064)
			(stroke
				(width 0.1524)
				(type default)
			)
			(layer "F.SilkS")
		)
		(fp_line
			(start 0.7874 0.4064)
			(end -0.7874 0.4064)
			(stroke
				(width 0.1524)
				(type default)
			)
			(layer "F.SilkS")
		)
		(fp_line
			(start -0.7874 0.4064)
			(end -0.7874 -0.4064)
			(stroke
				(width 0.1524)
				(type default)
			)
			(layer "F.SilkS")
		)
		(fp_line
			(start -0.12065 -0.305054)
			(end -0.12065 -0.2794)
			(stroke
				(width 0.1)
				(type default)
			)
			(layer "F.Fab")
		)
		(fp_line
			(start -0.67945 -0.305054)
			(end -0.12065 -0.305054)
			(stroke
				(width 0.1)
				(type default)
			)
			(layer "F.Fab")
		)
		(fp_line
			(start 0.67945 -0.3048)
			(end 0.67945 0.3048)
			(stroke
				(width 0.1)
				(type default)
			)
			(layer "F.Fab")
		)
		(fp_line
			(start 0.12065 -0.3048)
			(end 0.67945 -0.3048)
			(stroke
				(width 0.1)
				(type default)
			)
			(layer "F.Fab")
		)
		(fp_line
			(start 0.12065 -0.2794)
			(end 0.12065 -0.3048)
			(stroke
				(width 0.1)
				(type default)
			)
			(layer "F.Fab")
		)
		(fp_line
			(start -0.12065 -0.2794)
			(end 0.12065 -0.2794)
			(stroke
				(width 0.1)
				(type default)
			)
			(layer "F.Fab")
		)
		(fp_line
			(start 0.120396 0.2794)
			(end -0.12065 0.2794)
			(stroke
				(width 0.1)
				(type default)
			)
			(layer "F.Fab")
		)
		(fp_line
			(start -0.12065 0.2794)
			(end -0.12065 0.3048)
			(stroke
				(width 0.1)
				(type default)
			)
			(layer "F.Fab")
		)
		(fp_line
			(start 0.67945 0.3048)
			(end 0.120396 0.3048)
			(stroke
				(width 0.1)
				(type default)
			)
			(layer "F.Fab")
		)
		(fp_line
			(start 0.120396 0.3048)
			(end 0.120396 0.2794)
			(stroke
				(width 0.1)
				(type default)
			)
			(layer "F.Fab")
		)
		(fp_line
			(start -0.12065 0.3048)
			(end -0.67945 0.3048)
			(stroke
				(width 0.1)
				(type default)
			)
			(layer "F.Fab")
		)
		(fp_line
			(start -0.67945 0.3048)
			(end -0.67945 -0.305054)
			(stroke
				(width 0.1)
				(type default)
			)
			(layer "F.Fab")
		)
		(pad "1" smd circle
			(at -0.40005 0 90)
			(size 0 0)
			(layers "F.Cu" "F.Mask" "F.Paste")
			(net "P12V_OCP_V3_2")
		)
		(pad "2" smd circle
			(at 0.40005 0 90)
			(size 0 0)
			(layers "F.Cu" "F.Mask" "F.Paste")
			(net "P12V_OCP_OV_FB_2")
		)
	)
	(footprint ""
		(layer "F.Cu")
		(at 123.769882 -15.54607 180)
		(property "Reference" "R4192"
			(at 0 0 180)
			(layer "F.SilkS")
			(hide yes)
			(effects
				(font
					(size 1.27 1.27)
				)
			)
		)
		(property "Value" ""
			(at 0 0 180)
			(layer "F.Fab")
			(effects
				(font
					(size 1.27 1.27)
				)
			)
		)
		(duplicate_pad_numbers_are_jumpers no)
		(fp_line
			(start 0.7874 0.4064)
			(end -0.7874 0.4064)
			(stroke
				(width 0.1524)
				(type default)
			)
			(layer "F.SilkS")
		)
		(fp_line
			(start 0.7874 -0.4064)
			(end 0.7874 0.4064)
			(stroke
				(width 0.1524)
				(type default)
			)
			(layer "F.SilkS")
		)
		(fp_line
			(start -0.7874 0.4064)
			(end -0.7874 -0.4064)
			(stroke
				(width 0.1524)
				(type default)
			)
			(layer "F.SilkS")
		)
		(fp_line
			(start -0.7874 -0.4064)
			(end 0.7874 -0.4064)
			(stroke
				(width 0.1524)
				(type default)
			)
			(layer "F.SilkS")
		)
		(fp_line
			(start 0.67945 0.3048)
			(end 0.120396 0.3048)
			(stroke
				(width 0.1)
				(type default)
			)
			(layer "F.Fab")
		)
		(fp_line
			(start 0.67945 -0.3048)
			(end 0.67945 0.3048)
			(stroke
				(width 0.1)
				(type default)
			)
			(layer "F.Fab")
		)
		(fp_line
			(start 0.12065 -0.2794)
			(end 0.12065 -0.3048)
			(stroke
				(width 0.1)
				(type default)
			)
			(layer "F.Fab")
		)
		(fp_line
			(start 0.12065 -0.3048)
			(end 0.67945 -0.3048)
			(stroke
				(width 0.1)
				(type default)
			)
			(layer "F.Fab")
		)
		(fp_line
			(start 0.120396 0.3048)
			(end 0.120396 0.2794)
			(stroke
				(width 0.1)
				(type default)
			)
			(layer "F.Fab")
		)
		(fp_line
			(start 0.120396 0.2794)
			(end -0.12065 0.2794)
			(stroke
				(width 0.1)
				(type default)
			)
			(layer "F.Fab")
		)
		(fp_line
			(start -0.12065 0.3048)
			(end -0.67945 0.3048)
			(stroke
				(width 0.1)
				(type default)
			)
			(layer "F.Fab")
		)
		(fp_line
			(start -0.12065 0.2794)
			(end -0.12065 0.3048)
			(stroke
				(width 0.1)
				(type default)
			)
			(layer "F.Fab")
		)
		(fp_line
			(start -0.12065 -0.2794)
			(end 0.12065 -0.2794)
			(stroke
				(width 0.1)
				(type default)
			)
			(layer "F.Fab")
		)
		(fp_line
			(start -0.12065 -0.305054)
			(end -0.12065 -0.2794)
			(stroke
				(width 0.1)
				(type default)
			)
			(layer "F.Fab")
		)
		(fp_line
			(start -0.67945 0.3048)
			(end -0.67945 -0.305054)
			(stroke
				(width 0.1)
				(type default)
			)
			(layer "F.Fab")
		)
		(fp_line
			(start -0.67945 -0.305054)
			(end -0.12065 -0.305054)
			(stroke
				(width 0.1)
				(type default)
			)
			(layer "F.Fab")
		)
		(pad "1" smd circle
			(at -0.40005 0 180)
			(size 0 0)
			(layers "F.Cu" "F.Mask" "F.Paste")
			(net "P3V3_AUX")
		)
		(pad "2" smd circle
			(at 0.40005 0 180)
			(size 0 0)
			(layers "F.Cu" "F.Mask" "F.Paste")
			(net "U273_3_ADD1")
		)
	)
	(footprint ""
		(layer "F.Cu")
		(at 252.961648 -56.193182)
		(property "Reference" "PR3952"
			(at 0 0 0)
			(layer "F.SilkS")
			(hide yes)
			(effects
				(font
					(size 1.27 1.27)
				)
			)
		)
		(property "Value" ""
			(at 0 0 0)
			(layer "F.Fab")
			(effects
				(font
					(size 1.27 1.27)
				)
			)
		)
		(duplicate_pad_numbers_are_jumpers no)
		(fp_line
			(start -0.7874 -0.4064)
			(end 0.7874 -0.4064)
			(stroke
				(width 0.1524)
				(type default)
			)
			(layer "F.SilkS")
		)
		(fp_line
			(start -0.7874 0.4064)
			(end -0.7874 -0.4064)
			(stroke
				(width 0.1524)
				(type default)
			)
			(layer "F.SilkS")
		)
		(fp_line
			(start 0.7874 -0.4064)
			(end 0.7874 0.4064)
			(stroke
				(width 0.1524)
				(type default)
			)
			(layer "F.SilkS")
		)
		(fp_line
			(start 0.7874 0.4064)
			(end -0.7874 0.4064)
			(stroke
				(width 0.1524)
				(type default)
			)
			(layer "F.SilkS")
		)
		(fp_line
			(start -0.67945 -0.305054)
			(end -0.12065 -0.305054)
			(stroke
				(width 0.1)
				(type default)
			)
			(layer "F.Fab")
		)
		(fp_line
			(start -0.67945 0.3048)
			(end -0.67945 -0.305054)
			(stroke
				(width 0.1)
				(type default)
			)
			(layer "F.Fab")
		)
		(fp_line
			(start -0.12065 -0.305054)
			(end -0.12065 -0.2794)
			(stroke
				(width 0.1)
				(type default)
			)
			(layer "F.Fab")
		)
		(fp_line
			(start -0.12065 -0.2794)
			(end 0.12065 -0.2794)
			(stroke
				(width 0.1)
				(type default)
			)
			(layer "F.Fab")
		)
		(fp_line
			(start -0.12065 0.2794)
			(end -0.12065 0.3048)
			(stroke
				(width 0.1)
				(type default)
			)
			(layer "F.Fab")
		)
		(fp_line
			(start -0.12065 0.3048)
			(end -0.67945 0.3048)
			(stroke
				(width 0.1)
				(type default)
			)
			(layer "F.Fab")
		)
		(fp_line
			(start 0.120396 0.2794)
			(end -0.12065 0.2794)
			(stroke
				(width 0.1)
				(type default)
			)
			(layer "F.Fab")
		)
		(fp_line
			(start 0.120396 0.3048)
			(end 0.120396 0.2794)
			(stroke
				(width 0.1)
				(type default)
			)
			(layer "F.Fab")
		)
		(fp_line
			(start 0.12065 -0.3048)
			(end 0.67945 -0.3048)
			(stroke
				(width 0.1)
				(type default)
			)
			(layer "F.Fab")
		)
		(fp_line
			(start 0.12065 -0.2794)
			(end 0.12065 -0.3048)
			(stroke
				(width 0.1)
				(type default)
			)
			(layer "F.Fab")
		)
		(fp_line
			(start 0.67945 -0.3048)
			(end 0.67945 0.3048)
			(stroke
				(width 0.1)
				(type default)
			)
			(layer "F.Fab")
		)
		(fp_line
			(start 0.67945 0.3048)
			(end 0.120396 0.3048)
			(stroke
				(width 0.1)
				(type default)
			)
			(layer "F.Fab")
		)
		(pad "1" smd circle
			(at -0.40005 0)
			(size 0 0)
			(layers "F.Cu" "F.Mask" "F.Paste")
			(net "P12V_E1S_0")
		)
		(pad "2" smd circle
			(at 0.40005 0)
			(size 0 0)
			(layers "F.Cu" "F.Mask" "F.Paste")
			(net "P12V_E1S_OV_FB_0")
		)
	)
	(footprint ""
		(layer "F.Cu")
		(at 320.190622 -60.620148)
		(property "Reference" "R1477"
			(at 0 0 0)
			(layer "F.SilkS")
			(hide yes)
			(effects
				(font
					(size 1.27 1.27)
				)
			)
		)
		(property "Value" ""
			(at 0 0 0)
			(layer "F.Fab")
			(effects
				(font
					(size 1.27 1.27)
				)
			)
		)
		(duplicate_pad_numbers_are_jumpers no)
		(fp_line
			(start -0.7874 -0.4064)
			(end 0.7874 -0.4064)
			(stroke
				(width 0.1524)
				(type default)
			)
			(layer "F.SilkS")
		)
		(fp_line
			(start -0.7874 0.4064)
			(end -0.7874 -0.4064)
			(stroke
				(width 0.1524)
				(type default)
			)
			(layer "F.SilkS")
		)
		(fp_line
			(start 0.7874 -0.4064)
			(end 0.7874 0.4064)
			(stroke
				(width 0.1524)
				(type default)
			)
			(layer "F.SilkS")
		)
		(fp_line
			(start 0.7874 0.4064)
			(end -0.7874 0.4064)
			(stroke
				(width 0.1524)
				(type default)
			)
			(layer "F.SilkS")
		)
		(fp_line
			(start -0.67945 -0.305054)
			(end -0.12065 -0.305054)
			(stroke
				(width 0.1)
				(type default)
			)
			(layer "F.Fab")
		)
		(fp_line
			(start -0.67945 0.3048)
			(end -0.67945 -0.305054)
			(stroke
				(width 0.1)
				(type default)
			)
			(layer "F.Fab")
		)
		(fp_line
			(start -0.12065 -0.305054)
			(end -0.12065 -0.2794)
			(stroke
				(width 0.1)
				(type default)
			)
			(layer "F.Fab")
		)
		(fp_line
			(start -0.12065 -0.2794)
			(end 0.12065 -0.2794)
			(stroke
				(width 0.1)
				(type default)
			)
			(layer "F.Fab")
		)
		(fp_line
			(start -0.12065 0.2794)
			(end -0.12065 0.3048)
			(stroke
				(width 0.1)
				(type default)
			)
			(layer "F.Fab")
		)
		(fp_line
			(start -0.12065 0.3048)
			(end -0.67945 0.3048)
			(stroke
				(width 0.1)
				(type default)
			)
			(layer "F.Fab")
		)
		(fp_line
			(start 0.120396 0.2794)
			(end -0.12065 0.2794)
			(stroke
				(width 0.1)
				(type default)
			)
			(layer "F.Fab")
		)
		(fp_line
			(start 0.120396 0.3048)
			(end 0.120396 0.2794)
			(stroke
				(width 0.1)
				(type default)
			)
			(layer "F.Fab")
		)
		(fp_line
			(start 0.12065 -0.3048)
			(end 0.67945 -0.3048)
			(stroke
				(width 0.1)
				(type default)
			)
			(layer "F.Fab")
		)
		(fp_line
			(start 0.12065 -0.2794)
			(end 0.12065 -0.3048)
			(stroke
				(width 0.1)
				(type default)
			)
			(layer "F.Fab")
		)
		(fp_line
			(start 0.67945 -0.3048)
			(end 0.67945 0.3048)
			(stroke
				(width 0.1)
				(type default)
			)
			(layer "F.Fab")
		)
		(fp_line
			(start 0.67945 0.3048)
			(end 0.120396 0.3048)
			(stroke
				(width 0.1)
				(type default)
			)
			(layer "F.Fab")
		)
		(pad "1" smd circle
			(at -0.40005 0)
			(size 0 0)
			(layers "F.Cu" "F.Mask" "F.Paste")
			(net "P3V3_AUX")
		)
		(pad "2" smd circle
			(at 0.40005 0)
			(size 0 0)
			(layers "F.Cu" "F.Mask" "F.Paste")
			(net "FM_PCH_XTAL_INPUT_MODE_MGPIO_TE")
		)
	)
	(footprint ""
		(layer "F.Cu")
		(at 371.29847 -435.600094)
		(property "Reference" "H93"
			(at -6.50113 -4.379976 0)
			(unlocked yes)
			(layer "F.SilkS")
			(effects
				(font
					(size 0.7874 0.5842)
					(thickness 0.1524)
				)
				(justify left)
			)
		)
		(property "Value" ""
			(at 0 0 0)
			(layer "F.Fab")
			(effects
				(font
					(size 1.27 1.27)
				)
			)
		)
		(duplicate_pad_numbers_are_jumpers no)
		(pad "1" thru_hole circle
			(at 0 0)
			(size 10.0076 10.0076)
			(drill 5.6134)
			(layers "*.Cu" "*.Mask")
			(remove_unused_layers no)
			(net "GND")
			(clearance -1.9431)
		)
	)
	(footprint ""
		(layer "F.Cu")
		(at 144.635474 -402.371052 -90)
		(property "Reference" "C759"
			(at 0 0 270)
			(layer "F.SilkS")
			(hide yes)
			(effects
				(font
					(size 1.27 1.27)
				)
			)
		)
		(property "Value" ""
			(at 0 0 270)
			(layer "F.Fab")
			(effects
				(font
					(size 1.27 1.27)
				)
			)
		)
		(duplicate_pad_numbers_are_jumpers no)
		(fp_line
			(start -0.299974 0.150114)
			(end -0.299974 -0.150114)
			(stroke
				(width 0.1)
				(type default)
			)
			(layer "F.Fab")
		)
		(fp_line
			(start 0.299974 0.150114)
			(end -0.299974 0.150114)
			(stroke
				(width 0.1)
				(type default)
			)
			(layer "F.Fab")
		)
		(fp_line
			(start -0.299974 -0.150114)
			(end 0.299974 -0.150114)
			(stroke
				(width 0.1)
				(type default)
			)
			(layer "F.Fab")
		)
		(fp_line
			(start 0.299974 -0.150114)
			(end 0.299974 0.150114)
			(stroke
				(width 0.1)
				(type default)
			)
			(layer "F.Fab")
		)
		(pad "1" smd rect
			(at -0.2667 0 270)
			(size 0.3048 0.381)
			(layers "F.Cu" "F.Mask" "F.Paste")
			(net "P5E_CPU1_PE2_TX_C_DP<7>")
		)
		(pad "2" smd rect
			(at 0.2667 0 270)
			(size 0.3048 0.381)
			(layers "F.Cu" "F.Mask" "F.Paste")
			(net "P5E_CPU1_PE2_TX_DP<7>")
		)
	)
	(footprint ""
		(layer "F.Cu")
		(at 39.827454 -107.031282 180)
		(property "Reference" "R3682"
			(at 0 0 180)
			(layer "F.SilkS")
			(hide yes)
			(effects
				(font
					(size 1.27 1.27)
				)
			)
		)
		(property "Value" ""
			(at 0 0 180)
			(layer "F.Fab")
			(effects
				(font
					(size 1.27 1.27)
				)
			)
		)
		(duplicate_pad_numbers_are_jumpers no)
		(fp_line
			(start 0.7874 0.4064)
			(end -0.7874 0.4064)
			(stroke
				(width 0.1524)
				(type default)
			)
			(layer "F.SilkS")
		)
		(fp_line
			(start 0.7874 -0.4064)
			(end 0.7874 0.4064)
			(stroke
				(width 0.1524)
				(type default)
			)
			(layer "F.SilkS")
		)
		(fp_line
			(start -0.7874 0.4064)
			(end -0.7874 -0.4064)
			(stroke
				(width 0.1524)
				(type default)
			)
			(layer "F.SilkS")
		)
		(fp_line
			(start -0.7874 -0.4064)
			(end 0.7874 -0.4064)
			(stroke
				(width 0.1524)
				(type default)
			)
			(layer "F.SilkS")
		)
		(fp_line
			(start 0.67945 0.3048)
			(end 0.120396 0.3048)
			(stroke
				(width 0.1)
				(type default)
			)
			(layer "F.Fab")
		)
		(fp_line
			(start 0.67945 -0.3048)
			(end 0.67945 0.3048)
			(stroke
				(width 0.1)
				(type default)
			)
			(layer "F.Fab")
		)
		(fp_line
			(start 0.12065 -0.2794)
			(end 0.12065 -0.3048)
			(stroke
				(width 0.1)
				(type default)
			)
			(layer "F.Fab")
		)
		(fp_line
			(start 0.12065 -0.3048)
			(end 0.67945 -0.3048)
			(stroke
				(width 0.1)
				(type default)
			)
			(layer "F.Fab")
		)
		(fp_line
			(start 0.120396 0.3048)
			(end 0.120396 0.2794)
			(stroke
				(width 0.1)
				(type default)
			)
			(layer "F.Fab")
		)
		(fp_line
			(start 0.120396 0.2794)
			(end -0.12065 0.2794)
			(stroke
				(width 0.1)
				(type default)
			)
			(layer "F.Fab")
		)
		(fp_line
			(start -0.12065 0.3048)
			(end -0.67945 0.3048)
			(stroke
				(width 0.1)
				(type default)
			)
			(layer "F.Fab")
		)
		(fp_line
			(start -0.12065 0.2794)
			(end -0.12065 0.3048)
			(stroke
				(width 0.1)
				(type default)
			)
			(layer "F.Fab")
		)
		(fp_line
			(start -0.12065 -0.2794)
			(end 0.12065 -0.2794)
			(stroke
				(width 0.1)
				(type default)
			)
			(layer "F.Fab")
		)
		(fp_line
			(start -0.12065 -0.305054)
			(end -0.12065 -0.2794)
			(stroke
				(width 0.1)
				(type default)
			)
			(layer "F.Fab")
		)
		(fp_line
			(start -0.67945 0.3048)
			(end -0.67945 -0.305054)
			(stroke
				(width 0.1)
				(type default)
			)
			(layer "F.Fab")
		)
		(fp_line
			(start -0.67945 -0.305054)
			(end -0.12065 -0.305054)
			(stroke
				(width 0.1)
				(type default)
			)
			(layer "F.Fab")
		)
		(pad "1" smd rect
			(at -0.40005 0)
			(size 0.4572 0.508)
			(layers "F.Cu" "F.Mask" "F.Paste")
			(net "P3V3_AUX_ADC")
		)
		(pad "2" smd rect
			(at 0.40005 0)
			(size 0.4572 0.508)
			(layers "F.Cu" "F.Mask" "F.Paste")
			(net "P3V3_AUX_ADC_TIC")
		)
	)
	(footprint ""
		(layer "F.Cu")
		(at 419.76294 -101.270308 90)
		(property "Reference" "PR3846"
			(at 0 0 90)
			(layer "F.SilkS")
			(hide yes)
			(effects
				(font
					(size 1.27 1.27)
				)
			)
		)
		(property "Value" ""
			(at 0 0 90)
			(layer "F.Fab")
			(effects
				(font
					(size 1.27 1.27)
				)
			)
		)
		(duplicate_pad_numbers_are_jumpers no)
		(fp_line
			(start 0.7874 -0.4064)
			(end 0.7874 0.4064)
			(stroke
				(width 0.1524)
				(type default)
			)
			(layer "F.SilkS")
		)
		(fp_line
			(start -0.7874 -0.4064)
			(end 0.7874 -0.4064)
			(stroke
				(width 0.1524)
				(type default)
			)
			(layer "F.SilkS")
		)
		(fp_line
			(start 0.7874 0.4064)
			(end -0.7874 0.4064)
			(stroke
				(width 0.1524)
				(type default)
			)
			(layer "F.SilkS")
		)
		(fp_line
			(start -0.7874 0.4064)
			(end -0.7874 -0.4064)
			(stroke
				(width 0.1524)
				(type default)
			)
			(layer "F.SilkS")
		)
		(fp_line
			(start -0.12065 -0.305054)
			(end -0.12065 -0.2794)
			(stroke
				(width 0.1)
				(type default)
			)
			(layer "F.Fab")
		)
		(fp_line
			(start -0.67945 -0.305054)
			(end -0.12065 -0.305054)
			(stroke
				(width 0.1)
				(type default)
			)
			(layer "F.Fab")
		)
		(fp_line
			(start 0.67945 -0.3048)
			(end 0.67945 0.3048)
			(stroke
				(width 0.1)
				(type default)
			)
			(layer "F.Fab")
		)
		(fp_line
			(start 0.12065 -0.3048)
			(end 0.67945 -0.3048)
			(stroke
				(width 0.1)
				(type default)
			)
			(layer "F.Fab")
		)
		(fp_line
			(start 0.12065 -0.2794)
			(end 0.12065 -0.3048)
			(stroke
				(width 0.1)
				(type default)
			)
			(layer "F.Fab")
		)
		(fp_line
			(start -0.12065 -0.2794)
			(end 0.12065 -0.2794)
			(stroke
				(width 0.1)
				(type default)
			)
			(layer "F.Fab")
		)
		(fp_line
			(start 0.120396 0.2794)
			(end -0.12065 0.2794)
			(stroke
				(width 0.1)
				(type default)
			)
			(layer "F.Fab")
		)
		(fp_line
			(start -0.12065 0.2794)
			(end -0.12065 0.3048)
			(stroke
				(width 0.1)
				(type default)
			)
			(layer "F.Fab")
		)
		(fp_line
			(start 0.67945 0.3048)
			(end 0.120396 0.3048)
			(stroke
				(width 0.1)
				(type default)
			)
			(layer "F.Fab")
		)
		(fp_line
			(start 0.120396 0.3048)
			(end 0.120396 0.2794)
			(stroke
				(width 0.1)
				(type default)
			)
			(layer "F.Fab")
		)
		(fp_line
			(start -0.12065 0.3048)
			(end -0.67945 0.3048)
			(stroke
				(width 0.1)
				(type default)
			)
			(layer "F.Fab")
		)
		(fp_line
			(start -0.67945 0.3048)
			(end -0.67945 -0.305054)
			(stroke
				(width 0.1)
				(type default)
			)
			(layer "F.Fab")
		)
		(pad "1" smd circle
			(at -0.40005 0 90)
			(size 0 0)
			(layers "F.Cu" "F.Mask" "F.Paste")
			(net "GND")
		)
		(pad "2" smd circle
			(at 0.40005 0 90)
			(size 0 0)
			(layers "F.Cu" "F.Mask" "F.Paste")
			(net "P3V3_OCP_ILIMIT_1")
		)
	)
	(footprint ""
		(layer "F.Cu")
		(at 193.954654 -153.774902)
		(property "Reference" "H124"
			(at 1.36144 6.74243 0)
			(unlocked yes)
			(layer "F.SilkS")
			(effects
				(font
					(size 0.7874 0.5842)
					(thickness 0.1524)
				)
				(justify left)
			)
		)
		(property "Value" ""
			(at 0 0 0)
			(layer "F.Fab")
			(effects
				(font
					(size 1.27 1.27)
				)
			)
		)
		(duplicate_pad_numbers_are_jumpers no)
		(fp_circle
			(center 0 0)
			(end 5.8166 0)
			(stroke
				(width 0.1524)
				(type default)
			)
			(fill no)
			(layer "F.SilkS")
		)
		(fp_circle
			(center 0 0)
			(end 5.8166 0)
			(stroke
				(width 0.1524)
				(type default)
			)
			(fill no)
			(layer "B.SilkS")
		)
		(fp_circle
			(center 0 0)
			(end 5.8166 0)
			(stroke
				(width 0.1)
				(type default)
			)
			(fill no)
			(layer "B.Fab")
		)
		(fp_circle
			(center 0 0)
			(end 5.8166 0)
			(stroke
				(width 0.1)
				(type default)
			)
			(fill no)
			(layer "F.Fab")
		)
		(pad "" np_thru_hole circle
			(at 0 0)
			(size 10.0076 10.0076)
			(drill 10.0076)
			(layers "*.Cu" "*.Mask")
			(clearance 0.381)
			(thermal_gap 0.381)
		)
	)
	(footprint ""
		(layer "F.Cu")
		(at 46.093634 -391.089642)
		(property "Reference" "R4694"
			(at 0 0 0)
			(layer "F.SilkS")
			(hide yes)
			(effects
				(font
					(size 1.27 1.27)
				)
			)
		)
		(property "Value" ""
			(at 0 0 0)
			(layer "F.Fab")
			(effects
				(font
					(size 1.27 1.27)
				)
			)
		)
		(duplicate_pad_numbers_are_jumpers no)
		(fp_line
			(start -0.7874 -0.4064)
			(end 0.7874 -0.4064)
			(stroke
				(width 0.1524)
				(type default)
			)
			(layer "F.SilkS")
		)
		(fp_line
			(start -0.7874 0.4064)
			(end -0.7874 -0.4064)
			(stroke
				(width 0.1524)
				(type default)
			)
			(layer "F.SilkS")
		)
		(fp_line
			(start 0.7874 -0.4064)
			(end 0.7874 0.4064)
			(stroke
				(width 0.1524)
				(type default)
			)
			(layer "F.SilkS")
		)
		(fp_line
			(start 0.7874 0.4064)
			(end -0.7874 0.4064)
			(stroke
				(width 0.1524)
				(type default)
			)
			(layer "F.SilkS")
		)
		(fp_line
			(start -0.67945 -0.305054)
			(end -0.12065 -0.305054)
			(stroke
				(width 0.1)
				(type default)
			)
			(layer "F.Fab")
		)
		(fp_line
			(start -0.67945 0.3048)
			(end -0.67945 -0.305054)
			(stroke
				(width 0.1)
				(type default)
			)
			(layer "F.Fab")
		)
		(fp_line
			(start -0.12065 -0.305054)
			(end -0.12065 -0.2794)
			(stroke
				(width 0.1)
				(type default)
			)
			(layer "F.Fab")
		)
		(fp_line
			(start -0.12065 -0.2794)
			(end 0.12065 -0.2794)
			(stroke
				(width 0.1)
				(type default)
			)
			(layer "F.Fab")
		)
		(fp_line
			(start -0.12065 0.2794)
			(end -0.12065 0.3048)
			(stroke
				(width 0.1)
				(type default)
			)
			(layer "F.Fab")
		)
		(fp_line
			(start -0.12065 0.3048)
			(end -0.67945 0.3048)
			(stroke
				(width 0.1)
				(type default)
			)
			(layer "F.Fab")
		)
		(fp_line
			(start 0.120396 0.2794)
			(end -0.12065 0.2794)
			(stroke
				(width 0.1)
				(type default)
			)
			(layer "F.Fab")
		)
		(fp_line
			(start 0.120396 0.3048)
			(end 0.120396 0.2794)
			(stroke
				(width 0.1)
				(type default)
			)
			(layer "F.Fab")
		)
		(fp_line
			(start 0.12065 -0.3048)
			(end 0.67945 -0.3048)
			(stroke
				(width 0.1)
				(type default)
			)
			(layer "F.Fab")
		)
		(fp_line
			(start 0.12065 -0.2794)
			(end 0.12065 -0.3048)
			(stroke
				(width 0.1)
				(type default)
			)
			(layer "F.Fab")
		)
		(fp_line
			(start 0.67945 -0.3048)
			(end 0.67945 0.3048)
			(stroke
				(width 0.1)
				(type default)
			)
			(layer "F.Fab")
		)
		(fp_line
			(start 0.67945 0.3048)
			(end 0.120396 0.3048)
			(stroke
				(width 0.1)
				(type default)
			)
			(layer "F.Fab")
		)
		(pad "1" smd circle
			(at -0.40005 0)
			(size 0 0)
			(layers "F.Cu" "F.Mask" "F.Paste")
			(net "FM_P2E_BUF2_EQB1")
		)
		(pad "2" smd circle
			(at 0.40005 0)
			(size 0 0)
			(layers "F.Cu" "F.Mask" "F.Paste")
			(net "GND")
		)
	)
	(footprint ""
		(layer "F.Cu")
		(at 424.223942 -397.651478 180)
		(property "Reference" "R3430"
			(at 0 0 180)
			(layer "F.SilkS")
			(hide yes)
			(effects
				(font
					(size 1.27 1.27)
				)
			)
		)
		(property "Value" ""
			(at 0 0 180)
			(layer "F.Fab")
			(effects
				(font
					(size 1.27 1.27)
				)
			)
		)
		(duplicate_pad_numbers_are_jumpers no)
		(fp_line
			(start 0.7874 0.4064)
			(end -0.7874 0.4064)
			(stroke
				(width 0.1524)
				(type default)
			)
			(layer "F.SilkS")
		)
		(fp_line
			(start 0.7874 -0.4064)
			(end 0.7874 0.4064)
			(stroke
				(width 0.1524)
				(type default)
			)
			(layer "F.SilkS")
		)
		(fp_line
			(start -0.7874 0.4064)
			(end -0.7874 -0.4064)
			(stroke
				(width 0.1524)
				(type default)
			)
			(layer "F.SilkS")
		)
		(fp_line
			(start -0.7874 -0.4064)
			(end 0.7874 -0.4064)
			(stroke
				(width 0.1524)
				(type default)
			)
			(layer "F.SilkS")
		)
		(fp_line
			(start 0.67945 0.3048)
			(end 0.120396 0.3048)
			(stroke
				(width 0.1)
				(type default)
			)
			(layer "F.Fab")
		)
		(fp_line
			(start 0.67945 -0.3048)
			(end 0.67945 0.3048)
			(stroke
				(width 0.1)
				(type default)
			)
			(layer "F.Fab")
		)
		(fp_line
			(start 0.12065 -0.2794)
			(end 0.12065 -0.3048)
			(stroke
				(width 0.1)
				(type default)
			)
			(layer "F.Fab")
		)
		(fp_line
			(start 0.12065 -0.3048)
			(end 0.67945 -0.3048)
			(stroke
				(width 0.1)
				(type default)
			)
			(layer "F.Fab")
		)
		(fp_line
			(start 0.120396 0.3048)
			(end 0.120396 0.2794)
			(stroke
				(width 0.1)
				(type default)
			)
			(layer "F.Fab")
		)
		(fp_line
			(start 0.120396 0.2794)
			(end -0.12065 0.2794)
			(stroke
				(width 0.1)
				(type default)
			)
			(layer "F.Fab")
		)
		(fp_line
			(start -0.12065 0.3048)
			(end -0.67945 0.3048)
			(stroke
				(width 0.1)
				(type default)
			)
			(layer "F.Fab")
		)
		(fp_line
			(start -0.12065 0.2794)
			(end -0.12065 0.3048)
			(stroke
				(width 0.1)
				(type default)
			)
			(layer "F.Fab")
		)
		(fp_line
			(start -0.12065 -0.2794)
			(end 0.12065 -0.2794)
			(stroke
				(width 0.1)
				(type default)
			)
			(layer "F.Fab")
		)
		(fp_line
			(start -0.12065 -0.305054)
			(end -0.12065 -0.2794)
			(stroke
				(width 0.1)
				(type default)
			)
			(layer "F.Fab")
		)
		(fp_line
			(start -0.67945 0.3048)
			(end -0.67945 -0.305054)
			(stroke
				(width 0.1)
				(type default)
			)
			(layer "F.Fab")
		)
		(fp_line
			(start -0.67945 -0.305054)
			(end -0.12065 -0.305054)
			(stroke
				(width 0.1)
				(type default)
			)
			(layer "F.Fab")
		)
		(pad "1" smd circle
			(at -0.40005 0 180)
			(size 0 0)
			(layers "F.Cu" "F.Mask" "F.Paste")
			(net "GPU_FPGA_OVERT_N")
		)
		(pad "2" smd circle
			(at 0.40005 0 180)
			(size 0 0)
			(layers "F.Cu" "F.Mask" "F.Paste")
			(net "GND")
		)
	)
	(footprint ""
		(layer "F.Cu")
		(at 111.332772 -140.403326)
		(property "Reference" "R540"
			(at 0 0 0)
			(layer "F.SilkS")
			(hide yes)
			(effects
				(font
					(size 1.27 1.27)
				)
			)
		)
		(property "Value" ""
			(at 0 0 0)
			(layer "F.Fab")
			(effects
				(font
					(size 1.27 1.27)
				)
			)
		)
		(duplicate_pad_numbers_are_jumpers no)
		(fp_line
			(start -0.7874 -0.4064)
			(end 0.7874 -0.4064)
			(stroke
				(width 0.1524)
				(type default)
			)
			(layer "F.SilkS")
		)
		(fp_line
			(start -0.7874 0.4064)
			(end -0.7874 -0.4064)
			(stroke
				(width 0.1524)
				(type default)
			)
			(layer "F.SilkS")
		)
		(fp_line
			(start 0.7874 -0.4064)
			(end 0.7874 0.4064)
			(stroke
				(width 0.1524)
				(type default)
			)
			(layer "F.SilkS")
		)
		(fp_line
			(start 0.7874 0.4064)
			(end -0.7874 0.4064)
			(stroke
				(width 0.1524)
				(type default)
			)
			(layer "F.SilkS")
		)
		(fp_line
			(start -0.67945 -0.305054)
			(end -0.12065 -0.305054)
			(stroke
				(width 0.1)
				(type default)
			)
			(layer "F.Fab")
		)
		(fp_line
			(start -0.67945 0.3048)
			(end -0.67945 -0.305054)
			(stroke
				(width 0.1)
				(type default)
			)
			(layer "F.Fab")
		)
		(fp_line
			(start -0.12065 -0.305054)
			(end -0.12065 -0.2794)
			(stroke
				(width 0.1)
				(type default)
			)
			(layer "F.Fab")
		)
		(fp_line
			(start -0.12065 -0.2794)
			(end 0.12065 -0.2794)
			(stroke
				(width 0.1)
				(type default)
			)
			(layer "F.Fab")
		)
		(fp_line
			(start -0.12065 0.2794)
			(end -0.12065 0.3048)
			(stroke
				(width 0.1)
				(type default)
			)
			(layer "F.Fab")
		)
		(fp_line
			(start -0.12065 0.3048)
			(end -0.67945 0.3048)
			(stroke
				(width 0.1)
				(type default)
			)
			(layer "F.Fab")
		)
		(fp_line
			(start 0.120396 0.2794)
			(end -0.12065 0.2794)
			(stroke
				(width 0.1)
				(type default)
			)
			(layer "F.Fab")
		)
		(fp_line
			(start 0.120396 0.3048)
			(end 0.120396 0.2794)
			(stroke
				(width 0.1)
				(type default)
			)
			(layer "F.Fab")
		)
		(fp_line
			(start 0.12065 -0.3048)
			(end 0.67945 -0.3048)
			(stroke
				(width 0.1)
				(type default)
			)
			(layer "F.Fab")
		)
		(fp_line
			(start 0.12065 -0.2794)
			(end 0.12065 -0.3048)
			(stroke
				(width 0.1)
				(type default)
			)
			(layer "F.Fab")
		)
		(fp_line
			(start 0.67945 -0.3048)
			(end 0.67945 0.3048)
			(stroke
				(width 0.1)
				(type default)
			)
			(layer "F.Fab")
		)
		(fp_line
			(start 0.67945 0.3048)
			(end 0.120396 0.3048)
			(stroke
				(width 0.1)
				(type default)
			)
			(layer "F.Fab")
		)
		(pad "1" smd circle
			(at -0.40005 0)
			(size 0 0)
			(layers "F.Cu" "F.Mask" "F.Paste")
			(net "P3V3_AUX")
		)
		(pad "2" smd circle
			(at 0.40005 0)
			(size 0 0)
			(layers "F.Cu" "F.Mask" "F.Paste")
			(net "PCA9548_PCIE3_ADDR0")
		)
	)
	(footprint ""
		(layer "F.Cu")
		(at 124.33808 -106.238548 -90)
		(property "Reference" "R4048"
			(at 0 0 270)
			(layer "F.SilkS")
			(hide yes)
			(effects
				(font
					(size 1.27 1.27)
				)
			)
		)
		(property "Value" ""
			(at 0 0 270)
			(layer "F.Fab")
			(effects
				(font
					(size 1.27 1.27)
				)
			)
		)
		(duplicate_pad_numbers_are_jumpers no)
		(fp_line
			(start -0.7874 0.4064)
			(end -0.7874 -0.4064)
			(stroke
				(width 0.1524)
				(type default)
			)
			(layer "F.SilkS")
		)
		(fp_line
			(start 0.7874 0.4064)
			(end -0.7874 0.4064)
			(stroke
				(width 0.1524)
				(type default)
			)
			(layer "F.SilkS")
		)
		(fp_line
			(start -0.7874 -0.4064)
			(end 0.7874 -0.4064)
			(stroke
				(width 0.1524)
				(type default)
			)
			(layer "F.SilkS")
		)
		(fp_line
			(start 0.7874 -0.4064)
			(end 0.7874 0.4064)
			(stroke
				(width 0.1524)
				(type default)
			)
			(layer "F.SilkS")
		)
		(fp_line
			(start -0.67945 0.3048)
			(end -0.67945 -0.305054)
			(stroke
				(width 0.1)
				(type default)
			)
			(layer "F.Fab")
		)
		(fp_line
			(start -0.12065 0.3048)
			(end -0.67945 0.3048)
			(stroke
				(width 0.1)
				(type default)
			)
			(layer "F.Fab")
		)
		(fp_line
			(start 0.120396 0.3048)
			(end 0.120396 0.2794)
			(stroke
				(width 0.1)
				(type default)
			)
			(layer "F.Fab")
		)
		(fp_line
			(start 0.67945 0.3048)
			(end 0.120396 0.3048)
			(stroke
				(width 0.1)
				(type default)
			)
			(layer "F.Fab")
		)
		(fp_line
			(start -0.12065 0.2794)
			(end -0.12065 0.3048)
			(stroke
				(width 0.1)
				(type default)
			)
			(layer "F.Fab")
		)
		(fp_line
			(start 0.120396 0.2794)
			(end -0.12065 0.2794)
			(stroke
				(width 0.1)
				(type default)
			)
			(layer "F.Fab")
		)
		(fp_line
			(start -0.12065 -0.2794)
			(end 0.12065 -0.2794)
			(stroke
				(width 0.1)
				(type default)
			)
			(layer "F.Fab")
		)
		(fp_line
			(start 0.12065 -0.2794)
			(end 0.12065 -0.3048)
			(stroke
				(width 0.1)
				(type default)
			)
			(layer "F.Fab")
		)
		(fp_line
			(start 0.12065 -0.3048)
			(end 0.67945 -0.3048)
			(stroke
				(width 0.1)
				(type default)
			)
			(layer "F.Fab")
		)
		(fp_line
			(start 0.67945 -0.3048)
			(end 0.67945 0.3048)
			(stroke
				(width 0.1)
				(type default)
			)
			(layer "F.Fab")
		)
		(fp_line
			(start -0.67945 -0.305054)
			(end -0.12065 -0.305054)
			(stroke
				(width 0.1)
				(type default)
			)
			(layer "F.Fab")
		)
		(fp_line
			(start -0.12065 -0.305054)
			(end -0.12065 -0.2794)
			(stroke
				(width 0.1)
				(type default)
			)
			(layer "F.Fab")
		)
		(pad "1" smd circle
			(at -0.40005 0 270)
			(size 0 0)
			(layers "F.Cu" "F.Mask" "F.Paste")
			(net "RST_CPU1_DRAM_EF_PLD_LVT3_R_N")
		)
		(pad "2" smd circle
			(at 0.40005 0 270)
			(size 0 0)
			(layers "F.Cu" "F.Mask" "F.Paste")
			(net "RST_CPU1_DRAM_EF_PLD_LVT3_N")
		)
	)
	(footprint ""
		(layer "F.Cu")
		(at 120.10644 -414.274762 180)
		(property "Reference" "R4489"
			(at 0 0 180)
			(layer "F.SilkS")
			(hide yes)
			(effects
				(font
					(size 1.27 1.27)
				)
			)
		)
		(property "Value" ""
			(at 0 0 180)
			(layer "F.Fab")
			(effects
				(font
					(size 1.27 1.27)
				)
			)
		)
		(duplicate_pad_numbers_are_jumpers no)
		(fp_line
			(start 0.7874 0.4064)
			(end -0.7874 0.4064)
			(stroke
				(width 0.1524)
				(type default)
			)
			(layer "F.SilkS")
		)
		(fp_line
			(start 0.7874 -0.4064)
			(end 0.7874 0.4064)
			(stroke
				(width 0.1524)
				(type default)
			)
			(layer "F.SilkS")
		)
		(fp_line
			(start -0.7874 0.4064)
			(end -0.7874 -0.4064)
			(stroke
				(width 0.1524)
				(type default)
			)
			(layer "F.SilkS")
		)
		(fp_line
			(start -0.7874 -0.4064)
			(end 0.7874 -0.4064)
			(stroke
				(width 0.1524)
				(type default)
			)
			(layer "F.SilkS")
		)
		(fp_line
			(start 0.67945 0.3048)
			(end 0.120396 0.3048)
			(stroke
				(width 0.1)
				(type default)
			)
			(layer "F.Fab")
		)
		(fp_line
			(start 0.67945 -0.3048)
			(end 0.67945 0.3048)
			(stroke
				(width 0.1)
				(type default)
			)
			(layer "F.Fab")
		)
		(fp_line
			(start 0.12065 -0.2794)
			(end 0.12065 -0.3048)
			(stroke
				(width 0.1)
				(type default)
			)
			(layer "F.Fab")
		)
		(fp_line
			(start 0.12065 -0.3048)
			(end 0.67945 -0.3048)
			(stroke
				(width 0.1)
				(type default)
			)
			(layer "F.Fab")
		)
		(fp_line
			(start 0.120396 0.3048)
			(end 0.120396 0.2794)
			(stroke
				(width 0.1)
				(type default)
			)
			(layer "F.Fab")
		)
		(fp_line
			(start 0.120396 0.2794)
			(end -0.12065 0.2794)
			(stroke
				(width 0.1)
				(type default)
			)
			(layer "F.Fab")
		)
		(fp_line
			(start -0.12065 0.3048)
			(end -0.67945 0.3048)
			(stroke
				(width 0.1)
				(type default)
			)
			(layer "F.Fab")
		)
		(fp_line
			(start -0.12065 0.2794)
			(end -0.12065 0.3048)
			(stroke
				(width 0.1)
				(type default)
			)
			(layer "F.Fab")
		)
		(fp_line
			(start -0.12065 -0.2794)
			(end 0.12065 -0.2794)
			(stroke
				(width 0.1)
				(type default)
			)
			(layer "F.Fab")
		)
		(fp_line
			(start -0.12065 -0.305054)
			(end -0.12065 -0.2794)
			(stroke
				(width 0.1)
				(type default)
			)
			(layer "F.Fab")
		)
		(fp_line
			(start -0.67945 0.3048)
			(end -0.67945 -0.305054)
			(stroke
				(width 0.1)
				(type default)
			)
			(layer "F.Fab")
		)
		(fp_line
			(start -0.67945 -0.305054)
			(end -0.12065 -0.305054)
			(stroke
				(width 0.1)
				(type default)
			)
			(layer "F.Fab")
		)
		(pad "1" smd circle
			(at -0.40005 0 180)
			(size 0 0)
			(layers "F.Cu" "F.Mask" "F.Paste")
			(net "P3V3")
		)
		(pad "2" smd circle
			(at 0.40005 0 180)
			(size 0 0)
			(layers "F.Cu" "F.Mask" "F.Paste")
			(net "CLK_9ZXL045_SADR0")
		)
	)
	(footprint ""
		(layer "F.Cu")
		(at 44.29125 -181.983634)
		(property "Reference" "R330"
			(at 0 0 0)
			(layer "F.SilkS")
			(hide yes)
			(effects
				(font
					(size 1.27 1.27)
				)
			)
		)
		(property "Value" ""
			(at 0 0 0)
			(layer "F.Fab")
			(effects
				(font
					(size 1.27 1.27)
				)
			)
		)
		(duplicate_pad_numbers_are_jumpers no)
		(fp_line
			(start -2.044192 -0.94361)
			(end -2.044192 0.898398)
			(stroke
				(width 0.1524)
				(type default)
			)
			(layer "F.SilkS")
		)
		(fp_line
			(start -2.044192 0.94361)
			(end 2.044192 0.94361)
			(stroke
				(width 0.1524)
				(type default)
			)
			(layer "F.SilkS")
		)
		(fp_line
			(start 2.044192 -0.94361)
			(end -2.044192 -0.94361)
			(stroke
				(width 0.1524)
				(type default)
			)
			(layer "F.SilkS")
		)
		(fp_line
			(start 2.044192 0.94361)
			(end 2.044192 -0.94361)
			(stroke
				(width 0.1524)
				(type default)
			)
			(layer "F.SilkS")
		)
		(fp_line
			(start -1.625092 -0.87503)
			(end -1.625092 0.87503)
			(stroke
				(width 0.1)
				(type default)
			)
			(layer "F.Fab")
		)
		(fp_line
			(start -1.625092 0.87503)
			(end 1.625092 0.87503)
			(stroke
				(width 0.1)
				(type default)
			)
			(layer "F.Fab")
		)
		(fp_line
			(start 1.625092 -0.87503)
			(end -1.625092 -0.87503)
			(stroke
				(width 0.1)
				(type default)
			)
			(layer "F.Fab")
		)
		(fp_line
			(start 1.625092 0.87503)
			(end 1.625092 -0.87503)
			(stroke
				(width 0.1)
				(type default)
			)
			(layer "F.Fab")
		)
		(pad "1" smd rect
			(at -1.450086 0)
			(size 0.9144 1.6002)
			(layers "F.Cu" "F.Mask" "F.Paste")
			(net "PVNN_MAIN_CPU1")
		)
		(pad "2" smd rect
			(at 1.450086 0)
			(size 0.9144 1.6002)
			(layers "F.Cu" "F.Mask" "F.Paste")
			(net "PVNN_TERM_CPU1")
		)
	)
	(footprint ""
		(layer "F.Cu")
		(at 406.124664 -361.865926 180)
		(property "Reference" "R331"
			(at 0 0 180)
			(layer "F.SilkS")
			(hide yes)
			(effects
				(font
					(size 1.27 1.27)
				)
			)
		)
		(property "Value" ""
			(at 0 0 180)
			(layer "F.Fab")
			(effects
				(font
					(size 1.27 1.27)
				)
			)
		)
		(duplicate_pad_numbers_are_jumpers no)
		(fp_line
			(start 0.7874 0.4064)
			(end -0.7874 0.4064)
			(stroke
				(width 0.1524)
				(type default)
			)
			(layer "F.SilkS")
		)
		(fp_line
			(start 0.7874 -0.4064)
			(end 0.7874 0.4064)
			(stroke
				(width 0.1524)
				(type default)
			)
			(layer "F.SilkS")
		)
		(fp_line
			(start -0.7874 0.4064)
			(end -0.7874 -0.4064)
			(stroke
				(width 0.1524)
				(type default)
			)
			(layer "F.SilkS")
		)
		(fp_line
			(start -0.7874 -0.4064)
			(end 0.7874 -0.4064)
			(stroke
				(width 0.1524)
				(type default)
			)
			(layer "F.SilkS")
		)
		(fp_line
			(start 0.67945 0.3048)
			(end 0.120396 0.3048)
			(stroke
				(width 0.1)
				(type default)
			)
			(layer "F.Fab")
		)
		(fp_line
			(start 0.67945 -0.3048)
			(end 0.67945 0.3048)
			(stroke
				(width 0.1)
				(type default)
			)
			(layer "F.Fab")
		)
		(fp_line
			(start 0.12065 -0.2794)
			(end 0.12065 -0.3048)
			(stroke
				(width 0.1)
				(type default)
			)
			(layer "F.Fab")
		)
		(fp_line
			(start 0.12065 -0.3048)
			(end 0.67945 -0.3048)
			(stroke
				(width 0.1)
				(type default)
			)
			(layer "F.Fab")
		)
		(fp_line
			(start 0.120396 0.3048)
			(end 0.120396 0.2794)
			(stroke
				(width 0.1)
				(type default)
			)
			(layer "F.Fab")
		)
		(fp_line
			(start 0.120396 0.2794)
			(end -0.12065 0.2794)
			(stroke
				(width 0.1)
				(type default)
			)
			(layer "F.Fab")
		)
		(fp_line
			(start -0.12065 0.3048)
			(end -0.67945 0.3048)
			(stroke
				(width 0.1)
				(type default)
			)
			(layer "F.Fab")
		)
		(fp_line
			(start -0.12065 0.2794)
			(end -0.12065 0.3048)
			(stroke
				(width 0.1)
				(type default)
			)
			(layer "F.Fab")
		)
		(fp_line
			(start -0.12065 -0.2794)
			(end 0.12065 -0.2794)
			(stroke
				(width 0.1)
				(type default)
			)
			(layer "F.Fab")
		)
		(fp_line
			(start -0.12065 -0.305054)
			(end -0.12065 -0.2794)
			(stroke
				(width 0.1)
				(type default)
			)
			(layer "F.Fab")
		)
		(fp_line
			(start -0.67945 0.3048)
			(end -0.67945 -0.305054)
			(stroke
				(width 0.1)
				(type default)
			)
			(layer "F.Fab")
		)
		(fp_line
			(start -0.67945 -0.305054)
			(end -0.12065 -0.305054)
			(stroke
				(width 0.1)
				(type default)
			)
			(layer "F.Fab")
		)
		(pad "1" smd circle
			(at -0.40005 0 180)
			(size 0 0)
			(layers "F.Cu" "F.Mask" "F.Paste")
			(net "P3V3_AUX")
		)
		(pad "2" smd circle
			(at 0.40005 0 180)
			(size 0 0)
			(layers "F.Cu" "F.Mask" "F.Paste")
			(net "PD_PIROM_CPU0_ADDR2")
		)
	)
	(footprint ""
		(layer "F.Cu")
		(at 352.264726 -260.364986 -90)
		(property "Reference" "C406"
			(at 0 0 270)
			(layer "F.SilkS")
			(hide yes)
			(effects
				(font
					(size 1.27 1.27)
				)
			)
		)
		(property "Value" ""
			(at 0 0 270)
			(layer "F.Fab")
			(effects
				(font
					(size 1.27 1.27)
				)
			)
		)
		(duplicate_pad_numbers_are_jumpers no)
		(fp_line
			(start -0.7874 0.4064)
			(end -0.7874 -0.4064)
			(stroke
				(width 0.1524)
				(type default)
			)
			(layer "F.SilkS")
		)
		(fp_line
			(start 0.7874 0.4064)
			(end -0.7874 0.4064)
			(stroke
				(width 0.1524)
				(type default)
			)
			(layer "F.SilkS")
		)
		(fp_line
			(start -0.7874 -0.4064)
			(end 0.7874 -0.4064)
			(stroke
				(width 0.1524)
				(type default)
			)
			(layer "F.SilkS")
		)
		(fp_line
			(start 0.7874 -0.4064)
			(end 0.7874 0.4064)
			(stroke
				(width 0.1524)
				(type default)
			)
			(layer "F.SilkS")
		)
		(fp_line
			(start -0.67945 0.3048)
			(end -0.67945 -0.305054)
			(stroke
				(width 0.1)
				(type default)
			)
			(layer "F.Fab")
		)
		(fp_line
			(start -0.12065 0.3048)
			(end -0.67945 0.3048)
			(stroke
				(width 0.1)
				(type default)
			)
			(layer "F.Fab")
		)
		(fp_line
			(start 0.120396 0.3048)
			(end 0.120396 0.2794)
			(stroke
				(width 0.1)
				(type default)
			)
			(layer "F.Fab")
		)
		(fp_line
			(start 0.67945 0.3048)
			(end 0.120396 0.3048)
			(stroke
				(width 0.1)
				(type default)
			)
			(layer "F.Fab")
		)
		(fp_line
			(start -0.12065 0.2794)
			(end -0.12065 0.3048)
			(stroke
				(width 0.1)
				(type default)
			)
			(layer "F.Fab")
		)
		(fp_line
			(start 0.120396 0.2794)
			(end -0.12065 0.2794)
			(stroke
				(width 0.1)
				(type default)
			)
			(layer "F.Fab")
		)
		(fp_line
			(start -0.12065 -0.2794)
			(end 0.12065 -0.2794)
			(stroke
				(width 0.1)
				(type default)
			)
			(layer "F.Fab")
		)
		(fp_line
			(start 0.12065 -0.2794)
			(end 0.12065 -0.3048)
			(stroke
				(width 0.1)
				(type default)
			)
			(layer "F.Fab")
		)
		(fp_line
			(start 0.12065 -0.3048)
			(end 0.67945 -0.3048)
			(stroke
				(width 0.1)
				(type default)
			)
			(layer "F.Fab")
		)
		(fp_line
			(start 0.67945 -0.3048)
			(end 0.67945 0.3048)
			(stroke
				(width 0.1)
				(type default)
			)
			(layer "F.Fab")
		)
		(fp_line
			(start -0.67945 -0.305054)
			(end -0.12065 -0.305054)
			(stroke
				(width 0.1)
				(type default)
			)
			(layer "F.Fab")
		)
		(fp_line
			(start -0.12065 -0.305054)
			(end -0.12065 -0.2794)
			(stroke
				(width 0.1)
				(type default)
			)
			(layer "F.Fab")
		)
		(pad "1" smd circle
			(at -0.40005 0 270)
			(size 0 0)
			(layers "F.Cu" "F.Mask" "F.Paste")
			(net "PVCCFA_EHV_FIVRA_CPU0")
		)
		(pad "2" smd circle
			(at 0.40005 0 270)
			(size 0 0)
			(layers "F.Cu" "F.Mask" "F.Paste")
			(net "GND")
		)
	)
	(footprint ""
		(layer "F.Cu")
		(at 345.002358 -354.98913 -90)
		(property "Reference" "PC1652"
			(at 0 0 270)
			(layer "F.SilkS")
			(hide yes)
			(effects
				(font
					(size 1.27 1.27)
				)
			)
		)
		(property "Value" ""
			(at 0 0 270)
			(layer "F.Fab")
			(effects
				(font
					(size 1.27 1.27)
				)
			)
		)
		(duplicate_pad_numbers_are_jumpers no)
		(fp_line
			(start -0.7874 0.4064)
			(end -0.7874 -0.4064)
			(stroke
				(width 0.1524)
				(type default)
			)
			(layer "F.SilkS")
		)
		(fp_line
			(start 0.7874 0.4064)
			(end -0.7874 0.4064)
			(stroke
				(width 0.1524)
				(type default)
			)
			(layer "F.SilkS")
		)
		(fp_line
			(start -0.7874 -0.4064)
			(end 0.7874 -0.4064)
			(stroke
				(width 0.1524)
				(type default)
			)
			(layer "F.SilkS")
		)
		(fp_line
			(start 0.7874 -0.4064)
			(end 0.7874 0.4064)
			(stroke
				(width 0.1524)
				(type default)
			)
			(layer "F.SilkS")
		)
		(fp_line
			(start -0.67945 0.3048)
			(end -0.67945 -0.305054)
			(stroke
				(width 0.1)
				(type default)
			)
			(layer "F.Fab")
		)
		(fp_line
			(start -0.12065 0.3048)
			(end -0.67945 0.3048)
			(stroke
				(width 0.1)
				(type default)
			)
			(layer "F.Fab")
		)
		(fp_line
			(start 0.120396 0.3048)
			(end 0.120396 0.2794)
			(stroke
				(width 0.1)
				(type default)
			)
			(layer "F.Fab")
		)
		(fp_line
			(start 0.67945 0.3048)
			(end 0.120396 0.3048)
			(stroke
				(width 0.1)
				(type default)
			)
			(layer "F.Fab")
		)
		(fp_line
			(start -0.12065 0.2794)
			(end -0.12065 0.3048)
			(stroke
				(width 0.1)
				(type default)
			)
			(layer "F.Fab")
		)
		(fp_line
			(start 0.120396 0.2794)
			(end -0.12065 0.2794)
			(stroke
				(width 0.1)
				(type default)
			)
			(layer "F.Fab")
		)
		(fp_line
			(start -0.12065 -0.2794)
			(end 0.12065 -0.2794)
			(stroke
				(width 0.1)
				(type default)
			)
			(layer "F.Fab")
		)
		(fp_line
			(start 0.12065 -0.2794)
			(end 0.12065 -0.3048)
			(stroke
				(width 0.1)
				(type default)
			)
			(layer "F.Fab")
		)
		(fp_line
			(start 0.12065 -0.3048)
			(end 0.67945 -0.3048)
			(stroke
				(width 0.1)
				(type default)
			)
			(layer "F.Fab")
		)
		(fp_line
			(start 0.67945 -0.3048)
			(end 0.67945 0.3048)
			(stroke
				(width 0.1)
				(type default)
			)
			(layer "F.Fab")
		)
		(fp_line
			(start -0.67945 -0.305054)
			(end -0.12065 -0.305054)
			(stroke
				(width 0.1)
				(type default)
			)
			(layer "F.Fab")
		)
		(fp_line
			(start -0.12065 -0.305054)
			(end -0.12065 -0.2794)
			(stroke
				(width 0.1)
				(type default)
			)
			(layer "F.Fab")
		)
		(pad "1" smd circle
			(at -0.40005 0 270)
			(size 0 0)
			(layers "F.Cu" "F.Mask" "F.Paste")
			(net "P12V_AUX")
		)
		(pad "2" smd circle
			(at 0.40005 0 270)
			(size 0 0)
			(layers "F.Cu" "F.Mask" "F.Paste")
			(net "GND")
		)
	)
	(footprint ""
		(layer "F.Cu")
		(at 194.856608 -404.086822 180)
		(property "Reference" "PC2184"
			(at 0 0 180)
			(layer "F.SilkS")
			(hide yes)
			(effects
				(font
					(size 1.27 1.27)
				)
			)
		)
		(property "Value" ""
			(at 0 0 180)
			(layer "F.Fab")
			(effects
				(font
					(size 1.27 1.27)
				)
			)
		)
		(duplicate_pad_numbers_are_jumpers no)
		(fp_line
			(start 0.7874 0.4064)
			(end -0.7874 0.4064)
			(stroke
				(width 0.1524)
				(type default)
			)
			(layer "F.SilkS")
		)
		(fp_line
			(start 0.7874 -0.4064)
			(end 0.7874 0.4064)
			(stroke
				(width 0.1524)
				(type default)
			)
			(layer "F.SilkS")
		)
		(fp_line
			(start -0.7874 0.4064)
			(end -0.7874 -0.4064)
			(stroke
				(width 0.1524)
				(type default)
			)
			(layer "F.SilkS")
		)
		(fp_line
			(start -0.7874 -0.4064)
			(end 0.7874 -0.4064)
			(stroke
				(width 0.1524)
				(type default)
			)
			(layer "F.SilkS")
		)
		(fp_line
			(start 0.67945 0.3048)
			(end 0.120396 0.3048)
			(stroke
				(width 0.1)
				(type default)
			)
			(layer "F.Fab")
		)
		(fp_line
			(start 0.67945 -0.3048)
			(end 0.67945 0.3048)
			(stroke
				(width 0.1)
				(type default)
			)
			(layer "F.Fab")
		)
		(fp_line
			(start 0.12065 -0.2794)
			(end 0.12065 -0.3048)
			(stroke
				(width 0.1)
				(type default)
			)
			(layer "F.Fab")
		)
		(fp_line
			(start 0.12065 -0.3048)
			(end 0.67945 -0.3048)
			(stroke
				(width 0.1)
				(type default)
			)
			(layer "F.Fab")
		)
		(fp_line
			(start 0.120396 0.3048)
			(end 0.120396 0.2794)
			(stroke
				(width 0.1)
				(type default)
			)
			(layer "F.Fab")
		)
		(fp_line
			(start 0.120396 0.2794)
			(end -0.12065 0.2794)
			(stroke
				(width 0.1)
				(type default)
			)
			(layer "F.Fab")
		)
		(fp_line
			(start -0.12065 0.3048)
			(end -0.67945 0.3048)
			(stroke
				(width 0.1)
				(type default)
			)
			(layer "F.Fab")
		)
		(fp_line
			(start -0.12065 0.2794)
			(end -0.12065 0.3048)
			(stroke
				(width 0.1)
				(type default)
			)
			(layer "F.Fab")
		)
		(fp_line
			(start -0.12065 -0.2794)
			(end 0.12065 -0.2794)
			(stroke
				(width 0.1)
				(type default)
			)
			(layer "F.Fab")
		)
		(fp_line
			(start -0.12065 -0.305054)
			(end -0.12065 -0.2794)
			(stroke
				(width 0.1)
				(type default)
			)
			(layer "F.Fab")
		)
		(fp_line
			(start -0.67945 0.3048)
			(end -0.67945 -0.305054)
			(stroke
				(width 0.1)
				(type default)
			)
			(layer "F.Fab")
		)
		(fp_line
			(start -0.67945 -0.305054)
			(end -0.12065 -0.305054)
			(stroke
				(width 0.1)
				(type default)
			)
			(layer "F.Fab")
		)
		(pad "1" smd circle
			(at -0.40005 0 180)
			(size 0 0)
			(layers "F.Cu" "F.Mask" "F.Paste")
			(net "HSC_SS")
		)
		(pad "2" smd circle
			(at 0.40005 0 180)
			(size 0 0)
			(layers "F.Cu" "F.Mask" "F.Paste")
			(net "AGND_HSC")
		)
	)
	(footprint ""
		(layer "F.Cu")
		(at 205.397608 -405.839422 180)
		(property "Reference" "PC2185"
			(at 0 0 180)
			(layer "F.SilkS")
			(hide yes)
			(effects
				(font
					(size 1.27 1.27)
				)
			)
		)
		(property "Value" ""
			(at 0 0 180)
			(layer "F.Fab")
			(effects
				(font
					(size 1.27 1.27)
				)
			)
		)
		(duplicate_pad_numbers_are_jumpers no)
		(fp_line
			(start 0.7874 0.4064)
			(end -0.7874 0.4064)
			(stroke
				(width 0.1524)
				(type default)
			)
			(layer "F.SilkS")
		)
		(fp_line
			(start 0.7874 -0.4064)
			(end 0.7874 0.4064)
			(stroke
				(width 0.1524)
				(type default)
			)
			(layer "F.SilkS")
		)
		(fp_line
			(start -0.7874 0.4064)
			(end -0.7874 -0.4064)
			(stroke
				(width 0.1524)
				(type default)
			)
			(layer "F.SilkS")
		)
		(fp_line
			(start -0.7874 -0.4064)
			(end 0.7874 -0.4064)
			(stroke
				(width 0.1524)
				(type default)
			)
			(layer "F.SilkS")
		)
		(fp_line
			(start 0.67945 0.3048)
			(end 0.120396 0.3048)
			(stroke
				(width 0.1)
				(type default)
			)
			(layer "F.Fab")
		)
		(fp_line
			(start 0.67945 -0.3048)
			(end 0.67945 0.3048)
			(stroke
				(width 0.1)
				(type default)
			)
			(layer "F.Fab")
		)
		(fp_line
			(start 0.12065 -0.2794)
			(end 0.12065 -0.3048)
			(stroke
				(width 0.1)
				(type default)
			)
			(layer "F.Fab")
		)
		(fp_line
			(start 0.12065 -0.3048)
			(end 0.67945 -0.3048)
			(stroke
				(width 0.1)
				(type default)
			)
			(layer "F.Fab")
		)
		(fp_line
			(start 0.120396 0.3048)
			(end 0.120396 0.2794)
			(stroke
				(width 0.1)
				(type default)
			)
			(layer "F.Fab")
		)
		(fp_line
			(start 0.120396 0.2794)
			(end -0.12065 0.2794)
			(stroke
				(width 0.1)
				(type default)
			)
			(layer "F.Fab")
		)
		(fp_line
			(start -0.12065 0.3048)
			(end -0.67945 0.3048)
			(stroke
				(width 0.1)
				(type default)
			)
			(layer "F.Fab")
		)
		(fp_line
			(start -0.12065 0.2794)
			(end -0.12065 0.3048)
			(stroke
				(width 0.1)
				(type default)
			)
			(layer "F.Fab")
		)
		(fp_line
			(start -0.12065 -0.2794)
			(end 0.12065 -0.2794)
			(stroke
				(width 0.1)
				(type default)
			)
			(layer "F.Fab")
		)
		(fp_line
			(start -0.12065 -0.305054)
			(end -0.12065 -0.2794)
			(stroke
				(width 0.1)
				(type default)
			)
			(layer "F.Fab")
		)
		(fp_line
			(start -0.67945 0.3048)
			(end -0.67945 -0.305054)
			(stroke
				(width 0.1)
				(type default)
			)
			(layer "F.Fab")
		)
		(fp_line
			(start -0.67945 -0.305054)
			(end -0.12065 -0.305054)
			(stroke
				(width 0.1)
				(type default)
			)
			(layer "F.Fab")
		)
		(pad "1" smd circle
			(at -0.40005 0 180)
			(size 0 0)
			(layers "F.Cu" "F.Mask" "F.Paste")
			(net "HSC_SS")
		)
		(pad "2" smd circle
			(at 0.40005 0 180)
			(size 0 0)
			(layers "F.Cu" "F.Mask" "F.Paste")
			(net "AGND_HSC")
		)
	)
	(footprint ""
		(layer "F.Cu")
		(at 256.466594 -394.17117)
		(property "Reference" "PR2528"
			(at 0 0 0)
			(layer "F.SilkS")
			(hide yes)
			(effects
				(font
					(size 1.27 1.27)
				)
			)
		)
		(property "Value" ""
			(at 0 0 0)
			(layer "F.Fab")
			(effects
				(font
					(size 1.27 1.27)
				)
			)
		)
		(duplicate_pad_numbers_are_jumpers no)
		(fp_line
			(start -0.7874 -0.4064)
			(end 0.7874 -0.4064)
			(stroke
				(width 0.1524)
				(type default)
			)
			(layer "F.SilkS")
		)
		(fp_line
			(start -0.7874 0.4064)
			(end -0.7874 -0.4064)
			(stroke
				(width 0.1524)
				(type default)
			)
			(layer "F.SilkS")
		)
		(fp_line
			(start 0.7874 -0.4064)
			(end 0.7874 0.4064)
			(stroke
				(width 0.1524)
				(type default)
			)
			(layer "F.SilkS")
		)
		(fp_line
			(start 0.7874 0.4064)
			(end -0.7874 0.4064)
			(stroke
				(width 0.1524)
				(type default)
			)
			(layer "F.SilkS")
		)
		(fp_line
			(start -0.67945 -0.305054)
			(end -0.12065 -0.305054)
			(stroke
				(width 0.1)
				(type default)
			)
			(layer "F.Fab")
		)
		(fp_line
			(start -0.67945 0.3048)
			(end -0.67945 -0.305054)
			(stroke
				(width 0.1)
				(type default)
			)
			(layer "F.Fab")
		)
		(fp_line
			(start -0.12065 -0.305054)
			(end -0.12065 -0.2794)
			(stroke
				(width 0.1)
				(type default)
			)
			(layer "F.Fab")
		)
		(fp_line
			(start -0.12065 -0.2794)
			(end 0.12065 -0.2794)
			(stroke
				(width 0.1)
				(type default)
			)
			(layer "F.Fab")
		)
		(fp_line
			(start -0.12065 0.2794)
			(end -0.12065 0.3048)
			(stroke
				(width 0.1)
				(type default)
			)
			(layer "F.Fab")
		)
		(fp_line
			(start -0.12065 0.3048)
			(end -0.67945 0.3048)
			(stroke
				(width 0.1)
				(type default)
			)
			(layer "F.Fab")
		)
		(fp_line
			(start 0.120396 0.2794)
			(end -0.12065 0.2794)
			(stroke
				(width 0.1)
				(type default)
			)
			(layer "F.Fab")
		)
		(fp_line
			(start 0.120396 0.3048)
			(end 0.120396 0.2794)
			(stroke
				(width 0.1)
				(type default)
			)
			(layer "F.Fab")
		)
		(fp_line
			(start 0.12065 -0.3048)
			(end 0.67945 -0.3048)
			(stroke
				(width 0.1)
				(type default)
			)
			(layer "F.Fab")
		)
		(fp_line
			(start 0.12065 -0.2794)
			(end 0.12065 -0.3048)
			(stroke
				(width 0.1)
				(type default)
			)
			(layer "F.Fab")
		)
		(fp_line
			(start 0.67945 -0.3048)
			(end 0.67945 0.3048)
			(stroke
				(width 0.1)
				(type default)
			)
			(layer "F.Fab")
		)
		(fp_line
			(start 0.67945 0.3048)
			(end 0.120396 0.3048)
			(stroke
				(width 0.1)
				(type default)
			)
			(layer "F.Fab")
		)
		(pad "1" smd circle
			(at -0.40005 0)
			(size 0 0)
			(layers "F.Cu" "F.Mask" "F.Paste")
			(net "P12V_HSC_GATE_G1")
		)
		(pad "2" smd circle
			(at 0.40005 0)
			(size 0 0)
			(layers "F.Cu" "F.Mask" "F.Paste")
			(net "P12V_HSC_GATE2")
		)
	)
	(footprint ""
		(layer "F.Cu")
		(at 380.335536 -105.483152 90)
		(property "Reference" "R2513"
			(at 0 0 90)
			(layer "F.SilkS")
			(hide yes)
			(effects
				(font
					(size 1.27 1.27)
				)
			)
		)
		(property "Value" ""
			(at 0 0 90)
			(layer "F.Fab")
			(effects
				(font
					(size 1.27 1.27)
				)
			)
		)
		(duplicate_pad_numbers_are_jumpers no)
		(fp_line
			(start 0.7874 -0.4064)
			(end 0.7874 0.4064)
			(stroke
				(width 0.1524)
				(type default)
			)
			(layer "F.SilkS")
		)
		(fp_line
			(start -0.7874 -0.4064)
			(end 0.7874 -0.4064)
			(stroke
				(width 0.1524)
				(type default)
			)
			(layer "F.SilkS")
		)
		(fp_line
			(start 0.7874 0.4064)
			(end -0.7874 0.4064)
			(stroke
				(width 0.1524)
				(type default)
			)
			(layer "F.SilkS")
		)
		(fp_line
			(start -0.7874 0.4064)
			(end -0.7874 -0.4064)
			(stroke
				(width 0.1524)
				(type default)
			)
			(layer "F.SilkS")
		)
		(fp_line
			(start -0.12065 -0.305054)
			(end -0.12065 -0.2794)
			(stroke
				(width 0.1)
				(type default)
			)
			(layer "F.Fab")
		)
		(fp_line
			(start -0.67945 -0.305054)
			(end -0.12065 -0.305054)
			(stroke
				(width 0.1)
				(type default)
			)
			(layer "F.Fab")
		)
		(fp_line
			(start 0.67945 -0.3048)
			(end 0.67945 0.3048)
			(stroke
				(width 0.1)
				(type default)
			)
			(layer "F.Fab")
		)
		(fp_line
			(start 0.12065 -0.3048)
			(end 0.67945 -0.3048)
			(stroke
				(width 0.1)
				(type default)
			)
			(layer "F.Fab")
		)
		(fp_line
			(start 0.12065 -0.2794)
			(end 0.12065 -0.3048)
			(stroke
				(width 0.1)
				(type default)
			)
			(layer "F.Fab")
		)
		(fp_line
			(start -0.12065 -0.2794)
			(end 0.12065 -0.2794)
			(stroke
				(width 0.1)
				(type default)
			)
			(layer "F.Fab")
		)
		(fp_line
			(start 0.120396 0.2794)
			(end -0.12065 0.2794)
			(stroke
				(width 0.1)
				(type default)
			)
			(layer "F.Fab")
		)
		(fp_line
			(start -0.12065 0.2794)
			(end -0.12065 0.3048)
			(stroke
				(width 0.1)
				(type default)
			)
			(layer "F.Fab")
		)
		(fp_line
			(start 0.67945 0.3048)
			(end 0.120396 0.3048)
			(stroke
				(width 0.1)
				(type default)
			)
			(layer "F.Fab")
		)
		(fp_line
			(start 0.120396 0.3048)
			(end 0.120396 0.2794)
			(stroke
				(width 0.1)
				(type default)
			)
			(layer "F.Fab")
		)
		(fp_line
			(start -0.12065 0.3048)
			(end -0.67945 0.3048)
			(stroke
				(width 0.1)
				(type default)
			)
			(layer "F.Fab")
		)
		(fp_line
			(start -0.67945 0.3048)
			(end -0.67945 -0.305054)
			(stroke
				(width 0.1)
				(type default)
			)
			(layer "F.Fab")
		)
		(pad "1" smd circle
			(at -0.40005 0 90)
			(size 0 0)
			(layers "F.Cu" "F.Mask" "F.Paste")
			(net "PD_GTL2014_BMC_JTAG_DIR_2")
		)
		(pad "2" smd circle
			(at 0.40005 0 90)
			(size 0 0)
			(layers "F.Cu" "F.Mask" "F.Paste")
			(net "GND")
		)
	)
	(footprint ""
		(layer "F.Cu")
		(at 180.03393 -363.113066 90)
		(property "Reference" "PC1210"
			(at 0 0 90)
			(layer "F.SilkS")
			(hide yes)
			(effects
				(font
					(size 1.27 1.27)
				)
			)
		)
		(property "Value" ""
			(at 0 0 90)
			(layer "F.Fab")
			(effects
				(font
					(size 1.27 1.27)
				)
			)
		)
		(duplicate_pad_numbers_are_jumpers no)
		(fp_line
			(start -3.400044 1.249934)
			(end 3.400044 1.249934)
			(stroke
				(width 0.1524)
				(type default)
			)
			(layer "F.SilkS")
		)
		(fp_circle
			(center 0 1.249934)
			(end 0 4.649978)
			(stroke
				(width 0.1524)
				(type default)
			)
			(fill no)
			(layer "F.SilkS")
		)
		(fp_poly
			(pts
				(arc
					(start -3.400044 1.249934)
					(mid 0 4.649978)
					(end 3.400044 1.249934)
				)
			)
			(stroke
				(width 0)
				(type default)
			)
			(fill yes)
			(layer "F.SilkS")
		)
		(fp_circle
			(center 0 1.249934)
			(end 0 4.649978)
			(stroke
				(width 0.1)
				(type default)
			)
			(fill no)
			(layer "F.Fab")
		)
		(pad "1" thru_hole rect
			(at 0 0 90)
			(size 1.524 1.524)
			(drill 1.016)
			(layers "*.Cu" "*.Mask")
			(remove_unused_layers no)
			(net "SW_P12V_PVCCFA_EHV_FIVRA_CPU1_R")
			(clearance 0)
			(padstack
				(mode front_inner_back)
				(layer "Inner"
					(shape circle)
					(size 1.524 1.524)
					(clearance 0)
				)
				(layer "B.Cu"
					(shape rect)
					(size 1.524 1.524)
					(clearance 0)
				)
			)
		)
		(pad "2" thru_hole circle
			(at 0 2.500122 90)
			(size 1.524 1.524)
			(drill 1.016)
			(layers "*.Cu" "*.Mask")
			(remove_unused_layers no)
			(net "GND")
			(clearance 0)
		)
	)
	(footprint ""
		(layer "F.Cu")
		(at 15.288006 -104.73563 90)
		(property "Reference" "R3651"
			(at 0 0 90)
			(layer "F.SilkS")
			(hide yes)
			(effects
				(font
					(size 1.27 1.27)
				)
			)
		)
		(property "Value" ""
			(at 0 0 90)
			(layer "F.Fab")
			(effects
				(font
					(size 1.27 1.27)
				)
			)
		)
		(duplicate_pad_numbers_are_jumpers no)
		(fp_line
			(start 0.7874 -0.4064)
			(end 0.7874 0.4064)
			(stroke
				(width 0.1524)
				(type default)
			)
			(layer "F.SilkS")
		)
		(fp_line
			(start -0.7874 -0.4064)
			(end 0.00635 -0.4064)
			(stroke
				(width 0.1524)
				(type default)
			)
			(layer "F.SilkS")
		)
		(fp_line
			(start -0.01397 0.4064)
			(end -0.7874 0.4064)
			(stroke
				(width 0.1524)
				(type default)
			)
			(layer "F.SilkS")
		)
		(fp_line
			(start -0.12065 -0.305054)
			(end -0.12065 -0.2794)
			(stroke
				(width 0.1)
				(type default)
			)
			(layer "F.Fab")
		)
		(fp_line
			(start -0.67945 -0.305054)
			(end -0.12065 -0.305054)
			(stroke
				(width 0.1)
				(type default)
			)
			(layer "F.Fab")
		)
		(fp_line
			(start 0.67945 -0.3048)
			(end 0.67945 0.3048)
			(stroke
				(width 0.1)
				(type default)
			)
			(layer "F.Fab")
		)
		(fp_line
			(start 0.12065 -0.3048)
			(end 0.67945 -0.3048)
			(stroke
				(width 0.1)
				(type default)
			)
			(layer "F.Fab")
		)
		(fp_line
			(start 0.12065 -0.2794)
			(end 0.12065 -0.3048)
			(stroke
				(width 0.1)
				(type default)
			)
			(layer "F.Fab")
		)
		(fp_line
			(start -0.12065 -0.2794)
			(end 0.12065 -0.2794)
			(stroke
				(width 0.1)
				(type default)
			)
			(layer "F.Fab")
		)
		(fp_line
			(start 0.120396 0.2794)
			(end -0.12065 0.2794)
			(stroke
				(width 0.1)
				(type default)
			)
			(layer "F.Fab")
		)
		(fp_line
			(start -0.12065 0.2794)
			(end -0.12065 0.3048)
			(stroke
				(width 0.1)
				(type default)
			)
			(layer "F.Fab")
		)
		(fp_line
			(start 0.67945 0.3048)
			(end 0.120396 0.3048)
			(stroke
				(width 0.1)
				(type default)
			)
			(layer "F.Fab")
		)
		(fp_line
			(start 0.120396 0.3048)
			(end 0.120396 0.2794)
			(stroke
				(width 0.1)
				(type default)
			)
			(layer "F.Fab")
		)
		(fp_line
			(start -0.12065 0.3048)
			(end -0.67945 0.3048)
			(stroke
				(width 0.1)
				(type default)
			)
			(layer "F.Fab")
		)
		(fp_line
			(start -0.67945 0.3048)
			(end -0.67945 -0.305054)
			(stroke
				(width 0.1)
				(type default)
			)
			(layer "F.Fab")
		)
		(pad "1" smd rect
			(at -0.40005 0 270)
			(size 0.4572 0.508)
			(layers "F.Cu" "F.Mask" "F.Paste")
			(net "USB2_P0_R_DP")
		)
		(pad "2" smd rect
			(at 0.40005 0 270)
			(size 0.4572 0.508)
			(layers "F.Cu" "F.Mask" "F.Paste")
			(net "USB2_HOST_BMC_B_DP")
		)
	)
	(footprint ""
		(layer "F.Cu")
		(at 303.9872 -22.606 180)
		(property "Reference" "R4791"
			(at 0 0 180)
			(layer "F.SilkS")
			(hide yes)
			(effects
				(font
					(size 1.27 1.27)
				)
			)
		)
		(property "Value" ""
			(at 0 0 180)
			(layer "F.Fab")
			(effects
				(font
					(size 1.27 1.27)
				)
			)
		)
		(duplicate_pad_numbers_are_jumpers no)
		(fp_line
			(start 0.7874 0.4064)
			(end -0.7874 0.4064)
			(stroke
				(width 0.1524)
				(type default)
			)
			(layer "F.SilkS")
		)
		(fp_line
			(start 0.7874 -0.4064)
			(end 0.7874 0.4064)
			(stroke
				(width 0.1524)
				(type default)
			)
			(layer "F.SilkS")
		)
		(fp_line
			(start -0.7874 0.4064)
			(end -0.7874 -0.4064)
			(stroke
				(width 0.1524)
				(type default)
			)
			(layer "F.SilkS")
		)
		(fp_line
			(start -0.7874 -0.4064)
			(end 0.7874 -0.4064)
			(stroke
				(width 0.1524)
				(type default)
			)
			(layer "F.SilkS")
		)
		(fp_line
			(start 0.67945 0.3048)
			(end 0.120396 0.3048)
			(stroke
				(width 0.1)
				(type default)
			)
			(layer "F.Fab")
		)
		(fp_line
			(start 0.67945 -0.3048)
			(end 0.67945 0.3048)
			(stroke
				(width 0.1)
				(type default)
			)
			(layer "F.Fab")
		)
		(fp_line
			(start 0.12065 -0.2794)
			(end 0.12065 -0.3048)
			(stroke
				(width 0.1)
				(type default)
			)
			(layer "F.Fab")
		)
		(fp_line
			(start 0.12065 -0.3048)
			(end 0.67945 -0.3048)
			(stroke
				(width 0.1)
				(type default)
			)
			(layer "F.Fab")
		)
		(fp_line
			(start 0.120396 0.3048)
			(end 0.120396 0.2794)
			(stroke
				(width 0.1)
				(type default)
			)
			(layer "F.Fab")
		)
		(fp_line
			(start 0.120396 0.2794)
			(end -0.12065 0.2794)
			(stroke
				(width 0.1)
				(type default)
			)
			(layer "F.Fab")
		)
		(fp_line
			(start -0.12065 0.3048)
			(end -0.67945 0.3048)
			(stroke
				(width 0.1)
				(type default)
			)
			(layer "F.Fab")
		)
		(fp_line
			(start -0.12065 0.2794)
			(end -0.12065 0.3048)
			(stroke
				(width 0.1)
				(type default)
			)
			(layer "F.Fab")
		)
		(fp_line
			(start -0.12065 -0.2794)
			(end 0.12065 -0.2794)
			(stroke
				(width 0.1)
				(type default)
			)
			(layer "F.Fab")
		)
		(fp_line
			(start -0.12065 -0.305054)
			(end -0.12065 -0.2794)
			(stroke
				(width 0.1)
				(type default)
			)
			(layer "F.Fab")
		)
		(fp_line
			(start -0.67945 0.3048)
			(end -0.67945 -0.305054)
			(stroke
				(width 0.1)
				(type default)
			)
			(layer "F.Fab")
		)
		(fp_line
			(start -0.67945 -0.305054)
			(end -0.12065 -0.305054)
			(stroke
				(width 0.1)
				(type default)
			)
			(layer "F.Fab")
		)
		(pad "1" smd circle
			(at -0.40005 0 180)
			(size 0 0)
			(layers "F.Cu" "F.Mask" "F.Paste")
			(net "PWRGD_DSW_PWROK_TRIGGER")
		)
		(pad "2" smd circle
			(at 0.40005 0 180)
			(size 0 0)
			(layers "F.Cu" "F.Mask" "F.Paste")
			(net "GND")
		)
	)
	(footprint ""
		(layer "F.Cu")
		(at 255.37033 -54.844442 90)
		(property "Reference" "PR3951"
			(at 0 0 90)
			(layer "F.SilkS")
			(hide yes)
			(effects
				(font
					(size 1.27 1.27)
				)
			)
		)
		(property "Value" ""
			(at 0 0 90)
			(layer "F.Fab")
			(effects
				(font
					(size 1.27 1.27)
				)
			)
		)
		(duplicate_pad_numbers_are_jumpers no)
		(fp_line
			(start 0.7874 -0.4064)
			(end 0.7874 0.4064)
			(stroke
				(width 0.1524)
				(type default)
			)
			(layer "F.SilkS")
		)
		(fp_line
			(start -0.7874 -0.4064)
			(end 0.7874 -0.4064)
			(stroke
				(width 0.1524)
				(type default)
			)
			(layer "F.SilkS")
		)
		(fp_line
			(start 0.7874 0.4064)
			(end -0.7874 0.4064)
			(stroke
				(width 0.1524)
				(type default)
			)
			(layer "F.SilkS")
		)
		(fp_line
			(start -0.7874 0.4064)
			(end -0.7874 -0.4064)
			(stroke
				(width 0.1524)
				(type default)
			)
			(layer "F.SilkS")
		)
		(fp_line
			(start -0.12065 -0.305054)
			(end -0.12065 -0.2794)
			(stroke
				(width 0.1)
				(type default)
			)
			(layer "F.Fab")
		)
		(fp_line
			(start -0.67945 -0.305054)
			(end -0.12065 -0.305054)
			(stroke
				(width 0.1)
				(type default)
			)
			(layer "F.Fab")
		)
		(fp_line
			(start 0.67945 -0.3048)
			(end 0.67945 0.3048)
			(stroke
				(width 0.1)
				(type default)
			)
			(layer "F.Fab")
		)
		(fp_line
			(start 0.12065 -0.3048)
			(end 0.67945 -0.3048)
			(stroke
				(width 0.1)
				(type default)
			)
			(layer "F.Fab")
		)
		(fp_line
			(start 0.12065 -0.2794)
			(end 0.12065 -0.3048)
			(stroke
				(width 0.1)
				(type default)
			)
			(layer "F.Fab")
		)
		(fp_line
			(start -0.12065 -0.2794)
			(end 0.12065 -0.2794)
			(stroke
				(width 0.1)
				(type default)
			)
			(layer "F.Fab")
		)
		(fp_line
			(start 0.120396 0.2794)
			(end -0.12065 0.2794)
			(stroke
				(width 0.1)
				(type default)
			)
			(layer "F.Fab")
		)
		(fp_line
			(start -0.12065 0.2794)
			(end -0.12065 0.3048)
			(stroke
				(width 0.1)
				(type default)
			)
			(layer "F.Fab")
		)
		(fp_line
			(start 0.67945 0.3048)
			(end 0.120396 0.3048)
			(stroke
				(width 0.1)
				(type default)
			)
			(layer "F.Fab")
		)
		(fp_line
			(start 0.120396 0.3048)
			(end 0.120396 0.2794)
			(stroke
				(width 0.1)
				(type default)
			)
			(layer "F.Fab")
		)
		(fp_line
			(start -0.12065 0.3048)
			(end -0.67945 0.3048)
			(stroke
				(width 0.1)
				(type default)
			)
			(layer "F.Fab")
		)
		(fp_line
			(start -0.67945 0.3048)
			(end -0.67945 -0.305054)
			(stroke
				(width 0.1)
				(type default)
			)
			(layer "F.Fab")
		)
		(pad "1" smd circle
			(at -0.40005 0 90)
			(size 0 0)
			(layers "F.Cu" "F.Mask" "F.Paste")
			(net "P12V_E1S_FLTB_0")
		)
		(pad "2" smd circle
			(at 0.40005 0 90)
			(size 0 0)
			(layers "F.Cu" "F.Mask" "F.Paste")
			(net "P3V3_AUX")
		)
	)
	(footprint ""
		(layer "F.Cu")
		(at 226.733608 -404.823422)
		(property "Reference" "PC2224"
			(at 0 0 0)
			(layer "F.SilkS")
			(hide yes)
			(effects
				(font
					(size 1.27 1.27)
				)
			)
		)
		(property "Value" ""
			(at 0 0 0)
			(layer "F.Fab")
			(effects
				(font
					(size 1.27 1.27)
				)
			)
		)
		(duplicate_pad_numbers_are_jumpers no)
		(fp_line
			(start -0.7874 -0.4064)
			(end 0.7874 -0.4064)
			(stroke
				(width 0.1524)
				(type default)
			)
			(layer "F.SilkS")
		)
		(fp_line
			(start -0.7874 0.4064)
			(end -0.7874 -0.4064)
			(stroke
				(width 0.1524)
				(type default)
			)
			(layer "F.SilkS")
		)
		(fp_line
			(start 0.7874 -0.4064)
			(end 0.7874 0.4064)
			(stroke
				(width 0.1524)
				(type default)
			)
			(layer "F.SilkS")
		)
		(fp_line
			(start 0.7874 0.4064)
			(end -0.7874 0.4064)
			(stroke
				(width 0.1524)
				(type default)
			)
			(layer "F.SilkS")
		)
		(fp_line
			(start -0.67945 -0.305054)
			(end -0.12065 -0.305054)
			(stroke
				(width 0.1)
				(type default)
			)
			(layer "F.Fab")
		)
		(fp_line
			(start -0.67945 0.3048)
			(end -0.67945 -0.305054)
			(stroke
				(width 0.1)
				(type default)
			)
			(layer "F.Fab")
		)
		(fp_line
			(start -0.12065 -0.305054)
			(end -0.12065 -0.2794)
			(stroke
				(width 0.1)
				(type default)
			)
			(layer "F.Fab")
		)
		(fp_line
			(start -0.12065 -0.2794)
			(end 0.12065 -0.2794)
			(stroke
				(width 0.1)
				(type default)
			)
			(layer "F.Fab")
		)
		(fp_line
			(start -0.12065 0.2794)
			(end -0.12065 0.3048)
			(stroke
				(width 0.1)
				(type default)
			)
			(layer "F.Fab")
		)
		(fp_line
			(start -0.12065 0.3048)
			(end -0.67945 0.3048)
			(stroke
				(width 0.1)
				(type default)
			)
			(layer "F.Fab")
		)
		(fp_line
			(start 0.120396 0.2794)
			(end -0.12065 0.2794)
			(stroke
				(width 0.1)
				(type default)
			)
			(layer "F.Fab")
		)
		(fp_line
			(start 0.120396 0.3048)
			(end 0.120396 0.2794)
			(stroke
				(width 0.1)
				(type default)
			)
			(layer "F.Fab")
		)
		(fp_line
			(start 0.12065 -0.3048)
			(end 0.67945 -0.3048)
			(stroke
				(width 0.1)
				(type default)
			)
			(layer "F.Fab")
		)
		(fp_line
			(start 0.12065 -0.2794)
			(end 0.12065 -0.3048)
			(stroke
				(width 0.1)
				(type default)
			)
			(layer "F.Fab")
		)
		(fp_line
			(start 0.67945 -0.3048)
			(end 0.67945 0.3048)
			(stroke
				(width 0.1)
				(type default)
			)
			(layer "F.Fab")
		)
		(fp_line
			(start 0.67945 0.3048)
			(end 0.120396 0.3048)
			(stroke
				(width 0.1)
				(type default)
			)
			(layer "F.Fab")
		)
		(pad "1" smd circle
			(at -0.40005 0)
			(size 0 0)
			(layers "F.Cu" "F.Mask" "F.Paste")
			(net "HSC_ON")
		)
		(pad "2" smd circle
			(at 0.40005 0)
			(size 0 0)
			(layers "F.Cu" "F.Mask" "F.Paste")
			(net "AGND_HSC")
		)
	)
	(footprint ""
		(layer "F.Cu")
		(at 330.721208 -408.517344 -90)
		(property "Reference" "C919"
			(at 0 0 270)
			(layer "F.SilkS")
			(hide yes)
			(effects
				(font
					(size 1.27 1.27)
				)
			)
		)
		(property "Value" ""
			(at 0 0 270)
			(layer "F.Fab")
			(effects
				(font
					(size 1.27 1.27)
				)
			)
		)
		(duplicate_pad_numbers_are_jumpers no)
		(fp_line
			(start -0.299974 0.150114)
			(end -0.299974 -0.150114)
			(stroke
				(width 0.1)
				(type default)
			)
			(layer "F.Fab")
		)
		(fp_line
			(start 0.299974 0.150114)
			(end -0.299974 0.150114)
			(stroke
				(width 0.1)
				(type default)
			)
			(layer "F.Fab")
		)
		(fp_line
			(start -0.299974 -0.150114)
			(end 0.299974 -0.150114)
			(stroke
				(width 0.1)
				(type default)
			)
			(layer "F.Fab")
		)
		(fp_line
			(start 0.299974 -0.150114)
			(end 0.299974 0.150114)
			(stroke
				(width 0.1)
				(type default)
			)
			(layer "F.Fab")
		)
		(pad "1" smd rect
			(at -0.2667 0 270)
			(size 0.3048 0.381)
			(layers "F.Cu" "F.Mask" "F.Paste")
			(net "P5E_CPU0_PE0_TX_C_DP<7>")
		)
		(pad "2" smd rect
			(at 0.2667 0 270)
			(size 0.3048 0.381)
			(layers "F.Cu" "F.Mask" "F.Paste")
			(net "P5E_CPU0_PE0_TX_DP<7>")
		)
	)
	(footprint ""
		(layer "F.Cu")
		(at 116.399056 -66.664078 -90)
		(property "Reference" "R930"
			(at 0 0 270)
			(layer "F.SilkS")
			(hide yes)
			(effects
				(font
					(size 1.27 1.27)
				)
			)
		)
		(property "Value" ""
			(at 0 0 270)
			(layer "F.Fab")
			(effects
				(font
					(size 1.27 1.27)
				)
			)
		)
		(duplicate_pad_numbers_are_jumpers no)
		(fp_line
			(start -0.7874 0.4064)
			(end -0.7874 -0.4064)
			(stroke
				(width 0.1524)
				(type default)
			)
			(layer "F.SilkS")
		)
		(fp_line
			(start 0.7874 0.4064)
			(end -0.7874 0.4064)
			(stroke
				(width 0.1524)
				(type default)
			)
			(layer "F.SilkS")
		)
		(fp_line
			(start -0.7874 -0.4064)
			(end 0.7874 -0.4064)
			(stroke
				(width 0.1524)
				(type default)
			)
			(layer "F.SilkS")
		)
		(fp_line
			(start 0.7874 -0.4064)
			(end 0.7874 0.4064)
			(stroke
				(width 0.1524)
				(type default)
			)
			(layer "F.SilkS")
		)
		(fp_line
			(start -0.67945 0.3048)
			(end -0.67945 -0.305054)
			(stroke
				(width 0.1)
				(type default)
			)
			(layer "F.Fab")
		)
		(fp_line
			(start -0.12065 0.3048)
			(end -0.67945 0.3048)
			(stroke
				(width 0.1)
				(type default)
			)
			(layer "F.Fab")
		)
		(fp_line
			(start 0.120396 0.3048)
			(end 0.120396 0.2794)
			(stroke
				(width 0.1)
				(type default)
			)
			(layer "F.Fab")
		)
		(fp_line
			(start 0.67945 0.3048)
			(end 0.120396 0.3048)
			(stroke
				(width 0.1)
				(type default)
			)
			(layer "F.Fab")
		)
		(fp_line
			(start -0.12065 0.2794)
			(end -0.12065 0.3048)
			(stroke
				(width 0.1)
				(type default)
			)
			(layer "F.Fab")
		)
		(fp_line
			(start 0.120396 0.2794)
			(end -0.12065 0.2794)
			(stroke
				(width 0.1)
				(type default)
			)
			(layer "F.Fab")
		)
		(fp_line
			(start -0.12065 -0.2794)
			(end 0.12065 -0.2794)
			(stroke
				(width 0.1)
				(type default)
			)
			(layer "F.Fab")
		)
		(fp_line
			(start 0.12065 -0.2794)
			(end 0.12065 -0.3048)
			(stroke
				(width 0.1)
				(type default)
			)
			(layer "F.Fab")
		)
		(fp_line
			(start 0.12065 -0.3048)
			(end 0.67945 -0.3048)
			(stroke
				(width 0.1)
				(type default)
			)
			(layer "F.Fab")
		)
		(fp_line
			(start 0.67945 -0.3048)
			(end 0.67945 0.3048)
			(stroke
				(width 0.1)
				(type default)
			)
			(layer "F.Fab")
		)
		(fp_line
			(start -0.67945 -0.305054)
			(end -0.12065 -0.305054)
			(stroke
				(width 0.1)
				(type default)
			)
			(layer "F.Fab")
		)
		(fp_line
			(start -0.12065 -0.305054)
			(end -0.12065 -0.2794)
			(stroke
				(width 0.1)
				(type default)
			)
			(layer "F.Fab")
		)
		(pad "1" smd circle
			(at -0.40005 0 270)
			(size 0 0)
			(layers "F.Cu" "F.Mask" "F.Paste")
			(net "JTAG_BMC_PLD_TCK")
		)
		(pad "2" smd circle
			(at 0.40005 0 270)
			(size 0 0)
			(layers "F.Cu" "F.Mask" "F.Paste")
			(net "GND")
		)
	)
	(footprint ""
		(layer "F.Cu")
		(at 218.336368 -61.072014 180)
		(property "Reference" "PC2218"
			(at 0 0 180)
			(layer "F.SilkS")
			(hide yes)
			(effects
				(font
					(size 1.27 1.27)
				)
			)
		)
		(property "Value" ""
			(at 0 0 180)
			(layer "F.Fab")
			(effects
				(font
					(size 1.27 1.27)
				)
			)
		)
		(duplicate_pad_numbers_are_jumpers no)
		(fp_line
			(start 0.7874 0.4064)
			(end -0.7874 0.4064)
			(stroke
				(width 0.1524)
				(type default)
			)
			(layer "F.SilkS")
		)
		(fp_line
			(start 0.7874 -0.4064)
			(end 0.7874 0.4064)
			(stroke
				(width 0.1524)
				(type default)
			)
			(layer "F.SilkS")
		)
		(fp_line
			(start -0.7874 0.4064)
			(end -0.7874 -0.4064)
			(stroke
				(width 0.1524)
				(type default)
			)
			(layer "F.SilkS")
		)
		(fp_line
			(start -0.7874 -0.4064)
			(end 0.7874 -0.4064)
			(stroke
				(width 0.1524)
				(type default)
			)
			(layer "F.SilkS")
		)
		(fp_line
			(start 0.67945 0.3048)
			(end 0.120396 0.3048)
			(stroke
				(width 0.1)
				(type default)
			)
			(layer "F.Fab")
		)
		(fp_line
			(start 0.67945 -0.3048)
			(end 0.67945 0.3048)
			(stroke
				(width 0.1)
				(type default)
			)
			(layer "F.Fab")
		)
		(fp_line
			(start 0.12065 -0.2794)
			(end 0.12065 -0.3048)
			(stroke
				(width 0.1)
				(type default)
			)
			(layer "F.Fab")
		)
		(fp_line
			(start 0.12065 -0.3048)
			(end 0.67945 -0.3048)
			(stroke
				(width 0.1)
				(type default)
			)
			(layer "F.Fab")
		)
		(fp_line
			(start 0.120396 0.3048)
			(end 0.120396 0.2794)
			(stroke
				(width 0.1)
				(type default)
			)
			(layer "F.Fab")
		)
		(fp_line
			(start 0.120396 0.2794)
			(end -0.12065 0.2794)
			(stroke
				(width 0.1)
				(type default)
			)
			(layer "F.Fab")
		)
		(fp_line
			(start -0.12065 0.3048)
			(end -0.67945 0.3048)
			(stroke
				(width 0.1)
				(type default)
			)
			(layer "F.Fab")
		)
		(fp_line
			(start -0.12065 0.2794)
			(end -0.12065 0.3048)
			(stroke
				(width 0.1)
				(type default)
			)
			(layer "F.Fab")
		)
		(fp_line
			(start -0.12065 -0.2794)
			(end 0.12065 -0.2794)
			(stroke
				(width 0.1)
				(type default)
			)
			(layer "F.Fab")
		)
		(fp_line
			(start -0.12065 -0.305054)
			(end -0.12065 -0.2794)
			(stroke
				(width 0.1)
				(type default)
			)
			(layer "F.Fab")
		)
		(fp_line
			(start -0.67945 0.3048)
			(end -0.67945 -0.305054)
			(stroke
				(width 0.1)
				(type default)
			)
			(layer "F.Fab")
		)
		(fp_line
			(start -0.67945 -0.305054)
			(end -0.12065 -0.305054)
			(stroke
				(width 0.1)
				(type default)
			)
			(layer "F.Fab")
		)
		(pad "1" smd circle
			(at -0.40005 0 180)
			(size 0 0)
			(layers "F.Cu" "F.Mask" "F.Paste")
			(net "P3V3_E1S_0_R")
		)
		(pad "2" smd circle
			(at 0.40005 0 180)
			(size 0 0)
			(layers "F.Cu" "F.Mask" "F.Paste")
			(net "GND")
		)
	)
	(footprint ""
		(layer "F.Cu")
		(at 322.263516 -23.551896 180)
		(property "Reference" "R1810"
			(at 0 0 180)
			(layer "F.SilkS")
			(hide yes)
			(effects
				(font
					(size 1.27 1.27)
				)
			)
		)
		(property "Value" ""
			(at 0 0 180)
			(layer "F.Fab")
			(effects
				(font
					(size 1.27 1.27)
				)
			)
		)
		(duplicate_pad_numbers_are_jumpers no)
		(fp_line
			(start 0.7874 0.4064)
			(end -0.7874 0.4064)
			(stroke
				(width 0.1524)
				(type default)
			)
			(layer "F.SilkS")
		)
		(fp_line
			(start 0.7874 -0.4064)
			(end 0.7874 0.4064)
			(stroke
				(width 0.1524)
				(type default)
			)
			(layer "F.SilkS")
		)
		(fp_line
			(start -0.7874 0.4064)
			(end -0.7874 -0.4064)
			(stroke
				(width 0.1524)
				(type default)
			)
			(layer "F.SilkS")
		)
		(fp_line
			(start -0.7874 -0.4064)
			(end 0.7874 -0.4064)
			(stroke
				(width 0.1524)
				(type default)
			)
			(layer "F.SilkS")
		)
		(fp_line
			(start 0.67945 0.3048)
			(end 0.120396 0.3048)
			(stroke
				(width 0.1)
				(type default)
			)
			(layer "F.Fab")
		)
		(fp_line
			(start 0.67945 -0.3048)
			(end 0.67945 0.3048)
			(stroke
				(width 0.1)
				(type default)
			)
			(layer "F.Fab")
		)
		(fp_line
			(start 0.12065 -0.2794)
			(end 0.12065 -0.3048)
			(stroke
				(width 0.1)
				(type default)
			)
			(layer "F.Fab")
		)
		(fp_line
			(start 0.12065 -0.3048)
			(end 0.67945 -0.3048)
			(stroke
				(width 0.1)
				(type default)
			)
			(layer "F.Fab")
		)
		(fp_line
			(start 0.120396 0.3048)
			(end 0.120396 0.2794)
			(stroke
				(width 0.1)
				(type default)
			)
			(layer "F.Fab")
		)
		(fp_line
			(start 0.120396 0.2794)
			(end -0.12065 0.2794)
			(stroke
				(width 0.1)
				(type default)
			)
			(layer "F.Fab")
		)
		(fp_line
			(start -0.12065 0.3048)
			(end -0.67945 0.3048)
			(stroke
				(width 0.1)
				(type default)
			)
			(layer "F.Fab")
		)
		(fp_line
			(start -0.12065 0.2794)
			(end -0.12065 0.3048)
			(stroke
				(width 0.1)
				(type default)
			)
			(layer "F.Fab")
		)
		(fp_line
			(start -0.12065 -0.2794)
			(end 0.12065 -0.2794)
			(stroke
				(width 0.1)
				(type default)
			)
			(layer "F.Fab")
		)
		(fp_line
			(start -0.12065 -0.305054)
			(end -0.12065 -0.2794)
			(stroke
				(width 0.1)
				(type default)
			)
			(layer "F.Fab")
		)
		(fp_line
			(start -0.67945 0.3048)
			(end -0.67945 -0.305054)
			(stroke
				(width 0.1)
				(type default)
			)
			(layer "F.Fab")
		)
		(fp_line
			(start -0.67945 -0.305054)
			(end -0.12065 -0.305054)
			(stroke
				(width 0.1)
				(type default)
			)
			(layer "F.Fab")
		)
		(pad "1" smd circle
			(at -0.40005 0 180)
			(size 0 0)
			(layers "F.Cu" "F.Mask" "F.Paste")
			(net "FM_ADR_MODE0")
		)
		(pad "2" smd circle
			(at 0.40005 0 180)
			(size 0 0)
			(layers "F.Cu" "F.Mask" "F.Paste")
			(net "GND")
		)
	)
	(footprint ""
		(layer "F.Cu")
		(at 185.799222 -23.113492)
		(property "Reference" "PR4000"
			(at 0 0 0)
			(layer "F.SilkS")
			(hide yes)
			(effects
				(font
					(size 1.27 1.27)
				)
			)
		)
		(property "Value" ""
			(at 0 0 0)
			(layer "F.Fab")
			(effects
				(font
					(size 1.27 1.27)
				)
			)
		)
		(duplicate_pad_numbers_are_jumpers no)
		(fp_line
			(start -0.7874 -0.4064)
			(end 0.7874 -0.4064)
			(stroke
				(width 0.1524)
				(type default)
			)
			(layer "F.SilkS")
		)
		(fp_line
			(start -0.7874 0.4064)
			(end -0.7874 -0.4064)
			(stroke
				(width 0.1524)
				(type default)
			)
			(layer "F.SilkS")
		)
		(fp_line
			(start 0.7874 -0.4064)
			(end 0.7874 0.4064)
			(stroke
				(width 0.1524)
				(type default)
			)
			(layer "F.SilkS")
		)
		(fp_line
			(start 0.7874 0.4064)
			(end -0.7874 0.4064)
			(stroke
				(width 0.1524)
				(type default)
			)
			(layer "F.SilkS")
		)
		(fp_line
			(start -0.67945 -0.305054)
			(end -0.12065 -0.305054)
			(stroke
				(width 0.1)
				(type default)
			)
			(layer "F.Fab")
		)
		(fp_line
			(start -0.67945 0.3048)
			(end -0.67945 -0.305054)
			(stroke
				(width 0.1)
				(type default)
			)
			(layer "F.Fab")
		)
		(fp_line
			(start -0.12065 -0.305054)
			(end -0.12065 -0.2794)
			(stroke
				(width 0.1)
				(type default)
			)
			(layer "F.Fab")
		)
		(fp_line
			(start -0.12065 -0.2794)
			(end 0.12065 -0.2794)
			(stroke
				(width 0.1)
				(type default)
			)
			(layer "F.Fab")
		)
		(fp_line
			(start -0.12065 0.2794)
			(end -0.12065 0.3048)
			(stroke
				(width 0.1)
				(type default)
			)
			(layer "F.Fab")
		)
		(fp_line
			(start -0.12065 0.3048)
			(end -0.67945 0.3048)
			(stroke
				(width 0.1)
				(type default)
			)
			(layer "F.Fab")
		)
		(fp_line
			(start 0.120396 0.2794)
			(end -0.12065 0.2794)
			(stroke
				(width 0.1)
				(type default)
			)
			(layer "F.Fab")
		)
		(fp_line
			(start 0.120396 0.3048)
			(end 0.120396 0.2794)
			(stroke
				(width 0.1)
				(type default)
			)
			(layer "F.Fab")
		)
		(fp_line
			(start 0.12065 -0.3048)
			(end 0.67945 -0.3048)
			(stroke
				(width 0.1)
				(type default)
			)
			(layer "F.Fab")
		)
		(fp_line
			(start 0.12065 -0.2794)
			(end 0.12065 -0.3048)
			(stroke
				(width 0.1)
				(type default)
			)
			(layer "F.Fab")
		)
		(fp_line
			(start 0.67945 -0.3048)
			(end 0.67945 0.3048)
			(stroke
				(width 0.1)
				(type default)
			)
			(layer "F.Fab")
		)
		(fp_line
			(start 0.67945 0.3048)
			(end 0.120396 0.3048)
			(stroke
				(width 0.1)
				(type default)
			)
			(layer "F.Fab")
		)
		(pad "1" smd circle
			(at -0.40005 0)
			(size 0 0)
			(layers "F.Cu" "F.Mask" "F.Paste")
			(net "P12V_AUX")
		)
		(pad "2" smd circle
			(at 0.40005 0)
			(size 0 0)
			(layers "F.Cu" "F.Mask" "F.Paste")
			(net "P12V_SCM_UV")
		)
	)
	(footprint ""
		(layer "F.Cu")
		(at 193.38036 -124.170948)
		(property "Reference" "C1325"
			(at 0 0 0)
			(layer "F.SilkS")
			(hide yes)
			(effects
				(font
					(size 1.27 1.27)
				)
			)
		)
		(property "Value" ""
			(at 0 0 0)
			(layer "F.Fab")
			(effects
				(font
					(size 1.27 1.27)
				)
			)
		)
		(duplicate_pad_numbers_are_jumpers no)
		(fp_line
			(start -0.7874 -0.4064)
			(end 0.7874 -0.4064)
			(stroke
				(width 0.1524)
				(type default)
			)
			(layer "F.SilkS")
		)
		(fp_line
			(start -0.7874 0.4064)
			(end -0.7874 -0.4064)
			(stroke
				(width 0.1524)
				(type default)
			)
			(layer "F.SilkS")
		)
		(fp_line
			(start 0.7874 -0.4064)
			(end 0.7874 0.4064)
			(stroke
				(width 0.1524)
				(type default)
			)
			(layer "F.SilkS")
		)
		(fp_line
			(start 0.7874 0.4064)
			(end -0.7874 0.4064)
			(stroke
				(width 0.1524)
				(type default)
			)
			(layer "F.SilkS")
		)
		(fp_line
			(start -0.67945 -0.305054)
			(end -0.12065 -0.305054)
			(stroke
				(width 0.1)
				(type default)
			)
			(layer "F.Fab")
		)
		(fp_line
			(start -0.67945 0.3048)
			(end -0.67945 -0.305054)
			(stroke
				(width 0.1)
				(type default)
			)
			(layer "F.Fab")
		)
		(fp_line
			(start -0.12065 -0.305054)
			(end -0.12065 -0.2794)
			(stroke
				(width 0.1)
				(type default)
			)
			(layer "F.Fab")
		)
		(fp_line
			(start -0.12065 -0.2794)
			(end 0.12065 -0.2794)
			(stroke
				(width 0.1)
				(type default)
			)
			(layer "F.Fab")
		)
		(fp_line
			(start -0.12065 0.2794)
			(end -0.12065 0.3048)
			(stroke
				(width 0.1)
				(type default)
			)
			(layer "F.Fab")
		)
		(fp_line
			(start -0.12065 0.3048)
			(end -0.67945 0.3048)
			(stroke
				(width 0.1)
				(type default)
			)
			(layer "F.Fab")
		)
		(fp_line
			(start 0.120396 0.2794)
			(end -0.12065 0.2794)
			(stroke
				(width 0.1)
				(type default)
			)
			(layer "F.Fab")
		)
		(fp_line
			(start 0.120396 0.3048)
			(end 0.120396 0.2794)
			(stroke
				(width 0.1)
				(type default)
			)
			(layer "F.Fab")
		)
		(fp_line
			(start 0.12065 -0.3048)
			(end 0.67945 -0.3048)
			(stroke
				(width 0.1)
				(type default)
			)
			(layer "F.Fab")
		)
		(fp_line
			(start 0.12065 -0.2794)
			(end 0.12065 -0.3048)
			(stroke
				(width 0.1)
				(type default)
			)
			(layer "F.Fab")
		)
		(fp_line
			(start 0.67945 -0.3048)
			(end 0.67945 0.3048)
			(stroke
				(width 0.1)
				(type default)
			)
			(layer "F.Fab")
		)
		(fp_line
			(start 0.67945 0.3048)
			(end 0.120396 0.3048)
			(stroke
				(width 0.1)
				(type default)
			)
			(layer "F.Fab")
		)
		(pad "1" smd circle
			(at -0.40005 0)
			(size 0 0)
			(layers "F.Cu" "F.Mask" "F.Paste")
			(net "FM_PLD_REV_N")
		)
		(pad "2" smd circle
			(at 0.40005 0)
			(size 0 0)
			(layers "F.Cu" "F.Mask" "F.Paste")
			(net "GND")
		)
	)
	(footprint ""
		(layer "F.Cu")
		(at 179.352448 -402.255482)
		(property "Reference" "PR3002"
			(at 0 0 0)
			(layer "F.SilkS")
			(hide yes)
			(effects
				(font
					(size 1.27 1.27)
				)
			)
		)
		(property "Value" ""
			(at 0 0 0)
			(layer "F.Fab")
			(effects
				(font
					(size 1.27 1.27)
				)
			)
		)
		(duplicate_pad_numbers_are_jumpers no)
		(fp_line
			(start -0.7874 -0.4064)
			(end 0.7874 -0.4064)
			(stroke
				(width 0.1524)
				(type default)
			)
			(layer "F.SilkS")
		)
		(fp_line
			(start -0.7874 0.4064)
			(end -0.7874 -0.4064)
			(stroke
				(width 0.1524)
				(type default)
			)
			(layer "F.SilkS")
		)
		(fp_line
			(start 0.7874 -0.4064)
			(end 0.7874 0.4064)
			(stroke
				(width 0.1524)
				(type default)
			)
			(layer "F.SilkS")
		)
		(fp_line
			(start 0.7874 0.4064)
			(end -0.7874 0.4064)
			(stroke
				(width 0.1524)
				(type default)
			)
			(layer "F.SilkS")
		)
		(fp_line
			(start -0.67945 -0.305054)
			(end -0.12065 -0.305054)
			(stroke
				(width 0.1)
				(type default)
			)
			(layer "F.Fab")
		)
		(fp_line
			(start -0.67945 0.3048)
			(end -0.67945 -0.305054)
			(stroke
				(width 0.1)
				(type default)
			)
			(layer "F.Fab")
		)
		(fp_line
			(start -0.12065 -0.305054)
			(end -0.12065 -0.2794)
			(stroke
				(width 0.1)
				(type default)
			)
			(layer "F.Fab")
		)
		(fp_line
			(start -0.12065 -0.2794)
			(end 0.12065 -0.2794)
			(stroke
				(width 0.1)
				(type default)
			)
			(layer "F.Fab")
		)
		(fp_line
			(start -0.12065 0.2794)
			(end -0.12065 0.3048)
			(stroke
				(width 0.1)
				(type default)
			)
			(layer "F.Fab")
		)
		(fp_line
			(start -0.12065 0.3048)
			(end -0.67945 0.3048)
			(stroke
				(width 0.1)
				(type default)
			)
			(layer "F.Fab")
		)
		(fp_line
			(start 0.120396 0.2794)
			(end -0.12065 0.2794)
			(stroke
				(width 0.1)
				(type default)
			)
			(layer "F.Fab")
		)
		(fp_line
			(start 0.120396 0.3048)
			(end 0.120396 0.2794)
			(stroke
				(width 0.1)
				(type default)
			)
			(layer "F.Fab")
		)
		(fp_line
			(start 0.12065 -0.3048)
			(end 0.67945 -0.3048)
			(stroke
				(width 0.1)
				(type default)
			)
			(layer "F.Fab")
		)
		(fp_line
			(start 0.12065 -0.2794)
			(end 0.12065 -0.3048)
			(stroke
				(width 0.1)
				(type default)
			)
			(layer "F.Fab")
		)
		(fp_line
			(start 0.67945 -0.3048)
			(end 0.67945 0.3048)
			(stroke
				(width 0.1)
				(type default)
			)
			(layer "F.Fab")
		)
		(fp_line
			(start 0.67945 0.3048)
			(end 0.120396 0.3048)
			(stroke
				(width 0.1)
				(type default)
			)
			(layer "F.Fab")
		)
		(pad "1" smd circle
			(at -0.40005 0)
			(size 0 0)
			(layers "F.Cu" "F.Mask" "F.Paste")
			(net "GND")
		)
		(pad "2" smd circle
			(at 0.40005 0)
			(size 0 0)
			(layers "F.Cu" "F.Mask" "F.Paste")
			(net "AGND_HSC")
		)
	)
	(footprint ""
		(layer "F.Cu")
		(at 275.773134 -17.678908 180)
		(property "Reference" "C1822"
			(at 0 0 180)
			(layer "F.SilkS")
			(hide yes)
			(effects
				(font
					(size 1.27 1.27)
				)
			)
		)
		(property "Value" ""
			(at 0 0 180)
			(layer "F.Fab")
			(effects
				(font
					(size 1.27 1.27)
				)
			)
		)
		(duplicate_pad_numbers_are_jumpers no)
		(fp_line
			(start 0.7874 0.4064)
			(end -0.7874 0.4064)
			(stroke
				(width 0.1524)
				(type default)
			)
			(layer "F.SilkS")
		)
		(fp_line
			(start 0.7874 -0.4064)
			(end 0.7874 0.4064)
			(stroke
				(width 0.1524)
				(type default)
			)
			(layer "F.SilkS")
		)
		(fp_line
			(start -0.7874 0.4064)
			(end -0.7874 -0.4064)
			(stroke
				(width 0.1524)
				(type default)
			)
			(layer "F.SilkS")
		)
		(fp_line
			(start -0.7874 -0.4064)
			(end 0.7874 -0.4064)
			(stroke
				(width 0.1524)
				(type default)
			)
			(layer "F.SilkS")
		)
		(fp_line
			(start 0.67945 0.3048)
			(end 0.120396 0.3048)
			(stroke
				(width 0.1)
				(type default)
			)
			(layer "F.Fab")
		)
		(fp_line
			(start 0.67945 -0.3048)
			(end 0.67945 0.3048)
			(stroke
				(width 0.1)
				(type default)
			)
			(layer "F.Fab")
		)
		(fp_line
			(start 0.12065 -0.2794)
			(end 0.12065 -0.3048)
			(stroke
				(width 0.1)
				(type default)
			)
			(layer "F.Fab")
		)
		(fp_line
			(start 0.12065 -0.3048)
			(end 0.67945 -0.3048)
			(stroke
				(width 0.1)
				(type default)
			)
			(layer "F.Fab")
		)
		(fp_line
			(start 0.120396 0.3048)
			(end 0.120396 0.2794)
			(stroke
				(width 0.1)
				(type default)
			)
			(layer "F.Fab")
		)
		(fp_line
			(start 0.120396 0.2794)
			(end -0.12065 0.2794)
			(stroke
				(width 0.1)
				(type default)
			)
			(layer "F.Fab")
		)
		(fp_line
			(start -0.12065 0.3048)
			(end -0.67945 0.3048)
			(stroke
				(width 0.1)
				(type default)
			)
			(layer "F.Fab")
		)
		(fp_line
			(start -0.12065 0.2794)
			(end -0.12065 0.3048)
			(stroke
				(width 0.1)
				(type default)
			)
			(layer "F.Fab")
		)
		(fp_line
			(start -0.12065 -0.2794)
			(end 0.12065 -0.2794)
			(stroke
				(width 0.1)
				(type default)
			)
			(layer "F.Fab")
		)
		(fp_line
			(start -0.12065 -0.305054)
			(end -0.12065 -0.2794)
			(stroke
				(width 0.1)
				(type default)
			)
			(layer "F.Fab")
		)
		(fp_line
			(start -0.67945 0.3048)
			(end -0.67945 -0.305054)
			(stroke
				(width 0.1)
				(type default)
			)
			(layer "F.Fab")
		)
		(fp_line
			(start -0.67945 -0.305054)
			(end -0.12065 -0.305054)
			(stroke
				(width 0.1)
				(type default)
			)
			(layer "F.Fab")
		)
		(pad "1" smd circle
			(at -0.40005 0 180)
			(size 0 0)
			(layers "F.Cu" "F.Mask" "F.Paste")
			(net "P3V3_AUX")
		)
		(pad "2" smd circle
			(at 0.40005 0 180)
			(size 0 0)
			(layers "F.Cu" "F.Mask" "F.Paste")
			(net "GND")
		)
	)
	(footprint ""
		(layer "F.Cu")
		(at 461.463136 -385.742434 90)
		(property "Reference" "PC1898"
			(at 0 0 90)
			(layer "F.SilkS")
			(hide yes)
			(effects
				(font
					(size 1.27 1.27)
				)
			)
		)
		(property "Value" ""
			(at 0 0 90)
			(layer "F.Fab")
			(effects
				(font
					(size 1.27 1.27)
				)
			)
		)
		(duplicate_pad_numbers_are_jumpers no)
		(fp_line
			(start 1.524 -0.762)
			(end 1.524 0.762)
			(stroke
				(width 0.1524)
				(type default)
			)
			(layer "F.SilkS")
		)
		(fp_line
			(start -1.524 -0.762)
			(end 1.524 -0.762)
			(stroke
				(width 0.1524)
				(type default)
			)
			(layer "F.SilkS")
		)
		(fp_line
			(start 1.524 0.762)
			(end -1.524 0.762)
			(stroke
				(width 0.1524)
				(type default)
			)
			(layer "F.SilkS")
		)
		(fp_line
			(start -1.524 0.762)
			(end -1.524 -0.762)
			(stroke
				(width 0.1524)
				(type default)
			)
			(layer "F.SilkS")
		)
		(fp_line
			(start 1.1049 -0.724916)
			(end -1.1049 -0.724916)
			(stroke
				(width 0.1)
				(type default)
			)
			(layer "F.Fab")
		)
		(fp_line
			(start -1.1049 -0.724916)
			(end -1.1049 0.724916)
			(stroke
				(width 0.1)
				(type default)
			)
			(layer "F.Fab")
		)
		(fp_line
			(start 1.1049 0.724916)
			(end 1.1049 -0.724916)
			(stroke
				(width 0.1)
				(type default)
			)
			(layer "F.Fab")
		)
		(fp_line
			(start -1.1049 0.724916)
			(end 1.1049 0.724916)
			(stroke
				(width 0.1)
				(type default)
			)
			(layer "F.Fab")
		)
		(pad "1" smd rect
			(at -0.889 0 270)
			(size 1.016 1.27)
			(layers "F.Cu" "F.Mask" "F.Paste")
			(net "SW_P5V_AUX_FLT")
		)
		(pad "2" smd rect
			(at 0.889 0 270)
			(size 1.016 1.27)
			(layers "F.Cu" "F.Mask" "F.Paste")
			(net "GND")
		)
	)
	(footprint ""
		(layer "F.Cu")
		(at 305.629818 -420.23919 90)
		(property "Reference" "R4268"
			(at 0 0 90)
			(layer "F.SilkS")
			(hide yes)
			(effects
				(font
					(size 1.27 1.27)
				)
			)
		)
		(property "Value" ""
			(at 0 0 90)
			(layer "F.Fab")
			(effects
				(font
					(size 1.27 1.27)
				)
			)
		)
		(duplicate_pad_numbers_are_jumpers no)
		(fp_line
			(start 0.7874 -0.4064)
			(end 0.7874 0.4064)
			(stroke
				(width 0.1524)
				(type default)
			)
			(layer "F.SilkS")
		)
		(fp_line
			(start -0.7874 -0.4064)
			(end 0.7874 -0.4064)
			(stroke
				(width 0.1524)
				(type default)
			)
			(layer "F.SilkS")
		)
		(fp_line
			(start 0.7874 0.4064)
			(end -0.7874 0.4064)
			(stroke
				(width 0.1524)
				(type default)
			)
			(layer "F.SilkS")
		)
		(fp_line
			(start -0.7874 0.4064)
			(end -0.7874 -0.4064)
			(stroke
				(width 0.1524)
				(type default)
			)
			(layer "F.SilkS")
		)
		(fp_line
			(start -0.12065 -0.305054)
			(end -0.12065 -0.2794)
			(stroke
				(width 0.1)
				(type default)
			)
			(layer "F.Fab")
		)
		(fp_line
			(start -0.67945 -0.305054)
			(end -0.12065 -0.305054)
			(stroke
				(width 0.1)
				(type default)
			)
			(layer "F.Fab")
		)
		(fp_line
			(start 0.67945 -0.3048)
			(end 0.67945 0.3048)
			(stroke
				(width 0.1)
				(type default)
			)
			(layer "F.Fab")
		)
		(fp_line
			(start 0.12065 -0.3048)
			(end 0.67945 -0.3048)
			(stroke
				(width 0.1)
				(type default)
			)
			(layer "F.Fab")
		)
		(fp_line
			(start 0.12065 -0.2794)
			(end 0.12065 -0.3048)
			(stroke
				(width 0.1)
				(type default)
			)
			(layer "F.Fab")
		)
		(fp_line
			(start -0.12065 -0.2794)
			(end 0.12065 -0.2794)
			(stroke
				(width 0.1)
				(type default)
			)
			(layer "F.Fab")
		)
		(fp_line
			(start 0.120396 0.2794)
			(end -0.12065 0.2794)
			(stroke
				(width 0.1)
				(type default)
			)
			(layer "F.Fab")
		)
		(fp_line
			(start -0.12065 0.2794)
			(end -0.12065 0.3048)
			(stroke
				(width 0.1)
				(type default)
			)
			(layer "F.Fab")
		)
		(fp_line
			(start 0.67945 0.3048)
			(end 0.120396 0.3048)
			(stroke
				(width 0.1)
				(type default)
			)
			(layer "F.Fab")
		)
		(fp_line
			(start 0.120396 0.3048)
			(end 0.120396 0.2794)
			(stroke
				(width 0.1)
				(type default)
			)
			(layer "F.Fab")
		)
		(fp_line
			(start -0.12065 0.3048)
			(end -0.67945 0.3048)
			(stroke
				(width 0.1)
				(type default)
			)
			(layer "F.Fab")
		)
		(fp_line
			(start -0.67945 0.3048)
			(end -0.67945 -0.305054)
			(stroke
				(width 0.1)
				(type default)
			)
			(layer "F.Fab")
		)
		(pad "1" smd circle
			(at -0.40005 0 90)
			(size 0 0)
			(layers "F.Cu" "F.Mask" "F.Paste")
			(net "PWRGD_P3V3_AUX_PDB")
		)
		(pad "2" smd circle
			(at 0.40005 0 90)
			(size 0 0)
			(layers "F.Cu" "F.Mask" "F.Paste")
			(net "PWRGD_P3V3_AUX_PDB_R")
		)
	)
	(footprint ""
		(layer "F.Cu")
		(at 31.962852 -407.509218 180)
		(property "Reference" "R3432"
			(at 0 0 180)
			(layer "F.SilkS")
			(hide yes)
			(effects
				(font
					(size 1.27 1.27)
				)
			)
		)
		(property "Value" ""
			(at 0 0 180)
			(layer "F.Fab")
			(effects
				(font
					(size 1.27 1.27)
				)
			)
		)
		(duplicate_pad_numbers_are_jumpers no)
		(fp_line
			(start 0.7874 0.4064)
			(end -0.7874 0.4064)
			(stroke
				(width 0.1524)
				(type default)
			)
			(layer "F.SilkS")
		)
		(fp_line
			(start 0.7874 -0.4064)
			(end 0.7874 0.4064)
			(stroke
				(width 0.1524)
				(type default)
			)
			(layer "F.SilkS")
		)
		(fp_line
			(start -0.7874 0.4064)
			(end -0.7874 -0.4064)
			(stroke
				(width 0.1524)
				(type default)
			)
			(layer "F.SilkS")
		)
		(fp_line
			(start -0.7874 -0.4064)
			(end 0.7874 -0.4064)
			(stroke
				(width 0.1524)
				(type default)
			)
			(layer "F.SilkS")
		)
		(fp_line
			(start 0.67945 0.3048)
			(end 0.120396 0.3048)
			(stroke
				(width 0.1)
				(type default)
			)
			(layer "F.Fab")
		)
		(fp_line
			(start 0.67945 -0.3048)
			(end 0.67945 0.3048)
			(stroke
				(width 0.1)
				(type default)
			)
			(layer "F.Fab")
		)
		(fp_line
			(start 0.12065 -0.2794)
			(end 0.12065 -0.3048)
			(stroke
				(width 0.1)
				(type default)
			)
			(layer "F.Fab")
		)
		(fp_line
			(start 0.12065 -0.3048)
			(end 0.67945 -0.3048)
			(stroke
				(width 0.1)
				(type default)
			)
			(layer "F.Fab")
		)
		(fp_line
			(start 0.120396 0.3048)
			(end 0.120396 0.2794)
			(stroke
				(width 0.1)
				(type default)
			)
			(layer "F.Fab")
		)
		(fp_line
			(start 0.120396 0.2794)
			(end -0.12065 0.2794)
			(stroke
				(width 0.1)
				(type default)
			)
			(layer "F.Fab")
		)
		(fp_line
			(start -0.12065 0.3048)
			(end -0.67945 0.3048)
			(stroke
				(width 0.1)
				(type default)
			)
			(layer "F.Fab")
		)
		(fp_line
			(start -0.12065 0.2794)
			(end -0.12065 0.3048)
			(stroke
				(width 0.1)
				(type default)
			)
			(layer "F.Fab")
		)
		(fp_line
			(start -0.12065 -0.2794)
			(end 0.12065 -0.2794)
			(stroke
				(width 0.1)
				(type default)
			)
			(layer "F.Fab")
		)
		(fp_line
			(start -0.12065 -0.305054)
			(end -0.12065 -0.2794)
			(stroke
				(width 0.1)
				(type default)
			)
			(layer "F.Fab")
		)
		(fp_line
			(start -0.67945 0.3048)
			(end -0.67945 -0.305054)
			(stroke
				(width 0.1)
				(type default)
			)
			(layer "F.Fab")
		)
		(fp_line
			(start -0.67945 -0.305054)
			(end -0.12065 -0.305054)
			(stroke
				(width 0.1)
				(type default)
			)
			(layer "F.Fab")
		)
		(pad "1" smd circle
			(at -0.40005 0 180)
			(size 0 0)
			(layers "F.Cu" "F.Mask" "F.Paste")
			(net "P3V3_AUX")
		)
		(pad "2" smd circle
			(at 0.40005 0 180)
			(size 0 0)
			(layers "F.Cu" "F.Mask" "F.Paste")
			(net "GPU_FPGA_THERM_OVERT")
		)
	)
	(footprint ""
		(layer "F.Cu")
		(at 250.65482 -4.699 180)
		(property "Reference" "J67"
			(at -4.38785 -1.016 90)
			(unlocked yes)
			(layer "F.SilkS")
			(effects
				(font
					(size 0.7874 0.5842)
					(thickness 0.1524)
				)
				(justify left)
			)
		)
		(property "Value" ""
			(at 0 0 180)
			(layer "F.Fab")
			(effects
				(font
					(size 1.27 1.27)
				)
			)
		)
		(duplicate_pad_numbers_are_jumpers no)
		(fp_line
			(start 1.2192 2.1082)
			(end -1.2192 2.1082)
			(stroke
				(width 0.1524)
				(type default)
			)
			(layer "F.SilkS")
		)
		(fp_line
			(start 1.2192 -2.1082)
			(end 1.2192 2.1082)
			(stroke
				(width 0.1524)
				(type default)
			)
			(layer "F.SilkS")
		)
		(fp_line
			(start -1.2192 2.1082)
			(end -1.2192 -2.1082)
			(stroke
				(width 0.1524)
				(type default)
			)
			(layer "F.SilkS")
		)
		(fp_line
			(start -1.2192 -2.1082)
			(end 1.2192 -2.1082)
			(stroke
				(width 0.1524)
				(type default)
			)
			(layer "F.SilkS")
		)
		(pad "" np_thru_hole circle
			(at -2.8829 -1.27 90)
			(size 1.0414 1.0414)
			(drill 1.0414)
			(layers "*.Cu" "*.Mask")
			(clearance 0.381)
			(thermal_gap 0.381)
		)
		(pad "" np_thru_hole circle
			(at -2.8829 1.27 90)
			(size 1.0414 1.0414)
			(drill 1.0414)
			(layers "*.Cu" "*.Mask")
			(clearance 0.381)
			(thermal_gap 0.381)
		)
		(pad "" np_thru_hole circle
			(at 3.4671 -1.27 90)
			(size 1.0414 1.0414)
			(drill 1.0414)
			(layers "*.Cu" "*.Mask")
			(clearance 0.381)
			(thermal_gap 0.381)
		)
		(pad "" np_thru_hole circle
			(at 3.4671 1.27 90)
			(size 1.0414 1.0414)
			(drill 1.0414)
			(layers "*.Cu" "*.Mask")
			(clearance 0.381)
			(thermal_gap 0.381)
		)
		(pad "1" smd rect
			(at 0.8255 -0.249936 90)
			(size 0.3048 0.508)
			(layers "F.Cu" "F.Mask" "F.Paste")
			(net "DELTA_L_85_5INCH_IN3_DP")
		)
		(pad "2" smd rect
			(at 0.8255 0.249936 90)
			(size 0.3048 0.508)
			(layers "F.Cu" "F.Mask" "F.Paste")
			(net "DELTA_L_85_5INCH_IN3_DN")
		)
		(pad "3" smd circle
			(at 0 0 180)
			(size 0 0)
			(layers "F.Cu" "F.Mask" "F.Paste")
			(net "DELTA_L_GND_1")
		)
		(zone
			(layer "F.Cu")
			(hatch none 0.5)
			(connect_pads
				(clearance 0)
			)
			(min_thickness 0.25)
			(keepout
				(tracks not_allowed)
				(vias allowed)
				(pads allowed)
				(copperpour not_allowed)
				(footprints allowed)
			)
			(placement
				(enabled no)
				(sheetname "")
			)
			(fill
				(thermal_gap 0.5)
				(thermal_bridge_width 0.5)
				(island_removal_mode 0)
			)
			(polygon
				(pts
					(xy 249.53722 -4.15036) (xy 249.53722 -4.245864) (xy 250.13412 -4.245864) (xy 250.13412 -4.652264)
					(xy 249.53722 -4.652264) (xy 249.53722 -4.745736) (xy 250.13412 -4.745736) (xy 250.13412 -5.152136)
					(xy 249.53722 -5.152136) (xy 249.53722 -5.24764) (xy 250.23572 -5.24764) (xy 250.23572 -4.15036)
				)
			)
		)
		(zone
			(layers "F.Cu" "B.Cu" "In1.Cu" "In2.Cu" "In3.Cu" "In4.Cu" "In5.Cu" "In6.Cu"
				"In7.Cu" "In8.Cu" "In9.Cu" "In10.Cu" "In11.Cu" "In12.Cu" "In13.Cu" "In14.Cu"
				"In15.Cu" "In16.Cu"
			)
			(hatch none 0.5)
			(connect_pads
				(clearance 0)
			)
			(min_thickness 0.25)
			(keepout
				(tracks not_allowed)
				(vias allowed)
				(pads allowed)
				(copperpour not_allowed)
				(footprints allowed)
			)
			(placement
				(enabled no)
				(sheetname "")
			)
			(fill
				(thermal_gap 0.5)
				(thermal_bridge_width 0.5)
				(island_removal_mode 0)
			)
			(polygon
				(pts
					(arc
						(start 248.11482 -5.969)
						(mid 246.26062 -5.969)
						(end 248.11482 -5.969)
					)
				)
			)
		)
		(zone
			(layers "F.Cu" "B.Cu" "In1.Cu" "In2.Cu" "In3.Cu" "In4.Cu" "In5.Cu" "In6.Cu"
				"In7.Cu" "In8.Cu" "In9.Cu" "In10.Cu" "In11.Cu" "In12.Cu" "In13.Cu" "In14.Cu"
				"In15.Cu" "In16.Cu"
			)
			(hatch none 0.5)
			(connect_pads
				(clearance 0)
			)
			(min_thickness 0.25)
			(keepout
				(tracks not_allowed)
				(vias allowed)
				(pads allowed)
				(copperpour not_allowed)
				(footprints allowed)
			)
			(placement
				(enabled no)
				(sheetname "")
			)
			(fill
				(thermal_gap 0.5)
				(thermal_bridge_width 0.5)
				(island_removal_mode 0)
			)
			(polygon
				(pts
					(arc
						(start 248.11482 -3.429)
						(mid 246.26062 -3.429)
						(end 248.11482 -3.429)
					)
				)
			)
		)
		(zone
			(layers "F.Cu" "B.Cu" "In1.Cu" "In2.Cu" "In3.Cu" "In4.Cu" "In5.Cu" "In6.Cu"
				"In7.Cu" "In8.Cu" "In9.Cu" "In10.Cu" "In11.Cu" "In12.Cu" "In13.Cu" "In14.Cu"
				"In15.Cu" "In16.Cu"
			)
			(hatch none 0.5)
			(connect_pads
				(clearance 0)
			)
			(min_thickness 0.25)
			(keepout
				(tracks not_allowed)
				(vias allowed)
				(pads allowed)
				(copperpour not_allowed)
				(footprints allowed)
			)
			(placement
				(enabled no)
				(sheetname "")
			)
			(fill
				(thermal_gap 0.5)
				(thermal_bridge_width 0.5)
				(island_removal_mode 0)
			)
			(polygon
				(pts
					(arc
						(start 254.46482 -5.969)
						(mid 252.61062 -5.969)
						(end 254.46482 -5.969)
					)
				)
			)
		)
		(zone
			(layers "F.Cu" "B.Cu" "In1.Cu" "In2.Cu" "In3.Cu" "In4.Cu" "In5.Cu" "In6.Cu"
				"In7.Cu" "In8.Cu" "In9.Cu" "In10.Cu" "In11.Cu" "In12.Cu" "In13.Cu" "In14.Cu"
				"In15.Cu" "In16.Cu"
			)
			(hatch none 0.5)
			(connect_pads
				(clearance 0)
			)
			(min_thickness 0.25)
			(keepout
				(tracks not_allowed)
				(vias allowed)
				(pads allowed)
				(copperpour not_allowed)
				(footprints allowed)
			)
			(placement
				(enabled no)
				(sheetname "")
			)
			(fill
				(thermal_gap 0.5)
				(thermal_bridge_width 0.5)
				(island_removal_mode 0)
			)
			(polygon
				(pts
					(arc
						(start 254.46482 -3.429)
						(mid 252.61062 -3.429)
						(end 254.46482 -3.429)
					)
				)
			)
		)
	)
	(footprint ""
		(layer "F.Cu")
		(at 381.50165 -402.371052 -90)
		(property "Reference" "C940"
			(at 0 0 270)
			(layer "F.SilkS")
			(hide yes)
			(effects
				(font
					(size 1.27 1.27)
				)
			)
		)
		(property "Value" ""
			(at 0 0 270)
			(layer "F.Fab")
			(effects
				(font
					(size 1.27 1.27)
				)
			)
		)
		(duplicate_pad_numbers_are_jumpers no)
		(fp_line
			(start -0.299974 0.150114)
			(end -0.299974 -0.150114)
			(stroke
				(width 0.1)
				(type default)
			)
			(layer "F.Fab")
		)
		(fp_line
			(start 0.299974 0.150114)
			(end -0.299974 0.150114)
			(stroke
				(width 0.1)
				(type default)
			)
			(layer "F.Fab")
		)
		(fp_line
			(start -0.299974 -0.150114)
			(end 0.299974 -0.150114)
			(stroke
				(width 0.1)
				(type default)
			)
			(layer "F.Fab")
		)
		(fp_line
			(start 0.299974 -0.150114)
			(end 0.299974 0.150114)
			(stroke
				(width 0.1)
				(type default)
			)
			(layer "F.Fab")
		)
		(pad "1" smd rect
			(at -0.2667 0 270)
			(size 0.3048 0.381)
			(layers "F.Cu" "F.Mask" "F.Paste")
			(net "P5E_CPU0_PE2_TX_C_DN<12>")
		)
		(pad "2" smd rect
			(at 0.2667 0 270)
			(size 0.3048 0.381)
			(layers "F.Cu" "F.Mask" "F.Paste")
			(net "P5E_CPU0_PE2_TX_DN<12>")
		)
	)
	(footprint ""
		(layer "F.Cu")
		(at 180.4924 -94.338648 90)
		(property "Reference" "R4596"
			(at 0 0 90)
			(layer "F.SilkS")
			(hide yes)
			(effects
				(font
					(size 1.27 1.27)
				)
			)
		)
		(property "Value" ""
			(at 0 0 90)
			(layer "F.Fab")
			(effects
				(font
					(size 1.27 1.27)
				)
			)
		)
		(duplicate_pad_numbers_are_jumpers no)
		(fp_line
			(start 0.7874 -0.4064)
			(end 0.7874 0.4064)
			(stroke
				(width 0.1524)
				(type default)
			)
			(layer "F.SilkS")
		)
		(fp_line
			(start -0.7874 -0.4064)
			(end 0.7874 -0.4064)
			(stroke
				(width 0.1524)
				(type default)
			)
			(layer "F.SilkS")
		)
		(fp_line
			(start 0.7874 0.4064)
			(end -0.7874 0.4064)
			(stroke
				(width 0.1524)
				(type default)
			)
			(layer "F.SilkS")
		)
		(fp_line
			(start -0.7874 0.4064)
			(end -0.7874 -0.4064)
			(stroke
				(width 0.1524)
				(type default)
			)
			(layer "F.SilkS")
		)
		(fp_line
			(start -0.12065 -0.305054)
			(end -0.12065 -0.2794)
			(stroke
				(width 0.1)
				(type default)
			)
			(layer "F.Fab")
		)
		(fp_line
			(start -0.67945 -0.305054)
			(end -0.12065 -0.305054)
			(stroke
				(width 0.1)
				(type default)
			)
			(layer "F.Fab")
		)
		(fp_line
			(start 0.67945 -0.3048)
			(end 0.67945 0.3048)
			(stroke
				(width 0.1)
				(type default)
			)
			(layer "F.Fab")
		)
		(fp_line
			(start 0.12065 -0.3048)
			(end 0.67945 -0.3048)
			(stroke
				(width 0.1)
				(type default)
			)
			(layer "F.Fab")
		)
		(fp_line
			(start 0.12065 -0.2794)
			(end 0.12065 -0.3048)
			(stroke
				(width 0.1)
				(type default)
			)
			(layer "F.Fab")
		)
		(fp_line
			(start -0.12065 -0.2794)
			(end 0.12065 -0.2794)
			(stroke
				(width 0.1)
				(type default)
			)
			(layer "F.Fab")
		)
		(fp_line
			(start 0.120396 0.2794)
			(end -0.12065 0.2794)
			(stroke
				(width 0.1)
				(type default)
			)
			(layer "F.Fab")
		)
		(fp_line
			(start -0.12065 0.2794)
			(end -0.12065 0.3048)
			(stroke
				(width 0.1)
				(type default)
			)
			(layer "F.Fab")
		)
		(fp_line
			(start 0.67945 0.3048)
			(end 0.120396 0.3048)
			(stroke
				(width 0.1)
				(type default)
			)
			(layer "F.Fab")
		)
		(fp_line
			(start 0.120396 0.3048)
			(end 0.120396 0.2794)
			(stroke
				(width 0.1)
				(type default)
			)
			(layer "F.Fab")
		)
		(fp_line
			(start -0.12065 0.3048)
			(end -0.67945 0.3048)
			(stroke
				(width 0.1)
				(type default)
			)
			(layer "F.Fab")
		)
		(fp_line
			(start -0.67945 0.3048)
			(end -0.67945 -0.305054)
			(stroke
				(width 0.1)
				(type default)
			)
			(layer "F.Fab")
		)
		(pad "1" smd rect
			(at -0.40005 0 270)
			(size 0.4572 0.508)
			(layers "F.Cu" "F.Mask" "F.Paste")
			(net "FAB_BMC_REV_ID0")
		)
		(pad "2" smd rect
			(at 0.40005 0 270)
			(size 0.4572 0.508)
			(layers "F.Cu" "F.Mask" "F.Paste")
			(net "GND")
		)
	)
	(footprint ""
		(layer "F.Cu")
		(at 352.289618 -244.03177 90)
		(property "Reference" "C995"
			(at 0 0 90)
			(layer "F.SilkS")
			(hide yes)
			(effects
				(font
					(size 1.27 1.27)
				)
			)
		)
		(property "Value" ""
			(at 0 0 90)
			(layer "F.Fab")
			(effects
				(font
					(size 1.27 1.27)
				)
			)
		)
		(duplicate_pad_numbers_are_jumpers no)
		(fp_line
			(start 0.7874 -0.4064)
			(end 0.7874 0.4064)
			(stroke
				(width 0.1524)
				(type default)
			)
			(layer "F.SilkS")
		)
		(fp_line
			(start -0.7874 -0.4064)
			(end 0.7874 -0.4064)
			(stroke
				(width 0.1524)
				(type default)
			)
			(layer "F.SilkS")
		)
		(fp_line
			(start 0.7874 0.4064)
			(end -0.7874 0.4064)
			(stroke
				(width 0.1524)
				(type default)
			)
			(layer "F.SilkS")
		)
		(fp_line
			(start -0.7874 0.4064)
			(end -0.7874 -0.4064)
			(stroke
				(width 0.1524)
				(type default)
			)
			(layer "F.SilkS")
		)
		(fp_line
			(start -0.12065 -0.305054)
			(end -0.12065 -0.2794)
			(stroke
				(width 0.1)
				(type default)
			)
			(layer "F.Fab")
		)
		(fp_line
			(start -0.67945 -0.305054)
			(end -0.12065 -0.305054)
			(stroke
				(width 0.1)
				(type default)
			)
			(layer "F.Fab")
		)
		(fp_line
			(start 0.67945 -0.3048)
			(end 0.67945 0.3048)
			(stroke
				(width 0.1)
				(type default)
			)
			(layer "F.Fab")
		)
		(fp_line
			(start 0.12065 -0.3048)
			(end 0.67945 -0.3048)
			(stroke
				(width 0.1)
				(type default)
			)
			(layer "F.Fab")
		)
		(fp_line
			(start 0.12065 -0.2794)
			(end 0.12065 -0.3048)
			(stroke
				(width 0.1)
				(type default)
			)
			(layer "F.Fab")
		)
		(fp_line
			(start -0.12065 -0.2794)
			(end 0.12065 -0.2794)
			(stroke
				(width 0.1)
				(type default)
			)
			(layer "F.Fab")
		)
		(fp_line
			(start 0.120396 0.2794)
			(end -0.12065 0.2794)
			(stroke
				(width 0.1)
				(type default)
			)
			(layer "F.Fab")
		)
		(fp_line
			(start -0.12065 0.2794)
			(end -0.12065 0.3048)
			(stroke
				(width 0.1)
				(type default)
			)
			(layer "F.Fab")
		)
		(fp_line
			(start 0.67945 0.3048)
			(end 0.120396 0.3048)
			(stroke
				(width 0.1)
				(type default)
			)
			(layer "F.Fab")
		)
		(fp_line
			(start 0.120396 0.3048)
			(end 0.120396 0.2794)
			(stroke
				(width 0.1)
				(type default)
			)
			(layer "F.Fab")
		)
		(fp_line
			(start -0.12065 0.3048)
			(end -0.67945 0.3048)
			(stroke
				(width 0.1)
				(type default)
			)
			(layer "F.Fab")
		)
		(fp_line
			(start -0.67945 0.3048)
			(end -0.67945 -0.305054)
			(stroke
				(width 0.1)
				(type default)
			)
			(layer "F.Fab")
		)
		(pad "1" smd circle
			(at -0.40005 0 90)
			(size 0 0)
			(layers "F.Cu" "F.Mask" "F.Paste")
			(net "PVCCIN_CPU0")
		)
		(pad "2" smd circle
			(at 0.40005 0 90)
			(size 0 0)
			(layers "F.Cu" "F.Mask" "F.Paste")
			(net "GND")
		)
	)
	(footprint ""
		(layer "F.Cu")
		(at 63.11011 -152.052528 180)
		(property "Reference" "PR4247"
			(at 0 0 180)
			(layer "F.SilkS")
			(hide yes)
			(effects
				(font
					(size 1.27 1.27)
				)
			)
		)
		(property "Value" ""
			(at 0 0 180)
			(layer "F.Fab")
			(effects
				(font
					(size 1.27 1.27)
				)
			)
		)
		(duplicate_pad_numbers_are_jumpers no)
		(fp_line
			(start 0.7874 0.4064)
			(end -0.7874 0.4064)
			(stroke
				(width 0.1524)
				(type default)
			)
			(layer "F.SilkS")
		)
		(fp_line
			(start 0.7874 -0.4064)
			(end 0.7874 0.4064)
			(stroke
				(width 0.1524)
				(type default)
			)
			(layer "F.SilkS")
		)
		(fp_line
			(start -0.7874 0.4064)
			(end -0.7874 -0.4064)
			(stroke
				(width 0.1524)
				(type default)
			)
			(layer "F.SilkS")
		)
		(fp_line
			(start -0.7874 -0.4064)
			(end 0.7874 -0.4064)
			(stroke
				(width 0.1524)
				(type default)
			)
			(layer "F.SilkS")
		)
		(fp_line
			(start 0.67945 0.3048)
			(end 0.120396 0.3048)
			(stroke
				(width 0.1)
				(type default)
			)
			(layer "F.Fab")
		)
		(fp_line
			(start 0.67945 -0.3048)
			(end 0.67945 0.3048)
			(stroke
				(width 0.1)
				(type default)
			)
			(layer "F.Fab")
		)
		(fp_line
			(start 0.12065 -0.2794)
			(end 0.12065 -0.3048)
			(stroke
				(width 0.1)
				(type default)
			)
			(layer "F.Fab")
		)
		(fp_line
			(start 0.12065 -0.3048)
			(end 0.67945 -0.3048)
			(stroke
				(width 0.1)
				(type default)
			)
			(layer "F.Fab")
		)
		(fp_line
			(start 0.120396 0.3048)
			(end 0.120396 0.2794)
			(stroke
				(width 0.1)
				(type default)
			)
			(layer "F.Fab")
		)
		(fp_line
			(start 0.120396 0.2794)
			(end -0.12065 0.2794)
			(stroke
				(width 0.1)
				(type default)
			)
			(layer "F.Fab")
		)
		(fp_line
			(start -0.12065 0.3048)
			(end -0.67945 0.3048)
			(stroke
				(width 0.1)
				(type default)
			)
			(layer "F.Fab")
		)
		(fp_line
			(start -0.12065 0.2794)
			(end -0.12065 0.3048)
			(stroke
				(width 0.1)
				(type default)
			)
			(layer "F.Fab")
		)
		(fp_line
			(start -0.12065 -0.2794)
			(end 0.12065 -0.2794)
			(stroke
				(width 0.1)
				(type default)
			)
			(layer "F.Fab")
		)
		(fp_line
			(start -0.12065 -0.305054)
			(end -0.12065 -0.2794)
			(stroke
				(width 0.1)
				(type default)
			)
			(layer "F.Fab")
		)
		(fp_line
			(start -0.67945 0.3048)
			(end -0.67945 -0.305054)
			(stroke
				(width 0.1)
				(type default)
			)
			(layer "F.Fab")
		)
		(fp_line
			(start -0.67945 -0.305054)
			(end -0.12065 -0.305054)
			(stroke
				(width 0.1)
				(type default)
			)
			(layer "F.Fab")
		)
		(pad "1" smd circle
			(at -0.40005 0 180)
			(size 0 0)
			(layers "F.Cu" "F.Mask" "F.Paste")
			(net "PVCCINFAON_CPU1")
		)
		(pad "2" smd circle
			(at 0.40005 0 180)
			(size 0 0)
			(layers "F.Cu" "F.Mask" "F.Paste")
			(net "GND")
		)
	)
	(footprint ""
		(layer "F.Cu")
		(at 239.98809 -47.968408 180)
		(property "Reference" "R3779"
			(at 0 0 180)
			(layer "F.SilkS")
			(hide yes)
			(effects
				(font
					(size 1.27 1.27)
				)
			)
		)
		(property "Value" ""
			(at 0 0 180)
			(layer "F.Fab")
			(effects
				(font
					(size 1.27 1.27)
				)
			)
		)
		(duplicate_pad_numbers_are_jumpers no)
		(fp_line
			(start 0.7874 0.4064)
			(end -0.7874 0.4064)
			(stroke
				(width 0.1524)
				(type default)
			)
			(layer "F.SilkS")
		)
		(fp_line
			(start 0.7874 -0.4064)
			(end 0.7874 0.4064)
			(stroke
				(width 0.1524)
				(type default)
			)
			(layer "F.SilkS")
		)
		(fp_line
			(start -0.7874 0.4064)
			(end -0.7874 -0.4064)
			(stroke
				(width 0.1524)
				(type default)
			)
			(layer "F.SilkS")
		)
		(fp_line
			(start -0.7874 -0.4064)
			(end 0.7874 -0.4064)
			(stroke
				(width 0.1524)
				(type default)
			)
			(layer "F.SilkS")
		)
		(fp_line
			(start 0.67945 0.3048)
			(end 0.120396 0.3048)
			(stroke
				(width 0.1)
				(type default)
			)
			(layer "F.Fab")
		)
		(fp_line
			(start 0.67945 -0.3048)
			(end 0.67945 0.3048)
			(stroke
				(width 0.1)
				(type default)
			)
			(layer "F.Fab")
		)
		(fp_line
			(start 0.12065 -0.2794)
			(end 0.12065 -0.3048)
			(stroke
				(width 0.1)
				(type default)
			)
			(layer "F.Fab")
		)
		(fp_line
			(start 0.12065 -0.3048)
			(end 0.67945 -0.3048)
			(stroke
				(width 0.1)
				(type default)
			)
			(layer "F.Fab")
		)
		(fp_line
			(start 0.120396 0.3048)
			(end 0.120396 0.2794)
			(stroke
				(width 0.1)
				(type default)
			)
			(layer "F.Fab")
		)
		(fp_line
			(start 0.120396 0.2794)
			(end -0.12065 0.2794)
			(stroke
				(width 0.1)
				(type default)
			)
			(layer "F.Fab")
		)
		(fp_line
			(start -0.12065 0.3048)
			(end -0.67945 0.3048)
			(stroke
				(width 0.1)
				(type default)
			)
			(layer "F.Fab")
		)
		(fp_line
			(start -0.12065 0.2794)
			(end -0.12065 0.3048)
			(stroke
				(width 0.1)
				(type default)
			)
			(layer "F.Fab")
		)
		(fp_line
			(start -0.12065 -0.2794)
			(end 0.12065 -0.2794)
			(stroke
				(width 0.1)
				(type default)
			)
			(layer "F.Fab")
		)
		(fp_line
			(start -0.12065 -0.305054)
			(end -0.12065 -0.2794)
			(stroke
				(width 0.1)
				(type default)
			)
			(layer "F.Fab")
		)
		(fp_line
			(start -0.67945 0.3048)
			(end -0.67945 -0.305054)
			(stroke
				(width 0.1)
				(type default)
			)
			(layer "F.Fab")
		)
		(fp_line
			(start -0.67945 -0.305054)
			(end -0.12065 -0.305054)
			(stroke
				(width 0.1)
				(type default)
			)
			(layer "F.Fab")
		)
		(pad "1" smd circle
			(at -0.40005 0 180)
			(size 0 0)
			(layers "F.Cu" "F.Mask" "F.Paste")
			(net "RST_PCIE_PCH_DEV_PERST_E1S_R_N")
		)
		(pad "2" smd circle
			(at 0.40005 0 180)
			(size 0 0)
			(layers "F.Cu" "F.Mask" "F.Paste")
			(net "RST_PCIE_PCH_E1S_PERST_N")
		)
	)
	(footprint ""
		(layer "F.Cu")
		(at 160.83788 -116.296948)
		(property "Reference" "R1467"
			(at 0 0 0)
			(layer "F.SilkS")
			(hide yes)
			(effects
				(font
					(size 1.27 1.27)
				)
			)
		)
		(property "Value" ""
			(at 0 0 0)
			(layer "F.Fab")
			(effects
				(font
					(size 1.27 1.27)
				)
			)
		)
		(duplicate_pad_numbers_are_jumpers no)
		(fp_line
			(start -0.7874 -0.4064)
			(end 0.7874 -0.4064)
			(stroke
				(width 0.1524)
				(type default)
			)
			(layer "F.SilkS")
		)
		(fp_line
			(start -0.7874 0.4064)
			(end -0.7874 -0.4064)
			(stroke
				(width 0.1524)
				(type default)
			)
			(layer "F.SilkS")
		)
		(fp_line
			(start 0.7874 -0.4064)
			(end 0.7874 0.4064)
			(stroke
				(width 0.1524)
				(type default)
			)
			(layer "F.SilkS")
		)
		(fp_line
			(start 0.7874 0.4064)
			(end -0.7874 0.4064)
			(stroke
				(width 0.1524)
				(type default)
			)
			(layer "F.SilkS")
		)
		(fp_line
			(start -0.67945 -0.305054)
			(end -0.12065 -0.305054)
			(stroke
				(width 0.1)
				(type default)
			)
			(layer "F.Fab")
		)
		(fp_line
			(start -0.67945 0.3048)
			(end -0.67945 -0.305054)
			(stroke
				(width 0.1)
				(type default)
			)
			(layer "F.Fab")
		)
		(fp_line
			(start -0.12065 -0.305054)
			(end -0.12065 -0.2794)
			(stroke
				(width 0.1)
				(type default)
			)
			(layer "F.Fab")
		)
		(fp_line
			(start -0.12065 -0.2794)
			(end 0.12065 -0.2794)
			(stroke
				(width 0.1)
				(type default)
			)
			(layer "F.Fab")
		)
		(fp_line
			(start -0.12065 0.2794)
			(end -0.12065 0.3048)
			(stroke
				(width 0.1)
				(type default)
			)
			(layer "F.Fab")
		)
		(fp_line
			(start -0.12065 0.3048)
			(end -0.67945 0.3048)
			(stroke
				(width 0.1)
				(type default)
			)
			(layer "F.Fab")
		)
		(fp_line
			(start 0.120396 0.2794)
			(end -0.12065 0.2794)
			(stroke
				(width 0.1)
				(type default)
			)
			(layer "F.Fab")
		)
		(fp_line
			(start 0.120396 0.3048)
			(end 0.120396 0.2794)
			(stroke
				(width 0.1)
				(type default)
			)
			(layer "F.Fab")
		)
		(fp_line
			(start 0.12065 -0.3048)
			(end 0.67945 -0.3048)
			(stroke
				(width 0.1)
				(type default)
			)
			(layer "F.Fab")
		)
		(fp_line
			(start 0.12065 -0.2794)
			(end 0.12065 -0.3048)
			(stroke
				(width 0.1)
				(type default)
			)
			(layer "F.Fab")
		)
		(fp_line
			(start 0.67945 -0.3048)
			(end 0.67945 0.3048)
			(stroke
				(width 0.1)
				(type default)
			)
			(layer "F.Fab")
		)
		(fp_line
			(start 0.67945 0.3048)
			(end 0.120396 0.3048)
			(stroke
				(width 0.1)
				(type default)
			)
			(layer "F.Fab")
		)
		(pad "1" smd circle
			(at -0.40005 0)
			(size 0 0)
			(layers "F.Cu" "F.Mask" "F.Paste")
			(net "P3V3_AUX")
		)
		(pad "2" smd circle
			(at 0.40005 0)
			(size 0 0)
			(layers "F.Cu" "F.Mask" "F.Paste")
			(net "SMB_1_PLD_3V3AUX_SCL_R1")
		)
	)
	(footprint ""
		(layer "F.Cu")
		(at 115.680236 -355.985826 90)
		(property "Reference" "PJ49"
			(at -1.563878 1.821434 90)
			(unlocked yes)
			(layer "F.SilkS")
			(effects
				(font
					(size 0.7874 0.5842)
					(thickness 0.1524)
				)
				(justify left)
			)
		)
		(property "Value" ""
			(at 0 0 90)
			(layer "F.Fab")
			(effects
				(font
					(size 1.27 1.27)
				)
			)
		)
		(duplicate_pad_numbers_are_jumpers no)
		(pad "1" smd circle
			(at -0.7493 0 180)
			(size 0 0)
			(layers "F.Cu" "F.Mask" "F.Paste")
			(net "VSENSE_PVCCFA_EHV_FIVRA_CPU1_DP")
		)
		(pad "2" smd rect
			(at 0.7493 0)
			(size 0.7112 0.8128)
			(layers "F.Cu" "F.Mask" "F.Paste")
			(net "SH_PVCCFA_EHV_FIVRA_CPU1")
		)
		(zone
			(layer "F.Cu")
			(hatch none 0.5)
			(connect_pads
				(clearance 0)
			)
			(min_thickness 0.25)
			(keepout
				(tracks allowed)
				(vias not_allowed)
				(pads allowed)
				(copperpour not_allowed)
				(footprints allowed)
			)
			(placement
				(enabled no)
				(sheetname "")
			)
			(fill
				(thermal_gap 0.5)
				(thermal_bridge_width 0.5)
				(island_removal_mode 0)
			)
			(polygon
				(pts
					(xy 115.273836 -354.804726) (xy 116.091462 -354.804726) (xy 116.091462 -357.192326) (xy 115.273836 -357.192326)
				)
			)
		)
	)
	(footprint ""
		(layer "F.Cu")
		(at 48.931068 -176.180242)
		(property "Reference" "PC431"
			(at 0 0 0)
			(layer "F.SilkS")
			(hide yes)
			(effects
				(font
					(size 1.27 1.27)
				)
			)
		)
		(property "Value" ""
			(at 0 0 0)
			(layer "F.Fab")
			(effects
				(font
					(size 1.27 1.27)
				)
			)
		)
		(duplicate_pad_numbers_are_jumpers no)
		(fp_line
			(start -0.7874 -0.4064)
			(end 0.7874 -0.4064)
			(stroke
				(width 0.1524)
				(type default)
			)
			(layer "F.SilkS")
		)
		(fp_line
			(start -0.7874 0.4064)
			(end -0.7874 -0.4064)
			(stroke
				(width 0.1524)
				(type default)
			)
			(layer "F.SilkS")
		)
		(fp_line
			(start 0.7874 -0.4064)
			(end 0.7874 0.4064)
			(stroke
				(width 0.1524)
				(type default)
			)
			(layer "F.SilkS")
		)
		(fp_line
			(start 0.7874 0.4064)
			(end -0.7874 0.4064)
			(stroke
				(width 0.1524)
				(type default)
			)
			(layer "F.SilkS")
		)
		(fp_line
			(start -0.67945 -0.305054)
			(end -0.12065 -0.305054)
			(stroke
				(width 0.1)
				(type default)
			)
			(layer "F.Fab")
		)
		(fp_line
			(start -0.67945 0.3048)
			(end -0.67945 -0.305054)
			(stroke
				(width 0.1)
				(type default)
			)
			(layer "F.Fab")
		)
		(fp_line
			(start -0.12065 -0.305054)
			(end -0.12065 -0.2794)
			(stroke
				(width 0.1)
				(type default)
			)
			(layer "F.Fab")
		)
		(fp_line
			(start -0.12065 -0.2794)
			(end 0.12065 -0.2794)
			(stroke
				(width 0.1)
				(type default)
			)
			(layer "F.Fab")
		)
		(fp_line
			(start -0.12065 0.2794)
			(end -0.12065 0.3048)
			(stroke
				(width 0.1)
				(type default)
			)
			(layer "F.Fab")
		)
		(fp_line
			(start -0.12065 0.3048)
			(end -0.67945 0.3048)
			(stroke
				(width 0.1)
				(type default)
			)
			(layer "F.Fab")
		)
		(fp_line
			(start 0.120396 0.2794)
			(end -0.12065 0.2794)
			(stroke
				(width 0.1)
				(type default)
			)
			(layer "F.Fab")
		)
		(fp_line
			(start 0.120396 0.3048)
			(end 0.120396 0.2794)
			(stroke
				(width 0.1)
				(type default)
			)
			(layer "F.Fab")
		)
		(fp_line
			(start 0.12065 -0.3048)
			(end 0.67945 -0.3048)
			(stroke
				(width 0.1)
				(type default)
			)
			(layer "F.Fab")
		)
		(fp_line
			(start 0.12065 -0.2794)
			(end 0.12065 -0.3048)
			(stroke
				(width 0.1)
				(type default)
			)
			(layer "F.Fab")
		)
		(fp_line
			(start 0.67945 -0.3048)
			(end 0.67945 0.3048)
			(stroke
				(width 0.1)
				(type default)
			)
			(layer "F.Fab")
		)
		(fp_line
			(start 0.67945 0.3048)
			(end 0.120396 0.3048)
			(stroke
				(width 0.1)
				(type default)
			)
			(layer "F.Fab")
		)
		(pad "1" smd circle
			(at -0.40005 0)
			(size 0 0)
			(layers "F.Cu" "F.Mask" "F.Paste")
			(net "SW_PVCCFA_EHV_CPU1_BOOT1_R")
		)
		(pad "2" smd circle
			(at 0.40005 0)
			(size 0 0)
			(layers "F.Cu" "F.Mask" "F.Paste")
			(net "SW_PVCCFA_EHV_CPU1_BOOTR1")
		)
	)
	(footprint ""
		(layer "F.Cu")
		(at 164.52088 -43.525948)
		(property "Reference" "R487"
			(at 0 0 0)
			(layer "F.SilkS")
			(hide yes)
			(effects
				(font
					(size 1.27 1.27)
				)
			)
		)
		(property "Value" ""
			(at 0 0 0)
			(layer "F.Fab")
			(effects
				(font
					(size 1.27 1.27)
				)
			)
		)
		(duplicate_pad_numbers_are_jumpers no)
		(fp_line
			(start -0.7874 -0.4064)
			(end 0.7874 -0.4064)
			(stroke
				(width 0.1524)
				(type default)
			)
			(layer "F.SilkS")
		)
		(fp_line
			(start -0.7874 0.4064)
			(end -0.7874 -0.4064)
			(stroke
				(width 0.1524)
				(type default)
			)
			(layer "F.SilkS")
		)
		(fp_line
			(start 0.7874 -0.4064)
			(end 0.7874 0.4064)
			(stroke
				(width 0.1524)
				(type default)
			)
			(layer "F.SilkS")
		)
		(fp_line
			(start 0.7874 0.4064)
			(end -0.7874 0.4064)
			(stroke
				(width 0.1524)
				(type default)
			)
			(layer "F.SilkS")
		)
		(fp_line
			(start -0.67945 -0.305054)
			(end -0.12065 -0.305054)
			(stroke
				(width 0.1)
				(type default)
			)
			(layer "F.Fab")
		)
		(fp_line
			(start -0.67945 0.3048)
			(end -0.67945 -0.305054)
			(stroke
				(width 0.1)
				(type default)
			)
			(layer "F.Fab")
		)
		(fp_line
			(start -0.12065 -0.305054)
			(end -0.12065 -0.2794)
			(stroke
				(width 0.1)
				(type default)
			)
			(layer "F.Fab")
		)
		(fp_line
			(start -0.12065 -0.2794)
			(end 0.12065 -0.2794)
			(stroke
				(width 0.1)
				(type default)
			)
			(layer "F.Fab")
		)
		(fp_line
			(start -0.12065 0.2794)
			(end -0.12065 0.3048)
			(stroke
				(width 0.1)
				(type default)
			)
			(layer "F.Fab")
		)
		(fp_line
			(start -0.12065 0.3048)
			(end -0.67945 0.3048)
			(stroke
				(width 0.1)
				(type default)
			)
			(layer "F.Fab")
		)
		(fp_line
			(start 0.120396 0.2794)
			(end -0.12065 0.2794)
			(stroke
				(width 0.1)
				(type default)
			)
			(layer "F.Fab")
		)
		(fp_line
			(start 0.120396 0.3048)
			(end 0.120396 0.2794)
			(stroke
				(width 0.1)
				(type default)
			)
			(layer "F.Fab")
		)
		(fp_line
			(start 0.12065 -0.3048)
			(end 0.67945 -0.3048)
			(stroke
				(width 0.1)
				(type default)
			)
			(layer "F.Fab")
		)
		(fp_line
			(start 0.12065 -0.2794)
			(end 0.12065 -0.3048)
			(stroke
				(width 0.1)
				(type default)
			)
			(layer "F.Fab")
		)
		(fp_line
			(start 0.67945 -0.3048)
			(end 0.67945 0.3048)
			(stroke
				(width 0.1)
				(type default)
			)
			(layer "F.Fab")
		)
		(fp_line
			(start 0.67945 0.3048)
			(end 0.120396 0.3048)
			(stroke
				(width 0.1)
				(type default)
			)
			(layer "F.Fab")
		)
		(pad "1" smd circle
			(at -0.40005 0)
			(size 0 0)
			(layers "F.Cu" "F.Mask" "F.Paste")
			(net "P3V3_AUX")
		)
		(pad "2" smd circle
			(at 0.40005 0)
			(size 0 0)
			(layers "F.Cu" "F.Mask" "F.Paste")
			(net "M2_SSD0_CLKREQ_EN_N_BUF")
		)
	)
	(footprint ""
		(layer "F.Cu")
		(at 432.798728 -57.916826 90)
		(property "Reference" "C1339"
			(at 0 0 90)
			(layer "F.SilkS")
			(hide yes)
			(effects
				(font
					(size 1.27 1.27)
				)
			)
		)
		(property "Value" ""
			(at 0 0 90)
			(layer "F.Fab")
			(effects
				(font
					(size 1.27 1.27)
				)
			)
		)
		(duplicate_pad_numbers_are_jumpers no)
		(fp_line
			(start 0.7874 -0.4064)
			(end 0.7874 0.4064)
			(stroke
				(width 0.1524)
				(type default)
			)
			(layer "F.SilkS")
		)
		(fp_line
			(start -0.7874 -0.4064)
			(end 0.7874 -0.4064)
			(stroke
				(width 0.1524)
				(type default)
			)
			(layer "F.SilkS")
		)
		(fp_line
			(start 0.7874 0.4064)
			(end -0.7874 0.4064)
			(stroke
				(width 0.1524)
				(type default)
			)
			(layer "F.SilkS")
		)
		(fp_line
			(start -0.7874 0.4064)
			(end -0.7874 -0.4064)
			(stroke
				(width 0.1524)
				(type default)
			)
			(layer "F.SilkS")
		)
		(fp_line
			(start -0.12065 -0.305054)
			(end -0.12065 -0.2794)
			(stroke
				(width 0.1)
				(type default)
			)
			(layer "F.Fab")
		)
		(fp_line
			(start -0.67945 -0.305054)
			(end -0.12065 -0.305054)
			(stroke
				(width 0.1)
				(type default)
			)
			(layer "F.Fab")
		)
		(fp_line
			(start 0.67945 -0.3048)
			(end 0.67945 0.3048)
			(stroke
				(width 0.1)
				(type default)
			)
			(layer "F.Fab")
		)
		(fp_line
			(start 0.12065 -0.3048)
			(end 0.67945 -0.3048)
			(stroke
				(width 0.1)
				(type default)
			)
			(layer "F.Fab")
		)
		(fp_line
			(start 0.12065 -0.2794)
			(end 0.12065 -0.3048)
			(stroke
				(width 0.1)
				(type default)
			)
			(layer "F.Fab")
		)
		(fp_line
			(start -0.12065 -0.2794)
			(end 0.12065 -0.2794)
			(stroke
				(width 0.1)
				(type default)
			)
			(layer "F.Fab")
		)
		(fp_line
			(start 0.120396 0.2794)
			(end -0.12065 0.2794)
			(stroke
				(width 0.1)
				(type default)
			)
			(layer "F.Fab")
		)
		(fp_line
			(start -0.12065 0.2794)
			(end -0.12065 0.3048)
			(stroke
				(width 0.1)
				(type default)
			)
			(layer "F.Fab")
		)
		(fp_line
			(start 0.67945 0.3048)
			(end 0.120396 0.3048)
			(stroke
				(width 0.1)
				(type default)
			)
			(layer "F.Fab")
		)
		(fp_line
			(start 0.120396 0.3048)
			(end 0.120396 0.2794)
			(stroke
				(width 0.1)
				(type default)
			)
			(layer "F.Fab")
		)
		(fp_line
			(start -0.12065 0.3048)
			(end -0.67945 0.3048)
			(stroke
				(width 0.1)
				(type default)
			)
			(layer "F.Fab")
		)
		(fp_line
			(start -0.67945 0.3048)
			(end -0.67945 -0.305054)
			(stroke
				(width 0.1)
				(type default)
			)
			(layer "F.Fab")
		)
		(pad "1" smd circle
			(at -0.40005 0 90)
			(size 0 0)
			(layers "F.Cu" "F.Mask" "F.Paste")
			(net "P3V3")
		)
		(pad "2" smd circle
			(at 0.40005 0 90)
			(size 0 0)
			(layers "F.Cu" "F.Mask" "F.Paste")
			(net "GND")
		)
	)
	(footprint ""
		(layer "F.Cu")
		(at 493.36833 -303.592992 90)
		(property "Reference" "X10"
			(at -3.481832 3.05562 90)
			(unlocked yes)
			(layer "F.SilkS")
			(effects
				(font
					(size 0.7874 0.5842)
					(thickness 0.1524)
				)
				(justify left)
			)
		)
		(property "Value" ""
			(at 0 0 90)
			(layer "F.Fab")
			(effects
				(font
					(size 1.27 1.27)
				)
			)
		)
		(property "Device Type" "TP_TDR_4P_FTS_TH-TP_TDR_4P_DIPA"
			(at 1.30175 1.27 180)
			(unlocked yes)
			(layer "F.Fab")
			(hide yes)
			(effects
				(font
					(size 0.635 0.4064)
					(thickness 0.1524)
				)
			)
		)
		(property "User Part Number" "N_A"
			(at 1.30175 1.27 180)
			(unlocked yes)
			(layer "Cmts.User")
			(hide yes)
			(effects
				(font
					(size 0.635 0.4064)
					(thickness 0.1524)
				)
			)
		)
		(duplicate_pad_numbers_are_jumpers no)
		(fp_line
			(start 2.54 -1.27)
			(end 0 -1.27)
			(stroke
				(width 0.1524)
				(type default)
			)
			(layer "F.SilkS")
		)
		(fp_line
			(start 0 -1.27)
			(end 0 -0.635)
			(stroke
				(width 0.1524)
				(type default)
			)
			(layer "F.SilkS")
		)
		(fp_line
			(start 2.54 -1.1303)
			(end 2.54 -1.27)
			(stroke
				(width 0.1524)
				(type default)
			)
			(layer "F.SilkS")
		)
		(fp_line
			(start 0 0.635)
			(end 0 1.905)
			(stroke
				(width 0.1524)
				(type default)
			)
			(layer "F.SilkS")
		)
		(fp_line
			(start 2.54 1.4097)
			(end 2.54 1.1303)
			(stroke
				(width 0.1524)
				(type default)
			)
			(layer "F.SilkS")
		)
		(fp_line
			(start 0 3.175)
			(end 0 3.81)
			(stroke
				(width 0.1524)
				(type default)
			)
			(layer "F.SilkS")
		)
		(fp_line
			(start 2.54 3.81)
			(end 2.54 3.6703)
			(stroke
				(width 0.1524)
				(type default)
			)
			(layer "F.SilkS")
		)
		(fp_line
			(start 0 3.81)
			(end 2.54 3.81)
			(stroke
				(width 0.1524)
				(type default)
			)
			(layer "F.SilkS")
		)
		(fp_poly
			(pts
				(xy -0.761746 0) (xy -2.285746 0.762) (xy -2.285746 -0.762)
			)
			(stroke
				(width 0)
				(type default)
			)
			(fill yes)
			(layer "F.SilkS")
		)
		(fp_line
			(start 2.54 -1.27)
			(end 0 -1.27)
			(stroke
				(width 0.1)
				(type default)
			)
			(layer "F.Fab")
		)
		(fp_line
			(start 0 -1.27)
			(end 0 3.81)
			(stroke
				(width 0.1)
				(type default)
			)
			(layer "F.Fab")
		)
		(fp_line
			(start 2.54 3.81)
			(end 2.54 -1.27)
			(stroke
				(width 0.1)
				(type default)
			)
			(layer "F.Fab")
		)
		(fp_line
			(start 0 3.81)
			(end 2.54 3.81)
			(stroke
				(width 0.1)
				(type default)
			)
			(layer "F.Fab")
		)
		(fp_poly
			(pts
				(xy -0.761746 0) (xy -2.285746 -0.762) (xy -2.285746 0.762)
			)
			(stroke
				(width 0)
				(type default)
			)
			(fill yes)
			(layer "F.Fab")
		)
		(pad "1" thru_hole circle
			(at 0 0 90)
			(size 1.0033 1.0033)
			(drill 0.249936)
			(layers "*.Cu" "*.Mask")
			(remove_unused_layers no)
			(net "TDR_DIFF_85_IN3_DN")
			(clearance 0.10795)
			(thermal_gap 0.10795)
			(padstack
				(mode front_inner_back)
				(layer "Inner"
					(shape circle)
					(size 0.8001 0.8001)
					(clearance 0.1524)
				)
				(layer "B.Cu"
					(shape circle)
					(size 1.0033 1.0033)
					(clearance 0.10795)
				)
			)
		)
		(pad "2" thru_hole circle
			(at 2.54 0 90)
			(size 1.9939 1.9939)
			(drill 0.249936)
			(layers "*.Cu" "*.Mask")
			(remove_unused_layers no)
			(net "T1_GND")
			(clearance 0.10795)
			(thermal_gap 0.10795)
			(padstack
				(mode front_inner_back)
				(layer "Inner"
					(shape circle)
					(size 0.8001 0.8001)
					(clearance 0.1524)
				)
				(layer "B.Cu"
					(shape circle)
					(size 1.9939 1.9939)
					(clearance 0.10795)
				)
			)
		)
		(pad "3" thru_hole circle
			(at 2.54 2.54 90)
			(size 1.9939 1.9939)
			(drill 0.249936)
			(layers "*.Cu" "*.Mask")
			(remove_unused_layers no)
			(net "T1_GND")
			(clearance 0.10795)
			(thermal_gap 0.10795)
			(padstack
				(mode front_inner_back)
				(layer "Inner"
					(shape circle)
					(size 0.8001 0.8001)
					(clearance 0.1524)
				)
				(layer "B.Cu"
					(shape circle)
					(size 1.9939 1.9939)
					(clearance 0.10795)
				)
			)
		)
		(pad "4" thru_hole circle
			(at 0 2.54 90)
			(size 1.0033 1.0033)
			(drill 0.249936)
			(layers "*.Cu" "*.Mask")
			(remove_unused_layers no)
			(net "TDR_DIFF_85_IN3_DP")
			(clearance 0.10795)
			(thermal_gap 0.10795)
			(padstack
				(mode front_inner_back)
				(layer "Inner"
					(shape circle)
					(size 0.8001 0.8001)
					(clearance 0.1524)
				)
				(layer "B.Cu"
					(shape circle)
					(size 1.0033 1.0033)
					(clearance 0.10795)
				)
			)
		)
	)
	(footprint ""
		(layer "F.Cu")
		(at 10.339832 -347.699838)
		(property "Reference" "H97"
			(at -5.945632 -4.789932 0)
			(unlocked yes)
			(layer "F.SilkS")
			(effects
				(font
					(size 0.7874 0.5842)
					(thickness 0.1524)
				)
				(justify left)
			)
		)
		(property "Value" ""
			(at 0 0 0)
			(layer "F.Fab")
			(effects
				(font
					(size 1.27 1.27)
				)
			)
		)
		(duplicate_pad_numbers_are_jumpers no)
		(pad "1" thru_hole circle
			(at 0 0)
			(size 10.0076 10.0076)
			(drill 5.6134)
			(layers "*.Cu" "*.Mask")
			(remove_unused_layers no)
			(net "GND")
			(clearance -1.9431)
		)
	)
	(footprint ""
		(layer "F.Cu")
		(at 344.899488 -324.445376)
		(property "Reference" "PL114"
			(at -9.220708 5.188458 0)
			(unlocked yes)
			(layer "F.SilkS")
			(effects
				(font
					(size 0.7874 0.5842)
					(thickness 0.1524)
				)
				(justify left)
			)
		)
		(property "Value" ""
			(at 0 0 0)
			(layer "F.Fab")
			(effects
				(font
					(size 1.27 1.27)
				)
			)
		)
		(duplicate_pad_numbers_are_jumpers no)
		(fp_line
			(start -3.750056 -5.500116)
			(end -2.393442 -5.500116)
			(stroke
				(width 0.1524)
				(type default)
			)
			(layer "F.SilkS")
		)
		(fp_line
			(start -3.750056 5.500116)
			(end -3.750056 -5.500116)
			(stroke
				(width 0.1524)
				(type default)
			)
			(layer "F.SilkS")
		)
		(fp_line
			(start -2.393442 5.500116)
			(end -3.750056 5.500116)
			(stroke
				(width 0.1524)
				(type default)
			)
			(layer "F.SilkS")
		)
		(fp_line
			(start 2.393442 5.500116)
			(end 3.750056 5.500116)
			(stroke
				(width 0.1524)
				(type default)
			)
			(layer "F.SilkS")
		)
		(fp_line
			(start 3.750056 -5.500116)
			(end 2.393442 -5.500116)
			(stroke
				(width 0.1524)
				(type default)
			)
			(layer "F.SilkS")
		)
		(fp_line
			(start 3.750056 -4.576572)
			(end 3.750056 -5.500116)
			(stroke
				(width 0.1524)
				(type default)
			)
			(layer "F.SilkS")
		)
		(fp_line
			(start 3.750056 5.500116)
			(end 3.750056 -3.687572)
			(stroke
				(width 0.1524)
				(type default)
			)
			(layer "F.SilkS")
		)
		(fp_poly
			(pts
				(xy -3.280664 -7.074154) (xy -2.921508 -5.996432) (xy -3.998976 -6.355842)
			)
			(stroke
				(width 0)
				(type default)
			)
			(fill yes)
			(layer "F.SilkS")
		)
		(fp_line
			(start -3.750056 -5.500116)
			(end -3.750056 5.500116)
			(stroke
				(width 0.1)
				(type default)
			)
			(layer "F.Fab")
		)
		(fp_line
			(start -3.750056 5.500116)
			(end 3.750056 5.500116)
			(stroke
				(width 0.1)
				(type default)
			)
			(layer "F.Fab")
		)
		(fp_line
			(start 3.750056 -5.500116)
			(end -3.750056 -5.500116)
			(stroke
				(width 0.1)
				(type default)
			)
			(layer "F.Fab")
		)
		(fp_line
			(start 3.750056 5.500116)
			(end 3.750056 -5.500116)
			(stroke
				(width 0.1)
				(type default)
			)
			(layer "F.Fab")
		)
		(fp_poly
			(pts
				(xy -4.9276 -4.757928) (xy -4.9276 -3.741928) (xy -3.9116 -4.249928)
			)
			(stroke
				(width 0)
				(type default)
			)
			(fill yes)
			(layer "F.Fab")
		)
		(pad "1" smd rect
			(at 0 -4.249928 270)
			(size 2.413 4.5212)
			(layers "F.Cu" "F.Mask" "F.Paste")
			(net "SW_PVCCIN_CPU0_SW1")
		)
		(pad "2" smd rect
			(at 0 -1.175004 270)
			(size 1.3716 4.5212)
			(layers "F.Cu" "F.Mask" "F.Paste")
			(net "IND_P0_CPL1")
		)
		(pad "3" smd rect
			(at 0 1.175004 270)
			(size 1.3716 4.5212)
			(layers "F.Cu" "F.Mask" "F.Paste")
			(net "IND_P0_CPL2")
		)
		(pad "4" smd rect
			(at 0 4.249928 270)
			(size 2.413 4.5212)
			(layers "F.Cu" "F.Mask" "F.Paste")
			(net "PVCCIN_CPU0")
		)
	)
	(footprint ""
		(layer "F.Cu")
		(at 457.7461 -381.24892 -90)
		(property "Reference" "PC1853"
			(at 0 0 270)
			(layer "F.SilkS")
			(hide yes)
			(effects
				(font
					(size 1.27 1.27)
				)
			)
		)
		(property "Value" ""
			(at 0 0 270)
			(layer "F.Fab")
			(effects
				(font
					(size 1.27 1.27)
				)
			)
		)
		(duplicate_pad_numbers_are_jumpers no)
		(fp_line
			(start -0.7874 0.4064)
			(end -0.7874 -0.4064)
			(stroke
				(width 0.1524)
				(type default)
			)
			(layer "F.SilkS")
		)
		(fp_line
			(start 0.7874 0.4064)
			(end -0.7874 0.4064)
			(stroke
				(width 0.1524)
				(type default)
			)
			(layer "F.SilkS")
		)
		(fp_line
			(start -0.7874 -0.4064)
			(end 0.7874 -0.4064)
			(stroke
				(width 0.1524)
				(type default)
			)
			(layer "F.SilkS")
		)
		(fp_line
			(start 0.7874 -0.4064)
			(end 0.7874 0.4064)
			(stroke
				(width 0.1524)
				(type default)
			)
			(layer "F.SilkS")
		)
		(fp_line
			(start -0.67945 0.3048)
			(end -0.67945 -0.305054)
			(stroke
				(width 0.1)
				(type default)
			)
			(layer "F.Fab")
		)
		(fp_line
			(start -0.12065 0.3048)
			(end -0.67945 0.3048)
			(stroke
				(width 0.1)
				(type default)
			)
			(layer "F.Fab")
		)
		(fp_line
			(start 0.120396 0.3048)
			(end 0.120396 0.2794)
			(stroke
				(width 0.1)
				(type default)
			)
			(layer "F.Fab")
		)
		(fp_line
			(start 0.67945 0.3048)
			(end 0.120396 0.3048)
			(stroke
				(width 0.1)
				(type default)
			)
			(layer "F.Fab")
		)
		(fp_line
			(start -0.12065 0.2794)
			(end -0.12065 0.3048)
			(stroke
				(width 0.1)
				(type default)
			)
			(layer "F.Fab")
		)
		(fp_line
			(start 0.120396 0.2794)
			(end -0.12065 0.2794)
			(stroke
				(width 0.1)
				(type default)
			)
			(layer "F.Fab")
		)
		(fp_line
			(start -0.12065 -0.2794)
			(end 0.12065 -0.2794)
			(stroke
				(width 0.1)
				(type default)
			)
			(layer "F.Fab")
		)
		(fp_line
			(start 0.12065 -0.2794)
			(end 0.12065 -0.3048)
			(stroke
				(width 0.1)
				(type default)
			)
			(layer "F.Fab")
		)
		(fp_line
			(start 0.12065 -0.3048)
			(end 0.67945 -0.3048)
			(stroke
				(width 0.1)
				(type default)
			)
			(layer "F.Fab")
		)
		(fp_line
			(start 0.67945 -0.3048)
			(end 0.67945 0.3048)
			(stroke
				(width 0.1)
				(type default)
			)
			(layer "F.Fab")
		)
		(fp_line
			(start -0.67945 -0.305054)
			(end -0.12065 -0.305054)
			(stroke
				(width 0.1)
				(type default)
			)
			(layer "F.Fab")
		)
		(fp_line
			(start -0.12065 -0.305054)
			(end -0.12065 -0.2794)
			(stroke
				(width 0.1)
				(type default)
			)
			(layer "F.Fab")
		)
		(pad "1" smd circle
			(at -0.40005 0 270)
			(size 0 0)
			(layers "F.Cu" "F.Mask" "F.Paste")
			(net "P5V_AUX_REF")
		)
		(pad "2" smd circle
			(at 0.40005 0 270)
			(size 0 0)
			(layers "F.Cu" "F.Mask" "F.Paste")
			(net "GND")
		)
	)
	(footprint ""
		(layer "F.Cu")
		(at 391.672572 -76.460604 -90)
		(property "Reference" "PL16"
			(at 0 0 270)
			(layer "F.SilkS")
			(hide yes)
			(effects
				(font
					(size 1.27 1.27)
				)
			)
		)
		(property "Value" ""
			(at 0 0 270)
			(layer "F.Fab")
			(effects
				(font
					(size 1.27 1.27)
				)
			)
		)
		(duplicate_pad_numbers_are_jumpers no)
		(fp_line
			(start -1.27 0.5842)
			(end -1.27 -0.5842)
			(stroke
				(width 0.1524)
				(type default)
			)
			(layer "F.SilkS")
		)
		(fp_line
			(start -0.127 0.5842)
			(end -0.127 -0.5842)
			(stroke
				(width 0.1524)
				(type default)
			)
			(layer "F.SilkS")
		)
		(fp_line
			(start 0.127 0.5842)
			(end 0.127 -0.5842)
			(stroke
				(width 0.1524)
				(type default)
			)
			(layer "F.SilkS")
		)
		(fp_line
			(start 1.27 0.5842)
			(end -1.27 0.5842)
			(stroke
				(width 0.1524)
				(type default)
			)
			(layer "F.SilkS")
		)
		(fp_line
			(start 1.27 0.5842)
			(end 1.27 -0.5842)
			(stroke
				(width 0.1524)
				(type default)
			)
			(layer "F.SilkS")
		)
		(fp_line
			(start -1.27 -0.5588)
			(end -1.27 -0.5842)
			(stroke
				(width 0.1524)
				(type default)
			)
			(layer "F.SilkS")
		)
		(fp_line
			(start -1.27 -0.5842)
			(end 1.27 -0.5842)
			(stroke
				(width 0.1524)
				(type default)
			)
			(layer "F.SilkS")
		)
		(fp_line
			(start -0.9144 0.508)
			(end -0.9144 0.406654)
			(stroke
				(width 0.1)
				(type default)
			)
			(layer "F.Fab")
		)
		(fp_line
			(start 0.9144 0.508)
			(end -0.9144 0.508)
			(stroke
				(width 0.1)
				(type default)
			)
			(layer "F.Fab")
		)
		(fp_line
			(start -1.194308 0.406654)
			(end -1.194308 -0.406654)
			(stroke
				(width 0.1)
				(type default)
			)
			(layer "F.Fab")
		)
		(fp_line
			(start -0.9144 0.406654)
			(end -1.194308 0.406654)
			(stroke
				(width 0.1)
				(type default)
			)
			(layer "F.Fab")
		)
		(fp_line
			(start 0.9144 0.4064)
			(end 0.9144 0.508)
			(stroke
				(width 0.1)
				(type default)
			)
			(layer "F.Fab")
		)
		(fp_line
			(start 1.1938 0.4064)
			(end 0.9144 0.4064)
			(stroke
				(width 0.1)
				(type default)
			)
			(layer "F.Fab")
		)
		(fp_line
			(start -1.194308 -0.406654)
			(end -0.9144 -0.406654)
			(stroke
				(width 0.1)
				(type default)
			)
			(layer "F.Fab")
		)
		(fp_line
			(start -0.9144 -0.406654)
			(end -0.9144 -0.508)
			(stroke
				(width 0.1)
				(type default)
			)
			(layer "F.Fab")
		)
		(fp_line
			(start 0.9144 -0.406654)
			(end 1.1938 -0.406654)
			(stroke
				(width 0.1)
				(type default)
			)
			(layer "F.Fab")
		)
		(fp_line
			(start 1.1938 -0.406654)
			(end 1.1938 0.4064)
			(stroke
				(width 0.1)
				(type default)
			)
			(layer "F.Fab")
		)
		(fp_line
			(start -0.9144 -0.508)
			(end 0.9144 -0.508)
			(stroke
				(width 0.1)
				(type default)
			)
			(layer "F.Fab")
		)
		(fp_line
			(start 0.9144 -0.508)
			(end 0.9144 -0.406654)
			(stroke
				(width 0.1)
				(type default)
			)
			(layer "F.Fab")
		)
		(pad "1" smd rect
			(at -0.7366 0 180)
			(size 0.7112 0.8128)
			(layers "F.Cu" "F.Mask" "F.Paste")
			(net "P12V_AUX")
		)
		(pad "2" smd rect
			(at 0.7366 0 180)
			(size 0.7112 0.8128)
			(layers "F.Cu" "F.Mask" "F.Paste")
			(net "SW_P1V8_PCH_AUX_FLT")
		)
	)
	(footprint ""
		(layer "F.Cu")
		(at 376.8852 -107.183428 180)
		(property "Reference" "R1346"
			(at 0 0 180)
			(layer "F.SilkS")
			(hide yes)
			(effects
				(font
					(size 1.27 1.27)
				)
			)
		)
		(property "Value" ""
			(at 0 0 180)
			(layer "F.Fab")
			(effects
				(font
					(size 1.27 1.27)
				)
			)
		)
		(duplicate_pad_numbers_are_jumpers no)
		(fp_line
			(start 0.7874 0.4064)
			(end -0.7874 0.4064)
			(stroke
				(width 0.1524)
				(type default)
			)
			(layer "F.SilkS")
		)
		(fp_line
			(start 0.7874 -0.4064)
			(end 0.7874 0.4064)
			(stroke
				(width 0.1524)
				(type default)
			)
			(layer "F.SilkS")
		)
		(fp_line
			(start -0.7874 0.4064)
			(end -0.7874 -0.4064)
			(stroke
				(width 0.1524)
				(type default)
			)
			(layer "F.SilkS")
		)
		(fp_line
			(start -0.7874 -0.4064)
			(end 0.7874 -0.4064)
			(stroke
				(width 0.1524)
				(type default)
			)
			(layer "F.SilkS")
		)
		(fp_line
			(start 0.67945 0.3048)
			(end 0.120396 0.3048)
			(stroke
				(width 0.1)
				(type default)
			)
			(layer "F.Fab")
		)
		(fp_line
			(start 0.67945 -0.3048)
			(end 0.67945 0.3048)
			(stroke
				(width 0.1)
				(type default)
			)
			(layer "F.Fab")
		)
		(fp_line
			(start 0.12065 -0.2794)
			(end 0.12065 -0.3048)
			(stroke
				(width 0.1)
				(type default)
			)
			(layer "F.Fab")
		)
		(fp_line
			(start 0.12065 -0.3048)
			(end 0.67945 -0.3048)
			(stroke
				(width 0.1)
				(type default)
			)
			(layer "F.Fab")
		)
		(fp_line
			(start 0.120396 0.3048)
			(end 0.120396 0.2794)
			(stroke
				(width 0.1)
				(type default)
			)
			(layer "F.Fab")
		)
		(fp_line
			(start 0.120396 0.2794)
			(end -0.12065 0.2794)
			(stroke
				(width 0.1)
				(type default)
			)
			(layer "F.Fab")
		)
		(fp_line
			(start -0.12065 0.3048)
			(end -0.67945 0.3048)
			(stroke
				(width 0.1)
				(type default)
			)
			(layer "F.Fab")
		)
		(fp_line
			(start -0.12065 0.2794)
			(end -0.12065 0.3048)
			(stroke
				(width 0.1)
				(type default)
			)
			(layer "F.Fab")
		)
		(fp_line
			(start -0.12065 -0.2794)
			(end 0.12065 -0.2794)
			(stroke
				(width 0.1)
				(type default)
			)
			(layer "F.Fab")
		)
		(fp_line
			(start -0.12065 -0.305054)
			(end -0.12065 -0.2794)
			(stroke
				(width 0.1)
				(type default)
			)
			(layer "F.Fab")
		)
		(fp_line
			(start -0.67945 0.3048)
			(end -0.67945 -0.305054)
			(stroke
				(width 0.1)
				(type default)
			)
			(layer "F.Fab")
		)
		(fp_line
			(start -0.67945 -0.305054)
			(end -0.12065 -0.305054)
			(stroke
				(width 0.1)
				(type default)
			)
			(layer "F.Fab")
		)
		(pad "1" smd circle
			(at -0.40005 0 180)
			(size 0 0)
			(layers "F.Cu" "F.Mask" "F.Paste")
			(net "P0V7_JTAG_VREF_2")
		)
		(pad "2" smd circle
			(at 0.40005 0 180)
			(size 0 0)
			(layers "F.Cu" "F.Mask" "F.Paste")
			(net "GND")
		)
	)
	(footprint ""
		(layer "F.Cu")
		(at 139.586208 -347.520514 -90)
		(property "Reference" "PC487"
			(at 0 0 270)
			(layer "F.SilkS")
			(hide yes)
			(effects
				(font
					(size 1.27 1.27)
				)
			)
		)
		(property "Value" ""
			(at 0 0 270)
			(layer "F.Fab")
			(effects
				(font
					(size 1.27 1.27)
				)
			)
		)
		(duplicate_pad_numbers_are_jumpers no)
		(fp_line
			(start -0.7874 0.4064)
			(end -0.7874 -0.4064)
			(stroke
				(width 0.1524)
				(type default)
			)
			(layer "F.SilkS")
		)
		(fp_line
			(start 0.7874 0.4064)
			(end -0.7874 0.4064)
			(stroke
				(width 0.1524)
				(type default)
			)
			(layer "F.SilkS")
		)
		(fp_line
			(start -0.7874 -0.4064)
			(end 0.7874 -0.4064)
			(stroke
				(width 0.1524)
				(type default)
			)
			(layer "F.SilkS")
		)
		(fp_line
			(start 0.7874 -0.4064)
			(end 0.7874 0.4064)
			(stroke
				(width 0.1524)
				(type default)
			)
			(layer "F.SilkS")
		)
		(fp_line
			(start -0.67945 0.3048)
			(end -0.67945 -0.305054)
			(stroke
				(width 0.1)
				(type default)
			)
			(layer "F.Fab")
		)
		(fp_line
			(start -0.12065 0.3048)
			(end -0.67945 0.3048)
			(stroke
				(width 0.1)
				(type default)
			)
			(layer "F.Fab")
		)
		(fp_line
			(start 0.120396 0.3048)
			(end 0.120396 0.2794)
			(stroke
				(width 0.1)
				(type default)
			)
			(layer "F.Fab")
		)
		(fp_line
			(start 0.67945 0.3048)
			(end 0.120396 0.3048)
			(stroke
				(width 0.1)
				(type default)
			)
			(layer "F.Fab")
		)
		(fp_line
			(start -0.12065 0.2794)
			(end -0.12065 0.3048)
			(stroke
				(width 0.1)
				(type default)
			)
			(layer "F.Fab")
		)
		(fp_line
			(start 0.120396 0.2794)
			(end -0.12065 0.2794)
			(stroke
				(width 0.1)
				(type default)
			)
			(layer "F.Fab")
		)
		(fp_line
			(start -0.12065 -0.2794)
			(end 0.12065 -0.2794)
			(stroke
				(width 0.1)
				(type default)
			)
			(layer "F.Fab")
		)
		(fp_line
			(start 0.12065 -0.2794)
			(end 0.12065 -0.3048)
			(stroke
				(width 0.1)
				(type default)
			)
			(layer "F.Fab")
		)
		(fp_line
			(start 0.12065 -0.3048)
			(end 0.67945 -0.3048)
			(stroke
				(width 0.1)
				(type default)
			)
			(layer "F.Fab")
		)
		(fp_line
			(start 0.67945 -0.3048)
			(end 0.67945 0.3048)
			(stroke
				(width 0.1)
				(type default)
			)
			(layer "F.Fab")
		)
		(fp_line
			(start -0.67945 -0.305054)
			(end -0.12065 -0.305054)
			(stroke
				(width 0.1)
				(type default)
			)
			(layer "F.Fab")
		)
		(fp_line
			(start -0.12065 -0.305054)
			(end -0.12065 -0.2794)
			(stroke
				(width 0.1)
				(type default)
			)
			(layer "F.Fab")
		)
		(pad "1" smd circle
			(at -0.40005 0 270)
			(size 0 0)
			(layers "F.Cu" "F.Mask" "F.Paste")
			(net "SW_PVCCIN_CPU1_BOOT8_R")
		)
		(pad "2" smd circle
			(at 0.40005 0 270)
			(size 0 0)
			(layers "F.Cu" "F.Mask" "F.Paste")
			(net "SW_PVCCIN_CPU1_BOOTR8")
		)
	)
	(footprint ""
		(layer "F.Cu")
		(at 102.39375 -360.934762 -90)
		(property "Reference" "R307"
			(at 0 0 270)
			(layer "F.SilkS")
			(hide yes)
			(effects
				(font
					(size 1.27 1.27)
				)
			)
		)
		(property "Value" ""
			(at 0 0 270)
			(layer "F.Fab")
			(effects
				(font
					(size 1.27 1.27)
				)
			)
		)
		(duplicate_pad_numbers_are_jumpers no)
		(fp_line
			(start -0.7874 0.4064)
			(end -0.7874 -0.4064)
			(stroke
				(width 0.1524)
				(type default)
			)
			(layer "F.SilkS")
		)
		(fp_line
			(start 0.7874 0.4064)
			(end -0.7874 0.4064)
			(stroke
				(width 0.1524)
				(type default)
			)
			(layer "F.SilkS")
		)
		(fp_line
			(start -0.7874 -0.4064)
			(end 0.7874 -0.4064)
			(stroke
				(width 0.1524)
				(type default)
			)
			(layer "F.SilkS")
		)
		(fp_line
			(start 0.7874 -0.4064)
			(end 0.7874 0.4064)
			(stroke
				(width 0.1524)
				(type default)
			)
			(layer "F.SilkS")
		)
		(fp_line
			(start -0.67945 0.3048)
			(end -0.67945 -0.305054)
			(stroke
				(width 0.1)
				(type default)
			)
			(layer "F.Fab")
		)
		(fp_line
			(start -0.12065 0.3048)
			(end -0.67945 0.3048)
			(stroke
				(width 0.1)
				(type default)
			)
			(layer "F.Fab")
		)
		(fp_line
			(start 0.120396 0.3048)
			(end 0.120396 0.2794)
			(stroke
				(width 0.1)
				(type default)
			)
			(layer "F.Fab")
		)
		(fp_line
			(start 0.67945 0.3048)
			(end 0.120396 0.3048)
			(stroke
				(width 0.1)
				(type default)
			)
			(layer "F.Fab")
		)
		(fp_line
			(start -0.12065 0.2794)
			(end -0.12065 0.3048)
			(stroke
				(width 0.1)
				(type default)
			)
			(layer "F.Fab")
		)
		(fp_line
			(start 0.120396 0.2794)
			(end -0.12065 0.2794)
			(stroke
				(width 0.1)
				(type default)
			)
			(layer "F.Fab")
		)
		(fp_line
			(start -0.12065 -0.2794)
			(end 0.12065 -0.2794)
			(stroke
				(width 0.1)
				(type default)
			)
			(layer "F.Fab")
		)
		(fp_line
			(start 0.12065 -0.2794)
			(end 0.12065 -0.3048)
			(stroke
				(width 0.1)
				(type default)
			)
			(layer "F.Fab")
		)
		(fp_line
			(start 0.12065 -0.3048)
			(end 0.67945 -0.3048)
			(stroke
				(width 0.1)
				(type default)
			)
			(layer "F.Fab")
		)
		(fp_line
			(start 0.67945 -0.3048)
			(end 0.67945 0.3048)
			(stroke
				(width 0.1)
				(type default)
			)
			(layer "F.Fab")
		)
		(fp_line
			(start -0.67945 -0.305054)
			(end -0.12065 -0.305054)
			(stroke
				(width 0.1)
				(type default)
			)
			(layer "F.Fab")
		)
		(fp_line
			(start -0.12065 -0.305054)
			(end -0.12065 -0.2794)
			(stroke
				(width 0.1)
				(type default)
			)
			(layer "F.Fab")
		)
		(pad "1" smd circle
			(at -0.40005 0 270)
			(size 0 0)
			(layers "F.Cu" "F.Mask" "F.Paste")
			(net "P3V3_AUX")
		)
		(pad "2" smd circle
			(at 0.40005 0 270)
			(size 0 0)
			(layers "F.Cu" "F.Mask" "F.Paste")
			(net "PWRGD_PVCCIN_CPU1_R")
		)
	)
	(footprint ""
		(layer "F.Cu")
		(at 428.226474 -124.02566 180)
		(property "Reference" "PC631"
			(at 0 0 180)
			(layer "F.SilkS")
			(hide yes)
			(effects
				(font
					(size 1.27 1.27)
				)
			)
		)
		(property "Value" ""
			(at 0 0 180)
			(layer "F.Fab")
			(effects
				(font
					(size 1.27 1.27)
				)
			)
		)
		(duplicate_pad_numbers_are_jumpers no)
		(fp_line
			(start 0.7874 0.4064)
			(end -0.7874 0.4064)
			(stroke
				(width 0.1524)
				(type default)
			)
			(layer "F.SilkS")
		)
		(fp_line
			(start 0.7874 -0.4064)
			(end 0.7874 0.4064)
			(stroke
				(width 0.1524)
				(type default)
			)
			(layer "F.SilkS")
		)
		(fp_line
			(start -0.7874 0.4064)
			(end -0.7874 -0.4064)
			(stroke
				(width 0.1524)
				(type default)
			)
			(layer "F.SilkS")
		)
		(fp_line
			(start -0.7874 -0.4064)
			(end 0.7874 -0.4064)
			(stroke
				(width 0.1524)
				(type default)
			)
			(layer "F.SilkS")
		)
		(fp_line
			(start 0.67945 0.3048)
			(end 0.120396 0.3048)
			(stroke
				(width 0.1)
				(type default)
			)
			(layer "F.Fab")
		)
		(fp_line
			(start 0.67945 -0.3048)
			(end 0.67945 0.3048)
			(stroke
				(width 0.1)
				(type default)
			)
			(layer "F.Fab")
		)
		(fp_line
			(start 0.12065 -0.2794)
			(end 0.12065 -0.3048)
			(stroke
				(width 0.1)
				(type default)
			)
			(layer "F.Fab")
		)
		(fp_line
			(start 0.12065 -0.3048)
			(end 0.67945 -0.3048)
			(stroke
				(width 0.1)
				(type default)
			)
			(layer "F.Fab")
		)
		(fp_line
			(start 0.120396 0.3048)
			(end 0.120396 0.2794)
			(stroke
				(width 0.1)
				(type default)
			)
			(layer "F.Fab")
		)
		(fp_line
			(start 0.120396 0.2794)
			(end -0.12065 0.2794)
			(stroke
				(width 0.1)
				(type default)
			)
			(layer "F.Fab")
		)
		(fp_line
			(start -0.12065 0.3048)
			(end -0.67945 0.3048)
			(stroke
				(width 0.1)
				(type default)
			)
			(layer "F.Fab")
		)
		(fp_line
			(start -0.12065 0.2794)
			(end -0.12065 0.3048)
			(stroke
				(width 0.1)
				(type default)
			)
			(layer "F.Fab")
		)
		(fp_line
			(start -0.12065 -0.2794)
			(end 0.12065 -0.2794)
			(stroke
				(width 0.1)
				(type default)
			)
			(layer "F.Fab")
		)
		(fp_line
			(start -0.12065 -0.305054)
			(end -0.12065 -0.2794)
			(stroke
				(width 0.1)
				(type default)
			)
			(layer "F.Fab")
		)
		(fp_line
			(start -0.67945 0.3048)
			(end -0.67945 -0.305054)
			(stroke
				(width 0.1)
				(type default)
			)
			(layer "F.Fab")
		)
		(fp_line
			(start -0.67945 -0.305054)
			(end -0.12065 -0.305054)
			(stroke
				(width 0.1)
				(type default)
			)
			(layer "F.Fab")
		)
		(pad "1" smd circle
			(at -0.40005 0 180)
			(size 0 0)
			(layers "F.Cu" "F.Mask" "F.Paste")
			(net "PVCCD_HV_CPU0_ATSEN")
		)
		(pad "2" smd circle
			(at 0.40005 0 180)
			(size 0 0)
			(layers "F.Cu" "F.Mask" "F.Paste")
			(net "GND")
		)
	)
	(footprint ""
		(layer "F.Cu")
		(at 447.771774 -385.117594 180)
		(property "Reference" "PL65"
			(at -2.455926 5.957824 0)
			(unlocked yes)
			(layer "F.SilkS")
			(effects
				(font
					(size 0.7874 0.5842)
					(thickness 0.1524)
				)
				(justify left)
			)
		)
		(property "Value" ""
			(at 0 0 180)
			(layer "F.Fab")
			(effects
				(font
					(size 1.27 1.27)
				)
			)
		)
		(duplicate_pad_numbers_are_jumpers no)
		(fp_line
			(start 5.588 5.150104)
			(end 5.588 1.8034)
			(stroke
				(width 0.1524)
				(type default)
			)
			(layer "F.SilkS")
		)
		(fp_line
			(start 5.588 -1.8288)
			(end 5.588 -5.150104)
			(stroke
				(width 0.1524)
				(type default)
			)
			(layer "F.SilkS")
		)
		(fp_line
			(start 5.588 -5.150104)
			(end -5.588 -5.150104)
			(stroke
				(width 0.1524)
				(type default)
			)
			(layer "F.SilkS")
		)
		(fp_line
			(start -5.588 5.150104)
			(end 5.588 5.150104)
			(stroke
				(width 0.1524)
				(type default)
			)
			(layer "F.SilkS")
		)
		(fp_line
			(start -5.588 1.8288)
			(end -5.588 5.150104)
			(stroke
				(width 0.1524)
				(type default)
			)
			(layer "F.SilkS")
		)
		(fp_line
			(start -5.588 -5.150104)
			(end -5.588 -1.8542)
			(stroke
				(width 0.1524)
				(type default)
			)
			(layer "F.SilkS")
		)
		(fp_line
			(start 5.599938 5.150104)
			(end -5.599938 5.150104)
			(stroke
				(width 0.1)
				(type default)
			)
			(layer "F.Fab")
		)
		(fp_line
			(start 5.599938 -5.150104)
			(end 5.599938 5.150104)
			(stroke
				(width 0.1)
				(type default)
			)
			(layer "F.Fab")
		)
		(fp_line
			(start -5.599938 5.150104)
			(end -5.599938 -5.150104)
			(stroke
				(width 0.1)
				(type default)
			)
			(layer "F.Fab")
		)
		(fp_line
			(start -5.599938 -5.150104)
			(end 5.599938 -5.150104)
			(stroke
				(width 0.1)
				(type default)
			)
			(layer "F.Fab")
		)
		(pad "1" smd rect
			(at -4.338828 0 180)
			(size 3.302 3.302)
			(layers "F.Cu" "F.Mask" "F.Paste")
			(net "SW_P5V_AUX_SW")
		)
		(pad "2" smd rect
			(at 4.338828 0 180)
			(size 3.302 3.302)
			(layers "F.Cu" "F.Mask" "F.Paste")
			(net "P5V_AUX")
		)
	)
	(footprint ""
		(layer "F.Cu")
		(at 62.99708 -258.091686)
		(property "Reference" "J18"
			(at -1.547622 -81.836514 0)
			(unlocked yes)
			(layer "F.SilkS")
			(effects
				(font
					(size 0.7874 0.5842)
					(thickness 0.1524)
				)
				(justify left)
			)
		)
		(property "Value" ""
			(at 0 0 0)
			(layer "F.Fab")
			(effects
				(font
					(size 1.27 1.27)
				)
			)
		)
		(duplicate_pad_numbers_are_jumpers no)
		(fp_line
			(start -3.24993 -81.000092)
			(end -3.24993 81.000092)
			(stroke
				(width 0.1524)
				(type default)
			)
			(layer "F.SilkS")
		)
		(fp_line
			(start -3.24993 81.000092)
			(end 3.24993 81.000092)
			(stroke
				(width 0.1524)
				(type default)
			)
			(layer "F.SilkS")
		)
		(fp_line
			(start 3.24993 -81.000092)
			(end -3.24993 -81.000092)
			(stroke
				(width 0.1524)
				(type default)
			)
			(layer "F.SilkS")
		)
		(fp_line
			(start 3.24993 -72.00011)
			(end -3.24993 -72.00011)
			(stroke
				(width 0.1524)
				(type default)
			)
			(layer "F.SilkS")
		)
		(fp_line
			(start 3.24993 72.00011)
			(end -3.24993 72.00011)
			(stroke
				(width 0.1524)
				(type default)
			)
			(layer "F.SilkS")
		)
		(fp_line
			(start 3.24993 81.000092)
			(end 3.24993 -81.000092)
			(stroke
				(width 0.1524)
				(type default)
			)
			(layer "F.SilkS")
		)
		(fp_poly
			(pts
				(xy -4.227322 -63.72225) (xy -3.391408 -63.304166) (xy -4.227322 -62.886082)
			)
			(stroke
				(width 0)
				(type default)
			)
			(fill yes)
			(layer "F.SilkS")
		)
		(fp_line
			(start -3.24993 -81.000092)
			(end -3.24993 81.000092)
			(stroke
				(width 0.1)
				(type default)
			)
			(layer "F.Fab")
		)
		(fp_line
			(start -3.24993 81.000092)
			(end 3.24993 81.000092)
			(stroke
				(width 0.1)
				(type default)
			)
			(layer "F.Fab")
		)
		(fp_line
			(start 3.24993 -81.000092)
			(end -3.24993 -81.000092)
			(stroke
				(width 0.1)
				(type default)
			)
			(layer "F.Fab")
		)
		(fp_line
			(start 3.24993 -72.00011)
			(end -3.24993 -72.00011)
			(stroke
				(width 0.1)
				(type default)
			)
			(layer "F.Fab")
		)
		(fp_line
			(start 3.24993 -71.000112)
			(end -3.24993 -71.000112)
			(stroke
				(width 0.1)
				(type default)
			)
			(layer "F.Fab")
		)
		(fp_line
			(start 3.24993 71.000112)
			(end -3.24993 71.000112)
			(stroke
				(width 0.1)
				(type default)
			)
			(layer "F.Fab")
		)
		(fp_line
			(start 3.24993 72.00011)
			(end -3.24993 72.00011)
			(stroke
				(width 0.1)
				(type default)
			)
			(layer "F.Fab")
		)
		(fp_line
			(start 3.24993 81.000092)
			(end 3.24993 -81.000092)
			(stroke
				(width 0.1)
				(type default)
			)
			(layer "F.Fab")
		)
		(fp_poly
			(pts
				(xy -4.445 -63.832994) (xy -4.445 -62.816994) (xy -3.429 -63.324994)
			)
			(stroke
				(width 0)
				(type default)
			)
			(fill yes)
			(layer "F.Fab")
		)
		(pad "1" smd rect
			(at -2.050034 -63.324994 270)
			(size 0.519938 1.4986)
			(layers "F.Cu" "F.Mask" "F.Paste")
			(net "P12V_S3_AUX_CPU1_NVDIMM")
		)
		(pad "2" smd rect
			(at -2.050034 -62.47511 270)
			(size 0.519938 1.4986)
			(layers "F.Cu" "F.Mask" "F.Paste")
			(net "TP_CHA_CPU1_DIMM2_FRU_0")
		)
		(pad "3" smd rect
			(at -2.050034 -61.624972 270)
			(size 0.519938 1.4986)
			(layers "F.Cu" "F.Mask" "F.Paste")
			(net "P3V3_AUX")
		)
		(pad "4" smd rect
			(at -2.050034 -60.775088 270)
			(size 0.519938 1.4986)
			(layers "F.Cu" "F.Mask" "F.Paste")
			(net "I3C_SPD_DDRABCD_CPU1_LVC1_SCL_1")
		)
		(pad "5" smd rect
			(at -2.050034 -59.92495 270)
			(size 0.519938 1.4986)
			(layers "F.Cu" "F.Mask" "F.Paste")
			(net "I3C_SPD_DDRABCD_CPU1_LVC1_SDA")
		)
		(pad "6" smd rect
			(at -2.050034 -59.075066 270)
			(size 0.519938 1.4986)
			(layers "F.Cu" "F.Mask" "F.Paste")
			(net "GND")
		)
		(pad "7" smd rect
			(at -2.050034 -58.224928 270)
			(size 0.519938 1.4986)
			(layers "F.Cu" "F.Mask" "F.Paste")
			(net "M_A_CPU1_SA_DQ<0>")
		)
		(pad "8" smd rect
			(at -2.050034 -57.375044 270)
			(size 0.519938 1.4986)
			(layers "F.Cu" "F.Mask" "F.Paste")
			(net "GND")
		)
		(pad "9" smd rect
			(at -2.050034 -56.524906 270)
			(size 0.519938 1.4986)
			(layers "F.Cu" "F.Mask" "F.Paste")
			(net "M_A_CPU1_SA_DQ<1>")
		)
		(pad "10" smd rect
			(at -2.050034 -55.675022 270)
			(size 0.519938 1.4986)
			(layers "F.Cu" "F.Mask" "F.Paste")
			(net "GND")
		)
		(pad "11" smd rect
			(at -2.050034 -54.824884 270)
			(size 0.519938 1.4986)
			(layers "F.Cu" "F.Mask" "F.Paste")
			(net "M_A_CPU1_SA_DQS_DP<0>")
		)
		(pad "12" smd rect
			(at -2.050034 -53.975 270)
			(size 0.519938 1.4986)
			(layers "F.Cu" "F.Mask" "F.Paste")
			(net "M_A_CPU1_SA_DQS_DN<0>")
		)
		(pad "13" smd rect
			(at -2.050034 -53.125116 270)
			(size 0.519938 1.4986)
			(layers "F.Cu" "F.Mask" "F.Paste")
			(net "GND")
		)
		(pad "14" smd rect
			(at -2.050034 -52.274978 270)
			(size 0.519938 1.4986)
			(layers "F.Cu" "F.Mask" "F.Paste")
			(net "M_A_CPU1_SA_DQ<4>")
		)
		(pad "15" smd rect
			(at -2.050034 -51.425094 270)
			(size 0.519938 1.4986)
			(layers "F.Cu" "F.Mask" "F.Paste")
			(net "GND")
		)
		(pad "16" smd rect
			(at -2.050034 -50.574956 270)
			(size 0.519938 1.4986)
			(layers "F.Cu" "F.Mask" "F.Paste")
			(net "M_A_CPU1_SA_DQ<5>")
		)
		(pad "17" smd rect
			(at -2.050034 -49.725072 270)
			(size 0.519938 1.4986)
			(layers "F.Cu" "F.Mask" "F.Paste")
			(net "GND")
		)
		(pad "18" smd rect
			(at -2.050034 -48.874934 270)
			(size 0.519938 1.4986)
			(layers "F.Cu" "F.Mask" "F.Paste")
			(net "M_A_CPU1_SA_DQ<8>")
		)
		(pad "19" smd rect
			(at -2.050034 -48.02505 270)
			(size 0.519938 1.4986)
			(layers "F.Cu" "F.Mask" "F.Paste")
			(net "GND")
		)
		(pad "20" smd rect
			(at -2.050034 -47.174912 270)
			(size 0.519938 1.4986)
			(layers "F.Cu" "F.Mask" "F.Paste")
			(net "M_A_CPU1_SA_DQ<9>")
		)
		(pad "21" smd rect
			(at -2.050034 -46.325028 270)
			(size 0.519938 1.4986)
			(layers "F.Cu" "F.Mask" "F.Paste")
			(net "GND")
		)
		(pad "22" smd rect
			(at -2.050034 -45.47489 270)
			(size 0.519938 1.4986)
			(layers "F.Cu" "F.Mask" "F.Paste")
			(net "M_A_CPU1_SA_DQS_DP<1>")
		)
		(pad "23" smd rect
			(at -2.050034 -44.625006 270)
			(size 0.519938 1.4986)
			(layers "F.Cu" "F.Mask" "F.Paste")
			(net "M_A_CPU1_SA_DQS_DN<1>")
		)
		(pad "24" smd rect
			(at -2.050034 -43.775122 270)
			(size 0.519938 1.4986)
			(layers "F.Cu" "F.Mask" "F.Paste")
			(net "GND")
		)
		(pad "25" smd rect
			(at -2.050034 -42.924984 270)
			(size 0.519938 1.4986)
			(layers "F.Cu" "F.Mask" "F.Paste")
			(net "M_A_CPU1_SA_DQ<12>")
		)
		(pad "26" smd rect
			(at -2.050034 -42.0751 270)
			(size 0.519938 1.4986)
			(layers "F.Cu" "F.Mask" "F.Paste")
			(net "GND")
		)
		(pad "27" smd rect
			(at -2.050034 -41.224962 270)
			(size 0.519938 1.4986)
			(layers "F.Cu" "F.Mask" "F.Paste")
			(net "M_A_CPU1_SA_DQ<13>")
		)
		(pad "28" smd rect
			(at -2.050034 -40.375078 270)
			(size 0.519938 1.4986)
			(layers "F.Cu" "F.Mask" "F.Paste")
			(net "GND")
		)
		(pad "29" smd rect
			(at -2.050034 -39.52494 270)
			(size 0.519938 1.4986)
			(layers "F.Cu" "F.Mask" "F.Paste")
			(net "M_A_CPU1_SA_DQ<16>")
		)
		(pad "30" smd rect
			(at -2.050034 -38.675056 270)
			(size 0.519938 1.4986)
			(layers "F.Cu" "F.Mask" "F.Paste")
			(net "GND")
		)
		(pad "31" smd rect
			(at -2.050034 -37.824918 270)
			(size 0.519938 1.4986)
			(layers "F.Cu" "F.Mask" "F.Paste")
			(net "M_A_CPU1_SA_DQ<17>")
		)
		(pad "32" smd rect
			(at -2.050034 -36.975034 270)
			(size 0.519938 1.4986)
			(layers "F.Cu" "F.Mask" "F.Paste")
			(net "GND")
		)
		(pad "33" smd rect
			(at -2.050034 -36.124896 270)
			(size 0.519938 1.4986)
			(layers "F.Cu" "F.Mask" "F.Paste")
			(net "M_A_CPU1_SA_DQS_DP<2>")
		)
		(pad "34" smd rect
			(at -2.050034 -35.275012 270)
			(size 0.519938 1.4986)
			(layers "F.Cu" "F.Mask" "F.Paste")
			(net "M_A_CPU1_SA_DQS_DN<2>")
		)
		(pad "35" smd rect
			(at -2.050034 -34.425128 270)
			(size 0.519938 1.4986)
			(layers "F.Cu" "F.Mask" "F.Paste")
			(net "GND")
		)
		(pad "36" smd rect
			(at -2.050034 -33.57499 270)
			(size 0.519938 1.4986)
			(layers "F.Cu" "F.Mask" "F.Paste")
			(net "M_A_CPU1_SA_DQ<20>")
		)
		(pad "37" smd rect
			(at -2.050034 -32.725106 270)
			(size 0.519938 1.4986)
			(layers "F.Cu" "F.Mask" "F.Paste")
			(net "GND")
		)
		(pad "38" smd rect
			(at -2.050034 -31.874968 270)
			(size 0.519938 1.4986)
			(layers "F.Cu" "F.Mask" "F.Paste")
			(net "M_A_CPU1_SA_DQ<21>")
		)
		(pad "39" smd rect
			(at -2.050034 -31.025084 270)
			(size 0.519938 1.4986)
			(layers "F.Cu" "F.Mask" "F.Paste")
			(net "GND")
		)
		(pad "40" smd rect
			(at -2.050034 -30.174946 270)
			(size 0.519938 1.4986)
			(layers "F.Cu" "F.Mask" "F.Paste")
			(net "M_A_CPU1_SA_DQ<24>")
		)
		(pad "41" smd rect
			(at -2.050034 -29.325062 270)
			(size 0.519938 1.4986)
			(layers "F.Cu" "F.Mask" "F.Paste")
			(net "GND")
		)
		(pad "42" smd rect
			(at -2.050034 -28.474924 270)
			(size 0.519938 1.4986)
			(layers "F.Cu" "F.Mask" "F.Paste")
			(net "M_A_CPU1_SA_DQ<25>")
		)
		(pad "43" smd rect
			(at -2.050034 -27.62504 270)
			(size 0.519938 1.4986)
			(layers "F.Cu" "F.Mask" "F.Paste")
			(net "GND")
		)
		(pad "44" smd rect
			(at -2.050034 -26.774902 270)
			(size 0.519938 1.4986)
			(layers "F.Cu" "F.Mask" "F.Paste")
			(net "M_A_CPU1_SA_DQS_DP<3>")
		)
		(pad "45" smd rect
			(at -2.050034 -25.925018 270)
			(size 0.519938 1.4986)
			(layers "F.Cu" "F.Mask" "F.Paste")
			(net "M_A_CPU1_SA_DQS_DN<3>")
		)
		(pad "46" smd rect
			(at -2.050034 -25.07488 270)
			(size 0.519938 1.4986)
			(layers "F.Cu" "F.Mask" "F.Paste")
			(net "GND")
		)
		(pad "47" smd rect
			(at -2.050034 -24.224996 270)
			(size 0.519938 1.4986)
			(layers "F.Cu" "F.Mask" "F.Paste")
			(net "M_A_CPU1_SA_DQ<28>")
		)
		(pad "48" smd rect
			(at -2.050034 -23.375112 270)
			(size 0.519938 1.4986)
			(layers "F.Cu" "F.Mask" "F.Paste")
			(net "GND")
		)
		(pad "49" smd rect
			(at -2.050034 -22.524974 270)
			(size 0.519938 1.4986)
			(layers "F.Cu" "F.Mask" "F.Paste")
			(net "M_A_CPU1_SA_DQ<29>")
		)
		(pad "50" smd rect
			(at -2.050034 -21.67509 270)
			(size 0.519938 1.4986)
			(layers "F.Cu" "F.Mask" "F.Paste")
			(net "GND")
		)
		(pad "51" smd rect
			(at -2.050034 -20.824952 270)
			(size 0.519938 1.4986)
			(layers "F.Cu" "F.Mask" "F.Paste")
			(net "M_A_CPU1_SA_CB<0>")
		)
		(pad "52" smd rect
			(at -2.050034 -19.975068 270)
			(size 0.519938 1.4986)
			(layers "F.Cu" "F.Mask" "F.Paste")
			(net "GND")
		)
		(pad "53" smd rect
			(at -2.050034 -19.12493 270)
			(size 0.519938 1.4986)
			(layers "F.Cu" "F.Mask" "F.Paste")
			(net "M_A_CPU1_SA_CB<1>")
		)
		(pad "54" smd rect
			(at -2.050034 -18.275046 270)
			(size 0.519938 1.4986)
			(layers "F.Cu" "F.Mask" "F.Paste")
			(net "GND")
		)
		(pad "55" smd rect
			(at -2.050034 -17.424908 270)
			(size 0.519938 1.4986)
			(layers "F.Cu" "F.Mask" "F.Paste")
			(net "M_A_CPU1_SA_DQS_DP<4>")
		)
		(pad "56" smd rect
			(at -2.050034 -16.575024 270)
			(size 0.519938 1.4986)
			(layers "F.Cu" "F.Mask" "F.Paste")
			(net "M_A_CPU1_SA_DQS_DN<4>")
		)
		(pad "57" smd rect
			(at -2.050034 -15.724886 270)
			(size 0.519938 1.4986)
			(layers "F.Cu" "F.Mask" "F.Paste")
			(net "GND")
		)
		(pad "58" smd rect
			(at -2.050034 -14.875002 270)
			(size 0.519938 1.4986)
			(layers "F.Cu" "F.Mask" "F.Paste")
			(net "M_A_CPU1_SA_CB<4>")
		)
		(pad "59" smd rect
			(at -2.050034 -14.025118 270)
			(size 0.519938 1.4986)
			(layers "F.Cu" "F.Mask" "F.Paste")
			(net "GND")
		)
		(pad "60" smd rect
			(at -2.050034 -13.17498 270)
			(size 0.519938 1.4986)
			(layers "F.Cu" "F.Mask" "F.Paste")
			(net "M_A_CPU1_SA_CB<5>")
		)
		(pad "61" smd rect
			(at -2.050034 -12.325096 270)
			(size 0.519938 1.4986)
			(layers "F.Cu" "F.Mask" "F.Paste")
			(net "GND")
		)
		(pad "62" smd rect
			(at -2.050034 -11.474958 270)
			(size 0.519938 1.4986)
			(layers "F.Cu" "F.Mask" "F.Paste")
			(net "M_A_CPU1_ALERT_N")
		)
		(pad "63" smd rect
			(at -2.050034 -10.625074 270)
			(size 0.519938 1.4986)
			(layers "F.Cu" "F.Mask" "F.Paste")
			(net "GND")
		)
		(pad "64" smd rect
			(at -2.050034 -9.774936 270)
			(size 0.519938 1.4986)
			(layers "F.Cu" "F.Mask" "F.Paste")
			(net "M_A_CPU1_SA_CS_N<2>")
		)
		(pad "65" smd rect
			(at -2.050034 -8.925052 270)
			(size 0.519938 1.4986)
			(layers "F.Cu" "F.Mask" "F.Paste")
			(net "GND")
		)
		(pad "66" smd rect
			(at -2.050034 -8.074914 270)
			(size 0.519938 1.4986)
			(layers "F.Cu" "F.Mask" "F.Paste")
			(net "M_A_CPU1_SA_CA<0>")
		)
		(pad "67" smd rect
			(at -2.050034 -7.22503 270)
			(size 0.519938 1.4986)
			(layers "F.Cu" "F.Mask" "F.Paste")
			(net "GND")
		)
		(pad "68" smd rect
			(at -2.050034 -6.374892 270)
			(size 0.519938 1.4986)
			(layers "F.Cu" "F.Mask" "F.Paste")
			(net "M_A_CPU1_SA_CA<2>")
		)
		(pad "69" smd rect
			(at -2.050034 -5.525008 270)
			(size 0.519938 1.4986)
			(layers "F.Cu" "F.Mask" "F.Paste")
			(net "GND")
		)
		(pad "70" smd rect
			(at -2.050034 -4.675124 270)
			(size 0.519938 1.4986)
			(layers "F.Cu" "F.Mask" "F.Paste")
			(net "M_A_CPU1_SA_CA<4>")
		)
		(pad "71" smd rect
			(at -2.050034 -3.824986 270)
			(size 0.519938 1.4986)
			(layers "F.Cu" "F.Mask" "F.Paste")
			(net "GND")
		)
		(pad "72" smd rect
			(at -2.050034 -2.975102 270)
			(size 0.519938 1.4986)
			(layers "F.Cu" "F.Mask" "F.Paste")
			(net "M_A_CPU1_SA_CA<6>")
		)
		(pad "73" smd rect
			(at -2.050034 -2.124964 270)
			(size 0.519938 1.4986)
			(layers "F.Cu" "F.Mask" "F.Paste")
			(net "GND")
		)
		(pad "74" smd rect
			(at -2.050034 -1.27508 270)
			(size 0.519938 1.4986)
			(layers "F.Cu" "F.Mask" "F.Paste")
			(net "M_A_CPU1_SA_PAR")
		)
		(pad "75" smd rect
			(at -2.050034 -0.424942 270)
			(size 0.519938 1.4986)
			(layers "F.Cu" "F.Mask" "F.Paste")
			(net "GND")
		)
		(pad "76" smd rect
			(at -2.050034 5.525008 270)
			(size 0.519938 1.4986)
			(layers "F.Cu" "F.Mask" "F.Paste")
			(net "M_A_CPU1_SB_CA<0>")
		)
		(pad "77" smd rect
			(at -2.050034 6.374892 270)
			(size 0.519938 1.4986)
			(layers "F.Cu" "F.Mask" "F.Paste")
			(net "GND")
		)
		(pad "78" smd rect
			(at -2.050034 7.22503 270)
			(size 0.519938 1.4986)
			(layers "F.Cu" "F.Mask" "F.Paste")
			(net "M_A_CPU1_SB_CA<2>")
		)
		(pad "79" smd rect
			(at -2.050034 8.074914 270)
			(size 0.519938 1.4986)
			(layers "F.Cu" "F.Mask" "F.Paste")
			(net "GND")
		)
		(pad "80" smd rect
			(at -2.050034 8.925052 270)
			(size 0.519938 1.4986)
			(layers "F.Cu" "F.Mask" "F.Paste")
			(net "M_A_CPU1_SB_CA<4>")
		)
		(pad "81" smd rect
			(at -2.050034 9.774936 270)
			(size 0.519938 1.4986)
			(layers "F.Cu" "F.Mask" "F.Paste")
			(net "GND")
		)
		(pad "82" smd rect
			(at -2.050034 10.625074 270)
			(size 0.519938 1.4986)
			(layers "F.Cu" "F.Mask" "F.Paste")
			(net "M_A_CPU1_SB_CA<6>")
		)
		(pad "83" smd rect
			(at -2.050034 11.474958 270)
			(size 0.519938 1.4986)
			(layers "F.Cu" "F.Mask" "F.Paste")
			(net "GND")
		)
		(pad "84" smd rect
			(at -2.050034 12.325096 270)
			(size 0.519938 1.4986)
			(layers "F.Cu" "F.Mask" "F.Paste")
			(net "M_A_CPU1_SB_CS_N<2>")
		)
		(pad "85" smd rect
			(at -2.050034 13.17498 270)
			(size 0.519938 1.4986)
			(layers "F.Cu" "F.Mask" "F.Paste")
			(net "GND")
		)
		(pad "86" smd rect
			(at -2.050034 14.025118 270)
			(size 0.519938 1.4986)
			(layers "F.Cu" "F.Mask" "F.Paste")
			(net "M_A_CPU1_SA_RSP<1>")
		)
		(pad "87" smd rect
			(at -2.050034 14.875002 270)
			(size 0.519938 1.4986)
			(layers "F.Cu" "F.Mask" "F.Paste")
			(net "M_A_CPU1_SB_RSP<1>")
		)
		(pad "88" smd rect
			(at -2.050034 15.724886 270)
			(size 0.519938 1.4986)
			(layers "F.Cu" "F.Mask" "F.Paste")
			(net "GND")
		)
		(pad "89" smd rect
			(at -2.050034 16.575024 270)
			(size 0.519938 1.4986)
			(layers "F.Cu" "F.Mask" "F.Paste")
			(net "M_A_CPU1_SB_CB<4>")
		)
		(pad "90" smd rect
			(at -2.050034 17.424908 270)
			(size 0.519938 1.4986)
			(layers "F.Cu" "F.Mask" "F.Paste")
			(net "GND")
		)
		(pad "91" smd rect
			(at -2.050034 18.275046 270)
			(size 0.519938 1.4986)
			(layers "F.Cu" "F.Mask" "F.Paste")
			(net "M_A_CPU1_SB_CB<5>")
		)
		(pad "92" smd rect
			(at -2.050034 19.12493 270)
			(size 0.519938 1.4986)
			(layers "F.Cu" "F.Mask" "F.Paste")
			(net "GND")
		)
		(pad "93" smd rect
			(at -2.050034 19.975068 270)
			(size 0.519938 1.4986)
			(layers "F.Cu" "F.Mask" "F.Paste")
			(net "M_A_CPU1_SB_DQS_DP<9>")
		)
		(pad "94" smd rect
			(at -2.050034 20.824952 270)
			(size 0.519938 1.4986)
			(layers "F.Cu" "F.Mask" "F.Paste")
			(net "M_A_CPU1_SB_DQS_DN<9>")
		)
		(pad "95" smd rect
			(at -2.050034 21.67509 270)
			(size 0.519938 1.4986)
			(layers "F.Cu" "F.Mask" "F.Paste")
			(net "GND")
		)
		(pad "96" smd rect
			(at -2.050034 22.524974 270)
			(size 0.519938 1.4986)
			(layers "F.Cu" "F.Mask" "F.Paste")
			(net "M_A_CPU1_SB_CB<0>")
		)
		(pad "97" smd rect
			(at -2.050034 23.375112 270)
			(size 0.519938 1.4986)
			(layers "F.Cu" "F.Mask" "F.Paste")
			(net "GND")
		)
		(pad "98" smd rect
			(at -2.050034 24.224996 270)
			(size 0.519938 1.4986)
			(layers "F.Cu" "F.Mask" "F.Paste")
			(net "M_A_CPU1_SB_CB<1>")
		)
		(pad "99" smd rect
			(at -2.050034 25.07488 270)
			(size 0.519938 1.4986)
			(layers "F.Cu" "F.Mask" "F.Paste")
			(net "GND")
		)
		(pad "100" smd rect
			(at -2.050034 25.925018 270)
			(size 0.519938 1.4986)
			(layers "F.Cu" "F.Mask" "F.Paste")
			(net "M_A_CPU1_SB_DQ<0>")
		)
		(pad "101" smd rect
			(at -2.050034 26.774902 270)
			(size 0.519938 1.4986)
			(layers "F.Cu" "F.Mask" "F.Paste")
			(net "GND")
		)
		(pad "102" smd rect
			(at -2.050034 27.62504 270)
			(size 0.519938 1.4986)
			(layers "F.Cu" "F.Mask" "F.Paste")
			(net "M_A_CPU1_SB_DQ<1>")
		)
		(pad "103" smd rect
			(at -2.050034 28.474924 270)
			(size 0.519938 1.4986)
			(layers "F.Cu" "F.Mask" "F.Paste")
			(net "GND")
		)
		(pad "104" smd rect
			(at -2.050034 29.325062 270)
			(size 0.519938 1.4986)
			(layers "F.Cu" "F.Mask" "F.Paste")
			(net "M_A_CPU1_SB_DQS_DP<0>")
		)
		(pad "105" smd rect
			(at -2.050034 30.174946 270)
			(size 0.519938 1.4986)
			(layers "F.Cu" "F.Mask" "F.Paste")
			(net "M_A_CPU1_SB_DQS_DN<0>")
		)
		(pad "106" smd rect
			(at -2.050034 31.025084 270)
			(size 0.519938 1.4986)
			(layers "F.Cu" "F.Mask" "F.Paste")
			(net "GND")
		)
		(pad "107" smd rect
			(at -2.050034 31.874968 270)
			(size 0.519938 1.4986)
			(layers "F.Cu" "F.Mask" "F.Paste")
			(net "M_A_CPU1_SB_DQ<4>")
		)
		(pad "108" smd rect
			(at -2.050034 32.725106 270)
			(size 0.519938 1.4986)
			(layers "F.Cu" "F.Mask" "F.Paste")
			(net "GND")
		)
		(pad "109" smd rect
			(at -2.050034 33.57499 270)
			(size 0.519938 1.4986)
			(layers "F.Cu" "F.Mask" "F.Paste")
			(net "M_A_CPU1_SB_DQ<5>")
		)
		(pad "110" smd rect
			(at -2.050034 34.425128 270)
			(size 0.519938 1.4986)
			(layers "F.Cu" "F.Mask" "F.Paste")
			(net "GND")
		)
		(pad "111" smd rect
			(at -2.050034 35.275012 270)
			(size 0.519938 1.4986)
			(layers "F.Cu" "F.Mask" "F.Paste")
			(net "M_A_CPU1_SB_DQ<8>")
		)
		(pad "112" smd rect
			(at -2.050034 36.124896 270)
			(size 0.519938 1.4986)
			(layers "F.Cu" "F.Mask" "F.Paste")
			(net "GND")
		)
		(pad "113" smd rect
			(at -2.050034 36.975034 270)
			(size 0.519938 1.4986)
			(layers "F.Cu" "F.Mask" "F.Paste")
			(net "M_A_CPU1_SB_DQ<9>")
		)
		(pad "114" smd rect
			(at -2.050034 37.824918 270)
			(size 0.519938 1.4986)
			(layers "F.Cu" "F.Mask" "F.Paste")
			(net "GND")
		)
		(pad "115" smd rect
			(at -2.050034 38.675056 270)
			(size 0.519938 1.4986)
			(layers "F.Cu" "F.Mask" "F.Paste")
			(net "M_A_CPU1_SB_DQS_DP<1>")
		)
		(pad "116" smd rect
			(at -2.050034 39.52494 270)
			(size 0.519938 1.4986)
			(layers "F.Cu" "F.Mask" "F.Paste")
			(net "M_A_CPU1_SB_DQS_DN<1>")
		)
		(pad "117" smd rect
			(at -2.050034 40.375078 270)
			(size 0.519938 1.4986)
			(layers "F.Cu" "F.Mask" "F.Paste")
			(net "GND")
		)
		(pad "118" smd rect
			(at -2.050034 41.224962 270)
			(size 0.519938 1.4986)
			(layers "F.Cu" "F.Mask" "F.Paste")
			(net "M_A_CPU1_SB_DQ<12>")
		)
		(pad "119" smd rect
			(at -2.050034 42.0751 270)
			(size 0.519938 1.4986)
			(layers "F.Cu" "F.Mask" "F.Paste")
			(net "GND")
		)
		(pad "120" smd rect
			(at -2.050034 42.924984 270)
			(size 0.519938 1.4986)
			(layers "F.Cu" "F.Mask" "F.Paste")
			(net "M_A_CPU1_SB_DQ<13>")
		)
		(pad "121" smd rect
			(at -2.050034 43.775122 270)
			(size 0.519938 1.4986)
			(layers "F.Cu" "F.Mask" "F.Paste")
			(net "GND")
		)
		(pad "122" smd rect
			(at -2.050034 44.625006 270)
			(size 0.519938 1.4986)
			(layers "F.Cu" "F.Mask" "F.Paste")
			(net "M_A_CPU1_SB_DQ<16>")
		)
		(pad "123" smd rect
			(at -2.050034 45.47489 270)
			(size 0.519938 1.4986)
			(layers "F.Cu" "F.Mask" "F.Paste")
			(net "GND")
		)
		(pad "124" smd rect
			(at -2.050034 46.325028 270)
			(size 0.519938 1.4986)
			(layers "F.Cu" "F.Mask" "F.Paste")
			(net "M_A_CPU1_SB_DQ<17>")
		)
		(pad "125" smd rect
			(at -2.050034 47.174912 270)
			(size 0.519938 1.4986)
			(layers "F.Cu" "F.Mask" "F.Paste")
			(net "GND")
		)
		(pad "126" smd rect
			(at -2.050034 48.02505 270)
			(size 0.519938 1.4986)
			(layers "F.Cu" "F.Mask" "F.Paste")
			(net "M_A_CPU1_SB_DQS_DP<2>")
		)
		(pad "127" smd rect
			(at -2.050034 48.874934 270)
			(size 0.519938 1.4986)
			(layers "F.Cu" "F.Mask" "F.Paste")
			(net "M_A_CPU1_SB_DQS_DN<2>")
		)
		(pad "128" smd rect
			(at -2.050034 49.725072 270)
			(size 0.519938 1.4986)
			(layers "F.Cu" "F.Mask" "F.Paste")
			(net "GND")
		)
		(pad "129" smd rect
			(at -2.050034 50.574956 270)
			(size 0.519938 1.4986)
			(layers "F.Cu" "F.Mask" "F.Paste")
			(net "M_A_CPU1_SB_DQ<20>")
		)
		(pad "130" smd rect
			(at -2.050034 51.425094 270)
			(size 0.519938 1.4986)
			(layers "F.Cu" "F.Mask" "F.Paste")
			(net "GND")
		)
		(pad "131" smd rect
			(at -2.050034 52.274978 270)
			(size 0.519938 1.4986)
			(layers "F.Cu" "F.Mask" "F.Paste")
			(net "M_A_CPU1_SB_DQ<21>")
		)
		(pad "132" smd rect
			(at -2.050034 53.125116 270)
			(size 0.519938 1.4986)
			(layers "F.Cu" "F.Mask" "F.Paste")
			(net "GND")
		)
		(pad "133" smd rect
			(at -2.050034 53.975 270)
			(size 0.519938 1.4986)
			(layers "F.Cu" "F.Mask" "F.Paste")
			(net "M_A_CPU1_SB_DQ<24>")
		)
		(pad "134" smd rect
			(at -2.050034 54.824884 270)
			(size 0.519938 1.4986)
			(layers "F.Cu" "F.Mask" "F.Paste")
			(net "GND")
		)
		(pad "135" smd rect
			(at -2.050034 55.675022 270)
			(size 0.519938 1.4986)
			(layers "F.Cu" "F.Mask" "F.Paste")
			(net "M_A_CPU1_SB_DQ<25>")
		)
		(pad "136" smd rect
			(at -2.050034 56.524906 270)
			(size 0.519938 1.4986)
			(layers "F.Cu" "F.Mask" "F.Paste")
			(net "GND")
		)
		(pad "137" smd rect
			(at -2.050034 57.375044 270)
			(size 0.519938 1.4986)
			(layers "F.Cu" "F.Mask" "F.Paste")
			(net "M_A_CPU1_SB_DQS_DP<3>")
		)
		(pad "138" smd rect
			(at -2.050034 58.224928 270)
			(size 0.519938 1.4986)
			(layers "F.Cu" "F.Mask" "F.Paste")
			(net "M_A_CPU1_SB_DQS_DN<3>")
		)
		(pad "139" smd rect
			(at -2.050034 59.075066 270)
			(size 0.519938 1.4986)
			(layers "F.Cu" "F.Mask" "F.Paste")
			(net "GND")
		)
		(pad "140" smd rect
			(at -2.050034 59.92495 270)
			(size 0.519938 1.4986)
			(layers "F.Cu" "F.Mask" "F.Paste")
			(net "M_A_CPU1_SB_DQ<28>")
		)
		(pad "141" smd rect
			(at -2.050034 60.775088 270)
			(size 0.519938 1.4986)
			(layers "F.Cu" "F.Mask" "F.Paste")
			(net "GND")
		)
		(pad "142" smd rect
			(at -2.050034 61.624972 270)
			(size 0.519938 1.4986)
			(layers "F.Cu" "F.Mask" "F.Paste")
			(net "M_A_CPU1_SB_DQ<29>")
		)
		(pad "143" smd rect
			(at -2.050034 62.47511 270)
			(size 0.519938 1.4986)
			(layers "F.Cu" "F.Mask" "F.Paste")
			(net "GND")
		)
		(pad "144" smd rect
			(at -2.050034 63.324994 270)
			(size 0.519938 1.4986)
			(layers "F.Cu" "F.Mask" "F.Paste")
			(net "TP_CHA_CPU1_DIMM2_FRU_1")
		)
		(pad "145" smd rect
			(at 2.050034 -63.324994 270)
			(size 0.519938 1.4986)
			(layers "F.Cu" "F.Mask" "F.Paste")
			(net "P12V_S3_AUX_CPU1_NVDIMM")
		)
		(pad "146" smd rect
			(at 2.050034 -62.47511 270)
			(size 0.519938 1.4986)
			(layers "F.Cu" "F.Mask" "F.Paste")
			(net "P12V_S3_AUX_CPU1_NVDIMM")
		)
		(pad "147" smd rect
			(at 2.050034 -61.624972 270)
			(size 0.519938 1.4986)
			(layers "F.Cu" "F.Mask" "F.Paste")
			(net "PWRGD_CHA_CPU1_DIMM2")
		)
		(pad "148" smd rect
			(at 2.050034 -60.775088 270)
			(size 0.519938 1.4986)
			(layers "F.Cu" "F.Mask" "F.Paste")
			(net "PD_CHA_CPU1_DIMM2_SAA")
		)
		(pad "149" smd rect
			(at 2.050034 -59.92495 270)
			(size 0.519938 1.4986)
			(layers "F.Cu" "F.Mask" "F.Paste")
			(net "TP_CHA_CPU1_DIMM2_FRU_2")
		)
		(pad "150" smd rect
			(at 2.050034 -59.075066 270)
			(size 0.519938 1.4986)
			(layers "F.Cu" "F.Mask" "F.Paste")
			(net "TP_CHA_CPU1_DIMM2_FRU_3")
		)
		(pad "151" smd rect
			(at 2.050034 -58.224928 270)
			(size 0.519938 1.4986)
			(layers "F.Cu" "F.Mask" "F.Paste")
			(net "GND")
		)
		(pad "152" smd rect
			(at 2.050034 -57.375044 270)
			(size 0.519938 1.4986)
			(layers "F.Cu" "F.Mask" "F.Paste")
			(net "M_A_CPU1_SA_DQ<2>")
		)
		(pad "153" smd rect
			(at 2.050034 -56.524906 270)
			(size 0.519938 1.4986)
			(layers "F.Cu" "F.Mask" "F.Paste")
			(net "GND")
		)
		(pad "154" smd rect
			(at 2.050034 -55.675022 270)
			(size 0.519938 1.4986)
			(layers "F.Cu" "F.Mask" "F.Paste")
			(net "M_A_CPU1_SA_DQ<3>")
		)
		(pad "155" smd rect
			(at 2.050034 -54.824884 270)
			(size 0.519938 1.4986)
			(layers "F.Cu" "F.Mask" "F.Paste")
			(net "GND")
		)
		(pad "156" smd rect
			(at 2.050034 -53.975 270)
			(size 0.519938 1.4986)
			(layers "F.Cu" "F.Mask" "F.Paste")
			(net "M_A_CPU1_SA_DQS_DN<5>")
		)
		(pad "157" smd rect
			(at 2.050034 -53.125116 270)
			(size 0.519938 1.4986)
			(layers "F.Cu" "F.Mask" "F.Paste")
			(net "M_A_CPU1_SA_DQS_DP<5>")
		)
		(pad "158" smd rect
			(at 2.050034 -52.274978 270)
			(size 0.519938 1.4986)
			(layers "F.Cu" "F.Mask" "F.Paste")
			(net "GND")
		)
		(pad "159" smd rect
			(at 2.050034 -51.425094 270)
			(size 0.519938 1.4986)
			(layers "F.Cu" "F.Mask" "F.Paste")
			(net "M_A_CPU1_SA_DQ<6>")
		)
		(pad "160" smd rect
			(at 2.050034 -50.574956 270)
			(size 0.519938 1.4986)
			(layers "F.Cu" "F.Mask" "F.Paste")
			(net "GND")
		)
		(pad "161" smd rect
			(at 2.050034 -49.725072 270)
			(size 0.519938 1.4986)
			(layers "F.Cu" "F.Mask" "F.Paste")
			(net "M_A_CPU1_SA_DQ<7>")
		)
		(pad "162" smd rect
			(at 2.050034 -48.874934 270)
			(size 0.519938 1.4986)
			(layers "F.Cu" "F.Mask" "F.Paste")
			(net "GND")
		)
		(pad "163" smd rect
			(at 2.050034 -48.02505 270)
			(size 0.519938 1.4986)
			(layers "F.Cu" "F.Mask" "F.Paste")
			(net "M_A_CPU1_SA_DQ<10>")
		)
		(pad "164" smd rect
			(at 2.050034 -47.174912 270)
			(size 0.519938 1.4986)
			(layers "F.Cu" "F.Mask" "F.Paste")
			(net "GND")
		)
		(pad "165" smd rect
			(at 2.050034 -46.325028 270)
			(size 0.519938 1.4986)
			(layers "F.Cu" "F.Mask" "F.Paste")
			(net "M_A_CPU1_SA_DQ<11>")
		)
		(pad "166" smd rect
			(at 2.050034 -45.47489 270)
			(size 0.519938 1.4986)
			(layers "F.Cu" "F.Mask" "F.Paste")
			(net "GND")
		)
		(pad "167" smd rect
			(at 2.050034 -44.625006 270)
			(size 0.519938 1.4986)
			(layers "F.Cu" "F.Mask" "F.Paste")
			(net "M_A_CPU1_SA_DQS_DN<6>")
		)
		(pad "168" smd rect
			(at 2.050034 -43.775122 270)
			(size 0.519938 1.4986)
			(layers "F.Cu" "F.Mask" "F.Paste")
			(net "M_A_CPU1_SA_DQS_DP<6>")
		)
		(pad "169" smd rect
			(at 2.050034 -42.924984 270)
			(size 0.519938 1.4986)
			(layers "F.Cu" "F.Mask" "F.Paste")
			(net "GND")
		)
		(pad "170" smd rect
			(at 2.050034 -42.0751 270)
			(size 0.519938 1.4986)
			(layers "F.Cu" "F.Mask" "F.Paste")
			(net "M_A_CPU1_SA_DQ<14>")
		)
		(pad "171" smd rect
			(at 2.050034 -41.224962 270)
			(size 0.519938 1.4986)
			(layers "F.Cu" "F.Mask" "F.Paste")
			(net "GND")
		)
		(pad "172" smd rect
			(at 2.050034 -40.375078 270)
			(size 0.519938 1.4986)
			(layers "F.Cu" "F.Mask" "F.Paste")
			(net "M_A_CPU1_SA_DQ<15>")
		)
		(pad "173" smd rect
			(at 2.050034 -39.52494 270)
			(size 0.519938 1.4986)
			(layers "F.Cu" "F.Mask" "F.Paste")
			(net "GND")
		)
		(pad "174" smd rect
			(at 2.050034 -38.675056 270)
			(size 0.519938 1.4986)
			(layers "F.Cu" "F.Mask" "F.Paste")
			(net "M_A_CPU1_SA_DQ<18>")
		)
		(pad "175" smd rect
			(at 2.050034 -37.824918 270)
			(size 0.519938 1.4986)
			(layers "F.Cu" "F.Mask" "F.Paste")
			(net "GND")
		)
		(pad "176" smd rect
			(at 2.050034 -36.975034 270)
			(size 0.519938 1.4986)
			(layers "F.Cu" "F.Mask" "F.Paste")
			(net "M_A_CPU1_SA_DQ<19>")
		)
		(pad "177" smd rect
			(at 2.050034 -36.124896 270)
			(size 0.519938 1.4986)
			(layers "F.Cu" "F.Mask" "F.Paste")
			(net "GND")
		)
		(pad "178" smd rect
			(at 2.050034 -35.275012 270)
			(size 0.519938 1.4986)
			(layers "F.Cu" "F.Mask" "F.Paste")
			(net "M_A_CPU1_SA_DQS_DN<7>")
		)
		(pad "179" smd rect
			(at 2.050034 -34.425128 270)
			(size 0.519938 1.4986)
			(layers "F.Cu" "F.Mask" "F.Paste")
			(net "M_A_CPU1_SA_DQS_DP<7>")
		)
		(pad "180" smd rect
			(at 2.050034 -33.57499 270)
			(size 0.519938 1.4986)
			(layers "F.Cu" "F.Mask" "F.Paste")
			(net "GND")
		)
		(pad "181" smd rect
			(at 2.050034 -32.725106 270)
			(size 0.519938 1.4986)
			(layers "F.Cu" "F.Mask" "F.Paste")
			(net "M_A_CPU1_SA_DQ<22>")
		)
		(pad "182" smd rect
			(at 2.050034 -31.874968 270)
			(size 0.519938 1.4986)
			(layers "F.Cu" "F.Mask" "F.Paste")
			(net "GND")
		)
		(pad "183" smd rect
			(at 2.050034 -31.025084 270)
			(size 0.519938 1.4986)
			(layers "F.Cu" "F.Mask" "F.Paste")
			(net "M_A_CPU1_SA_DQ<23>")
		)
		(pad "184" smd rect
			(at 2.050034 -30.174946 270)
			(size 0.519938 1.4986)
			(layers "F.Cu" "F.Mask" "F.Paste")
			(net "GND")
		)
		(pad "185" smd rect
			(at 2.050034 -29.325062 270)
			(size 0.519938 1.4986)
			(layers "F.Cu" "F.Mask" "F.Paste")
			(net "M_A_CPU1_SA_DQ<26>")
		)
		(pad "186" smd rect
			(at 2.050034 -28.474924 270)
			(size 0.519938 1.4986)
			(layers "F.Cu" "F.Mask" "F.Paste")
			(net "GND")
		)
		(pad "187" smd rect
			(at 2.050034 -27.62504 270)
			(size 0.519938 1.4986)
			(layers "F.Cu" "F.Mask" "F.Paste")
			(net "M_A_CPU1_SA_DQ<27>")
		)
		(pad "188" smd rect
			(at 2.050034 -26.774902 270)
			(size 0.519938 1.4986)
			(layers "F.Cu" "F.Mask" "F.Paste")
			(net "GND")
		)
		(pad "189" smd rect
			(at 2.050034 -25.925018 270)
			(size 0.519938 1.4986)
			(layers "F.Cu" "F.Mask" "F.Paste")
			(net "M_A_CPU1_SA_DQS_DN<8>")
		)
		(pad "190" smd rect
			(at 2.050034 -25.07488 270)
			(size 0.519938 1.4986)
			(layers "F.Cu" "F.Mask" "F.Paste")
			(net "M_A_CPU1_SA_DQS_DP<8>")
		)
		(pad "191" smd rect
			(at 2.050034 -24.224996 270)
			(size 0.519938 1.4986)
			(layers "F.Cu" "F.Mask" "F.Paste")
			(net "GND")
		)
		(pad "192" smd rect
			(at 2.050034 -23.375112 270)
			(size 0.519938 1.4986)
			(layers "F.Cu" "F.Mask" "F.Paste")
			(net "M_A_CPU1_SA_DQ<30>")
		)
		(pad "193" smd rect
			(at 2.050034 -22.524974 270)
			(size 0.519938 1.4986)
			(layers "F.Cu" "F.Mask" "F.Paste")
			(net "GND")
		)
		(pad "194" smd rect
			(at 2.050034 -21.67509 270)
			(size 0.519938 1.4986)
			(layers "F.Cu" "F.Mask" "F.Paste")
			(net "M_A_CPU1_SA_DQ<31>")
		)
		(pad "195" smd rect
			(at 2.050034 -20.824952 270)
			(size 0.519938 1.4986)
			(layers "F.Cu" "F.Mask" "F.Paste")
			(net "GND")
		)
		(pad "196" smd rect
			(at 2.050034 -19.975068 270)
			(size 0.519938 1.4986)
			(layers "F.Cu" "F.Mask" "F.Paste")
			(net "M_A_CPU1_SA_CB<2>")
		)
		(pad "197" smd rect
			(at 2.050034 -19.12493 270)
			(size 0.519938 1.4986)
			(layers "F.Cu" "F.Mask" "F.Paste")
			(net "GND")
		)
		(pad "198" smd rect
			(at 2.050034 -18.275046 270)
			(size 0.519938 1.4986)
			(layers "F.Cu" "F.Mask" "F.Paste")
			(net "M_A_CPU1_SA_CB<3>")
		)
		(pad "199" smd rect
			(at 2.050034 -17.424908 270)
			(size 0.519938 1.4986)
			(layers "F.Cu" "F.Mask" "F.Paste")
			(net "GND")
		)
		(pad "200" smd rect
			(at 2.050034 -16.575024 270)
			(size 0.519938 1.4986)
			(layers "F.Cu" "F.Mask" "F.Paste")
			(net "M_A_CPU1_SA_DQS_DN<9>")
		)
		(pad "201" smd rect
			(at 2.050034 -15.724886 270)
			(size 0.519938 1.4986)
			(layers "F.Cu" "F.Mask" "F.Paste")
			(net "M_A_CPU1_SA_DQS_DP<9>")
		)
		(pad "202" smd rect
			(at 2.050034 -14.875002 270)
			(size 0.519938 1.4986)
			(layers "F.Cu" "F.Mask" "F.Paste")
			(net "GND")
		)
		(pad "203" smd rect
			(at 2.050034 -14.025118 270)
			(size 0.519938 1.4986)
			(layers "F.Cu" "F.Mask" "F.Paste")
			(net "M_A_CPU1_SA_CB<6>")
		)
		(pad "204" smd rect
			(at 2.050034 -13.17498 270)
			(size 0.519938 1.4986)
			(layers "F.Cu" "F.Mask" "F.Paste")
			(net "GND")
		)
		(pad "205" smd rect
			(at 2.050034 -12.325096 270)
			(size 0.519938 1.4986)
			(layers "F.Cu" "F.Mask" "F.Paste")
			(net "M_A_CPU1_SA_CB<7>")
		)
		(pad "206" smd rect
			(at 2.050034 -11.474958 270)
			(size 0.519938 1.4986)
			(layers "F.Cu" "F.Mask" "F.Paste")
			(net "GND")
		)
		(pad "207" smd rect
			(at 2.050034 -10.625074 270)
			(size 0.519938 1.4986)
			(layers "F.Cu" "F.Mask" "F.Paste")
			(net "RST_M_AB_CPU1_FPGA_N")
		)
		(pad "208" smd rect
			(at 2.050034 -9.774936 270)
			(size 0.519938 1.4986)
			(layers "F.Cu" "F.Mask" "F.Paste")
			(net "GND")
		)
		(pad "209" smd rect
			(at 2.050034 -8.925052 270)
			(size 0.519938 1.4986)
			(layers "F.Cu" "F.Mask" "F.Paste")
			(net "M_A_CPU1_SA_CS_N<3>")
		)
		(pad "210" smd rect
			(at 2.050034 -8.074914 270)
			(size 0.519938 1.4986)
			(layers "F.Cu" "F.Mask" "F.Paste")
			(net "GND")
		)
		(pad "211" smd rect
			(at 2.050034 -7.22503 270)
			(size 0.519938 1.4986)
			(layers "F.Cu" "F.Mask" "F.Paste")
			(net "M_A_CPU1_SA_CA<1>")
		)
		(pad "212" smd rect
			(at 2.050034 -6.374892 270)
			(size 0.519938 1.4986)
			(layers "F.Cu" "F.Mask" "F.Paste")
			(net "GND")
		)
		(pad "213" smd rect
			(at 2.050034 -5.525008 270)
			(size 0.519938 1.4986)
			(layers "F.Cu" "F.Mask" "F.Paste")
			(net "M_A_CPU1_SA_CA<3>")
		)
		(pad "214" smd rect
			(at 2.050034 -4.675124 270)
			(size 0.519938 1.4986)
			(layers "F.Cu" "F.Mask" "F.Paste")
			(net "GND")
		)
		(pad "215" smd rect
			(at 2.050034 -3.824986 270)
			(size 0.519938 1.4986)
			(layers "F.Cu" "F.Mask" "F.Paste")
			(net "M_A_CPU1_SA_CA<5>")
		)
		(pad "216" smd rect
			(at 2.050034 -2.975102 270)
			(size 0.519938 1.4986)
			(layers "F.Cu" "F.Mask" "F.Paste")
			(net "GND")
		)
		(pad "217" smd rect
			(at 2.050034 -2.124964 270)
			(size 0.519938 1.4986)
			(layers "F.Cu" "F.Mask" "F.Paste")
			(net "M_A_CPU1_CLK_DP<1>")
		)
		(pad "218" smd rect
			(at 2.050034 -1.27508 270)
			(size 0.519938 1.4986)
			(layers "F.Cu" "F.Mask" "F.Paste")
			(net "M_A_CPU1_CLK_DN<1>")
		)
		(pad "219" smd rect
			(at 2.050034 -0.424942 270)
			(size 0.519938 1.4986)
			(layers "F.Cu" "F.Mask" "F.Paste")
			(net "GND")
		)
		(pad "220" smd rect
			(at 2.050034 5.525008 270)
			(size 0.519938 1.4986)
			(layers "F.Cu" "F.Mask" "F.Paste")
			(net "TP_CHA_CPU1_DIMM2_FRU_4")
		)
		(pad "221" smd rect
			(at 2.050034 6.374892 270)
			(size 0.519938 1.4986)
			(layers "F.Cu" "F.Mask" "F.Paste")
			(net "M_A_CPU1_SB_CA<1>")
		)
		(pad "222" smd rect
			(at 2.050034 7.22503 270)
			(size 0.519938 1.4986)
			(layers "F.Cu" "F.Mask" "F.Paste")
			(net "GND")
		)
		(pad "223" smd rect
			(at 2.050034 8.074914 270)
			(size 0.519938 1.4986)
			(layers "F.Cu" "F.Mask" "F.Paste")
			(net "M_A_CPU1_SB_CA<3>")
		)
		(pad "224" smd rect
			(at 2.050034 8.925052 270)
			(size 0.519938 1.4986)
			(layers "F.Cu" "F.Mask" "F.Paste")
			(net "GND")
		)
		(pad "225" smd rect
			(at 2.050034 9.774936 270)
			(size 0.519938 1.4986)
			(layers "F.Cu" "F.Mask" "F.Paste")
			(net "M_A_CPU1_SB_CA<5>")
		)
		(pad "226" smd rect
			(at 2.050034 10.625074 270)
			(size 0.519938 1.4986)
			(layers "F.Cu" "F.Mask" "F.Paste")
			(net "GND")
		)
		(pad "227" smd rect
			(at 2.050034 11.474958 270)
			(size 0.519938 1.4986)
			(layers "F.Cu" "F.Mask" "F.Paste")
			(net "M_A_CPU1_SB_PAR")
		)
		(pad "228" smd rect
			(at 2.050034 12.325096 270)
			(size 0.519938 1.4986)
			(layers "F.Cu" "F.Mask" "F.Paste")
			(net "GND")
		)
		(pad "229" smd rect
			(at 2.050034 13.17498 270)
			(size 0.519938 1.4986)
			(layers "F.Cu" "F.Mask" "F.Paste")
			(net "M_A_CPU1_SB_CS_N<3>")
		)
		(pad "230" smd rect
			(at 2.050034 14.025118 270)
			(size 0.519938 1.4986)
			(layers "F.Cu" "F.Mask" "F.Paste")
			(net "GND")
		)
		(pad "231" smd rect
			(at 2.050034 14.875002 270)
			(size 0.519938 1.4986)
			(layers "F.Cu" "F.Mask" "F.Paste")
			(net "TP_CHA_CPU1_DIMM2_FRU_5")
		)
		(pad "232" smd rect
			(at 2.050034 15.724886 270)
			(size 0.519938 1.4986)
			(layers "F.Cu" "F.Mask" "F.Paste")
			(net "TP_CHA_CPU1_DIMM2_FRU_6")
		)
		(pad "233" smd rect
			(at 2.050034 16.575024 270)
			(size 0.519938 1.4986)
			(layers "F.Cu" "F.Mask" "F.Paste")
			(net "GND")
		)
		(pad "234" smd rect
			(at 2.050034 17.424908 270)
			(size 0.519938 1.4986)
			(layers "F.Cu" "F.Mask" "F.Paste")
			(net "M_A_CPU1_SB_CB<6>")
		)
		(pad "235" smd rect
			(at 2.050034 18.275046 270)
			(size 0.519938 1.4986)
			(layers "F.Cu" "F.Mask" "F.Paste")
			(net "GND")
		)
		(pad "236" smd rect
			(at 2.050034 19.12493 270)
			(size 0.519938 1.4986)
			(layers "F.Cu" "F.Mask" "F.Paste")
			(net "M_A_CPU1_SB_CB<7>")
		)
		(pad "237" smd rect
			(at 2.050034 19.975068 270)
			(size 0.519938 1.4986)
			(layers "F.Cu" "F.Mask" "F.Paste")
			(net "GND")
		)
		(pad "238" smd rect
			(at 2.050034 20.824952 270)
			(size 0.519938 1.4986)
			(layers "F.Cu" "F.Mask" "F.Paste")
			(net "M_A_CPU1_SB_DQS_DN<4>")
		)
		(pad "239" smd rect
			(at 2.050034 21.67509 270)
			(size 0.519938 1.4986)
			(layers "F.Cu" "F.Mask" "F.Paste")
			(net "M_A_CPU1_SB_DQS_DP<4>")
		)
		(pad "240" smd rect
			(at 2.050034 22.524974 270)
			(size 0.519938 1.4986)
			(layers "F.Cu" "F.Mask" "F.Paste")
			(net "GND")
		)
		(pad "241" smd rect
			(at 2.050034 23.375112 270)
			(size 0.519938 1.4986)
			(layers "F.Cu" "F.Mask" "F.Paste")
			(net "M_A_CPU1_SB_CB<2>")
		)
		(pad "242" smd rect
			(at 2.050034 24.224996 270)
			(size 0.519938 1.4986)
			(layers "F.Cu" "F.Mask" "F.Paste")
			(net "GND")
		)
		(pad "243" smd rect
			(at 2.050034 25.07488 270)
			(size 0.519938 1.4986)
			(layers "F.Cu" "F.Mask" "F.Paste")
			(net "M_A_CPU1_SB_CB<3>")
		)
		(pad "244" smd rect
			(at 2.050034 25.925018 270)
			(size 0.519938 1.4986)
			(layers "F.Cu" "F.Mask" "F.Paste")
			(net "GND")
		)
		(pad "245" smd rect
			(at 2.050034 26.774902 270)
			(size 0.519938 1.4986)
			(layers "F.Cu" "F.Mask" "F.Paste")
			(net "M_A_CPU1_SB_DQ<2>")
		)
		(pad "246" smd rect
			(at 2.050034 27.62504 270)
			(size 0.519938 1.4986)
			(layers "F.Cu" "F.Mask" "F.Paste")
			(net "GND")
		)
		(pad "247" smd rect
			(at 2.050034 28.474924 270)
			(size 0.519938 1.4986)
			(layers "F.Cu" "F.Mask" "F.Paste")
			(net "M_A_CPU1_SB_DQ<3>")
		)
		(pad "248" smd rect
			(at 2.050034 29.325062 270)
			(size 0.519938 1.4986)
			(layers "F.Cu" "F.Mask" "F.Paste")
			(net "GND")
		)
		(pad "249" smd rect
			(at 2.050034 30.174946 270)
			(size 0.519938 1.4986)
			(layers "F.Cu" "F.Mask" "F.Paste")
			(net "M_A_CPU1_SB_DQS_DN<5>")
		)
		(pad "250" smd rect
			(at 2.050034 31.025084 270)
			(size 0.519938 1.4986)
			(layers "F.Cu" "F.Mask" "F.Paste")
			(net "M_A_CPU1_SB_DQS_DP<5>")
		)
		(pad "251" smd rect
			(at 2.050034 31.874968 270)
			(size 0.519938 1.4986)
			(layers "F.Cu" "F.Mask" "F.Paste")
			(net "GND")
		)
		(pad "252" smd rect
			(at 2.050034 32.725106 270)
			(size 0.519938 1.4986)
			(layers "F.Cu" "F.Mask" "F.Paste")
			(net "M_A_CPU1_SB_DQ<6>")
		)
		(pad "253" smd rect
			(at 2.050034 33.57499 270)
			(size 0.519938 1.4986)
			(layers "F.Cu" "F.Mask" "F.Paste")
			(net "GND")
		)
		(pad "254" smd rect
			(at 2.050034 34.425128 270)
			(size 0.519938 1.4986)
			(layers "F.Cu" "F.Mask" "F.Paste")
			(net "M_A_CPU1_SB_DQ<7>")
		)
		(pad "255" smd rect
			(at 2.050034 35.275012 270)
			(size 0.519938 1.4986)
			(layers "F.Cu" "F.Mask" "F.Paste")
			(net "GND")
		)
		(pad "256" smd rect
			(at 2.050034 36.124896 270)
			(size 0.519938 1.4986)
			(layers "F.Cu" "F.Mask" "F.Paste")
			(net "M_A_CPU1_SB_DQ<10>")
		)
		(pad "257" smd rect
			(at 2.050034 36.975034 270)
			(size 0.519938 1.4986)
			(layers "F.Cu" "F.Mask" "F.Paste")
			(net "GND")
		)
		(pad "258" smd rect
			(at 2.050034 37.824918 270)
			(size 0.519938 1.4986)
			(layers "F.Cu" "F.Mask" "F.Paste")
			(net "M_A_CPU1_SB_DQ<11>")
		)
		(pad "259" smd rect
			(at 2.050034 38.675056 270)
			(size 0.519938 1.4986)
			(layers "F.Cu" "F.Mask" "F.Paste")
			(net "GND")
		)
		(pad "260" smd rect
			(at 2.050034 39.52494 270)
			(size 0.519938 1.4986)
			(layers "F.Cu" "F.Mask" "F.Paste")
			(net "M_A_CPU1_SB_DQS_DN<6>")
		)
		(pad "261" smd rect
			(at 2.050034 40.375078 270)
			(size 0.519938 1.4986)
			(layers "F.Cu" "F.Mask" "F.Paste")
			(net "M_A_CPU1_SB_DQS_DP<6>")
		)
		(pad "262" smd rect
			(at 2.050034 41.224962 270)
			(size 0.519938 1.4986)
			(layers "F.Cu" "F.Mask" "F.Paste")
			(net "GND")
		)
		(pad "263" smd rect
			(at 2.050034 42.0751 270)
			(size 0.519938 1.4986)
			(layers "F.Cu" "F.Mask" "F.Paste")
			(net "M_A_CPU1_SB_DQ<14>")
		)
		(pad "264" smd rect
			(at 2.050034 42.924984 270)
			(size 0.519938 1.4986)
			(layers "F.Cu" "F.Mask" "F.Paste")
			(net "GND")
		)
		(pad "265" smd rect
			(at 2.050034 43.775122 270)
			(size 0.519938 1.4986)
			(layers "F.Cu" "F.Mask" "F.Paste")
			(net "M_A_CPU1_SB_DQ<15>")
		)
		(pad "266" smd rect
			(at 2.050034 44.625006 270)
			(size 0.519938 1.4986)
			(layers "F.Cu" "F.Mask" "F.Paste")
			(net "GND")
		)
		(pad "267" smd rect
			(at 2.050034 45.47489 270)
			(size 0.519938 1.4986)
			(layers "F.Cu" "F.Mask" "F.Paste")
			(net "M_A_CPU1_SB_DQ<18>")
		)
		(pad "268" smd rect
			(at 2.050034 46.325028 270)
			(size 0.519938 1.4986)
			(layers "F.Cu" "F.Mask" "F.Paste")
			(net "GND")
		)
		(pad "269" smd rect
			(at 2.050034 47.174912 270)
			(size 0.519938 1.4986)
			(layers "F.Cu" "F.Mask" "F.Paste")
			(net "M_A_CPU1_SB_DQ<19>")
		)
		(pad "270" smd rect
			(at 2.050034 48.02505 270)
			(size 0.519938 1.4986)
			(layers "F.Cu" "F.Mask" "F.Paste")
			(net "GND")
		)
		(pad "271" smd rect
			(at 2.050034 48.874934 270)
			(size 0.519938 1.4986)
			(layers "F.Cu" "F.Mask" "F.Paste")
			(net "M_A_CPU1_SB_DQS_DN<7>")
		)
		(pad "272" smd rect
			(at 2.050034 49.725072 270)
			(size 0.519938 1.4986)
			(layers "F.Cu" "F.Mask" "F.Paste")
			(net "M_A_CPU1_SB_DQS_DP<7>")
		)
		(pad "273" smd rect
			(at 2.050034 50.574956 270)
			(size 0.519938 1.4986)
			(layers "F.Cu" "F.Mask" "F.Paste")
			(net "GND")
		)
		(pad "274" smd rect
			(at 2.050034 51.425094 270)
			(size 0.519938 1.4986)
			(layers "F.Cu" "F.Mask" "F.Paste")
			(net "M_A_CPU1_SB_DQ<22>")
		)
		(pad "275" smd rect
			(at 2.050034 52.274978 270)
			(size 0.519938 1.4986)
			(layers "F.Cu" "F.Mask" "F.Paste")
			(net "GND")
		)
		(pad "276" smd rect
			(at 2.050034 53.125116 270)
			(size 0.519938 1.4986)
			(layers "F.Cu" "F.Mask" "F.Paste")
			(net "M_A_CPU1_SB_DQ<23>")
		)
		(pad "277" smd rect
			(at 2.050034 53.975 270)
			(size 0.519938 1.4986)
			(layers "F.Cu" "F.Mask" "F.Paste")
			(net "GND")
		)
		(pad "278" smd rect
			(at 2.050034 54.824884 270)
			(size 0.519938 1.4986)
			(layers "F.Cu" "F.Mask" "F.Paste")
			(net "M_A_CPU1_SB_DQ<26>")
		)
		(pad "279" smd rect
			(at 2.050034 55.675022 270)
			(size 0.519938 1.4986)
			(layers "F.Cu" "F.Mask" "F.Paste")
			(net "GND")
		)
		(pad "280" smd rect
			(at 2.050034 56.524906 270)
			(size 0.519938 1.4986)
			(layers "F.Cu" "F.Mask" "F.Paste")
			(net "M_A_CPU1_SB_DQ<27>")
		)
		(pad "281" smd rect
			(at 2.050034 57.375044 270)
			(size 0.519938 1.4986)
			(layers "F.Cu" "F.Mask" "F.Paste")
			(net "GND")
		)
		(pad "282" smd rect
			(at 2.050034 58.224928 270)
			(size 0.519938 1.4986)
			(layers "F.Cu" "F.Mask" "F.Paste")
			(net "M_A_CPU1_SB_DQS_DN<8>")
		)
		(pad "283" smd rect
			(at 2.050034 59.075066 270)
			(size 0.519938 1.4986)
			(layers "F.Cu" "F.Mask" "F.Paste")
			(net "M_A_CPU1_SB_DQS_DP<8>")
		)
		(pad "284" smd rect
			(at 2.050034 59.92495 270)
			(size 0.519938 1.4986)
			(layers "F.Cu" "F.Mask" "F.Paste")
			(net "GND")
		)
		(pad "285" smd rect
			(at 2.050034 60.775088 270)
			(size 0.519938 1.4986)
			(layers "F.Cu" "F.Mask" "F.Paste")
			(net "M_A_CPU1_SB_DQ<30>")
		)
		(pad "286" smd rect
			(at 2.050034 61.624972 270)
			(size 0.519938 1.4986)
			(layers "F.Cu" "F.Mask" "F.Paste")
			(net "GND")
		)
		(pad "287" smd rect
			(at 2.050034 62.47511 270)
			(size 0.519938 1.4986)
			(layers "F.Cu" "F.Mask" "F.Paste")
			(net "M_A_CPU1_SB_DQ<31>")
		)
		(pad "288" smd rect
			(at 2.050034 63.324994 270)
			(size 0.519938 1.4986)
			(layers "F.Cu" "F.Mask" "F.Paste")
			(net "GND")
		)
		(pad "G1" thru_hole oval
			(at 0 -68.97497)
			(size 2.8194 1.5748)
			(drill oval 2.4384 1.1938)
			(layers "*.Cu" "*.Mask")
			(remove_unused_layers no)
			(net "GND")
			(clearance 0.127)
			(thermal_gap 0.127)
		)
		(pad "G2" thru_hole oval
			(at 0 3.875024)
			(size 2.8194 1.5748)
			(drill oval 2.4384 1.1938)
			(layers "*.Cu" "*.Mask")
			(remove_unused_layers no)
			(net "GND")
			(clearance 0.127)
			(thermal_gap 0.127)
		)
		(pad "G3" thru_hole oval
			(at 0 68.97497)
			(size 2.8194 1.5748)
			(drill oval 2.4384 1.1938)
			(layers "*.Cu" "*.Mask")
			(remove_unused_layers no)
			(net "GND")
			(clearance 0.127)
			(thermal_gap 0.127)
		)
	)
	(footprint ""
		(layer "F.Cu")
		(at 50.256694 -16.099536 90)
		(property "Reference" "C830"
			(at 0 0 90)
			(layer "F.SilkS")
			(hide yes)
			(effects
				(font
					(size 1.27 1.27)
				)
			)
		)
		(property "Value" ""
			(at 0 0 90)
			(layer "F.Fab")
			(effects
				(font
					(size 1.27 1.27)
				)
			)
		)
		(duplicate_pad_numbers_are_jumpers no)
		(fp_line
			(start 0.299974 -0.150114)
			(end 0.299974 0.150114)
			(stroke
				(width 0.1)
				(type default)
			)
			(layer "F.Fab")
		)
		(fp_line
			(start -0.299974 -0.150114)
			(end 0.299974 -0.150114)
			(stroke
				(width 0.1)
				(type default)
			)
			(layer "F.Fab")
		)
		(fp_line
			(start 0.299974 0.150114)
			(end -0.299974 0.150114)
			(stroke
				(width 0.1)
				(type default)
			)
			(layer "F.Fab")
		)
		(fp_line
			(start -0.299974 0.150114)
			(end -0.299974 -0.150114)
			(stroke
				(width 0.1)
				(type default)
			)
			(layer "F.Fab")
		)
		(pad "1" smd rect
			(at -0.2667 0 90)
			(size 0.3048 0.381)
			(layers "F.Cu" "F.Mask" "F.Paste")
			(net "P5E_CPU1_PE1_TX_C_DN<3>")
		)
		(pad "2" smd rect
			(at 0.2667 0 90)
			(size 0.3048 0.381)
			(layers "F.Cu" "F.Mask" "F.Paste")
			(net "P5E_CPU1_PE1_TX_DN<3>")
		)
	)
	(footprint ""
		(layer "F.Cu")
		(at 418.36594 -109.271308 90)
		(property "Reference" "PC2161"
			(at 0 0 90)
			(layer "F.SilkS")
			(hide yes)
			(effects
				(font
					(size 1.27 1.27)
				)
			)
		)
		(property "Value" ""
			(at 0 0 90)
			(layer "F.Fab")
			(effects
				(font
					(size 1.27 1.27)
				)
			)
		)
		(duplicate_pad_numbers_are_jumpers no)
		(fp_line
			(start 0.7874 -0.4064)
			(end 0.7874 0.4064)
			(stroke
				(width 0.1524)
				(type default)
			)
			(layer "F.SilkS")
		)
		(fp_line
			(start -0.7874 -0.4064)
			(end 0.7874 -0.4064)
			(stroke
				(width 0.1524)
				(type default)
			)
			(layer "F.SilkS")
		)
		(fp_line
			(start 0.7874 0.4064)
			(end -0.7874 0.4064)
			(stroke
				(width 0.1524)
				(type default)
			)
			(layer "F.SilkS")
		)
		(fp_line
			(start -0.7874 0.4064)
			(end -0.7874 -0.4064)
			(stroke
				(width 0.1524)
				(type default)
			)
			(layer "F.SilkS")
		)
		(fp_line
			(start -0.12065 -0.305054)
			(end -0.12065 -0.2794)
			(stroke
				(width 0.1)
				(type default)
			)
			(layer "F.Fab")
		)
		(fp_line
			(start -0.67945 -0.305054)
			(end -0.12065 -0.305054)
			(stroke
				(width 0.1)
				(type default)
			)
			(layer "F.Fab")
		)
		(fp_line
			(start 0.67945 -0.3048)
			(end 0.67945 0.3048)
			(stroke
				(width 0.1)
				(type default)
			)
			(layer "F.Fab")
		)
		(fp_line
			(start 0.12065 -0.3048)
			(end 0.67945 -0.3048)
			(stroke
				(width 0.1)
				(type default)
			)
			(layer "F.Fab")
		)
		(fp_line
			(start 0.12065 -0.2794)
			(end 0.12065 -0.3048)
			(stroke
				(width 0.1)
				(type default)
			)
			(layer "F.Fab")
		)
		(fp_line
			(start -0.12065 -0.2794)
			(end 0.12065 -0.2794)
			(stroke
				(width 0.1)
				(type default)
			)
			(layer "F.Fab")
		)
		(fp_line
			(start 0.120396 0.2794)
			(end -0.12065 0.2794)
			(stroke
				(width 0.1)
				(type default)
			)
			(layer "F.Fab")
		)
		(fp_line
			(start -0.12065 0.2794)
			(end -0.12065 0.3048)
			(stroke
				(width 0.1)
				(type default)
			)
			(layer "F.Fab")
		)
		(fp_line
			(start 0.67945 0.3048)
			(end 0.120396 0.3048)
			(stroke
				(width 0.1)
				(type default)
			)
			(layer "F.Fab")
		)
		(fp_line
			(start 0.120396 0.3048)
			(end 0.120396 0.2794)
			(stroke
				(width 0.1)
				(type default)
			)
			(layer "F.Fab")
		)
		(fp_line
			(start -0.12065 0.3048)
			(end -0.67945 0.3048)
			(stroke
				(width 0.1)
				(type default)
			)
			(layer "F.Fab")
		)
		(fp_line
			(start -0.67945 0.3048)
			(end -0.67945 -0.305054)
			(stroke
				(width 0.1)
				(type default)
			)
			(layer "F.Fab")
		)
		(pad "1" smd circle
			(at -0.40005 0 90)
			(size 0 0)
			(layers "F.Cu" "F.Mask" "F.Paste")
			(net "P3V3_OCP_DVDT_1")
		)
		(pad "2" smd circle
			(at 0.40005 0 90)
			(size 0 0)
			(layers "F.Cu" "F.Mask" "F.Paste")
			(net "GND")
		)
	)
	(footprint ""
		(layer "F.Cu")
		(at 424.204892 -384.266948 180)
		(property "Reference" "C1774"
			(at 0 0 180)
			(layer "F.SilkS")
			(hide yes)
			(effects
				(font
					(size 1.27 1.27)
				)
			)
		)
		(property "Value" ""
			(at 0 0 180)
			(layer "F.Fab")
			(effects
				(font
					(size 1.27 1.27)
				)
			)
		)
		(duplicate_pad_numbers_are_jumpers no)
		(fp_line
			(start 0.7874 0.4064)
			(end -0.7874 0.4064)
			(stroke
				(width 0.1524)
				(type default)
			)
			(layer "F.SilkS")
		)
		(fp_line
			(start 0.7874 -0.4064)
			(end 0.7874 0.4064)
			(stroke
				(width 0.1524)
				(type default)
			)
			(layer "F.SilkS")
		)
		(fp_line
			(start -0.7874 0.4064)
			(end -0.7874 -0.4064)
			(stroke
				(width 0.1524)
				(type default)
			)
			(layer "F.SilkS")
		)
		(fp_line
			(start -0.7874 -0.4064)
			(end 0.7874 -0.4064)
			(stroke
				(width 0.1524)
				(type default)
			)
			(layer "F.SilkS")
		)
		(fp_line
			(start 0.67945 0.3048)
			(end 0.120396 0.3048)
			(stroke
				(width 0.1)
				(type default)
			)
			(layer "F.Fab")
		)
		(fp_line
			(start 0.67945 -0.3048)
			(end 0.67945 0.3048)
			(stroke
				(width 0.1)
				(type default)
			)
			(layer "F.Fab")
		)
		(fp_line
			(start 0.12065 -0.2794)
			(end 0.12065 -0.3048)
			(stroke
				(width 0.1)
				(type default)
			)
			(layer "F.Fab")
		)
		(fp_line
			(start 0.12065 -0.3048)
			(end 0.67945 -0.3048)
			(stroke
				(width 0.1)
				(type default)
			)
			(layer "F.Fab")
		)
		(fp_line
			(start 0.120396 0.3048)
			(end 0.120396 0.2794)
			(stroke
				(width 0.1)
				(type default)
			)
			(layer "F.Fab")
		)
		(fp_line
			(start 0.120396 0.2794)
			(end -0.12065 0.2794)
			(stroke
				(width 0.1)
				(type default)
			)
			(layer "F.Fab")
		)
		(fp_line
			(start -0.12065 0.3048)
			(end -0.67945 0.3048)
			(stroke
				(width 0.1)
				(type default)
			)
			(layer "F.Fab")
		)
		(fp_line
			(start -0.12065 0.2794)
			(end -0.12065 0.3048)
			(stroke
				(width 0.1)
				(type default)
			)
			(layer "F.Fab")
		)
		(fp_line
			(start -0.12065 -0.2794)
			(end 0.12065 -0.2794)
			(stroke
				(width 0.1)
				(type default)
			)
			(layer "F.Fab")
		)
		(fp_line
			(start -0.12065 -0.305054)
			(end -0.12065 -0.2794)
			(stroke
				(width 0.1)
				(type default)
			)
			(layer "F.Fab")
		)
		(fp_line
			(start -0.67945 0.3048)
			(end -0.67945 -0.305054)
			(stroke
				(width 0.1)
				(type default)
			)
			(layer "F.Fab")
		)
		(fp_line
			(start -0.67945 -0.305054)
			(end -0.12065 -0.305054)
			(stroke
				(width 0.1)
				(type default)
			)
			(layer "F.Fab")
		)
		(pad "1" smd circle
			(at -0.40005 0 180)
			(size 0 0)
			(layers "F.Cu" "F.Mask" "F.Paste")
			(net "FM_SWB_PWRGD_ISO")
		)
		(pad "2" smd circle
			(at 0.40005 0 180)
			(size 0 0)
			(layers "F.Cu" "F.Mask" "F.Paste")
			(net "GND")
		)
	)
	(footprint ""
		(layer "F.Cu")
		(at 421.15359 -172.113194 -90)
		(property "Reference" "PR1708"
			(at 0 0 270)
			(layer "F.SilkS")
			(hide yes)
			(effects
				(font
					(size 1.27 1.27)
				)
			)
		)
		(property "Value" ""
			(at 0 0 270)
			(layer "F.Fab")
			(effects
				(font
					(size 1.27 1.27)
				)
			)
		)
		(duplicate_pad_numbers_are_jumpers no)
		(fp_line
			(start -0.7874 0.4064)
			(end -0.7874 -0.4064)
			(stroke
				(width 0.1524)
				(type default)
			)
			(layer "F.SilkS")
		)
		(fp_line
			(start 0.7874 0.4064)
			(end -0.7874 0.4064)
			(stroke
				(width 0.1524)
				(type default)
			)
			(layer "F.SilkS")
		)
		(fp_line
			(start -0.7874 -0.4064)
			(end 0.7874 -0.4064)
			(stroke
				(width 0.1524)
				(type default)
			)
			(layer "F.SilkS")
		)
		(fp_line
			(start 0.7874 -0.4064)
			(end 0.7874 0.4064)
			(stroke
				(width 0.1524)
				(type default)
			)
			(layer "F.SilkS")
		)
		(fp_line
			(start -0.67945 0.3048)
			(end -0.67945 -0.305054)
			(stroke
				(width 0.1)
				(type default)
			)
			(layer "F.Fab")
		)
		(fp_line
			(start -0.12065 0.3048)
			(end -0.67945 0.3048)
			(stroke
				(width 0.1)
				(type default)
			)
			(layer "F.Fab")
		)
		(fp_line
			(start 0.120396 0.3048)
			(end 0.120396 0.2794)
			(stroke
				(width 0.1)
				(type default)
			)
			(layer "F.Fab")
		)
		(fp_line
			(start 0.67945 0.3048)
			(end 0.120396 0.3048)
			(stroke
				(width 0.1)
				(type default)
			)
			(layer "F.Fab")
		)
		(fp_line
			(start -0.12065 0.2794)
			(end -0.12065 0.3048)
			(stroke
				(width 0.1)
				(type default)
			)
			(layer "F.Fab")
		)
		(fp_line
			(start 0.120396 0.2794)
			(end -0.12065 0.2794)
			(stroke
				(width 0.1)
				(type default)
			)
			(layer "F.Fab")
		)
		(fp_line
			(start -0.12065 -0.2794)
			(end 0.12065 -0.2794)
			(stroke
				(width 0.1)
				(type default)
			)
			(layer "F.Fab")
		)
		(fp_line
			(start 0.12065 -0.2794)
			(end 0.12065 -0.3048)
			(stroke
				(width 0.1)
				(type default)
			)
			(layer "F.Fab")
		)
		(fp_line
			(start 0.12065 -0.3048)
			(end 0.67945 -0.3048)
			(stroke
				(width 0.1)
				(type default)
			)
			(layer "F.Fab")
		)
		(fp_line
			(start 0.67945 -0.3048)
			(end 0.67945 0.3048)
			(stroke
				(width 0.1)
				(type default)
			)
			(layer "F.Fab")
		)
		(fp_line
			(start -0.67945 -0.305054)
			(end -0.12065 -0.305054)
			(stroke
				(width 0.1)
				(type default)
			)
			(layer "F.Fab")
		)
		(fp_line
			(start -0.12065 -0.305054)
			(end -0.12065 -0.2794)
			(stroke
				(width 0.1)
				(type default)
			)
			(layer "F.Fab")
		)
		(pad "1" smd circle
			(at -0.40005 0 270)
			(size 0 0)
			(layers "F.Cu" "F.Mask" "F.Paste")
			(net "PVCCINFAON_CPU0_LSET1")
		)
		(pad "2" smd circle
			(at 0.40005 0 270)
			(size 0 0)
			(layers "F.Cu" "F.Mask" "F.Paste")
			(net "GND")
		)
	)
	(footprint ""
		(layer "F.Cu")
		(at 36.956238 -127.71374)
		(property "Reference" "C2451"
			(at 0 0 0)
			(layer "F.SilkS")
			(hide yes)
			(effects
				(font
					(size 1.27 1.27)
				)
			)
		)
		(property "Value" ""
			(at 0 0 0)
			(layer "F.Fab")
			(effects
				(font
					(size 1.27 1.27)
				)
			)
		)
		(duplicate_pad_numbers_are_jumpers no)
		(fp_line
			(start -0.7874 -0.4064)
			(end 0.7874 -0.4064)
			(stroke
				(width 0.1524)
				(type default)
			)
			(layer "F.SilkS")
		)
		(fp_line
			(start -0.7874 0.4064)
			(end -0.7874 -0.4064)
			(stroke
				(width 0.1524)
				(type default)
			)
			(layer "F.SilkS")
		)
		(fp_line
			(start 0.7874 -0.4064)
			(end 0.7874 0.4064)
			(stroke
				(width 0.1524)
				(type default)
			)
			(layer "F.SilkS")
		)
		(fp_line
			(start 0.7874 0.4064)
			(end -0.7874 0.4064)
			(stroke
				(width 0.1524)
				(type default)
			)
			(layer "F.SilkS")
		)
		(fp_line
			(start -0.67945 -0.305054)
			(end -0.12065 -0.305054)
			(stroke
				(width 0.1)
				(type default)
			)
			(layer "F.Fab")
		)
		(fp_line
			(start -0.67945 0.3048)
			(end -0.67945 -0.305054)
			(stroke
				(width 0.1)
				(type default)
			)
			(layer "F.Fab")
		)
		(fp_line
			(start -0.12065 -0.305054)
			(end -0.12065 -0.2794)
			(stroke
				(width 0.1)
				(type default)
			)
			(layer "F.Fab")
		)
		(fp_line
			(start -0.12065 -0.2794)
			(end 0.12065 -0.2794)
			(stroke
				(width 0.1)
				(type default)
			)
			(layer "F.Fab")
		)
		(fp_line
			(start -0.12065 0.2794)
			(end -0.12065 0.3048)
			(stroke
				(width 0.1)
				(type default)
			)
			(layer "F.Fab")
		)
		(fp_line
			(start -0.12065 0.3048)
			(end -0.67945 0.3048)
			(stroke
				(width 0.1)
				(type default)
			)
			(layer "F.Fab")
		)
		(fp_line
			(start 0.120396 0.2794)
			(end -0.12065 0.2794)
			(stroke
				(width 0.1)
				(type default)
			)
			(layer "F.Fab")
		)
		(fp_line
			(start 0.120396 0.3048)
			(end 0.120396 0.2794)
			(stroke
				(width 0.1)
				(type default)
			)
			(layer "F.Fab")
		)
		(fp_line
			(start 0.12065 -0.3048)
			(end 0.67945 -0.3048)
			(stroke
				(width 0.1)
				(type default)
			)
			(layer "F.Fab")
		)
		(fp_line
			(start 0.12065 -0.2794)
			(end 0.12065 -0.3048)
			(stroke
				(width 0.1)
				(type default)
			)
			(layer "F.Fab")
		)
		(fp_line
			(start 0.67945 -0.3048)
			(end 0.67945 0.3048)
			(stroke
				(width 0.1)
				(type default)
			)
			(layer "F.Fab")
		)
		(fp_line
			(start 0.67945 0.3048)
			(end 0.120396 0.3048)
			(stroke
				(width 0.1)
				(type default)
			)
			(layer "F.Fab")
		)
		(pad "1" smd circle
			(at -0.40005 0)
			(size 0 0)
			(layers "F.Cu" "F.Mask" "F.Paste")
			(net "PVCCINFAON_CPU1_EN_R")
		)
		(pad "2" smd circle
			(at 0.40005 0)
			(size 0 0)
			(layers "F.Cu" "F.Mask" "F.Paste")
			(net "GND")
		)
	)
	(footprint ""
		(layer "F.Cu")
		(at 461.53705 -41.002458)
		(property "Reference" "Q124"
			(at -3.73507 -2.576576 0)
			(unlocked yes)
			(layer "F.SilkS")
			(effects
				(font
					(size 0.7874 0.5842)
					(thickness 0.1524)
				)
				(justify left)
			)
		)
		(property "Value" ""
			(at 0 0 0)
			(layer "F.Fab")
			(effects
				(font
					(size 1.27 1.27)
				)
			)
		)
		(duplicate_pad_numbers_are_jumpers no)
		(fp_line
			(start -1.332738 -1.100074)
			(end -0.4826 -1.100074)
			(stroke
				(width 0.1524)
				(type default)
			)
			(layer "F.SilkS")
		)
		(fp_line
			(start -1.332738 1.100074)
			(end -1.332738 -1.100074)
			(stroke
				(width 0.1524)
				(type default)
			)
			(layer "F.SilkS")
		)
		(fp_line
			(start -0.4826 -1.100074)
			(end 0 -0.541274)
			(stroke
				(width 0.1524)
				(type default)
			)
			(layer "F.SilkS")
		)
		(fp_line
			(start 0 -0.541274)
			(end 0.4826 -1.100074)
			(stroke
				(width 0.1524)
				(type default)
			)
			(layer "F.SilkS")
		)
		(fp_line
			(start 0.4826 -1.100074)
			(end 1.332738 -1.100074)
			(stroke
				(width 0.1524)
				(type default)
			)
			(layer "F.SilkS")
		)
		(fp_line
			(start 1.332738 -1.100074)
			(end 1.332738 1.100074)
			(stroke
				(width 0.1524)
				(type default)
			)
			(layer "F.SilkS")
		)
		(fp_line
			(start 1.332738 1.100074)
			(end -1.332738 1.100074)
			(stroke
				(width 0.1524)
				(type default)
			)
			(layer "F.SilkS")
		)
		(fp_poly
			(pts
				(xy -0.672846 -2.01422) (xy -1.023874 -1.312164) (xy -1.374902 -2.01422)
			)
			(stroke
				(width 0)
				(type default)
			)
			(fill yes)
			(layer "F.SilkS")
		)
		(fp_line
			(start -0.674878 -1.100074)
			(end 0.674878 -1.100074)
			(stroke
				(width 0.1)
				(type default)
			)
			(layer "F.Fab")
		)
		(fp_line
			(start -0.674878 1.100074)
			(end -0.674878 -1.100074)
			(stroke
				(width 0.1)
				(type default)
			)
			(layer "F.Fab")
		)
		(fp_line
			(start 0.674878 -1.100074)
			(end 0.674878 1.100074)
			(stroke
				(width 0.1)
				(type default)
			)
			(layer "F.Fab")
		)
		(fp_line
			(start 0.674878 1.100074)
			(end -0.674878 1.100074)
			(stroke
				(width 0.1)
				(type default)
			)
			(layer "F.Fab")
		)
		(fp_poly
			(pts
				(xy -2.2352 -0.298958) (xy -2.2352 -1.001014) (xy -1.533144 -0.649986)
			)
			(stroke
				(width 0)
				(type default)
			)
			(fill yes)
			(layer "F.Fab")
		)
		(pad "1" smd rect
			(at -0.94996 -0.649986 90)
			(size 0.4318 0.508)
			(layers "F.Cu" "F.Mask" "F.Paste")
			(net "GND")
		)
		(pad "2" smd rect
			(at -0.94996 0 90)
			(size 0.4318 0.508)
			(layers "F.Cu" "F.Mask" "F.Paste")
			(net "P3V3_OCP_EN_1_R")
		)
		(pad "3" smd rect
			(at -0.94996 0.649986 90)
			(size 0.4318 0.508)
			(layers "F.Cu" "F.Mask" "F.Paste")
			(net "P3V3_OCP_UV_1_R1")
		)
		(pad "4" smd rect
			(at 0.94996 0.649986 90)
			(size 0.4318 0.508)
			(layers "F.Cu" "F.Mask" "F.Paste")
			(net "GND")
		)
		(pad "5" smd rect
			(at 0.94996 0 90)
			(size 0.4318 0.508)
			(layers "F.Cu" "F.Mask" "F.Paste")
			(net "P3V3_OCP_1_EN_G")
		)
		(pad "6" smd rect
			(at 0.94996 -0.649986 90)
			(size 0.4318 0.508)
			(layers "F.Cu" "F.Mask" "F.Paste")
			(net "P3V3_OCP_1_EN_G")
		)
	)
	(footprint ""
		(layer "F.Cu")
		(at 309.372 -23.7744 180)
		(property "Reference" "R4786"
			(at 0 0 180)
			(layer "F.SilkS")
			(hide yes)
			(effects
				(font
					(size 1.27 1.27)
				)
			)
		)
		(property "Value" ""
			(at 0 0 180)
			(layer "F.Fab")
			(effects
				(font
					(size 1.27 1.27)
				)
			)
		)
		(duplicate_pad_numbers_are_jumpers no)
		(fp_line
			(start 0.7874 0.4064)
			(end -0.7874 0.4064)
			(stroke
				(width 0.1524)
				(type default)
			)
			(layer "F.SilkS")
		)
		(fp_line
			(start 0.7874 -0.4064)
			(end 0.7874 0.4064)
			(stroke
				(width 0.1524)
				(type default)
			)
			(layer "F.SilkS")
		)
		(fp_line
			(start -0.7874 0.4064)
			(end -0.7874 -0.4064)
			(stroke
				(width 0.1524)
				(type default)
			)
			(layer "F.SilkS")
		)
		(fp_line
			(start -0.7874 -0.4064)
			(end 0.7874 -0.4064)
			(stroke
				(width 0.1524)
				(type default)
			)
			(layer "F.SilkS")
		)
		(fp_line
			(start 0.67945 0.3048)
			(end 0.120396 0.3048)
			(stroke
				(width 0.1)
				(type default)
			)
			(layer "F.Fab")
		)
		(fp_line
			(start 0.67945 -0.3048)
			(end 0.67945 0.3048)
			(stroke
				(width 0.1)
				(type default)
			)
			(layer "F.Fab")
		)
		(fp_line
			(start 0.12065 -0.2794)
			(end 0.12065 -0.3048)
			(stroke
				(width 0.1)
				(type default)
			)
			(layer "F.Fab")
		)
		(fp_line
			(start 0.12065 -0.3048)
			(end 0.67945 -0.3048)
			(stroke
				(width 0.1)
				(type default)
			)
			(layer "F.Fab")
		)
		(fp_line
			(start 0.120396 0.3048)
			(end 0.120396 0.2794)
			(stroke
				(width 0.1)
				(type default)
			)
			(layer "F.Fab")
		)
		(fp_line
			(start 0.120396 0.2794)
			(end -0.12065 0.2794)
			(stroke
				(width 0.1)
				(type default)
			)
			(layer "F.Fab")
		)
		(fp_line
			(start -0.12065 0.3048)
			(end -0.67945 0.3048)
			(stroke
				(width 0.1)
				(type default)
			)
			(layer "F.Fab")
		)
		(fp_line
			(start -0.12065 0.2794)
			(end -0.12065 0.3048)
			(stroke
				(width 0.1)
				(type default)
			)
			(layer "F.Fab")
		)
		(fp_line
			(start -0.12065 -0.2794)
			(end 0.12065 -0.2794)
			(stroke
				(width 0.1)
				(type default)
			)
			(layer "F.Fab")
		)
		(fp_line
			(start -0.12065 -0.305054)
			(end -0.12065 -0.2794)
			(stroke
				(width 0.1)
				(type default)
			)
			(layer "F.Fab")
		)
		(fp_line
			(start -0.67945 0.3048)
			(end -0.67945 -0.305054)
			(stroke
				(width 0.1)
				(type default)
			)
			(layer "F.Fab")
		)
		(fp_line
			(start -0.67945 -0.305054)
			(end -0.12065 -0.305054)
			(stroke
				(width 0.1)
				(type default)
			)
			(layer "F.Fab")
		)
		(pad "1" smd circle
			(at -0.40005 0 180)
			(size 0 0)
			(layers "F.Cu" "F.Mask" "F.Paste")
			(net "P3V3_AUX")
		)
		(pad "2" smd circle
			(at 0.40005 0 180)
			(size 0 0)
			(layers "F.Cu" "F.Mask" "F.Paste")
			(net "DSW_PWROK_P2V5_COMP")
		)
	)
	(footprint ""
		(layer "F.Cu")
		(at 355.216714 -256.654046 -90)
		(property "Reference" "C978"
			(at 0 0 270)
			(layer "F.SilkS")
			(hide yes)
			(effects
				(font
					(size 1.27 1.27)
				)
			)
		)
		(property "Value" ""
			(at 0 0 270)
			(layer "F.Fab")
			(effects
				(font
					(size 1.27 1.27)
				)
			)
		)
		(duplicate_pad_numbers_are_jumpers no)
		(fp_line
			(start -0.7874 0.4064)
			(end -0.7874 -0.4064)
			(stroke
				(width 0.1524)
				(type default)
			)
			(layer "F.SilkS")
		)
		(fp_line
			(start 0.7874 0.4064)
			(end -0.7874 0.4064)
			(stroke
				(width 0.1524)
				(type default)
			)
			(layer "F.SilkS")
		)
		(fp_line
			(start -0.7874 -0.4064)
			(end 0.7874 -0.4064)
			(stroke
				(width 0.1524)
				(type default)
			)
			(layer "F.SilkS")
		)
		(fp_line
			(start 0.7874 -0.4064)
			(end 0.7874 0.4064)
			(stroke
				(width 0.1524)
				(type default)
			)
			(layer "F.SilkS")
		)
		(fp_line
			(start -0.67945 0.3048)
			(end -0.67945 -0.305054)
			(stroke
				(width 0.1)
				(type default)
			)
			(layer "F.Fab")
		)
		(fp_line
			(start -0.12065 0.3048)
			(end -0.67945 0.3048)
			(stroke
				(width 0.1)
				(type default)
			)
			(layer "F.Fab")
		)
		(fp_line
			(start 0.120396 0.3048)
			(end 0.120396 0.2794)
			(stroke
				(width 0.1)
				(type default)
			)
			(layer "F.Fab")
		)
		(fp_line
			(start 0.67945 0.3048)
			(end 0.120396 0.3048)
			(stroke
				(width 0.1)
				(type default)
			)
			(layer "F.Fab")
		)
		(fp_line
			(start -0.12065 0.2794)
			(end -0.12065 0.3048)
			(stroke
				(width 0.1)
				(type default)
			)
			(layer "F.Fab")
		)
		(fp_line
			(start 0.120396 0.2794)
			(end -0.12065 0.2794)
			(stroke
				(width 0.1)
				(type default)
			)
			(layer "F.Fab")
		)
		(fp_line
			(start -0.12065 -0.2794)
			(end 0.12065 -0.2794)
			(stroke
				(width 0.1)
				(type default)
			)
			(layer "F.Fab")
		)
		(fp_line
			(start 0.12065 -0.2794)
			(end 0.12065 -0.3048)
			(stroke
				(width 0.1)
				(type default)
			)
			(layer "F.Fab")
		)
		(fp_line
			(start 0.12065 -0.3048)
			(end 0.67945 -0.3048)
			(stroke
				(width 0.1)
				(type default)
			)
			(layer "F.Fab")
		)
		(fp_line
			(start 0.67945 -0.3048)
			(end 0.67945 0.3048)
			(stroke
				(width 0.1)
				(type default)
			)
			(layer "F.Fab")
		)
		(fp_line
			(start -0.67945 -0.305054)
			(end -0.12065 -0.305054)
			(stroke
				(width 0.1)
				(type default)
			)
			(layer "F.Fab")
		)
		(fp_line
			(start -0.12065 -0.305054)
			(end -0.12065 -0.2794)
			(stroke
				(width 0.1)
				(type default)
			)
			(layer "F.Fab")
		)
		(pad "1" smd circle
			(at -0.40005 0 270)
			(size 0 0)
			(layers "F.Cu" "F.Mask" "F.Paste")
			(net "PVCCIN_CPU0")
		)
		(pad "2" smd circle
			(at 0.40005 0 270)
			(size 0 0)
			(layers "F.Cu" "F.Mask" "F.Paste")
			(net "GND")
		)
	)
	(footprint ""
		(layer "F.Cu")
		(at 453.719946 -106.408728)
		(property "Reference" "R1907"
			(at 0 0 0)
			(layer "F.SilkS")
			(hide yes)
			(effects
				(font
					(size 1.27 1.27)
				)
			)
		)
		(property "Value" ""
			(at 0 0 0)
			(layer "F.Fab")
			(effects
				(font
					(size 1.27 1.27)
				)
			)
		)
		(duplicate_pad_numbers_are_jumpers no)
		(fp_line
			(start -0.7874 -0.4064)
			(end 0.7874 -0.4064)
			(stroke
				(width 0.1524)
				(type default)
			)
			(layer "F.SilkS")
		)
		(fp_line
			(start -0.7874 0.4064)
			(end -0.7874 -0.4064)
			(stroke
				(width 0.1524)
				(type default)
			)
			(layer "F.SilkS")
		)
		(fp_line
			(start 0.7874 -0.4064)
			(end 0.7874 0.4064)
			(stroke
				(width 0.1524)
				(type default)
			)
			(layer "F.SilkS")
		)
		(fp_line
			(start 0.7874 0.4064)
			(end -0.7874 0.4064)
			(stroke
				(width 0.1524)
				(type default)
			)
			(layer "F.SilkS")
		)
		(fp_line
			(start -0.67945 -0.305054)
			(end -0.12065 -0.305054)
			(stroke
				(width 0.1)
				(type default)
			)
			(layer "F.Fab")
		)
		(fp_line
			(start -0.67945 0.3048)
			(end -0.67945 -0.305054)
			(stroke
				(width 0.1)
				(type default)
			)
			(layer "F.Fab")
		)
		(fp_line
			(start -0.12065 -0.305054)
			(end -0.12065 -0.2794)
			(stroke
				(width 0.1)
				(type default)
			)
			(layer "F.Fab")
		)
		(fp_line
			(start -0.12065 -0.2794)
			(end 0.12065 -0.2794)
			(stroke
				(width 0.1)
				(type default)
			)
			(layer "F.Fab")
		)
		(fp_line
			(start -0.12065 0.2794)
			(end -0.12065 0.3048)
			(stroke
				(width 0.1)
				(type default)
			)
			(layer "F.Fab")
		)
		(fp_line
			(start -0.12065 0.3048)
			(end -0.67945 0.3048)
			(stroke
				(width 0.1)
				(type default)
			)
			(layer "F.Fab")
		)
		(fp_line
			(start 0.120396 0.2794)
			(end -0.12065 0.2794)
			(stroke
				(width 0.1)
				(type default)
			)
			(layer "F.Fab")
		)
		(fp_line
			(start 0.120396 0.3048)
			(end 0.120396 0.2794)
			(stroke
				(width 0.1)
				(type default)
			)
			(layer "F.Fab")
		)
		(fp_line
			(start 0.12065 -0.3048)
			(end 0.67945 -0.3048)
			(stroke
				(width 0.1)
				(type default)
			)
			(layer "F.Fab")
		)
		(fp_line
			(start 0.12065 -0.2794)
			(end 0.12065 -0.3048)
			(stroke
				(width 0.1)
				(type default)
			)
			(layer "F.Fab")
		)
		(fp_line
			(start 0.67945 -0.3048)
			(end 0.67945 0.3048)
			(stroke
				(width 0.1)
				(type default)
			)
			(layer "F.Fab")
		)
		(fp_line
			(start 0.67945 0.3048)
			(end 0.120396 0.3048)
			(stroke
				(width 0.1)
				(type default)
			)
			(layer "F.Fab")
		)
		(pad "1" smd circle
			(at -0.40005 0)
			(size 0 0)
			(layers "F.Cu" "F.Mask" "F.Paste")
			(net "P3V3_AUX")
		)
		(pad "2" smd circle
			(at 0.40005 0)
			(size 0 0)
			(layers "F.Cu" "F.Mask" "F.Paste")
			(net "OCP_SFF_PRSNT1_R_N")
		)
	)
	(footprint ""
		(layer "F.Cu")
		(at 123.19508 -106.238548 -90)
		(property "Reference" "R4047"
			(at 0 0 270)
			(layer "F.SilkS")
			(hide yes)
			(effects
				(font
					(size 1.27 1.27)
				)
			)
		)
		(property "Value" ""
			(at 0 0 270)
			(layer "F.Fab")
			(effects
				(font
					(size 1.27 1.27)
				)
			)
		)
		(duplicate_pad_numbers_are_jumpers no)
		(fp_line
			(start -0.7874 0.4064)
			(end -0.7874 -0.4064)
			(stroke
				(width 0.1524)
				(type default)
			)
			(layer "F.SilkS")
		)
		(fp_line
			(start 0.7874 0.4064)
			(end -0.7874 0.4064)
			(stroke
				(width 0.1524)
				(type default)
			)
			(layer "F.SilkS")
		)
		(fp_line
			(start -0.7874 -0.4064)
			(end 0.7874 -0.4064)
			(stroke
				(width 0.1524)
				(type default)
			)
			(layer "F.SilkS")
		)
		(fp_line
			(start 0.7874 -0.4064)
			(end 0.7874 0.4064)
			(stroke
				(width 0.1524)
				(type default)
			)
			(layer "F.SilkS")
		)
		(fp_line
			(start -0.67945 0.3048)
			(end -0.67945 -0.305054)
			(stroke
				(width 0.1)
				(type default)
			)
			(layer "F.Fab")
		)
		(fp_line
			(start -0.12065 0.3048)
			(end -0.67945 0.3048)
			(stroke
				(width 0.1)
				(type default)
			)
			(layer "F.Fab")
		)
		(fp_line
			(start 0.120396 0.3048)
			(end 0.120396 0.2794)
			(stroke
				(width 0.1)
				(type default)
			)
			(layer "F.Fab")
		)
		(fp_line
			(start 0.67945 0.3048)
			(end 0.120396 0.3048)
			(stroke
				(width 0.1)
				(type default)
			)
			(layer "F.Fab")
		)
		(fp_line
			(start -0.12065 0.2794)
			(end -0.12065 0.3048)
			(stroke
				(width 0.1)
				(type default)
			)
			(layer "F.Fab")
		)
		(fp_line
			(start 0.120396 0.2794)
			(end -0.12065 0.2794)
			(stroke
				(width 0.1)
				(type default)
			)
			(layer "F.Fab")
		)
		(fp_line
			(start -0.12065 -0.2794)
			(end 0.12065 -0.2794)
			(stroke
				(width 0.1)
				(type default)
			)
			(layer "F.Fab")
		)
		(fp_line
			(start 0.12065 -0.2794)
			(end 0.12065 -0.3048)
			(stroke
				(width 0.1)
				(type default)
			)
			(layer "F.Fab")
		)
		(fp_line
			(start 0.12065 -0.3048)
			(end 0.67945 -0.3048)
			(stroke
				(width 0.1)
				(type default)
			)
			(layer "F.Fab")
		)
		(fp_line
			(start 0.67945 -0.3048)
			(end 0.67945 0.3048)
			(stroke
				(width 0.1)
				(type default)
			)
			(layer "F.Fab")
		)
		(fp_line
			(start -0.67945 -0.305054)
			(end -0.12065 -0.305054)
			(stroke
				(width 0.1)
				(type default)
			)
			(layer "F.Fab")
		)
		(fp_line
			(start -0.12065 -0.305054)
			(end -0.12065 -0.2794)
			(stroke
				(width 0.1)
				(type default)
			)
			(layer "F.Fab")
		)
		(pad "1" smd circle
			(at -0.40005 0 270)
			(size 0 0)
			(layers "F.Cu" "F.Mask" "F.Paste")
			(net "RST_CPU1_DRAM_CD_PLD_LVT3_R_N")
		)
		(pad "2" smd circle
			(at 0.40005 0 270)
			(size 0 0)
			(layers "F.Cu" "F.Mask" "F.Paste")
			(net "RST_CPU1_DRAM_CD_PLD_LVT3_N")
		)
	)
	(footprint ""
		(layer "F.Cu")
		(at 115.75288 -101.793548 -90)
		(property "Reference" "R4016"
			(at 0 0 270)
			(layer "F.SilkS")
			(hide yes)
			(effects
				(font
					(size 1.27 1.27)
				)
			)
		)
		(property "Value" ""
			(at 0 0 270)
			(layer "F.Fab")
			(effects
				(font
					(size 1.27 1.27)
				)
			)
		)
		(duplicate_pad_numbers_are_jumpers no)
		(fp_line
			(start -0.7874 0.4064)
			(end -0.7874 -0.4064)
			(stroke
				(width 0.1524)
				(type default)
			)
			(layer "F.SilkS")
		)
		(fp_line
			(start 0.7874 0.4064)
			(end -0.7874 0.4064)
			(stroke
				(width 0.1524)
				(type default)
			)
			(layer "F.SilkS")
		)
		(fp_line
			(start -0.7874 -0.4064)
			(end 0.7874 -0.4064)
			(stroke
				(width 0.1524)
				(type default)
			)
			(layer "F.SilkS")
		)
		(fp_line
			(start 0.7874 -0.4064)
			(end 0.7874 0.4064)
			(stroke
				(width 0.1524)
				(type default)
			)
			(layer "F.SilkS")
		)
		(fp_line
			(start -0.67945 0.3048)
			(end -0.67945 -0.305054)
			(stroke
				(width 0.1)
				(type default)
			)
			(layer "F.Fab")
		)
		(fp_line
			(start -0.12065 0.3048)
			(end -0.67945 0.3048)
			(stroke
				(width 0.1)
				(type default)
			)
			(layer "F.Fab")
		)
		(fp_line
			(start 0.120396 0.3048)
			(end 0.120396 0.2794)
			(stroke
				(width 0.1)
				(type default)
			)
			(layer "F.Fab")
		)
		(fp_line
			(start 0.67945 0.3048)
			(end 0.120396 0.3048)
			(stroke
				(width 0.1)
				(type default)
			)
			(layer "F.Fab")
		)
		(fp_line
			(start -0.12065 0.2794)
			(end -0.12065 0.3048)
			(stroke
				(width 0.1)
				(type default)
			)
			(layer "F.Fab")
		)
		(fp_line
			(start 0.120396 0.2794)
			(end -0.12065 0.2794)
			(stroke
				(width 0.1)
				(type default)
			)
			(layer "F.Fab")
		)
		(fp_line
			(start -0.12065 -0.2794)
			(end 0.12065 -0.2794)
			(stroke
				(width 0.1)
				(type default)
			)
			(layer "F.Fab")
		)
		(fp_line
			(start 0.12065 -0.2794)
			(end 0.12065 -0.3048)
			(stroke
				(width 0.1)
				(type default)
			)
			(layer "F.Fab")
		)
		(fp_line
			(start 0.12065 -0.3048)
			(end 0.67945 -0.3048)
			(stroke
				(width 0.1)
				(type default)
			)
			(layer "F.Fab")
		)
		(fp_line
			(start 0.67945 -0.3048)
			(end 0.67945 0.3048)
			(stroke
				(width 0.1)
				(type default)
			)
			(layer "F.Fab")
		)
		(fp_line
			(start -0.67945 -0.305054)
			(end -0.12065 -0.305054)
			(stroke
				(width 0.1)
				(type default)
			)
			(layer "F.Fab")
		)
		(fp_line
			(start -0.12065 -0.305054)
			(end -0.12065 -0.2794)
			(stroke
				(width 0.1)
				(type default)
			)
			(layer "F.Fab")
		)
		(pad "1" smd circle
			(at -0.40005 0 270)
			(size 0 0)
			(layers "F.Cu" "F.Mask" "F.Paste")
			(net "P3V3")
		)
		(pad "2" smd circle
			(at 0.40005 0 270)
			(size 0 0)
			(layers "F.Cu" "F.Mask" "F.Paste")
			(net "P0V62_CPU0_ERRS_VREF")
		)
	)
	(footprint ""
		(layer "F.Cu")
		(at 388.278116 -14.25321 90)
		(property "Reference" "R444"
			(at 0 0 90)
			(layer "F.SilkS")
			(hide yes)
			(effects
				(font
					(size 1.27 1.27)
				)
			)
		)
		(property "Value" ""
			(at 0 0 90)
			(layer "F.Fab")
			(effects
				(font
					(size 1.27 1.27)
				)
			)
		)
		(duplicate_pad_numbers_are_jumpers no)
		(fp_line
			(start 0.7874 -0.4064)
			(end 0.7874 0.4064)
			(stroke
				(width 0.1524)
				(type default)
			)
			(layer "F.SilkS")
		)
		(fp_line
			(start -0.7874 -0.4064)
			(end 0.7874 -0.4064)
			(stroke
				(width 0.1524)
				(type default)
			)
			(layer "F.SilkS")
		)
		(fp_line
			(start 0.7874 0.4064)
			(end -0.7874 0.4064)
			(stroke
				(width 0.1524)
				(type default)
			)
			(layer "F.SilkS")
		)
		(fp_line
			(start -0.7874 0.4064)
			(end -0.7874 -0.4064)
			(stroke
				(width 0.1524)
				(type default)
			)
			(layer "F.SilkS")
		)
		(fp_line
			(start -0.12065 -0.305054)
			(end -0.12065 -0.2794)
			(stroke
				(width 0.1)
				(type default)
			)
			(layer "F.Fab")
		)
		(fp_line
			(start -0.67945 -0.305054)
			(end -0.12065 -0.305054)
			(stroke
				(width 0.1)
				(type default)
			)
			(layer "F.Fab")
		)
		(fp_line
			(start 0.67945 -0.3048)
			(end 0.67945 0.3048)
			(stroke
				(width 0.1)
				(type default)
			)
			(layer "F.Fab")
		)
		(fp_line
			(start 0.12065 -0.3048)
			(end 0.67945 -0.3048)
			(stroke
				(width 0.1)
				(type default)
			)
			(layer "F.Fab")
		)
		(fp_line
			(start 0.12065 -0.2794)
			(end 0.12065 -0.3048)
			(stroke
				(width 0.1)
				(type default)
			)
			(layer "F.Fab")
		)
		(fp_line
			(start -0.12065 -0.2794)
			(end 0.12065 -0.2794)
			(stroke
				(width 0.1)
				(type default)
			)
			(layer "F.Fab")
		)
		(fp_line
			(start 0.120396 0.2794)
			(end -0.12065 0.2794)
			(stroke
				(width 0.1)
				(type default)
			)
			(layer "F.Fab")
		)
		(fp_line
			(start -0.12065 0.2794)
			(end -0.12065 0.3048)
			(stroke
				(width 0.1)
				(type default)
			)
			(layer "F.Fab")
		)
		(fp_line
			(start 0.67945 0.3048)
			(end 0.120396 0.3048)
			(stroke
				(width 0.1)
				(type default)
			)
			(layer "F.Fab")
		)
		(fp_line
			(start 0.120396 0.3048)
			(end 0.120396 0.2794)
			(stroke
				(width 0.1)
				(type default)
			)
			(layer "F.Fab")
		)
		(fp_line
			(start -0.12065 0.3048)
			(end -0.67945 0.3048)
			(stroke
				(width 0.1)
				(type default)
			)
			(layer "F.Fab")
		)
		(fp_line
			(start -0.67945 0.3048)
			(end -0.67945 -0.305054)
			(stroke
				(width 0.1)
				(type default)
			)
			(layer "F.Fab")
		)
		(pad "1" smd circle
			(at -0.40005 0 90)
			(size 0 0)
			(layers "F.Cu" "F.Mask" "F.Paste")
			(net "OCP_SFF_USB2_3_DN")
		)
		(pad "2" smd circle
			(at 0.40005 0 90)
			(size 0 0)
			(layers "F.Cu" "F.Mask" "F.Paste")
			(net "USB2_3_DN")
		)
	)
	(footprint ""
		(layer "F.Cu")
		(at 120.326658 -15.526766)
		(property "Reference" "R4193"
			(at 0 0 0)
			(layer "F.SilkS")
			(hide yes)
			(effects
				(font
					(size 1.27 1.27)
				)
			)
		)
		(property "Value" ""
			(at 0 0 0)
			(layer "F.Fab")
			(effects
				(font
					(size 1.27 1.27)
				)
			)
		)
		(duplicate_pad_numbers_are_jumpers no)
		(fp_line
			(start -0.7874 -0.4064)
			(end 0.7874 -0.4064)
			(stroke
				(width 0.1524)
				(type default)
			)
			(layer "F.SilkS")
		)
		(fp_line
			(start -0.7874 0.4064)
			(end -0.7874 -0.4064)
			(stroke
				(width 0.1524)
				(type default)
			)
			(layer "F.SilkS")
		)
		(fp_line
			(start 0.7874 -0.4064)
			(end 0.7874 0.4064)
			(stroke
				(width 0.1524)
				(type default)
			)
			(layer "F.SilkS")
		)
		(fp_line
			(start 0.7874 0.4064)
			(end -0.7874 0.4064)
			(stroke
				(width 0.1524)
				(type default)
			)
			(layer "F.SilkS")
		)
		(fp_line
			(start -0.67945 -0.305054)
			(end -0.12065 -0.305054)
			(stroke
				(width 0.1)
				(type default)
			)
			(layer "F.Fab")
		)
		(fp_line
			(start -0.67945 0.3048)
			(end -0.67945 -0.305054)
			(stroke
				(width 0.1)
				(type default)
			)
			(layer "F.Fab")
		)
		(fp_line
			(start -0.12065 -0.305054)
			(end -0.12065 -0.2794)
			(stroke
				(width 0.1)
				(type default)
			)
			(layer "F.Fab")
		)
		(fp_line
			(start -0.12065 -0.2794)
			(end 0.12065 -0.2794)
			(stroke
				(width 0.1)
				(type default)
			)
			(layer "F.Fab")
		)
		(fp_line
			(start -0.12065 0.2794)
			(end -0.12065 0.3048)
			(stroke
				(width 0.1)
				(type default)
			)
			(layer "F.Fab")
		)
		(fp_line
			(start -0.12065 0.3048)
			(end -0.67945 0.3048)
			(stroke
				(width 0.1)
				(type default)
			)
			(layer "F.Fab")
		)
		(fp_line
			(start 0.120396 0.2794)
			(end -0.12065 0.2794)
			(stroke
				(width 0.1)
				(type default)
			)
			(layer "F.Fab")
		)
		(fp_line
			(start 0.120396 0.3048)
			(end 0.120396 0.2794)
			(stroke
				(width 0.1)
				(type default)
			)
			(layer "F.Fab")
		)
		(fp_line
			(start 0.12065 -0.3048)
			(end 0.67945 -0.3048)
			(stroke
				(width 0.1)
				(type default)
			)
			(layer "F.Fab")
		)
		(fp_line
			(start 0.12065 -0.2794)
			(end 0.12065 -0.3048)
			(stroke
				(width 0.1)
				(type default)
			)
			(layer "F.Fab")
		)
		(fp_line
			(start 0.67945 -0.3048)
			(end 0.67945 0.3048)
			(stroke
				(width 0.1)
				(type default)
			)
			(layer "F.Fab")
		)
		(fp_line
			(start 0.67945 0.3048)
			(end 0.120396 0.3048)
			(stroke
				(width 0.1)
				(type default)
			)
			(layer "F.Fab")
		)
		(pad "1" smd circle
			(at -0.40005 0)
			(size 0 0)
			(layers "F.Cu" "F.Mask" "F.Paste")
			(net "U273_3_ADD1")
		)
		(pad "2" smd circle
			(at 0.40005 0)
			(size 0 0)
			(layers "F.Cu" "F.Mask" "F.Paste")
			(net "GND")
		)
	)
	(footprint ""
		(layer "F.Cu")
		(at 438.978548 -258.091686)
		(property "Reference" "J14"
			(at -3.683 -81.702148 0)
			(unlocked yes)
			(layer "F.SilkS")
			(effects
				(font
					(size 0.7874 0.5842)
					(thickness 0.1524)
				)
				(justify left)
			)
		)
		(property "Value" ""
			(at 0 0 0)
			(layer "F.Fab")
			(effects
				(font
					(size 1.27 1.27)
				)
			)
		)
		(duplicate_pad_numbers_are_jumpers no)
		(fp_line
			(start -3.24993 -81.000092)
			(end -3.24993 75.315318)
			(stroke
				(width 0.1524)
				(type default)
			)
			(layer "F.SilkS")
		)
		(fp_line
			(start -3.24993 80.181958)
			(end -3.24993 81.000092)
			(stroke
				(width 0.1524)
				(type default)
			)
			(layer "F.SilkS")
		)
		(fp_line
			(start -3.24993 81.000092)
			(end 3.24993 81.000092)
			(stroke
				(width 0.1524)
				(type default)
			)
			(layer "F.SilkS")
		)
		(fp_line
			(start 3.24993 -81.000092)
			(end -3.24993 -81.000092)
			(stroke
				(width 0.1524)
				(type default)
			)
			(layer "F.SilkS")
		)
		(fp_line
			(start 3.24993 -80.267302)
			(end 3.24993 -81.000092)
			(stroke
				(width 0.1524)
				(type default)
			)
			(layer "F.SilkS")
		)
		(fp_line
			(start 3.24993 -72.00011)
			(end -3.24993 -72.00011)
			(stroke
				(width 0.1524)
				(type default)
			)
			(layer "F.SilkS")
		)
		(fp_line
			(start 3.24993 72.00011)
			(end -3.24993 72.00011)
			(stroke
				(width 0.1524)
				(type default)
			)
			(layer "F.SilkS")
		)
		(fp_line
			(start 3.24993 81.000092)
			(end 3.24993 -74.760582)
			(stroke
				(width 0.1524)
				(type default)
			)
			(layer "F.SilkS")
		)
		(fp_poly
			(pts
				(xy -4.154424 -63.74765) (xy -3.364992 -63.352934) (xy -4.154424 -62.958218)
			)
			(stroke
				(width 0)
				(type default)
			)
			(fill yes)
			(layer "F.SilkS")
		)
		(fp_line
			(start -3.24993 -81.000092)
			(end -3.24993 81.000092)
			(stroke
				(width 0.1)
				(type default)
			)
			(layer "F.Fab")
		)
		(fp_line
			(start -3.24993 81.000092)
			(end 3.24993 81.000092)
			(stroke
				(width 0.1)
				(type default)
			)
			(layer "F.Fab")
		)
		(fp_line
			(start 3.24993 -81.000092)
			(end -3.24993 -81.000092)
			(stroke
				(width 0.1)
				(type default)
			)
			(layer "F.Fab")
		)
		(fp_line
			(start 3.24993 -72.00011)
			(end -3.24993 -72.00011)
			(stroke
				(width 0.1)
				(type default)
			)
			(layer "F.Fab")
		)
		(fp_line
			(start 3.24993 -71.000112)
			(end -3.24993 -71.000112)
			(stroke
				(width 0.1)
				(type default)
			)
			(layer "F.Fab")
		)
		(fp_line
			(start 3.24993 71.000112)
			(end -3.24993 71.000112)
			(stroke
				(width 0.1)
				(type default)
			)
			(layer "F.Fab")
		)
		(fp_line
			(start 3.24993 72.00011)
			(end -3.24993 72.00011)
			(stroke
				(width 0.1)
				(type default)
			)
			(layer "F.Fab")
		)
		(fp_line
			(start 3.24993 81.000092)
			(end 3.24993 -81.000092)
			(stroke
				(width 0.1)
				(type default)
			)
			(layer "F.Fab")
		)
		(fp_poly
			(pts
				(xy -4.445 -63.832994) (xy -4.445 -62.816994) (xy -3.429 -63.324994)
			)
			(stroke
				(width 0)
				(type default)
			)
			(fill yes)
			(layer "F.Fab")
		)
		(pad "1" smd rect
			(at -2.050034 -63.324994 270)
			(size 0.519938 1.4986)
			(layers "F.Cu" "F.Mask" "F.Paste")
			(net "P12V_S3_AUX_CPU0_NVDIMM")
		)
		(pad "2" smd rect
			(at -2.050034 -62.47511 270)
			(size 0.519938 1.4986)
			(layers "F.Cu" "F.Mask" "F.Paste")
			(net "TP_CHG_CPU0_DIMM2_FRU_0")
		)
		(pad "3" smd rect
			(at -2.050034 -61.624972 270)
			(size 0.519938 1.4986)
			(layers "F.Cu" "F.Mask" "F.Paste")
			(net "P3V3_AUX")
		)
		(pad "4" smd rect
			(at -2.050034 -60.775088 270)
			(size 0.519938 1.4986)
			(layers "F.Cu" "F.Mask" "F.Paste")
			(net "I3C_SPD_DDREFGH_CPU0_LVC1_SCL_5")
		)
		(pad "5" smd rect
			(at -2.050034 -59.92495 270)
			(size 0.519938 1.4986)
			(layers "F.Cu" "F.Mask" "F.Paste")
			(net "I3C_SPD_DDREFGH_CPU0_LVC1_SDA")
		)
		(pad "6" smd rect
			(at -2.050034 -59.075066 270)
			(size 0.519938 1.4986)
			(layers "F.Cu" "F.Mask" "F.Paste")
			(net "GND")
		)
		(pad "7" smd rect
			(at -2.050034 -58.224928 270)
			(size 0.519938 1.4986)
			(layers "F.Cu" "F.Mask" "F.Paste")
			(net "M_G_CPU0_SA_DQ<0>")
		)
		(pad "8" smd rect
			(at -2.050034 -57.375044 270)
			(size 0.519938 1.4986)
			(layers "F.Cu" "F.Mask" "F.Paste")
			(net "GND")
		)
		(pad "9" smd rect
			(at -2.050034 -56.524906 270)
			(size 0.519938 1.4986)
			(layers "F.Cu" "F.Mask" "F.Paste")
			(net "M_G_CPU0_SA_DQ<1>")
		)
		(pad "10" smd rect
			(at -2.050034 -55.675022 270)
			(size 0.519938 1.4986)
			(layers "F.Cu" "F.Mask" "F.Paste")
			(net "GND")
		)
		(pad "11" smd rect
			(at -2.050034 -54.824884 270)
			(size 0.519938 1.4986)
			(layers "F.Cu" "F.Mask" "F.Paste")
			(net "M_G_CPU0_SA_DQS_DP<0>")
		)
		(pad "12" smd rect
			(at -2.050034 -53.975 270)
			(size 0.519938 1.4986)
			(layers "F.Cu" "F.Mask" "F.Paste")
			(net "M_G_CPU0_SA_DQS_DN<0>")
		)
		(pad "13" smd rect
			(at -2.050034 -53.125116 270)
			(size 0.519938 1.4986)
			(layers "F.Cu" "F.Mask" "F.Paste")
			(net "GND")
		)
		(pad "14" smd rect
			(at -2.050034 -52.274978 270)
			(size 0.519938 1.4986)
			(layers "F.Cu" "F.Mask" "F.Paste")
			(net "M_G_CPU0_SA_DQ<4>")
		)
		(pad "15" smd rect
			(at -2.050034 -51.425094 270)
			(size 0.519938 1.4986)
			(layers "F.Cu" "F.Mask" "F.Paste")
			(net "GND")
		)
		(pad "16" smd rect
			(at -2.050034 -50.574956 270)
			(size 0.519938 1.4986)
			(layers "F.Cu" "F.Mask" "F.Paste")
			(net "M_G_CPU0_SA_DQ<5>")
		)
		(pad "17" smd rect
			(at -2.050034 -49.725072 270)
			(size 0.519938 1.4986)
			(layers "F.Cu" "F.Mask" "F.Paste")
			(net "GND")
		)
		(pad "18" smd rect
			(at -2.050034 -48.874934 270)
			(size 0.519938 1.4986)
			(layers "F.Cu" "F.Mask" "F.Paste")
			(net "M_G_CPU0_SA_DQ<8>")
		)
		(pad "19" smd rect
			(at -2.050034 -48.02505 270)
			(size 0.519938 1.4986)
			(layers "F.Cu" "F.Mask" "F.Paste")
			(net "GND")
		)
		(pad "20" smd rect
			(at -2.050034 -47.174912 270)
			(size 0.519938 1.4986)
			(layers "F.Cu" "F.Mask" "F.Paste")
			(net "M_G_CPU0_SA_DQ<9>")
		)
		(pad "21" smd rect
			(at -2.050034 -46.325028 270)
			(size 0.519938 1.4986)
			(layers "F.Cu" "F.Mask" "F.Paste")
			(net "GND")
		)
		(pad "22" smd rect
			(at -2.050034 -45.47489 270)
			(size 0.519938 1.4986)
			(layers "F.Cu" "F.Mask" "F.Paste")
			(net "M_G_CPU0_SA_DQS_DP<1>")
		)
		(pad "23" smd rect
			(at -2.050034 -44.625006 270)
			(size 0.519938 1.4986)
			(layers "F.Cu" "F.Mask" "F.Paste")
			(net "M_G_CPU0_SA_DQS_DN<1>")
		)
		(pad "24" smd rect
			(at -2.050034 -43.775122 270)
			(size 0.519938 1.4986)
			(layers "F.Cu" "F.Mask" "F.Paste")
			(net "GND")
		)
		(pad "25" smd rect
			(at -2.050034 -42.924984 270)
			(size 0.519938 1.4986)
			(layers "F.Cu" "F.Mask" "F.Paste")
			(net "M_G_CPU0_SA_DQ<12>")
		)
		(pad "26" smd rect
			(at -2.050034 -42.0751 270)
			(size 0.519938 1.4986)
			(layers "F.Cu" "F.Mask" "F.Paste")
			(net "GND")
		)
		(pad "27" smd rect
			(at -2.050034 -41.224962 270)
			(size 0.519938 1.4986)
			(layers "F.Cu" "F.Mask" "F.Paste")
			(net "M_G_CPU0_SA_DQ<13>")
		)
		(pad "28" smd rect
			(at -2.050034 -40.375078 270)
			(size 0.519938 1.4986)
			(layers "F.Cu" "F.Mask" "F.Paste")
			(net "GND")
		)
		(pad "29" smd rect
			(at -2.050034 -39.52494 270)
			(size 0.519938 1.4986)
			(layers "F.Cu" "F.Mask" "F.Paste")
			(net "M_G_CPU0_SA_DQ<16>")
		)
		(pad "30" smd rect
			(at -2.050034 -38.675056 270)
			(size 0.519938 1.4986)
			(layers "F.Cu" "F.Mask" "F.Paste")
			(net "GND")
		)
		(pad "31" smd rect
			(at -2.050034 -37.824918 270)
			(size 0.519938 1.4986)
			(layers "F.Cu" "F.Mask" "F.Paste")
			(net "M_G_CPU0_SA_DQ<17>")
		)
		(pad "32" smd rect
			(at -2.050034 -36.975034 270)
			(size 0.519938 1.4986)
			(layers "F.Cu" "F.Mask" "F.Paste")
			(net "GND")
		)
		(pad "33" smd rect
			(at -2.050034 -36.124896 270)
			(size 0.519938 1.4986)
			(layers "F.Cu" "F.Mask" "F.Paste")
			(net "M_G_CPU0_SA_DQS_DP<2>")
		)
		(pad "34" smd rect
			(at -2.050034 -35.275012 270)
			(size 0.519938 1.4986)
			(layers "F.Cu" "F.Mask" "F.Paste")
			(net "M_G_CPU0_SA_DQS_DN<2>")
		)
		(pad "35" smd rect
			(at -2.050034 -34.425128 270)
			(size 0.519938 1.4986)
			(layers "F.Cu" "F.Mask" "F.Paste")
			(net "GND")
		)
		(pad "36" smd rect
			(at -2.050034 -33.57499 270)
			(size 0.519938 1.4986)
			(layers "F.Cu" "F.Mask" "F.Paste")
			(net "M_G_CPU0_SA_DQ<20>")
		)
		(pad "37" smd rect
			(at -2.050034 -32.725106 270)
			(size 0.519938 1.4986)
			(layers "F.Cu" "F.Mask" "F.Paste")
			(net "GND")
		)
		(pad "38" smd rect
			(at -2.050034 -31.874968 270)
			(size 0.519938 1.4986)
			(layers "F.Cu" "F.Mask" "F.Paste")
			(net "M_G_CPU0_SA_DQ<21>")
		)
		(pad "39" smd rect
			(at -2.050034 -31.025084 270)
			(size 0.519938 1.4986)
			(layers "F.Cu" "F.Mask" "F.Paste")
			(net "GND")
		)
		(pad "40" smd rect
			(at -2.050034 -30.174946 270)
			(size 0.519938 1.4986)
			(layers "F.Cu" "F.Mask" "F.Paste")
			(net "M_G_CPU0_SA_DQ<24>")
		)
		(pad "41" smd rect
			(at -2.050034 -29.325062 270)
			(size 0.519938 1.4986)
			(layers "F.Cu" "F.Mask" "F.Paste")
			(net "GND")
		)
		(pad "42" smd rect
			(at -2.050034 -28.474924 270)
			(size 0.519938 1.4986)
			(layers "F.Cu" "F.Mask" "F.Paste")
			(net "M_G_CPU0_SA_DQ<25>")
		)
		(pad "43" smd rect
			(at -2.050034 -27.62504 270)
			(size 0.519938 1.4986)
			(layers "F.Cu" "F.Mask" "F.Paste")
			(net "GND")
		)
		(pad "44" smd rect
			(at -2.050034 -26.774902 270)
			(size 0.519938 1.4986)
			(layers "F.Cu" "F.Mask" "F.Paste")
			(net "M_G_CPU0_SA_DQS_DP<3>")
		)
		(pad "45" smd rect
			(at -2.050034 -25.925018 270)
			(size 0.519938 1.4986)
			(layers "F.Cu" "F.Mask" "F.Paste")
			(net "M_G_CPU0_SA_DQS_DN<3>")
		)
		(pad "46" smd rect
			(at -2.050034 -25.07488 270)
			(size 0.519938 1.4986)
			(layers "F.Cu" "F.Mask" "F.Paste")
			(net "GND")
		)
		(pad "47" smd rect
			(at -2.050034 -24.224996 270)
			(size 0.519938 1.4986)
			(layers "F.Cu" "F.Mask" "F.Paste")
			(net "M_G_CPU0_SA_DQ<28>")
		)
		(pad "48" smd rect
			(at -2.050034 -23.375112 270)
			(size 0.519938 1.4986)
			(layers "F.Cu" "F.Mask" "F.Paste")
			(net "GND")
		)
		(pad "49" smd rect
			(at -2.050034 -22.524974 270)
			(size 0.519938 1.4986)
			(layers "F.Cu" "F.Mask" "F.Paste")
			(net "M_G_CPU0_SA_DQ<29>")
		)
		(pad "50" smd rect
			(at -2.050034 -21.67509 270)
			(size 0.519938 1.4986)
			(layers "F.Cu" "F.Mask" "F.Paste")
			(net "GND")
		)
		(pad "51" smd rect
			(at -2.050034 -20.824952 270)
			(size 0.519938 1.4986)
			(layers "F.Cu" "F.Mask" "F.Paste")
			(net "M_G_CPU0_SA_CB<0>")
		)
		(pad "52" smd rect
			(at -2.050034 -19.975068 270)
			(size 0.519938 1.4986)
			(layers "F.Cu" "F.Mask" "F.Paste")
			(net "GND")
		)
		(pad "53" smd rect
			(at -2.050034 -19.12493 270)
			(size 0.519938 1.4986)
			(layers "F.Cu" "F.Mask" "F.Paste")
			(net "M_G_CPU0_SA_CB<1>")
		)
		(pad "54" smd rect
			(at -2.050034 -18.275046 270)
			(size 0.519938 1.4986)
			(layers "F.Cu" "F.Mask" "F.Paste")
			(net "GND")
		)
		(pad "55" smd rect
			(at -2.050034 -17.424908 270)
			(size 0.519938 1.4986)
			(layers "F.Cu" "F.Mask" "F.Paste")
			(net "M_G_CPU0_SA_DQS_DP<4>")
		)
		(pad "56" smd rect
			(at -2.050034 -16.575024 270)
			(size 0.519938 1.4986)
			(layers "F.Cu" "F.Mask" "F.Paste")
			(net "M_G_CPU0_SA_DQS_DN<4>")
		)
		(pad "57" smd rect
			(at -2.050034 -15.724886 270)
			(size 0.519938 1.4986)
			(layers "F.Cu" "F.Mask" "F.Paste")
			(net "GND")
		)
		(pad "58" smd rect
			(at -2.050034 -14.875002 270)
			(size 0.519938 1.4986)
			(layers "F.Cu" "F.Mask" "F.Paste")
			(net "M_G_CPU0_SA_CB<4>")
		)
		(pad "59" smd rect
			(at -2.050034 -14.025118 270)
			(size 0.519938 1.4986)
			(layers "F.Cu" "F.Mask" "F.Paste")
			(net "GND")
		)
		(pad "60" smd rect
			(at -2.050034 -13.17498 270)
			(size 0.519938 1.4986)
			(layers "F.Cu" "F.Mask" "F.Paste")
			(net "M_G_CPU0_SA_CB<5>")
		)
		(pad "61" smd rect
			(at -2.050034 -12.325096 270)
			(size 0.519938 1.4986)
			(layers "F.Cu" "F.Mask" "F.Paste")
			(net "GND")
		)
		(pad "62" smd rect
			(at -2.050034 -11.474958 270)
			(size 0.519938 1.4986)
			(layers "F.Cu" "F.Mask" "F.Paste")
			(net "M_G_CPU0_ALERT_N")
		)
		(pad "63" smd rect
			(at -2.050034 -10.625074 270)
			(size 0.519938 1.4986)
			(layers "F.Cu" "F.Mask" "F.Paste")
			(net "GND")
		)
		(pad "64" smd rect
			(at -2.050034 -9.774936 270)
			(size 0.519938 1.4986)
			(layers "F.Cu" "F.Mask" "F.Paste")
			(net "M_G_CPU0_SA_CS_N<2>")
		)
		(pad "65" smd rect
			(at -2.050034 -8.925052 270)
			(size 0.519938 1.4986)
			(layers "F.Cu" "F.Mask" "F.Paste")
			(net "GND")
		)
		(pad "66" smd rect
			(at -2.050034 -8.074914 270)
			(size 0.519938 1.4986)
			(layers "F.Cu" "F.Mask" "F.Paste")
			(net "M_G_CPU0_SA_CA<0>")
		)
		(pad "67" smd rect
			(at -2.050034 -7.22503 270)
			(size 0.519938 1.4986)
			(layers "F.Cu" "F.Mask" "F.Paste")
			(net "GND")
		)
		(pad "68" smd rect
			(at -2.050034 -6.374892 270)
			(size 0.519938 1.4986)
			(layers "F.Cu" "F.Mask" "F.Paste")
			(net "M_G_CPU0_SA_CA<2>")
		)
		(pad "69" smd rect
			(at -2.050034 -5.525008 270)
			(size 0.519938 1.4986)
			(layers "F.Cu" "F.Mask" "F.Paste")
			(net "GND")
		)
		(pad "70" smd rect
			(at -2.050034 -4.675124 270)
			(size 0.519938 1.4986)
			(layers "F.Cu" "F.Mask" "F.Paste")
			(net "M_G_CPU0_SA_CA<4>")
		)
		(pad "71" smd rect
			(at -2.050034 -3.824986 270)
			(size 0.519938 1.4986)
			(layers "F.Cu" "F.Mask" "F.Paste")
			(net "GND")
		)
		(pad "72" smd rect
			(at -2.050034 -2.975102 270)
			(size 0.519938 1.4986)
			(layers "F.Cu" "F.Mask" "F.Paste")
			(net "M_G_CPU0_SA_CA<6>")
		)
		(pad "73" smd rect
			(at -2.050034 -2.124964 270)
			(size 0.519938 1.4986)
			(layers "F.Cu" "F.Mask" "F.Paste")
			(net "GND")
		)
		(pad "74" smd rect
			(at -2.050034 -1.27508 270)
			(size 0.519938 1.4986)
			(layers "F.Cu" "F.Mask" "F.Paste")
			(net "M_G_CPU0_SA_PAR")
		)
		(pad "75" smd rect
			(at -2.050034 -0.424942 270)
			(size 0.519938 1.4986)
			(layers "F.Cu" "F.Mask" "F.Paste")
			(net "GND")
		)
		(pad "76" smd rect
			(at -2.050034 5.525008 270)
			(size 0.519938 1.4986)
			(layers "F.Cu" "F.Mask" "F.Paste")
			(net "M_G_CPU0_SB_CA<0>")
		)
		(pad "77" smd rect
			(at -2.050034 6.374892 270)
			(size 0.519938 1.4986)
			(layers "F.Cu" "F.Mask" "F.Paste")
			(net "GND")
		)
		(pad "78" smd rect
			(at -2.050034 7.22503 270)
			(size 0.519938 1.4986)
			(layers "F.Cu" "F.Mask" "F.Paste")
			(net "M_G_CPU0_SB_CA<2>")
		)
		(pad "79" smd rect
			(at -2.050034 8.074914 270)
			(size 0.519938 1.4986)
			(layers "F.Cu" "F.Mask" "F.Paste")
			(net "GND")
		)
		(pad "80" smd rect
			(at -2.050034 8.925052 270)
			(size 0.519938 1.4986)
			(layers "F.Cu" "F.Mask" "F.Paste")
			(net "M_G_CPU0_SB_CA<4>")
		)
		(pad "81" smd rect
			(at -2.050034 9.774936 270)
			(size 0.519938 1.4986)
			(layers "F.Cu" "F.Mask" "F.Paste")
			(net "GND")
		)
		(pad "82" smd rect
			(at -2.050034 10.625074 270)
			(size 0.519938 1.4986)
			(layers "F.Cu" "F.Mask" "F.Paste")
			(net "M_G_CPU0_SB_CA<6>")
		)
		(pad "83" smd rect
			(at -2.050034 11.474958 270)
			(size 0.519938 1.4986)
			(layers "F.Cu" "F.Mask" "F.Paste")
			(net "GND")
		)
		(pad "84" smd rect
			(at -2.050034 12.325096 270)
			(size 0.519938 1.4986)
			(layers "F.Cu" "F.Mask" "F.Paste")
			(net "M_G_CPU0_SB_CS_N<2>")
		)
		(pad "85" smd rect
			(at -2.050034 13.17498 270)
			(size 0.519938 1.4986)
			(layers "F.Cu" "F.Mask" "F.Paste")
			(net "GND")
		)
		(pad "86" smd rect
			(at -2.050034 14.025118 270)
			(size 0.519938 1.4986)
			(layers "F.Cu" "F.Mask" "F.Paste")
			(net "M_G_CPU0_SA_RSP<1>")
		)
		(pad "87" smd rect
			(at -2.050034 14.875002 270)
			(size 0.519938 1.4986)
			(layers "F.Cu" "F.Mask" "F.Paste")
			(net "M_G_CPU0_SB_RSP<1>")
		)
		(pad "88" smd rect
			(at -2.050034 15.724886 270)
			(size 0.519938 1.4986)
			(layers "F.Cu" "F.Mask" "F.Paste")
			(net "GND")
		)
		(pad "89" smd rect
			(at -2.050034 16.575024 270)
			(size 0.519938 1.4986)
			(layers "F.Cu" "F.Mask" "F.Paste")
			(net "M_G_CPU0_SB_CB<4>")
		)
		(pad "90" smd rect
			(at -2.050034 17.424908 270)
			(size 0.519938 1.4986)
			(layers "F.Cu" "F.Mask" "F.Paste")
			(net "GND")
		)
		(pad "91" smd rect
			(at -2.050034 18.275046 270)
			(size 0.519938 1.4986)
			(layers "F.Cu" "F.Mask" "F.Paste")
			(net "M_G_CPU0_SB_CB<5>")
		)
		(pad "92" smd rect
			(at -2.050034 19.12493 270)
			(size 0.519938 1.4986)
			(layers "F.Cu" "F.Mask" "F.Paste")
			(net "GND")
		)
		(pad "93" smd rect
			(at -2.050034 19.975068 270)
			(size 0.519938 1.4986)
			(layers "F.Cu" "F.Mask" "F.Paste")
			(net "M_G_CPU0_SB_DQS_DP<9>")
		)
		(pad "94" smd rect
			(at -2.050034 20.824952 270)
			(size 0.519938 1.4986)
			(layers "F.Cu" "F.Mask" "F.Paste")
			(net "M_G_CPU0_SB_DQS_DN<9>")
		)
		(pad "95" smd rect
			(at -2.050034 21.67509 270)
			(size 0.519938 1.4986)
			(layers "F.Cu" "F.Mask" "F.Paste")
			(net "GND")
		)
		(pad "96" smd rect
			(at -2.050034 22.524974 270)
			(size 0.519938 1.4986)
			(layers "F.Cu" "F.Mask" "F.Paste")
			(net "M_G_CPU0_SB_CB<0>")
		)
		(pad "97" smd rect
			(at -2.050034 23.375112 270)
			(size 0.519938 1.4986)
			(layers "F.Cu" "F.Mask" "F.Paste")
			(net "GND")
		)
		(pad "98" smd rect
			(at -2.050034 24.224996 270)
			(size 0.519938 1.4986)
			(layers "F.Cu" "F.Mask" "F.Paste")
			(net "M_G_CPU0_SB_CB<1>")
		)
		(pad "99" smd rect
			(at -2.050034 25.07488 270)
			(size 0.519938 1.4986)
			(layers "F.Cu" "F.Mask" "F.Paste")
			(net "GND")
		)
		(pad "100" smd rect
			(at -2.050034 25.925018 270)
			(size 0.519938 1.4986)
			(layers "F.Cu" "F.Mask" "F.Paste")
			(net "M_G_CPU0_SB_DQ<0>")
		)
		(pad "101" smd rect
			(at -2.050034 26.774902 270)
			(size 0.519938 1.4986)
			(layers "F.Cu" "F.Mask" "F.Paste")
			(net "GND")
		)
		(pad "102" smd rect
			(at -2.050034 27.62504 270)
			(size 0.519938 1.4986)
			(layers "F.Cu" "F.Mask" "F.Paste")
			(net "M_G_CPU0_SB_DQ<1>")
		)
		(pad "103" smd rect
			(at -2.050034 28.474924 270)
			(size 0.519938 1.4986)
			(layers "F.Cu" "F.Mask" "F.Paste")
			(net "GND")
		)
		(pad "104" smd rect
			(at -2.050034 29.325062 270)
			(size 0.519938 1.4986)
			(layers "F.Cu" "F.Mask" "F.Paste")
			(net "M_G_CPU0_SB_DQS_DP<0>")
		)
		(pad "105" smd rect
			(at -2.050034 30.174946 270)
			(size 0.519938 1.4986)
			(layers "F.Cu" "F.Mask" "F.Paste")
			(net "M_G_CPU0_SB_DQS_DN<0>")
		)
		(pad "106" smd rect
			(at -2.050034 31.025084 270)
			(size 0.519938 1.4986)
			(layers "F.Cu" "F.Mask" "F.Paste")
			(net "GND")
		)
		(pad "107" smd rect
			(at -2.050034 31.874968 270)
			(size 0.519938 1.4986)
			(layers "F.Cu" "F.Mask" "F.Paste")
			(net "M_G_CPU0_SB_DQ<4>")
		)
		(pad "108" smd rect
			(at -2.050034 32.725106 270)
			(size 0.519938 1.4986)
			(layers "F.Cu" "F.Mask" "F.Paste")
			(net "GND")
		)
		(pad "109" smd rect
			(at -2.050034 33.57499 270)
			(size 0.519938 1.4986)
			(layers "F.Cu" "F.Mask" "F.Paste")
			(net "M_G_CPU0_SB_DQ<5>")
		)
		(pad "110" smd rect
			(at -2.050034 34.425128 270)
			(size 0.519938 1.4986)
			(layers "F.Cu" "F.Mask" "F.Paste")
			(net "GND")
		)
		(pad "111" smd rect
			(at -2.050034 35.275012 270)
			(size 0.519938 1.4986)
			(layers "F.Cu" "F.Mask" "F.Paste")
			(net "M_G_CPU0_SB_DQ<8>")
		)
		(pad "112" smd rect
			(at -2.050034 36.124896 270)
			(size 0.519938 1.4986)
			(layers "F.Cu" "F.Mask" "F.Paste")
			(net "GND")
		)
		(pad "113" smd rect
			(at -2.050034 36.975034 270)
			(size 0.519938 1.4986)
			(layers "F.Cu" "F.Mask" "F.Paste")
			(net "M_G_CPU0_SB_DQ<9>")
		)
		(pad "114" smd rect
			(at -2.050034 37.824918 270)
			(size 0.519938 1.4986)
			(layers "F.Cu" "F.Mask" "F.Paste")
			(net "GND")
		)
		(pad "115" smd rect
			(at -2.050034 38.675056 270)
			(size 0.519938 1.4986)
			(layers "F.Cu" "F.Mask" "F.Paste")
			(net "M_G_CPU0_SB_DQS_DP<1>")
		)
		(pad "116" smd rect
			(at -2.050034 39.52494 270)
			(size 0.519938 1.4986)
			(layers "F.Cu" "F.Mask" "F.Paste")
			(net "M_G_CPU0_SB_DQS_DN<1>")
		)
		(pad "117" smd rect
			(at -2.050034 40.375078 270)
			(size 0.519938 1.4986)
			(layers "F.Cu" "F.Mask" "F.Paste")
			(net "GND")
		)
		(pad "118" smd rect
			(at -2.050034 41.224962 270)
			(size 0.519938 1.4986)
			(layers "F.Cu" "F.Mask" "F.Paste")
			(net "M_G_CPU0_SB_DQ<12>")
		)
		(pad "119" smd rect
			(at -2.050034 42.0751 270)
			(size 0.519938 1.4986)
			(layers "F.Cu" "F.Mask" "F.Paste")
			(net "GND")
		)
		(pad "120" smd rect
			(at -2.050034 42.924984 270)
			(size 0.519938 1.4986)
			(layers "F.Cu" "F.Mask" "F.Paste")
			(net "M_G_CPU0_SB_DQ<13>")
		)
		(pad "121" smd rect
			(at -2.050034 43.775122 270)
			(size 0.519938 1.4986)
			(layers "F.Cu" "F.Mask" "F.Paste")
			(net "GND")
		)
		(pad "122" smd rect
			(at -2.050034 44.625006 270)
			(size 0.519938 1.4986)
			(layers "F.Cu" "F.Mask" "F.Paste")
			(net "M_G_CPU0_SB_DQ<16>")
		)
		(pad "123" smd rect
			(at -2.050034 45.47489 270)
			(size 0.519938 1.4986)
			(layers "F.Cu" "F.Mask" "F.Paste")
			(net "GND")
		)
		(pad "124" smd rect
			(at -2.050034 46.325028 270)
			(size 0.519938 1.4986)
			(layers "F.Cu" "F.Mask" "F.Paste")
			(net "M_G_CPU0_SB_DQ<17>")
		)
		(pad "125" smd rect
			(at -2.050034 47.174912 270)
			(size 0.519938 1.4986)
			(layers "F.Cu" "F.Mask" "F.Paste")
			(net "GND")
		)
		(pad "126" smd rect
			(at -2.050034 48.02505 270)
			(size 0.519938 1.4986)
			(layers "F.Cu" "F.Mask" "F.Paste")
			(net "M_G_CPU0_SB_DQS_DP<2>")
		)
		(pad "127" smd rect
			(at -2.050034 48.874934 270)
			(size 0.519938 1.4986)
			(layers "F.Cu" "F.Mask" "F.Paste")
			(net "M_G_CPU0_SB_DQS_DN<2>")
		)
		(pad "128" smd rect
			(at -2.050034 49.725072 270)
			(size 0.519938 1.4986)
			(layers "F.Cu" "F.Mask" "F.Paste")
			(net "GND")
		)
		(pad "129" smd rect
			(at -2.050034 50.574956 270)
			(size 0.519938 1.4986)
			(layers "F.Cu" "F.Mask" "F.Paste")
			(net "M_G_CPU0_SB_DQ<20>")
		)
		(pad "130" smd rect
			(at -2.050034 51.425094 270)
			(size 0.519938 1.4986)
			(layers "F.Cu" "F.Mask" "F.Paste")
			(net "GND")
		)
		(pad "131" smd rect
			(at -2.050034 52.274978 270)
			(size 0.519938 1.4986)
			(layers "F.Cu" "F.Mask" "F.Paste")
			(net "M_G_CPU0_SB_DQ<21>")
		)
		(pad "132" smd rect
			(at -2.050034 53.125116 270)
			(size 0.519938 1.4986)
			(layers "F.Cu" "F.Mask" "F.Paste")
			(net "GND")
		)
		(pad "133" smd rect
			(at -2.050034 53.975 270)
			(size 0.519938 1.4986)
			(layers "F.Cu" "F.Mask" "F.Paste")
			(net "M_G_CPU0_SB_DQ<24>")
		)
		(pad "134" smd rect
			(at -2.050034 54.824884 270)
			(size 0.519938 1.4986)
			(layers "F.Cu" "F.Mask" "F.Paste")
			(net "GND")
		)
		(pad "135" smd rect
			(at -2.050034 55.675022 270)
			(size 0.519938 1.4986)
			(layers "F.Cu" "F.Mask" "F.Paste")
			(net "M_G_CPU0_SB_DQ<25>")
		)
		(pad "136" smd rect
			(at -2.050034 56.524906 270)
			(size 0.519938 1.4986)
			(layers "F.Cu" "F.Mask" "F.Paste")
			(net "GND")
		)
		(pad "137" smd rect
			(at -2.050034 57.375044 270)
			(size 0.519938 1.4986)
			(layers "F.Cu" "F.Mask" "F.Paste")
			(net "M_G_CPU0_SB_DQS_DP<3>")
		)
		(pad "138" smd rect
			(at -2.050034 58.224928 270)
			(size 0.519938 1.4986)
			(layers "F.Cu" "F.Mask" "F.Paste")
			(net "M_G_CPU0_SB_DQS_DN<3>")
		)
		(pad "139" smd rect
			(at -2.050034 59.075066 270)
			(size 0.519938 1.4986)
			(layers "F.Cu" "F.Mask" "F.Paste")
			(net "GND")
		)
		(pad "140" smd rect
			(at -2.050034 59.92495 270)
			(size 0.519938 1.4986)
			(layers "F.Cu" "F.Mask" "F.Paste")
			(net "M_G_CPU0_SB_DQ<28>")
		)
		(pad "141" smd rect
			(at -2.050034 60.775088 270)
			(size 0.519938 1.4986)
			(layers "F.Cu" "F.Mask" "F.Paste")
			(net "GND")
		)
		(pad "142" smd rect
			(at -2.050034 61.624972 270)
			(size 0.519938 1.4986)
			(layers "F.Cu" "F.Mask" "F.Paste")
			(net "M_G_CPU0_SB_DQ<29>")
		)
		(pad "143" smd rect
			(at -2.050034 62.47511 270)
			(size 0.519938 1.4986)
			(layers "F.Cu" "F.Mask" "F.Paste")
			(net "GND")
		)
		(pad "144" smd rect
			(at -2.050034 63.324994 270)
			(size 0.519938 1.4986)
			(layers "F.Cu" "F.Mask" "F.Paste")
			(net "TP_CHG_CPU0_DIMM2_FRU_1")
		)
		(pad "145" smd rect
			(at 2.050034 -63.324994 270)
			(size 0.519938 1.4986)
			(layers "F.Cu" "F.Mask" "F.Paste")
			(net "P12V_S3_AUX_CPU0_NVDIMM")
		)
		(pad "146" smd rect
			(at 2.050034 -62.47511 270)
			(size 0.519938 1.4986)
			(layers "F.Cu" "F.Mask" "F.Paste")
			(net "P12V_S3_AUX_CPU0_NVDIMM")
		)
		(pad "147" smd rect
			(at 2.050034 -61.624972 270)
			(size 0.519938 1.4986)
			(layers "F.Cu" "F.Mask" "F.Paste")
			(net "PWRGD_CHG_CPU0_DIMM2")
		)
		(pad "148" smd rect
			(at 2.050034 -60.775088 270)
			(size 0.519938 1.4986)
			(layers "F.Cu" "F.Mask" "F.Paste")
			(net "PD_CHG_CPU0_DIMM2_SAA")
		)
		(pad "149" smd rect
			(at 2.050034 -59.92495 270)
			(size 0.519938 1.4986)
			(layers "F.Cu" "F.Mask" "F.Paste")
			(net "TP_CHG_CPU0_DIMM2_FRU_2")
		)
		(pad "150" smd rect
			(at 2.050034 -59.075066 270)
			(size 0.519938 1.4986)
			(layers "F.Cu" "F.Mask" "F.Paste")
			(net "TP_CHG_CPU0_DIMM2_FRU_3")
		)
		(pad "151" smd rect
			(at 2.050034 -58.224928 270)
			(size 0.519938 1.4986)
			(layers "F.Cu" "F.Mask" "F.Paste")
			(net "GND")
		)
		(pad "152" smd rect
			(at 2.050034 -57.375044 270)
			(size 0.519938 1.4986)
			(layers "F.Cu" "F.Mask" "F.Paste")
			(net "M_G_CPU0_SA_DQ<2>")
		)
		(pad "153" smd rect
			(at 2.050034 -56.524906 270)
			(size 0.519938 1.4986)
			(layers "F.Cu" "F.Mask" "F.Paste")
			(net "GND")
		)
		(pad "154" smd rect
			(at 2.050034 -55.675022 270)
			(size 0.519938 1.4986)
			(layers "F.Cu" "F.Mask" "F.Paste")
			(net "M_G_CPU0_SA_DQ<3>")
		)
		(pad "155" smd rect
			(at 2.050034 -54.824884 270)
			(size 0.519938 1.4986)
			(layers "F.Cu" "F.Mask" "F.Paste")
			(net "GND")
		)
		(pad "156" smd rect
			(at 2.050034 -53.975 270)
			(size 0.519938 1.4986)
			(layers "F.Cu" "F.Mask" "F.Paste")
			(net "M_G_CPU0_SA_DQS_DN<5>")
		)
		(pad "157" smd rect
			(at 2.050034 -53.125116 270)
			(size 0.519938 1.4986)
			(layers "F.Cu" "F.Mask" "F.Paste")
			(net "M_G_CPU0_SA_DQS_DP<5>")
		)
		(pad "158" smd rect
			(at 2.050034 -52.274978 270)
			(size 0.519938 1.4986)
			(layers "F.Cu" "F.Mask" "F.Paste")
			(net "GND")
		)
		(pad "159" smd rect
			(at 2.050034 -51.425094 270)
			(size 0.519938 1.4986)
			(layers "F.Cu" "F.Mask" "F.Paste")
			(net "M_G_CPU0_SA_DQ<6>")
		)
		(pad "160" smd rect
			(at 2.050034 -50.574956 270)
			(size 0.519938 1.4986)
			(layers "F.Cu" "F.Mask" "F.Paste")
			(net "GND")
		)
		(pad "161" smd rect
			(at 2.050034 -49.725072 270)
			(size 0.519938 1.4986)
			(layers "F.Cu" "F.Mask" "F.Paste")
			(net "M_G_CPU0_SA_DQ<7>")
		)
		(pad "162" smd rect
			(at 2.050034 -48.874934 270)
			(size 0.519938 1.4986)
			(layers "F.Cu" "F.Mask" "F.Paste")
			(net "GND")
		)
		(pad "163" smd rect
			(at 2.050034 -48.02505 270)
			(size 0.519938 1.4986)
			(layers "F.Cu" "F.Mask" "F.Paste")
			(net "M_G_CPU0_SA_DQ<10>")
		)
		(pad "164" smd rect
			(at 2.050034 -47.174912 270)
			(size 0.519938 1.4986)
			(layers "F.Cu" "F.Mask" "F.Paste")
			(net "GND")
		)
		(pad "165" smd rect
			(at 2.050034 -46.325028 270)
			(size 0.519938 1.4986)
			(layers "F.Cu" "F.Mask" "F.Paste")
			(net "M_G_CPU0_SA_DQ<11>")
		)
		(pad "166" smd rect
			(at 2.050034 -45.47489 270)
			(size 0.519938 1.4986)
			(layers "F.Cu" "F.Mask" "F.Paste")
			(net "GND")
		)
		(pad "167" smd rect
			(at 2.050034 -44.625006 270)
			(size 0.519938 1.4986)
			(layers "F.Cu" "F.Mask" "F.Paste")
			(net "M_G_CPU0_SA_DQS_DN<6>")
		)
		(pad "168" smd rect
			(at 2.050034 -43.775122 270)
			(size 0.519938 1.4986)
			(layers "F.Cu" "F.Mask" "F.Paste")
			(net "M_G_CPU0_SA_DQS_DP<6>")
		)
		(pad "169" smd rect
			(at 2.050034 -42.924984 270)
			(size 0.519938 1.4986)
			(layers "F.Cu" "F.Mask" "F.Paste")
			(net "GND")
		)
		(pad "170" smd rect
			(at 2.050034 -42.0751 270)
			(size 0.519938 1.4986)
			(layers "F.Cu" "F.Mask" "F.Paste")
			(net "M_G_CPU0_SA_DQ<14>")
		)
		(pad "171" smd rect
			(at 2.050034 -41.224962 270)
			(size 0.519938 1.4986)
			(layers "F.Cu" "F.Mask" "F.Paste")
			(net "GND")
		)
		(pad "172" smd rect
			(at 2.050034 -40.375078 270)
			(size 0.519938 1.4986)
			(layers "F.Cu" "F.Mask" "F.Paste")
			(net "M_G_CPU0_SA_DQ<15>")
		)
		(pad "173" smd rect
			(at 2.050034 -39.52494 270)
			(size 0.519938 1.4986)
			(layers "F.Cu" "F.Mask" "F.Paste")
			(net "GND")
		)
		(pad "174" smd rect
			(at 2.050034 -38.675056 270)
			(size 0.519938 1.4986)
			(layers "F.Cu" "F.Mask" "F.Paste")
			(net "M_G_CPU0_SA_DQ<18>")
		)
		(pad "175" smd rect
			(at 2.050034 -37.824918 270)
			(size 0.519938 1.4986)
			(layers "F.Cu" "F.Mask" "F.Paste")
			(net "GND")
		)
		(pad "176" smd rect
			(at 2.050034 -36.975034 270)
			(size 0.519938 1.4986)
			(layers "F.Cu" "F.Mask" "F.Paste")
			(net "M_G_CPU0_SA_DQ<19>")
		)
		(pad "177" smd rect
			(at 2.050034 -36.124896 270)
			(size 0.519938 1.4986)
			(layers "F.Cu" "F.Mask" "F.Paste")
			(net "GND")
		)
		(pad "178" smd rect
			(at 2.050034 -35.275012 270)
			(size 0.519938 1.4986)
			(layers "F.Cu" "F.Mask" "F.Paste")
			(net "M_G_CPU0_SA_DQS_DN<7>")
		)
		(pad "179" smd rect
			(at 2.050034 -34.425128 270)
			(size 0.519938 1.4986)
			(layers "F.Cu" "F.Mask" "F.Paste")
			(net "M_G_CPU0_SA_DQS_DP<7>")
		)
		(pad "180" smd rect
			(at 2.050034 -33.57499 270)
			(size 0.519938 1.4986)
			(layers "F.Cu" "F.Mask" "F.Paste")
			(net "GND")
		)
		(pad "181" smd rect
			(at 2.050034 -32.725106 270)
			(size 0.519938 1.4986)
			(layers "F.Cu" "F.Mask" "F.Paste")
			(net "M_G_CPU0_SA_DQ<22>")
		)
		(pad "182" smd rect
			(at 2.050034 -31.874968 270)
			(size 0.519938 1.4986)
			(layers "F.Cu" "F.Mask" "F.Paste")
			(net "GND")
		)
		(pad "183" smd rect
			(at 2.050034 -31.025084 270)
			(size 0.519938 1.4986)
			(layers "F.Cu" "F.Mask" "F.Paste")
			(net "M_G_CPU0_SA_DQ<23>")
		)
		(pad "184" smd rect
			(at 2.050034 -30.174946 270)
			(size 0.519938 1.4986)
			(layers "F.Cu" "F.Mask" "F.Paste")
			(net "GND")
		)
		(pad "185" smd rect
			(at 2.050034 -29.325062 270)
			(size 0.519938 1.4986)
			(layers "F.Cu" "F.Mask" "F.Paste")
			(net "M_G_CPU0_SA_DQ<26>")
		)
		(pad "186" smd rect
			(at 2.050034 -28.474924 270)
			(size 0.519938 1.4986)
			(layers "F.Cu" "F.Mask" "F.Paste")
			(net "GND")
		)
		(pad "187" smd rect
			(at 2.050034 -27.62504 270)
			(size 0.519938 1.4986)
			(layers "F.Cu" "F.Mask" "F.Paste")
			(net "M_G_CPU0_SA_DQ<27>")
		)
		(pad "188" smd rect
			(at 2.050034 -26.774902 270)
			(size 0.519938 1.4986)
			(layers "F.Cu" "F.Mask" "F.Paste")
			(net "GND")
		)
		(pad "189" smd rect
			(at 2.050034 -25.925018 270)
			(size 0.519938 1.4986)
			(layers "F.Cu" "F.Mask" "F.Paste")
			(net "M_G_CPU0_SA_DQS_DN<8>")
		)
		(pad "190" smd rect
			(at 2.050034 -25.07488 270)
			(size 0.519938 1.4986)
			(layers "F.Cu" "F.Mask" "F.Paste")
			(net "M_G_CPU0_SA_DQS_DP<8>")
		)
		(pad "191" smd rect
			(at 2.050034 -24.224996 270)
			(size 0.519938 1.4986)
			(layers "F.Cu" "F.Mask" "F.Paste")
			(net "GND")
		)
		(pad "192" smd rect
			(at 2.050034 -23.375112 270)
			(size 0.519938 1.4986)
			(layers "F.Cu" "F.Mask" "F.Paste")
			(net "M_G_CPU0_SA_DQ<30>")
		)
		(pad "193" smd rect
			(at 2.050034 -22.524974 270)
			(size 0.519938 1.4986)
			(layers "F.Cu" "F.Mask" "F.Paste")
			(net "GND")
		)
		(pad "194" smd rect
			(at 2.050034 -21.67509 270)
			(size 0.519938 1.4986)
			(layers "F.Cu" "F.Mask" "F.Paste")
			(net "M_G_CPU0_SA_DQ<31>")
		)
		(pad "195" smd rect
			(at 2.050034 -20.824952 270)
			(size 0.519938 1.4986)
			(layers "F.Cu" "F.Mask" "F.Paste")
			(net "GND")
		)
		(pad "196" smd rect
			(at 2.050034 -19.975068 270)
			(size 0.519938 1.4986)
			(layers "F.Cu" "F.Mask" "F.Paste")
			(net "M_G_CPU0_SA_CB<2>")
		)
		(pad "197" smd rect
			(at 2.050034 -19.12493 270)
			(size 0.519938 1.4986)
			(layers "F.Cu" "F.Mask" "F.Paste")
			(net "GND")
		)
		(pad "198" smd rect
			(at 2.050034 -18.275046 270)
			(size 0.519938 1.4986)
			(layers "F.Cu" "F.Mask" "F.Paste")
			(net "M_G_CPU0_SA_CB<3>")
		)
		(pad "199" smd rect
			(at 2.050034 -17.424908 270)
			(size 0.519938 1.4986)
			(layers "F.Cu" "F.Mask" "F.Paste")
			(net "GND")
		)
		(pad "200" smd rect
			(at 2.050034 -16.575024 270)
			(size 0.519938 1.4986)
			(layers "F.Cu" "F.Mask" "F.Paste")
			(net "M_G_CPU0_SA_DQS_DN<9>")
		)
		(pad "201" smd rect
			(at 2.050034 -15.724886 270)
			(size 0.519938 1.4986)
			(layers "F.Cu" "F.Mask" "F.Paste")
			(net "M_G_CPU0_SA_DQS_DP<9>")
		)
		(pad "202" smd rect
			(at 2.050034 -14.875002 270)
			(size 0.519938 1.4986)
			(layers "F.Cu" "F.Mask" "F.Paste")
			(net "GND")
		)
		(pad "203" smd rect
			(at 2.050034 -14.025118 270)
			(size 0.519938 1.4986)
			(layers "F.Cu" "F.Mask" "F.Paste")
			(net "M_G_CPU0_SA_CB<6>")
		)
		(pad "204" smd rect
			(at 2.050034 -13.17498 270)
			(size 0.519938 1.4986)
			(layers "F.Cu" "F.Mask" "F.Paste")
			(net "GND")
		)
		(pad "205" smd rect
			(at 2.050034 -12.325096 270)
			(size 0.519938 1.4986)
			(layers "F.Cu" "F.Mask" "F.Paste")
			(net "M_G_CPU0_SA_CB<7>")
		)
		(pad "206" smd rect
			(at 2.050034 -11.474958 270)
			(size 0.519938 1.4986)
			(layers "F.Cu" "F.Mask" "F.Paste")
			(net "GND")
		)
		(pad "207" smd rect
			(at 2.050034 -10.625074 270)
			(size 0.519938 1.4986)
			(layers "F.Cu" "F.Mask" "F.Paste")
			(net "RST_M_GH_CPU0_FPGA_N")
		)
		(pad "208" smd rect
			(at 2.050034 -9.774936 270)
			(size 0.519938 1.4986)
			(layers "F.Cu" "F.Mask" "F.Paste")
			(net "GND")
		)
		(pad "209" smd rect
			(at 2.050034 -8.925052 270)
			(size 0.519938 1.4986)
			(layers "F.Cu" "F.Mask" "F.Paste")
			(net "M_G_CPU0_SA_CS_N<3>")
		)
		(pad "210" smd rect
			(at 2.050034 -8.074914 270)
			(size 0.519938 1.4986)
			(layers "F.Cu" "F.Mask" "F.Paste")
			(net "GND")
		)
		(pad "211" smd rect
			(at 2.050034 -7.22503 270)
			(size 0.519938 1.4986)
			(layers "F.Cu" "F.Mask" "F.Paste")
			(net "M_G_CPU0_SA_CA<1>")
		)
		(pad "212" smd rect
			(at 2.050034 -6.374892 270)
			(size 0.519938 1.4986)
			(layers "F.Cu" "F.Mask" "F.Paste")
			(net "GND")
		)
		(pad "213" smd rect
			(at 2.050034 -5.525008 270)
			(size 0.519938 1.4986)
			(layers "F.Cu" "F.Mask" "F.Paste")
			(net "M_G_CPU0_SA_CA<3>")
		)
		(pad "214" smd rect
			(at 2.050034 -4.675124 270)
			(size 0.519938 1.4986)
			(layers "F.Cu" "F.Mask" "F.Paste")
			(net "GND")
		)
		(pad "215" smd rect
			(at 2.050034 -3.824986 270)
			(size 0.519938 1.4986)
			(layers "F.Cu" "F.Mask" "F.Paste")
			(net "M_G_CPU0_SA_CA<5>")
		)
		(pad "216" smd rect
			(at 2.050034 -2.975102 270)
			(size 0.519938 1.4986)
			(layers "F.Cu" "F.Mask" "F.Paste")
			(net "GND")
		)
		(pad "217" smd rect
			(at 2.050034 -2.124964 270)
			(size 0.519938 1.4986)
			(layers "F.Cu" "F.Mask" "F.Paste")
			(net "M_G_CPU0_CLK_DP<1>")
		)
		(pad "218" smd rect
			(at 2.050034 -1.27508 270)
			(size 0.519938 1.4986)
			(layers "F.Cu" "F.Mask" "F.Paste")
			(net "M_G_CPU0_CLK_DN<1>")
		)
		(pad "219" smd rect
			(at 2.050034 -0.424942 270)
			(size 0.519938 1.4986)
			(layers "F.Cu" "F.Mask" "F.Paste")
			(net "GND")
		)
		(pad "220" smd rect
			(at 2.050034 5.525008 270)
			(size 0.519938 1.4986)
			(layers "F.Cu" "F.Mask" "F.Paste")
			(net "TP_CHG_CPU0_DIMM2_FRU_4")
		)
		(pad "221" smd rect
			(at 2.050034 6.374892 270)
			(size 0.519938 1.4986)
			(layers "F.Cu" "F.Mask" "F.Paste")
			(net "M_G_CPU0_SB_CA<1>")
		)
		(pad "222" smd rect
			(at 2.050034 7.22503 270)
			(size 0.519938 1.4986)
			(layers "F.Cu" "F.Mask" "F.Paste")
			(net "GND")
		)
		(pad "223" smd rect
			(at 2.050034 8.074914 270)
			(size 0.519938 1.4986)
			(layers "F.Cu" "F.Mask" "F.Paste")
			(net "M_G_CPU0_SB_CA<3>")
		)
		(pad "224" smd rect
			(at 2.050034 8.925052 270)
			(size 0.519938 1.4986)
			(layers "F.Cu" "F.Mask" "F.Paste")
			(net "GND")
		)
		(pad "225" smd rect
			(at 2.050034 9.774936 270)
			(size 0.519938 1.4986)
			(layers "F.Cu" "F.Mask" "F.Paste")
			(net "M_G_CPU0_SB_CA<5>")
		)
		(pad "226" smd rect
			(at 2.050034 10.625074 270)
			(size 0.519938 1.4986)
			(layers "F.Cu" "F.Mask" "F.Paste")
			(net "GND")
		)
		(pad "227" smd rect
			(at 2.050034 11.474958 270)
			(size 0.519938 1.4986)
			(layers "F.Cu" "F.Mask" "F.Paste")
			(net "M_G_CPU0_SB_PAR")
		)
		(pad "228" smd rect
			(at 2.050034 12.325096 270)
			(size 0.519938 1.4986)
			(layers "F.Cu" "F.Mask" "F.Paste")
			(net "GND")
		)
		(pad "229" smd rect
			(at 2.050034 13.17498 270)
			(size 0.519938 1.4986)
			(layers "F.Cu" "F.Mask" "F.Paste")
			(net "M_G_CPU0_SB_CS_N<3>")
		)
		(pad "230" smd rect
			(at 2.050034 14.025118 270)
			(size 0.519938 1.4986)
			(layers "F.Cu" "F.Mask" "F.Paste")
			(net "GND")
		)
		(pad "231" smd rect
			(at 2.050034 14.875002 270)
			(size 0.519938 1.4986)
			(layers "F.Cu" "F.Mask" "F.Paste")
			(net "TP_CHG_CPU0_DIMM2_FRU_5")
		)
		(pad "232" smd rect
			(at 2.050034 15.724886 270)
			(size 0.519938 1.4986)
			(layers "F.Cu" "F.Mask" "F.Paste")
			(net "TP_CHG_CPU0_DIMM2_FRU_6")
		)
		(pad "233" smd rect
			(at 2.050034 16.575024 270)
			(size 0.519938 1.4986)
			(layers "F.Cu" "F.Mask" "F.Paste")
			(net "GND")
		)
		(pad "234" smd rect
			(at 2.050034 17.424908 270)
			(size 0.519938 1.4986)
			(layers "F.Cu" "F.Mask" "F.Paste")
			(net "M_G_CPU0_SB_CB<6>")
		)
		(pad "235" smd rect
			(at 2.050034 18.275046 270)
			(size 0.519938 1.4986)
			(layers "F.Cu" "F.Mask" "F.Paste")
			(net "GND")
		)
		(pad "236" smd rect
			(at 2.050034 19.12493 270)
			(size 0.519938 1.4986)
			(layers "F.Cu" "F.Mask" "F.Paste")
			(net "M_G_CPU0_SB_CB<7>")
		)
		(pad "237" smd rect
			(at 2.050034 19.975068 270)
			(size 0.519938 1.4986)
			(layers "F.Cu" "F.Mask" "F.Paste")
			(net "GND")
		)
		(pad "238" smd rect
			(at 2.050034 20.824952 270)
			(size 0.519938 1.4986)
			(layers "F.Cu" "F.Mask" "F.Paste")
			(net "M_G_CPU0_SB_DQS_DN<4>")
		)
		(pad "239" smd rect
			(at 2.050034 21.67509 270)
			(size 0.519938 1.4986)
			(layers "F.Cu" "F.Mask" "F.Paste")
			(net "M_G_CPU0_SB_DQS_DP<4>")
		)
		(pad "240" smd rect
			(at 2.050034 22.524974 270)
			(size 0.519938 1.4986)
			(layers "F.Cu" "F.Mask" "F.Paste")
			(net "GND")
		)
		(pad "241" smd rect
			(at 2.050034 23.375112 270)
			(size 0.519938 1.4986)
			(layers "F.Cu" "F.Mask" "F.Paste")
			(net "M_G_CPU0_SB_CB<2>")
		)
		(pad "242" smd rect
			(at 2.050034 24.224996 270)
			(size 0.519938 1.4986)
			(layers "F.Cu" "F.Mask" "F.Paste")
			(net "GND")
		)
		(pad "243" smd rect
			(at 2.050034 25.07488 270)
			(size 0.519938 1.4986)
			(layers "F.Cu" "F.Mask" "F.Paste")
			(net "M_G_CPU0_SB_CB<3>")
		)
		(pad "244" smd rect
			(at 2.050034 25.925018 270)
			(size 0.519938 1.4986)
			(layers "F.Cu" "F.Mask" "F.Paste")
			(net "GND")
		)
		(pad "245" smd rect
			(at 2.050034 26.774902 270)
			(size 0.519938 1.4986)
			(layers "F.Cu" "F.Mask" "F.Paste")
			(net "M_G_CPU0_SB_DQ<2>")
		)
		(pad "246" smd rect
			(at 2.050034 27.62504 270)
			(size 0.519938 1.4986)
			(layers "F.Cu" "F.Mask" "F.Paste")
			(net "GND")
		)
		(pad "247" smd rect
			(at 2.050034 28.474924 270)
			(size 0.519938 1.4986)
			(layers "F.Cu" "F.Mask" "F.Paste")
			(net "M_G_CPU0_SB_DQ<3>")
		)
		(pad "248" smd rect
			(at 2.050034 29.325062 270)
			(size 0.519938 1.4986)
			(layers "F.Cu" "F.Mask" "F.Paste")
			(net "GND")
		)
		(pad "249" smd rect
			(at 2.050034 30.174946 270)
			(size 0.519938 1.4986)
			(layers "F.Cu" "F.Mask" "F.Paste")
			(net "M_G_CPU0_SB_DQS_DN<5>")
		)
		(pad "250" smd rect
			(at 2.050034 31.025084 270)
			(size 0.519938 1.4986)
			(layers "F.Cu" "F.Mask" "F.Paste")
			(net "M_G_CPU0_SB_DQS_DP<5>")
		)
		(pad "251" smd rect
			(at 2.050034 31.874968 270)
			(size 0.519938 1.4986)
			(layers "F.Cu" "F.Mask" "F.Paste")
			(net "GND")
		)
		(pad "252" smd rect
			(at 2.050034 32.725106 270)
			(size 0.519938 1.4986)
			(layers "F.Cu" "F.Mask" "F.Paste")
			(net "M_G_CPU0_SB_DQ<6>")
		)
		(pad "253" smd rect
			(at 2.050034 33.57499 270)
			(size 0.519938 1.4986)
			(layers "F.Cu" "F.Mask" "F.Paste")
			(net "GND")
		)
		(pad "254" smd rect
			(at 2.050034 34.425128 270)
			(size 0.519938 1.4986)
			(layers "F.Cu" "F.Mask" "F.Paste")
			(net "M_G_CPU0_SB_DQ<7>")
		)
		(pad "255" smd rect
			(at 2.050034 35.275012 270)
			(size 0.519938 1.4986)
			(layers "F.Cu" "F.Mask" "F.Paste")
			(net "GND")
		)
		(pad "256" smd rect
			(at 2.050034 36.124896 270)
			(size 0.519938 1.4986)
			(layers "F.Cu" "F.Mask" "F.Paste")
			(net "M_G_CPU0_SB_DQ<10>")
		)
		(pad "257" smd rect
			(at 2.050034 36.975034 270)
			(size 0.519938 1.4986)
			(layers "F.Cu" "F.Mask" "F.Paste")
			(net "GND")
		)
		(pad "258" smd rect
			(at 2.050034 37.824918 270)
			(size 0.519938 1.4986)
			(layers "F.Cu" "F.Mask" "F.Paste")
			(net "M_G_CPU0_SB_DQ<11>")
		)
		(pad "259" smd rect
			(at 2.050034 38.675056 270)
			(size 0.519938 1.4986)
			(layers "F.Cu" "F.Mask" "F.Paste")
			(net "GND")
		)
		(pad "260" smd rect
			(at 2.050034 39.52494 270)
			(size 0.519938 1.4986)
			(layers "F.Cu" "F.Mask" "F.Paste")
			(net "M_G_CPU0_SB_DQS_DN<6>")
		)
		(pad "261" smd rect
			(at 2.050034 40.375078 270)
			(size 0.519938 1.4986)
			(layers "F.Cu" "F.Mask" "F.Paste")
			(net "M_G_CPU0_SB_DQS_DP<6>")
		)
		(pad "262" smd rect
			(at 2.050034 41.224962 270)
			(size 0.519938 1.4986)
			(layers "F.Cu" "F.Mask" "F.Paste")
			(net "GND")
		)
		(pad "263" smd rect
			(at 2.050034 42.0751 270)
			(size 0.519938 1.4986)
			(layers "F.Cu" "F.Mask" "F.Paste")
			(net "M_G_CPU0_SB_DQ<14>")
		)
		(pad "264" smd rect
			(at 2.050034 42.924984 270)
			(size 0.519938 1.4986)
			(layers "F.Cu" "F.Mask" "F.Paste")
			(net "GND")
		)
		(pad "265" smd rect
			(at 2.050034 43.775122 270)
			(size 0.519938 1.4986)
			(layers "F.Cu" "F.Mask" "F.Paste")
			(net "M_G_CPU0_SB_DQ<15>")
		)
		(pad "266" smd rect
			(at 2.050034 44.625006 270)
			(size 0.519938 1.4986)
			(layers "F.Cu" "F.Mask" "F.Paste")
			(net "GND")
		)
		(pad "267" smd rect
			(at 2.050034 45.47489 270)
			(size 0.519938 1.4986)
			(layers "F.Cu" "F.Mask" "F.Paste")
			(net "M_G_CPU0_SB_DQ<18>")
		)
		(pad "268" smd rect
			(at 2.050034 46.325028 270)
			(size 0.519938 1.4986)
			(layers "F.Cu" "F.Mask" "F.Paste")
			(net "GND")
		)
		(pad "269" smd rect
			(at 2.050034 47.174912 270)
			(size 0.519938 1.4986)
			(layers "F.Cu" "F.Mask" "F.Paste")
			(net "M_G_CPU0_SB_DQ<19>")
		)
		(pad "270" smd rect
			(at 2.050034 48.02505 270)
			(size 0.519938 1.4986)
			(layers "F.Cu" "F.Mask" "F.Paste")
			(net "GND")
		)
		(pad "271" smd rect
			(at 2.050034 48.874934 270)
			(size 0.519938 1.4986)
			(layers "F.Cu" "F.Mask" "F.Paste")
			(net "M_G_CPU0_SB_DQS_DN<7>")
		)
		(pad "272" smd rect
			(at 2.050034 49.725072 270)
			(size 0.519938 1.4986)
			(layers "F.Cu" "F.Mask" "F.Paste")
			(net "M_G_CPU0_SB_DQS_DP<7>")
		)
		(pad "273" smd rect
			(at 2.050034 50.574956 270)
			(size 0.519938 1.4986)
			(layers "F.Cu" "F.Mask" "F.Paste")
			(net "GND")
		)
		(pad "274" smd rect
			(at 2.050034 51.425094 270)
			(size 0.519938 1.4986)
			(layers "F.Cu" "F.Mask" "F.Paste")
			(net "M_G_CPU0_SB_DQ<22>")
		)
		(pad "275" smd rect
			(at 2.050034 52.274978 270)
			(size 0.519938 1.4986)
			(layers "F.Cu" "F.Mask" "F.Paste")
			(net "GND")
		)
		(pad "276" smd rect
			(at 2.050034 53.125116 270)
			(size 0.519938 1.4986)
			(layers "F.Cu" "F.Mask" "F.Paste")
			(net "M_G_CPU0_SB_DQ<23>")
		)
		(pad "277" smd rect
			(at 2.050034 53.975 270)
			(size 0.519938 1.4986)
			(layers "F.Cu" "F.Mask" "F.Paste")
			(net "GND")
		)
		(pad "278" smd rect
			(at 2.050034 54.824884 270)
			(size 0.519938 1.4986)
			(layers "F.Cu" "F.Mask" "F.Paste")
			(net "M_G_CPU0_SB_DQ<26>")
		)
		(pad "279" smd rect
			(at 2.050034 55.675022 270)
			(size 0.519938 1.4986)
			(layers "F.Cu" "F.Mask" "F.Paste")
			(net "GND")
		)
		(pad "280" smd rect
			(at 2.050034 56.524906 270)
			(size 0.519938 1.4986)
			(layers "F.Cu" "F.Mask" "F.Paste")
			(net "M_G_CPU0_SB_DQ<27>")
		)
		(pad "281" smd rect
			(at 2.050034 57.375044 270)
			(size 0.519938 1.4986)
			(layers "F.Cu" "F.Mask" "F.Paste")
			(net "GND")
		)
		(pad "282" smd rect
			(at 2.050034 58.224928 270)
			(size 0.519938 1.4986)
			(layers "F.Cu" "F.Mask" "F.Paste")
			(net "M_G_CPU0_SB_DQS_DN<8>")
		)
		(pad "283" smd rect
			(at 2.050034 59.075066 270)
			(size 0.519938 1.4986)
			(layers "F.Cu" "F.Mask" "F.Paste")
			(net "M_G_CPU0_SB_DQS_DP<8>")
		)
		(pad "284" smd rect
			(at 2.050034 59.92495 270)
			(size 0.519938 1.4986)
			(layers "F.Cu" "F.Mask" "F.Paste")
			(net "GND")
		)
		(pad "285" smd rect
			(at 2.050034 60.775088 270)
			(size 0.519938 1.4986)
			(layers "F.Cu" "F.Mask" "F.Paste")
			(net "M_G_CPU0_SB_DQ<30>")
		)
		(pad "286" smd rect
			(at 2.050034 61.624972 270)
			(size 0.519938 1.4986)
			(layers "F.Cu" "F.Mask" "F.Paste")
			(net "GND")
		)
		(pad "287" smd rect
			(at 2.050034 62.47511 270)
			(size 0.519938 1.4986)
			(layers "F.Cu" "F.Mask" "F.Paste")
			(net "M_G_CPU0_SB_DQ<31>")
		)
		(pad "288" smd rect
			(at 2.050034 63.324994 270)
			(size 0.519938 1.4986)
			(layers "F.Cu" "F.Mask" "F.Paste")
			(net "GND")
		)
		(pad "G1" thru_hole oval
			(at 0 -68.97497)
			(size 2.8194 1.5748)
			(drill oval 2.4384 1.1938)
			(layers "*.Cu" "*.Mask")
			(remove_unused_layers no)
			(net "GND")
			(clearance 0.127)
			(thermal_gap 0.127)
		)
		(pad "G2" thru_hole oval
			(at 0 3.875024)
			(size 2.8194 1.5748)
			(drill oval 2.4384 1.1938)
			(layers "*.Cu" "*.Mask")
			(remove_unused_layers no)
			(net "GND")
			(clearance 0.127)
			(thermal_gap 0.127)
		)
		(pad "G3" thru_hole oval
			(at 0 68.97497)
			(size 2.8194 1.5748)
			(drill oval 2.4384 1.1938)
			(layers "*.Cu" "*.Mask")
			(remove_unused_layers no)
			(net "GND")
			(clearance 0.127)
			(thermal_gap 0.127)
		)
	)
	(footprint ""
		(layer "F.Cu")
		(at 292.19398 -53.652674)
		(property "Reference" "R4074"
			(at 0 0 0)
			(layer "F.SilkS")
			(hide yes)
			(effects
				(font
					(size 1.27 1.27)
				)
			)
		)
		(property "Value" ""
			(at 0 0 0)
			(layer "F.Fab")
			(effects
				(font
					(size 1.27 1.27)
				)
			)
		)
		(duplicate_pad_numbers_are_jumpers no)
		(fp_line
			(start -0.7874 -0.4064)
			(end 0.7874 -0.4064)
			(stroke
				(width 0.1524)
				(type default)
			)
			(layer "F.SilkS")
		)
		(fp_line
			(start -0.7874 0.4064)
			(end -0.7874 -0.4064)
			(stroke
				(width 0.1524)
				(type default)
			)
			(layer "F.SilkS")
		)
		(fp_line
			(start 0.7874 -0.4064)
			(end 0.7874 0.4064)
			(stroke
				(width 0.1524)
				(type default)
			)
			(layer "F.SilkS")
		)
		(fp_line
			(start 0.7874 0.4064)
			(end -0.7874 0.4064)
			(stroke
				(width 0.1524)
				(type default)
			)
			(layer "F.SilkS")
		)
		(fp_line
			(start -0.67945 -0.305054)
			(end -0.12065 -0.305054)
			(stroke
				(width 0.1)
				(type default)
			)
			(layer "F.Fab")
		)
		(fp_line
			(start -0.67945 0.3048)
			(end -0.67945 -0.305054)
			(stroke
				(width 0.1)
				(type default)
			)
			(layer "F.Fab")
		)
		(fp_line
			(start -0.12065 -0.305054)
			(end -0.12065 -0.2794)
			(stroke
				(width 0.1)
				(type default)
			)
			(layer "F.Fab")
		)
		(fp_line
			(start -0.12065 -0.2794)
			(end 0.12065 -0.2794)
			(stroke
				(width 0.1)
				(type default)
			)
			(layer "F.Fab")
		)
		(fp_line
			(start -0.12065 0.2794)
			(end -0.12065 0.3048)
			(stroke
				(width 0.1)
				(type default)
			)
			(layer "F.Fab")
		)
		(fp_line
			(start -0.12065 0.3048)
			(end -0.67945 0.3048)
			(stroke
				(width 0.1)
				(type default)
			)
			(layer "F.Fab")
		)
		(fp_line
			(start 0.120396 0.2794)
			(end -0.12065 0.2794)
			(stroke
				(width 0.1)
				(type default)
			)
			(layer "F.Fab")
		)
		(fp_line
			(start 0.120396 0.3048)
			(end 0.120396 0.2794)
			(stroke
				(width 0.1)
				(type default)
			)
			(layer "F.Fab")
		)
		(fp_line
			(start 0.12065 -0.3048)
			(end 0.67945 -0.3048)
			(stroke
				(width 0.1)
				(type default)
			)
			(layer "F.Fab")
		)
		(fp_line
			(start 0.12065 -0.2794)
			(end 0.12065 -0.3048)
			(stroke
				(width 0.1)
				(type default)
			)
			(layer "F.Fab")
		)
		(fp_line
			(start 0.67945 -0.3048)
			(end 0.67945 0.3048)
			(stroke
				(width 0.1)
				(type default)
			)
			(layer "F.Fab")
		)
		(fp_line
			(start 0.67945 0.3048)
			(end 0.120396 0.3048)
			(stroke
				(width 0.1)
				(type default)
			)
			(layer "F.Fab")
		)
		(pad "1" smd circle
			(at -0.40005 0)
			(size 0 0)
			(layers "F.Cu" "F.Mask" "F.Paste")
			(net "P12V_AUX")
		)
		(pad "2" smd circle
			(at 0.40005 0)
			(size 0 0)
			(layers "F.Cu" "F.Mask" "F.Paste")
			(net "P12V_E1S_0_EN_G")
		)
	)
	(footprint ""
		(layer "F.Cu")
		(at 416.160458 -362.087668)
		(property "Reference" "PU69_P0_1"
			(at -7.134098 -6.55193 0)
			(unlocked yes)
			(layer "F.SilkS")
			(effects
				(font
					(size 0.7874 0.5842)
					(thickness 0.1524)
				)
				(justify left)
			)
		)
		(property "Value" ""
			(at 0 0 0)
			(layer "F.Fab")
			(effects
				(font
					(size 1.27 1.27)
				)
			)
		)
		(duplicate_pad_numbers_are_jumpers no)
		(fp_line
			(start -2.500122 -2.999994)
			(end -2.24409 -2.999994)
			(stroke
				(width 0.1524)
				(type default)
			)
			(layer "F.SilkS")
		)
		(fp_line
			(start -2.500122 -2.529078)
			(end -2.500122 -2.999994)
			(stroke
				(width 0.1524)
				(type default)
			)
			(layer "F.SilkS")
		)
		(fp_line
			(start -2.500122 0.6604)
			(end -2.500122 0.229108)
			(stroke
				(width 0.1524)
				(type default)
			)
			(layer "F.SilkS")
		)
		(fp_line
			(start -2.500122 2.999994)
			(end -2.500122 2.339594)
			(stroke
				(width 0.1524)
				(type default)
			)
			(layer "F.SilkS")
		)
		(fp_line
			(start -2.2987 2.999994)
			(end -2.500122 2.999994)
			(stroke
				(width 0.1524)
				(type default)
			)
			(layer "F.SilkS")
		)
		(fp_line
			(start 2.31394 -2.999994)
			(end 2.500122 -2.999994)
			(stroke
				(width 0.1524)
				(type default)
			)
			(layer "F.SilkS")
		)
		(fp_line
			(start 2.500122 -2.999994)
			(end 2.500122 -2.44348)
			(stroke
				(width 0.1524)
				(type default)
			)
			(layer "F.SilkS")
		)
		(fp_line
			(start 2.500122 2.339594)
			(end 2.500122 2.999994)
			(stroke
				(width 0.1524)
				(type default)
			)
			(layer "F.SilkS")
		)
		(fp_line
			(start 2.500122 2.999994)
			(end 2.2987 2.999994)
			(stroke
				(width 0.1524)
				(type default)
			)
			(layer "F.SilkS")
		)
		(fp_poly
			(pts
				(xy -2.16916 -3.647694) (xy -2.67716 -2.631694) (xy -3.18516 -3.647694)
			)
			(stroke
				(width 0)
				(type default)
			)
			(fill yes)
			(layer "F.SilkS")
		)
		(fp_line
			(start -2.500122 -2.999994)
			(end 2.500122 -2.999994)
			(stroke
				(width 0.1)
				(type default)
			)
			(layer "F.Fab")
		)
		(fp_line
			(start -2.500122 2.999994)
			(end -2.500122 -2.999994)
			(stroke
				(width 0.1)
				(type default)
			)
			(layer "F.Fab")
		)
		(fp_line
			(start 2.500122 -2.999994)
			(end 2.500122 2.999994)
			(stroke
				(width 0.1)
				(type default)
			)
			(layer "F.Fab")
		)
		(fp_line
			(start 2.500122 2.999994)
			(end -2.500122 2.999994)
			(stroke
				(width 0.1)
				(type default)
			)
			(layer "F.Fab")
		)
		(fp_poly
			(pts
				(xy -4.218432 -2.783078) (xy -4.218432 -1.767078) (xy -3.202432 -2.275078)
			)
			(stroke
				(width 0)
				(type default)
			)
			(fill yes)
			(layer "F.Fab")
		)
		(pad "1" smd rect
			(at -2.400046 -2.275078 90)
			(size 0.2286 0.6096)
			(layers "F.Cu" "F.Mask" "F.Paste")
			(net "PVCCFA_EHV_FIVRA_CPU0_VOS1")
		)
		(pad "2" smd rect
			(at -2.400046 -1.82499 90)
			(size 0.2286 0.6096)
			(layers "F.Cu" "F.Mask" "F.Paste")
			(net "GND")
		)
		(pad "3" smd rect
			(at -2.400046 -1.374902 90)
			(size 0.2286 0.6096)
			(layers "F.Cu" "F.Mask" "F.Paste")
			(net "PVCCFA_EHV_FIVRA_CPU0_VDD1")
		)
		(pad "4" smd rect
			(at -2.400046 -0.925068 90)
			(size 0.2286 0.6096)
			(layers "F.Cu" "F.Mask" "F.Paste")
			(net "PVCCFA_EHV_FIVRA_CPU0_PVCC1")
		)
		(pad "5" smd rect
			(at -2.400046 -0.47498 90)
			(size 0.2286 0.6096)
			(layers "F.Cu" "F.Mask" "F.Paste")
			(net "GND")
		)
		(pad "6" smd rect
			(at -2.400046 -0.024892 90)
			(size 0.2286 0.6096)
			(layers "F.Cu" "F.Mask" "F.Paste")
			(net "Net_8517")
		)
		(pad "7_9-20_24" smd circle
			(at 0 1.150112 90)
			(size 0 0)
			(layers "F.Cu" "F.Mask" "F.Paste")
			(net "GND")
		)
		(pad "10_19" smd rect
			(at 0 2.899918 90)
			(size 0.6096 4.318)
			(layers "F.Cu" "F.Mask" "F.Paste")
			(net "SW_PVCCFA_EHV_FIVRA_CPU0_SW1")
		)
		(pad "25_29" smd rect
			(at 1.549908 -1.279906 270)
			(size 2.0574 2.3114)
			(layers "F.Cu" "F.Mask" "F.Paste")
			(net "SW_P12V_PVCCFA_EHV_FIVRA_CPU0_R")
		)
		(pad "30" smd rect
			(at 2.05994 -2.899918)
			(size 0.2286 0.6096)
			(layers "F.Cu" "F.Mask" "F.Paste")
			(net "SW_P12V_PVCCFA_EHV_FIVRA_CPU0_R")
		)
		(pad "31" smd rect
			(at 1.610106 -2.899918)
			(size 0.2286 0.6096)
			(layers "F.Cu" "F.Mask" "F.Paste")
			(net "Net_8518")
		)
		(pad "32" smd rect
			(at 1.160018 -2.899918)
			(size 0.2286 0.6096)
			(layers "F.Cu" "F.Mask" "F.Paste")
			(net "SW_PVCCFA_EHV_FIVRA_CPU0_BOOTR1")
		)
		(pad "33" smd rect
			(at 0.70993 -2.899918)
			(size 0.2286 0.6096)
			(layers "F.Cu" "F.Mask" "F.Paste")
			(net "SW_PVCCFA_EHV_FIVRA_CPU0_BOOT1")
		)
		(pad "34" smd rect
			(at 0.260096 -2.899918)
			(size 0.2286 0.6096)
			(layers "F.Cu" "F.Mask" "F.Paste")
			(net "PVCCFA_EHV_FIVRA_CPU0_PWM1")
		)
		(pad "35" smd rect
			(at -0.189992 -2.899918)
			(size 0.2286 0.6096)
			(layers "F.Cu" "F.Mask" "F.Paste")
			(net "PVCCFA_EHV_FIVRA_CPU0_VDD1")
		)
		(pad "36" smd rect
			(at -0.64008 -2.899918)
			(size 0.2286 0.6096)
			(layers "F.Cu" "F.Mask" "F.Paste")
			(net "PVCCFA_EHV_FIVRA_CPU0_BTSEN")
		)
		(pad "37" smd rect
			(at -1.089914 -2.899918)
			(size 0.2286 0.6096)
			(layers "F.Cu" "F.Mask" "F.Paste")
			(net "PVCCFA_EHV_FIVRA_CPU0_LSET1")
		)
		(pad "38" smd rect
			(at -1.540002 -2.899918)
			(size 0.2286 0.6096)
			(layers "F.Cu" "F.Mask" "F.Paste")
			(net "PVCCFA_EHV_FIVRA_CPU0_IMON1")
		)
		(pad "39" smd rect
			(at -1.99009 -2.899918)
			(size 0.2286 0.6096)
			(layers "F.Cu" "F.Mask" "F.Paste")
			(net "PVCCIN_CPU0_VREF")
		)
		(pad "40" smd rect
			(at -0.87503 -1.27508)
			(size 1.7526 1.9558)
			(layers "F.Cu" "F.Mask" "F.Paste")
			(net "GND")
		)
		(pad "41" smd rect
			(at -1.525016 0.249936 270)
			(size 0.3048 0.4572)
			(layers "F.Cu" "F.Mask" "F.Paste")
			(net "Net_8516")
		)
		(zone
			(layer "F.Cu")
			(hatch none 0.5)
			(connect_pads
				(clearance 0)
			)
			(min_thickness 0.25)
			(keepout
				(tracks not_allowed)
				(vias allowed)
				(pads allowed)
				(copperpour not_allowed)
				(footprints allowed)
			)
			(placement
				(enabled no)
				(sheetname "")
			)
			(fill
				(thermal_gap 0.5)
				(thermal_bridge_width 0.5)
				(island_removal_mode 0)
			)
			(polygon
				(pts
					(xy 413.660336 -359.087674) (xy 413.660336 -359.836974) (xy 418.66058 -359.836974) (xy 418.66058 -359.087674)
					(xy 418.370258 -359.087674) (xy 418.370258 -359.54335) (xy 413.950658 -359.54335) (xy 413.950658 -359.087674)
				)
			)
		)
		(zone
			(layer "F.Cu")
			(hatch none 0.5)
			(connect_pads
				(clearance 0)
			)
			(min_thickness 0.25)
			(keepout
				(tracks not_allowed)
				(vias allowed)
				(pads allowed)
				(copperpour not_allowed)
				(footprints allowed)
			)
			(placement
				(enabled no)
				(sheetname "")
			)
			(fill
				(thermal_gap 0.5)
				(thermal_bridge_width 0.5)
				(island_removal_mode 0)
			)
			(polygon
				(pts
					(xy 414.116012 -362.359956) (xy 414.358328 -362.359956) (xy 414.358328 -362.334048) (xy 415.174684 -362.334048)
					(xy 415.174684 -362.009182) (xy 415.209736 -362.009182) (xy 415.209736 -361.387644) (xy 415.16046 -361.338368)
					(xy 413.660336 -361.338368) (xy 413.660336 -361.79506) (xy 414.356042 -361.79506) (xy 414.356042 -361.634532)
					(xy 414.914842 -361.634532) (xy 414.914842 -362.040932) (xy 414.356042 -362.040932) (xy 414.356042 -361.82046)
					(xy 413.660336 -361.82046) (xy 413.660336 -361.94746) (xy 414.116012 -361.94746)
				)
			)
		)
	)
	(footprint ""
		(layer "F.Cu")
		(at 182.964582 -426.8216 180)
		(property "Reference" "R2950"
			(at 0 0 180)
			(layer "F.SilkS")
			(hide yes)
			(effects
				(font
					(size 1.27 1.27)
				)
			)
		)
		(property "Value" ""
			(at 0 0 180)
			(layer "F.Fab")
			(effects
				(font
					(size 1.27 1.27)
				)
			)
		)
		(duplicate_pad_numbers_are_jumpers no)
		(fp_line
			(start 0.7874 0.4064)
			(end -0.7874 0.4064)
			(stroke
				(width 0.1524)
				(type default)
			)
			(layer "F.SilkS")
		)
		(fp_line
			(start 0.7874 -0.4064)
			(end 0.7874 0.4064)
			(stroke
				(width 0.1524)
				(type default)
			)
			(layer "F.SilkS")
		)
		(fp_line
			(start -0.7874 0.4064)
			(end -0.7874 -0.4064)
			(stroke
				(width 0.1524)
				(type default)
			)
			(layer "F.SilkS")
		)
		(fp_line
			(start -0.7874 -0.4064)
			(end 0.7874 -0.4064)
			(stroke
				(width 0.1524)
				(type default)
			)
			(layer "F.SilkS")
		)
		(fp_line
			(start 0.67945 0.3048)
			(end 0.120396 0.3048)
			(stroke
				(width 0.1)
				(type default)
			)
			(layer "F.Fab")
		)
		(fp_line
			(start 0.67945 -0.3048)
			(end 0.67945 0.3048)
			(stroke
				(width 0.1)
				(type default)
			)
			(layer "F.Fab")
		)
		(fp_line
			(start 0.12065 -0.2794)
			(end 0.12065 -0.3048)
			(stroke
				(width 0.1)
				(type default)
			)
			(layer "F.Fab")
		)
		(fp_line
			(start 0.12065 -0.3048)
			(end 0.67945 -0.3048)
			(stroke
				(width 0.1)
				(type default)
			)
			(layer "F.Fab")
		)
		(fp_line
			(start 0.120396 0.3048)
			(end 0.120396 0.2794)
			(stroke
				(width 0.1)
				(type default)
			)
			(layer "F.Fab")
		)
		(fp_line
			(start 0.120396 0.2794)
			(end -0.12065 0.2794)
			(stroke
				(width 0.1)
				(type default)
			)
			(layer "F.Fab")
		)
		(fp_line
			(start -0.12065 0.3048)
			(end -0.67945 0.3048)
			(stroke
				(width 0.1)
				(type default)
			)
			(layer "F.Fab")
		)
		(fp_line
			(start -0.12065 0.2794)
			(end -0.12065 0.3048)
			(stroke
				(width 0.1)
				(type default)
			)
			(layer "F.Fab")
		)
		(fp_line
			(start -0.12065 -0.2794)
			(end 0.12065 -0.2794)
			(stroke
				(width 0.1)
				(type default)
			)
			(layer "F.Fab")
		)
		(fp_line
			(start -0.12065 -0.305054)
			(end -0.12065 -0.2794)
			(stroke
				(width 0.1)
				(type default)
			)
			(layer "F.Fab")
		)
		(fp_line
			(start -0.67945 0.3048)
			(end -0.67945 -0.305054)
			(stroke
				(width 0.1)
				(type default)
			)
			(layer "F.Fab")
		)
		(fp_line
			(start -0.67945 -0.305054)
			(end -0.12065 -0.305054)
			(stroke
				(width 0.1)
				(type default)
			)
			(layer "F.Fab")
		)
		(pad "1" smd circle
			(at -0.40005 0 180)
			(size 0 0)
			(layers "F.Cu" "F.Mask" "F.Paste")
			(net "P3V3_AUX")
		)
		(pad "2" smd circle
			(at 0.40005 0 180)
			(size 0 0)
			(layers "F.Cu" "F.Mask" "F.Paste")
			(net "FM_PDB_BUF_EN_R")
		)
	)
	(footprint ""
		(layer "F.Cu")
		(at 160.83788 -121.376948 180)
		(property "Reference" "R1405"
			(at 0 0 180)
			(layer "F.SilkS")
			(hide yes)
			(effects
				(font
					(size 1.27 1.27)
				)
			)
		)
		(property "Value" ""
			(at 0 0 180)
			(layer "F.Fab")
			(effects
				(font
					(size 1.27 1.27)
				)
			)
		)
		(duplicate_pad_numbers_are_jumpers no)
		(fp_line
			(start 0.7874 0.4064)
			(end -0.7874 0.4064)
			(stroke
				(width 0.1524)
				(type default)
			)
			(layer "F.SilkS")
		)
		(fp_line
			(start 0.7874 -0.4064)
			(end 0.7874 0.4064)
			(stroke
				(width 0.1524)
				(type default)
			)
			(layer "F.SilkS")
		)
		(fp_line
			(start -0.7874 0.4064)
			(end -0.7874 -0.4064)
			(stroke
				(width 0.1524)
				(type default)
			)
			(layer "F.SilkS")
		)
		(fp_line
			(start -0.7874 -0.4064)
			(end 0.7874 -0.4064)
			(stroke
				(width 0.1524)
				(type default)
			)
			(layer "F.SilkS")
		)
		(fp_line
			(start 0.67945 0.3048)
			(end 0.120396 0.3048)
			(stroke
				(width 0.1)
				(type default)
			)
			(layer "F.Fab")
		)
		(fp_line
			(start 0.67945 -0.3048)
			(end 0.67945 0.3048)
			(stroke
				(width 0.1)
				(type default)
			)
			(layer "F.Fab")
		)
		(fp_line
			(start 0.12065 -0.2794)
			(end 0.12065 -0.3048)
			(stroke
				(width 0.1)
				(type default)
			)
			(layer "F.Fab")
		)
		(fp_line
			(start 0.12065 -0.3048)
			(end 0.67945 -0.3048)
			(stroke
				(width 0.1)
				(type default)
			)
			(layer "F.Fab")
		)
		(fp_line
			(start 0.120396 0.3048)
			(end 0.120396 0.2794)
			(stroke
				(width 0.1)
				(type default)
			)
			(layer "F.Fab")
		)
		(fp_line
			(start 0.120396 0.2794)
			(end -0.12065 0.2794)
			(stroke
				(width 0.1)
				(type default)
			)
			(layer "F.Fab")
		)
		(fp_line
			(start -0.12065 0.3048)
			(end -0.67945 0.3048)
			(stroke
				(width 0.1)
				(type default)
			)
			(layer "F.Fab")
		)
		(fp_line
			(start -0.12065 0.2794)
			(end -0.12065 0.3048)
			(stroke
				(width 0.1)
				(type default)
			)
			(layer "F.Fab")
		)
		(fp_line
			(start -0.12065 -0.2794)
			(end 0.12065 -0.2794)
			(stroke
				(width 0.1)
				(type default)
			)
			(layer "F.Fab")
		)
		(fp_line
			(start -0.12065 -0.305054)
			(end -0.12065 -0.2794)
			(stroke
				(width 0.1)
				(type default)
			)
			(layer "F.Fab")
		)
		(fp_line
			(start -0.67945 0.3048)
			(end -0.67945 -0.305054)
			(stroke
				(width 0.1)
				(type default)
			)
			(layer "F.Fab")
		)
		(fp_line
			(start -0.67945 -0.305054)
			(end -0.12065 -0.305054)
			(stroke
				(width 0.1)
				(type default)
			)
			(layer "F.Fab")
		)
		(pad "1" smd circle
			(at -0.40005 0 180)
			(size 0 0)
			(layers "F.Cu" "F.Mask" "F.Paste")
			(net "FM_PVCCIN_CPU0_R_EN")
		)
		(pad "2" smd circle
			(at 0.40005 0 180)
			(size 0 0)
			(layers "F.Cu" "F.Mask" "F.Paste")
			(net "GND")
		)
	)
	(footprint ""
		(layer "F.Cu")
		(at 348.506796 -333.804514 -90)
		(property "Reference" "PC299_P0_1"
			(at 0 0 270)
			(layer "F.SilkS")
			(hide yes)
			(effects
				(font
					(size 1.27 1.27)
				)
			)
		)
		(property "Value" ""
			(at 0 0 270)
			(layer "F.Fab")
			(effects
				(font
					(size 1.27 1.27)
				)
			)
		)
		(duplicate_pad_numbers_are_jumpers no)
		(fp_line
			(start -0.7874 0.4064)
			(end -0.7874 -0.4064)
			(stroke
				(width 0.1524)
				(type default)
			)
			(layer "F.SilkS")
		)
		(fp_line
			(start 0.7874 0.4064)
			(end -0.7874 0.4064)
			(stroke
				(width 0.1524)
				(type default)
			)
			(layer "F.SilkS")
		)
		(fp_line
			(start -0.7874 -0.4064)
			(end 0.7874 -0.4064)
			(stroke
				(width 0.1524)
				(type default)
			)
			(layer "F.SilkS")
		)
		(fp_line
			(start 0.7874 -0.4064)
			(end 0.7874 0.4064)
			(stroke
				(width 0.1524)
				(type default)
			)
			(layer "F.SilkS")
		)
		(fp_line
			(start -0.67945 0.3048)
			(end -0.67945 -0.305054)
			(stroke
				(width 0.1)
				(type default)
			)
			(layer "F.Fab")
		)
		(fp_line
			(start -0.12065 0.3048)
			(end -0.67945 0.3048)
			(stroke
				(width 0.1)
				(type default)
			)
			(layer "F.Fab")
		)
		(fp_line
			(start 0.120396 0.3048)
			(end 0.120396 0.2794)
			(stroke
				(width 0.1)
				(type default)
			)
			(layer "F.Fab")
		)
		(fp_line
			(start 0.67945 0.3048)
			(end 0.120396 0.3048)
			(stroke
				(width 0.1)
				(type default)
			)
			(layer "F.Fab")
		)
		(fp_line
			(start -0.12065 0.2794)
			(end -0.12065 0.3048)
			(stroke
				(width 0.1)
				(type default)
			)
			(layer "F.Fab")
		)
		(fp_line
			(start 0.120396 0.2794)
			(end -0.12065 0.2794)
			(stroke
				(width 0.1)
				(type default)
			)
			(layer "F.Fab")
		)
		(fp_line
			(start -0.12065 -0.2794)
			(end 0.12065 -0.2794)
			(stroke
				(width 0.1)
				(type default)
			)
			(layer "F.Fab")
		)
		(fp_line
			(start 0.12065 -0.2794)
			(end 0.12065 -0.3048)
			(stroke
				(width 0.1)
				(type default)
			)
			(layer "F.Fab")
		)
		(fp_line
			(start 0.12065 -0.3048)
			(end 0.67945 -0.3048)
			(stroke
				(width 0.1)
				(type default)
			)
			(layer "F.Fab")
		)
		(fp_line
			(start 0.67945 -0.3048)
			(end 0.67945 0.3048)
			(stroke
				(width 0.1)
				(type default)
			)
			(layer "F.Fab")
		)
		(fp_line
			(start -0.67945 -0.305054)
			(end -0.12065 -0.305054)
			(stroke
				(width 0.1)
				(type default)
			)
			(layer "F.Fab")
		)
		(fp_line
			(start -0.12065 -0.305054)
			(end -0.12065 -0.2794)
			(stroke
				(width 0.1)
				(type default)
			)
			(layer "F.Fab")
		)
		(pad "1" smd circle
			(at -0.40005 0 270)
			(size 0 0)
			(layers "F.Cu" "F.Mask" "F.Paste")
			(net "SW_P12V_PVCCIN_CPU0_FLT")
		)
		(pad "2" smd circle
			(at 0.40005 0 270)
			(size 0 0)
			(layers "F.Cu" "F.Mask" "F.Paste")
			(net "GND")
		)
	)
	(footprint ""
		(layer "F.Cu")
		(at 117.526816 -258.72694 90)
		(property "Reference" "C306"
			(at 0 0 90)
			(layer "F.SilkS")
			(hide yes)
			(effects
				(font
					(size 1.27 1.27)
				)
			)
		)
		(property "Value" ""
			(at 0 0 90)
			(layer "F.Fab")
			(effects
				(font
					(size 1.27 1.27)
				)
			)
		)
		(duplicate_pad_numbers_are_jumpers no)
		(fp_line
			(start 0.7874 -0.4064)
			(end 0.7874 0.4064)
			(stroke
				(width 0.1524)
				(type default)
			)
			(layer "F.SilkS")
		)
		(fp_line
			(start -0.7874 -0.4064)
			(end 0.7874 -0.4064)
			(stroke
				(width 0.1524)
				(type default)
			)
			(layer "F.SilkS")
		)
		(fp_line
			(start 0.7874 0.4064)
			(end -0.7874 0.4064)
			(stroke
				(width 0.1524)
				(type default)
			)
			(layer "F.SilkS")
		)
		(fp_line
			(start -0.7874 0.4064)
			(end -0.7874 -0.4064)
			(stroke
				(width 0.1524)
				(type default)
			)
			(layer "F.SilkS")
		)
		(fp_line
			(start -0.12065 -0.305054)
			(end -0.12065 -0.2794)
			(stroke
				(width 0.1)
				(type default)
			)
			(layer "F.Fab")
		)
		(fp_line
			(start -0.67945 -0.305054)
			(end -0.12065 -0.305054)
			(stroke
				(width 0.1)
				(type default)
			)
			(layer "F.Fab")
		)
		(fp_line
			(start 0.67945 -0.3048)
			(end 0.67945 0.3048)
			(stroke
				(width 0.1)
				(type default)
			)
			(layer "F.Fab")
		)
		(fp_line
			(start 0.12065 -0.3048)
			(end 0.67945 -0.3048)
			(stroke
				(width 0.1)
				(type default)
			)
			(layer "F.Fab")
		)
		(fp_line
			(start 0.12065 -0.2794)
			(end 0.12065 -0.3048)
			(stroke
				(width 0.1)
				(type default)
			)
			(layer "F.Fab")
		)
		(fp_line
			(start -0.12065 -0.2794)
			(end 0.12065 -0.2794)
			(stroke
				(width 0.1)
				(type default)
			)
			(layer "F.Fab")
		)
		(fp_line
			(start 0.120396 0.2794)
			(end -0.12065 0.2794)
			(stroke
				(width 0.1)
				(type default)
			)
			(layer "F.Fab")
		)
		(fp_line
			(start -0.12065 0.2794)
			(end -0.12065 0.3048)
			(stroke
				(width 0.1)
				(type default)
			)
			(layer "F.Fab")
		)
		(fp_line
			(start 0.67945 0.3048)
			(end 0.120396 0.3048)
			(stroke
				(width 0.1)
				(type default)
			)
			(layer "F.Fab")
		)
		(fp_line
			(start 0.120396 0.3048)
			(end 0.120396 0.2794)
			(stroke
				(width 0.1)
				(type default)
			)
			(layer "F.Fab")
		)
		(fp_line
			(start -0.12065 0.3048)
			(end -0.67945 0.3048)
			(stroke
				(width 0.1)
				(type default)
			)
			(layer "F.Fab")
		)
		(fp_line
			(start -0.67945 0.3048)
			(end -0.67945 -0.305054)
			(stroke
				(width 0.1)
				(type default)
			)
			(layer "F.Fab")
		)
		(pad "1" smd circle
			(at -0.40005 0 90)
			(size 0 0)
			(layers "F.Cu" "F.Mask" "F.Paste")
			(net "PVCCIN_CPU1")
		)
		(pad "2" smd circle
			(at 0.40005 0 90)
			(size 0 0)
			(layers "F.Cu" "F.Mask" "F.Paste")
			(net "GND")
		)
	)
	(footprint ""
		(layer "F.Cu")
		(at 435.588664 -128.877314)
		(property "Reference" "PJ54"
			(at 0.826516 -1.260856 0)
			(unlocked yes)
			(layer "F.SilkS")
			(effects
				(font
					(size 0.7874 0.5842)
					(thickness 0.1524)
				)
				(justify left)
			)
		)
		(property "Value" ""
			(at 0 0 0)
			(layer "F.Fab")
			(effects
				(font
					(size 1.27 1.27)
				)
			)
		)
		(duplicate_pad_numbers_are_jumpers no)
		(pad "1" smd circle
			(at -0.7493 0 90)
			(size 0 0)
			(layers "F.Cu" "F.Mask" "F.Paste")
			(net "VSENSE_PVCCD_HV_CPU0_DP")
		)
		(pad "2" smd rect
			(at 0.7493 0 270)
			(size 0.7112 0.8128)
			(layers "F.Cu" "F.Mask" "F.Paste")
			(net "SH_PVCCD_HV_CPU0")
		)
		(zone
			(layer "F.Cu")
			(hatch none 0.5)
			(connect_pads
				(clearance 0)
			)
			(min_thickness 0.25)
			(keepout
				(tracks allowed)
				(vias not_allowed)
				(pads allowed)
				(copperpour not_allowed)
				(footprints allowed)
			)
			(placement
				(enabled no)
				(sheetname "")
			)
			(fill
				(thermal_gap 0.5)
				(thermal_bridge_width 0.5)
				(island_removal_mode 0)
			)
			(polygon
				(pts
					(xy 434.407564 -128.466088) (xy 436.795164 -128.466088) (xy 436.795164 -129.283714) (xy 434.407564 -129.283714)
				)
			)
		)
	)
	(footprint ""
		(layer "F.Cu")
		(at 378.43841 -402.371052 -90)
		(property "Reference" "C938"
			(at 0 0 270)
			(layer "F.SilkS")
			(hide yes)
			(effects
				(font
					(size 1.27 1.27)
				)
			)
		)
		(property "Value" ""
			(at 0 0 270)
			(layer "F.Fab")
			(effects
				(font
					(size 1.27 1.27)
				)
			)
		)
		(duplicate_pad_numbers_are_jumpers no)
		(fp_line
			(start -0.299974 0.150114)
			(end -0.299974 -0.150114)
			(stroke
				(width 0.1)
				(type default)
			)
			(layer "F.Fab")
		)
		(fp_line
			(start 0.299974 0.150114)
			(end -0.299974 0.150114)
			(stroke
				(width 0.1)
				(type default)
			)
			(layer "F.Fab")
		)
		(fp_line
			(start -0.299974 -0.150114)
			(end 0.299974 -0.150114)
			(stroke
				(width 0.1)
				(type default)
			)
			(layer "F.Fab")
		)
		(fp_line
			(start 0.299974 -0.150114)
			(end 0.299974 0.150114)
			(stroke
				(width 0.1)
				(type default)
			)
			(layer "F.Fab")
		)
		(pad "1" smd rect
			(at -0.2667 0 270)
			(size 0.3048 0.381)
			(layers "F.Cu" "F.Mask" "F.Paste")
			(net "P5E_CPU0_PE2_TX_C_DN<13>")
		)
		(pad "2" smd rect
			(at 0.2667 0 270)
			(size 0.3048 0.381)
			(layers "F.Cu" "F.Mask" "F.Paste")
			(net "P5E_CPU0_PE2_TX_DN<13>")
		)
	)
	(footprint ""
		(layer "F.Cu")
		(at 117.526816 -241.97691 -90)
		(property "Reference" "C290"
			(at 0 0 270)
			(layer "F.SilkS")
			(hide yes)
			(effects
				(font
					(size 1.27 1.27)
				)
			)
		)
		(property "Value" ""
			(at 0 0 270)
			(layer "F.Fab")
			(effects
				(font
					(size 1.27 1.27)
				)
			)
		)
		(duplicate_pad_numbers_are_jumpers no)
		(fp_line
			(start -0.7874 0.4064)
			(end -0.7874 -0.4064)
			(stroke
				(width 0.1524)
				(type default)
			)
			(layer "F.SilkS")
		)
		(fp_line
			(start 0.7874 0.4064)
			(end -0.7874 0.4064)
			(stroke
				(width 0.1524)
				(type default)
			)
			(layer "F.SilkS")
		)
		(fp_line
			(start -0.7874 -0.4064)
			(end 0.7874 -0.4064)
			(stroke
				(width 0.1524)
				(type default)
			)
			(layer "F.SilkS")
		)
		(fp_line
			(start 0.7874 -0.4064)
			(end 0.7874 0.4064)
			(stroke
				(width 0.1524)
				(type default)
			)
			(layer "F.SilkS")
		)
		(fp_line
			(start -0.67945 0.3048)
			(end -0.67945 -0.305054)
			(stroke
				(width 0.1)
				(type default)
			)
			(layer "F.Fab")
		)
		(fp_line
			(start -0.12065 0.3048)
			(end -0.67945 0.3048)
			(stroke
				(width 0.1)
				(type default)
			)
			(layer "F.Fab")
		)
		(fp_line
			(start 0.120396 0.3048)
			(end 0.120396 0.2794)
			(stroke
				(width 0.1)
				(type default)
			)
			(layer "F.Fab")
		)
		(fp_line
			(start 0.67945 0.3048)
			(end 0.120396 0.3048)
			(stroke
				(width 0.1)
				(type default)
			)
			(layer "F.Fab")
		)
		(fp_line
			(start -0.12065 0.2794)
			(end -0.12065 0.3048)
			(stroke
				(width 0.1)
				(type default)
			)
			(layer "F.Fab")
		)
		(fp_line
			(start 0.120396 0.2794)
			(end -0.12065 0.2794)
			(stroke
				(width 0.1)
				(type default)
			)
			(layer "F.Fab")
		)
		(fp_line
			(start -0.12065 -0.2794)
			(end 0.12065 -0.2794)
			(stroke
				(width 0.1)
				(type default)
			)
			(layer "F.Fab")
		)
		(fp_line
			(start 0.12065 -0.2794)
			(end 0.12065 -0.3048)
			(stroke
				(width 0.1)
				(type default)
			)
			(layer "F.Fab")
		)
		(fp_line
			(start 0.12065 -0.3048)
			(end 0.67945 -0.3048)
			(stroke
				(width 0.1)
				(type default)
			)
			(layer "F.Fab")
		)
		(fp_line
			(start 0.67945 -0.3048)
			(end 0.67945 0.3048)
			(stroke
				(width 0.1)
				(type default)
			)
			(layer "F.Fab")
		)
		(fp_line
			(start -0.67945 -0.305054)
			(end -0.12065 -0.305054)
			(stroke
				(width 0.1)
				(type default)
			)
			(layer "F.Fab")
		)
		(fp_line
			(start -0.12065 -0.305054)
			(end -0.12065 -0.2794)
			(stroke
				(width 0.1)
				(type default)
			)
			(layer "F.Fab")
		)
		(pad "1" smd circle
			(at -0.40005 0 270)
			(size 0 0)
			(layers "F.Cu" "F.Mask" "F.Paste")
			(net "PVCCIN_CPU1")
		)
		(pad "2" smd circle
			(at 0.40005 0 270)
			(size 0 0)
			(layers "F.Cu" "F.Mask" "F.Paste")
			(net "GND")
		)
	)
	(footprint ""
		(layer "F.Cu")
		(at 125.124972 -139.178538)
		(property "Reference" "C174"
			(at 0 0 0)
			(layer "F.SilkS")
			(hide yes)
			(effects
				(font
					(size 1.27 1.27)
				)
			)
		)
		(property "Value" ""
			(at 0 0 0)
			(layer "F.Fab")
			(effects
				(font
					(size 1.27 1.27)
				)
			)
		)
		(duplicate_pad_numbers_are_jumpers no)
		(fp_line
			(start -0.7874 -0.4064)
			(end 0.7874 -0.4064)
			(stroke
				(width 0.1524)
				(type default)
			)
			(layer "F.SilkS")
		)
		(fp_line
			(start -0.7874 0.4064)
			(end -0.7874 -0.4064)
			(stroke
				(width 0.1524)
				(type default)
			)
			(layer "F.SilkS")
		)
		(fp_line
			(start 0.7874 -0.4064)
			(end 0.7874 0.4064)
			(stroke
				(width 0.1524)
				(type default)
			)
			(layer "F.SilkS")
		)
		(fp_line
			(start 0.7874 0.4064)
			(end -0.7874 0.4064)
			(stroke
				(width 0.1524)
				(type default)
			)
			(layer "F.SilkS")
		)
		(fp_line
			(start -0.67945 -0.305054)
			(end -0.12065 -0.305054)
			(stroke
				(width 0.1)
				(type default)
			)
			(layer "F.Fab")
		)
		(fp_line
			(start -0.67945 0.3048)
			(end -0.67945 -0.305054)
			(stroke
				(width 0.1)
				(type default)
			)
			(layer "F.Fab")
		)
		(fp_line
			(start -0.12065 -0.305054)
			(end -0.12065 -0.2794)
			(stroke
				(width 0.1)
				(type default)
			)
			(layer "F.Fab")
		)
		(fp_line
			(start -0.12065 -0.2794)
			(end 0.12065 -0.2794)
			(stroke
				(width 0.1)
				(type default)
			)
			(layer "F.Fab")
		)
		(fp_line
			(start -0.12065 0.2794)
			(end -0.12065 0.3048)
			(stroke
				(width 0.1)
				(type default)
			)
			(layer "F.Fab")
		)
		(fp_line
			(start -0.12065 0.3048)
			(end -0.67945 0.3048)
			(stroke
				(width 0.1)
				(type default)
			)
			(layer "F.Fab")
		)
		(fp_line
			(start 0.120396 0.2794)
			(end -0.12065 0.2794)
			(stroke
				(width 0.1)
				(type default)
			)
			(layer "F.Fab")
		)
		(fp_line
			(start 0.120396 0.3048)
			(end 0.120396 0.2794)
			(stroke
				(width 0.1)
				(type default)
			)
			(layer "F.Fab")
		)
		(fp_line
			(start 0.12065 -0.3048)
			(end 0.67945 -0.3048)
			(stroke
				(width 0.1)
				(type default)
			)
			(layer "F.Fab")
		)
		(fp_line
			(start 0.12065 -0.2794)
			(end 0.12065 -0.3048)
			(stroke
				(width 0.1)
				(type default)
			)
			(layer "F.Fab")
		)
		(fp_line
			(start 0.67945 -0.3048)
			(end 0.67945 0.3048)
			(stroke
				(width 0.1)
				(type default)
			)
			(layer "F.Fab")
		)
		(fp_line
			(start 0.67945 0.3048)
			(end 0.120396 0.3048)
			(stroke
				(width 0.1)
				(type default)
			)
			(layer "F.Fab")
		)
		(pad "1" smd circle
			(at -0.40005 0)
			(size 0 0)
			(layers "F.Cu" "F.Mask" "F.Paste")
			(net "P3V3_AUX")
		)
		(pad "2" smd circle
			(at 0.40005 0)
			(size 0 0)
			(layers "F.Cu" "F.Mask" "F.Paste")
			(net "GND")
		)
	)
	(footprint ""
		(layer "F.Cu")
		(at 357.487982 -385.17449 180)
		(property "Reference" "C2271"
			(at 0 0 180)
			(layer "F.SilkS")
			(hide yes)
			(effects
				(font
					(size 1.27 1.27)
				)
			)
		)
		(property "Value" ""
			(at 0 0 180)
			(layer "F.Fab")
			(effects
				(font
					(size 1.27 1.27)
				)
			)
		)
		(duplicate_pad_numbers_are_jumpers no)
		(fp_line
			(start 0.7874 0.4064)
			(end -0.7874 0.4064)
			(stroke
				(width 0.1524)
				(type default)
			)
			(layer "F.SilkS")
		)
		(fp_line
			(start 0.7874 -0.4064)
			(end 0.7874 0.4064)
			(stroke
				(width 0.1524)
				(type default)
			)
			(layer "F.SilkS")
		)
		(fp_line
			(start -0.7874 0.4064)
			(end -0.7874 -0.4064)
			(stroke
				(width 0.1524)
				(type default)
			)
			(layer "F.SilkS")
		)
		(fp_line
			(start -0.7874 -0.4064)
			(end 0.7874 -0.4064)
			(stroke
				(width 0.1524)
				(type default)
			)
			(layer "F.SilkS")
		)
		(fp_line
			(start 0.67945 0.3048)
			(end 0.120396 0.3048)
			(stroke
				(width 0.1)
				(type default)
			)
			(layer "F.Fab")
		)
		(fp_line
			(start 0.67945 -0.3048)
			(end 0.67945 0.3048)
			(stroke
				(width 0.1)
				(type default)
			)
			(layer "F.Fab")
		)
		(fp_line
			(start 0.12065 -0.2794)
			(end 0.12065 -0.3048)
			(stroke
				(width 0.1)
				(type default)
			)
			(layer "F.Fab")
		)
		(fp_line
			(start 0.12065 -0.3048)
			(end 0.67945 -0.3048)
			(stroke
				(width 0.1)
				(type default)
			)
			(layer "F.Fab")
		)
		(fp_line
			(start 0.120396 0.3048)
			(end 0.120396 0.2794)
			(stroke
				(width 0.1)
				(type default)
			)
			(layer "F.Fab")
		)
		(fp_line
			(start 0.120396 0.2794)
			(end -0.12065 0.2794)
			(stroke
				(width 0.1)
				(type default)
			)
			(layer "F.Fab")
		)
		(fp_line
			(start -0.12065 0.3048)
			(end -0.67945 0.3048)
			(stroke
				(width 0.1)
				(type default)
			)
			(layer "F.Fab")
		)
		(fp_line
			(start -0.12065 0.2794)
			(end -0.12065 0.3048)
			(stroke
				(width 0.1)
				(type default)
			)
			(layer "F.Fab")
		)
		(fp_line
			(start -0.12065 -0.2794)
			(end 0.12065 -0.2794)
			(stroke
				(width 0.1)
				(type default)
			)
			(layer "F.Fab")
		)
		(fp_line
			(start -0.12065 -0.305054)
			(end -0.12065 -0.2794)
			(stroke
				(width 0.1)
				(type default)
			)
			(layer "F.Fab")
		)
		(fp_line
			(start -0.67945 0.3048)
			(end -0.67945 -0.305054)
			(stroke
				(width 0.1)
				(type default)
			)
			(layer "F.Fab")
		)
		(fp_line
			(start -0.67945 -0.305054)
			(end -0.12065 -0.305054)
			(stroke
				(width 0.1)
				(type default)
			)
			(layer "F.Fab")
		)
		(pad "1" smd circle
			(at -0.40005 0 180)
			(size 0 0)
			(layers "F.Cu" "F.Mask" "F.Paste")
			(net "GPU_3V3IO_RSVD1_ISO")
		)
		(pad "2" smd circle
			(at 0.40005 0 180)
			(size 0 0)
			(layers "F.Cu" "F.Mask" "F.Paste")
			(net "GND")
		)
	)
	(footprint ""
		(layer "F.Cu")
		(at 261.704582 -71.441056 -90)
		(property "Reference" "PU73"
			(at 0.689864 -2.87274 270)
			(unlocked yes)
			(layer "F.SilkS")
			(effects
				(font
					(size 0.7874 0.5842)
					(thickness 0.1524)
				)
				(justify left)
			)
		)
		(property "Value" ""
			(at 0 0 270)
			(layer "F.Fab")
			(effects
				(font
					(size 1.27 1.27)
				)
			)
		)
		(duplicate_pad_numbers_are_jumpers no)
		(fp_line
			(start -1.549908 2.050034)
			(end -0.5842 2.050034)
			(stroke
				(width 0.1524)
				(type default)
			)
			(layer "F.SilkS")
		)
		(fp_line
			(start 0 2.050034)
			(end 1.549908 2.050034)
			(stroke
				(width 0.1524)
				(type default)
			)
			(layer "F.SilkS")
		)
		(fp_line
			(start 1.549908 2.050034)
			(end 1.549908 1.9304)
			(stroke
				(width 0.1524)
				(type default)
			)
			(layer "F.SilkS")
		)
		(fp_line
			(start -1.549908 1.9812)
			(end -1.549908 2.050034)
			(stroke
				(width 0.1524)
				(type default)
			)
			(layer "F.SilkS")
		)
		(fp_line
			(start 1.549908 -1.9812)
			(end 1.549908 -2.050034)
			(stroke
				(width 0.1524)
				(type default)
			)
			(layer "F.SilkS")
		)
		(fp_line
			(start -1.549908 -2.050034)
			(end -1.549908 -1.9812)
			(stroke
				(width 0.1524)
				(type default)
			)
			(layer "F.SilkS")
		)
		(fp_line
			(start -0.5842 -2.050034)
			(end -1.549908 -2.050034)
			(stroke
				(width 0.1524)
				(type default)
			)
			(layer "F.SilkS")
		)
		(fp_line
			(start 1.549908 -2.050034)
			(end 0.5842 -2.050034)
			(stroke
				(width 0.1524)
				(type default)
			)
			(layer "F.SilkS")
		)
		(fp_poly
			(pts
				(xy -3.273044 -2.227072) (xy -3.273044 -1.211072) (xy -2.257044 -1.719072)
			)
			(stroke
				(width 0)
				(type default)
			)
			(fill yes)
			(layer "F.SilkS")
		)
		(fp_line
			(start -1.549908 2.050034)
			(end 1.549908 2.050034)
			(stroke
				(width 0.1)
				(type default)
			)
			(layer "F.Fab")
		)
		(fp_line
			(start 1.549908 2.050034)
			(end 1.549908 -2.050034)
			(stroke
				(width 0.1)
				(type default)
			)
			(layer "F.Fab")
		)
		(fp_line
			(start -1.549908 -2.050034)
			(end -1.549908 2.050034)
			(stroke
				(width 0.1)
				(type default)
			)
			(layer "F.Fab")
		)
		(fp_line
			(start 1.549908 -2.050034)
			(end -1.549908 -2.050034)
			(stroke
				(width 0.1)
				(type default)
			)
			(layer "F.Fab")
		)
		(fp_poly
			(pts
				(xy -2.9464 -2.208022) (xy -2.9464 -1.192022) (xy -1.9304 -1.700022)
			)
			(stroke
				(width 0)
				(type default)
			)
			(fill yes)
			(layer "F.Fab")
		)
		(pad "1" smd circle
			(at -1.35001 -1.700022 270)
			(size 0 0)
			(layers "F.Cu" "F.Mask" "F.Paste")
			(net "SW_P1V05_PCH_AUX_BST")
		)
		(pad "2" smd rect
			(at -1.400048 -1.199896)
			(size 0.1778 0.8128)
			(layers "F.Cu" "F.Mask" "F.Paste")
			(net "GND")
		)
		(pad "3" smd rect
			(at -1.400048 -0.8001)
			(size 0.1778 0.8128)
			(layers "F.Cu" "F.Mask" "F.Paste")
			(net "P1V05_PCH_AUX_CS")
		)
		(pad "4" smd rect
			(at -1.400048 -0.40005)
			(size 0.1778 0.8128)
			(layers "F.Cu" "F.Mask" "F.Paste")
			(net "P1V05_PCH_AUX_MODE")
		)
		(pad "5" smd rect
			(at -1.400048 0)
			(size 0.1778 0.8128)
			(layers "F.Cu" "F.Mask" "F.Paste")
			(net "P1V05_PCH_AUX_REF")
		)
		(pad "6" smd rect
			(at -1.400048 0.40005)
			(size 0.1778 0.8128)
			(layers "F.Cu" "F.Mask" "F.Paste")
			(net "SH_P1V05_PCH_AUX_N")
		)
		(pad "7" smd rect
			(at -1.400048 0.8001)
			(size 0.1778 0.8128)
			(layers "F.Cu" "F.Mask" "F.Paste")
			(net "P1V05_PCH_AUX_FB")
		)
		(pad "8" smd rect
			(at -1.400048 1.199896)
			(size 0.1778 0.8128)
			(layers "F.Cu" "F.Mask" "F.Paste")
			(net "FM_P1V05_PCH_AUX_R_EN")
		)
		(pad "9" smd rect
			(at -1.400048 1.700022)
			(size 0.3048 0.8128)
			(layers "F.Cu" "F.Mask" "F.Paste")
			(net "PWRGD_P1V05_PCH_AUX_R")
		)
		(pad "10" smd rect
			(at -0.299974 1.299972 270)
			(size 0.3048 2.0066)
			(layers "F.Cu" "F.Mask" "F.Paste")
			(net "SW_P12V_AUX_P1V05_PCH_AUX_FLT")
		)
		(pad "11_18" smd circle
			(at 1.175004 0.275082 270)
			(size 0 0)
			(layers "F.Cu" "F.Mask" "F.Paste")
			(net "GND")
		)
		(pad "19" smd rect
			(at 1.400048 -1.700022 180)
			(size 0.3048 0.8128)
			(layers "F.Cu" "F.Mask" "F.Paste")
			(net "P1V05_PCH_AUX_VCC")
		)
		(pad "20" smd rect
			(at 0.299974 -1.299972 270)
			(size 0.3048 2.0066)
			(layers "F.Cu" "F.Mask" "F.Paste")
			(net "SW_P1V05_PCH_AUX_SW")
		)
		(pad "21" smd rect
			(at -0.299974 -1.299972 270)
			(size 0.3048 2.0066)
			(layers "F.Cu" "F.Mask" "F.Paste")
			(net "SW_P12V_AUX_P1V05_PCH_AUX_FLT")
		)
	)
	(footprint ""
		(layer "F.Cu")
		(at 343.73439 -70.52056 90)
		(property "Reference" "C152"
			(at 0 0 90)
			(layer "F.SilkS")
			(hide yes)
			(effects
				(font
					(size 1.27 1.27)
				)
			)
		)
		(property "Value" ""
			(at 0 0 90)
			(layer "F.Fab")
			(effects
				(font
					(size 1.27 1.27)
				)
			)
		)
		(duplicate_pad_numbers_are_jumpers no)
		(fp_line
			(start 0.299974 -0.150114)
			(end 0.299974 0.150114)
			(stroke
				(width 0.1)
				(type default)
			)
			(layer "F.Fab")
		)
		(fp_line
			(start -0.299974 -0.150114)
			(end 0.299974 -0.150114)
			(stroke
				(width 0.1)
				(type default)
			)
			(layer "F.Fab")
		)
		(fp_line
			(start 0.299974 0.150114)
			(end -0.299974 0.150114)
			(stroke
				(width 0.1)
				(type default)
			)
			(layer "F.Fab")
		)
		(fp_line
			(start -0.299974 0.150114)
			(end -0.299974 -0.150114)
			(stroke
				(width 0.1)
				(type default)
			)
			(layer "F.Fab")
		)
		(pad "1" smd rect
			(at -0.2667 0 90)
			(size 0.3048 0.381)
			(layers "F.Cu" "F.Mask" "F.Paste")
			(net "DMI_CPU0_PCH_TX_C_DP<1>")
		)
		(pad "2" smd rect
			(at 0.2667 0 90)
			(size 0.3048 0.381)
			(layers "F.Cu" "F.Mask" "F.Paste")
			(net "DMI_CPU0_PCH_TX_DP<1>")
		)
	)
	(footprint ""
		(layer "F.Cu")
		(at 465.089748 -62.166246 90)
		(property "Reference" "PL45"
			(at -0.437388 -6.243828 0)
			(unlocked yes)
			(layer "F.SilkS")
			(effects
				(font
					(size 0.7874 0.5842)
					(thickness 0.1524)
				)
				(justify left)
			)
		)
		(property "Value" ""
			(at 0 0 90)
			(layer "F.Fab")
			(effects
				(font
					(size 1.27 1.27)
				)
			)
		)
		(duplicate_pad_numbers_are_jumpers no)
		(fp_line
			(start 2.249932 -2.249932)
			(end 2.249932 -1.3843)
			(stroke
				(width 0.1524)
				(type default)
			)
			(layer "F.SilkS")
		)
		(fp_line
			(start -2.249932 -2.249932)
			(end 2.249932 -2.249932)
			(stroke
				(width 0.1524)
				(type default)
			)
			(layer "F.SilkS")
		)
		(fp_line
			(start -2.249932 -1.3843)
			(end -2.249932 -2.249932)
			(stroke
				(width 0.1524)
				(type default)
			)
			(layer "F.SilkS")
		)
		(fp_line
			(start 2.249932 1.3843)
			(end 2.249932 2.249932)
			(stroke
				(width 0.1524)
				(type default)
			)
			(layer "F.SilkS")
		)
		(fp_line
			(start 2.249932 2.249932)
			(end -2.249932 2.249932)
			(stroke
				(width 0.1524)
				(type default)
			)
			(layer "F.SilkS")
		)
		(fp_line
			(start -2.249932 2.249932)
			(end -2.249932 1.3843)
			(stroke
				(width 0.1524)
				(type default)
			)
			(layer "F.SilkS")
		)
		(fp_line
			(start 2.249932 -2.249932)
			(end 2.249932 2.249932)
			(stroke
				(width 0.1)
				(type default)
			)
			(layer "F.Fab")
		)
		(fp_line
			(start -2.249932 -2.249932)
			(end 2.249932 -2.249932)
			(stroke
				(width 0.1)
				(type default)
			)
			(layer "F.Fab")
		)
		(fp_line
			(start 2.249932 2.249932)
			(end -2.249932 2.249932)
			(stroke
				(width 0.1)
				(type default)
			)
			(layer "F.Fab")
		)
		(fp_line
			(start -2.249932 2.249932)
			(end -2.249932 -2.249932)
			(stroke
				(width 0.1)
				(type default)
			)
			(layer "F.Fab")
		)
		(pad "1" smd rect
			(at -1.82499 0 90)
			(size 1.0668 2.5146)
			(layers "F.Cu" "F.Mask" "F.Paste")
			(net "P12V_AUX")
		)
		(pad "2" smd rect
			(at 1.82499 0 90)
			(size 1.0668 2.5146)
			(layers "F.Cu" "F.Mask" "F.Paste")
			(net "SW_P3V3_AUX_FLT")
		)
	)
	(footprint ""
		(layer "F.Cu")
		(at 94.20606 -414.218628 90)
		(property "Reference" "Q148"
			(at -2.023872 -0.03556 0)
			(unlocked yes)
			(layer "F.SilkS")
			(effects
				(font
					(size 0.7874 0.5842)
					(thickness 0.1524)
				)
				(justify left)
			)
		)
		(property "Value" ""
			(at 0 0 90)
			(layer "F.Fab")
			(effects
				(font
					(size 1.27 1.27)
				)
			)
		)
		(duplicate_pad_numbers_are_jumpers no)
		(fp_line
			(start 1.332738 -1.100074)
			(end 1.332738 1.100074)
			(stroke
				(width 0.1524)
				(type default)
			)
			(layer "F.SilkS")
		)
		(fp_line
			(start 0.4826 -1.100074)
			(end 1.332738 -1.100074)
			(stroke
				(width 0.1524)
				(type default)
			)
			(layer "F.SilkS")
		)
		(fp_line
			(start -0.4826 -1.100074)
			(end 0 -0.541274)
			(stroke
				(width 0.1524)
				(type default)
			)
			(layer "F.SilkS")
		)
		(fp_line
			(start -1.332738 -1.100074)
			(end -0.4826 -1.100074)
			(stroke
				(width 0.1524)
				(type default)
			)
			(layer "F.SilkS")
		)
		(fp_line
			(start 0 -0.541274)
			(end 0.4826 -1.100074)
			(stroke
				(width 0.1524)
				(type default)
			)
			(layer "F.SilkS")
		)
		(fp_line
			(start 1.332738 1.100074)
			(end -1.332738 1.100074)
			(stroke
				(width 0.1524)
				(type default)
			)
			(layer "F.SilkS")
		)
		(fp_line
			(start -1.332738 1.100074)
			(end -1.332738 -1.100074)
			(stroke
				(width 0.1524)
				(type default)
			)
			(layer "F.SilkS")
		)
		(fp_poly
			(pts
				(xy -2.27838 -1.082294) (xy -1.576324 -0.731266) (xy -2.27838 -0.380238)
			)
			(stroke
				(width 0)
				(type default)
			)
			(fill yes)
			(layer "F.SilkS")
		)
		(fp_line
			(start 0.674878 -1.100074)
			(end 0.674878 1.100074)
			(stroke
				(width 0.1)
				(type default)
			)
			(layer "F.Fab")
		)
		(fp_line
			(start -0.674878 -1.100074)
			(end 0.674878 -1.100074)
			(stroke
				(width 0.1)
				(type default)
			)
			(layer "F.Fab")
		)
		(fp_line
			(start 0.674878 1.100074)
			(end -0.674878 1.100074)
			(stroke
				(width 0.1)
				(type default)
			)
			(layer "F.Fab")
		)
		(fp_line
			(start -0.674878 1.100074)
			(end -0.674878 -1.100074)
			(stroke
				(width 0.1)
				(type default)
			)
			(layer "F.Fab")
		)
		(fp_poly
			(pts
				(xy -2.2352 -0.298958) (xy -2.2352 -1.001014) (xy -1.533144 -0.649986)
			)
			(stroke
				(width 0)
				(type default)
			)
			(fill yes)
			(layer "F.Fab")
		)
		(pad "1" smd rect
			(at -0.94996 -0.649986 180)
			(size 0.4318 0.508)
			(layers "F.Cu" "F.Mask" "F.Paste")
			(net "GND")
		)
		(pad "2" smd rect
			(at -0.94996 0 180)
			(size 0.4318 0.508)
			(layers "F.Cu" "F.Mask" "F.Paste")
			(net "HGX_DETECT_N")
		)
		(pad "3" smd rect
			(at -0.94996 0.649986 180)
			(size 0.4318 0.508)
			(layers "F.Cu" "F.Mask" "F.Paste")
			(net "HGX_DETECT_N_ISO")
		)
		(pad "4" smd rect
			(at 0.94996 0.649986 180)
			(size 0.4318 0.508)
			(layers "F.Cu" "F.Mask" "F.Paste")
			(net "GND")
		)
		(pad "5" smd rect
			(at 0.94996 0 180)
			(size 0.4318 0.508)
			(layers "F.Cu" "F.Mask" "F.Paste")
			(net "HGX_DETECT")
		)
		(pad "6" smd rect
			(at 0.94996 -0.649986 180)
			(size 0.4318 0.508)
			(layers "F.Cu" "F.Mask" "F.Paste")
			(net "HGX_DETECT")
		)
	)
	(footprint ""
		(layer "F.Cu")
		(at 313.535314 -27.078686 180)
		(property "Reference" "R1453"
			(at 0 0 180)
			(layer "F.SilkS")
			(hide yes)
			(effects
				(font
					(size 1.27 1.27)
				)
			)
		)
		(property "Value" ""
			(at 0 0 180)
			(layer "F.Fab")
			(effects
				(font
					(size 1.27 1.27)
				)
			)
		)
		(duplicate_pad_numbers_are_jumpers no)
		(fp_line
			(start 0.7874 0.4064)
			(end -0.7874 0.4064)
			(stroke
				(width 0.1524)
				(type default)
			)
			(layer "F.SilkS")
		)
		(fp_line
			(start 0.7874 -0.4064)
			(end 0.7874 0.4064)
			(stroke
				(width 0.1524)
				(type default)
			)
			(layer "F.SilkS")
		)
		(fp_line
			(start -0.7874 0.4064)
			(end -0.7874 -0.4064)
			(stroke
				(width 0.1524)
				(type default)
			)
			(layer "F.SilkS")
		)
		(fp_line
			(start -0.7874 -0.4064)
			(end 0.7874 -0.4064)
			(stroke
				(width 0.1524)
				(type default)
			)
			(layer "F.SilkS")
		)
		(fp_line
			(start 0.67945 0.3048)
			(end 0.120396 0.3048)
			(stroke
				(width 0.1)
				(type default)
			)
			(layer "F.Fab")
		)
		(fp_line
			(start 0.67945 -0.3048)
			(end 0.67945 0.3048)
			(stroke
				(width 0.1)
				(type default)
			)
			(layer "F.Fab")
		)
		(fp_line
			(start 0.12065 -0.2794)
			(end 0.12065 -0.3048)
			(stroke
				(width 0.1)
				(type default)
			)
			(layer "F.Fab")
		)
		(fp_line
			(start 0.12065 -0.3048)
			(end 0.67945 -0.3048)
			(stroke
				(width 0.1)
				(type default)
			)
			(layer "F.Fab")
		)
		(fp_line
			(start 0.120396 0.3048)
			(end 0.120396 0.2794)
			(stroke
				(width 0.1)
				(type default)
			)
			(layer "F.Fab")
		)
		(fp_line
			(start 0.120396 0.2794)
			(end -0.12065 0.2794)
			(stroke
				(width 0.1)
				(type default)
			)
			(layer "F.Fab")
		)
		(fp_line
			(start -0.12065 0.3048)
			(end -0.67945 0.3048)
			(stroke
				(width 0.1)
				(type default)
			)
			(layer "F.Fab")
		)
		(fp_line
			(start -0.12065 0.2794)
			(end -0.12065 0.3048)
			(stroke
				(width 0.1)
				(type default)
			)
			(layer "F.Fab")
		)
		(fp_line
			(start -0.12065 -0.2794)
			(end 0.12065 -0.2794)
			(stroke
				(width 0.1)
				(type default)
			)
			(layer "F.Fab")
		)
		(fp_line
			(start -0.12065 -0.305054)
			(end -0.12065 -0.2794)
			(stroke
				(width 0.1)
				(type default)
			)
			(layer "F.Fab")
		)
		(fp_line
			(start -0.67945 0.3048)
			(end -0.67945 -0.305054)
			(stroke
				(width 0.1)
				(type default)
			)
			(layer "F.Fab")
		)
		(fp_line
			(start -0.67945 -0.305054)
			(end -0.12065 -0.305054)
			(stroke
				(width 0.1)
				(type default)
			)
			(layer "F.Fab")
		)
		(pad "1" smd circle
			(at -0.40005 0 180)
			(size 0 0)
			(layers "F.Cu" "F.Mask" "F.Paste")
			(net "PU_SMB_SML4_3V3AUX_PCH_SCL")
		)
		(pad "2" smd circle
			(at 0.40005 0 180)
			(size 0 0)
			(layers "F.Cu" "F.Mask" "F.Paste")
			(net "P3V3_AUX")
		)
	)
	(footprint ""
		(layer "F.Cu")
		(at 421.54094 -101.270308 -90)
		(property "Reference" "PC2157"
			(at 0 0 270)
			(layer "F.SilkS")
			(hide yes)
			(effects
				(font
					(size 1.27 1.27)
				)
			)
		)
		(property "Value" ""
			(at 0 0 270)
			(layer "F.Fab")
			(effects
				(font
					(size 1.27 1.27)
				)
			)
		)
		(duplicate_pad_numbers_are_jumpers no)
		(fp_line
			(start -0.7874 0.4064)
			(end -0.7874 -0.4064)
			(stroke
				(width 0.1524)
				(type default)
			)
			(layer "F.SilkS")
		)
		(fp_line
			(start 0.7874 0.4064)
			(end -0.7874 0.4064)
			(stroke
				(width 0.1524)
				(type default)
			)
			(layer "F.SilkS")
		)
		(fp_line
			(start -0.7874 -0.4064)
			(end 0.7874 -0.4064)
			(stroke
				(width 0.1524)
				(type default)
			)
			(layer "F.SilkS")
		)
		(fp_line
			(start 0.7874 -0.4064)
			(end 0.7874 0.4064)
			(stroke
				(width 0.1524)
				(type default)
			)
			(layer "F.SilkS")
		)
		(fp_line
			(start -0.67945 0.3048)
			(end -0.67945 -0.305054)
			(stroke
				(width 0.1)
				(type default)
			)
			(layer "F.Fab")
		)
		(fp_line
			(start -0.12065 0.3048)
			(end -0.67945 0.3048)
			(stroke
				(width 0.1)
				(type default)
			)
			(layer "F.Fab")
		)
		(fp_line
			(start 0.120396 0.3048)
			(end 0.120396 0.2794)
			(stroke
				(width 0.1)
				(type default)
			)
			(layer "F.Fab")
		)
		(fp_line
			(start 0.67945 0.3048)
			(end 0.120396 0.3048)
			(stroke
				(width 0.1)
				(type default)
			)
			(layer "F.Fab")
		)
		(fp_line
			(start -0.12065 0.2794)
			(end -0.12065 0.3048)
			(stroke
				(width 0.1)
				(type default)
			)
			(layer "F.Fab")
		)
		(fp_line
			(start 0.120396 0.2794)
			(end -0.12065 0.2794)
			(stroke
				(width 0.1)
				(type default)
			)
			(layer "F.Fab")
		)
		(fp_line
			(start -0.12065 -0.2794)
			(end 0.12065 -0.2794)
			(stroke
				(width 0.1)
				(type default)
			)
			(layer "F.Fab")
		)
		(fp_line
			(start 0.12065 -0.2794)
			(end 0.12065 -0.3048)
			(stroke
				(width 0.1)
				(type default)
			)
			(layer "F.Fab")
		)
		(fp_line
			(start 0.12065 -0.3048)
			(end 0.67945 -0.3048)
			(stroke
				(width 0.1)
				(type default)
			)
			(layer "F.Fab")
		)
		(fp_line
			(start 0.67945 -0.3048)
			(end 0.67945 0.3048)
			(stroke
				(width 0.1)
				(type default)
			)
			(layer "F.Fab")
		)
		(fp_line
			(start -0.67945 -0.305054)
			(end -0.12065 -0.305054)
			(stroke
				(width 0.1)
				(type default)
			)
			(layer "F.Fab")
		)
		(fp_line
			(start -0.12065 -0.305054)
			(end -0.12065 -0.2794)
			(stroke
				(width 0.1)
				(type default)
			)
			(layer "F.Fab")
		)
		(pad "1" smd circle
			(at -0.40005 0 270)
			(size 0 0)
			(layers "F.Cu" "F.Mask" "F.Paste")
			(net "P3V3_OCP_MODE_1")
		)
		(pad "2" smd circle
			(at 0.40005 0 270)
			(size 0 0)
			(layers "F.Cu" "F.Mask" "F.Paste")
			(net "GND")
		)
	)
	(footprint ""
		(layer "F.Cu")
		(at 123.296426 -315.66739 90)
		(property "Reference" "PC83"
			(at 0 0 90)
			(layer "F.SilkS")
			(hide yes)
			(effects
				(font
					(size 1.27 1.27)
				)
			)
		)
		(property "Value" ""
			(at 0 0 90)
			(layer "F.Fab")
			(effects
				(font
					(size 1.27 1.27)
				)
			)
		)
		(duplicate_pad_numbers_are_jumpers no)
		(fp_line
			(start 2.750058 0.999998)
			(end -2.750058 0.999998)
			(stroke
				(width 0.1524)
				(type default)
			)
			(layer "F.SilkS")
		)
		(fp_circle
			(center 0 0.999998)
			(end 0 3.750056)
			(stroke
				(width 0.1524)
				(type default)
			)
			(fill no)
			(layer "F.SilkS")
		)
		(fp_poly
			(pts
				(arc
					(start 2.750058 0.999998)
					(mid 0 3.750056)
					(end -2.750058 0.999998)
				)
			)
			(stroke
				(width 0)
				(type default)
			)
			(fill yes)
			(layer "F.SilkS")
		)
		(fp_circle
			(center 0 0.999998)
			(end 0 3.750056)
			(stroke
				(width 0.1)
				(type default)
			)
			(fill no)
			(layer "F.Fab")
		)
		(pad "1" thru_hole rect
			(at 0 0 90)
			(size 1.5748 1.5748)
			(drill 1.0668)
			(layers "*.Cu" "*.Mask")
			(remove_unused_layers no)
			(net "PVCCIN_CPU1")
			(clearance 0)
			(padstack
				(mode front_inner_back)
				(layer "Inner"
					(shape circle)
					(size 1.5748 1.5748)
					(clearance 0)
				)
				(layer "B.Cu"
					(shape rect)
					(size 1.5748 1.5748)
					(clearance 0)
				)
			)
		)
		(pad "2" thru_hole circle
			(at 0 1.999996 90)
			(size 1.5748 1.5748)
			(drill 1.0668)
			(layers "*.Cu" "*.Mask")
			(remove_unused_layers no)
			(net "GND")
			(clearance 0)
		)
	)
	(footprint ""
		(layer "F.Cu")
		(at 208.1022 -114.0968 180)
		(property "Reference" "C2380"
			(at 0 0 180)
			(layer "F.SilkS")
			(hide yes)
			(effects
				(font
					(size 1.27 1.27)
				)
			)
		)
		(property "Value" ""
			(at 0 0 180)
			(layer "F.Fab")
			(effects
				(font
					(size 1.27 1.27)
				)
			)
		)
		(duplicate_pad_numbers_are_jumpers no)
		(fp_line
			(start 0.7874 0.4064)
			(end -0.7874 0.4064)
			(stroke
				(width 0.1524)
				(type default)
			)
			(layer "F.SilkS")
		)
		(fp_line
			(start 0.7874 -0.4064)
			(end 0.7874 0.4064)
			(stroke
				(width 0.1524)
				(type default)
			)
			(layer "F.SilkS")
		)
		(fp_line
			(start -0.7874 0.4064)
			(end -0.7874 -0.4064)
			(stroke
				(width 0.1524)
				(type default)
			)
			(layer "F.SilkS")
		)
		(fp_line
			(start -0.7874 -0.4064)
			(end 0.7874 -0.4064)
			(stroke
				(width 0.1524)
				(type default)
			)
			(layer "F.SilkS")
		)
		(fp_line
			(start 0.67945 0.3048)
			(end 0.120396 0.3048)
			(stroke
				(width 0.1)
				(type default)
			)
			(layer "F.Fab")
		)
		(fp_line
			(start 0.67945 -0.3048)
			(end 0.67945 0.3048)
			(stroke
				(width 0.1)
				(type default)
			)
			(layer "F.Fab")
		)
		(fp_line
			(start 0.12065 -0.2794)
			(end 0.12065 -0.3048)
			(stroke
				(width 0.1)
				(type default)
			)
			(layer "F.Fab")
		)
		(fp_line
			(start 0.12065 -0.3048)
			(end 0.67945 -0.3048)
			(stroke
				(width 0.1)
				(type default)
			)
			(layer "F.Fab")
		)
		(fp_line
			(start 0.120396 0.3048)
			(end 0.120396 0.2794)
			(stroke
				(width 0.1)
				(type default)
			)
			(layer "F.Fab")
		)
		(fp_line
			(start 0.120396 0.2794)
			(end -0.12065 0.2794)
			(stroke
				(width 0.1)
				(type default)
			)
			(layer "F.Fab")
		)
		(fp_line
			(start -0.12065 0.3048)
			(end -0.67945 0.3048)
			(stroke
				(width 0.1)
				(type default)
			)
			(layer "F.Fab")
		)
		(fp_line
			(start -0.12065 0.2794)
			(end -0.12065 0.3048)
			(stroke
				(width 0.1)
				(type default)
			)
			(layer "F.Fab")
		)
		(fp_line
			(start -0.12065 -0.2794)
			(end 0.12065 -0.2794)
			(stroke
				(width 0.1)
				(type default)
			)
			(layer "F.Fab")
		)
		(fp_line
			(start -0.12065 -0.305054)
			(end -0.12065 -0.2794)
			(stroke
				(width 0.1)
				(type default)
			)
			(layer "F.Fab")
		)
		(fp_line
			(start -0.67945 0.3048)
			(end -0.67945 -0.305054)
			(stroke
				(width 0.1)
				(type default)
			)
			(layer "F.Fab")
		)
		(fp_line
			(start -0.67945 -0.305054)
			(end -0.12065 -0.305054)
			(stroke
				(width 0.1)
				(type default)
			)
			(layer "F.Fab")
		)
		(pad "1" smd circle
			(at -0.40005 0 180)
			(size 0 0)
			(layers "F.Cu" "F.Mask" "F.Paste")
			(net "UV_P2V5_COMP")
		)
		(pad "2" smd circle
			(at 0.40005 0 180)
			(size 0 0)
			(layers "F.Cu" "F.Mask" "F.Paste")
			(net "GND")
		)
	)
	(footprint ""
		(layer "F.Cu")
		(at 350.78543 -355.773736)
		(property "Reference" "R2370"
			(at 0 0 0)
			(layer "F.SilkS")
			(hide yes)
			(effects
				(font
					(size 1.27 1.27)
				)
			)
		)
		(property "Value" ""
			(at 0 0 0)
			(layer "F.Fab")
			(effects
				(font
					(size 1.27 1.27)
				)
			)
		)
		(duplicate_pad_numbers_are_jumpers no)
		(fp_line
			(start -0.7874 -0.4064)
			(end 0.7874 -0.4064)
			(stroke
				(width 0.1524)
				(type default)
			)
			(layer "F.SilkS")
		)
		(fp_line
			(start -0.7874 0.4064)
			(end -0.7874 -0.4064)
			(stroke
				(width 0.1524)
				(type default)
			)
			(layer "F.SilkS")
		)
		(fp_line
			(start 0.7874 -0.4064)
			(end 0.7874 0.4064)
			(stroke
				(width 0.1524)
				(type default)
			)
			(layer "F.SilkS")
		)
		(fp_line
			(start 0.7874 0.4064)
			(end -0.7874 0.4064)
			(stroke
				(width 0.1524)
				(type default)
			)
			(layer "F.SilkS")
		)
		(fp_line
			(start -0.67945 -0.305054)
			(end -0.12065 -0.305054)
			(stroke
				(width 0.1)
				(type default)
			)
			(layer "F.Fab")
		)
		(fp_line
			(start -0.67945 0.3048)
			(end -0.67945 -0.305054)
			(stroke
				(width 0.1)
				(type default)
			)
			(layer "F.Fab")
		)
		(fp_line
			(start -0.12065 -0.305054)
			(end -0.12065 -0.2794)
			(stroke
				(width 0.1)
				(type default)
			)
			(layer "F.Fab")
		)
		(fp_line
			(start -0.12065 -0.2794)
			(end 0.12065 -0.2794)
			(stroke
				(width 0.1)
				(type default)
			)
			(layer "F.Fab")
		)
		(fp_line
			(start -0.12065 0.2794)
			(end -0.12065 0.3048)
			(stroke
				(width 0.1)
				(type default)
			)
			(layer "F.Fab")
		)
		(fp_line
			(start -0.12065 0.3048)
			(end -0.67945 0.3048)
			(stroke
				(width 0.1)
				(type default)
			)
			(layer "F.Fab")
		)
		(fp_line
			(start 0.120396 0.2794)
			(end -0.12065 0.2794)
			(stroke
				(width 0.1)
				(type default)
			)
			(layer "F.Fab")
		)
		(fp_line
			(start 0.120396 0.3048)
			(end 0.120396 0.2794)
			(stroke
				(width 0.1)
				(type default)
			)
			(layer "F.Fab")
		)
		(fp_line
			(start 0.12065 -0.3048)
			(end 0.67945 -0.3048)
			(stroke
				(width 0.1)
				(type default)
			)
			(layer "F.Fab")
		)
		(fp_line
			(start 0.12065 -0.2794)
			(end 0.12065 -0.3048)
			(stroke
				(width 0.1)
				(type default)
			)
			(layer "F.Fab")
		)
		(fp_line
			(start 0.67945 -0.3048)
			(end 0.67945 0.3048)
			(stroke
				(width 0.1)
				(type default)
			)
			(layer "F.Fab")
		)
		(fp_line
			(start 0.67945 0.3048)
			(end 0.120396 0.3048)
			(stroke
				(width 0.1)
				(type default)
			)
			(layer "F.Fab")
		)
		(pad "1" smd circle
			(at -0.40005 0)
			(size 0 0)
			(layers "F.Cu" "F.Mask" "F.Paste")
			(net "SVID_ALERT0_CPU0_R_N")
		)
		(pad "2" smd circle
			(at 0.40005 0)
			(size 0 0)
			(layers "F.Cu" "F.Mask" "F.Paste")
			(net "SVID_ALERT_PVCCIN_CPU0_R")
		)
	)
	(footprint ""
		(layer "F.Cu")
		(at 210.560158 -104.96804)
		(property "Reference" "R4804"
			(at 0 0 0)
			(layer "F.SilkS")
			(hide yes)
			(effects
				(font
					(size 1.27 1.27)
				)
			)
		)
		(property "Value" ""
			(at 0 0 0)
			(layer "F.Fab")
			(effects
				(font
					(size 1.27 1.27)
				)
			)
		)
		(duplicate_pad_numbers_are_jumpers no)
		(fp_line
			(start -0.7874 -0.4064)
			(end 0.7874 -0.4064)
			(stroke
				(width 0.1524)
				(type default)
			)
			(layer "F.SilkS")
		)
		(fp_line
			(start -0.7874 0.4064)
			(end -0.7874 -0.4064)
			(stroke
				(width 0.1524)
				(type default)
			)
			(layer "F.SilkS")
		)
		(fp_line
			(start 0.7874 -0.4064)
			(end 0.7874 0.4064)
			(stroke
				(width 0.1524)
				(type default)
			)
			(layer "F.SilkS")
		)
		(fp_line
			(start 0.7874 0.4064)
			(end -0.7874 0.4064)
			(stroke
				(width 0.1524)
				(type default)
			)
			(layer "F.SilkS")
		)
		(fp_line
			(start -0.67945 -0.305054)
			(end -0.12065 -0.305054)
			(stroke
				(width 0.1)
				(type default)
			)
			(layer "F.Fab")
		)
		(fp_line
			(start -0.67945 0.3048)
			(end -0.67945 -0.305054)
			(stroke
				(width 0.1)
				(type default)
			)
			(layer "F.Fab")
		)
		(fp_line
			(start -0.12065 -0.305054)
			(end -0.12065 -0.2794)
			(stroke
				(width 0.1)
				(type default)
			)
			(layer "F.Fab")
		)
		(fp_line
			(start -0.12065 -0.2794)
			(end 0.12065 -0.2794)
			(stroke
				(width 0.1)
				(type default)
			)
			(layer "F.Fab")
		)
		(fp_line
			(start -0.12065 0.2794)
			(end -0.12065 0.3048)
			(stroke
				(width 0.1)
				(type default)
			)
			(layer "F.Fab")
		)
		(fp_line
			(start -0.12065 0.3048)
			(end -0.67945 0.3048)
			(stroke
				(width 0.1)
				(type default)
			)
			(layer "F.Fab")
		)
		(fp_line
			(start 0.120396 0.2794)
			(end -0.12065 0.2794)
			(stroke
				(width 0.1)
				(type default)
			)
			(layer "F.Fab")
		)
		(fp_line
			(start 0.120396 0.3048)
			(end 0.120396 0.2794)
			(stroke
				(width 0.1)
				(type default)
			)
			(layer "F.Fab")
		)
		(fp_line
			(start 0.12065 -0.3048)
			(end 0.67945 -0.3048)
			(stroke
				(width 0.1)
				(type default)
			)
			(layer "F.Fab")
		)
		(fp_line
			(start 0.12065 -0.2794)
			(end 0.12065 -0.3048)
			(stroke
				(width 0.1)
				(type default)
			)
			(layer "F.Fab")
		)
		(fp_line
			(start 0.67945 -0.3048)
			(end 0.67945 0.3048)
			(stroke
				(width 0.1)
				(type default)
			)
			(layer "F.Fab")
		)
		(fp_line
			(start 0.67945 0.3048)
			(end 0.120396 0.3048)
			(stroke
				(width 0.1)
				(type default)
			)
			(layer "F.Fab")
		)
		(pad "1" smd circle
			(at -0.40005 0)
			(size 0 0)
			(layers "F.Cu" "F.Mask" "F.Paste")
			(net "P3V3_AUX")
		)
		(pad "2" smd circle
			(at 0.40005 0)
			(size 0 0)
			(layers "F.Cu" "F.Mask" "F.Paste")
			(net "U205_VDD")
		)
	)
	(footprint ""
		(layer "F.Cu")
		(at 443.23 -74.640948 90)
		(property "Reference" "PC591"
			(at 0 0 90)
			(layer "F.SilkS")
			(hide yes)
			(effects
				(font
					(size 1.27 1.27)
				)
			)
		)
		(property "Value" ""
			(at 0 0 90)
			(layer "F.Fab")
			(effects
				(font
					(size 1.27 1.27)
				)
			)
		)
		(duplicate_pad_numbers_are_jumpers no)
		(fp_line
			(start 1.2954 -0.5842)
			(end 1.2954 0.5842)
			(stroke
				(width 0.1524)
				(type default)
			)
			(layer "F.SilkS")
		)
		(fp_line
			(start 0 -0.5842)
			(end 0 0.5842)
			(stroke
				(width 0.1524)
				(type default)
			)
			(layer "F.SilkS")
		)
		(fp_line
			(start -1.2954 -0.5842)
			(end 1.2954 -0.5842)
			(stroke
				(width 0.1524)
				(type default)
			)
			(layer "F.SilkS")
		)
		(fp_line
			(start 1.2954 0.5842)
			(end -1.2954 0.5842)
			(stroke
				(width 0.1524)
				(type default)
			)
			(layer "F.SilkS")
		)
		(fp_line
			(start -1.2954 0.5842)
			(end -1.2954 -0.5842)
			(stroke
				(width 0.1524)
				(type default)
			)
			(layer "F.SilkS")
		)
		(fp_line
			(start 0.8636 -0.4572)
			(end 0.8636 -0.4064)
			(stroke
				(width 0.1)
				(type default)
			)
			(layer "F.Fab")
		)
		(fp_line
			(start -0.8636 -0.4572)
			(end 0.8636 -0.4572)
			(stroke
				(width 0.1)
				(type default)
			)
			(layer "F.Fab")
		)
		(fp_line
			(start 1.1938 -0.4064)
			(end 1.1938 0.4064)
			(stroke
				(width 0.1)
				(type default)
			)
			(layer "F.Fab")
		)
		(fp_line
			(start 0.8636 -0.4064)
			(end 1.1938 -0.4064)
			(stroke
				(width 0.1)
				(type default)
			)
			(layer "F.Fab")
		)
		(fp_line
			(start -0.8636 -0.4064)
			(end -0.8636 -0.4572)
			(stroke
				(width 0.1)
				(type default)
			)
			(layer "F.Fab")
		)
		(fp_line
			(start -1.1938 -0.4064)
			(end -0.8636 -0.4064)
			(stroke
				(width 0.1)
				(type default)
			)
			(layer "F.Fab")
		)
		(fp_line
			(start 1.1938 0.4064)
			(end 0.8636 0.4064)
			(stroke
				(width 0.1)
				(type default)
			)
			(layer "F.Fab")
		)
		(fp_line
			(start 0.8636 0.4064)
			(end 0.8636 0.4572)
			(stroke
				(width 0.1)
				(type default)
			)
			(layer "F.Fab")
		)
		(fp_line
			(start -0.8636 0.4064)
			(end -1.1938 0.4064)
			(stroke
				(width 0.1)
				(type default)
			)
			(layer "F.Fab")
		)
		(fp_line
			(start -1.1938 0.4064)
			(end -1.1938 -0.4064)
			(stroke
				(width 0.1)
				(type default)
			)
			(layer "F.Fab")
		)
		(fp_line
			(start 0.8636 0.4572)
			(end -0.8636 0.4572)
			(stroke
				(width 0.1)
				(type default)
			)
			(layer "F.Fab")
		)
		(fp_line
			(start -0.8636 0.4572)
			(end -0.8636 0.4064)
			(stroke
				(width 0.1)
				(type default)
			)
			(layer "F.Fab")
		)
		(pad "1" smd rect
			(at -0.7366 0)
			(size 0.7112 0.8128)
			(layers "F.Cu" "F.Mask" "F.Paste")
			(net "P3V3_AUX_VCC")
		)
		(pad "2" smd rect
			(at 0.7366 0)
			(size 0.7112 0.8128)
			(layers "F.Cu" "F.Mask" "F.Paste")
			(net "GND")
		)
	)
	(footprint ""
		(layer "F.Cu")
		(at 85.915246 -57.279286 90)
		(property "Reference" "PC190"
			(at 0 0 90)
			(layer "F.SilkS")
			(hide yes)
			(effects
				(font
					(size 1.27 1.27)
				)
			)
		)
		(property "Value" ""
			(at 0 0 90)
			(layer "F.Fab")
			(effects
				(font
					(size 1.27 1.27)
				)
			)
		)
		(duplicate_pad_numbers_are_jumpers no)
		(fp_line
			(start 0.7874 -0.4064)
			(end 0.7874 0.4064)
			(stroke
				(width 0.1524)
				(type default)
			)
			(layer "F.SilkS")
		)
		(fp_line
			(start -0.7874 -0.4064)
			(end 0.7874 -0.4064)
			(stroke
				(width 0.1524)
				(type default)
			)
			(layer "F.SilkS")
		)
		(fp_line
			(start 0.7874 0.4064)
			(end -0.7874 0.4064)
			(stroke
				(width 0.1524)
				(type default)
			)
			(layer "F.SilkS")
		)
		(fp_line
			(start -0.7874 0.4064)
			(end -0.7874 -0.4064)
			(stroke
				(width 0.1524)
				(type default)
			)
			(layer "F.SilkS")
		)
		(fp_line
			(start -0.12065 -0.305054)
			(end -0.12065 -0.2794)
			(stroke
				(width 0.1)
				(type default)
			)
			(layer "F.Fab")
		)
		(fp_line
			(start -0.67945 -0.305054)
			(end -0.12065 -0.305054)
			(stroke
				(width 0.1)
				(type default)
			)
			(layer "F.Fab")
		)
		(fp_line
			(start 0.67945 -0.3048)
			(end 0.67945 0.3048)
			(stroke
				(width 0.1)
				(type default)
			)
			(layer "F.Fab")
		)
		(fp_line
			(start 0.12065 -0.3048)
			(end 0.67945 -0.3048)
			(stroke
				(width 0.1)
				(type default)
			)
			(layer "F.Fab")
		)
		(fp_line
			(start 0.12065 -0.2794)
			(end 0.12065 -0.3048)
			(stroke
				(width 0.1)
				(type default)
			)
			(layer "F.Fab")
		)
		(fp_line
			(start -0.12065 -0.2794)
			(end 0.12065 -0.2794)
			(stroke
				(width 0.1)
				(type default)
			)
			(layer "F.Fab")
		)
		(fp_line
			(start 0.120396 0.2794)
			(end -0.12065 0.2794)
			(stroke
				(width 0.1)
				(type default)
			)
			(layer "F.Fab")
		)
		(fp_line
			(start -0.12065 0.2794)
			(end -0.12065 0.3048)
			(stroke
				(width 0.1)
				(type default)
			)
			(layer "F.Fab")
		)
		(fp_line
			(start 0.67945 0.3048)
			(end 0.120396 0.3048)
			(stroke
				(width 0.1)
				(type default)
			)
			(layer "F.Fab")
		)
		(fp_line
			(start 0.120396 0.3048)
			(end 0.120396 0.2794)
			(stroke
				(width 0.1)
				(type default)
			)
			(layer "F.Fab")
		)
		(fp_line
			(start -0.12065 0.3048)
			(end -0.67945 0.3048)
			(stroke
				(width 0.1)
				(type default)
			)
			(layer "F.Fab")
		)
		(fp_line
			(start -0.67945 0.3048)
			(end -0.67945 -0.305054)
			(stroke
				(width 0.1)
				(type default)
			)
			(layer "F.Fab")
		)
		(pad "1" smd circle
			(at -0.40005 0 90)
			(size 0 0)
			(layers "F.Cu" "F.Mask" "F.Paste")
			(net "P3V3_OCP_VCC_2")
		)
		(pad "2" smd circle
			(at 0.40005 0 90)
			(size 0 0)
			(layers "F.Cu" "F.Mask" "F.Paste")
			(net "GND")
		)
	)
	(footprint ""
		(layer "F.Cu")
		(at 176.17948 -426.430948 180)
		(property "Reference" "R2820"
			(at 0 0 180)
			(layer "F.SilkS")
			(hide yes)
			(effects
				(font
					(size 1.27 1.27)
				)
			)
		)
		(property "Value" ""
			(at 0 0 180)
			(layer "F.Fab")
			(effects
				(font
					(size 1.27 1.27)
				)
			)
		)
		(duplicate_pad_numbers_are_jumpers no)
		(fp_line
			(start 0.7874 0.4064)
			(end -0.7874 0.4064)
			(stroke
				(width 0.1524)
				(type default)
			)
			(layer "F.SilkS")
		)
		(fp_line
			(start 0.7874 -0.4064)
			(end 0.7874 0.4064)
			(stroke
				(width 0.1524)
				(type default)
			)
			(layer "F.SilkS")
		)
		(fp_line
			(start -0.7874 0.4064)
			(end -0.7874 -0.4064)
			(stroke
				(width 0.1524)
				(type default)
			)
			(layer "F.SilkS")
		)
		(fp_line
			(start -0.7874 -0.4064)
			(end 0.7874 -0.4064)
			(stroke
				(width 0.1524)
				(type default)
			)
			(layer "F.SilkS")
		)
		(fp_line
			(start 0.67945 0.3048)
			(end 0.120396 0.3048)
			(stroke
				(width 0.1)
				(type default)
			)
			(layer "F.Fab")
		)
		(fp_line
			(start 0.67945 -0.3048)
			(end 0.67945 0.3048)
			(stroke
				(width 0.1)
				(type default)
			)
			(layer "F.Fab")
		)
		(fp_line
			(start 0.12065 -0.2794)
			(end 0.12065 -0.3048)
			(stroke
				(width 0.1)
				(type default)
			)
			(layer "F.Fab")
		)
		(fp_line
			(start 0.12065 -0.3048)
			(end 0.67945 -0.3048)
			(stroke
				(width 0.1)
				(type default)
			)
			(layer "F.Fab")
		)
		(fp_line
			(start 0.120396 0.3048)
			(end 0.120396 0.2794)
			(stroke
				(width 0.1)
				(type default)
			)
			(layer "F.Fab")
		)
		(fp_line
			(start 0.120396 0.2794)
			(end -0.12065 0.2794)
			(stroke
				(width 0.1)
				(type default)
			)
			(layer "F.Fab")
		)
		(fp_line
			(start -0.12065 0.3048)
			(end -0.67945 0.3048)
			(stroke
				(width 0.1)
				(type default)
			)
			(layer "F.Fab")
		)
		(fp_line
			(start -0.12065 0.2794)
			(end -0.12065 0.3048)
			(stroke
				(width 0.1)
				(type default)
			)
			(layer "F.Fab")
		)
		(fp_line
			(start -0.12065 -0.2794)
			(end 0.12065 -0.2794)
			(stroke
				(width 0.1)
				(type default)
			)
			(layer "F.Fab")
		)
		(fp_line
			(start -0.12065 -0.305054)
			(end -0.12065 -0.2794)
			(stroke
				(width 0.1)
				(type default)
			)
			(layer "F.Fab")
		)
		(fp_line
			(start -0.67945 0.3048)
			(end -0.67945 -0.305054)
			(stroke
				(width 0.1)
				(type default)
			)
			(layer "F.Fab")
		)
		(fp_line
			(start -0.67945 -0.305054)
			(end -0.12065 -0.305054)
			(stroke
				(width 0.1)
				(type default)
			)
			(layer "F.Fab")
		)
		(pad "1" smd circle
			(at -0.40005 0 180)
			(size 0 0)
			(layers "F.Cu" "F.Mask" "F.Paste")
			(net "P3V3_AUX")
		)
		(pad "2" smd circle
			(at 0.40005 0 180)
			(size 0 0)
			(layers "F.Cu" "F.Mask" "F.Paste")
			(net "BMC_MONITER_BUF_R")
		)
	)
	(footprint ""
		(layer "F.Cu")
		(at 240.00841 -46.967648 180)
		(property "Reference" "R2317"
			(at 0 0 180)
			(layer "F.SilkS")
			(hide yes)
			(effects
				(font
					(size 1.27 1.27)
				)
			)
		)
		(property "Value" ""
			(at 0 0 180)
			(layer "F.Fab")
			(effects
				(font
					(size 1.27 1.27)
				)
			)
		)
		(duplicate_pad_numbers_are_jumpers no)
		(fp_line
			(start 0.7874 0.4064)
			(end -0.7874 0.4064)
			(stroke
				(width 0.1524)
				(type default)
			)
			(layer "F.SilkS")
		)
		(fp_line
			(start 0.7874 -0.4064)
			(end 0.7874 0.4064)
			(stroke
				(width 0.1524)
				(type default)
			)
			(layer "F.SilkS")
		)
		(fp_line
			(start -0.7874 0.4064)
			(end -0.7874 -0.4064)
			(stroke
				(width 0.1524)
				(type default)
			)
			(layer "F.SilkS")
		)
		(fp_line
			(start -0.7874 -0.4064)
			(end 0.7874 -0.4064)
			(stroke
				(width 0.1524)
				(type default)
			)
			(layer "F.SilkS")
		)
		(fp_line
			(start 0.67945 0.3048)
			(end 0.120396 0.3048)
			(stroke
				(width 0.1)
				(type default)
			)
			(layer "F.Fab")
		)
		(fp_line
			(start 0.67945 -0.3048)
			(end 0.67945 0.3048)
			(stroke
				(width 0.1)
				(type default)
			)
			(layer "F.Fab")
		)
		(fp_line
			(start 0.12065 -0.2794)
			(end 0.12065 -0.3048)
			(stroke
				(width 0.1)
				(type default)
			)
			(layer "F.Fab")
		)
		(fp_line
			(start 0.12065 -0.3048)
			(end 0.67945 -0.3048)
			(stroke
				(width 0.1)
				(type default)
			)
			(layer "F.Fab")
		)
		(fp_line
			(start 0.120396 0.3048)
			(end 0.120396 0.2794)
			(stroke
				(width 0.1)
				(type default)
			)
			(layer "F.Fab")
		)
		(fp_line
			(start 0.120396 0.2794)
			(end -0.12065 0.2794)
			(stroke
				(width 0.1)
				(type default)
			)
			(layer "F.Fab")
		)
		(fp_line
			(start -0.12065 0.3048)
			(end -0.67945 0.3048)
			(stroke
				(width 0.1)
				(type default)
			)
			(layer "F.Fab")
		)
		(fp_line
			(start -0.12065 0.2794)
			(end -0.12065 0.3048)
			(stroke
				(width 0.1)
				(type default)
			)
			(layer "F.Fab")
		)
		(fp_line
			(start -0.12065 -0.2794)
			(end 0.12065 -0.2794)
			(stroke
				(width 0.1)
				(type default)
			)
			(layer "F.Fab")
		)
		(fp_line
			(start -0.12065 -0.305054)
			(end -0.12065 -0.2794)
			(stroke
				(width 0.1)
				(type default)
			)
			(layer "F.Fab")
		)
		(fp_line
			(start -0.67945 0.3048)
			(end -0.67945 -0.305054)
			(stroke
				(width 0.1)
				(type default)
			)
			(layer "F.Fab")
		)
		(fp_line
			(start -0.67945 -0.305054)
			(end -0.12065 -0.305054)
			(stroke
				(width 0.1)
				(type default)
			)
			(layer "F.Fab")
		)
		(pad "1" smd circle
			(at -0.40005 0 180)
			(size 0 0)
			(layers "F.Cu" "F.Mask" "F.Paste")
			(net "P3V3_E1S_0")
		)
		(pad "2" smd circle
			(at 0.40005 0 180)
			(size 0 0)
			(layers "F.Cu" "F.Mask" "F.Paste")
			(net "PU_E1S_0_DUALPORT_EN_N")
		)
	)
	(footprint ""
		(layer "F.Cu")
		(at 24.046942 -414.111948)
		(property "Reference" "R2935"
			(at 0 0 0)
			(layer "F.SilkS")
			(hide yes)
			(effects
				(font
					(size 1.27 1.27)
				)
			)
		)
		(property "Value" ""
			(at 0 0 0)
			(layer "F.Fab")
			(effects
				(font
					(size 1.27 1.27)
				)
			)
		)
		(duplicate_pad_numbers_are_jumpers no)
		(fp_line
			(start -0.7874 -0.4064)
			(end 0.7874 -0.4064)
			(stroke
				(width 0.1524)
				(type default)
			)
			(layer "F.SilkS")
		)
		(fp_line
			(start -0.7874 0.4064)
			(end -0.7874 -0.4064)
			(stroke
				(width 0.1524)
				(type default)
			)
			(layer "F.SilkS")
		)
		(fp_line
			(start 0.7874 -0.4064)
			(end 0.7874 0.4064)
			(stroke
				(width 0.1524)
				(type default)
			)
			(layer "F.SilkS")
		)
		(fp_line
			(start 0.7874 0.4064)
			(end -0.7874 0.4064)
			(stroke
				(width 0.1524)
				(type default)
			)
			(layer "F.SilkS")
		)
		(fp_line
			(start -0.67945 -0.305054)
			(end -0.12065 -0.305054)
			(stroke
				(width 0.1)
				(type default)
			)
			(layer "F.Fab")
		)
		(fp_line
			(start -0.67945 0.3048)
			(end -0.67945 -0.305054)
			(stroke
				(width 0.1)
				(type default)
			)
			(layer "F.Fab")
		)
		(fp_line
			(start -0.12065 -0.305054)
			(end -0.12065 -0.2794)
			(stroke
				(width 0.1)
				(type default)
			)
			(layer "F.Fab")
		)
		(fp_line
			(start -0.12065 -0.2794)
			(end 0.12065 -0.2794)
			(stroke
				(width 0.1)
				(type default)
			)
			(layer "F.Fab")
		)
		(fp_line
			(start -0.12065 0.2794)
			(end -0.12065 0.3048)
			(stroke
				(width 0.1)
				(type default)
			)
			(layer "F.Fab")
		)
		(fp_line
			(start -0.12065 0.3048)
			(end -0.67945 0.3048)
			(stroke
				(width 0.1)
				(type default)
			)
			(layer "F.Fab")
		)
		(fp_line
			(start 0.120396 0.2794)
			(end -0.12065 0.2794)
			(stroke
				(width 0.1)
				(type default)
			)
			(layer "F.Fab")
		)
		(fp_line
			(start 0.120396 0.3048)
			(end 0.120396 0.2794)
			(stroke
				(width 0.1)
				(type default)
			)
			(layer "F.Fab")
		)
		(fp_line
			(start 0.12065 -0.3048)
			(end 0.67945 -0.3048)
			(stroke
				(width 0.1)
				(type default)
			)
			(layer "F.Fab")
		)
		(fp_line
			(start 0.12065 -0.2794)
			(end 0.12065 -0.3048)
			(stroke
				(width 0.1)
				(type default)
			)
			(layer "F.Fab")
		)
		(fp_line
			(start 0.67945 -0.3048)
			(end 0.67945 0.3048)
			(stroke
				(width 0.1)
				(type default)
			)
			(layer "F.Fab")
		)
		(fp_line
			(start 0.67945 0.3048)
			(end 0.120396 0.3048)
			(stroke
				(width 0.1)
				(type default)
			)
			(layer "F.Fab")
		)
		(pad "1" smd circle
			(at -0.40005 0)
			(size 0 0)
			(layers "F.Cu" "F.Mask" "F.Paste")
			(net "P3V3_AUX")
		)
		(pad "2" smd circle
			(at 0.40005 0)
			(size 0 0)
			(layers "F.Cu" "F.Mask" "F.Paste")
			(net "FM_GPU_PWRGD_ISO")
		)
	)
	(footprint ""
		(layer "F.Cu")
		(at 122.292872 -357.11638 90)
		(property "Reference" "PR1314"
			(at 0 0 90)
			(layer "F.SilkS")
			(hide yes)
			(effects
				(font
					(size 1.27 1.27)
				)
			)
		)
		(property "Value" ""
			(at 0 0 90)
			(layer "F.Fab")
			(effects
				(font
					(size 1.27 1.27)
				)
			)
		)
		(duplicate_pad_numbers_are_jumpers no)
		(fp_line
			(start 0.7874 -0.4064)
			(end 0.7874 0.4064)
			(stroke
				(width 0.1524)
				(type default)
			)
			(layer "F.SilkS")
		)
		(fp_line
			(start -0.7874 -0.4064)
			(end 0.7874 -0.4064)
			(stroke
				(width 0.1524)
				(type default)
			)
			(layer "F.SilkS")
		)
		(fp_line
			(start 0.7874 0.4064)
			(end -0.7874 0.4064)
			(stroke
				(width 0.1524)
				(type default)
			)
			(layer "F.SilkS")
		)
		(fp_line
			(start -0.7874 0.4064)
			(end -0.7874 -0.4064)
			(stroke
				(width 0.1524)
				(type default)
			)
			(layer "F.SilkS")
		)
		(fp_line
			(start -0.12065 -0.305054)
			(end -0.12065 -0.2794)
			(stroke
				(width 0.1)
				(type default)
			)
			(layer "F.Fab")
		)
		(fp_line
			(start -0.67945 -0.305054)
			(end -0.12065 -0.305054)
			(stroke
				(width 0.1)
				(type default)
			)
			(layer "F.Fab")
		)
		(fp_line
			(start 0.67945 -0.3048)
			(end 0.67945 0.3048)
			(stroke
				(width 0.1)
				(type default)
			)
			(layer "F.Fab")
		)
		(fp_line
			(start 0.12065 -0.3048)
			(end 0.67945 -0.3048)
			(stroke
				(width 0.1)
				(type default)
			)
			(layer "F.Fab")
		)
		(fp_line
			(start 0.12065 -0.2794)
			(end 0.12065 -0.3048)
			(stroke
				(width 0.1)
				(type default)
			)
			(layer "F.Fab")
		)
		(fp_line
			(start -0.12065 -0.2794)
			(end 0.12065 -0.2794)
			(stroke
				(width 0.1)
				(type default)
			)
			(layer "F.Fab")
		)
		(fp_line
			(start 0.120396 0.2794)
			(end -0.12065 0.2794)
			(stroke
				(width 0.1)
				(type default)
			)
			(layer "F.Fab")
		)
		(fp_line
			(start -0.12065 0.2794)
			(end -0.12065 0.3048)
			(stroke
				(width 0.1)
				(type default)
			)
			(layer "F.Fab")
		)
		(fp_line
			(start 0.67945 0.3048)
			(end 0.120396 0.3048)
			(stroke
				(width 0.1)
				(type default)
			)
			(layer "F.Fab")
		)
		(fp_line
			(start 0.120396 0.3048)
			(end 0.120396 0.2794)
			(stroke
				(width 0.1)
				(type default)
			)
			(layer "F.Fab")
		)
		(fp_line
			(start -0.12065 0.3048)
			(end -0.67945 0.3048)
			(stroke
				(width 0.1)
				(type default)
			)
			(layer "F.Fab")
		)
		(fp_line
			(start -0.67945 0.3048)
			(end -0.67945 -0.305054)
			(stroke
				(width 0.1)
				(type default)
			)
			(layer "F.Fab")
		)
		(pad "1" smd circle
			(at -0.40005 0 90)
			(size 0 0)
			(layers "F.Cu" "F.Mask" "F.Paste")
			(net "PVPP_HBM_CPU1_FB")
		)
		(pad "2" smd circle
			(at 0.40005 0 90)
			(size 0 0)
			(layers "F.Cu" "F.Mask" "F.Paste")
			(net "SH_PVPP_HBM_CPU1_N")
		)
	)
	(footprint ""
		(layer "F.Cu")
		(at 382.005332 -71.134224 180)
		(property "Reference" "PR395"
			(at 0 0 180)
			(layer "F.SilkS")
			(hide yes)
			(effects
				(font
					(size 1.27 1.27)
				)
			)
		)
		(property "Value" ""
			(at 0 0 180)
			(layer "F.Fab")
			(effects
				(font
					(size 1.27 1.27)
				)
			)
		)
		(duplicate_pad_numbers_are_jumpers no)
		(fp_line
			(start 0.7874 0.4064)
			(end -0.7874 0.4064)
			(stroke
				(width 0.1524)
				(type default)
			)
			(layer "F.SilkS")
		)
		(fp_line
			(start 0.7874 -0.4064)
			(end 0.7874 0.4064)
			(stroke
				(width 0.1524)
				(type default)
			)
			(layer "F.SilkS")
		)
		(fp_line
			(start -0.7874 0.4064)
			(end -0.7874 -0.4064)
			(stroke
				(width 0.1524)
				(type default)
			)
			(layer "F.SilkS")
		)
		(fp_line
			(start -0.7874 -0.4064)
			(end 0.7874 -0.4064)
			(stroke
				(width 0.1524)
				(type default)
			)
			(layer "F.SilkS")
		)
		(fp_line
			(start 0.67945 0.3048)
			(end 0.120396 0.3048)
			(stroke
				(width 0.1)
				(type default)
			)
			(layer "F.Fab")
		)
		(fp_line
			(start 0.67945 -0.3048)
			(end 0.67945 0.3048)
			(stroke
				(width 0.1)
				(type default)
			)
			(layer "F.Fab")
		)
		(fp_line
			(start 0.12065 -0.2794)
			(end 0.12065 -0.3048)
			(stroke
				(width 0.1)
				(type default)
			)
			(layer "F.Fab")
		)
		(fp_line
			(start 0.12065 -0.3048)
			(end 0.67945 -0.3048)
			(stroke
				(width 0.1)
				(type default)
			)
			(layer "F.Fab")
		)
		(fp_line
			(start 0.120396 0.3048)
			(end 0.120396 0.2794)
			(stroke
				(width 0.1)
				(type default)
			)
			(layer "F.Fab")
		)
		(fp_line
			(start 0.120396 0.2794)
			(end -0.12065 0.2794)
			(stroke
				(width 0.1)
				(type default)
			)
			(layer "F.Fab")
		)
		(fp_line
			(start -0.12065 0.3048)
			(end -0.67945 0.3048)
			(stroke
				(width 0.1)
				(type default)
			)
			(layer "F.Fab")
		)
		(fp_line
			(start -0.12065 0.2794)
			(end -0.12065 0.3048)
			(stroke
				(width 0.1)
				(type default)
			)
			(layer "F.Fab")
		)
		(fp_line
			(start -0.12065 -0.2794)
			(end 0.12065 -0.2794)
			(stroke
				(width 0.1)
				(type default)
			)
			(layer "F.Fab")
		)
		(fp_line
			(start -0.12065 -0.305054)
			(end -0.12065 -0.2794)
			(stroke
				(width 0.1)
				(type default)
			)
			(layer "F.Fab")
		)
		(fp_line
			(start -0.67945 0.3048)
			(end -0.67945 -0.305054)
			(stroke
				(width 0.1)
				(type default)
			)
			(layer "F.Fab")
		)
		(fp_line
			(start -0.67945 -0.305054)
			(end -0.12065 -0.305054)
			(stroke
				(width 0.1)
				(type default)
			)
			(layer "F.Fab")
		)
		(pad "1" smd circle
			(at -0.40005 0 180)
			(size 0 0)
			(layers "F.Cu" "F.Mask" "F.Paste")
			(net "P3V3_AUX")
		)
		(pad "2" smd circle
			(at 0.40005 0 180)
			(size 0 0)
			(layers "F.Cu" "F.Mask" "F.Paste")
			(net "PVCC1_AUX")
		)
	)
	(footprint ""
		(layer "F.Cu")
		(at 61.778896 -70.78599)
		(property "Reference" "D71"
			(at -33.207706 50.178462 90)
			(unlocked yes)
			(layer "F.SilkS")
			(effects
				(font
					(size 0.635 0.4064)
					(thickness 0.1524)
				)
				(justify left)
			)
		)
		(property "Value" ""
			(at 0 0 0)
			(layer "F.Fab")
			(effects
				(font
					(size 1.27 1.27)
				)
			)
		)
		(duplicate_pad_numbers_are_jumpers no)
		(fp_line
			(start -0.90678 0.4826)
			(end -0.90678 -0.4699)
			(stroke
				(width 0.1524)
				(type default)
			)
			(layer "F.SilkS")
		)
		(fp_line
			(start -0.89408 -0.4826)
			(end 0.90678 -0.4826)
			(stroke
				(width 0.1524)
				(type default)
			)
			(layer "F.SilkS")
		)
		(fp_line
			(start -0.79248 -0.4826)
			(end 1.03378 -0.4826)
			(stroke
				(width 0.1524)
				(type default)
			)
			(layer "F.SilkS")
		)
		(fp_line
			(start -0.64008 -0.4826)
			(end 1.16078 -0.4826)
			(stroke
				(width 0.1524)
				(type default)
			)
			(layer "F.SilkS")
		)
		(fp_line
			(start 0.90678 -0.4826)
			(end 0.90678 0.4826)
			(stroke
				(width 0.1524)
				(type default)
			)
			(layer "F.SilkS")
		)
		(fp_line
			(start 0.90678 0.4826)
			(end -0.90678 0.4826)
			(stroke
				(width 0.1524)
				(type default)
			)
			(layer "F.SilkS")
		)
		(fp_line
			(start 1.03378 -0.4826)
			(end 1.03378 0.4826)
			(stroke
				(width 0.1524)
				(type default)
			)
			(layer "F.SilkS")
		)
		(fp_line
			(start 1.03378 0.4826)
			(end -0.79248 0.4826)
			(stroke
				(width 0.1524)
				(type default)
			)
			(layer "F.SilkS")
		)
		(fp_line
			(start 1.16078 -0.4826)
			(end 1.16078 0.4826)
			(stroke
				(width 0.1524)
				(type default)
			)
			(layer "F.SilkS")
		)
		(fp_line
			(start 1.16078 0.4826)
			(end -0.64008 0.4826)
			(stroke
				(width 0.1524)
				(type default)
			)
			(layer "F.SilkS")
		)
		(fp_line
			(start -0.499872 -0.249936)
			(end 0.499872 -0.249936)
			(stroke
				(width 0.1)
				(type default)
			)
			(layer "F.Fab")
		)
		(fp_line
			(start -0.499872 0.249936)
			(end -0.499872 -0.249936)
			(stroke
				(width 0.1)
				(type default)
			)
			(layer "F.Fab")
		)
		(fp_line
			(start 0.499872 -0.249936)
			(end 0.499872 0.249936)
			(stroke
				(width 0.1)
				(type default)
			)
			(layer "F.Fab")
		)
		(fp_line
			(start 0.499872 0.249936)
			(end -0.499872 0.249936)
			(stroke
				(width 0.1)
				(type default)
			)
			(layer "F.Fab")
		)
		(pad "A" smd rect
			(at -0.47498 0)
			(size 0.6096 0.7112)
			(layers "F.Cu" "F.Mask" "F.Paste")
			(net "LED_RST_PLD_CPU1_DRAM_EF_N")
		)
		(pad "C" smd rect
			(at 0.47498 0)
			(size 0.6096 0.7112)
			(layers "F.Cu" "F.Mask" "F.Paste")
			(net "LED_RST_PLD_CPU1_DRAM_EF_N_D")
		)
	)
	(footprint ""
		(layer "F.Cu")
		(at 80.847438 -408.517344 -90)
		(property "Reference" "C689"
			(at 0 0 270)
			(layer "F.SilkS")
			(hide yes)
			(effects
				(font
					(size 1.27 1.27)
				)
			)
		)
		(property "Value" ""
			(at 0 0 270)
			(layer "F.Fab")
			(effects
				(font
					(size 1.27 1.27)
				)
			)
		)
		(duplicate_pad_numbers_are_jumpers no)
		(fp_line
			(start -0.299974 0.150114)
			(end -0.299974 -0.150114)
			(stroke
				(width 0.1)
				(type default)
			)
			(layer "F.Fab")
		)
		(fp_line
			(start 0.299974 0.150114)
			(end -0.299974 0.150114)
			(stroke
				(width 0.1)
				(type default)
			)
			(layer "F.Fab")
		)
		(fp_line
			(start -0.299974 -0.150114)
			(end 0.299974 -0.150114)
			(stroke
				(width 0.1)
				(type default)
			)
			(layer "F.Fab")
		)
		(fp_line
			(start 0.299974 -0.150114)
			(end 0.299974 0.150114)
			(stroke
				(width 0.1)
				(type default)
			)
			(layer "F.Fab")
		)
		(pad "1" smd rect
			(at -0.2667 0 270)
			(size 0.3048 0.381)
			(layers "F.Cu" "F.Mask" "F.Paste")
			(net "P5E_CPU1_PE4_TX_C_DP<10>")
		)
		(pad "2" smd rect
			(at 0.2667 0 270)
			(size 0.3048 0.381)
			(layers "F.Cu" "F.Mask" "F.Paste")
			(net "P5E_CPU1_PE4_TX_DP<10>")
		)
	)
	(footprint ""
		(layer "F.Cu")
		(at 123.994926 -122.096784 90)
		(property "Reference" "C2253"
			(at 0 0 90)
			(layer "F.SilkS")
			(hide yes)
			(effects
				(font
					(size 1.27 1.27)
				)
			)
		)
		(property "Value" ""
			(at 0 0 90)
			(layer "F.Fab")
			(effects
				(font
					(size 1.27 1.27)
				)
			)
		)
		(duplicate_pad_numbers_are_jumpers no)
		(fp_line
			(start 0.7874 -0.4064)
			(end 0.7874 0.4064)
			(stroke
				(width 0.1524)
				(type default)
			)
			(layer "F.SilkS")
		)
		(fp_line
			(start -0.7874 -0.4064)
			(end 0.7874 -0.4064)
			(stroke
				(width 0.1524)
				(type default)
			)
			(layer "F.SilkS")
		)
		(fp_line
			(start 0.7874 0.4064)
			(end -0.7874 0.4064)
			(stroke
				(width 0.1524)
				(type default)
			)
			(layer "F.SilkS")
		)
		(fp_line
			(start -0.7874 0.4064)
			(end -0.7874 -0.4064)
			(stroke
				(width 0.1524)
				(type default)
			)
			(layer "F.SilkS")
		)
		(fp_line
			(start -0.12065 -0.305054)
			(end -0.12065 -0.2794)
			(stroke
				(width 0.1)
				(type default)
			)
			(layer "F.Fab")
		)
		(fp_line
			(start -0.67945 -0.305054)
			(end -0.12065 -0.305054)
			(stroke
				(width 0.1)
				(type default)
			)
			(layer "F.Fab")
		)
		(fp_line
			(start 0.67945 -0.3048)
			(end 0.67945 0.3048)
			(stroke
				(width 0.1)
				(type default)
			)
			(layer "F.Fab")
		)
		(fp_line
			(start 0.12065 -0.3048)
			(end 0.67945 -0.3048)
			(stroke
				(width 0.1)
				(type default)
			)
			(layer "F.Fab")
		)
		(fp_line
			(start 0.12065 -0.2794)
			(end 0.12065 -0.3048)
			(stroke
				(width 0.1)
				(type default)
			)
			(layer "F.Fab")
		)
		(fp_line
			(start -0.12065 -0.2794)
			(end 0.12065 -0.2794)
			(stroke
				(width 0.1)
				(type default)
			)
			(layer "F.Fab")
		)
		(fp_line
			(start 0.120396 0.2794)
			(end -0.12065 0.2794)
			(stroke
				(width 0.1)
				(type default)
			)
			(layer "F.Fab")
		)
		(fp_line
			(start -0.12065 0.2794)
			(end -0.12065 0.3048)
			(stroke
				(width 0.1)
				(type default)
			)
			(layer "F.Fab")
		)
		(fp_line
			(start 0.67945 0.3048)
			(end 0.120396 0.3048)
			(stroke
				(width 0.1)
				(type default)
			)
			(layer "F.Fab")
		)
		(fp_line
			(start 0.120396 0.3048)
			(end 0.120396 0.2794)
			(stroke
				(width 0.1)
				(type default)
			)
			(layer "F.Fab")
		)
		(fp_line
			(start -0.12065 0.3048)
			(end -0.67945 0.3048)
			(stroke
				(width 0.1)
				(type default)
			)
			(layer "F.Fab")
		)
		(fp_line
			(start -0.67945 0.3048)
			(end -0.67945 -0.305054)
			(stroke
				(width 0.1)
				(type default)
			)
			(layer "F.Fab")
		)
		(pad "1" smd circle
			(at -0.40005 0 90)
			(size 0 0)
			(layers "F.Cu" "F.Mask" "F.Paste")
			(net "P0V62_CPU1_RST_DDR_VREF")
		)
		(pad "2" smd circle
			(at 0.40005 0 90)
			(size 0 0)
			(layers "F.Cu" "F.Mask" "F.Paste")
			(net "GND")
		)
	)
	(footprint ""
		(layer "F.Cu")
		(at 416.54349 -408.517344 -90)
		(property "Reference" "C899"
			(at 0 0 270)
			(layer "F.SilkS")
			(hide yes)
			(effects
				(font
					(size 1.27 1.27)
				)
			)
		)
		(property "Value" ""
			(at 0 0 270)
			(layer "F.Fab")
			(effects
				(font
					(size 1.27 1.27)
				)
			)
		)
		(duplicate_pad_numbers_are_jumpers no)
		(fp_line
			(start -0.299974 0.150114)
			(end -0.299974 -0.150114)
			(stroke
				(width 0.1)
				(type default)
			)
			(layer "F.Fab")
		)
		(fp_line
			(start 0.299974 0.150114)
			(end -0.299974 0.150114)
			(stroke
				(width 0.1)
				(type default)
			)
			(layer "F.Fab")
		)
		(fp_line
			(start -0.299974 -0.150114)
			(end 0.299974 -0.150114)
			(stroke
				(width 0.1)
				(type default)
			)
			(layer "F.Fab")
		)
		(fp_line
			(start 0.299974 -0.150114)
			(end 0.299974 0.150114)
			(stroke
				(width 0.1)
				(type default)
			)
			(layer "F.Fab")
		)
		(pad "1" smd rect
			(at -0.2667 0 270)
			(size 0.3048 0.381)
			(layers "F.Cu" "F.Mask" "F.Paste")
			(net "P5E_CPU0_PE3_TX_C_DP<1>")
		)
		(pad "2" smd rect
			(at 0.2667 0 270)
			(size 0.3048 0.381)
			(layers "F.Cu" "F.Mask" "F.Paste")
			(net "P5E_CPU0_PE3_TX_DP<1>")
		)
	)
	(footprint ""
		(layer "F.Cu")
		(at 352.283014 -252.956314 -90)
		(property "Reference" "C998"
			(at 0 0 270)
			(layer "F.SilkS")
			(hide yes)
			(effects
				(font
					(size 1.27 1.27)
				)
			)
		)
		(property "Value" ""
			(at 0 0 270)
			(layer "F.Fab")
			(effects
				(font
					(size 1.27 1.27)
				)
			)
		)
		(duplicate_pad_numbers_are_jumpers no)
		(fp_line
			(start -0.7874 0.4064)
			(end -0.7874 -0.4064)
			(stroke
				(width 0.1524)
				(type default)
			)
			(layer "F.SilkS")
		)
		(fp_line
			(start 0.7874 0.4064)
			(end -0.7874 0.4064)
			(stroke
				(width 0.1524)
				(type default)
			)
			(layer "F.SilkS")
		)
		(fp_line
			(start -0.7874 -0.4064)
			(end 0.7874 -0.4064)
			(stroke
				(width 0.1524)
				(type default)
			)
			(layer "F.SilkS")
		)
		(fp_line
			(start 0.7874 -0.4064)
			(end 0.7874 0.4064)
			(stroke
				(width 0.1524)
				(type default)
			)
			(layer "F.SilkS")
		)
		(fp_line
			(start -0.67945 0.3048)
			(end -0.67945 -0.305054)
			(stroke
				(width 0.1)
				(type default)
			)
			(layer "F.Fab")
		)
		(fp_line
			(start -0.12065 0.3048)
			(end -0.67945 0.3048)
			(stroke
				(width 0.1)
				(type default)
			)
			(layer "F.Fab")
		)
		(fp_line
			(start 0.120396 0.3048)
			(end 0.120396 0.2794)
			(stroke
				(width 0.1)
				(type default)
			)
			(layer "F.Fab")
		)
		(fp_line
			(start 0.67945 0.3048)
			(end 0.120396 0.3048)
			(stroke
				(width 0.1)
				(type default)
			)
			(layer "F.Fab")
		)
		(fp_line
			(start -0.12065 0.2794)
			(end -0.12065 0.3048)
			(stroke
				(width 0.1)
				(type default)
			)
			(layer "F.Fab")
		)
		(fp_line
			(start 0.120396 0.2794)
			(end -0.12065 0.2794)
			(stroke
				(width 0.1)
				(type default)
			)
			(layer "F.Fab")
		)
		(fp_line
			(start -0.12065 -0.2794)
			(end 0.12065 -0.2794)
			(stroke
				(width 0.1)
				(type default)
			)
			(layer "F.Fab")
		)
		(fp_line
			(start 0.12065 -0.2794)
			(end 0.12065 -0.3048)
			(stroke
				(width 0.1)
				(type default)
			)
			(layer "F.Fab")
		)
		(fp_line
			(start 0.12065 -0.3048)
			(end 0.67945 -0.3048)
			(stroke
				(width 0.1)
				(type default)
			)
			(layer "F.Fab")
		)
		(fp_line
			(start 0.67945 -0.3048)
			(end 0.67945 0.3048)
			(stroke
				(width 0.1)
				(type default)
			)
			(layer "F.Fab")
		)
		(fp_line
			(start -0.67945 -0.305054)
			(end -0.12065 -0.305054)
			(stroke
				(width 0.1)
				(type default)
			)
			(layer "F.Fab")
		)
		(fp_line
			(start -0.12065 -0.305054)
			(end -0.12065 -0.2794)
			(stroke
				(width 0.1)
				(type default)
			)
			(layer "F.Fab")
		)
		(pad "1" smd circle
			(at -0.40005 0 270)
			(size 0 0)
			(layers "F.Cu" "F.Mask" "F.Paste")
			(net "PVCCIN_CPU0")
		)
		(pad "2" smd circle
			(at 0.40005 0 270)
			(size 0 0)
			(layers "F.Cu" "F.Mask" "F.Paste")
			(net "GND")
		)
	)
	(footprint ""
		(layer "F.Cu")
		(at 461.579214 -120.020334)
		(property "Reference" "C579"
			(at 0 0 0)
			(layer "F.SilkS")
			(hide yes)
			(effects
				(font
					(size 1.27 1.27)
				)
			)
		)
		(property "Value" ""
			(at 0 0 0)
			(layer "F.Fab")
			(effects
				(font
					(size 1.27 1.27)
				)
			)
		)
		(duplicate_pad_numbers_are_jumpers no)
		(fp_line
			(start -0.7874 -0.4064)
			(end 0.7874 -0.4064)
			(stroke
				(width 0.1524)
				(type default)
			)
			(layer "F.SilkS")
		)
		(fp_line
			(start -0.7874 0.4064)
			(end -0.7874 -0.4064)
			(stroke
				(width 0.1524)
				(type default)
			)
			(layer "F.SilkS")
		)
		(fp_line
			(start 0.7874 -0.4064)
			(end 0.7874 0.4064)
			(stroke
				(width 0.1524)
				(type default)
			)
			(layer "F.SilkS")
		)
		(fp_line
			(start 0.7874 0.4064)
			(end -0.7874 0.4064)
			(stroke
				(width 0.1524)
				(type default)
			)
			(layer "F.SilkS")
		)
		(fp_line
			(start -0.67945 -0.305054)
			(end -0.12065 -0.305054)
			(stroke
				(width 0.1)
				(type default)
			)
			(layer "F.Fab")
		)
		(fp_line
			(start -0.67945 0.3048)
			(end -0.67945 -0.305054)
			(stroke
				(width 0.1)
				(type default)
			)
			(layer "F.Fab")
		)
		(fp_line
			(start -0.12065 -0.305054)
			(end -0.12065 -0.2794)
			(stroke
				(width 0.1)
				(type default)
			)
			(layer "F.Fab")
		)
		(fp_line
			(start -0.12065 -0.2794)
			(end 0.12065 -0.2794)
			(stroke
				(width 0.1)
				(type default)
			)
			(layer "F.Fab")
		)
		(fp_line
			(start -0.12065 0.2794)
			(end -0.12065 0.3048)
			(stroke
				(width 0.1)
				(type default)
			)
			(layer "F.Fab")
		)
		(fp_line
			(start -0.12065 0.3048)
			(end -0.67945 0.3048)
			(stroke
				(width 0.1)
				(type default)
			)
			(layer "F.Fab")
		)
		(fp_line
			(start 0.120396 0.2794)
			(end -0.12065 0.2794)
			(stroke
				(width 0.1)
				(type default)
			)
			(layer "F.Fab")
		)
		(fp_line
			(start 0.120396 0.3048)
			(end 0.120396 0.2794)
			(stroke
				(width 0.1)
				(type default)
			)
			(layer "F.Fab")
		)
		(fp_line
			(start 0.12065 -0.3048)
			(end 0.67945 -0.3048)
			(stroke
				(width 0.1)
				(type default)
			)
			(layer "F.Fab")
		)
		(fp_line
			(start 0.12065 -0.2794)
			(end 0.12065 -0.3048)
			(stroke
				(width 0.1)
				(type default)
			)
			(layer "F.Fab")
		)
		(fp_line
			(start 0.67945 -0.3048)
			(end 0.67945 0.3048)
			(stroke
				(width 0.1)
				(type default)
			)
			(layer "F.Fab")
		)
		(fp_line
			(start 0.67945 0.3048)
			(end 0.120396 0.3048)
			(stroke
				(width 0.1)
				(type default)
			)
			(layer "F.Fab")
		)
		(pad "1" smd circle
			(at -0.40005 0)
			(size 0 0)
			(layers "F.Cu" "F.Mask" "F.Paste")
			(net "P3V3_AUX")
		)
		(pad "2" smd circle
			(at 0.40005 0)
			(size 0 0)
			(layers "F.Cu" "F.Mask" "F.Paste")
			(net "GND")
		)
	)
	(footprint ""
		(layer "F.Cu")
		(at 205.54188 -109.057948 90)
		(property "Reference" "Q33"
			(at 1.09601 -4.26466 0)
			(unlocked yes)
			(layer "F.SilkS")
			(effects
				(font
					(size 0.7874 0.5842)
					(thickness 0.1524)
				)
				(justify left)
			)
		)
		(property "Value" ""
			(at 0 0 90)
			(layer "F.Fab")
			(effects
				(font
					(size 1.27 1.27)
				)
			)
		)
		(duplicate_pad_numbers_are_jumpers no)
		(fp_line
			(start 1.603248 -1.500124)
			(end 1.603248 1.500124)
			(stroke
				(width 0.1524)
				(type default)
			)
			(layer "F.SilkS")
		)
		(fp_line
			(start -1.603248 -1.500124)
			(end 1.603248 -1.500124)
			(stroke
				(width 0.1524)
				(type default)
			)
			(layer "F.SilkS")
		)
		(fp_line
			(start 1.603248 1.500124)
			(end -1.603248 1.500124)
			(stroke
				(width 0.1524)
				(type default)
			)
			(layer "F.SilkS")
		)
		(fp_line
			(start -1.603248 1.500124)
			(end -1.603248 -1.500124)
			(stroke
				(width 0.1524)
				(type default)
			)
			(layer "F.SilkS")
		)
		(fp_line
			(start 0.700024 -1.500124)
			(end -0.700024 -1.500124)
			(stroke
				(width 0.1)
				(type default)
			)
			(layer "F.Fab")
		)
		(fp_line
			(start -0.700024 -1.500124)
			(end -0.700024 -1.169924)
			(stroke
				(width 0.1)
				(type default)
			)
			(layer "F.Fab")
		)
		(fp_line
			(start -0.700024 -1.169924)
			(end -1.249934 -1.169924)
			(stroke
				(width 0.1)
				(type default)
			)
			(layer "F.Fab")
		)
		(fp_line
			(start -1.249934 -1.169924)
			(end -1.249934 -0.729996)
			(stroke
				(width 0.1)
				(type default)
			)
			(layer "F.Fab")
		)
		(fp_line
			(start -0.6985 -0.729996)
			(end -0.6985 0.729996)
			(stroke
				(width 0.1)
				(type default)
			)
			(layer "F.Fab")
		)
		(fp_line
			(start -1.249934 -0.729996)
			(end -0.6985 -0.729996)
			(stroke
				(width 0.1)
				(type default)
			)
			(layer "F.Fab")
		)
		(fp_line
			(start 1.249934 -0.219964)
			(end 0.700024 -0.219964)
			(stroke
				(width 0.1)
				(type default)
			)
			(layer "F.Fab")
		)
		(fp_line
			(start 0.700024 -0.219964)
			(end 0.700024 -1.500124)
			(stroke
				(width 0.1)
				(type default)
			)
			(layer "F.Fab")
		)
		(fp_line
			(start 1.249934 0.219964)
			(end 1.249934 -0.219964)
			(stroke
				(width 0.1)
				(type default)
			)
			(layer "F.Fab")
		)
		(fp_line
			(start 0.700024 0.219964)
			(end 1.249934 0.219964)
			(stroke
				(width 0.1)
				(type default)
			)
			(layer "F.Fab")
		)
		(fp_line
			(start -0.6985 0.729996)
			(end -1.249934 0.729996)
			(stroke
				(width 0.1)
				(type default)
			)
			(layer "F.Fab")
		)
		(fp_line
			(start -1.249934 0.729996)
			(end -1.249934 1.169924)
			(stroke
				(width 0.1)
				(type default)
			)
			(layer "F.Fab")
		)
		(fp_line
			(start -0.700024 1.169924)
			(end -0.700024 1.500124)
			(stroke
				(width 0.1)
				(type default)
			)
			(layer "F.Fab")
		)
		(fp_line
			(start -1.249934 1.169924)
			(end -0.700024 1.169924)
			(stroke
				(width 0.1)
				(type default)
			)
			(layer "F.Fab")
		)
		(fp_line
			(start 0.700024 1.500124)
			(end 0.700024 0.219964)
			(stroke
				(width 0.1)
				(type default)
			)
			(layer "F.Fab")
		)
		(fp_line
			(start -0.700024 1.500124)
			(end 0.700024 1.500124)
			(stroke
				(width 0.1)
				(type default)
			)
			(layer "F.Fab")
		)
		(fp_rect
			(start -0.700024 -1.500124)
			(end 0.700024 1.500124)
			(stroke
				(width 0)
				(type default)
			)
			(fill no)
			(layer "F.Fab")
		)
		(pad "D" smd rect
			(at 0.999998 0)
			(size 0.8128 0.9144)
			(layers "F.Cu" "F.Mask" "F.Paste")
			(net "LED_CPU_RMCA_CATERR")
		)
		(pad "G" smd rect
			(at -0.999998 -0.94996)
			(size 0.8128 0.9144)
			(layers "F.Cu" "F.Mask" "F.Paste")
			(net "CPU_RMCA_CATERR_LVT3_N")
		)
		(pad "S" smd rect
			(at -0.999998 0.94996)
			(size 0.8128 0.9144)
			(layers "F.Cu" "F.Mask" "F.Paste")
			(net "LED_CPU_RMCA_CATERR_R")
		)
	)
	(footprint ""
		(layer "F.Cu")
		(at 120.603264 -38.005512)
		(property "Reference" "U248"
			(at -1.48336 1.88849 0)
			(unlocked yes)
			(layer "F.SilkS")
			(effects
				(font
					(size 0.7874 0.5842)
					(thickness 0.1524)
				)
				(justify left)
			)
		)
		(property "Value" ""
			(at 0 0 0)
			(layer "F.Fab")
			(effects
				(font
					(size 1.27 1.27)
				)
			)
		)
		(duplicate_pad_numbers_are_jumpers no)
		(fp_line
			(start -1.4986 -1.100074)
			(end 1.4986 -1.100074)
			(stroke
				(width 0.1524)
				(type default)
			)
			(layer "F.SilkS")
		)
		(fp_line
			(start -1.4986 1.100074)
			(end -1.4986 -1.100074)
			(stroke
				(width 0.1524)
				(type default)
			)
			(layer "F.SilkS")
		)
		(fp_line
			(start 1.4986 -1.100074)
			(end 1.4986 1.100074)
			(stroke
				(width 0.1524)
				(type default)
			)
			(layer "F.SilkS")
		)
		(fp_line
			(start 1.4986 1.100074)
			(end -1.4986 1.100074)
			(stroke
				(width 0.1524)
				(type default)
			)
			(layer "F.SilkS")
		)
		(fp_poly
			(pts
				(xy -0.715772 -1.863852) (xy -1.04394 -1.310132) (xy -1.340612 -1.863852)
			)
			(stroke
				(width 0)
				(type default)
			)
			(fill yes)
			(layer "F.SilkS")
		)
		(fp_line
			(start -0.67437 -1.100074)
			(end 0.67437 -1.100074)
			(stroke
				(width 0.1)
				(type default)
			)
			(layer "F.Fab")
		)
		(fp_line
			(start -0.67437 1.100074)
			(end -0.67437 -1.100074)
			(stroke
				(width 0.1)
				(type default)
			)
			(layer "F.Fab")
		)
		(fp_line
			(start 0.67437 -1.100074)
			(end 0.67437 1.100074)
			(stroke
				(width 0.1)
				(type default)
			)
			(layer "F.Fab")
		)
		(fp_line
			(start 0.67437 1.100074)
			(end -0.67437 1.100074)
			(stroke
				(width 0.1)
				(type default)
			)
			(layer "F.Fab")
		)
		(fp_poly
			(pts
				(xy -2.20472 -0.338328) (xy -2.20472 -0.963168) (xy -1.651 -0.635)
			)
			(stroke
				(width 0)
				(type default)
			)
			(fill yes)
			(layer "F.Fab")
		)
		(pad "1" smd rect
			(at -0.889 -0.649986)
			(size 1.016 0.381)
			(layers "F.Cu" "F.Mask" "F.Paste")
			(net "GPU_FPGA_READY_R_N")
		)
		(pad "2" smd rect
			(at -0.889 0)
			(size 1.016 0.381)
			(layers "F.Cu" "F.Mask" "F.Paste")
			(net "CLK_GEN2_GPU_FPGA_OE_R2_N")
		)
		(pad "3" smd rect
			(at -0.889 0.649986)
			(size 1.016 0.381)
			(layers "F.Cu" "F.Mask" "F.Paste")
			(net "GND")
		)
		(pad "4" smd rect
			(at 0.889 0.649986)
			(size 1.016 0.381)
			(layers "F.Cu" "F.Mask" "F.Paste")
			(net "CLK_GEN2_GPU_FPGA_OE_OR_N")
		)
		(pad "5" smd rect
			(at 0.889 -0.649986)
			(size 1.016 0.381)
			(layers "F.Cu" "F.Mask" "F.Paste")
			(net "P3V3_AUX")
		)
	)
	(footprint ""
		(layer "F.Cu")
		(at 420.473632 -170.126914)
		(property "Reference" "PR1774"
			(at 0 0 0)
			(layer "F.SilkS")
			(hide yes)
			(effects
				(font
					(size 1.27 1.27)
				)
			)
		)
		(property "Value" ""
			(at 0 0 0)
			(layer "F.Fab")
			(effects
				(font
					(size 1.27 1.27)
				)
			)
		)
		(duplicate_pad_numbers_are_jumpers no)
		(fp_line
			(start -0.7874 -0.4064)
			(end 0.7874 -0.4064)
			(stroke
				(width 0.1524)
				(type default)
			)
			(layer "F.SilkS")
		)
		(fp_line
			(start -0.7874 0.4064)
			(end -0.7874 -0.4064)
			(stroke
				(width 0.1524)
				(type default)
			)
			(layer "F.SilkS")
		)
		(fp_line
			(start 0.7874 -0.4064)
			(end 0.7874 0.4064)
			(stroke
				(width 0.1524)
				(type default)
			)
			(layer "F.SilkS")
		)
		(fp_line
			(start 0.7874 0.4064)
			(end -0.7874 0.4064)
			(stroke
				(width 0.1524)
				(type default)
			)
			(layer "F.SilkS")
		)
		(fp_line
			(start -0.67945 -0.305054)
			(end -0.12065 -0.305054)
			(stroke
				(width 0.1)
				(type default)
			)
			(layer "F.Fab")
		)
		(fp_line
			(start -0.67945 0.3048)
			(end -0.67945 -0.305054)
			(stroke
				(width 0.1)
				(type default)
			)
			(layer "F.Fab")
		)
		(fp_line
			(start -0.12065 -0.305054)
			(end -0.12065 -0.2794)
			(stroke
				(width 0.1)
				(type default)
			)
			(layer "F.Fab")
		)
		(fp_line
			(start -0.12065 -0.2794)
			(end 0.12065 -0.2794)
			(stroke
				(width 0.1)
				(type default)
			)
			(layer "F.Fab")
		)
		(fp_line
			(start -0.12065 0.2794)
			(end -0.12065 0.3048)
			(stroke
				(width 0.1)
				(type default)
			)
			(layer "F.Fab")
		)
		(fp_line
			(start -0.12065 0.3048)
			(end -0.67945 0.3048)
			(stroke
				(width 0.1)
				(type default)
			)
			(layer "F.Fab")
		)
		(fp_line
			(start 0.120396 0.2794)
			(end -0.12065 0.2794)
			(stroke
				(width 0.1)
				(type default)
			)
			(layer "F.Fab")
		)
		(fp_line
			(start 0.120396 0.3048)
			(end 0.120396 0.2794)
			(stroke
				(width 0.1)
				(type default)
			)
			(layer "F.Fab")
		)
		(fp_line
			(start 0.12065 -0.3048)
			(end 0.67945 -0.3048)
			(stroke
				(width 0.1)
				(type default)
			)
			(layer "F.Fab")
		)
		(fp_line
			(start 0.12065 -0.2794)
			(end 0.12065 -0.3048)
			(stroke
				(width 0.1)
				(type default)
			)
			(layer "F.Fab")
		)
		(fp_line
			(start 0.67945 -0.3048)
			(end 0.67945 0.3048)
			(stroke
				(width 0.1)
				(type default)
			)
			(layer "F.Fab")
		)
		(fp_line
			(start 0.67945 0.3048)
			(end 0.120396 0.3048)
			(stroke
				(width 0.1)
				(type default)
			)
			(layer "F.Fab")
		)
		(pad "1" smd circle
			(at -0.40005 0)
			(size 0 0)
			(layers "F.Cu" "F.Mask" "F.Paste")
			(net "SW_PVCCINFAON_CPU0_BOOT1")
		)
		(pad "2" smd circle
			(at 0.40005 0)
			(size 0 0)
			(layers "F.Cu" "F.Mask" "F.Paste")
			(net "SW_PVCCINFAON_CPU0_BOOT1_R")
		)
	)
	(footprint ""
		(layer "F.Cu")
		(at 101.833934 -396.44574 180)
		(property "Reference" "R3493"
			(at 0 0 180)
			(layer "F.SilkS")
			(hide yes)
			(effects
				(font
					(size 1.27 1.27)
				)
			)
		)
		(property "Value" ""
			(at 0 0 180)
			(layer "F.Fab")
			(effects
				(font
					(size 1.27 1.27)
				)
			)
		)
		(duplicate_pad_numbers_are_jumpers no)
		(fp_line
			(start 0.7874 0.4064)
			(end -0.7874 0.4064)
			(stroke
				(width 0.1524)
				(type default)
			)
			(layer "F.SilkS")
		)
		(fp_line
			(start 0.7874 -0.4064)
			(end 0.7874 0.4064)
			(stroke
				(width 0.1524)
				(type default)
			)
			(layer "F.SilkS")
		)
		(fp_line
			(start -0.7874 0.4064)
			(end -0.7874 -0.4064)
			(stroke
				(width 0.1524)
				(type default)
			)
			(layer "F.SilkS")
		)
		(fp_line
			(start -0.7874 -0.4064)
			(end 0.7874 -0.4064)
			(stroke
				(width 0.1524)
				(type default)
			)
			(layer "F.SilkS")
		)
		(fp_line
			(start 0.67945 0.3048)
			(end 0.120396 0.3048)
			(stroke
				(width 0.1)
				(type default)
			)
			(layer "F.Fab")
		)
		(fp_line
			(start 0.67945 -0.3048)
			(end 0.67945 0.3048)
			(stroke
				(width 0.1)
				(type default)
			)
			(layer "F.Fab")
		)
		(fp_line
			(start 0.12065 -0.2794)
			(end 0.12065 -0.3048)
			(stroke
				(width 0.1)
				(type default)
			)
			(layer "F.Fab")
		)
		(fp_line
			(start 0.12065 -0.3048)
			(end 0.67945 -0.3048)
			(stroke
				(width 0.1)
				(type default)
			)
			(layer "F.Fab")
		)
		(fp_line
			(start 0.120396 0.3048)
			(end 0.120396 0.2794)
			(stroke
				(width 0.1)
				(type default)
			)
			(layer "F.Fab")
		)
		(fp_line
			(start 0.120396 0.2794)
			(end -0.12065 0.2794)
			(stroke
				(width 0.1)
				(type default)
			)
			(layer "F.Fab")
		)
		(fp_line
			(start -0.12065 0.3048)
			(end -0.67945 0.3048)
			(stroke
				(width 0.1)
				(type default)
			)
			(layer "F.Fab")
		)
		(fp_line
			(start -0.12065 0.2794)
			(end -0.12065 0.3048)
			(stroke
				(width 0.1)
				(type default)
			)
			(layer "F.Fab")
		)
		(fp_line
			(start -0.12065 -0.2794)
			(end 0.12065 -0.2794)
			(stroke
				(width 0.1)
				(type default)
			)
			(layer "F.Fab")
		)
		(fp_line
			(start -0.12065 -0.305054)
			(end -0.12065 -0.2794)
			(stroke
				(width 0.1)
				(type default)
			)
			(layer "F.Fab")
		)
		(fp_line
			(start -0.67945 0.3048)
			(end -0.67945 -0.305054)
			(stroke
				(width 0.1)
				(type default)
			)
			(layer "F.Fab")
		)
		(fp_line
			(start -0.67945 -0.305054)
			(end -0.12065 -0.305054)
			(stroke
				(width 0.1)
				(type default)
			)
			(layer "F.Fab")
		)
		(pad "1" smd circle
			(at -0.40005 0 180)
			(size 0 0)
			(layers "F.Cu" "F.Mask" "F.Paste")
			(net "GPU_FPGA_EROT_RST_BUF_R_N")
		)
		(pad "2" smd circle
			(at 0.40005 0 180)
			(size 0 0)
			(layers "F.Cu" "F.Mask" "F.Paste")
			(net "GND")
		)
	)
	(footprint ""
		(layer "F.Cu")
		(at 352.281744 -240.276888 90)
		(property "Reference" "C418"
			(at 0 0 90)
			(layer "F.SilkS")
			(hide yes)
			(effects
				(font
					(size 1.27 1.27)
				)
			)
		)
		(property "Value" ""
			(at 0 0 90)
			(layer "F.Fab")
			(effects
				(font
					(size 1.27 1.27)
				)
			)
		)
		(duplicate_pad_numbers_are_jumpers no)
		(fp_line
			(start 0.7874 -0.4064)
			(end 0.7874 0.4064)
			(stroke
				(width 0.1524)
				(type default)
			)
			(layer "F.SilkS")
		)
		(fp_line
			(start -0.7874 -0.4064)
			(end 0.7874 -0.4064)
			(stroke
				(width 0.1524)
				(type default)
			)
			(layer "F.SilkS")
		)
		(fp_line
			(start 0.7874 0.4064)
			(end -0.7874 0.4064)
			(stroke
				(width 0.1524)
				(type default)
			)
			(layer "F.SilkS")
		)
		(fp_line
			(start -0.7874 0.4064)
			(end -0.7874 -0.4064)
			(stroke
				(width 0.1524)
				(type default)
			)
			(layer "F.SilkS")
		)
		(fp_line
			(start -0.12065 -0.305054)
			(end -0.12065 -0.2794)
			(stroke
				(width 0.1)
				(type default)
			)
			(layer "F.Fab")
		)
		(fp_line
			(start -0.67945 -0.305054)
			(end -0.12065 -0.305054)
			(stroke
				(width 0.1)
				(type default)
			)
			(layer "F.Fab")
		)
		(fp_line
			(start 0.67945 -0.3048)
			(end 0.67945 0.3048)
			(stroke
				(width 0.1)
				(type default)
			)
			(layer "F.Fab")
		)
		(fp_line
			(start 0.12065 -0.3048)
			(end 0.67945 -0.3048)
			(stroke
				(width 0.1)
				(type default)
			)
			(layer "F.Fab")
		)
		(fp_line
			(start 0.12065 -0.2794)
			(end 0.12065 -0.3048)
			(stroke
				(width 0.1)
				(type default)
			)
			(layer "F.Fab")
		)
		(fp_line
			(start -0.12065 -0.2794)
			(end 0.12065 -0.2794)
			(stroke
				(width 0.1)
				(type default)
			)
			(layer "F.Fab")
		)
		(fp_line
			(start 0.120396 0.2794)
			(end -0.12065 0.2794)
			(stroke
				(width 0.1)
				(type default)
			)
			(layer "F.Fab")
		)
		(fp_line
			(start -0.12065 0.2794)
			(end -0.12065 0.3048)
			(stroke
				(width 0.1)
				(type default)
			)
			(layer "F.Fab")
		)
		(fp_line
			(start 0.67945 0.3048)
			(end 0.120396 0.3048)
			(stroke
				(width 0.1)
				(type default)
			)
			(layer "F.Fab")
		)
		(fp_line
			(start 0.120396 0.3048)
			(end 0.120396 0.2794)
			(stroke
				(width 0.1)
				(type default)
			)
			(layer "F.Fab")
		)
		(fp_line
			(start -0.12065 0.3048)
			(end -0.67945 0.3048)
			(stroke
				(width 0.1)
				(type default)
			)
			(layer "F.Fab")
		)
		(fp_line
			(start -0.67945 0.3048)
			(end -0.67945 -0.305054)
			(stroke
				(width 0.1)
				(type default)
			)
			(layer "F.Fab")
		)
		(pad "1" smd circle
			(at -0.40005 0 90)
			(size 0 0)
			(layers "F.Cu" "F.Mask" "F.Paste")
			(net "PVCCFA_EHV_FIVRA_CPU0")
		)
		(pad "2" smd circle
			(at 0.40005 0 90)
			(size 0 0)
			(layers "F.Cu" "F.Mask" "F.Paste")
			(net "GND")
		)
	)
	(footprint ""
		(layer "F.Cu")
		(at 188.0108 -93.91015 -90)
		(property "Reference" "R1318"
			(at 0 0 270)
			(layer "F.SilkS")
			(hide yes)
			(effects
				(font
					(size 1.27 1.27)
				)
			)
		)
		(property "Value" ""
			(at 0 0 270)
			(layer "F.Fab")
			(effects
				(font
					(size 1.27 1.27)
				)
			)
		)
		(duplicate_pad_numbers_are_jumpers no)
		(fp_line
			(start -0.7874 0.4064)
			(end -0.7874 -0.4064)
			(stroke
				(width 0.1524)
				(type default)
			)
			(layer "F.SilkS")
		)
		(fp_line
			(start 0.7874 0.4064)
			(end -0.7874 0.4064)
			(stroke
				(width 0.1524)
				(type default)
			)
			(layer "F.SilkS")
		)
		(fp_line
			(start -0.7874 -0.4064)
			(end 0.7874 -0.4064)
			(stroke
				(width 0.1524)
				(type default)
			)
			(layer "F.SilkS")
		)
		(fp_line
			(start 0.7874 -0.4064)
			(end 0.7874 0.4064)
			(stroke
				(width 0.1524)
				(type default)
			)
			(layer "F.SilkS")
		)
		(fp_line
			(start -0.67945 0.3048)
			(end -0.67945 -0.305054)
			(stroke
				(width 0.1)
				(type default)
			)
			(layer "F.Fab")
		)
		(fp_line
			(start -0.12065 0.3048)
			(end -0.67945 0.3048)
			(stroke
				(width 0.1)
				(type default)
			)
			(layer "F.Fab")
		)
		(fp_line
			(start 0.120396 0.3048)
			(end 0.120396 0.2794)
			(stroke
				(width 0.1)
				(type default)
			)
			(layer "F.Fab")
		)
		(fp_line
			(start 0.67945 0.3048)
			(end 0.120396 0.3048)
			(stroke
				(width 0.1)
				(type default)
			)
			(layer "F.Fab")
		)
		(fp_line
			(start -0.12065 0.2794)
			(end -0.12065 0.3048)
			(stroke
				(width 0.1)
				(type default)
			)
			(layer "F.Fab")
		)
		(fp_line
			(start 0.120396 0.2794)
			(end -0.12065 0.2794)
			(stroke
				(width 0.1)
				(type default)
			)
			(layer "F.Fab")
		)
		(fp_line
			(start -0.12065 -0.2794)
			(end 0.12065 -0.2794)
			(stroke
				(width 0.1)
				(type default)
			)
			(layer "F.Fab")
		)
		(fp_line
			(start 0.12065 -0.2794)
			(end 0.12065 -0.3048)
			(stroke
				(width 0.1)
				(type default)
			)
			(layer "F.Fab")
		)
		(fp_line
			(start 0.12065 -0.3048)
			(end 0.67945 -0.3048)
			(stroke
				(width 0.1)
				(type default)
			)
			(layer "F.Fab")
		)
		(fp_line
			(start 0.67945 -0.3048)
			(end 0.67945 0.3048)
			(stroke
				(width 0.1)
				(type default)
			)
			(layer "F.Fab")
		)
		(fp_line
			(start -0.67945 -0.305054)
			(end -0.12065 -0.305054)
			(stroke
				(width 0.1)
				(type default)
			)
			(layer "F.Fab")
		)
		(fp_line
			(start -0.12065 -0.305054)
			(end -0.12065 -0.2794)
			(stroke
				(width 0.1)
				(type default)
			)
			(layer "F.Fab")
		)
		(pad "1" smd circle
			(at -0.40005 0 270)
			(size 0 0)
			(layers "F.Cu" "F.Mask" "F.Paste")
			(net "FM_THERMTRIP_DLY_LVC1_R_N")
		)
		(pad "2" smd circle
			(at 0.40005 0 270)
			(size 0 0)
			(layers "F.Cu" "F.Mask" "F.Paste")
			(net "FM_THERMTRIP_DLY_LVC1_N")
		)
	)
	(footprint ""
		(layer "F.Cu")
		(at 323.342 -31.0642 135)
		(property "Reference" "Y1"
			(at -0.163979 -3.010002 0)
			(unlocked yes)
			(layer "F.SilkS")
			(effects
				(font
					(size 0.7874 0.5842)
					(thickness 0.1524)
				)
				(justify left)
			)
		)
		(property "Value" ""
			(at 0 0 135)
			(layer "F.Fab")
			(effects
				(font
					(size 1.27 1.27)
				)
			)
		)
		(duplicate_pad_numbers_are_jumpers no)
		(fp_line
			(start 1.904892 -1.04135)
			(end -1.904892 -1.04135)
			(stroke
				(width 0.1524)
				(type default)
			)
			(layer "F.SilkS")
		)
		(fp_line
			(start 1.904892 1.04135)
			(end 1.904892 -1.04135)
			(stroke
				(width 0.1524)
				(type default)
			)
			(layer "F.SilkS")
		)
		(fp_line
			(start -1.904892 -1.04135)
			(end -1.904892 1.04135)
			(stroke
				(width 0.1524)
				(type default)
			)
			(layer "F.SilkS")
		)
		(fp_line
			(start -1.904892 1.04135)
			(end 1.904892 1.04135)
			(stroke
				(width 0.1524)
				(type default)
			)
			(layer "F.SilkS")
		)
		(fp_line
			(start 1.650032 -0.824926)
			(end -1.650032 -0.824926)
			(stroke
				(width 0.1)
				(type default)
			)
			(layer "F.Fab")
		)
		(fp_line
			(start 1.650032 0.824926)
			(end 1.650032 -0.824926)
			(stroke
				(width 0.1)
				(type default)
			)
			(layer "F.Fab")
		)
		(fp_line
			(start -1.650032 -0.824926)
			(end -1.650032 0.824926)
			(stroke
				(width 0.1)
				(type default)
			)
			(layer "F.Fab")
		)
		(fp_line
			(start -1.650032 0.824926)
			(end 1.650032 0.824926)
			(stroke
				(width 0.1)
				(type default)
			)
			(layer "F.Fab")
		)
		(pad "1" smd rect
			(at -1.249934 0 135)
			(size 1.016 1.8034)
			(layers "F.Cu" "F.Mask" "F.Paste")
			(net "XTAL_PCH_RTC2_R")
		)
		(pad "2" smd rect
			(at 1.249934 0 315)
			(size 1.016 1.8034)
			(layers "F.Cu" "F.Mask" "F.Paste")
			(net "XTAL_PCH_RTC1")
		)
		(zone
			(layer "F.Cu")
			(hatch none 0.5)
			(connect_pads
				(clearance 0)
			)
			(min_thickness 0.25)
			(keepout
				(tracks not_allowed)
				(vias allowed)
				(pads allowed)
				(copperpour not_allowed)
				(footprints allowed)
			)
			(placement
				(enabled no)
				(sheetname "")
			)
			(fill
				(thermal_gap 0.5)
				(thermal_bridge_width 0.5)
				(island_removal_mode 0)
			)
			(polygon
				(pts
					(xy 323.157088 -29.901896) (xy 324.504304 -31.249112) (xy 323.526912 -32.226504) (xy 322.179696 -30.879288)
				)
			)
		)
	)
	(footprint ""
		(layer "F.Cu")
		(at 364.879382 -386.46989)
		(property "Reference" "Q135"
			(at 2.24282 0.802132 0)
			(unlocked yes)
			(layer "F.SilkS")
			(effects
				(font
					(size 0.7874 0.5842)
					(thickness 0.1524)
				)
				(justify left)
			)
		)
		(property "Value" ""
			(at 0 0 0)
			(layer "F.Fab")
			(effects
				(font
					(size 1.27 1.27)
				)
			)
		)
		(duplicate_pad_numbers_are_jumpers no)
		(fp_line
			(start -1.332738 -1.100074)
			(end -0.4826 -1.100074)
			(stroke
				(width 0.1524)
				(type default)
			)
			(layer "F.SilkS")
		)
		(fp_line
			(start -1.332738 1.100074)
			(end -1.332738 -1.100074)
			(stroke
				(width 0.1524)
				(type default)
			)
			(layer "F.SilkS")
		)
		(fp_line
			(start -0.4826 -1.100074)
			(end 0 -0.541274)
			(stroke
				(width 0.1524)
				(type default)
			)
			(layer "F.SilkS")
		)
		(fp_line
			(start 0 -0.541274)
			(end 0.4826 -1.100074)
			(stroke
				(width 0.1524)
				(type default)
			)
			(layer "F.SilkS")
		)
		(fp_line
			(start 0.4826 -1.100074)
			(end 1.332738 -1.100074)
			(stroke
				(width 0.1524)
				(type default)
			)
			(layer "F.SilkS")
		)
		(fp_line
			(start 1.332738 -1.100074)
			(end 1.332738 1.100074)
			(stroke
				(width 0.1524)
				(type default)
			)
			(layer "F.SilkS")
		)
		(fp_line
			(start 1.332738 1.100074)
			(end -1.332738 1.100074)
			(stroke
				(width 0.1524)
				(type default)
			)
			(layer "F.SilkS")
		)
		(fp_poly
			(pts
				(xy -2.2352 -1.001014) (xy -1.533144 -0.649986) (xy -2.2352 -0.298958)
			)
			(stroke
				(width 0)
				(type default)
			)
			(fill yes)
			(layer "F.SilkS")
		)
		(fp_line
			(start -0.674878 -1.100074)
			(end 0.674878 -1.100074)
			(stroke
				(width 0.1)
				(type default)
			)
			(layer "F.Fab")
		)
		(fp_line
			(start -0.674878 1.100074)
			(end -0.674878 -1.100074)
			(stroke
				(width 0.1)
				(type default)
			)
			(layer "F.Fab")
		)
		(fp_line
			(start 0.674878 -1.100074)
			(end 0.674878 1.100074)
			(stroke
				(width 0.1)
				(type default)
			)
			(layer "F.Fab")
		)
		(fp_line
			(start 0.674878 1.100074)
			(end -0.674878 1.100074)
			(stroke
				(width 0.1)
				(type default)
			)
			(layer "F.Fab")
		)
		(fp_poly
			(pts
				(xy -2.2352 -0.298958) (xy -2.2352 -1.001014) (xy -1.533144 -0.649986)
			)
			(stroke
				(width 0)
				(type default)
			)
			(fill yes)
			(layer "F.Fab")
		)
		(pad "1" smd rect
			(at -0.94996 -0.649986 90)
			(size 0.4318 0.508)
			(layers "F.Cu" "F.Mask" "F.Paste")
			(net "GND")
		)
		(pad "2" smd rect
			(at -0.94996 0 90)
			(size 0.4318 0.508)
			(layers "F.Cu" "F.Mask" "F.Paste")
			(net "GPU_3V3IO_RSVD1")
		)
		(pad "3" smd rect
			(at -0.94996 0.649986 90)
			(size 0.4318 0.508)
			(layers "F.Cu" "F.Mask" "F.Paste")
			(net "GPU_3V3IO_RSVD1_ISO")
		)
		(pad "4" smd rect
			(at 0.94996 0.649986 90)
			(size 0.4318 0.508)
			(layers "F.Cu" "F.Mask" "F.Paste")
			(net "GND")
		)
		(pad "5" smd rect
			(at 0.94996 0 90)
			(size 0.4318 0.508)
			(layers "F.Cu" "F.Mask" "F.Paste")
			(net "GPU_3V3IO_RSVD1_N")
		)
		(pad "6" smd rect
			(at 0.94996 -0.649986 90)
			(size 0.4318 0.508)
			(layers "F.Cu" "F.Mask" "F.Paste")
			(net "GPU_3V3IO_RSVD1_N")
		)
	)
	(footprint ""
		(layer "F.Cu")
		(at 125.53696 -335.176368)
		(property "Reference" "PC527_P1_4"
			(at 0 0 0)
			(layer "F.SilkS")
			(hide yes)
			(effects
				(font
					(size 1.27 1.27)
				)
			)
		)
		(property "Value" ""
			(at 0 0 0)
			(layer "F.Fab")
			(effects
				(font
					(size 1.27 1.27)
				)
			)
		)
		(duplicate_pad_numbers_are_jumpers no)
		(fp_line
			(start -0.7874 -0.4064)
			(end 0.7874 -0.4064)
			(stroke
				(width 0.1524)
				(type default)
			)
			(layer "F.SilkS")
		)
		(fp_line
			(start -0.7874 0.4064)
			(end -0.7874 -0.4064)
			(stroke
				(width 0.1524)
				(type default)
			)
			(layer "F.SilkS")
		)
		(fp_line
			(start 0.7874 -0.4064)
			(end 0.7874 0.4064)
			(stroke
				(width 0.1524)
				(type default)
			)
			(layer "F.SilkS")
		)
		(fp_line
			(start 0.7874 0.4064)
			(end -0.7874 0.4064)
			(stroke
				(width 0.1524)
				(type default)
			)
			(layer "F.SilkS")
		)
		(fp_line
			(start -0.67945 -0.305054)
			(end -0.12065 -0.305054)
			(stroke
				(width 0.1)
				(type default)
			)
			(layer "F.Fab")
		)
		(fp_line
			(start -0.67945 0.3048)
			(end -0.67945 -0.305054)
			(stroke
				(width 0.1)
				(type default)
			)
			(layer "F.Fab")
		)
		(fp_line
			(start -0.12065 -0.305054)
			(end -0.12065 -0.2794)
			(stroke
				(width 0.1)
				(type default)
			)
			(layer "F.Fab")
		)
		(fp_line
			(start -0.12065 -0.2794)
			(end 0.12065 -0.2794)
			(stroke
				(width 0.1)
				(type default)
			)
			(layer "F.Fab")
		)
		(fp_line
			(start -0.12065 0.2794)
			(end -0.12065 0.3048)
			(stroke
				(width 0.1)
				(type default)
			)
			(layer "F.Fab")
		)
		(fp_line
			(start -0.12065 0.3048)
			(end -0.67945 0.3048)
			(stroke
				(width 0.1)
				(type default)
			)
			(layer "F.Fab")
		)
		(fp_line
			(start 0.120396 0.2794)
			(end -0.12065 0.2794)
			(stroke
				(width 0.1)
				(type default)
			)
			(layer "F.Fab")
		)
		(fp_line
			(start 0.120396 0.3048)
			(end 0.120396 0.2794)
			(stroke
				(width 0.1)
				(type default)
			)
			(layer "F.Fab")
		)
		(fp_line
			(start 0.12065 -0.3048)
			(end 0.67945 -0.3048)
			(stroke
				(width 0.1)
				(type default)
			)
			(layer "F.Fab")
		)
		(fp_line
			(start 0.12065 -0.2794)
			(end 0.12065 -0.3048)
			(stroke
				(width 0.1)
				(type default)
			)
			(layer "F.Fab")
		)
		(fp_line
			(start 0.67945 -0.3048)
			(end 0.67945 0.3048)
			(stroke
				(width 0.1)
				(type default)
			)
			(layer "F.Fab")
		)
		(fp_line
			(start 0.67945 0.3048)
			(end 0.120396 0.3048)
			(stroke
				(width 0.1)
				(type default)
			)
			(layer "F.Fab")
		)
		(pad "1" smd circle
			(at -0.40005 0)
			(size 0 0)
			(layers "F.Cu" "F.Mask" "F.Paste")
			(net "SW_P12V_PVCCIN_CPU1_FLT")
		)
		(pad "2" smd circle
			(at 0.40005 0)
			(size 0 0)
			(layers "F.Cu" "F.Mask" "F.Paste")
			(net "GND")
		)
	)
	(footprint ""
		(layer "F.Cu")
		(at 304.869088 -402.371052 -90)
		(property "Reference" "C1579"
			(at 0 0 270)
			(layer "F.SilkS")
			(hide yes)
			(effects
				(font
					(size 1.27 1.27)
				)
			)
		)
		(property "Value" ""
			(at 0 0 270)
			(layer "F.Fab")
			(effects
				(font
					(size 1.27 1.27)
				)
			)
		)
		(duplicate_pad_numbers_are_jumpers no)
		(fp_line
			(start -0.299974 0.150114)
			(end -0.299974 -0.150114)
			(stroke
				(width 0.1)
				(type default)
			)
			(layer "F.Fab")
		)
		(fp_line
			(start 0.299974 0.150114)
			(end -0.299974 0.150114)
			(stroke
				(width 0.1)
				(type default)
			)
			(layer "F.Fab")
		)
		(fp_line
			(start -0.299974 -0.150114)
			(end 0.299974 -0.150114)
			(stroke
				(width 0.1)
				(type default)
			)
			(layer "F.Fab")
		)
		(fp_line
			(start 0.299974 -0.150114)
			(end 0.299974 0.150114)
			(stroke
				(width 0.1)
				(type default)
			)
			(layer "F.Fab")
		)
		(pad "1" smd rect
			(at -0.2667 0 270)
			(size 0.3048 0.381)
			(layers "F.Cu" "F.Mask" "F.Paste")
			(net "P5E_CPU0_PE4_TX_C_DP<0>")
		)
		(pad "2" smd rect
			(at 0.2667 0 270)
			(size 0.3048 0.381)
			(layers "F.Cu" "F.Mask" "F.Paste")
			(net "P5E_CPU0_PE4_TX_DP<0>")
		)
	)
	(footprint ""
		(layer "F.Cu")
		(at 109.063282 -406.058116 90)
		(property "Reference" "R3497"
			(at 0 0 90)
			(layer "F.SilkS")
			(hide yes)
			(effects
				(font
					(size 1.27 1.27)
				)
			)
		)
		(property "Value" ""
			(at 0 0 90)
			(layer "F.Fab")
			(effects
				(font
					(size 1.27 1.27)
				)
			)
		)
		(duplicate_pad_numbers_are_jumpers no)
		(fp_line
			(start 0.7874 -0.4064)
			(end 0.7874 0.4064)
			(stroke
				(width 0.1524)
				(type default)
			)
			(layer "F.SilkS")
		)
		(fp_line
			(start -0.7874 -0.4064)
			(end 0.7874 -0.4064)
			(stroke
				(width 0.1524)
				(type default)
			)
			(layer "F.SilkS")
		)
		(fp_line
			(start 0.7874 0.4064)
			(end -0.7874 0.4064)
			(stroke
				(width 0.1524)
				(type default)
			)
			(layer "F.SilkS")
		)
		(fp_line
			(start -0.7874 0.4064)
			(end -0.7874 -0.4064)
			(stroke
				(width 0.1524)
				(type default)
			)
			(layer "F.SilkS")
		)
		(fp_line
			(start -0.12065 -0.305054)
			(end -0.12065 -0.2794)
			(stroke
				(width 0.1)
				(type default)
			)
			(layer "F.Fab")
		)
		(fp_line
			(start -0.67945 -0.305054)
			(end -0.12065 -0.305054)
			(stroke
				(width 0.1)
				(type default)
			)
			(layer "F.Fab")
		)
		(fp_line
			(start 0.67945 -0.3048)
			(end 0.67945 0.3048)
			(stroke
				(width 0.1)
				(type default)
			)
			(layer "F.Fab")
		)
		(fp_line
			(start 0.12065 -0.3048)
			(end 0.67945 -0.3048)
			(stroke
				(width 0.1)
				(type default)
			)
			(layer "F.Fab")
		)
		(fp_line
			(start 0.12065 -0.2794)
			(end 0.12065 -0.3048)
			(stroke
				(width 0.1)
				(type default)
			)
			(layer "F.Fab")
		)
		(fp_line
			(start -0.12065 -0.2794)
			(end 0.12065 -0.2794)
			(stroke
				(width 0.1)
				(type default)
			)
			(layer "F.Fab")
		)
		(fp_line
			(start 0.120396 0.2794)
			(end -0.12065 0.2794)
			(stroke
				(width 0.1)
				(type default)
			)
			(layer "F.Fab")
		)
		(fp_line
			(start -0.12065 0.2794)
			(end -0.12065 0.3048)
			(stroke
				(width 0.1)
				(type default)
			)
			(layer "F.Fab")
		)
		(fp_line
			(start 0.67945 0.3048)
			(end 0.120396 0.3048)
			(stroke
				(width 0.1)
				(type default)
			)
			(layer "F.Fab")
		)
		(fp_line
			(start 0.120396 0.3048)
			(end 0.120396 0.2794)
			(stroke
				(width 0.1)
				(type default)
			)
			(layer "F.Fab")
		)
		(fp_line
			(start -0.12065 0.3048)
			(end -0.67945 0.3048)
			(stroke
				(width 0.1)
				(type default)
			)
			(layer "F.Fab")
		)
		(fp_line
			(start -0.67945 0.3048)
			(end -0.67945 -0.305054)
			(stroke
				(width 0.1)
				(type default)
			)
			(layer "F.Fab")
		)
		(pad "1" smd circle
			(at -0.40005 0 90)
			(size 0 0)
			(layers "F.Cu" "F.Mask" "F.Paste")
			(net "GPU_FPGA_EROT_RECOV_BUF_R_N")
		)
		(pad "2" smd circle
			(at 0.40005 0 90)
			(size 0 0)
			(layers "F.Cu" "F.Mask" "F.Paste")
			(net "GPU_FPGA_EROT_RECOV_BUF_N")
		)
	)
	(footprint ""
		(layer "F.Cu")
		(at 98.13036 -412.171388 180)
		(property "Reference" "R4543"
			(at 0 0 180)
			(layer "F.SilkS")
			(hide yes)
			(effects
				(font
					(size 1.27 1.27)
				)
			)
		)
		(property "Value" ""
			(at 0 0 180)
			(layer "F.Fab")
			(effects
				(font
					(size 1.27 1.27)
				)
			)
		)
		(duplicate_pad_numbers_are_jumpers no)
		(fp_line
			(start 0.7874 0.4064)
			(end -0.7874 0.4064)
			(stroke
				(width 0.1524)
				(type default)
			)
			(layer "F.SilkS")
		)
		(fp_line
			(start 0.7874 -0.4064)
			(end 0.7874 0.4064)
			(stroke
				(width 0.1524)
				(type default)
			)
			(layer "F.SilkS")
		)
		(fp_line
			(start -0.7874 0.4064)
			(end -0.7874 -0.4064)
			(stroke
				(width 0.1524)
				(type default)
			)
			(layer "F.SilkS")
		)
		(fp_line
			(start -0.7874 -0.4064)
			(end 0.7874 -0.4064)
			(stroke
				(width 0.1524)
				(type default)
			)
			(layer "F.SilkS")
		)
		(fp_line
			(start 0.67945 0.3048)
			(end 0.120396 0.3048)
			(stroke
				(width 0.1)
				(type default)
			)
			(layer "F.Fab")
		)
		(fp_line
			(start 0.67945 -0.3048)
			(end 0.67945 0.3048)
			(stroke
				(width 0.1)
				(type default)
			)
			(layer "F.Fab")
		)
		(fp_line
			(start 0.12065 -0.2794)
			(end 0.12065 -0.3048)
			(stroke
				(width 0.1)
				(type default)
			)
			(layer "F.Fab")
		)
		(fp_line
			(start 0.12065 -0.3048)
			(end 0.67945 -0.3048)
			(stroke
				(width 0.1)
				(type default)
			)
			(layer "F.Fab")
		)
		(fp_line
			(start 0.120396 0.3048)
			(end 0.120396 0.2794)
			(stroke
				(width 0.1)
				(type default)
			)
			(layer "F.Fab")
		)
		(fp_line
			(start 0.120396 0.2794)
			(end -0.12065 0.2794)
			(stroke
				(width 0.1)
				(type default)
			)
			(layer "F.Fab")
		)
		(fp_line
			(start -0.12065 0.3048)
			(end -0.67945 0.3048)
			(stroke
				(width 0.1)
				(type default)
			)
			(layer "F.Fab")
		)
		(fp_line
			(start -0.12065 0.2794)
			(end -0.12065 0.3048)
			(stroke
				(width 0.1)
				(type default)
			)
			(layer "F.Fab")
		)
		(fp_line
			(start -0.12065 -0.2794)
			(end 0.12065 -0.2794)
			(stroke
				(width 0.1)
				(type default)
			)
			(layer "F.Fab")
		)
		(fp_line
			(start -0.12065 -0.305054)
			(end -0.12065 -0.2794)
			(stroke
				(width 0.1)
				(type default)
			)
			(layer "F.Fab")
		)
		(fp_line
			(start -0.67945 0.3048)
			(end -0.67945 -0.305054)
			(stroke
				(width 0.1)
				(type default)
			)
			(layer "F.Fab")
		)
		(fp_line
			(start -0.67945 -0.305054)
			(end -0.12065 -0.305054)
			(stroke
				(width 0.1)
				(type default)
			)
			(layer "F.Fab")
		)
		(pad "1" smd circle
			(at -0.40005 0 180)
			(size 0 0)
			(layers "F.Cu" "F.Mask" "F.Paste")
			(net "P3V3_AUX")
		)
		(pad "2" smd circle
			(at 0.40005 0 180)
			(size 0 0)
			(layers "F.Cu" "F.Mask" "F.Paste")
			(net "HGX_DETECT_N")
		)
	)
	(footprint ""
		(layer "F.Cu")
		(at 437.242966 -124.680726 180)
		(property "Reference" "R2400"
			(at 0 0 180)
			(layer "F.SilkS")
			(hide yes)
			(effects
				(font
					(size 1.27 1.27)
				)
			)
		)
		(property "Value" ""
			(at 0 0 180)
			(layer "F.Fab")
			(effects
				(font
					(size 1.27 1.27)
				)
			)
		)
		(duplicate_pad_numbers_are_jumpers no)
		(fp_line
			(start 0.7874 0.4064)
			(end -0.7874 0.4064)
			(stroke
				(width 0.1524)
				(type default)
			)
			(layer "F.SilkS")
		)
		(fp_line
			(start 0.7874 -0.4064)
			(end 0.7874 0.4064)
			(stroke
				(width 0.1524)
				(type default)
			)
			(layer "F.SilkS")
		)
		(fp_line
			(start -0.7874 0.4064)
			(end -0.7874 -0.4064)
			(stroke
				(width 0.1524)
				(type default)
			)
			(layer "F.SilkS")
		)
		(fp_line
			(start -0.7874 -0.4064)
			(end 0.7874 -0.4064)
			(stroke
				(width 0.1524)
				(type default)
			)
			(layer "F.SilkS")
		)
		(fp_line
			(start 0.67945 0.3048)
			(end 0.120396 0.3048)
			(stroke
				(width 0.1)
				(type default)
			)
			(layer "F.Fab")
		)
		(fp_line
			(start 0.67945 -0.3048)
			(end 0.67945 0.3048)
			(stroke
				(width 0.1)
				(type default)
			)
			(layer "F.Fab")
		)
		(fp_line
			(start 0.12065 -0.2794)
			(end 0.12065 -0.3048)
			(stroke
				(width 0.1)
				(type default)
			)
			(layer "F.Fab")
		)
		(fp_line
			(start 0.12065 -0.3048)
			(end 0.67945 -0.3048)
			(stroke
				(width 0.1)
				(type default)
			)
			(layer "F.Fab")
		)
		(fp_line
			(start 0.120396 0.3048)
			(end 0.120396 0.2794)
			(stroke
				(width 0.1)
				(type default)
			)
			(layer "F.Fab")
		)
		(fp_line
			(start 0.120396 0.2794)
			(end -0.12065 0.2794)
			(stroke
				(width 0.1)
				(type default)
			)
			(layer "F.Fab")
		)
		(fp_line
			(start -0.12065 0.3048)
			(end -0.67945 0.3048)
			(stroke
				(width 0.1)
				(type default)
			)
			(layer "F.Fab")
		)
		(fp_line
			(start -0.12065 0.2794)
			(end -0.12065 0.3048)
			(stroke
				(width 0.1)
				(type default)
			)
			(layer "F.Fab")
		)
		(fp_line
			(start -0.12065 -0.2794)
			(end 0.12065 -0.2794)
			(stroke
				(width 0.1)
				(type default)
			)
			(layer "F.Fab")
		)
		(fp_line
			(start -0.12065 -0.305054)
			(end -0.12065 -0.2794)
			(stroke
				(width 0.1)
				(type default)
			)
			(layer "F.Fab")
		)
		(fp_line
			(start -0.67945 0.3048)
			(end -0.67945 -0.305054)
			(stroke
				(width 0.1)
				(type default)
			)
			(layer "F.Fab")
		)
		(fp_line
			(start -0.67945 -0.305054)
			(end -0.12065 -0.305054)
			(stroke
				(width 0.1)
				(type default)
			)
			(layer "F.Fab")
		)
		(pad "1" smd circle
			(at -0.40005 0 180)
			(size 0 0)
			(layers "F.Cu" "F.Mask" "F.Paste")
			(net "SVID_DIO1_CPU0_R")
		)
		(pad "2" smd circle
			(at 0.40005 0 180)
			(size 0 0)
			(layers "F.Cu" "F.Mask" "F.Paste")
			(net "SVID_DIO_PVCCD_HV_CPU0_R")
		)
	)
	(footprint ""
		(layer "F.Cu")
		(at 77.77226 -128.8161)
		(property "Reference" "ME2"
			(at -9.652 -9.540748 0)
			(unlocked yes)
			(layer "F.SilkS")
			(effects
				(font
					(size 0.7874 0.5842)
					(thickness 0.1524)
				)
				(justify left)
			)
		)
		(property "Value" ""
			(at 0 0 0)
			(layer "F.Fab")
			(effects
				(font
					(size 1.27 1.27)
				)
			)
		)
		(duplicate_pad_numbers_are_jumpers no)
		(zone
			(layer "F.Cu")
			(hatch none 0.5)
			(connect_pads
				(clearance 0)
			)
			(min_thickness 0.25)
			(keepout
				(tracks allowed)
				(vias allowed)
				(pads allowed)
				(copperpour allowed)
				(footprints not_allowed)
			)
			(placement
				(enabled no)
				(sheetname "")
			)
			(fill
				(thermal_gap 0.5)
				(thermal_bridge_width 0.5)
				(island_removal_mode 0)
			)
			(polygon
				(pts
					(arc
						(start 87.77224 -128.8161)
						(mid 67.77228 -128.8161)
						(end 87.77224 -128.8161)
					)
				)
			)
		)
	)
	(footprint ""
		(layer "F.Cu")
		(at 404.006812 -57.791604)
		(property "Reference" "R780"
			(at 0 0 0)
			(layer "F.SilkS")
			(hide yes)
			(effects
				(font
					(size 1.27 1.27)
				)
			)
		)
		(property "Value" ""
			(at 0 0 0)
			(layer "F.Fab")
			(effects
				(font
					(size 1.27 1.27)
				)
			)
		)
		(duplicate_pad_numbers_are_jumpers no)
		(fp_line
			(start -0.7874 -0.4064)
			(end 0.7874 -0.4064)
			(stroke
				(width 0.1524)
				(type default)
			)
			(layer "F.SilkS")
		)
		(fp_line
			(start -0.7874 0.4064)
			(end -0.7874 -0.4064)
			(stroke
				(width 0.1524)
				(type default)
			)
			(layer "F.SilkS")
		)
		(fp_line
			(start 0.7874 -0.4064)
			(end 0.7874 0.4064)
			(stroke
				(width 0.1524)
				(type default)
			)
			(layer "F.SilkS")
		)
		(fp_line
			(start 0.7874 0.4064)
			(end -0.7874 0.4064)
			(stroke
				(width 0.1524)
				(type default)
			)
			(layer "F.SilkS")
		)
		(fp_line
			(start -0.67945 -0.305054)
			(end -0.12065 -0.305054)
			(stroke
				(width 0.1)
				(type default)
			)
			(layer "F.Fab")
		)
		(fp_line
			(start -0.67945 0.3048)
			(end -0.67945 -0.305054)
			(stroke
				(width 0.1)
				(type default)
			)
			(layer "F.Fab")
		)
		(fp_line
			(start -0.12065 -0.305054)
			(end -0.12065 -0.2794)
			(stroke
				(width 0.1)
				(type default)
			)
			(layer "F.Fab")
		)
		(fp_line
			(start -0.12065 -0.2794)
			(end 0.12065 -0.2794)
			(stroke
				(width 0.1)
				(type default)
			)
			(layer "F.Fab")
		)
		(fp_line
			(start -0.12065 0.2794)
			(end -0.12065 0.3048)
			(stroke
				(width 0.1)
				(type default)
			)
			(layer "F.Fab")
		)
		(fp_line
			(start -0.12065 0.3048)
			(end -0.67945 0.3048)
			(stroke
				(width 0.1)
				(type default)
			)
			(layer "F.Fab")
		)
		(fp_line
			(start 0.120396 0.2794)
			(end -0.12065 0.2794)
			(stroke
				(width 0.1)
				(type default)
			)
			(layer "F.Fab")
		)
		(fp_line
			(start 0.120396 0.3048)
			(end 0.120396 0.2794)
			(stroke
				(width 0.1)
				(type default)
			)
			(layer "F.Fab")
		)
		(fp_line
			(start 0.12065 -0.3048)
			(end 0.67945 -0.3048)
			(stroke
				(width 0.1)
				(type default)
			)
			(layer "F.Fab")
		)
		(fp_line
			(start 0.12065 -0.2794)
			(end 0.12065 -0.3048)
			(stroke
				(width 0.1)
				(type default)
			)
			(layer "F.Fab")
		)
		(fp_line
			(start 0.67945 -0.3048)
			(end 0.67945 0.3048)
			(stroke
				(width 0.1)
				(type default)
			)
			(layer "F.Fab")
		)
		(fp_line
			(start 0.67945 0.3048)
			(end 0.120396 0.3048)
			(stroke
				(width 0.1)
				(type default)
			)
			(layer "F.Fab")
		)
		(pad "1" smd circle
			(at -0.40005 0)
			(size 0 0)
			(layers "F.Cu" "F.Mask" "F.Paste")
			(net "FM_CPU_FBRK_DEBUG_N")
		)
		(pad "2" smd circle
			(at 0.40005 0)
			(size 0 0)
			(layers "F.Cu" "F.Mask" "F.Paste")
			(net "FM_CPU_FBRK_DEBUG_R_N")
		)
	)
	(footprint ""
		(layer "F.Cu")
		(at 352.839274 -343.902284 90)
		(property "Reference" "PC324"
			(at 0 0 90)
			(layer "F.SilkS")
			(hide yes)
			(effects
				(font
					(size 1.27 1.27)
				)
			)
		)
		(property "Value" ""
			(at 0 0 90)
			(layer "F.Fab")
			(effects
				(font
					(size 1.27 1.27)
				)
			)
		)
		(duplicate_pad_numbers_are_jumpers no)
		(fp_line
			(start -3.400044 1.249934)
			(end 3.400044 1.249934)
			(stroke
				(width 0.1524)
				(type default)
			)
			(layer "F.SilkS")
		)
		(fp_circle
			(center 0 1.249934)
			(end 0 4.649978)
			(stroke
				(width 0.1524)
				(type default)
			)
			(fill no)
			(layer "F.SilkS")
		)
		(fp_poly
			(pts
				(arc
					(start -3.400044 1.249934)
					(mid 0 4.649978)
					(end 3.400044 1.249934)
				)
			)
			(stroke
				(width 0)
				(type default)
			)
			(fill yes)
			(layer "F.SilkS")
		)
		(fp_circle
			(center 0 1.249934)
			(end 0 4.649978)
			(stroke
				(width 0.1)
				(type default)
			)
			(fill no)
			(layer "F.Fab")
		)
		(pad "1" thru_hole rect
			(at 0 0 90)
			(size 1.524 1.524)
			(drill 1.016)
			(layers "*.Cu" "*.Mask")
			(remove_unused_layers no)
			(net "SW_P12V_PVCCIN_CPU0_FLT")
			(clearance 0)
			(padstack
				(mode front_inner_back)
				(layer "Inner"
					(shape circle)
					(size 1.524 1.524)
					(clearance 0)
				)
				(layer "B.Cu"
					(shape rect)
					(size 1.524 1.524)
					(clearance 0)
				)
			)
		)
		(pad "2" thru_hole circle
			(at 0 2.500122 90)
			(size 1.524 1.524)
			(drill 1.016)
			(layers "*.Cu" "*.Mask")
			(remove_unused_layers no)
			(net "GND")
			(clearance 0)
		)
	)
	(footprint ""
		(layer "F.Cu")
		(at 36.84143 -174.804578)
		(property "Reference" "PC1284"
			(at 0 0 0)
			(layer "F.SilkS")
			(hide yes)
			(effects
				(font
					(size 1.27 1.27)
				)
			)
		)
		(property "Value" ""
			(at 0 0 0)
			(layer "F.Fab")
			(effects
				(font
					(size 1.27 1.27)
				)
			)
		)
		(duplicate_pad_numbers_are_jumpers no)
		(fp_line
			(start -0.7874 -0.4064)
			(end 0.7874 -0.4064)
			(stroke
				(width 0.1524)
				(type default)
			)
			(layer "F.SilkS")
		)
		(fp_line
			(start -0.7874 0.4064)
			(end -0.7874 -0.4064)
			(stroke
				(width 0.1524)
				(type default)
			)
			(layer "F.SilkS")
		)
		(fp_line
			(start 0.7874 -0.4064)
			(end 0.7874 0.4064)
			(stroke
				(width 0.1524)
				(type default)
			)
			(layer "F.SilkS")
		)
		(fp_line
			(start 0.7874 0.4064)
			(end -0.7874 0.4064)
			(stroke
				(width 0.1524)
				(type default)
			)
			(layer "F.SilkS")
		)
		(fp_line
			(start -0.67945 -0.305054)
			(end -0.12065 -0.305054)
			(stroke
				(width 0.1)
				(type default)
			)
			(layer "F.Fab")
		)
		(fp_line
			(start -0.67945 0.3048)
			(end -0.67945 -0.305054)
			(stroke
				(width 0.1)
				(type default)
			)
			(layer "F.Fab")
		)
		(fp_line
			(start -0.12065 -0.305054)
			(end -0.12065 -0.2794)
			(stroke
				(width 0.1)
				(type default)
			)
			(layer "F.Fab")
		)
		(fp_line
			(start -0.12065 -0.2794)
			(end 0.12065 -0.2794)
			(stroke
				(width 0.1)
				(type default)
			)
			(layer "F.Fab")
		)
		(fp_line
			(start -0.12065 0.2794)
			(end -0.12065 0.3048)
			(stroke
				(width 0.1)
				(type default)
			)
			(layer "F.Fab")
		)
		(fp_line
			(start -0.12065 0.3048)
			(end -0.67945 0.3048)
			(stroke
				(width 0.1)
				(type default)
			)
			(layer "F.Fab")
		)
		(fp_line
			(start 0.120396 0.2794)
			(end -0.12065 0.2794)
			(stroke
				(width 0.1)
				(type default)
			)
			(layer "F.Fab")
		)
		(fp_line
			(start 0.120396 0.3048)
			(end 0.120396 0.2794)
			(stroke
				(width 0.1)
				(type default)
			)
			(layer "F.Fab")
		)
		(fp_line
			(start 0.12065 -0.3048)
			(end 0.67945 -0.3048)
			(stroke
				(width 0.1)
				(type default)
			)
			(layer "F.Fab")
		)
		(fp_line
			(start 0.12065 -0.2794)
			(end 0.12065 -0.3048)
			(stroke
				(width 0.1)
				(type default)
			)
			(layer "F.Fab")
		)
		(fp_line
			(start 0.67945 -0.3048)
			(end 0.67945 0.3048)
			(stroke
				(width 0.1)
				(type default)
			)
			(layer "F.Fab")
		)
		(fp_line
			(start 0.67945 0.3048)
			(end 0.120396 0.3048)
			(stroke
				(width 0.1)
				(type default)
			)
			(layer "F.Fab")
		)
		(pad "1" smd circle
			(at -0.40005 0)
			(size 0 0)
			(layers "F.Cu" "F.Mask" "F.Paste")
			(net "PVNN_MAIN_CPU1")
		)
		(pad "2" smd circle
			(at 0.40005 0)
			(size 0 0)
			(layers "F.Cu" "F.Mask" "F.Paste")
			(net "GND")
		)
	)
	(footprint ""
		(layer "F.Cu")
		(at 461.916526 -100.470208)
		(property "Reference" "C639"
			(at 0 0 0)
			(layer "F.SilkS")
			(hide yes)
			(effects
				(font
					(size 1.27 1.27)
				)
			)
		)
		(property "Value" ""
			(at 0 0 0)
			(layer "F.Fab")
			(effects
				(font
					(size 1.27 1.27)
				)
			)
		)
		(duplicate_pad_numbers_are_jumpers no)
		(fp_line
			(start -0.7874 -0.4064)
			(end 0.7874 -0.4064)
			(stroke
				(width 0.1524)
				(type default)
			)
			(layer "F.SilkS")
		)
		(fp_line
			(start -0.7874 0.4064)
			(end -0.7874 -0.4064)
			(stroke
				(width 0.1524)
				(type default)
			)
			(layer "F.SilkS")
		)
		(fp_line
			(start 0.7874 -0.4064)
			(end 0.7874 0.4064)
			(stroke
				(width 0.1524)
				(type default)
			)
			(layer "F.SilkS")
		)
		(fp_line
			(start 0.7874 0.4064)
			(end -0.7874 0.4064)
			(stroke
				(width 0.1524)
				(type default)
			)
			(layer "F.SilkS")
		)
		(fp_line
			(start -0.67945 -0.305054)
			(end -0.12065 -0.305054)
			(stroke
				(width 0.1)
				(type default)
			)
			(layer "F.Fab")
		)
		(fp_line
			(start -0.67945 0.3048)
			(end -0.67945 -0.305054)
			(stroke
				(width 0.1)
				(type default)
			)
			(layer "F.Fab")
		)
		(fp_line
			(start -0.12065 -0.305054)
			(end -0.12065 -0.2794)
			(stroke
				(width 0.1)
				(type default)
			)
			(layer "F.Fab")
		)
		(fp_line
			(start -0.12065 -0.2794)
			(end 0.12065 -0.2794)
			(stroke
				(width 0.1)
				(type default)
			)
			(layer "F.Fab")
		)
		(fp_line
			(start -0.12065 0.2794)
			(end -0.12065 0.3048)
			(stroke
				(width 0.1)
				(type default)
			)
			(layer "F.Fab")
		)
		(fp_line
			(start -0.12065 0.3048)
			(end -0.67945 0.3048)
			(stroke
				(width 0.1)
				(type default)
			)
			(layer "F.Fab")
		)
		(fp_line
			(start 0.120396 0.2794)
			(end -0.12065 0.2794)
			(stroke
				(width 0.1)
				(type default)
			)
			(layer "F.Fab")
		)
		(fp_line
			(start 0.120396 0.3048)
			(end 0.120396 0.2794)
			(stroke
				(width 0.1)
				(type default)
			)
			(layer "F.Fab")
		)
		(fp_line
			(start 0.12065 -0.3048)
			(end 0.67945 -0.3048)
			(stroke
				(width 0.1)
				(type default)
			)
			(layer "F.Fab")
		)
		(fp_line
			(start 0.12065 -0.2794)
			(end 0.12065 -0.3048)
			(stroke
				(width 0.1)
				(type default)
			)
			(layer "F.Fab")
		)
		(fp_line
			(start 0.67945 -0.3048)
			(end 0.67945 0.3048)
			(stroke
				(width 0.1)
				(type default)
			)
			(layer "F.Fab")
		)
		(fp_line
			(start 0.67945 0.3048)
			(end 0.120396 0.3048)
			(stroke
				(width 0.1)
				(type default)
			)
			(layer "F.Fab")
		)
		(pad "1" smd circle
			(at -0.40005 0)
			(size 0 0)
			(layers "F.Cu" "F.Mask" "F.Paste")
			(net "P3V3_AUX")
		)
		(pad "2" smd circle
			(at 0.40005 0)
			(size 0 0)
			(layers "F.Cu" "F.Mask" "F.Paste")
			(net "GND")
		)
	)
	(footprint ""
		(layer "F.Cu")
		(at 393.741148 -162.360864 -90)
		(property "Reference" "R993"
			(at 0 0 270)
			(layer "F.SilkS")
			(hide yes)
			(effects
				(font
					(size 1.27 1.27)
				)
			)
		)
		(property "Value" ""
			(at 0 0 270)
			(layer "F.Fab")
			(effects
				(font
					(size 1.27 1.27)
				)
			)
		)
		(duplicate_pad_numbers_are_jumpers no)
		(fp_line
			(start -0.7874 0.4064)
			(end -0.7874 -0.4064)
			(stroke
				(width 0.1524)
				(type default)
			)
			(layer "F.SilkS")
		)
		(fp_line
			(start 0.7874 0.4064)
			(end -0.7874 0.4064)
			(stroke
				(width 0.1524)
				(type default)
			)
			(layer "F.SilkS")
		)
		(fp_line
			(start -0.7874 -0.4064)
			(end 0.7874 -0.4064)
			(stroke
				(width 0.1524)
				(type default)
			)
			(layer "F.SilkS")
		)
		(fp_line
			(start 0.7874 -0.4064)
			(end 0.7874 0.4064)
			(stroke
				(width 0.1524)
				(type default)
			)
			(layer "F.SilkS")
		)
		(fp_line
			(start -0.67945 0.3048)
			(end -0.67945 -0.305054)
			(stroke
				(width 0.1)
				(type default)
			)
			(layer "F.Fab")
		)
		(fp_line
			(start -0.12065 0.3048)
			(end -0.67945 0.3048)
			(stroke
				(width 0.1)
				(type default)
			)
			(layer "F.Fab")
		)
		(fp_line
			(start 0.120396 0.3048)
			(end 0.120396 0.2794)
			(stroke
				(width 0.1)
				(type default)
			)
			(layer "F.Fab")
		)
		(fp_line
			(start 0.67945 0.3048)
			(end 0.120396 0.3048)
			(stroke
				(width 0.1)
				(type default)
			)
			(layer "F.Fab")
		)
		(fp_line
			(start -0.12065 0.2794)
			(end -0.12065 0.3048)
			(stroke
				(width 0.1)
				(type default)
			)
			(layer "F.Fab")
		)
		(fp_line
			(start 0.120396 0.2794)
			(end -0.12065 0.2794)
			(stroke
				(width 0.1)
				(type default)
			)
			(layer "F.Fab")
		)
		(fp_line
			(start -0.12065 -0.2794)
			(end 0.12065 -0.2794)
			(stroke
				(width 0.1)
				(type default)
			)
			(layer "F.Fab")
		)
		(fp_line
			(start 0.12065 -0.2794)
			(end 0.12065 -0.3048)
			(stroke
				(width 0.1)
				(type default)
			)
			(layer "F.Fab")
		)
		(fp_line
			(start 0.12065 -0.3048)
			(end 0.67945 -0.3048)
			(stroke
				(width 0.1)
				(type default)
			)
			(layer "F.Fab")
		)
		(fp_line
			(start 0.67945 -0.3048)
			(end 0.67945 0.3048)
			(stroke
				(width 0.1)
				(type default)
			)
			(layer "F.Fab")
		)
		(fp_line
			(start -0.67945 -0.305054)
			(end -0.12065 -0.305054)
			(stroke
				(width 0.1)
				(type default)
			)
			(layer "F.Fab")
		)
		(fp_line
			(start -0.12065 -0.305054)
			(end -0.12065 -0.2794)
			(stroke
				(width 0.1)
				(type default)
			)
			(layer "F.Fab")
		)
		(pad "1" smd circle
			(at -0.40005 0 270)
			(size 0 0)
			(layers "F.Cu" "F.Mask" "F.Paste")
			(net "SMB_S3M_CPU0_SCL")
		)
		(pad "2" smd circle
			(at 0.40005 0 270)
			(size 0 0)
			(layers "F.Cu" "F.Mask" "F.Paste")
			(net "SMB_S3M_CPU0_R_SCL")
		)
	)
	(footprint ""
		(layer "F.Cu")
		(at 201.00036 -120.614948)
		(property "Reference" "R736"
			(at 0 0 0)
			(layer "F.SilkS")
			(hide yes)
			(effects
				(font
					(size 1.27 1.27)
				)
			)
		)
		(property "Value" ""
			(at 0 0 0)
			(layer "F.Fab")
			(effects
				(font
					(size 1.27 1.27)
				)
			)
		)
		(duplicate_pad_numbers_are_jumpers no)
		(fp_line
			(start -0.7874 -0.4064)
			(end 0.7874 -0.4064)
			(stroke
				(width 0.1524)
				(type default)
			)
			(layer "F.SilkS")
		)
		(fp_line
			(start -0.7874 0.4064)
			(end -0.7874 -0.4064)
			(stroke
				(width 0.1524)
				(type default)
			)
			(layer "F.SilkS")
		)
		(fp_line
			(start 0.7874 -0.4064)
			(end 0.7874 0.4064)
			(stroke
				(width 0.1524)
				(type default)
			)
			(layer "F.SilkS")
		)
		(fp_line
			(start 0.7874 0.4064)
			(end -0.7874 0.4064)
			(stroke
				(width 0.1524)
				(type default)
			)
			(layer "F.SilkS")
		)
		(fp_line
			(start -0.67945 -0.305054)
			(end -0.12065 -0.305054)
			(stroke
				(width 0.1)
				(type default)
			)
			(layer "F.Fab")
		)
		(fp_line
			(start -0.67945 0.3048)
			(end -0.67945 -0.305054)
			(stroke
				(width 0.1)
				(type default)
			)
			(layer "F.Fab")
		)
		(fp_line
			(start -0.12065 -0.305054)
			(end -0.12065 -0.2794)
			(stroke
				(width 0.1)
				(type default)
			)
			(layer "F.Fab")
		)
		(fp_line
			(start -0.12065 -0.2794)
			(end 0.12065 -0.2794)
			(stroke
				(width 0.1)
				(type default)
			)
			(layer "F.Fab")
		)
		(fp_line
			(start -0.12065 0.2794)
			(end -0.12065 0.3048)
			(stroke
				(width 0.1)
				(type default)
			)
			(layer "F.Fab")
		)
		(fp_line
			(start -0.12065 0.3048)
			(end -0.67945 0.3048)
			(stroke
				(width 0.1)
				(type default)
			)
			(layer "F.Fab")
		)
		(fp_line
			(start 0.120396 0.2794)
			(end -0.12065 0.2794)
			(stroke
				(width 0.1)
				(type default)
			)
			(layer "F.Fab")
		)
		(fp_line
			(start 0.120396 0.3048)
			(end 0.120396 0.2794)
			(stroke
				(width 0.1)
				(type default)
			)
			(layer "F.Fab")
		)
		(fp_line
			(start 0.12065 -0.3048)
			(end 0.67945 -0.3048)
			(stroke
				(width 0.1)
				(type default)
			)
			(layer "F.Fab")
		)
		(fp_line
			(start 0.12065 -0.2794)
			(end 0.12065 -0.3048)
			(stroke
				(width 0.1)
				(type default)
			)
			(layer "F.Fab")
		)
		(fp_line
			(start 0.67945 -0.3048)
			(end 0.67945 0.3048)
			(stroke
				(width 0.1)
				(type default)
			)
			(layer "F.Fab")
		)
		(fp_line
			(start 0.67945 0.3048)
			(end 0.120396 0.3048)
			(stroke
				(width 0.1)
				(type default)
			)
			(layer "F.Fab")
		)
		(pad "1" smd circle
			(at -0.40005 0)
			(size 0 0)
			(layers "F.Cu" "F.Mask" "F.Paste")
			(net "FM_DIMM_12V_CPS_SX_N")
		)
		(pad "2" smd circle
			(at 0.40005 0)
			(size 0 0)
			(layers "F.Cu" "F.Mask" "F.Paste")
			(net "GND")
		)
	)
	(footprint ""
		(layer "F.Cu")
		(at 303.954688 -402.371052 -90)
		(property "Reference" "C1578"
			(at 0 0 270)
			(layer "F.SilkS")
			(hide yes)
			(effects
				(font
					(size 1.27 1.27)
				)
			)
		)
		(property "Value" ""
			(at 0 0 270)
			(layer "F.Fab")
			(effects
				(font
					(size 1.27 1.27)
				)
			)
		)
		(duplicate_pad_numbers_are_jumpers no)
		(fp_line
			(start -0.299974 0.150114)
			(end -0.299974 -0.150114)
			(stroke
				(width 0.1)
				(type default)
			)
			(layer "F.Fab")
		)
		(fp_line
			(start 0.299974 0.150114)
			(end -0.299974 0.150114)
			(stroke
				(width 0.1)
				(type default)
			)
			(layer "F.Fab")
		)
		(fp_line
			(start -0.299974 -0.150114)
			(end 0.299974 -0.150114)
			(stroke
				(width 0.1)
				(type default)
			)
			(layer "F.Fab")
		)
		(fp_line
			(start 0.299974 -0.150114)
			(end 0.299974 0.150114)
			(stroke
				(width 0.1)
				(type default)
			)
			(layer "F.Fab")
		)
		(pad "1" smd rect
			(at -0.2667 0 270)
			(size 0.3048 0.381)
			(layers "F.Cu" "F.Mask" "F.Paste")
			(net "P5E_CPU0_PE4_TX_C_DN<0>")
		)
		(pad "2" smd rect
			(at 0.2667 0 270)
			(size 0.3048 0.381)
			(layers "F.Cu" "F.Mask" "F.Paste")
			(net "P5E_CPU0_PE4_TX_DN<0>")
		)
	)
	(footprint ""
		(layer "F.Cu")
		(at 385.318 -34.585148)
		(property "Reference" "R4618"
			(at 0 0 0)
			(layer "F.SilkS")
			(hide yes)
			(effects
				(font
					(size 1.27 1.27)
				)
			)
		)
		(property "Value" ""
			(at 0 0 0)
			(layer "F.Fab")
			(effects
				(font
					(size 1.27 1.27)
				)
			)
		)
		(duplicate_pad_numbers_are_jumpers no)
		(fp_line
			(start -0.7874 -0.4064)
			(end 0.7874 -0.4064)
			(stroke
				(width 0.1524)
				(type default)
			)
			(layer "F.SilkS")
		)
		(fp_line
			(start -0.7874 0.4064)
			(end -0.7874 -0.4064)
			(stroke
				(width 0.1524)
				(type default)
			)
			(layer "F.SilkS")
		)
		(fp_line
			(start 0.7874 -0.4064)
			(end 0.7874 0.4064)
			(stroke
				(width 0.1524)
				(type default)
			)
			(layer "F.SilkS")
		)
		(fp_line
			(start 0.7874 0.4064)
			(end -0.7874 0.4064)
			(stroke
				(width 0.1524)
				(type default)
			)
			(layer "F.SilkS")
		)
		(fp_line
			(start -0.67945 -0.305054)
			(end -0.12065 -0.305054)
			(stroke
				(width 0.1)
				(type default)
			)
			(layer "F.Fab")
		)
		(fp_line
			(start -0.67945 0.3048)
			(end -0.67945 -0.305054)
			(stroke
				(width 0.1)
				(type default)
			)
			(layer "F.Fab")
		)
		(fp_line
			(start -0.12065 -0.305054)
			(end -0.12065 -0.2794)
			(stroke
				(width 0.1)
				(type default)
			)
			(layer "F.Fab")
		)
		(fp_line
			(start -0.12065 -0.2794)
			(end 0.12065 -0.2794)
			(stroke
				(width 0.1)
				(type default)
			)
			(layer "F.Fab")
		)
		(fp_line
			(start -0.12065 0.2794)
			(end -0.12065 0.3048)
			(stroke
				(width 0.1)
				(type default)
			)
			(layer "F.Fab")
		)
		(fp_line
			(start -0.12065 0.3048)
			(end -0.67945 0.3048)
			(stroke
				(width 0.1)
				(type default)
			)
			(layer "F.Fab")
		)
		(fp_line
			(start 0.120396 0.2794)
			(end -0.12065 0.2794)
			(stroke
				(width 0.1)
				(type default)
			)
			(layer "F.Fab")
		)
		(fp_line
			(start 0.120396 0.3048)
			(end 0.120396 0.2794)
			(stroke
				(width 0.1)
				(type default)
			)
			(layer "F.Fab")
		)
		(fp_line
			(start 0.12065 -0.3048)
			(end 0.67945 -0.3048)
			(stroke
				(width 0.1)
				(type default)
			)
			(layer "F.Fab")
		)
		(fp_line
			(start 0.12065 -0.2794)
			(end 0.12065 -0.3048)
			(stroke
				(width 0.1)
				(type default)
			)
			(layer "F.Fab")
		)
		(fp_line
			(start 0.67945 -0.3048)
			(end 0.67945 0.3048)
			(stroke
				(width 0.1)
				(type default)
			)
			(layer "F.Fab")
		)
		(fp_line
			(start 0.67945 0.3048)
			(end 0.120396 0.3048)
			(stroke
				(width 0.1)
				(type default)
			)
			(layer "F.Fab")
		)
		(pad "1" smd circle
			(at -0.40005 0)
			(size 0 0)
			(layers "F.Cu" "F.Mask" "F.Paste")
			(net "HP_LVC3_OCP_V3_1_PWRGD")
		)
		(pad "2" smd circle
			(at 0.40005 0)
			(size 0 0)
			(layers "F.Cu" "F.Mask" "F.Paste")
			(net "HP_LVC3_OCP_V3_1_PWRGD_R")
		)
	)
	(footprint ""
		(layer "F.Cu")
		(at 205.397608 -407.871422 180)
		(property "Reference" "PR1134"
			(at 0 0 180)
			(layer "F.SilkS")
			(hide yes)
			(effects
				(font
					(size 1.27 1.27)
				)
			)
		)
		(property "Value" ""
			(at 0 0 180)
			(layer "F.Fab")
			(effects
				(font
					(size 1.27 1.27)
				)
			)
		)
		(duplicate_pad_numbers_are_jumpers no)
		(fp_line
			(start 0.7874 0.4064)
			(end -0.7874 0.4064)
			(stroke
				(width 0.1524)
				(type default)
			)
			(layer "F.SilkS")
		)
		(fp_line
			(start 0.7874 -0.4064)
			(end 0.7874 0.4064)
			(stroke
				(width 0.1524)
				(type default)
			)
			(layer "F.SilkS")
		)
		(fp_line
			(start -0.7874 0.4064)
			(end -0.7874 -0.4064)
			(stroke
				(width 0.1524)
				(type default)
			)
			(layer "F.SilkS")
		)
		(fp_line
			(start -0.7874 -0.4064)
			(end 0.7874 -0.4064)
			(stroke
				(width 0.1524)
				(type default)
			)
			(layer "F.SilkS")
		)
		(fp_line
			(start 0.67945 0.3048)
			(end 0.120396 0.3048)
			(stroke
				(width 0.1)
				(type default)
			)
			(layer "F.Fab")
		)
		(fp_line
			(start 0.67945 -0.3048)
			(end 0.67945 0.3048)
			(stroke
				(width 0.1)
				(type default)
			)
			(layer "F.Fab")
		)
		(fp_line
			(start 0.12065 -0.2794)
			(end 0.12065 -0.3048)
			(stroke
				(width 0.1)
				(type default)
			)
			(layer "F.Fab")
		)
		(fp_line
			(start 0.12065 -0.3048)
			(end 0.67945 -0.3048)
			(stroke
				(width 0.1)
				(type default)
			)
			(layer "F.Fab")
		)
		(fp_line
			(start 0.120396 0.3048)
			(end 0.120396 0.2794)
			(stroke
				(width 0.1)
				(type default)
			)
			(layer "F.Fab")
		)
		(fp_line
			(start 0.120396 0.2794)
			(end -0.12065 0.2794)
			(stroke
				(width 0.1)
				(type default)
			)
			(layer "F.Fab")
		)
		(fp_line
			(start -0.12065 0.3048)
			(end -0.67945 0.3048)
			(stroke
				(width 0.1)
				(type default)
			)
			(layer "F.Fab")
		)
		(fp_line
			(start -0.12065 0.2794)
			(end -0.12065 0.3048)
			(stroke
				(width 0.1)
				(type default)
			)
			(layer "F.Fab")
		)
		(fp_line
			(start -0.12065 -0.2794)
			(end 0.12065 -0.2794)
			(stroke
				(width 0.1)
				(type default)
			)
			(layer "F.Fab")
		)
		(fp_line
			(start -0.12065 -0.305054)
			(end -0.12065 -0.2794)
			(stroke
				(width 0.1)
				(type default)
			)
			(layer "F.Fab")
		)
		(fp_line
			(start -0.67945 0.3048)
			(end -0.67945 -0.305054)
			(stroke
				(width 0.1)
				(type default)
			)
			(layer "F.Fab")
		)
		(fp_line
			(start -0.67945 -0.305054)
			(end -0.12065 -0.305054)
			(stroke
				(width 0.1)
				(type default)
			)
			(layer "F.Fab")
		)
		(pad "1" smd circle
			(at -0.40005 0 180)
			(size 0 0)
			(layers "F.Cu" "F.Mask" "F.Paste")
			(net "AGND_HSC")
		)
		(pad "2" smd circle
			(at 0.40005 0 180)
			(size 0 0)
			(layers "F.Cu" "F.Mask" "F.Paste")
			(net "HSC_MODE_1")
		)
	)
	(footprint ""
		(layer "F.Cu")
		(at 180.528468 -48.053498 180)
		(property "Reference" "C1100"
			(at 0 0 180)
			(layer "F.SilkS")
			(hide yes)
			(effects
				(font
					(size 1.27 1.27)
				)
			)
		)
		(property "Value" ""
			(at 0 0 180)
			(layer "F.Fab")
			(effects
				(font
					(size 1.27 1.27)
				)
			)
		)
		(duplicate_pad_numbers_are_jumpers no)
		(fp_line
			(start 0.299974 0.150114)
			(end -0.299974 0.150114)
			(stroke
				(width 0.1)
				(type default)
			)
			(layer "F.Fab")
		)
		(fp_line
			(start 0.299974 -0.150114)
			(end 0.299974 0.150114)
			(stroke
				(width 0.1)
				(type default)
			)
			(layer "F.Fab")
		)
		(fp_line
			(start -0.299974 0.150114)
			(end -0.299974 -0.150114)
			(stroke
				(width 0.1)
				(type default)
			)
			(layer "F.Fab")
		)
		(fp_line
			(start -0.299974 -0.150114)
			(end 0.299974 -0.150114)
			(stroke
				(width 0.1)
				(type default)
			)
			(layer "F.Fab")
		)
		(pad "1" smd rect
			(at -0.2667 0 180)
			(size 0.3048 0.381)
			(layers "F.Cu" "F.Mask" "F.Paste")
			(net "P3E_PCH_M2_TX_DP<2>")
		)
		(pad "2" smd rect
			(at 0.2667 0 180)
			(size 0.3048 0.381)
			(layers "F.Cu" "F.Mask" "F.Paste")
			(net "P3E_PCH_M2_TX_C_DP<2>")
		)
		(zone
			(layer "In1.Cu")
			(hatch none 0.5)
			(connect_pads
				(clearance 0)
			)
			(min_thickness 0.25)
			(keepout
				(tracks not_allowed)
				(vias allowed)
				(pads allowed)
				(copperpour not_allowed)
				(footprints allowed)
			)
			(placement
				(enabled no)
				(sheetname "")
			)
			(fill
				(thermal_gap 0.5)
				(thermal_bridge_width 0.5)
				(island_removal_mode 0)
			)
			(polygon
				(pts
					(arc
						(start 180.388768 -48.294798)
						(mid 180.44265 -48.27248)
						(end 180.464968 -48.218598)
					)
					(arc
						(start 180.464968 -47.888398)
						(mid 180.44265 -47.834516)
						(end 180.388768 -47.812198)
					)
					(arc
						(start 180.134768 -47.812198)
						(mid 180.080886 -47.834516)
						(end 180.058568 -47.888398)
					)
					(arc
						(start 180.058568 -48.218598)
						(mid 180.080886 -48.27248)
						(end 180.134768 -48.294798)
					)
				)
			)
		)
		(zone
			(layer "In1.Cu")
			(hatch none 0.5)
			(connect_pads
				(clearance 0)
			)
			(min_thickness 0.25)
			(keepout
				(tracks not_allowed)
				(vias allowed)
				(pads allowed)
				(copperpour not_allowed)
				(footprints allowed)
			)
			(placement
				(enabled no)
				(sheetname "")
			)
			(fill
				(thermal_gap 0.5)
				(thermal_bridge_width 0.5)
				(island_removal_mode 0)
			)
			(polygon
				(pts
					(arc
						(start 180.922168 -48.294798)
						(mid 180.97605 -48.27248)
						(end 180.998368 -48.218598)
					)
					(arc
						(start 180.998368 -47.888398)
						(mid 180.97605 -47.834516)
						(end 180.922168 -47.812198)
					)
					(arc
						(start 180.668168 -47.812198)
						(mid 180.614286 -47.834516)
						(end 180.591968 -47.888398)
					)
					(arc
						(start 180.591968 -48.218598)
						(mid 180.614286 -48.27248)
						(end 180.668168 -48.294798)
					)
				)
			)
		)
	)
	(footprint ""
		(layer "F.Cu")
		(at 365.46663 -240.276888 90)
		(property "Reference" "C1045"
			(at 0 0 90)
			(layer "F.SilkS")
			(hide yes)
			(effects
				(font
					(size 1.27 1.27)
				)
			)
		)
		(property "Value" ""
			(at 0 0 90)
			(layer "F.Fab")
			(effects
				(font
					(size 1.27 1.27)
				)
			)
		)
		(duplicate_pad_numbers_are_jumpers no)
		(fp_line
			(start 0.7874 -0.4064)
			(end 0.7874 0.4064)
			(stroke
				(width 0.1524)
				(type default)
			)
			(layer "F.SilkS")
		)
		(fp_line
			(start -0.7874 -0.4064)
			(end 0.7874 -0.4064)
			(stroke
				(width 0.1524)
				(type default)
			)
			(layer "F.SilkS")
		)
		(fp_line
			(start 0.7874 0.4064)
			(end -0.7874 0.4064)
			(stroke
				(width 0.1524)
				(type default)
			)
			(layer "F.SilkS")
		)
		(fp_line
			(start -0.7874 0.4064)
			(end -0.7874 -0.4064)
			(stroke
				(width 0.1524)
				(type default)
			)
			(layer "F.SilkS")
		)
		(fp_line
			(start -0.12065 -0.305054)
			(end -0.12065 -0.2794)
			(stroke
				(width 0.1)
				(type default)
			)
			(layer "F.Fab")
		)
		(fp_line
			(start -0.67945 -0.305054)
			(end -0.12065 -0.305054)
			(stroke
				(width 0.1)
				(type default)
			)
			(layer "F.Fab")
		)
		(fp_line
			(start 0.67945 -0.3048)
			(end 0.67945 0.3048)
			(stroke
				(width 0.1)
				(type default)
			)
			(layer "F.Fab")
		)
		(fp_line
			(start 0.12065 -0.3048)
			(end 0.67945 -0.3048)
			(stroke
				(width 0.1)
				(type default)
			)
			(layer "F.Fab")
		)
		(fp_line
			(start 0.12065 -0.2794)
			(end 0.12065 -0.3048)
			(stroke
				(width 0.1)
				(type default)
			)
			(layer "F.Fab")
		)
		(fp_line
			(start -0.12065 -0.2794)
			(end 0.12065 -0.2794)
			(stroke
				(width 0.1)
				(type default)
			)
			(layer "F.Fab")
		)
		(fp_line
			(start 0.120396 0.2794)
			(end -0.12065 0.2794)
			(stroke
				(width 0.1)
				(type default)
			)
			(layer "F.Fab")
		)
		(fp_line
			(start -0.12065 0.2794)
			(end -0.12065 0.3048)
			(stroke
				(width 0.1)
				(type default)
			)
			(layer "F.Fab")
		)
		(fp_line
			(start 0.67945 0.3048)
			(end 0.120396 0.3048)
			(stroke
				(width 0.1)
				(type default)
			)
			(layer "F.Fab")
		)
		(fp_line
			(start 0.120396 0.3048)
			(end 0.120396 0.2794)
			(stroke
				(width 0.1)
				(type default)
			)
			(layer "F.Fab")
		)
		(fp_line
			(start -0.12065 0.3048)
			(end -0.67945 0.3048)
			(stroke
				(width 0.1)
				(type default)
			)
			(layer "F.Fab")
		)
		(fp_line
			(start -0.67945 0.3048)
			(end -0.67945 -0.305054)
			(stroke
				(width 0.1)
				(type default)
			)
			(layer "F.Fab")
		)
		(pad "1" smd circle
			(at -0.40005 0 90)
			(size 0 0)
			(layers "F.Cu" "F.Mask" "F.Paste")
			(net "PVCCIN_CPU0")
		)
		(pad "2" smd circle
			(at 0.40005 0 90)
			(size 0 0)
			(layers "F.Cu" "F.Mask" "F.Paste")
			(net "GND")
		)
	)
	(footprint ""
		(layer "F.Cu")
		(at 5.35432 -74.719688)
		(property "Reference" "U241"
			(at -1.23698 2.420112 0)
			(unlocked yes)
			(layer "F.SilkS")
			(effects
				(font
					(size 0.7874 0.5842)
					(thickness 0.1524)
				)
				(justify left)
			)
		)
		(property "Value" ""
			(at 0 0 0)
			(layer "F.Fab")
			(effects
				(font
					(size 1.27 1.27)
				)
			)
		)
		(duplicate_pad_numbers_are_jumpers no)
		(fp_line
			(start -1.207008 -1.549908)
			(end -1.207008 1.549908)
			(stroke
				(width 0.1524)
				(type default)
			)
			(layer "F.SilkS")
		)
		(fp_line
			(start -1.207008 1.549908)
			(end 1.207008 1.549908)
			(stroke
				(width 0.1524)
				(type default)
			)
			(layer "F.SilkS")
		)
		(fp_line
			(start -0.762508 -1.549908)
			(end -1.207008 -1.549908)
			(stroke
				(width 0.1524)
				(type default)
			)
			(layer "F.SilkS")
		)
		(fp_line
			(start 0 -0.635)
			(end -0.762508 -1.549908)
			(stroke
				(width 0.1524)
				(type default)
			)
			(layer "F.SilkS")
		)
		(fp_line
			(start 0.762508 -1.549908)
			(end 0 -0.635)
			(stroke
				(width 0.1524)
				(type default)
			)
			(layer "F.SilkS")
		)
		(fp_line
			(start 1.207008 -1.549908)
			(end 0.762508 -1.549908)
			(stroke
				(width 0.1524)
				(type default)
			)
			(layer "F.SilkS")
		)
		(fp_line
			(start 1.207008 1.549908)
			(end 1.207008 -1.549908)
			(stroke
				(width 0.1524)
				(type default)
			)
			(layer "F.SilkS")
		)
		(fp_poly
			(pts
				(xy -3.48996 -1.64211) (xy -2.47396 -1.13411) (xy -3.48996 -0.62611)
			)
			(stroke
				(width 0)
				(type default)
			)
			(fill yes)
			(layer "F.SilkS")
		)
		(fp_line
			(start -1.549908 -1.549908)
			(end -1.549908 1.549908)
			(stroke
				(width 0.1)
				(type default)
			)
			(layer "F.Fab")
		)
		(fp_line
			(start -1.549908 1.549908)
			(end 1.549908 1.549908)
			(stroke
				(width 0.1)
				(type default)
			)
			(layer "F.Fab")
		)
		(fp_line
			(start 1.549908 -1.549908)
			(end -1.549908 -1.549908)
			(stroke
				(width 0.1)
				(type default)
			)
			(layer "F.Fab")
		)
		(fp_line
			(start 1.549908 1.549908)
			(end 1.549908 -1.549908)
			(stroke
				(width 0.1)
				(type default)
			)
			(layer "F.Fab")
		)
		(fp_poly
			(pts
				(xy -3.4036 -1.53289) (xy -3.4036 -0.51689) (xy -2.3876 -1.02489)
			)
			(stroke
				(width 0)
				(type default)
			)
			(fill yes)
			(layer "F.Fab")
		)
		(pad "1" smd rect
			(at -1.774952 -1.02489 270)
			(size 0.508 0.8636)
			(layers "F.Cu" "F.Mask" "F.Paste")
			(net "OCP_V3_2_PRSNT0_R_N")
		)
		(pad "2" smd rect
			(at -1.774952 -0.32512 270)
			(size 0.4064 0.8636)
			(layers "F.Cu" "F.Mask" "F.Paste")
			(net "OCP_V3_2_PRSNT1_R_N")
		)
		(pad "3" smd rect
			(at -1.774952 0.32512 270)
			(size 0.4064 0.8636)
			(layers "F.Cu" "F.Mask" "F.Paste")
			(net "OCP_V3_2_PRSNT23_R_N")
		)
		(pad "4" smd rect
			(at -1.774952 1.02489 270)
			(size 0.508 0.8636)
			(layers "F.Cu" "F.Mask" "F.Paste")
			(net "GND")
		)
		(pad "5" smd rect
			(at 1.774952 1.02489 270)
			(size 0.508 0.8636)
			(layers "F.Cu" "F.Mask" "F.Paste")
			(net "OCP_V3_2_PRSNT2_R_N")
		)
		(pad "6" smd rect
			(at 1.774952 0.32512 270)
			(size 0.4064 0.8636)
			(layers "F.Cu" "F.Mask" "F.Paste")
			(net "OCP_V3_2_PRSNT3_R_N")
		)
		(pad "7" smd rect
			(at 1.774952 -0.32512 270)
			(size 0.4064 0.8636)
			(layers "F.Cu" "F.Mask" "F.Paste")
			(net "OCP_V3_2_PRSNT01_R_N")
		)
		(pad "8" smd rect
			(at 1.774952 -1.02489 270)
			(size 0.508 0.8636)
			(layers "F.Cu" "F.Mask" "F.Paste")
			(net "P3V3_AUX")
		)
	)
	(footprint ""
		(layer "F.Cu")
		(at 70.052438 -31.887922 -90)
		(property "Reference" "R3630"
			(at 0 0 270)
			(layer "F.SilkS")
			(hide yes)
			(effects
				(font
					(size 1.27 1.27)
				)
			)
		)
		(property "Value" ""
			(at 0 0 270)
			(layer "F.Fab")
			(effects
				(font
					(size 1.27 1.27)
				)
			)
		)
		(duplicate_pad_numbers_are_jumpers no)
		(fp_line
			(start -0.7874 0.4064)
			(end -0.7874 -0.4064)
			(stroke
				(width 0.1524)
				(type default)
			)
			(layer "F.SilkS")
		)
		(fp_line
			(start 0.7874 0.4064)
			(end -0.7874 0.4064)
			(stroke
				(width 0.1524)
				(type default)
			)
			(layer "F.SilkS")
		)
		(fp_line
			(start -0.7874 -0.4064)
			(end 0.7874 -0.4064)
			(stroke
				(width 0.1524)
				(type default)
			)
			(layer "F.SilkS")
		)
		(fp_line
			(start 0.7874 -0.4064)
			(end 0.7874 0.4064)
			(stroke
				(width 0.1524)
				(type default)
			)
			(layer "F.SilkS")
		)
		(fp_line
			(start -0.67945 0.3048)
			(end -0.67945 -0.305054)
			(stroke
				(width 0.1)
				(type default)
			)
			(layer "F.Fab")
		)
		(fp_line
			(start -0.12065 0.3048)
			(end -0.67945 0.3048)
			(stroke
				(width 0.1)
				(type default)
			)
			(layer "F.Fab")
		)
		(fp_line
			(start 0.120396 0.3048)
			(end 0.120396 0.2794)
			(stroke
				(width 0.1)
				(type default)
			)
			(layer "F.Fab")
		)
		(fp_line
			(start 0.67945 0.3048)
			(end 0.120396 0.3048)
			(stroke
				(width 0.1)
				(type default)
			)
			(layer "F.Fab")
		)
		(fp_line
			(start -0.12065 0.2794)
			(end -0.12065 0.3048)
			(stroke
				(width 0.1)
				(type default)
			)
			(layer "F.Fab")
		)
		(fp_line
			(start 0.120396 0.2794)
			(end -0.12065 0.2794)
			(stroke
				(width 0.1)
				(type default)
			)
			(layer "F.Fab")
		)
		(fp_line
			(start -0.12065 -0.2794)
			(end 0.12065 -0.2794)
			(stroke
				(width 0.1)
				(type default)
			)
			(layer "F.Fab")
		)
		(fp_line
			(start 0.12065 -0.2794)
			(end 0.12065 -0.3048)
			(stroke
				(width 0.1)
				(type default)
			)
			(layer "F.Fab")
		)
		(fp_line
			(start 0.12065 -0.3048)
			(end 0.67945 -0.3048)
			(stroke
				(width 0.1)
				(type default)
			)
			(layer "F.Fab")
		)
		(fp_line
			(start 0.67945 -0.3048)
			(end 0.67945 0.3048)
			(stroke
				(width 0.1)
				(type default)
			)
			(layer "F.Fab")
		)
		(fp_line
			(start -0.67945 -0.305054)
			(end -0.12065 -0.305054)
			(stroke
				(width 0.1)
				(type default)
			)
			(layer "F.Fab")
		)
		(fp_line
			(start -0.12065 -0.305054)
			(end -0.12065 -0.2794)
			(stroke
				(width 0.1)
				(type default)
			)
			(layer "F.Fab")
		)
		(pad "1" smd circle
			(at -0.40005 0 270)
			(size 0 0)
			(layers "F.Cu" "F.Mask" "F.Paste")
			(net "HP_LVC3_OCP_V3_2_EN")
		)
		(pad "2" smd circle
			(at 0.40005 0 270)
			(size 0 0)
			(layers "F.Cu" "F.Mask" "F.Paste")
			(net "P12V_OCP_V3_2_EN_2_R3")
		)
	)
	(footprint ""
		(layer "F.Cu")
		(at 441.52566 -106.38536 -90)
		(property "Reference" "R4748"
			(at 0 0 270)
			(layer "F.SilkS")
			(hide yes)
			(effects
				(font
					(size 1.27 1.27)
				)
			)
		)
		(property "Value" ""
			(at 0 0 270)
			(layer "F.Fab")
			(effects
				(font
					(size 1.27 1.27)
				)
			)
		)
		(duplicate_pad_numbers_are_jumpers no)
		(fp_line
			(start -0.7874 0.4064)
			(end -0.7874 -0.4064)
			(stroke
				(width 0.1524)
				(type default)
			)
			(layer "F.SilkS")
		)
		(fp_line
			(start 0.7874 0.4064)
			(end -0.7874 0.4064)
			(stroke
				(width 0.1524)
				(type default)
			)
			(layer "F.SilkS")
		)
		(fp_line
			(start -0.7874 -0.4064)
			(end 0.7874 -0.4064)
			(stroke
				(width 0.1524)
				(type default)
			)
			(layer "F.SilkS")
		)
		(fp_line
			(start 0.7874 -0.4064)
			(end 0.7874 0.4064)
			(stroke
				(width 0.1524)
				(type default)
			)
			(layer "F.SilkS")
		)
		(fp_line
			(start -0.67945 0.3048)
			(end -0.67945 -0.305054)
			(stroke
				(width 0.1)
				(type default)
			)
			(layer "F.Fab")
		)
		(fp_line
			(start -0.12065 0.3048)
			(end -0.67945 0.3048)
			(stroke
				(width 0.1)
				(type default)
			)
			(layer "F.Fab")
		)
		(fp_line
			(start 0.120396 0.3048)
			(end 0.120396 0.2794)
			(stroke
				(width 0.1)
				(type default)
			)
			(layer "F.Fab")
		)
		(fp_line
			(start 0.67945 0.3048)
			(end 0.120396 0.3048)
			(stroke
				(width 0.1)
				(type default)
			)
			(layer "F.Fab")
		)
		(fp_line
			(start -0.12065 0.2794)
			(end -0.12065 0.3048)
			(stroke
				(width 0.1)
				(type default)
			)
			(layer "F.Fab")
		)
		(fp_line
			(start 0.120396 0.2794)
			(end -0.12065 0.2794)
			(stroke
				(width 0.1)
				(type default)
			)
			(layer "F.Fab")
		)
		(fp_line
			(start -0.12065 -0.2794)
			(end 0.12065 -0.2794)
			(stroke
				(width 0.1)
				(type default)
			)
			(layer "F.Fab")
		)
		(fp_line
			(start 0.12065 -0.2794)
			(end 0.12065 -0.3048)
			(stroke
				(width 0.1)
				(type default)
			)
			(layer "F.Fab")
		)
		(fp_line
			(start 0.12065 -0.3048)
			(end 0.67945 -0.3048)
			(stroke
				(width 0.1)
				(type default)
			)
			(layer "F.Fab")
		)
		(fp_line
			(start 0.67945 -0.3048)
			(end 0.67945 0.3048)
			(stroke
				(width 0.1)
				(type default)
			)
			(layer "F.Fab")
		)
		(fp_line
			(start -0.67945 -0.305054)
			(end -0.12065 -0.305054)
			(stroke
				(width 0.1)
				(type default)
			)
			(layer "F.Fab")
		)
		(fp_line
			(start -0.12065 -0.305054)
			(end -0.12065 -0.2794)
			(stroke
				(width 0.1)
				(type default)
			)
			(layer "F.Fab")
		)
		(pad "1" smd circle
			(at -0.40005 0 270)
			(size 0 0)
			(layers "F.Cu" "F.Mask" "F.Paste")
			(net "HP_LVC3_OCP_V3_1_PWRGD_R2")
		)
		(pad "2" smd circle
			(at 0.40005 0 270)
			(size 0 0)
			(layers "F.Cu" "F.Mask" "F.Paste")
			(net "OCP_SFF_AUX_PWR_EN_R2")
		)
	)
	(footprint ""
		(layer "F.Cu")
		(at 117.526816 -260.36524 -90)
		(property "Reference" "C441"
			(at 0 0 270)
			(layer "F.SilkS")
			(hide yes)
			(effects
				(font
					(size 1.27 1.27)
				)
			)
		)
		(property "Value" ""
			(at 0 0 270)
			(layer "F.Fab")
			(effects
				(font
					(size 1.27 1.27)
				)
			)
		)
		(duplicate_pad_numbers_are_jumpers no)
		(fp_line
			(start -0.7874 0.4064)
			(end -0.7874 -0.4064)
			(stroke
				(width 0.1524)
				(type default)
			)
			(layer "F.SilkS")
		)
		(fp_line
			(start 0.7874 0.4064)
			(end -0.7874 0.4064)
			(stroke
				(width 0.1524)
				(type default)
			)
			(layer "F.SilkS")
		)
		(fp_line
			(start -0.7874 -0.4064)
			(end 0.7874 -0.4064)
			(stroke
				(width 0.1524)
				(type default)
			)
			(layer "F.SilkS")
		)
		(fp_line
			(start 0.7874 -0.4064)
			(end 0.7874 0.4064)
			(stroke
				(width 0.1524)
				(type default)
			)
			(layer "F.SilkS")
		)
		(fp_line
			(start -0.67945 0.3048)
			(end -0.67945 -0.305054)
			(stroke
				(width 0.1)
				(type default)
			)
			(layer "F.Fab")
		)
		(fp_line
			(start -0.12065 0.3048)
			(end -0.67945 0.3048)
			(stroke
				(width 0.1)
				(type default)
			)
			(layer "F.Fab")
		)
		(fp_line
			(start 0.120396 0.3048)
			(end 0.120396 0.2794)
			(stroke
				(width 0.1)
				(type default)
			)
			(layer "F.Fab")
		)
		(fp_line
			(start 0.67945 0.3048)
			(end 0.120396 0.3048)
			(stroke
				(width 0.1)
				(type default)
			)
			(layer "F.Fab")
		)
		(fp_line
			(start -0.12065 0.2794)
			(end -0.12065 0.3048)
			(stroke
				(width 0.1)
				(type default)
			)
			(layer "F.Fab")
		)
		(fp_line
			(start 0.120396 0.2794)
			(end -0.12065 0.2794)
			(stroke
				(width 0.1)
				(type default)
			)
			(layer "F.Fab")
		)
		(fp_line
			(start -0.12065 -0.2794)
			(end 0.12065 -0.2794)
			(stroke
				(width 0.1)
				(type default)
			)
			(layer "F.Fab")
		)
		(fp_line
			(start 0.12065 -0.2794)
			(end 0.12065 -0.3048)
			(stroke
				(width 0.1)
				(type default)
			)
			(layer "F.Fab")
		)
		(fp_line
			(start 0.12065 -0.3048)
			(end 0.67945 -0.3048)
			(stroke
				(width 0.1)
				(type default)
			)
			(layer "F.Fab")
		)
		(fp_line
			(start 0.67945 -0.3048)
			(end 0.67945 0.3048)
			(stroke
				(width 0.1)
				(type default)
			)
			(layer "F.Fab")
		)
		(fp_line
			(start -0.67945 -0.305054)
			(end -0.12065 -0.305054)
			(stroke
				(width 0.1)
				(type default)
			)
			(layer "F.Fab")
		)
		(fp_line
			(start -0.12065 -0.305054)
			(end -0.12065 -0.2794)
			(stroke
				(width 0.1)
				(type default)
			)
			(layer "F.Fab")
		)
		(pad "1" smd circle
			(at -0.40005 0 270)
			(size 0 0)
			(layers "F.Cu" "F.Mask" "F.Paste")
			(net "PVCCFA_EHV_FIVRA_CPU1")
		)
		(pad "2" smd circle
			(at 0.40005 0 270)
			(size 0 0)
			(layers "F.Cu" "F.Mask" "F.Paste")
			(net "GND")
		)
	)
	(footprint ""
		(layer "F.Cu")
		(at 30.71114 -438.161938 -90)
		(property "Reference" "R3004"
			(at 0 0 270)
			(layer "F.SilkS")
			(hide yes)
			(effects
				(font
					(size 1.27 1.27)
				)
			)
		)
		(property "Value" ""
			(at 0 0 270)
			(layer "F.Fab")
			(effects
				(font
					(size 1.27 1.27)
				)
			)
		)
		(duplicate_pad_numbers_are_jumpers no)
		(fp_line
			(start -0.7874 0.4064)
			(end -0.7874 -0.4064)
			(stroke
				(width 0.1524)
				(type default)
			)
			(layer "F.SilkS")
		)
		(fp_line
			(start 0.7874 0.4064)
			(end -0.7874 0.4064)
			(stroke
				(width 0.1524)
				(type default)
			)
			(layer "F.SilkS")
		)
		(fp_line
			(start -0.7874 -0.4064)
			(end 0.7874 -0.4064)
			(stroke
				(width 0.1524)
				(type default)
			)
			(layer "F.SilkS")
		)
		(fp_line
			(start 0.7874 -0.4064)
			(end 0.7874 0.4064)
			(stroke
				(width 0.1524)
				(type default)
			)
			(layer "F.SilkS")
		)
		(fp_line
			(start -0.67945 0.3048)
			(end -0.67945 -0.305054)
			(stroke
				(width 0.1)
				(type default)
			)
			(layer "F.Fab")
		)
		(fp_line
			(start -0.12065 0.3048)
			(end -0.67945 0.3048)
			(stroke
				(width 0.1)
				(type default)
			)
			(layer "F.Fab")
		)
		(fp_line
			(start 0.120396 0.3048)
			(end 0.120396 0.2794)
			(stroke
				(width 0.1)
				(type default)
			)
			(layer "F.Fab")
		)
		(fp_line
			(start 0.67945 0.3048)
			(end 0.120396 0.3048)
			(stroke
				(width 0.1)
				(type default)
			)
			(layer "F.Fab")
		)
		(fp_line
			(start -0.12065 0.2794)
			(end -0.12065 0.3048)
			(stroke
				(width 0.1)
				(type default)
			)
			(layer "F.Fab")
		)
		(fp_line
			(start 0.120396 0.2794)
			(end -0.12065 0.2794)
			(stroke
				(width 0.1)
				(type default)
			)
			(layer "F.Fab")
		)
		(fp_line
			(start -0.12065 -0.2794)
			(end 0.12065 -0.2794)
			(stroke
				(width 0.1)
				(type default)
			)
			(layer "F.Fab")
		)
		(fp_line
			(start 0.12065 -0.2794)
			(end 0.12065 -0.3048)
			(stroke
				(width 0.1)
				(type default)
			)
			(layer "F.Fab")
		)
		(fp_line
			(start 0.12065 -0.3048)
			(end 0.67945 -0.3048)
			(stroke
				(width 0.1)
				(type default)
			)
			(layer "F.Fab")
		)
		(fp_line
			(start 0.67945 -0.3048)
			(end 0.67945 0.3048)
			(stroke
				(width 0.1)
				(type default)
			)
			(layer "F.Fab")
		)
		(fp_line
			(start -0.67945 -0.305054)
			(end -0.12065 -0.305054)
			(stroke
				(width 0.1)
				(type default)
			)
			(layer "F.Fab")
		)
		(fp_line
			(start -0.12065 -0.305054)
			(end -0.12065 -0.2794)
			(stroke
				(width 0.1)
				(type default)
			)
			(layer "F.Fab")
		)
		(pad "1" smd circle
			(at -0.40005 0 270)
			(size 0 0)
			(layers "F.Cu" "F.Mask" "F.Paste")
			(net "SMB_2_BMC_GPU_SDA")
		)
		(pad "2" smd circle
			(at 0.40005 0 270)
			(size 0 0)
			(layers "F.Cu" "F.Mask" "F.Paste")
			(net "P3V3_AUX")
		)
	)
	(footprint ""
		(layer "F.Cu")
		(at 164.592 -102.199948)
		(property "Reference" "R1756"
			(at 0 0 0)
			(layer "F.SilkS")
			(hide yes)
			(effects
				(font
					(size 1.27 1.27)
				)
			)
		)
		(property "Value" ""
			(at 0 0 0)
			(layer "F.Fab")
			(effects
				(font
					(size 1.27 1.27)
				)
			)
		)
		(duplicate_pad_numbers_are_jumpers no)
		(fp_line
			(start -0.7874 -0.4064)
			(end 0.7874 -0.4064)
			(stroke
				(width 0.1524)
				(type default)
			)
			(layer "F.SilkS")
		)
		(fp_line
			(start -0.7874 0.4064)
			(end -0.7874 -0.4064)
			(stroke
				(width 0.1524)
				(type default)
			)
			(layer "F.SilkS")
		)
		(fp_line
			(start 0.7874 -0.4064)
			(end 0.7874 0.4064)
			(stroke
				(width 0.1524)
				(type default)
			)
			(layer "F.SilkS")
		)
		(fp_line
			(start 0.7874 0.4064)
			(end -0.7874 0.4064)
			(stroke
				(width 0.1524)
				(type default)
			)
			(layer "F.SilkS")
		)
		(fp_line
			(start -0.67945 -0.305054)
			(end -0.12065 -0.305054)
			(stroke
				(width 0.1)
				(type default)
			)
			(layer "F.Fab")
		)
		(fp_line
			(start -0.67945 0.3048)
			(end -0.67945 -0.305054)
			(stroke
				(width 0.1)
				(type default)
			)
			(layer "F.Fab")
		)
		(fp_line
			(start -0.12065 -0.305054)
			(end -0.12065 -0.2794)
			(stroke
				(width 0.1)
				(type default)
			)
			(layer "F.Fab")
		)
		(fp_line
			(start -0.12065 -0.2794)
			(end 0.12065 -0.2794)
			(stroke
				(width 0.1)
				(type default)
			)
			(layer "F.Fab")
		)
		(fp_line
			(start -0.12065 0.2794)
			(end -0.12065 0.3048)
			(stroke
				(width 0.1)
				(type default)
			)
			(layer "F.Fab")
		)
		(fp_line
			(start -0.12065 0.3048)
			(end -0.67945 0.3048)
			(stroke
				(width 0.1)
				(type default)
			)
			(layer "F.Fab")
		)
		(fp_line
			(start 0.120396 0.2794)
			(end -0.12065 0.2794)
			(stroke
				(width 0.1)
				(type default)
			)
			(layer "F.Fab")
		)
		(fp_line
			(start 0.120396 0.3048)
			(end 0.120396 0.2794)
			(stroke
				(width 0.1)
				(type default)
			)
			(layer "F.Fab")
		)
		(fp_line
			(start 0.12065 -0.3048)
			(end 0.67945 -0.3048)
			(stroke
				(width 0.1)
				(type default)
			)
			(layer "F.Fab")
		)
		(fp_line
			(start 0.12065 -0.2794)
			(end 0.12065 -0.3048)
			(stroke
				(width 0.1)
				(type default)
			)
			(layer "F.Fab")
		)
		(fp_line
			(start 0.67945 -0.3048)
			(end 0.67945 0.3048)
			(stroke
				(width 0.1)
				(type default)
			)
			(layer "F.Fab")
		)
		(fp_line
			(start 0.67945 0.3048)
			(end 0.120396 0.3048)
			(stroke
				(width 0.1)
				(type default)
			)
			(layer "F.Fab")
		)
		(pad "1" smd circle
			(at -0.40005 0)
			(size 0 0)
			(layers "F.Cu" "F.Mask" "F.Paste")
			(net "SGPIO_CLK_1")
		)
		(pad "2" smd circle
			(at 0.40005 0)
			(size 0 0)
			(layers "F.Cu" "F.Mask" "F.Paste")
			(net "SGPIO_BMC_CLK")
		)
	)
	(footprint ""
		(layer "F.Cu")
		(at 365.03864 -315.66739 90)
		(property "Reference" "PC316"
			(at 0 0 90)
			(layer "F.SilkS")
			(hide yes)
			(effects
				(font
					(size 1.27 1.27)
				)
			)
		)
		(property "Value" ""
			(at 0 0 90)
			(layer "F.Fab")
			(effects
				(font
					(size 1.27 1.27)
				)
			)
		)
		(duplicate_pad_numbers_are_jumpers no)
		(fp_line
			(start 2.750058 0.999998)
			(end -2.750058 0.999998)
			(stroke
				(width 0.1524)
				(type default)
			)
			(layer "F.SilkS")
		)
		(fp_circle
			(center 0 0.999998)
			(end 0 3.750056)
			(stroke
				(width 0.1524)
				(type default)
			)
			(fill no)
			(layer "F.SilkS")
		)
		(fp_poly
			(pts
				(arc
					(start 2.750058 0.999998)
					(mid 0 3.750056)
					(end -2.750058 0.999998)
				)
			)
			(stroke
				(width 0)
				(type default)
			)
			(fill yes)
			(layer "F.SilkS")
		)
		(fp_circle
			(center 0 0.999998)
			(end 0 3.750056)
			(stroke
				(width 0.1)
				(type default)
			)
			(fill no)
			(layer "F.Fab")
		)
		(pad "1" thru_hole rect
			(at 0 0 90)
			(size 1.5748 1.5748)
			(drill 1.0668)
			(layers "*.Cu" "*.Mask")
			(remove_unused_layers no)
			(net "PVCCIN_CPU0")
			(clearance 0)
			(padstack
				(mode front_inner_back)
				(layer "Inner"
					(shape circle)
					(size 1.5748 1.5748)
					(clearance 0)
				)
				(layer "B.Cu"
					(shape rect)
					(size 1.5748 1.5748)
					(clearance 0)
				)
			)
		)
		(pad "2" thru_hole circle
			(at 0 1.999996 90)
			(size 1.5748 1.5748)
			(drill 1.0668)
			(layers "*.Cu" "*.Mask")
			(remove_unused_layers no)
			(net "GND")
			(clearance 0)
		)
	)
	(footprint ""
		(layer "F.Cu")
		(at 213.66988 -258.091686)
		(property "Reference" "J31"
			(at -3.683 -81.702148 0)
			(unlocked yes)
			(layer "F.SilkS")
			(effects
				(font
					(size 0.7874 0.5842)
					(thickness 0.1524)
				)
				(justify left)
			)
		)
		(property "Value" ""
			(at 0 0 0)
			(layer "F.Fab")
			(effects
				(font
					(size 1.27 1.27)
				)
			)
		)
		(duplicate_pad_numbers_are_jumpers no)
		(fp_line
			(start -3.24993 -81.000092)
			(end -3.24993 72.884538)
			(stroke
				(width 0.1524)
				(type default)
			)
			(layer "F.SilkS")
		)
		(fp_line
			(start -3.24993 74.245978)
			(end -3.24993 81.000092)
			(stroke
				(width 0.1524)
				(type default)
			)
			(layer "F.SilkS")
		)
		(fp_line
			(start -3.24993 81.000092)
			(end 3.24993 81.000092)
			(stroke
				(width 0.1524)
				(type default)
			)
			(layer "F.SilkS")
		)
		(fp_line
			(start -1.13792 72.00011)
			(end -3.24993 72.00011)
			(stroke
				(width 0.1524)
				(type default)
			)
			(layer "F.SilkS")
		)
		(fp_line
			(start 0.32258 -81.000092)
			(end -3.24993 -81.000092)
			(stroke
				(width 0.1524)
				(type default)
			)
			(layer "F.SilkS")
		)
		(fp_line
			(start 3.24993 -72.00011)
			(end -3.24993 -72.00011)
			(stroke
				(width 0.1524)
				(type default)
			)
			(layer "F.SilkS")
		)
		(fp_line
			(start 3.24993 70.029578)
			(end 3.24993 -75.497182)
			(stroke
				(width 0.1524)
				(type default)
			)
			(layer "F.SilkS")
		)
		(fp_line
			(start 3.24993 72.00011)
			(end 1.16332 72.00011)
			(stroke
				(width 0.1524)
				(type default)
			)
			(layer "F.SilkS")
		)
		(fp_line
			(start 3.24993 81.000092)
			(end 3.24993 71.197978)
			(stroke
				(width 0.1524)
				(type default)
			)
			(layer "F.SilkS")
		)
		(fp_poly
			(pts
				(xy -4.217162 -63.81369) (xy -3.320288 -63.365126) (xy -4.217162 -62.916562)
			)
			(stroke
				(width 0)
				(type default)
			)
			(fill yes)
			(layer "F.SilkS")
		)
		(fp_line
			(start -3.24993 -81.000092)
			(end -3.24993 81.000092)
			(stroke
				(width 0.1)
				(type default)
			)
			(layer "F.Fab")
		)
		(fp_line
			(start -3.24993 81.000092)
			(end 3.24993 81.000092)
			(stroke
				(width 0.1)
				(type default)
			)
			(layer "F.Fab")
		)
		(fp_line
			(start 3.24993 -81.000092)
			(end -3.24993 -81.000092)
			(stroke
				(width 0.1)
				(type default)
			)
			(layer "F.Fab")
		)
		(fp_line
			(start 3.24993 -72.00011)
			(end -3.24993 -72.00011)
			(stroke
				(width 0.1)
				(type default)
			)
			(layer "F.Fab")
		)
		(fp_line
			(start 3.24993 -71.000112)
			(end -3.24993 -71.000112)
			(stroke
				(width 0.1)
				(type default)
			)
			(layer "F.Fab")
		)
		(fp_line
			(start 3.24993 71.000112)
			(end -3.24993 71.000112)
			(stroke
				(width 0.1)
				(type default)
			)
			(layer "F.Fab")
		)
		(fp_line
			(start 3.24993 72.00011)
			(end -3.24993 72.00011)
			(stroke
				(width 0.1)
				(type default)
			)
			(layer "F.Fab")
		)
		(fp_line
			(start 3.24993 81.000092)
			(end 3.24993 -81.000092)
			(stroke
				(width 0.1)
				(type default)
			)
			(layer "F.Fab")
		)
		(fp_poly
			(pts
				(xy -4.445 -63.832994) (xy -4.445 -62.816994) (xy -3.429 -63.324994)
			)
			(stroke
				(width 0)
				(type default)
			)
			(fill yes)
			(layer "F.Fab")
		)
		(pad "1" smd rect
			(at -2.050034 -63.324994 270)
			(size 0.519938 1.4986)
			(layers "F.Cu" "F.Mask" "F.Paste")
			(net "P12V_S3_AUX_CPU1_NVDIMM")
		)
		(pad "2" smd rect
			(at -2.050034 -62.47511 270)
			(size 0.519938 1.4986)
			(layers "F.Cu" "F.Mask" "F.Paste")
			(net "TP_CHH_CPU1_DIMM1_FRU_0")
		)
		(pad "3" smd rect
			(at -2.050034 -61.624972 270)
			(size 0.519938 1.4986)
			(layers "F.Cu" "F.Mask" "F.Paste")
			(net "P3V3_AUX")
		)
		(pad "4" smd rect
			(at -2.050034 -60.775088 270)
			(size 0.519938 1.4986)
			(layers "F.Cu" "F.Mask" "F.Paste")
			(net "I3C_SPD_DDREFGH_CPU1_LVC1_SCL_6")
		)
		(pad "5" smd rect
			(at -2.050034 -59.92495 270)
			(size 0.519938 1.4986)
			(layers "F.Cu" "F.Mask" "F.Paste")
			(net "I3C_SPD_DDREFGH_CPU1_LVC1_SDA")
		)
		(pad "6" smd rect
			(at -2.050034 -59.075066 270)
			(size 0.519938 1.4986)
			(layers "F.Cu" "F.Mask" "F.Paste")
			(net "GND")
		)
		(pad "7" smd rect
			(at -2.050034 -58.224928 270)
			(size 0.519938 1.4986)
			(layers "F.Cu" "F.Mask" "F.Paste")
			(net "M_H_CPU1_SA_DQ<0>")
		)
		(pad "8" smd rect
			(at -2.050034 -57.375044 270)
			(size 0.519938 1.4986)
			(layers "F.Cu" "F.Mask" "F.Paste")
			(net "GND")
		)
		(pad "9" smd rect
			(at -2.050034 -56.524906 270)
			(size 0.519938 1.4986)
			(layers "F.Cu" "F.Mask" "F.Paste")
			(net "M_H_CPU1_SA_DQ<1>")
		)
		(pad "10" smd rect
			(at -2.050034 -55.675022 270)
			(size 0.519938 1.4986)
			(layers "F.Cu" "F.Mask" "F.Paste")
			(net "GND")
		)
		(pad "11" smd rect
			(at -2.050034 -54.824884 270)
			(size 0.519938 1.4986)
			(layers "F.Cu" "F.Mask" "F.Paste")
			(net "M_H_CPU1_SA_DQS_DP<0>")
		)
		(pad "12" smd rect
			(at -2.050034 -53.975 270)
			(size 0.519938 1.4986)
			(layers "F.Cu" "F.Mask" "F.Paste")
			(net "M_H_CPU1_SA_DQS_DN<0>")
		)
		(pad "13" smd rect
			(at -2.050034 -53.125116 270)
			(size 0.519938 1.4986)
			(layers "F.Cu" "F.Mask" "F.Paste")
			(net "GND")
		)
		(pad "14" smd rect
			(at -2.050034 -52.274978 270)
			(size 0.519938 1.4986)
			(layers "F.Cu" "F.Mask" "F.Paste")
			(net "M_H_CPU1_SA_DQ<4>")
		)
		(pad "15" smd rect
			(at -2.050034 -51.425094 270)
			(size 0.519938 1.4986)
			(layers "F.Cu" "F.Mask" "F.Paste")
			(net "GND")
		)
		(pad "16" smd rect
			(at -2.050034 -50.574956 270)
			(size 0.519938 1.4986)
			(layers "F.Cu" "F.Mask" "F.Paste")
			(net "M_H_CPU1_SA_DQ<5>")
		)
		(pad "17" smd rect
			(at -2.050034 -49.725072 270)
			(size 0.519938 1.4986)
			(layers "F.Cu" "F.Mask" "F.Paste")
			(net "GND")
		)
		(pad "18" smd rect
			(at -2.050034 -48.874934 270)
			(size 0.519938 1.4986)
			(layers "F.Cu" "F.Mask" "F.Paste")
			(net "M_H_CPU1_SA_DQ<8>")
		)
		(pad "19" smd rect
			(at -2.050034 -48.02505 270)
			(size 0.519938 1.4986)
			(layers "F.Cu" "F.Mask" "F.Paste")
			(net "GND")
		)
		(pad "20" smd rect
			(at -2.050034 -47.174912 270)
			(size 0.519938 1.4986)
			(layers "F.Cu" "F.Mask" "F.Paste")
			(net "M_H_CPU1_SA_DQ<9>")
		)
		(pad "21" smd rect
			(at -2.050034 -46.325028 270)
			(size 0.519938 1.4986)
			(layers "F.Cu" "F.Mask" "F.Paste")
			(net "GND")
		)
		(pad "22" smd rect
			(at -2.050034 -45.47489 270)
			(size 0.519938 1.4986)
			(layers "F.Cu" "F.Mask" "F.Paste")
			(net "M_H_CPU1_SA_DQS_DP<1>")
		)
		(pad "23" smd rect
			(at -2.050034 -44.625006 270)
			(size 0.519938 1.4986)
			(layers "F.Cu" "F.Mask" "F.Paste")
			(net "M_H_CPU1_SA_DQS_DN<1>")
		)
		(pad "24" smd rect
			(at -2.050034 -43.775122 270)
			(size 0.519938 1.4986)
			(layers "F.Cu" "F.Mask" "F.Paste")
			(net "GND")
		)
		(pad "25" smd rect
			(at -2.050034 -42.924984 270)
			(size 0.519938 1.4986)
			(layers "F.Cu" "F.Mask" "F.Paste")
			(net "M_H_CPU1_SA_DQ<12>")
		)
		(pad "26" smd rect
			(at -2.050034 -42.0751 270)
			(size 0.519938 1.4986)
			(layers "F.Cu" "F.Mask" "F.Paste")
			(net "GND")
		)
		(pad "27" smd rect
			(at -2.050034 -41.224962 270)
			(size 0.519938 1.4986)
			(layers "F.Cu" "F.Mask" "F.Paste")
			(net "M_H_CPU1_SA_DQ<13>")
		)
		(pad "28" smd rect
			(at -2.050034 -40.375078 270)
			(size 0.519938 1.4986)
			(layers "F.Cu" "F.Mask" "F.Paste")
			(net "GND")
		)
		(pad "29" smd rect
			(at -2.050034 -39.52494 270)
			(size 0.519938 1.4986)
			(layers "F.Cu" "F.Mask" "F.Paste")
			(net "M_H_CPU1_SA_DQ<16>")
		)
		(pad "30" smd rect
			(at -2.050034 -38.675056 270)
			(size 0.519938 1.4986)
			(layers "F.Cu" "F.Mask" "F.Paste")
			(net "GND")
		)
		(pad "31" smd rect
			(at -2.050034 -37.824918 270)
			(size 0.519938 1.4986)
			(layers "F.Cu" "F.Mask" "F.Paste")
			(net "M_H_CPU1_SA_DQ<17>")
		)
		(pad "32" smd rect
			(at -2.050034 -36.975034 270)
			(size 0.519938 1.4986)
			(layers "F.Cu" "F.Mask" "F.Paste")
			(net "GND")
		)
		(pad "33" smd rect
			(at -2.050034 -36.124896 270)
			(size 0.519938 1.4986)
			(layers "F.Cu" "F.Mask" "F.Paste")
			(net "M_H_CPU1_SA_DQS_DP<2>")
		)
		(pad "34" smd rect
			(at -2.050034 -35.275012 270)
			(size 0.519938 1.4986)
			(layers "F.Cu" "F.Mask" "F.Paste")
			(net "M_H_CPU1_SA_DQS_DN<2>")
		)
		(pad "35" smd rect
			(at -2.050034 -34.425128 270)
			(size 0.519938 1.4986)
			(layers "F.Cu" "F.Mask" "F.Paste")
			(net "GND")
		)
		(pad "36" smd rect
			(at -2.050034 -33.57499 270)
			(size 0.519938 1.4986)
			(layers "F.Cu" "F.Mask" "F.Paste")
			(net "M_H_CPU1_SA_DQ<20>")
		)
		(pad "37" smd rect
			(at -2.050034 -32.725106 270)
			(size 0.519938 1.4986)
			(layers "F.Cu" "F.Mask" "F.Paste")
			(net "GND")
		)
		(pad "38" smd rect
			(at -2.050034 -31.874968 270)
			(size 0.519938 1.4986)
			(layers "F.Cu" "F.Mask" "F.Paste")
			(net "M_H_CPU1_SA_DQ<21>")
		)
		(pad "39" smd rect
			(at -2.050034 -31.025084 270)
			(size 0.519938 1.4986)
			(layers "F.Cu" "F.Mask" "F.Paste")
			(net "GND")
		)
		(pad "40" smd rect
			(at -2.050034 -30.174946 270)
			(size 0.519938 1.4986)
			(layers "F.Cu" "F.Mask" "F.Paste")
			(net "M_H_CPU1_SA_DQ<24>")
		)
		(pad "41" smd rect
			(at -2.050034 -29.325062 270)
			(size 0.519938 1.4986)
			(layers "F.Cu" "F.Mask" "F.Paste")
			(net "GND")
		)
		(pad "42" smd rect
			(at -2.050034 -28.474924 270)
			(size 0.519938 1.4986)
			(layers "F.Cu" "F.Mask" "F.Paste")
			(net "M_H_CPU1_SA_DQ<25>")
		)
		(pad "43" smd rect
			(at -2.050034 -27.62504 270)
			(size 0.519938 1.4986)
			(layers "F.Cu" "F.Mask" "F.Paste")
			(net "GND")
		)
		(pad "44" smd rect
			(at -2.050034 -26.774902 270)
			(size 0.519938 1.4986)
			(layers "F.Cu" "F.Mask" "F.Paste")
			(net "M_H_CPU1_SA_DQS_DP<3>")
		)
		(pad "45" smd rect
			(at -2.050034 -25.925018 270)
			(size 0.519938 1.4986)
			(layers "F.Cu" "F.Mask" "F.Paste")
			(net "M_H_CPU1_SA_DQS_DN<3>")
		)
		(pad "46" smd rect
			(at -2.050034 -25.07488 270)
			(size 0.519938 1.4986)
			(layers "F.Cu" "F.Mask" "F.Paste")
			(net "GND")
		)
		(pad "47" smd rect
			(at -2.050034 -24.224996 270)
			(size 0.519938 1.4986)
			(layers "F.Cu" "F.Mask" "F.Paste")
			(net "M_H_CPU1_SA_DQ<28>")
		)
		(pad "48" smd rect
			(at -2.050034 -23.375112 270)
			(size 0.519938 1.4986)
			(layers "F.Cu" "F.Mask" "F.Paste")
			(net "GND")
		)
		(pad "49" smd rect
			(at -2.050034 -22.524974 270)
			(size 0.519938 1.4986)
			(layers "F.Cu" "F.Mask" "F.Paste")
			(net "M_H_CPU1_SA_DQ<29>")
		)
		(pad "50" smd rect
			(at -2.050034 -21.67509 270)
			(size 0.519938 1.4986)
			(layers "F.Cu" "F.Mask" "F.Paste")
			(net "GND")
		)
		(pad "51" smd rect
			(at -2.050034 -20.824952 270)
			(size 0.519938 1.4986)
			(layers "F.Cu" "F.Mask" "F.Paste")
			(net "M_H_CPU1_SA_CB<0>")
		)
		(pad "52" smd rect
			(at -2.050034 -19.975068 270)
			(size 0.519938 1.4986)
			(layers "F.Cu" "F.Mask" "F.Paste")
			(net "GND")
		)
		(pad "53" smd rect
			(at -2.050034 -19.12493 270)
			(size 0.519938 1.4986)
			(layers "F.Cu" "F.Mask" "F.Paste")
			(net "M_H_CPU1_SA_CB<1>")
		)
		(pad "54" smd rect
			(at -2.050034 -18.275046 270)
			(size 0.519938 1.4986)
			(layers "F.Cu" "F.Mask" "F.Paste")
			(net "GND")
		)
		(pad "55" smd rect
			(at -2.050034 -17.424908 270)
			(size 0.519938 1.4986)
			(layers "F.Cu" "F.Mask" "F.Paste")
			(net "M_H_CPU1_SA_DQS_DP<4>")
		)
		(pad "56" smd rect
			(at -2.050034 -16.575024 270)
			(size 0.519938 1.4986)
			(layers "F.Cu" "F.Mask" "F.Paste")
			(net "M_H_CPU1_SA_DQS_DN<4>")
		)
		(pad "57" smd rect
			(at -2.050034 -15.724886 270)
			(size 0.519938 1.4986)
			(layers "F.Cu" "F.Mask" "F.Paste")
			(net "GND")
		)
		(pad "58" smd rect
			(at -2.050034 -14.875002 270)
			(size 0.519938 1.4986)
			(layers "F.Cu" "F.Mask" "F.Paste")
			(net "M_H_CPU1_SA_CB<4>")
		)
		(pad "59" smd rect
			(at -2.050034 -14.025118 270)
			(size 0.519938 1.4986)
			(layers "F.Cu" "F.Mask" "F.Paste")
			(net "GND")
		)
		(pad "60" smd rect
			(at -2.050034 -13.17498 270)
			(size 0.519938 1.4986)
			(layers "F.Cu" "F.Mask" "F.Paste")
			(net "M_H_CPU1_SA_CB<5>")
		)
		(pad "61" smd rect
			(at -2.050034 -12.325096 270)
			(size 0.519938 1.4986)
			(layers "F.Cu" "F.Mask" "F.Paste")
			(net "GND")
		)
		(pad "62" smd rect
			(at -2.050034 -11.474958 270)
			(size 0.519938 1.4986)
			(layers "F.Cu" "F.Mask" "F.Paste")
			(net "M_H_CPU1_ALERT_N")
		)
		(pad "63" smd rect
			(at -2.050034 -10.625074 270)
			(size 0.519938 1.4986)
			(layers "F.Cu" "F.Mask" "F.Paste")
			(net "GND")
		)
		(pad "64" smd rect
			(at -2.050034 -9.774936 270)
			(size 0.519938 1.4986)
			(layers "F.Cu" "F.Mask" "F.Paste")
			(net "M_H_CPU1_SA_CS_N<0>")
		)
		(pad "65" smd rect
			(at -2.050034 -8.925052 270)
			(size 0.519938 1.4986)
			(layers "F.Cu" "F.Mask" "F.Paste")
			(net "GND")
		)
		(pad "66" smd rect
			(at -2.050034 -8.074914 270)
			(size 0.519938 1.4986)
			(layers "F.Cu" "F.Mask" "F.Paste")
			(net "M_H_CPU1_SA_CA<0>")
		)
		(pad "67" smd rect
			(at -2.050034 -7.22503 270)
			(size 0.519938 1.4986)
			(layers "F.Cu" "F.Mask" "F.Paste")
			(net "GND")
		)
		(pad "68" smd rect
			(at -2.050034 -6.374892 270)
			(size 0.519938 1.4986)
			(layers "F.Cu" "F.Mask" "F.Paste")
			(net "M_H_CPU1_SA_CA<2>")
		)
		(pad "69" smd rect
			(at -2.050034 -5.525008 270)
			(size 0.519938 1.4986)
			(layers "F.Cu" "F.Mask" "F.Paste")
			(net "GND")
		)
		(pad "70" smd rect
			(at -2.050034 -4.675124 270)
			(size 0.519938 1.4986)
			(layers "F.Cu" "F.Mask" "F.Paste")
			(net "M_H_CPU1_SA_CA<4>")
		)
		(pad "71" smd rect
			(at -2.050034 -3.824986 270)
			(size 0.519938 1.4986)
			(layers "F.Cu" "F.Mask" "F.Paste")
			(net "GND")
		)
		(pad "72" smd rect
			(at -2.050034 -2.975102 270)
			(size 0.519938 1.4986)
			(layers "F.Cu" "F.Mask" "F.Paste")
			(net "M_H_CPU1_SA_CA<6>")
		)
		(pad "73" smd rect
			(at -2.050034 -2.124964 270)
			(size 0.519938 1.4986)
			(layers "F.Cu" "F.Mask" "F.Paste")
			(net "GND")
		)
		(pad "74" smd rect
			(at -2.050034 -1.27508 270)
			(size 0.519938 1.4986)
			(layers "F.Cu" "F.Mask" "F.Paste")
			(net "M_H_CPU1_SA_PAR")
		)
		(pad "75" smd rect
			(at -2.050034 -0.424942 270)
			(size 0.519938 1.4986)
			(layers "F.Cu" "F.Mask" "F.Paste")
			(net "GND")
		)
		(pad "76" smd rect
			(at -2.050034 5.525008 270)
			(size 0.519938 1.4986)
			(layers "F.Cu" "F.Mask" "F.Paste")
			(net "M_H_CPU1_SB_CA<0>")
		)
		(pad "77" smd rect
			(at -2.050034 6.374892 270)
			(size 0.519938 1.4986)
			(layers "F.Cu" "F.Mask" "F.Paste")
			(net "GND")
		)
		(pad "78" smd rect
			(at -2.050034 7.22503 270)
			(size 0.519938 1.4986)
			(layers "F.Cu" "F.Mask" "F.Paste")
			(net "M_H_CPU1_SB_CA<2>")
		)
		(pad "79" smd rect
			(at -2.050034 8.074914 270)
			(size 0.519938 1.4986)
			(layers "F.Cu" "F.Mask" "F.Paste")
			(net "GND")
		)
		(pad "80" smd rect
			(at -2.050034 8.925052 270)
			(size 0.519938 1.4986)
			(layers "F.Cu" "F.Mask" "F.Paste")
			(net "M_H_CPU1_SB_CA<4>")
		)
		(pad "81" smd rect
			(at -2.050034 9.774936 270)
			(size 0.519938 1.4986)
			(layers "F.Cu" "F.Mask" "F.Paste")
			(net "GND")
		)
		(pad "82" smd rect
			(at -2.050034 10.625074 270)
			(size 0.519938 1.4986)
			(layers "F.Cu" "F.Mask" "F.Paste")
			(net "M_H_CPU1_SB_CA<6>")
		)
		(pad "83" smd rect
			(at -2.050034 11.474958 270)
			(size 0.519938 1.4986)
			(layers "F.Cu" "F.Mask" "F.Paste")
			(net "GND")
		)
		(pad "84" smd rect
			(at -2.050034 12.325096 270)
			(size 0.519938 1.4986)
			(layers "F.Cu" "F.Mask" "F.Paste")
			(net "M_H_CPU1_SB_CS_N<0>")
		)
		(pad "85" smd rect
			(at -2.050034 13.17498 270)
			(size 0.519938 1.4986)
			(layers "F.Cu" "F.Mask" "F.Paste")
			(net "GND")
		)
		(pad "86" smd rect
			(at -2.050034 14.025118 270)
			(size 0.519938 1.4986)
			(layers "F.Cu" "F.Mask" "F.Paste")
			(net "M_H_CPU1_SA_RSP<0>")
		)
		(pad "87" smd rect
			(at -2.050034 14.875002 270)
			(size 0.519938 1.4986)
			(layers "F.Cu" "F.Mask" "F.Paste")
			(net "M_H_CPU1_SB_RSP<0>")
		)
		(pad "88" smd rect
			(at -2.050034 15.724886 270)
			(size 0.519938 1.4986)
			(layers "F.Cu" "F.Mask" "F.Paste")
			(net "GND")
		)
		(pad "89" smd rect
			(at -2.050034 16.575024 270)
			(size 0.519938 1.4986)
			(layers "F.Cu" "F.Mask" "F.Paste")
			(net "M_H_CPU1_SB_CB<4>")
		)
		(pad "90" smd rect
			(at -2.050034 17.424908 270)
			(size 0.519938 1.4986)
			(layers "F.Cu" "F.Mask" "F.Paste")
			(net "GND")
		)
		(pad "91" smd rect
			(at -2.050034 18.275046 270)
			(size 0.519938 1.4986)
			(layers "F.Cu" "F.Mask" "F.Paste")
			(net "M_H_CPU1_SB_CB<5>")
		)
		(pad "92" smd rect
			(at -2.050034 19.12493 270)
			(size 0.519938 1.4986)
			(layers "F.Cu" "F.Mask" "F.Paste")
			(net "GND")
		)
		(pad "93" smd rect
			(at -2.050034 19.975068 270)
			(size 0.519938 1.4986)
			(layers "F.Cu" "F.Mask" "F.Paste")
			(net "M_H_CPU1_SB_DQS_DP<9>")
		)
		(pad "94" smd rect
			(at -2.050034 20.824952 270)
			(size 0.519938 1.4986)
			(layers "F.Cu" "F.Mask" "F.Paste")
			(net "M_H_CPU1_SB_DQS_DN<9>")
		)
		(pad "95" smd rect
			(at -2.050034 21.67509 270)
			(size 0.519938 1.4986)
			(layers "F.Cu" "F.Mask" "F.Paste")
			(net "GND")
		)
		(pad "96" smd rect
			(at -2.050034 22.524974 270)
			(size 0.519938 1.4986)
			(layers "F.Cu" "F.Mask" "F.Paste")
			(net "M_H_CPU1_SB_CB<0>")
		)
		(pad "97" smd rect
			(at -2.050034 23.375112 270)
			(size 0.519938 1.4986)
			(layers "F.Cu" "F.Mask" "F.Paste")
			(net "GND")
		)
		(pad "98" smd rect
			(at -2.050034 24.224996 270)
			(size 0.519938 1.4986)
			(layers "F.Cu" "F.Mask" "F.Paste")
			(net "M_H_CPU1_SB_CB<1>")
		)
		(pad "99" smd rect
			(at -2.050034 25.07488 270)
			(size 0.519938 1.4986)
			(layers "F.Cu" "F.Mask" "F.Paste")
			(net "GND")
		)
		(pad "100" smd rect
			(at -2.050034 25.925018 270)
			(size 0.519938 1.4986)
			(layers "F.Cu" "F.Mask" "F.Paste")
			(net "M_H_CPU1_SB_DQ<0>")
		)
		(pad "101" smd rect
			(at -2.050034 26.774902 270)
			(size 0.519938 1.4986)
			(layers "F.Cu" "F.Mask" "F.Paste")
			(net "GND")
		)
		(pad "102" smd rect
			(at -2.050034 27.62504 270)
			(size 0.519938 1.4986)
			(layers "F.Cu" "F.Mask" "F.Paste")
			(net "M_H_CPU1_SB_DQ<1>")
		)
		(pad "103" smd rect
			(at -2.050034 28.474924 270)
			(size 0.519938 1.4986)
			(layers "F.Cu" "F.Mask" "F.Paste")
			(net "GND")
		)
		(pad "104" smd rect
			(at -2.050034 29.325062 270)
			(size 0.519938 1.4986)
			(layers "F.Cu" "F.Mask" "F.Paste")
			(net "M_H_CPU1_SB_DQS_DP<0>")
		)
		(pad "105" smd rect
			(at -2.050034 30.174946 270)
			(size 0.519938 1.4986)
			(layers "F.Cu" "F.Mask" "F.Paste")
			(net "M_H_CPU1_SB_DQS_DN<0>")
		)
		(pad "106" smd rect
			(at -2.050034 31.025084 270)
			(size 0.519938 1.4986)
			(layers "F.Cu" "F.Mask" "F.Paste")
			(net "GND")
		)
		(pad "107" smd rect
			(at -2.050034 31.874968 270)
			(size 0.519938 1.4986)
			(layers "F.Cu" "F.Mask" "F.Paste")
			(net "M_H_CPU1_SB_DQ<4>")
		)
		(pad "108" smd rect
			(at -2.050034 32.725106 270)
			(size 0.519938 1.4986)
			(layers "F.Cu" "F.Mask" "F.Paste")
			(net "GND")
		)
		(pad "109" smd rect
			(at -2.050034 33.57499 270)
			(size 0.519938 1.4986)
			(layers "F.Cu" "F.Mask" "F.Paste")
			(net "M_H_CPU1_SB_DQ<5>")
		)
		(pad "110" smd rect
			(at -2.050034 34.425128 270)
			(size 0.519938 1.4986)
			(layers "F.Cu" "F.Mask" "F.Paste")
			(net "GND")
		)
		(pad "111" smd rect
			(at -2.050034 35.275012 270)
			(size 0.519938 1.4986)
			(layers "F.Cu" "F.Mask" "F.Paste")
			(net "M_H_CPU1_SB_DQ<8>")
		)
		(pad "112" smd rect
			(at -2.050034 36.124896 270)
			(size 0.519938 1.4986)
			(layers "F.Cu" "F.Mask" "F.Paste")
			(net "GND")
		)
		(pad "113" smd rect
			(at -2.050034 36.975034 270)
			(size 0.519938 1.4986)
			(layers "F.Cu" "F.Mask" "F.Paste")
			(net "M_H_CPU1_SB_DQ<9>")
		)
		(pad "114" smd rect
			(at -2.050034 37.824918 270)
			(size 0.519938 1.4986)
			(layers "F.Cu" "F.Mask" "F.Paste")
			(net "GND")
		)
		(pad "115" smd rect
			(at -2.050034 38.675056 270)
			(size 0.519938 1.4986)
			(layers "F.Cu" "F.Mask" "F.Paste")
			(net "M_H_CPU1_SB_DQS_DP<1>")
		)
		(pad "116" smd rect
			(at -2.050034 39.52494 270)
			(size 0.519938 1.4986)
			(layers "F.Cu" "F.Mask" "F.Paste")
			(net "M_H_CPU1_SB_DQS_DN<1>")
		)
		(pad "117" smd rect
			(at -2.050034 40.375078 270)
			(size 0.519938 1.4986)
			(layers "F.Cu" "F.Mask" "F.Paste")
			(net "GND")
		)
		(pad "118" smd rect
			(at -2.050034 41.224962 270)
			(size 0.519938 1.4986)
			(layers "F.Cu" "F.Mask" "F.Paste")
			(net "M_H_CPU1_SB_DQ<12>")
		)
		(pad "119" smd rect
			(at -2.050034 42.0751 270)
			(size 0.519938 1.4986)
			(layers "F.Cu" "F.Mask" "F.Paste")
			(net "GND")
		)
		(pad "120" smd rect
			(at -2.050034 42.924984 270)
			(size 0.519938 1.4986)
			(layers "F.Cu" "F.Mask" "F.Paste")
			(net "M_H_CPU1_SB_DQ<13>")
		)
		(pad "121" smd rect
			(at -2.050034 43.775122 270)
			(size 0.519938 1.4986)
			(layers "F.Cu" "F.Mask" "F.Paste")
			(net "GND")
		)
		(pad "122" smd rect
			(at -2.050034 44.625006 270)
			(size 0.519938 1.4986)
			(layers "F.Cu" "F.Mask" "F.Paste")
			(net "M_H_CPU1_SB_DQ<16>")
		)
		(pad "123" smd rect
			(at -2.050034 45.47489 270)
			(size 0.519938 1.4986)
			(layers "F.Cu" "F.Mask" "F.Paste")
			(net "GND")
		)
		(pad "124" smd rect
			(at -2.050034 46.325028 270)
			(size 0.519938 1.4986)
			(layers "F.Cu" "F.Mask" "F.Paste")
			(net "M_H_CPU1_SB_DQ<17>")
		)
		(pad "125" smd rect
			(at -2.050034 47.174912 270)
			(size 0.519938 1.4986)
			(layers "F.Cu" "F.Mask" "F.Paste")
			(net "GND")
		)
		(pad "126" smd rect
			(at -2.050034 48.02505 270)
			(size 0.519938 1.4986)
			(layers "F.Cu" "F.Mask" "F.Paste")
			(net "M_H_CPU1_SB_DQS_DP<2>")
		)
		(pad "127" smd rect
			(at -2.050034 48.874934 270)
			(size 0.519938 1.4986)
			(layers "F.Cu" "F.Mask" "F.Paste")
			(net "M_H_CPU1_SB_DQS_DN<2>")
		)
		(pad "128" smd rect
			(at -2.050034 49.725072 270)
			(size 0.519938 1.4986)
			(layers "F.Cu" "F.Mask" "F.Paste")
			(net "GND")
		)
		(pad "129" smd rect
			(at -2.050034 50.574956 270)
			(size 0.519938 1.4986)
			(layers "F.Cu" "F.Mask" "F.Paste")
			(net "M_H_CPU1_SB_DQ<20>")
		)
		(pad "130" smd rect
			(at -2.050034 51.425094 270)
			(size 0.519938 1.4986)
			(layers "F.Cu" "F.Mask" "F.Paste")
			(net "GND")
		)
		(pad "131" smd rect
			(at -2.050034 52.274978 270)
			(size 0.519938 1.4986)
			(layers "F.Cu" "F.Mask" "F.Paste")
			(net "M_H_CPU1_SB_DQ<21>")
		)
		(pad "132" smd rect
			(at -2.050034 53.125116 270)
			(size 0.519938 1.4986)
			(layers "F.Cu" "F.Mask" "F.Paste")
			(net "GND")
		)
		(pad "133" smd rect
			(at -2.050034 53.975 270)
			(size 0.519938 1.4986)
			(layers "F.Cu" "F.Mask" "F.Paste")
			(net "M_H_CPU1_SB_DQ<24>")
		)
		(pad "134" smd rect
			(at -2.050034 54.824884 270)
			(size 0.519938 1.4986)
			(layers "F.Cu" "F.Mask" "F.Paste")
			(net "GND")
		)
		(pad "135" smd rect
			(at -2.050034 55.675022 270)
			(size 0.519938 1.4986)
			(layers "F.Cu" "F.Mask" "F.Paste")
			(net "M_H_CPU1_SB_DQ<25>")
		)
		(pad "136" smd rect
			(at -2.050034 56.524906 270)
			(size 0.519938 1.4986)
			(layers "F.Cu" "F.Mask" "F.Paste")
			(net "GND")
		)
		(pad "137" smd rect
			(at -2.050034 57.375044 270)
			(size 0.519938 1.4986)
			(layers "F.Cu" "F.Mask" "F.Paste")
			(net "M_H_CPU1_SB_DQS_DP<3>")
		)
		(pad "138" smd rect
			(at -2.050034 58.224928 270)
			(size 0.519938 1.4986)
			(layers "F.Cu" "F.Mask" "F.Paste")
			(net "M_H_CPU1_SB_DQS_DN<3>")
		)
		(pad "139" smd rect
			(at -2.050034 59.075066 270)
			(size 0.519938 1.4986)
			(layers "F.Cu" "F.Mask" "F.Paste")
			(net "GND")
		)
		(pad "140" smd rect
			(at -2.050034 59.92495 270)
			(size 0.519938 1.4986)
			(layers "F.Cu" "F.Mask" "F.Paste")
			(net "M_H_CPU1_SB_DQ<28>")
		)
		(pad "141" smd rect
			(at -2.050034 60.775088 270)
			(size 0.519938 1.4986)
			(layers "F.Cu" "F.Mask" "F.Paste")
			(net "GND")
		)
		(pad "142" smd rect
			(at -2.050034 61.624972 270)
			(size 0.519938 1.4986)
			(layers "F.Cu" "F.Mask" "F.Paste")
			(net "M_H_CPU1_SB_DQ<29>")
		)
		(pad "143" smd rect
			(at -2.050034 62.47511 270)
			(size 0.519938 1.4986)
			(layers "F.Cu" "F.Mask" "F.Paste")
			(net "GND")
		)
		(pad "144" smd rect
			(at -2.050034 63.324994 270)
			(size 0.519938 1.4986)
			(layers "F.Cu" "F.Mask" "F.Paste")
			(net "TP_CHH_CPU1_DIMM1_FRU_1")
		)
		(pad "145" smd rect
			(at 2.050034 -63.324994 270)
			(size 0.519938 1.4986)
			(layers "F.Cu" "F.Mask" "F.Paste")
			(net "P12V_S3_AUX_CPU1_NVDIMM")
		)
		(pad "146" smd rect
			(at 2.050034 -62.47511 270)
			(size 0.519938 1.4986)
			(layers "F.Cu" "F.Mask" "F.Paste")
			(net "P12V_S3_AUX_CPU1_NVDIMM")
		)
		(pad "147" smd rect
			(at 2.050034 -61.624972 270)
			(size 0.519938 1.4986)
			(layers "F.Cu" "F.Mask" "F.Paste")
			(net "PWRGD_CHH_CPU1_DIMM1")
		)
		(pad "148" smd rect
			(at 2.050034 -60.775088 270)
			(size 0.519938 1.4986)
			(layers "F.Cu" "F.Mask" "F.Paste")
			(net "PD_CHH_CPU1_DIMM1_SAA")
		)
		(pad "149" smd rect
			(at 2.050034 -59.92495 270)
			(size 0.519938 1.4986)
			(layers "F.Cu" "F.Mask" "F.Paste")
			(net "TP_CHH_CPU1_DIMM1_FRU_2")
		)
		(pad "150" smd rect
			(at 2.050034 -59.075066 270)
			(size 0.519938 1.4986)
			(layers "F.Cu" "F.Mask" "F.Paste")
			(net "TP_CHH_CPU1_DIMM1_FRU_3")
		)
		(pad "151" smd rect
			(at 2.050034 -58.224928 270)
			(size 0.519938 1.4986)
			(layers "F.Cu" "F.Mask" "F.Paste")
			(net "GND")
		)
		(pad "152" smd rect
			(at 2.050034 -57.375044 270)
			(size 0.519938 1.4986)
			(layers "F.Cu" "F.Mask" "F.Paste")
			(net "M_H_CPU1_SA_DQ<2>")
		)
		(pad "153" smd rect
			(at 2.050034 -56.524906 270)
			(size 0.519938 1.4986)
			(layers "F.Cu" "F.Mask" "F.Paste")
			(net "GND")
		)
		(pad "154" smd rect
			(at 2.050034 -55.675022 270)
			(size 0.519938 1.4986)
			(layers "F.Cu" "F.Mask" "F.Paste")
			(net "M_H_CPU1_SA_DQ<3>")
		)
		(pad "155" smd rect
			(at 2.050034 -54.824884 270)
			(size 0.519938 1.4986)
			(layers "F.Cu" "F.Mask" "F.Paste")
			(net "GND")
		)
		(pad "156" smd rect
			(at 2.050034 -53.975 270)
			(size 0.519938 1.4986)
			(layers "F.Cu" "F.Mask" "F.Paste")
			(net "M_H_CPU1_SA_DQS_DN<5>")
		)
		(pad "157" smd rect
			(at 2.050034 -53.125116 270)
			(size 0.519938 1.4986)
			(layers "F.Cu" "F.Mask" "F.Paste")
			(net "M_H_CPU1_SA_DQS_DP<5>")
		)
		(pad "158" smd rect
			(at 2.050034 -52.274978 270)
			(size 0.519938 1.4986)
			(layers "F.Cu" "F.Mask" "F.Paste")
			(net "GND")
		)
		(pad "159" smd rect
			(at 2.050034 -51.425094 270)
			(size 0.519938 1.4986)
			(layers "F.Cu" "F.Mask" "F.Paste")
			(net "M_H_CPU1_SA_DQ<6>")
		)
		(pad "160" smd rect
			(at 2.050034 -50.574956 270)
			(size 0.519938 1.4986)
			(layers "F.Cu" "F.Mask" "F.Paste")
			(net "GND")
		)
		(pad "161" smd rect
			(at 2.050034 -49.725072 270)
			(size 0.519938 1.4986)
			(layers "F.Cu" "F.Mask" "F.Paste")
			(net "M_H_CPU1_SA_DQ<7>")
		)
		(pad "162" smd rect
			(at 2.050034 -48.874934 270)
			(size 0.519938 1.4986)
			(layers "F.Cu" "F.Mask" "F.Paste")
			(net "GND")
		)
		(pad "163" smd rect
			(at 2.050034 -48.02505 270)
			(size 0.519938 1.4986)
			(layers "F.Cu" "F.Mask" "F.Paste")
			(net "M_H_CPU1_SA_DQ<10>")
		)
		(pad "164" smd rect
			(at 2.050034 -47.174912 270)
			(size 0.519938 1.4986)
			(layers "F.Cu" "F.Mask" "F.Paste")
			(net "GND")
		)
		(pad "165" smd rect
			(at 2.050034 -46.325028 270)
			(size 0.519938 1.4986)
			(layers "F.Cu" "F.Mask" "F.Paste")
			(net "M_H_CPU1_SA_DQ<11>")
		)
		(pad "166" smd rect
			(at 2.050034 -45.47489 270)
			(size 0.519938 1.4986)
			(layers "F.Cu" "F.Mask" "F.Paste")
			(net "GND")
		)
		(pad "167" smd rect
			(at 2.050034 -44.625006 270)
			(size 0.519938 1.4986)
			(layers "F.Cu" "F.Mask" "F.Paste")
			(net "M_H_CPU1_SA_DQS_DN<6>")
		)
		(pad "168" smd rect
			(at 2.050034 -43.775122 270)
			(size 0.519938 1.4986)
			(layers "F.Cu" "F.Mask" "F.Paste")
			(net "M_H_CPU1_SA_DQS_DP<6>")
		)
		(pad "169" smd rect
			(at 2.050034 -42.924984 270)
			(size 0.519938 1.4986)
			(layers "F.Cu" "F.Mask" "F.Paste")
			(net "GND")
		)
		(pad "170" smd rect
			(at 2.050034 -42.0751 270)
			(size 0.519938 1.4986)
			(layers "F.Cu" "F.Mask" "F.Paste")
			(net "M_H_CPU1_SA_DQ<14>")
		)
		(pad "171" smd rect
			(at 2.050034 -41.224962 270)
			(size 0.519938 1.4986)
			(layers "F.Cu" "F.Mask" "F.Paste")
			(net "GND")
		)
		(pad "172" smd rect
			(at 2.050034 -40.375078 270)
			(size 0.519938 1.4986)
			(layers "F.Cu" "F.Mask" "F.Paste")
			(net "M_H_CPU1_SA_DQ<15>")
		)
		(pad "173" smd rect
			(at 2.050034 -39.52494 270)
			(size 0.519938 1.4986)
			(layers "F.Cu" "F.Mask" "F.Paste")
			(net "GND")
		)
		(pad "174" smd rect
			(at 2.050034 -38.675056 270)
			(size 0.519938 1.4986)
			(layers "F.Cu" "F.Mask" "F.Paste")
			(net "M_H_CPU1_SA_DQ<18>")
		)
		(pad "175" smd rect
			(at 2.050034 -37.824918 270)
			(size 0.519938 1.4986)
			(layers "F.Cu" "F.Mask" "F.Paste")
			(net "GND")
		)
		(pad "176" smd rect
			(at 2.050034 -36.975034 270)
			(size 0.519938 1.4986)
			(layers "F.Cu" "F.Mask" "F.Paste")
			(net "M_H_CPU1_SA_DQ<19>")
		)
		(pad "177" smd rect
			(at 2.050034 -36.124896 270)
			(size 0.519938 1.4986)
			(layers "F.Cu" "F.Mask" "F.Paste")
			(net "GND")
		)
		(pad "178" smd rect
			(at 2.050034 -35.275012 270)
			(size 0.519938 1.4986)
			(layers "F.Cu" "F.Mask" "F.Paste")
			(net "M_H_CPU1_SA_DQS_DN<7>")
		)
		(pad "179" smd rect
			(at 2.050034 -34.425128 270)
			(size 0.519938 1.4986)
			(layers "F.Cu" "F.Mask" "F.Paste")
			(net "M_H_CPU1_SA_DQS_DP<7>")
		)
		(pad "180" smd rect
			(at 2.050034 -33.57499 270)
			(size 0.519938 1.4986)
			(layers "F.Cu" "F.Mask" "F.Paste")
			(net "GND")
		)
		(pad "181" smd rect
			(at 2.050034 -32.725106 270)
			(size 0.519938 1.4986)
			(layers "F.Cu" "F.Mask" "F.Paste")
			(net "M_H_CPU1_SA_DQ<22>")
		)
		(pad "182" smd rect
			(at 2.050034 -31.874968 270)
			(size 0.519938 1.4986)
			(layers "F.Cu" "F.Mask" "F.Paste")
			(net "GND")
		)
		(pad "183" smd rect
			(at 2.050034 -31.025084 270)
			(size 0.519938 1.4986)
			(layers "F.Cu" "F.Mask" "F.Paste")
			(net "M_H_CPU1_SA_DQ<23>")
		)
		(pad "184" smd rect
			(at 2.050034 -30.174946 270)
			(size 0.519938 1.4986)
			(layers "F.Cu" "F.Mask" "F.Paste")
			(net "GND")
		)
		(pad "185" smd rect
			(at 2.050034 -29.325062 270)
			(size 0.519938 1.4986)
			(layers "F.Cu" "F.Mask" "F.Paste")
			(net "M_H_CPU1_SA_DQ<26>")
		)
		(pad "186" smd rect
			(at 2.050034 -28.474924 270)
			(size 0.519938 1.4986)
			(layers "F.Cu" "F.Mask" "F.Paste")
			(net "GND")
		)
		(pad "187" smd rect
			(at 2.050034 -27.62504 270)
			(size 0.519938 1.4986)
			(layers "F.Cu" "F.Mask" "F.Paste")
			(net "M_H_CPU1_SA_DQ<27>")
		)
		(pad "188" smd rect
			(at 2.050034 -26.774902 270)
			(size 0.519938 1.4986)
			(layers "F.Cu" "F.Mask" "F.Paste")
			(net "GND")
		)
		(pad "189" smd rect
			(at 2.050034 -25.925018 270)
			(size 0.519938 1.4986)
			(layers "F.Cu" "F.Mask" "F.Paste")
			(net "M_H_CPU1_SA_DQS_DN<8>")
		)
		(pad "190" smd rect
			(at 2.050034 -25.07488 270)
			(size 0.519938 1.4986)
			(layers "F.Cu" "F.Mask" "F.Paste")
			(net "M_H_CPU1_SA_DQS_DP<8>")
		)
		(pad "191" smd rect
			(at 2.050034 -24.224996 270)
			(size 0.519938 1.4986)
			(layers "F.Cu" "F.Mask" "F.Paste")
			(net "GND")
		)
		(pad "192" smd rect
			(at 2.050034 -23.375112 270)
			(size 0.519938 1.4986)
			(layers "F.Cu" "F.Mask" "F.Paste")
			(net "M_H_CPU1_SA_DQ<30>")
		)
		(pad "193" smd rect
			(at 2.050034 -22.524974 270)
			(size 0.519938 1.4986)
			(layers "F.Cu" "F.Mask" "F.Paste")
			(net "GND")
		)
		(pad "194" smd rect
			(at 2.050034 -21.67509 270)
			(size 0.519938 1.4986)
			(layers "F.Cu" "F.Mask" "F.Paste")
			(net "M_H_CPU1_SA_DQ<31>")
		)
		(pad "195" smd rect
			(at 2.050034 -20.824952 270)
			(size 0.519938 1.4986)
			(layers "F.Cu" "F.Mask" "F.Paste")
			(net "GND")
		)
		(pad "196" smd rect
			(at 2.050034 -19.975068 270)
			(size 0.519938 1.4986)
			(layers "F.Cu" "F.Mask" "F.Paste")
			(net "M_H_CPU1_SA_CB<2>")
		)
		(pad "197" smd rect
			(at 2.050034 -19.12493 270)
			(size 0.519938 1.4986)
			(layers "F.Cu" "F.Mask" "F.Paste")
			(net "GND")
		)
		(pad "198" smd rect
			(at 2.050034 -18.275046 270)
			(size 0.519938 1.4986)
			(layers "F.Cu" "F.Mask" "F.Paste")
			(net "M_H_CPU1_SA_CB<3>")
		)
		(pad "199" smd rect
			(at 2.050034 -17.424908 270)
			(size 0.519938 1.4986)
			(layers "F.Cu" "F.Mask" "F.Paste")
			(net "GND")
		)
		(pad "200" smd rect
			(at 2.050034 -16.575024 270)
			(size 0.519938 1.4986)
			(layers "F.Cu" "F.Mask" "F.Paste")
			(net "M_H_CPU1_SA_DQS_DN<9>")
		)
		(pad "201" smd rect
			(at 2.050034 -15.724886 270)
			(size 0.519938 1.4986)
			(layers "F.Cu" "F.Mask" "F.Paste")
			(net "M_H_CPU1_SA_DQS_DP<9>")
		)
		(pad "202" smd rect
			(at 2.050034 -14.875002 270)
			(size 0.519938 1.4986)
			(layers "F.Cu" "F.Mask" "F.Paste")
			(net "GND")
		)
		(pad "203" smd rect
			(at 2.050034 -14.025118 270)
			(size 0.519938 1.4986)
			(layers "F.Cu" "F.Mask" "F.Paste")
			(net "M_H_CPU1_SA_CB<6>")
		)
		(pad "204" smd rect
			(at 2.050034 -13.17498 270)
			(size 0.519938 1.4986)
			(layers "F.Cu" "F.Mask" "F.Paste")
			(net "GND")
		)
		(pad "205" smd rect
			(at 2.050034 -12.325096 270)
			(size 0.519938 1.4986)
			(layers "F.Cu" "F.Mask" "F.Paste")
			(net "M_H_CPU1_SA_CB<7>")
		)
		(pad "206" smd rect
			(at 2.050034 -11.474958 270)
			(size 0.519938 1.4986)
			(layers "F.Cu" "F.Mask" "F.Paste")
			(net "GND")
		)
		(pad "207" smd rect
			(at 2.050034 -10.625074 270)
			(size 0.519938 1.4986)
			(layers "F.Cu" "F.Mask" "F.Paste")
			(net "RST_M_GH_CPU1_FPGA_N")
		)
		(pad "208" smd rect
			(at 2.050034 -9.774936 270)
			(size 0.519938 1.4986)
			(layers "F.Cu" "F.Mask" "F.Paste")
			(net "GND")
		)
		(pad "209" smd rect
			(at 2.050034 -8.925052 270)
			(size 0.519938 1.4986)
			(layers "F.Cu" "F.Mask" "F.Paste")
			(net "M_H_CPU1_SA_CS_N<1>")
		)
		(pad "210" smd rect
			(at 2.050034 -8.074914 270)
			(size 0.519938 1.4986)
			(layers "F.Cu" "F.Mask" "F.Paste")
			(net "GND")
		)
		(pad "211" smd rect
			(at 2.050034 -7.22503 270)
			(size 0.519938 1.4986)
			(layers "F.Cu" "F.Mask" "F.Paste")
			(net "M_H_CPU1_SA_CA<1>")
		)
		(pad "212" smd rect
			(at 2.050034 -6.374892 270)
			(size 0.519938 1.4986)
			(layers "F.Cu" "F.Mask" "F.Paste")
			(net "GND")
		)
		(pad "213" smd rect
			(at 2.050034 -5.525008 270)
			(size 0.519938 1.4986)
			(layers "F.Cu" "F.Mask" "F.Paste")
			(net "M_H_CPU1_SA_CA<3>")
		)
		(pad "214" smd rect
			(at 2.050034 -4.675124 270)
			(size 0.519938 1.4986)
			(layers "F.Cu" "F.Mask" "F.Paste")
			(net "GND")
		)
		(pad "215" smd rect
			(at 2.050034 -3.824986 270)
			(size 0.519938 1.4986)
			(layers "F.Cu" "F.Mask" "F.Paste")
			(net "M_H_CPU1_SA_CA<5>")
		)
		(pad "216" smd rect
			(at 2.050034 -2.975102 270)
			(size 0.519938 1.4986)
			(layers "F.Cu" "F.Mask" "F.Paste")
			(net "GND")
		)
		(pad "217" smd rect
			(at 2.050034 -2.124964 270)
			(size 0.519938 1.4986)
			(layers "F.Cu" "F.Mask" "F.Paste")
			(net "M_H_CPU1_CLK_DP<0>")
		)
		(pad "218" smd rect
			(at 2.050034 -1.27508 270)
			(size 0.519938 1.4986)
			(layers "F.Cu" "F.Mask" "F.Paste")
			(net "M_H_CPU1_CLK_DN<0>")
		)
		(pad "219" smd rect
			(at 2.050034 -0.424942 270)
			(size 0.519938 1.4986)
			(layers "F.Cu" "F.Mask" "F.Paste")
			(net "GND")
		)
		(pad "220" smd rect
			(at 2.050034 5.525008 270)
			(size 0.519938 1.4986)
			(layers "F.Cu" "F.Mask" "F.Paste")
			(net "TP_CHH_CPU1_DIMM1_FRU_4")
		)
		(pad "221" smd rect
			(at 2.050034 6.374892 270)
			(size 0.519938 1.4986)
			(layers "F.Cu" "F.Mask" "F.Paste")
			(net "M_H_CPU1_SB_CA<1>")
		)
		(pad "222" smd rect
			(at 2.050034 7.22503 270)
			(size 0.519938 1.4986)
			(layers "F.Cu" "F.Mask" "F.Paste")
			(net "GND")
		)
		(pad "223" smd rect
			(at 2.050034 8.074914 270)
			(size 0.519938 1.4986)
			(layers "F.Cu" "F.Mask" "F.Paste")
			(net "M_H_CPU1_SB_CA<3>")
		)
		(pad "224" smd rect
			(at 2.050034 8.925052 270)
			(size 0.519938 1.4986)
			(layers "F.Cu" "F.Mask" "F.Paste")
			(net "GND")
		)
		(pad "225" smd rect
			(at 2.050034 9.774936 270)
			(size 0.519938 1.4986)
			(layers "F.Cu" "F.Mask" "F.Paste")
			(net "M_H_CPU1_SB_CA<5>")
		)
		(pad "226" smd rect
			(at 2.050034 10.625074 270)
			(size 0.519938 1.4986)
			(layers "F.Cu" "F.Mask" "F.Paste")
			(net "GND")
		)
		(pad "227" smd rect
			(at 2.050034 11.474958 270)
			(size 0.519938 1.4986)
			(layers "F.Cu" "F.Mask" "F.Paste")
			(net "M_H_CPU1_SB_PAR")
		)
		(pad "228" smd rect
			(at 2.050034 12.325096 270)
			(size 0.519938 1.4986)
			(layers "F.Cu" "F.Mask" "F.Paste")
			(net "GND")
		)
		(pad "229" smd rect
			(at 2.050034 13.17498 270)
			(size 0.519938 1.4986)
			(layers "F.Cu" "F.Mask" "F.Paste")
			(net "M_H_CPU1_SB_CS_N<1>")
		)
		(pad "230" smd rect
			(at 2.050034 14.025118 270)
			(size 0.519938 1.4986)
			(layers "F.Cu" "F.Mask" "F.Paste")
			(net "GND")
		)
		(pad "231" smd rect
			(at 2.050034 14.875002 270)
			(size 0.519938 1.4986)
			(layers "F.Cu" "F.Mask" "F.Paste")
			(net "TP_CHH_CPU1_DIMM1_FRU_5")
		)
		(pad "232" smd rect
			(at 2.050034 15.724886 270)
			(size 0.519938 1.4986)
			(layers "F.Cu" "F.Mask" "F.Paste")
			(net "TP_CHH_CPU1_DIMM1_FRU_6")
		)
		(pad "233" smd rect
			(at 2.050034 16.575024 270)
			(size 0.519938 1.4986)
			(layers "F.Cu" "F.Mask" "F.Paste")
			(net "GND")
		)
		(pad "234" smd rect
			(at 2.050034 17.424908 270)
			(size 0.519938 1.4986)
			(layers "F.Cu" "F.Mask" "F.Paste")
			(net "M_H_CPU1_SB_CB<6>")
		)
		(pad "235" smd rect
			(at 2.050034 18.275046 270)
			(size 0.519938 1.4986)
			(layers "F.Cu" "F.Mask" "F.Paste")
			(net "GND")
		)
		(pad "236" smd rect
			(at 2.050034 19.12493 270)
			(size 0.519938 1.4986)
			(layers "F.Cu" "F.Mask" "F.Paste")
			(net "M_H_CPU1_SB_CB<7>")
		)
		(pad "237" smd rect
			(at 2.050034 19.975068 270)
			(size 0.519938 1.4986)
			(layers "F.Cu" "F.Mask" "F.Paste")
			(net "GND")
		)
		(pad "238" smd rect
			(at 2.050034 20.824952 270)
			(size 0.519938 1.4986)
			(layers "F.Cu" "F.Mask" "F.Paste")
			(net "M_H_CPU1_SB_DQS_DN<4>")
		)
		(pad "239" smd rect
			(at 2.050034 21.67509 270)
			(size 0.519938 1.4986)
			(layers "F.Cu" "F.Mask" "F.Paste")
			(net "M_H_CPU1_SB_DQS_DP<4>")
		)
		(pad "240" smd rect
			(at 2.050034 22.524974 270)
			(size 0.519938 1.4986)
			(layers "F.Cu" "F.Mask" "F.Paste")
			(net "GND")
		)
		(pad "241" smd rect
			(at 2.050034 23.375112 270)
			(size 0.519938 1.4986)
			(layers "F.Cu" "F.Mask" "F.Paste")
			(net "M_H_CPU1_SB_CB<2>")
		)
		(pad "242" smd rect
			(at 2.050034 24.224996 270)
			(size 0.519938 1.4986)
			(layers "F.Cu" "F.Mask" "F.Paste")
			(net "GND")
		)
		(pad "243" smd rect
			(at 2.050034 25.07488 270)
			(size 0.519938 1.4986)
			(layers "F.Cu" "F.Mask" "F.Paste")
			(net "M_H_CPU1_SB_CB<3>")
		)
		(pad "244" smd rect
			(at 2.050034 25.925018 270)
			(size 0.519938 1.4986)
			(layers "F.Cu" "F.Mask" "F.Paste")
			(net "GND")
		)
		(pad "245" smd rect
			(at 2.050034 26.774902 270)
			(size 0.519938 1.4986)
			(layers "F.Cu" "F.Mask" "F.Paste")
			(net "M_H_CPU1_SB_DQ<2>")
		)
		(pad "246" smd rect
			(at 2.050034 27.62504 270)
			(size 0.519938 1.4986)
			(layers "F.Cu" "F.Mask" "F.Paste")
			(net "GND")
		)
		(pad "247" smd rect
			(at 2.050034 28.474924 270)
			(size 0.519938 1.4986)
			(layers "F.Cu" "F.Mask" "F.Paste")
			(net "M_H_CPU1_SB_DQ<3>")
		)
		(pad "248" smd rect
			(at 2.050034 29.325062 270)
			(size 0.519938 1.4986)
			(layers "F.Cu" "F.Mask" "F.Paste")
			(net "GND")
		)
		(pad "249" smd rect
			(at 2.050034 30.174946 270)
			(size 0.519938 1.4986)
			(layers "F.Cu" "F.Mask" "F.Paste")
			(net "M_H_CPU1_SB_DQS_DN<5>")
		)
		(pad "250" smd rect
			(at 2.050034 31.025084 270)
			(size 0.519938 1.4986)
			(layers "F.Cu" "F.Mask" "F.Paste")
			(net "M_H_CPU1_SB_DQS_DP<5>")
		)
		(pad "251" smd rect
			(at 2.050034 31.874968 270)
			(size 0.519938 1.4986)
			(layers "F.Cu" "F.Mask" "F.Paste")
			(net "GND")
		)
		(pad "252" smd rect
			(at 2.050034 32.725106 270)
			(size 0.519938 1.4986)
			(layers "F.Cu" "F.Mask" "F.Paste")
			(net "M_H_CPU1_SB_DQ<6>")
		)
		(pad "253" smd rect
			(at 2.050034 33.57499 270)
			(size 0.519938 1.4986)
			(layers "F.Cu" "F.Mask" "F.Paste")
			(net "GND")
		)
		(pad "254" smd rect
			(at 2.050034 34.425128 270)
			(size 0.519938 1.4986)
			(layers "F.Cu" "F.Mask" "F.Paste")
			(net "M_H_CPU1_SB_DQ<7>")
		)
		(pad "255" smd rect
			(at 2.050034 35.275012 270)
			(size 0.519938 1.4986)
			(layers "F.Cu" "F.Mask" "F.Paste")
			(net "GND")
		)
		(pad "256" smd rect
			(at 2.050034 36.124896 270)
			(size 0.519938 1.4986)
			(layers "F.Cu" "F.Mask" "F.Paste")
			(net "M_H_CPU1_SB_DQ<10>")
		)
		(pad "257" smd rect
			(at 2.050034 36.975034 270)
			(size 0.519938 1.4986)
			(layers "F.Cu" "F.Mask" "F.Paste")
			(net "GND")
		)
		(pad "258" smd rect
			(at 2.050034 37.824918 270)
			(size 0.519938 1.4986)
			(layers "F.Cu" "F.Mask" "F.Paste")
			(net "M_H_CPU1_SB_DQ<11>")
		)
		(pad "259" smd rect
			(at 2.050034 38.675056 270)
			(size 0.519938 1.4986)
			(layers "F.Cu" "F.Mask" "F.Paste")
			(net "GND")
		)
		(pad "260" smd rect
			(at 2.050034 39.52494 270)
			(size 0.519938 1.4986)
			(layers "F.Cu" "F.Mask" "F.Paste")
			(net "M_H_CPU1_SB_DQS_DN<6>")
		)
		(pad "261" smd rect
			(at 2.050034 40.375078 270)
			(size 0.519938 1.4986)
			(layers "F.Cu" "F.Mask" "F.Paste")
			(net "M_H_CPU1_SB_DQS_DP<6>")
		)
		(pad "262" smd rect
			(at 2.050034 41.224962 270)
			(size 0.519938 1.4986)
			(layers "F.Cu" "F.Mask" "F.Paste")
			(net "GND")
		)
		(pad "263" smd rect
			(at 2.050034 42.0751 270)
			(size 0.519938 1.4986)
			(layers "F.Cu" "F.Mask" "F.Paste")
			(net "M_H_CPU1_SB_DQ<14>")
		)
		(pad "264" smd rect
			(at 2.050034 42.924984 270)
			(size 0.519938 1.4986)
			(layers "F.Cu" "F.Mask" "F.Paste")
			(net "GND")
		)
		(pad "265" smd rect
			(at 2.050034 43.775122 270)
			(size 0.519938 1.4986)
			(layers "F.Cu" "F.Mask" "F.Paste")
			(net "M_H_CPU1_SB_DQ<15>")
		)
		(pad "266" smd rect
			(at 2.050034 44.625006 270)
			(size 0.519938 1.4986)
			(layers "F.Cu" "F.Mask" "F.Paste")
			(net "GND")
		)
		(pad "267" smd rect
			(at 2.050034 45.47489 270)
			(size 0.519938 1.4986)
			(layers "F.Cu" "F.Mask" "F.Paste")
			(net "M_H_CPU1_SB_DQ<18>")
		)
		(pad "268" smd rect
			(at 2.050034 46.325028 270)
			(size 0.519938 1.4986)
			(layers "F.Cu" "F.Mask" "F.Paste")
			(net "GND")
		)
		(pad "269" smd rect
			(at 2.050034 47.174912 270)
			(size 0.519938 1.4986)
			(layers "F.Cu" "F.Mask" "F.Paste")
			(net "M_H_CPU1_SB_DQ<19>")
		)
		(pad "270" smd rect
			(at 2.050034 48.02505 270)
			(size 0.519938 1.4986)
			(layers "F.Cu" "F.Mask" "F.Paste")
			(net "GND")
		)
		(pad "271" smd rect
			(at 2.050034 48.874934 270)
			(size 0.519938 1.4986)
			(layers "F.Cu" "F.Mask" "F.Paste")
			(net "M_H_CPU1_SB_DQS_DN<7>")
		)
		(pad "272" smd rect
			(at 2.050034 49.725072 270)
			(size 0.519938 1.4986)
			(layers "F.Cu" "F.Mask" "F.Paste")
			(net "M_H_CPU1_SB_DQS_DP<7>")
		)
		(pad "273" smd rect
			(at 2.050034 50.574956 270)
			(size 0.519938 1.4986)
			(layers "F.Cu" "F.Mask" "F.Paste")
			(net "GND")
		)
		(pad "274" smd rect
			(at 2.050034 51.425094 270)
			(size 0.519938 1.4986)
			(layers "F.Cu" "F.Mask" "F.Paste")
			(net "M_H_CPU1_SB_DQ<22>")
		)
		(pad "275" smd rect
			(at 2.050034 52.274978 270)
			(size 0.519938 1.4986)
			(layers "F.Cu" "F.Mask" "F.Paste")
			(net "GND")
		)
		(pad "276" smd rect
			(at 2.050034 53.125116 270)
			(size 0.519938 1.4986)
			(layers "F.Cu" "F.Mask" "F.Paste")
			(net "M_H_CPU1_SB_DQ<23>")
		)
		(pad "277" smd rect
			(at 2.050034 53.975 270)
			(size 0.519938 1.4986)
			(layers "F.Cu" "F.Mask" "F.Paste")
			(net "GND")
		)
		(pad "278" smd rect
			(at 2.050034 54.824884 270)
			(size 0.519938 1.4986)
			(layers "F.Cu" "F.Mask" "F.Paste")
			(net "M_H_CPU1_SB_DQ<26>")
		)
		(pad "279" smd rect
			(at 2.050034 55.675022 270)
			(size 0.519938 1.4986)
			(layers "F.Cu" "F.Mask" "F.Paste")
			(net "GND")
		)
		(pad "280" smd rect
			(at 2.050034 56.524906 270)
			(size 0.519938 1.4986)
			(layers "F.Cu" "F.Mask" "F.Paste")
			(net "M_H_CPU1_SB_DQ<27>")
		)
		(pad "281" smd rect
			(at 2.050034 57.375044 270)
			(size 0.519938 1.4986)
			(layers "F.Cu" "F.Mask" "F.Paste")
			(net "GND")
		)
		(pad "282" smd rect
			(at 2.050034 58.224928 270)
			(size 0.519938 1.4986)
			(layers "F.Cu" "F.Mask" "F.Paste")
			(net "M_H_CPU1_SB_DQS_DN<8>")
		)
		(pad "283" smd rect
			(at 2.050034 59.075066 270)
			(size 0.519938 1.4986)
			(layers "F.Cu" "F.Mask" "F.Paste")
			(net "M_H_CPU1_SB_DQS_DP<8>")
		)
		(pad "284" smd rect
			(at 2.050034 59.92495 270)
			(size 0.519938 1.4986)
			(layers "F.Cu" "F.Mask" "F.Paste")
			(net "GND")
		)
		(pad "285" smd rect
			(at 2.050034 60.775088 270)
			(size 0.519938 1.4986)
			(layers "F.Cu" "F.Mask" "F.Paste")
			(net "M_H_CPU1_SB_DQ<30>")
		)
		(pad "286" smd rect
			(at 2.050034 61.624972 270)
			(size 0.519938 1.4986)
			(layers "F.Cu" "F.Mask" "F.Paste")
			(net "GND")
		)
		(pad "287" smd rect
			(at 2.050034 62.47511 270)
			(size 0.519938 1.4986)
			(layers "F.Cu" "F.Mask" "F.Paste")
			(net "M_H_CPU1_SB_DQ<31>")
		)
		(pad "288" smd rect
			(at 2.050034 63.324994 270)
			(size 0.519938 1.4986)
			(layers "F.Cu" "F.Mask" "F.Paste")
			(net "GND")
		)
		(pad "G1" thru_hole oval
			(at 0 -68.97497)
			(size 2.8194 1.5748)
			(drill oval 2.4384 1.1938)
			(layers "*.Cu" "*.Mask")
			(remove_unused_layers no)
			(net "GND")
			(clearance 0.127)
			(thermal_gap 0.127)
		)
		(pad "G2" thru_hole oval
			(at 0 3.875024)
			(size 2.8194 1.5748)
			(drill oval 2.4384 1.1938)
			(layers "*.Cu" "*.Mask")
			(remove_unused_layers no)
			(net "GND")
			(clearance 0.127)
			(thermal_gap 0.127)
		)
		(pad "G3" thru_hole oval
			(at 0 68.97497)
			(size 2.8194 1.5748)
			(drill oval 2.4384 1.1938)
			(layers "*.Cu" "*.Mask")
			(remove_unused_layers no)
			(net "GND")
			(clearance 0.127)
			(thermal_gap 0.127)
		)
	)
	(footprint ""
		(layer "F.Cu")
		(at 285.268162 -15.37843)
		(property "Reference" "R4179"
			(at 0 0 0)
			(layer "F.SilkS")
			(hide yes)
			(effects
				(font
					(size 1.27 1.27)
				)
			)
		)
		(property "Value" ""
			(at 0 0 0)
			(layer "F.Fab")
			(effects
				(font
					(size 1.27 1.27)
				)
			)
		)
		(duplicate_pad_numbers_are_jumpers no)
		(fp_line
			(start -0.7874 -0.4064)
			(end 0.7874 -0.4064)
			(stroke
				(width 0.1524)
				(type default)
			)
			(layer "F.SilkS")
		)
		(fp_line
			(start -0.7874 0.4064)
			(end -0.7874 -0.4064)
			(stroke
				(width 0.1524)
				(type default)
			)
			(layer "F.SilkS")
		)
		(fp_line
			(start 0.7874 -0.4064)
			(end 0.7874 0.4064)
			(stroke
				(width 0.1524)
				(type default)
			)
			(layer "F.SilkS")
		)
		(fp_line
			(start 0.7874 0.4064)
			(end -0.7874 0.4064)
			(stroke
				(width 0.1524)
				(type default)
			)
			(layer "F.SilkS")
		)
		(fp_line
			(start -0.67945 -0.305054)
			(end -0.12065 -0.305054)
			(stroke
				(width 0.1)
				(type default)
			)
			(layer "F.Fab")
		)
		(fp_line
			(start -0.67945 0.3048)
			(end -0.67945 -0.305054)
			(stroke
				(width 0.1)
				(type default)
			)
			(layer "F.Fab")
		)
		(fp_line
			(start -0.12065 -0.305054)
			(end -0.12065 -0.2794)
			(stroke
				(width 0.1)
				(type default)
			)
			(layer "F.Fab")
		)
		(fp_line
			(start -0.12065 -0.2794)
			(end 0.12065 -0.2794)
			(stroke
				(width 0.1)
				(type default)
			)
			(layer "F.Fab")
		)
		(fp_line
			(start -0.12065 0.2794)
			(end -0.12065 0.3048)
			(stroke
				(width 0.1)
				(type default)
			)
			(layer "F.Fab")
		)
		(fp_line
			(start -0.12065 0.3048)
			(end -0.67945 0.3048)
			(stroke
				(width 0.1)
				(type default)
			)
			(layer "F.Fab")
		)
		(fp_line
			(start 0.120396 0.2794)
			(end -0.12065 0.2794)
			(stroke
				(width 0.1)
				(type default)
			)
			(layer "F.Fab")
		)
		(fp_line
			(start 0.120396 0.3048)
			(end 0.120396 0.2794)
			(stroke
				(width 0.1)
				(type default)
			)
			(layer "F.Fab")
		)
		(fp_line
			(start 0.12065 -0.3048)
			(end 0.67945 -0.3048)
			(stroke
				(width 0.1)
				(type default)
			)
			(layer "F.Fab")
		)
		(fp_line
			(start 0.12065 -0.2794)
			(end 0.12065 -0.3048)
			(stroke
				(width 0.1)
				(type default)
			)
			(layer "F.Fab")
		)
		(fp_line
			(start 0.67945 -0.3048)
			(end 0.67945 0.3048)
			(stroke
				(width 0.1)
				(type default)
			)
			(layer "F.Fab")
		)
		(fp_line
			(start 0.67945 0.3048)
			(end 0.120396 0.3048)
			(stroke
				(width 0.1)
				(type default)
			)
			(layer "F.Fab")
		)
		(pad "1" smd circle
			(at -0.40005 0)
			(size 0 0)
			(layers "F.Cu" "F.Mask" "F.Paste")
			(net "SMB_LM75_1_3V3AUX_SCL")
		)
		(pad "2" smd circle
			(at 0.40005 0)
			(size 0 0)
			(layers "F.Cu" "F.Mask" "F.Paste")
			(net "SMB_LM75_1_3V3AUX_SCL_R1")
		)
	)
	(footprint ""
		(layer "F.Cu")
		(at 160.8328 -122.596148)
		(property "Reference" "R4625"
			(at 0 0 0)
			(layer "F.SilkS")
			(hide yes)
			(effects
				(font
					(size 1.27 1.27)
				)
			)
		)
		(property "Value" ""
			(at 0 0 0)
			(layer "F.Fab")
			(effects
				(font
					(size 1.27 1.27)
				)
			)
		)
		(duplicate_pad_numbers_are_jumpers no)
		(fp_line
			(start -0.7874 -0.4064)
			(end 0.7874 -0.4064)
			(stroke
				(width 0.1524)
				(type default)
			)
			(layer "F.SilkS")
		)
		(fp_line
			(start -0.7874 0.4064)
			(end -0.7874 -0.4064)
			(stroke
				(width 0.1524)
				(type default)
			)
			(layer "F.SilkS")
		)
		(fp_line
			(start 0.7874 -0.4064)
			(end 0.7874 0.4064)
			(stroke
				(width 0.1524)
				(type default)
			)
			(layer "F.SilkS")
		)
		(fp_line
			(start 0.7874 0.4064)
			(end -0.7874 0.4064)
			(stroke
				(width 0.1524)
				(type default)
			)
			(layer "F.SilkS")
		)
		(fp_line
			(start -0.67945 -0.305054)
			(end -0.12065 -0.305054)
			(stroke
				(width 0.1)
				(type default)
			)
			(layer "F.Fab")
		)
		(fp_line
			(start -0.67945 0.3048)
			(end -0.67945 -0.305054)
			(stroke
				(width 0.1)
				(type default)
			)
			(layer "F.Fab")
		)
		(fp_line
			(start -0.12065 -0.305054)
			(end -0.12065 -0.2794)
			(stroke
				(width 0.1)
				(type default)
			)
			(layer "F.Fab")
		)
		(fp_line
			(start -0.12065 -0.2794)
			(end 0.12065 -0.2794)
			(stroke
				(width 0.1)
				(type default)
			)
			(layer "F.Fab")
		)
		(fp_line
			(start -0.12065 0.2794)
			(end -0.12065 0.3048)
			(stroke
				(width 0.1)
				(type default)
			)
			(layer "F.Fab")
		)
		(fp_line
			(start -0.12065 0.3048)
			(end -0.67945 0.3048)
			(stroke
				(width 0.1)
				(type default)
			)
			(layer "F.Fab")
		)
		(fp_line
			(start 0.120396 0.2794)
			(end -0.12065 0.2794)
			(stroke
				(width 0.1)
				(type default)
			)
			(layer "F.Fab")
		)
		(fp_line
			(start 0.120396 0.3048)
			(end 0.120396 0.2794)
			(stroke
				(width 0.1)
				(type default)
			)
			(layer "F.Fab")
		)
		(fp_line
			(start 0.12065 -0.3048)
			(end 0.67945 -0.3048)
			(stroke
				(width 0.1)
				(type default)
			)
			(layer "F.Fab")
		)
		(fp_line
			(start 0.12065 -0.2794)
			(end 0.12065 -0.3048)
			(stroke
				(width 0.1)
				(type default)
			)
			(layer "F.Fab")
		)
		(fp_line
			(start 0.67945 -0.3048)
			(end 0.67945 0.3048)
			(stroke
				(width 0.1)
				(type default)
			)
			(layer "F.Fab")
		)
		(fp_line
			(start 0.67945 0.3048)
			(end 0.120396 0.3048)
			(stroke
				(width 0.1)
				(type default)
			)
			(layer "F.Fab")
		)
		(pad "1" smd circle
			(at -0.40005 0)
			(size 0 0)
			(layers "F.Cu" "F.Mask" "F.Paste")
			(net "JTAG_BMC_SW_OE")
		)
		(pad "2" smd circle
			(at 0.40005 0)
			(size 0 0)
			(layers "F.Cu" "F.Mask" "F.Paste")
			(net "JTAG_BMC_SW_PLD_OE")
		)
	)
	(footprint ""
		(layer "F.Cu")
		(at 106.328464 -238.162592 -90)
		(property "Reference" "C262"
			(at 0 0 270)
			(layer "F.SilkS")
			(hide yes)
			(effects
				(font
					(size 1.27 1.27)
				)
			)
		)
		(property "Value" ""
			(at 0 0 270)
			(layer "F.Fab")
			(effects
				(font
					(size 1.27 1.27)
				)
			)
		)
		(duplicate_pad_numbers_are_jumpers no)
		(fp_line
			(start -0.7874 0.4064)
			(end -0.7874 -0.4064)
			(stroke
				(width 0.1524)
				(type default)
			)
			(layer "F.SilkS")
		)
		(fp_line
			(start 0.7874 0.4064)
			(end -0.7874 0.4064)
			(stroke
				(width 0.1524)
				(type default)
			)
			(layer "F.SilkS")
		)
		(fp_line
			(start -0.7874 -0.4064)
			(end 0.7874 -0.4064)
			(stroke
				(width 0.1524)
				(type default)
			)
			(layer "F.SilkS")
		)
		(fp_line
			(start 0.7874 -0.4064)
			(end 0.7874 0.4064)
			(stroke
				(width 0.1524)
				(type default)
			)
			(layer "F.SilkS")
		)
		(fp_line
			(start -0.67945 0.3048)
			(end -0.67945 -0.305054)
			(stroke
				(width 0.1)
				(type default)
			)
			(layer "F.Fab")
		)
		(fp_line
			(start -0.12065 0.3048)
			(end -0.67945 0.3048)
			(stroke
				(width 0.1)
				(type default)
			)
			(layer "F.Fab")
		)
		(fp_line
			(start 0.120396 0.3048)
			(end 0.120396 0.2794)
			(stroke
				(width 0.1)
				(type default)
			)
			(layer "F.Fab")
		)
		(fp_line
			(start 0.67945 0.3048)
			(end 0.120396 0.3048)
			(stroke
				(width 0.1)
				(type default)
			)
			(layer "F.Fab")
		)
		(fp_line
			(start -0.12065 0.2794)
			(end -0.12065 0.3048)
			(stroke
				(width 0.1)
				(type default)
			)
			(layer "F.Fab")
		)
		(fp_line
			(start 0.120396 0.2794)
			(end -0.12065 0.2794)
			(stroke
				(width 0.1)
				(type default)
			)
			(layer "F.Fab")
		)
		(fp_line
			(start -0.12065 -0.2794)
			(end 0.12065 -0.2794)
			(stroke
				(width 0.1)
				(type default)
			)
			(layer "F.Fab")
		)
		(fp_line
			(start 0.12065 -0.2794)
			(end 0.12065 -0.3048)
			(stroke
				(width 0.1)
				(type default)
			)
			(layer "F.Fab")
		)
		(fp_line
			(start 0.12065 -0.3048)
			(end 0.67945 -0.3048)
			(stroke
				(width 0.1)
				(type default)
			)
			(layer "F.Fab")
		)
		(fp_line
			(start 0.67945 -0.3048)
			(end 0.67945 0.3048)
			(stroke
				(width 0.1)
				(type default)
			)
			(layer "F.Fab")
		)
		(fp_line
			(start -0.67945 -0.305054)
			(end -0.12065 -0.305054)
			(stroke
				(width 0.1)
				(type default)
			)
			(layer "F.Fab")
		)
		(fp_line
			(start -0.12065 -0.305054)
			(end -0.12065 -0.2794)
			(stroke
				(width 0.1)
				(type default)
			)
			(layer "F.Fab")
		)
		(pad "1" smd circle
			(at -0.40005 0 270)
			(size 0 0)
			(layers "F.Cu" "F.Mask" "F.Paste")
			(net "PVCCIN_CPU1")
		)
		(pad "2" smd circle
			(at 0.40005 0 270)
			(size 0 0)
			(layers "F.Cu" "F.Mask" "F.Paste")
			(net "GND")
		)
	)
	(footprint ""
		(layer "F.Cu")
		(at 254 -37.667946 180)
		(property "Reference" "R3976"
			(at 0 0 180)
			(layer "F.SilkS")
			(hide yes)
			(effects
				(font
					(size 1.27 1.27)
				)
			)
		)
		(property "Value" ""
			(at 0 0 180)
			(layer "F.Fab")
			(effects
				(font
					(size 1.27 1.27)
				)
			)
		)
		(duplicate_pad_numbers_are_jumpers no)
		(fp_line
			(start 0.7874 0.4064)
			(end -0.7874 0.4064)
			(stroke
				(width 0.1524)
				(type default)
			)
			(layer "F.SilkS")
		)
		(fp_line
			(start 0.7874 -0.4064)
			(end 0.7874 0.4064)
			(stroke
				(width 0.1524)
				(type default)
			)
			(layer "F.SilkS")
		)
		(fp_line
			(start -0.7874 0.4064)
			(end -0.7874 -0.4064)
			(stroke
				(width 0.1524)
				(type default)
			)
			(layer "F.SilkS")
		)
		(fp_line
			(start -0.7874 -0.4064)
			(end 0.7874 -0.4064)
			(stroke
				(width 0.1524)
				(type default)
			)
			(layer "F.SilkS")
		)
		(fp_line
			(start 0.67945 0.3048)
			(end 0.120396 0.3048)
			(stroke
				(width 0.1)
				(type default)
			)
			(layer "F.Fab")
		)
		(fp_line
			(start 0.67945 -0.3048)
			(end 0.67945 0.3048)
			(stroke
				(width 0.1)
				(type default)
			)
			(layer "F.Fab")
		)
		(fp_line
			(start 0.12065 -0.2794)
			(end 0.12065 -0.3048)
			(stroke
				(width 0.1)
				(type default)
			)
			(layer "F.Fab")
		)
		(fp_line
			(start 0.12065 -0.3048)
			(end 0.67945 -0.3048)
			(stroke
				(width 0.1)
				(type default)
			)
			(layer "F.Fab")
		)
		(fp_line
			(start 0.120396 0.3048)
			(end 0.120396 0.2794)
			(stroke
				(width 0.1)
				(type default)
			)
			(layer "F.Fab")
		)
		(fp_line
			(start 0.120396 0.2794)
			(end -0.12065 0.2794)
			(stroke
				(width 0.1)
				(type default)
			)
			(layer "F.Fab")
		)
		(fp_line
			(start -0.12065 0.3048)
			(end -0.67945 0.3048)
			(stroke
				(width 0.1)
				(type default)
			)
			(layer "F.Fab")
		)
		(fp_line
			(start -0.12065 0.2794)
			(end -0.12065 0.3048)
			(stroke
				(width 0.1)
				(type default)
			)
			(layer "F.Fab")
		)
		(fp_line
			(start -0.12065 -0.2794)
			(end 0.12065 -0.2794)
			(stroke
				(width 0.1)
				(type default)
			)
			(layer "F.Fab")
		)
		(fp_line
			(start -0.12065 -0.305054)
			(end -0.12065 -0.2794)
			(stroke
				(width 0.1)
				(type default)
			)
			(layer "F.Fab")
		)
		(fp_line
			(start -0.67945 0.3048)
			(end -0.67945 -0.305054)
			(stroke
				(width 0.1)
				(type default)
			)
			(layer "F.Fab")
		)
		(fp_line
			(start -0.67945 -0.305054)
			(end -0.12065 -0.305054)
			(stroke
				(width 0.1)
				(type default)
			)
			(layer "F.Fab")
		)
		(pad "1" smd circle
			(at -0.40005 0 180)
			(size 0 0)
			(layers "F.Cu" "F.Mask" "F.Paste")
			(net "P3V3_AUX")
		)
		(pad "2" smd circle
			(at 0.40005 0 180)
			(size 0 0)
			(layers "F.Cu" "F.Mask" "F.Paste")
			(net "P12V_E1S_FAULT_0")
		)
	)
	(footprint ""
		(layer "F.Cu")
		(at 462.078832 -360.76382)
		(property "Reference" "H127"
			(at -3.766312 -6.887718 0)
			(unlocked yes)
			(layer "F.SilkS")
			(effects
				(font
					(size 0.7874 0.5842)
					(thickness 0.1524)
				)
				(justify left)
			)
		)
		(property "Value" ""
			(at 0 0 0)
			(layer "F.Fab")
			(effects
				(font
					(size 1.27 1.27)
				)
			)
		)
		(duplicate_pad_numbers_are_jumpers no)
		(fp_arc
			(start 4.69773 3.430016)
			(mid -5.81025 -0.291475)
			(end 5.017516 -2.942082)
			(stroke
				(width 0.1524)
				(type default)
			)
			(layer "F.SilkS")
		)
		(fp_arc
			(start 4.7879 3.303016)
			(mid -5.810958 -0.220995)
			(end 5.025136 -2.929128)
			(stroke
				(width 0.1524)
				(type default)
			)
			(layer "B.SilkS")
		)
		(fp_circle
			(center 0 0)
			(end 5.8166 0)
			(stroke
				(width 0.1)
				(type default)
			)
			(fill no)
			(layer "B.Fab")
		)
		(fp_circle
			(center 0 0)
			(end 5.8166 0)
			(stroke
				(width 0.1)
				(type default)
			)
			(fill no)
			(layer "F.Fab")
		)
		(pad "" np_thru_hole circle
			(at 0 0)
			(size 10.0076 10.0076)
			(drill 10.0076)
			(layers "*.Cu" "*.Mask")
			(clearance 0.381)
			(thermal_gap 0.381)
		)
		(zone
			(layers "F.Cu" "B.Cu" "In1.Cu" "In2.Cu" "In3.Cu" "In4.Cu" "In5.Cu" "In6.Cu"
				"In7.Cu" "In8.Cu" "In9.Cu" "In10.Cu" "In11.Cu" "In12.Cu" "In13.Cu" "In14.Cu"
				"In15.Cu" "In16.Cu"
			)
			(hatch none 0.5)
			(connect_pads
				(clearance 0)
			)
			(min_thickness 0.25)
			(keepout
				(tracks not_allowed)
				(vias allowed)
				(pads allowed)
				(copperpour not_allowed)
				(footprints allowed)
			)
			(placement
				(enabled no)
				(sheetname "")
			)
			(fill
				(thermal_gap 0.5)
				(thermal_bridge_width 0.5)
				(island_removal_mode 0)
			)
			(polygon
				(pts
					(arc
						(start 467.590632 -360.76382)
						(mid 456.567032 -360.76382)
						(end 467.590632 -360.76382)
					)
				)
			)
		)
	)
	(footprint ""
		(layer "F.Cu")
		(at 179.760626 -421.729154 -90)
		(property "Reference" "U192"
			(at 6.665214 1.705864 90)
			(unlocked yes)
			(layer "F.SilkS")
			(effects
				(font
					(size 0.7874 0.5842)
					(thickness 0.1524)
				)
				(justify left)
			)
		)
		(property "Value" ""
			(at 0 0 270)
			(layer "F.Fab")
			(effects
				(font
					(size 1.27 1.27)
				)
			)
		)
		(duplicate_pad_numbers_are_jumpers no)
		(fp_line
			(start -1.3716 1.524)
			(end -1.3716 -1.524)
			(stroke
				(width 0.1524)
				(type default)
			)
			(layer "F.SilkS")
		)
		(fp_line
			(start 1.3716 1.524)
			(end -1.3716 1.524)
			(stroke
				(width 0.1524)
				(type default)
			)
			(layer "F.SilkS")
		)
		(fp_line
			(start 0 -1.016)
			(end 0.508 -1.524)
			(stroke
				(width 0.1524)
				(type default)
			)
			(layer "F.SilkS")
		)
		(fp_line
			(start -1.3716 -1.524)
			(end -0.508 -1.524)
			(stroke
				(width 0.1524)
				(type default)
			)
			(layer "F.SilkS")
		)
		(fp_line
			(start -0.508 -1.524)
			(end 0 -1.016)
			(stroke
				(width 0.1524)
				(type default)
			)
			(layer "F.SilkS")
		)
		(fp_line
			(start 0.508 -1.524)
			(end 1.3716 -1.524)
			(stroke
				(width 0.1524)
				(type default)
			)
			(layer "F.SilkS")
		)
		(fp_line
			(start 1.3716 -1.524)
			(end 1.3716 1.524)
			(stroke
				(width 0.1524)
				(type default)
			)
			(layer "F.SilkS")
		)
		(fp_poly
			(pts
				(xy -1.8669 -1.852676) (xy -2.195068 -1.298956) (xy -2.49174 -1.852676)
			)
			(stroke
				(width 0)
				(type default)
			)
			(fill yes)
			(layer "F.SilkS")
		)
		(fp_line
			(start -1.5494 1.524)
			(end -1.5494 1.0668)
			(stroke
				(width 0.1)
				(type default)
			)
			(layer "F.Fab")
		)
		(fp_line
			(start 1.5494 1.524)
			(end -1.5494 1.524)
			(stroke
				(width 0.1)
				(type default)
			)
			(layer "F.Fab")
		)
		(fp_line
			(start -2.54 1.0668)
			(end -2.54 -1.0668)
			(stroke
				(width 0.1)
				(type default)
			)
			(layer "F.Fab")
		)
		(fp_line
			(start -1.5494 1.0668)
			(end -2.54 1.0668)
			(stroke
				(width 0.1)
				(type default)
			)
			(layer "F.Fab")
		)
		(fp_line
			(start -1.5494 1.0668)
			(end -1.5494 -1.0668)
			(stroke
				(width 0.1)
				(type default)
			)
			(layer "F.Fab")
		)
		(fp_line
			(start 1.5494 1.0668)
			(end 1.5494 1.524)
			(stroke
				(width 0.1)
				(type default)
			)
			(layer "F.Fab")
		)
		(fp_line
			(start 2.54 1.0668)
			(end 1.5494 1.0668)
			(stroke
				(width 0.1)
				(type default)
			)
			(layer "F.Fab")
		)
		(fp_line
			(start -2.54 -1.0668)
			(end -1.5494 -1.0668)
			(stroke
				(width 0.1)
				(type default)
			)
			(layer "F.Fab")
		)
		(fp_line
			(start -1.5494 -1.0668)
			(end -1.5494 -1.524)
			(stroke
				(width 0.1)
				(type default)
			)
			(layer "F.Fab")
		)
		(fp_line
			(start 1.5494 -1.0668)
			(end 1.5494 1.0668)
			(stroke
				(width 0.1)
				(type default)
			)
			(layer "F.Fab")
		)
		(fp_line
			(start 1.5494 -1.0668)
			(end 2.54 -1.0668)
			(stroke
				(width 0.1)
				(type default)
			)
			(layer "F.Fab")
		)
		(fp_line
			(start 2.54 -1.0668)
			(end 2.54 1.0668)
			(stroke
				(width 0.1)
				(type default)
			)
			(layer "F.Fab")
		)
		(fp_line
			(start -1.5494 -1.524)
			(end 1.5494 -1.524)
			(stroke
				(width 0.1)
				(type default)
			)
			(layer "F.Fab")
		)
		(fp_line
			(start 1.5494 -1.524)
			(end 1.5494 -1.0668)
			(stroke
				(width 0.1)
				(type default)
			)
			(layer "F.Fab")
		)
		(fp_poly
			(pts
				(xy -3.60172 -0.719328) (xy -3.60172 -1.344168) (xy -3.048 -1.016)
			)
			(stroke
				(width 0)
				(type default)
			)
			(fill yes)
			(layer "F.Fab")
		)
		(pad "1" smd rect
			(at -2.232406 -0.975106 180)
			(size 0.3556 1.4224)
			(layers "F.Cu" "F.Mask" "F.Paste")
			(net "FM_MB_PDB_SMB9_R_EN")
		)
		(pad "2" smd rect
			(at -2.232406 -0.32512 180)
			(size 0.3556 1.4224)
			(layers "F.Cu" "F.Mask" "F.Paste")
			(net "SMB_FAN_3V3AUX_BUF_SCL")
		)
		(pad "3" smd rect
			(at -2.232406 0.32512 180)
			(size 0.3556 1.4224)
			(layers "F.Cu" "F.Mask" "F.Paste")
			(net "SMB_FAN_3V3AUX_R_SCL")
		)
		(pad "4" smd rect
			(at -2.232406 0.975106 180)
			(size 0.3556 1.4224)
			(layers "F.Cu" "F.Mask" "F.Paste")
			(net "GND")
		)
		(pad "5" smd rect
			(at 2.232406 0.975106 180)
			(size 0.3556 1.4224)
			(layers "F.Cu" "F.Mask" "F.Paste")
			(net "Net_1935")
		)
		(pad "6" smd rect
			(at 2.232406 0.32512 180)
			(size 0.3556 1.4224)
			(layers "F.Cu" "F.Mask" "F.Paste")
			(net "SMB_FAN_3V3AUX_R_SDA")
		)
		(pad "7" smd rect
			(at 2.232406 -0.32512 180)
			(size 0.3556 1.4224)
			(layers "F.Cu" "F.Mask" "F.Paste")
			(net "SMB_FAN_3V3AUX_BUF_SDA")
		)
		(pad "8" smd rect
			(at 2.232406 -0.975106 180)
			(size 0.3556 1.4224)
			(layers "F.Cu" "F.Mask" "F.Paste")
			(net "P3V3_AUX")
		)
	)
	(footprint ""
		(layer "F.Cu")
		(at 151.69388 -22.824948 90)
		(property "Reference" "R2994"
			(at 0 0 90)
			(layer "F.SilkS")
			(hide yes)
			(effects
				(font
					(size 1.27 1.27)
				)
			)
		)
		(property "Value" ""
			(at 0 0 90)
			(layer "F.Fab")
			(effects
				(font
					(size 1.27 1.27)
				)
			)
		)
		(duplicate_pad_numbers_are_jumpers no)
		(fp_line
			(start 0.7874 -0.4064)
			(end 0.7874 0.4064)
			(stroke
				(width 0.1524)
				(type default)
			)
			(layer "F.SilkS")
		)
		(fp_line
			(start -0.7874 -0.4064)
			(end 0.7874 -0.4064)
			(stroke
				(width 0.1524)
				(type default)
			)
			(layer "F.SilkS")
		)
		(fp_line
			(start 0.7874 0.4064)
			(end -0.7874 0.4064)
			(stroke
				(width 0.1524)
				(type default)
			)
			(layer "F.SilkS")
		)
		(fp_line
			(start -0.7874 0.4064)
			(end -0.7874 -0.4064)
			(stroke
				(width 0.1524)
				(type default)
			)
			(layer "F.SilkS")
		)
		(fp_line
			(start -0.12065 -0.305054)
			(end -0.12065 -0.2794)
			(stroke
				(width 0.1)
				(type default)
			)
			(layer "F.Fab")
		)
		(fp_line
			(start -0.67945 -0.305054)
			(end -0.12065 -0.305054)
			(stroke
				(width 0.1)
				(type default)
			)
			(layer "F.Fab")
		)
		(fp_line
			(start 0.67945 -0.3048)
			(end 0.67945 0.3048)
			(stroke
				(width 0.1)
				(type default)
			)
			(layer "F.Fab")
		)
		(fp_line
			(start 0.12065 -0.3048)
			(end 0.67945 -0.3048)
			(stroke
				(width 0.1)
				(type default)
			)
			(layer "F.Fab")
		)
		(fp_line
			(start 0.12065 -0.2794)
			(end 0.12065 -0.3048)
			(stroke
				(width 0.1)
				(type default)
			)
			(layer "F.Fab")
		)
		(fp_line
			(start -0.12065 -0.2794)
			(end 0.12065 -0.2794)
			(stroke
				(width 0.1)
				(type default)
			)
			(layer "F.Fab")
		)
		(fp_line
			(start 0.120396 0.2794)
			(end -0.12065 0.2794)
			(stroke
				(width 0.1)
				(type default)
			)
			(layer "F.Fab")
		)
		(fp_line
			(start -0.12065 0.2794)
			(end -0.12065 0.3048)
			(stroke
				(width 0.1)
				(type default)
			)
			(layer "F.Fab")
		)
		(fp_line
			(start 0.67945 0.3048)
			(end 0.120396 0.3048)
			(stroke
				(width 0.1)
				(type default)
			)
			(layer "F.Fab")
		)
		(fp_line
			(start 0.120396 0.3048)
			(end 0.120396 0.2794)
			(stroke
				(width 0.1)
				(type default)
			)
			(layer "F.Fab")
		)
		(fp_line
			(start -0.12065 0.3048)
			(end -0.67945 0.3048)
			(stroke
				(width 0.1)
				(type default)
			)
			(layer "F.Fab")
		)
		(fp_line
			(start -0.67945 0.3048)
			(end -0.67945 -0.305054)
			(stroke
				(width 0.1)
				(type default)
			)
			(layer "F.Fab")
		)
		(pad "1" smd circle
			(at -0.40005 0 90)
			(size 0 0)
			(layers "F.Cu" "F.Mask" "F.Paste")
			(net "P3V_BAT_R1")
		)
		(pad "2" smd circle
			(at 0.40005 0 90)
			(size 0 0)
			(layers "F.Cu" "F.Mask" "F.Paste")
			(net "P3V_BAT_R")
		)
	)
	(footprint ""
		(layer "F.Cu")
		(at 27.628596 -388.262876 180)
		(property "Reference" "R3292"
			(at 0 0 180)
			(layer "F.SilkS")
			(hide yes)
			(effects
				(font
					(size 1.27 1.27)
				)
			)
		)
		(property "Value" ""
			(at 0 0 180)
			(layer "F.Fab")
			(effects
				(font
					(size 1.27 1.27)
				)
			)
		)
		(duplicate_pad_numbers_are_jumpers no)
		(fp_line
			(start 0.7874 0.4064)
			(end -0.7874 0.4064)
			(stroke
				(width 0.1524)
				(type default)
			)
			(layer "F.SilkS")
		)
		(fp_line
			(start 0.7874 -0.4064)
			(end 0.7874 0.4064)
			(stroke
				(width 0.1524)
				(type default)
			)
			(layer "F.SilkS")
		)
		(fp_line
			(start -0.7874 0.4064)
			(end -0.7874 -0.4064)
			(stroke
				(width 0.1524)
				(type default)
			)
			(layer "F.SilkS")
		)
		(fp_line
			(start -0.7874 -0.4064)
			(end 0.7874 -0.4064)
			(stroke
				(width 0.1524)
				(type default)
			)
			(layer "F.SilkS")
		)
		(fp_line
			(start 0.67945 0.3048)
			(end 0.120396 0.3048)
			(stroke
				(width 0.1)
				(type default)
			)
			(layer "F.Fab")
		)
		(fp_line
			(start 0.67945 -0.3048)
			(end 0.67945 0.3048)
			(stroke
				(width 0.1)
				(type default)
			)
			(layer "F.Fab")
		)
		(fp_line
			(start 0.12065 -0.2794)
			(end 0.12065 -0.3048)
			(stroke
				(width 0.1)
				(type default)
			)
			(layer "F.Fab")
		)
		(fp_line
			(start 0.12065 -0.3048)
			(end 0.67945 -0.3048)
			(stroke
				(width 0.1)
				(type default)
			)
			(layer "F.Fab")
		)
		(fp_line
			(start 0.120396 0.3048)
			(end 0.120396 0.2794)
			(stroke
				(width 0.1)
				(type default)
			)
			(layer "F.Fab")
		)
		(fp_line
			(start 0.120396 0.2794)
			(end -0.12065 0.2794)
			(stroke
				(width 0.1)
				(type default)
			)
			(layer "F.Fab")
		)
		(fp_line
			(start -0.12065 0.3048)
			(end -0.67945 0.3048)
			(stroke
				(width 0.1)
				(type default)
			)
			(layer "F.Fab")
		)
		(fp_line
			(start -0.12065 0.2794)
			(end -0.12065 0.3048)
			(stroke
				(width 0.1)
				(type default)
			)
			(layer "F.Fab")
		)
		(fp_line
			(start -0.12065 -0.2794)
			(end 0.12065 -0.2794)
			(stroke
				(width 0.1)
				(type default)
			)
			(layer "F.Fab")
		)
		(fp_line
			(start -0.12065 -0.305054)
			(end -0.12065 -0.2794)
			(stroke
				(width 0.1)
				(type default)
			)
			(layer "F.Fab")
		)
		(fp_line
			(start -0.67945 0.3048)
			(end -0.67945 -0.305054)
			(stroke
				(width 0.1)
				(type default)
			)
			(layer "F.Fab")
		)
		(fp_line
			(start -0.67945 -0.305054)
			(end -0.12065 -0.305054)
			(stroke
				(width 0.1)
				(type default)
			)
			(layer "F.Fab")
		)
		(pad "1" smd circle
			(at -0.40005 0 180)
			(size 0 0)
			(layers "F.Cu" "F.Mask" "F.Paste")
			(net "P3V3_AUX")
		)
		(pad "2" smd circle
			(at 0.40005 0 180)
			(size 0 0)
			(layers "F.Cu" "F.Mask" "F.Paste")
			(net "CLK_GEN2_GPU_FPGA_OE_OR_N")
		)
	)
	(footprint ""
		(layer "F.Cu")
		(at 107.296204 -245.634256 -90)
		(property "Reference" "C272"
			(at 0 0 270)
			(layer "F.SilkS")
			(hide yes)
			(effects
				(font
					(size 1.27 1.27)
				)
			)
		)
		(property "Value" ""
			(at 0 0 270)
			(layer "F.Fab")
			(effects
				(font
					(size 1.27 1.27)
				)
			)
		)
		(duplicate_pad_numbers_are_jumpers no)
		(fp_line
			(start -0.7874 0.4064)
			(end -0.7874 -0.4064)
			(stroke
				(width 0.1524)
				(type default)
			)
			(layer "F.SilkS")
		)
		(fp_line
			(start 0.7874 0.4064)
			(end -0.7874 0.4064)
			(stroke
				(width 0.1524)
				(type default)
			)
			(layer "F.SilkS")
		)
		(fp_line
			(start -0.7874 -0.4064)
			(end 0.7874 -0.4064)
			(stroke
				(width 0.1524)
				(type default)
			)
			(layer "F.SilkS")
		)
		(fp_line
			(start 0.7874 -0.4064)
			(end 0.7874 0.4064)
			(stroke
				(width 0.1524)
				(type default)
			)
			(layer "F.SilkS")
		)
		(fp_line
			(start -0.67945 0.3048)
			(end -0.67945 -0.305054)
			(stroke
				(width 0.1)
				(type default)
			)
			(layer "F.Fab")
		)
		(fp_line
			(start -0.12065 0.3048)
			(end -0.67945 0.3048)
			(stroke
				(width 0.1)
				(type default)
			)
			(layer "F.Fab")
		)
		(fp_line
			(start 0.120396 0.3048)
			(end 0.120396 0.2794)
			(stroke
				(width 0.1)
				(type default)
			)
			(layer "F.Fab")
		)
		(fp_line
			(start 0.67945 0.3048)
			(end 0.120396 0.3048)
			(stroke
				(width 0.1)
				(type default)
			)
			(layer "F.Fab")
		)
		(fp_line
			(start -0.12065 0.2794)
			(end -0.12065 0.3048)
			(stroke
				(width 0.1)
				(type default)
			)
			(layer "F.Fab")
		)
		(fp_line
			(start 0.120396 0.2794)
			(end -0.12065 0.2794)
			(stroke
				(width 0.1)
				(type default)
			)
			(layer "F.Fab")
		)
		(fp_line
			(start -0.12065 -0.2794)
			(end 0.12065 -0.2794)
			(stroke
				(width 0.1)
				(type default)
			)
			(layer "F.Fab")
		)
		(fp_line
			(start 0.12065 -0.2794)
			(end 0.12065 -0.3048)
			(stroke
				(width 0.1)
				(type default)
			)
			(layer "F.Fab")
		)
		(fp_line
			(start 0.12065 -0.3048)
			(end 0.67945 -0.3048)
			(stroke
				(width 0.1)
				(type default)
			)
			(layer "F.Fab")
		)
		(fp_line
			(start 0.67945 -0.3048)
			(end 0.67945 0.3048)
			(stroke
				(width 0.1)
				(type default)
			)
			(layer "F.Fab")
		)
		(fp_line
			(start -0.67945 -0.305054)
			(end -0.12065 -0.305054)
			(stroke
				(width 0.1)
				(type default)
			)
			(layer "F.Fab")
		)
		(fp_line
			(start -0.12065 -0.305054)
			(end -0.12065 -0.2794)
			(stroke
				(width 0.1)
				(type default)
			)
			(layer "F.Fab")
		)
		(pad "1" smd circle
			(at -0.40005 0 270)
			(size 0 0)
			(layers "F.Cu" "F.Mask" "F.Paste")
			(net "PVCCIN_CPU1")
		)
		(pad "2" smd circle
			(at 0.40005 0 270)
			(size 0 0)
			(layers "F.Cu" "F.Mask" "F.Paste")
			(net "GND")
		)
	)
	(footprint ""
		(layer "F.Cu")
		(at 307.363622 -41.900348 180)
		(property "Reference" "R1300"
			(at 0 0 180)
			(layer "F.SilkS")
			(hide yes)
			(effects
				(font
					(size 1.27 1.27)
				)
			)
		)
		(property "Value" ""
			(at 0 0 180)
			(layer "F.Fab")
			(effects
				(font
					(size 1.27 1.27)
				)
			)
		)
		(duplicate_pad_numbers_are_jumpers no)
		(fp_line
			(start 0.7874 0.4064)
			(end -0.7874 0.4064)
			(stroke
				(width 0.1524)
				(type default)
			)
			(layer "F.SilkS")
		)
		(fp_line
			(start 0.7874 -0.4064)
			(end 0.7874 0.4064)
			(stroke
				(width 0.1524)
				(type default)
			)
			(layer "F.SilkS")
		)
		(fp_line
			(start -0.7874 0.4064)
			(end -0.7874 -0.4064)
			(stroke
				(width 0.1524)
				(type default)
			)
			(layer "F.SilkS")
		)
		(fp_line
			(start -0.7874 -0.4064)
			(end 0.7874 -0.4064)
			(stroke
				(width 0.1524)
				(type default)
			)
			(layer "F.SilkS")
		)
		(fp_line
			(start 0.67945 0.3048)
			(end 0.120396 0.3048)
			(stroke
				(width 0.1)
				(type default)
			)
			(layer "F.Fab")
		)
		(fp_line
			(start 0.67945 -0.3048)
			(end 0.67945 0.3048)
			(stroke
				(width 0.1)
				(type default)
			)
			(layer "F.Fab")
		)
		(fp_line
			(start 0.12065 -0.2794)
			(end 0.12065 -0.3048)
			(stroke
				(width 0.1)
				(type default)
			)
			(layer "F.Fab")
		)
		(fp_line
			(start 0.12065 -0.3048)
			(end 0.67945 -0.3048)
			(stroke
				(width 0.1)
				(type default)
			)
			(layer "F.Fab")
		)
		(fp_line
			(start 0.120396 0.3048)
			(end 0.120396 0.2794)
			(stroke
				(width 0.1)
				(type default)
			)
			(layer "F.Fab")
		)
		(fp_line
			(start 0.120396 0.2794)
			(end -0.12065 0.2794)
			(stroke
				(width 0.1)
				(type default)
			)
			(layer "F.Fab")
		)
		(fp_line
			(start -0.12065 0.3048)
			(end -0.67945 0.3048)
			(stroke
				(width 0.1)
				(type default)
			)
			(layer "F.Fab")
		)
		(fp_line
			(start -0.12065 0.2794)
			(end -0.12065 0.3048)
			(stroke
				(width 0.1)
				(type default)
			)
			(layer "F.Fab")
		)
		(fp_line
			(start -0.12065 -0.2794)
			(end 0.12065 -0.2794)
			(stroke
				(width 0.1)
				(type default)
			)
			(layer "F.Fab")
		)
		(fp_line
			(start -0.12065 -0.305054)
			(end -0.12065 -0.2794)
			(stroke
				(width 0.1)
				(type default)
			)
			(layer "F.Fab")
		)
		(fp_line
			(start -0.67945 0.3048)
			(end -0.67945 -0.305054)
			(stroke
				(width 0.1)
				(type default)
			)
			(layer "F.Fab")
		)
		(fp_line
			(start -0.67945 -0.305054)
			(end -0.12065 -0.305054)
			(stroke
				(width 0.1)
				(type default)
			)
			(layer "F.Fab")
		)
		(pad "1" smd circle
			(at -0.40005 0 180)
			(size 0 0)
			(layers "F.Cu" "F.Mask" "F.Paste")
			(net "FM_BIOS_POST_CMPLT_N")
		)
		(pad "2" smd circle
			(at 0.40005 0 180)
			(size 0 0)
			(layers "F.Cu" "F.Mask" "F.Paste")
			(net "FM_BIOS_POST_CMPLT_BMC_N")
		)
	)
	(footprint ""
		(layer "F.Cu")
		(at 325.605902 -20.548346 -90)
		(property "Reference" "R1487"
			(at 0 0 270)
			(layer "F.SilkS")
			(hide yes)
			(effects
				(font
					(size 1.27 1.27)
				)
			)
		)
		(property "Value" ""
			(at 0 0 270)
			(layer "F.Fab")
			(effects
				(font
					(size 1.27 1.27)
				)
			)
		)
		(duplicate_pad_numbers_are_jumpers no)
		(fp_line
			(start -0.7874 0.4064)
			(end -0.7874 -0.4064)
			(stroke
				(width 0.1524)
				(type default)
			)
			(layer "F.SilkS")
		)
		(fp_line
			(start 0.7874 0.4064)
			(end -0.7874 0.4064)
			(stroke
				(width 0.1524)
				(type default)
			)
			(layer "F.SilkS")
		)
		(fp_line
			(start -0.7874 -0.4064)
			(end 0.7874 -0.4064)
			(stroke
				(width 0.1524)
				(type default)
			)
			(layer "F.SilkS")
		)
		(fp_line
			(start 0.7874 -0.4064)
			(end 0.7874 0.4064)
			(stroke
				(width 0.1524)
				(type default)
			)
			(layer "F.SilkS")
		)
		(fp_line
			(start -0.67945 0.3048)
			(end -0.67945 -0.305054)
			(stroke
				(width 0.1)
				(type default)
			)
			(layer "F.Fab")
		)
		(fp_line
			(start -0.12065 0.3048)
			(end -0.67945 0.3048)
			(stroke
				(width 0.1)
				(type default)
			)
			(layer "F.Fab")
		)
		(fp_line
			(start 0.120396 0.3048)
			(end 0.120396 0.2794)
			(stroke
				(width 0.1)
				(type default)
			)
			(layer "F.Fab")
		)
		(fp_line
			(start 0.67945 0.3048)
			(end 0.120396 0.3048)
			(stroke
				(width 0.1)
				(type default)
			)
			(layer "F.Fab")
		)
		(fp_line
			(start -0.12065 0.2794)
			(end -0.12065 0.3048)
			(stroke
				(width 0.1)
				(type default)
			)
			(layer "F.Fab")
		)
		(fp_line
			(start 0.120396 0.2794)
			(end -0.12065 0.2794)
			(stroke
				(width 0.1)
				(type default)
			)
			(layer "F.Fab")
		)
		(fp_line
			(start -0.12065 -0.2794)
			(end 0.12065 -0.2794)
			(stroke
				(width 0.1)
				(type default)
			)
			(layer "F.Fab")
		)
		(fp_line
			(start 0.12065 -0.2794)
			(end 0.12065 -0.3048)
			(stroke
				(width 0.1)
				(type default)
			)
			(layer "F.Fab")
		)
		(fp_line
			(start 0.12065 -0.3048)
			(end 0.67945 -0.3048)
			(stroke
				(width 0.1)
				(type default)
			)
			(layer "F.Fab")
		)
		(fp_line
			(start 0.67945 -0.3048)
			(end 0.67945 0.3048)
			(stroke
				(width 0.1)
				(type default)
			)
			(layer "F.Fab")
		)
		(fp_line
			(start -0.67945 -0.305054)
			(end -0.12065 -0.305054)
			(stroke
				(width 0.1)
				(type default)
			)
			(layer "F.Fab")
		)
		(fp_line
			(start -0.12065 -0.305054)
			(end -0.12065 -0.2794)
			(stroke
				(width 0.1)
				(type default)
			)
			(layer "F.Fab")
		)
		(pad "1" smd circle
			(at -0.40005 0 270)
			(size 0 0)
			(layers "F.Cu" "F.Mask" "F.Paste")
			(net "FM_PCH_SATA_RAID_KEY")
		)
		(pad "2" smd circle
			(at 0.40005 0 270)
			(size 0 0)
			(layers "F.Cu" "F.Mask" "F.Paste")
			(net "GND")
		)
	)
	(footprint ""
		(layer "F.Cu")
		(at 312.341768 -408.517344 -90)
		(property "Reference" "C907"
			(at 0 0 270)
			(layer "F.SilkS")
			(hide yes)
			(effects
				(font
					(size 1.27 1.27)
				)
			)
		)
		(property "Value" ""
			(at 0 0 270)
			(layer "F.Fab")
			(effects
				(font
					(size 1.27 1.27)
				)
			)
		)
		(duplicate_pad_numbers_are_jumpers no)
		(fp_line
			(start -0.299974 0.150114)
			(end -0.299974 -0.150114)
			(stroke
				(width 0.1)
				(type default)
			)
			(layer "F.Fab")
		)
		(fp_line
			(start 0.299974 0.150114)
			(end -0.299974 0.150114)
			(stroke
				(width 0.1)
				(type default)
			)
			(layer "F.Fab")
		)
		(fp_line
			(start -0.299974 -0.150114)
			(end 0.299974 -0.150114)
			(stroke
				(width 0.1)
				(type default)
			)
			(layer "F.Fab")
		)
		(fp_line
			(start 0.299974 -0.150114)
			(end 0.299974 0.150114)
			(stroke
				(width 0.1)
				(type default)
			)
			(layer "F.Fab")
		)
		(pad "1" smd rect
			(at -0.2667 0 270)
			(size 0.3048 0.381)
			(layers "F.Cu" "F.Mask" "F.Paste")
			(net "P5E_CPU0_PE0_TX_C_DP<13>")
		)
		(pad "2" smd rect
			(at 0.2667 0 270)
			(size 0.3048 0.381)
			(layers "F.Cu" "F.Mask" "F.Paste")
			(net "P5E_CPU0_PE0_TX_DP<13>")
		)
	)
	(footprint ""
		(layer "F.Cu")
		(at 401.22729 -408.517344 -90)
		(property "Reference" "C889"
			(at 0 0 270)
			(layer "F.SilkS")
			(hide yes)
			(effects
				(font
					(size 1.27 1.27)
				)
			)
		)
		(property "Value" ""
			(at 0 0 270)
			(layer "F.Fab")
			(effects
				(font
					(size 1.27 1.27)
				)
			)
		)
		(duplicate_pad_numbers_are_jumpers no)
		(fp_line
			(start -0.299974 0.150114)
			(end -0.299974 -0.150114)
			(stroke
				(width 0.1)
				(type default)
			)
			(layer "F.Fab")
		)
		(fp_line
			(start 0.299974 0.150114)
			(end -0.299974 0.150114)
			(stroke
				(width 0.1)
				(type default)
			)
			(layer "F.Fab")
		)
		(fp_line
			(start -0.299974 -0.150114)
			(end 0.299974 -0.150114)
			(stroke
				(width 0.1)
				(type default)
			)
			(layer "F.Fab")
		)
		(fp_line
			(start 0.299974 -0.150114)
			(end 0.299974 0.150114)
			(stroke
				(width 0.1)
				(type default)
			)
			(layer "F.Fab")
		)
		(pad "1" smd rect
			(at -0.2667 0 270)
			(size 0.3048 0.381)
			(layers "F.Cu" "F.Mask" "F.Paste")
			(net "P5E_CPU0_PE3_TX_C_DP<6>")
		)
		(pad "2" smd rect
			(at 0.2667 0 270)
			(size 0.3048 0.381)
			(layers "F.Cu" "F.Mask" "F.Paste")
			(net "P5E_CPU0_PE3_TX_DP<6>")
		)
	)
	(footprint ""
		(layer "F.Cu")
		(at 230.248206 -247.684036 180)
		(property "Reference" "R3337"
			(at 0 0 180)
			(layer "F.SilkS")
			(hide yes)
			(effects
				(font
					(size 1.27 1.27)
				)
			)
		)
		(property "Value" ""
			(at 0 0 180)
			(layer "F.Fab")
			(effects
				(font
					(size 1.27 1.27)
				)
			)
		)
		(duplicate_pad_numbers_are_jumpers no)
		(fp_line
			(start 0.7874 0.4064)
			(end -0.7874 0.4064)
			(stroke
				(width 0.1524)
				(type default)
			)
			(layer "F.SilkS")
		)
		(fp_line
			(start 0.7874 -0.4064)
			(end 0.7874 0.4064)
			(stroke
				(width 0.1524)
				(type default)
			)
			(layer "F.SilkS")
		)
		(fp_line
			(start -0.7874 0.4064)
			(end -0.7874 -0.4064)
			(stroke
				(width 0.1524)
				(type default)
			)
			(layer "F.SilkS")
		)
		(fp_line
			(start -0.7874 -0.4064)
			(end 0.7874 -0.4064)
			(stroke
				(width 0.1524)
				(type default)
			)
			(layer "F.SilkS")
		)
		(fp_line
			(start 0.67945 0.3048)
			(end 0.120396 0.3048)
			(stroke
				(width 0.1)
				(type default)
			)
			(layer "F.Fab")
		)
		(fp_line
			(start 0.67945 -0.3048)
			(end 0.67945 0.3048)
			(stroke
				(width 0.1)
				(type default)
			)
			(layer "F.Fab")
		)
		(fp_line
			(start 0.12065 -0.2794)
			(end 0.12065 -0.3048)
			(stroke
				(width 0.1)
				(type default)
			)
			(layer "F.Fab")
		)
		(fp_line
			(start 0.12065 -0.3048)
			(end 0.67945 -0.3048)
			(stroke
				(width 0.1)
				(type default)
			)
			(layer "F.Fab")
		)
		(fp_line
			(start 0.120396 0.3048)
			(end 0.120396 0.2794)
			(stroke
				(width 0.1)
				(type default)
			)
			(layer "F.Fab")
		)
		(fp_line
			(start 0.120396 0.2794)
			(end -0.12065 0.2794)
			(stroke
				(width 0.1)
				(type default)
			)
			(layer "F.Fab")
		)
		(fp_line
			(start -0.12065 0.3048)
			(end -0.67945 0.3048)
			(stroke
				(width 0.1)
				(type default)
			)
			(layer "F.Fab")
		)
		(fp_line
			(start -0.12065 0.2794)
			(end -0.12065 0.3048)
			(stroke
				(width 0.1)
				(type default)
			)
			(layer "F.Fab")
		)
		(fp_line
			(start -0.12065 -0.2794)
			(end 0.12065 -0.2794)
			(stroke
				(width 0.1)
				(type default)
			)
			(layer "F.Fab")
		)
		(fp_line
			(start -0.12065 -0.305054)
			(end -0.12065 -0.2794)
			(stroke
				(width 0.1)
				(type default)
			)
			(layer "F.Fab")
		)
		(fp_line
			(start -0.67945 0.3048)
			(end -0.67945 -0.305054)
			(stroke
				(width 0.1)
				(type default)
			)
			(layer "F.Fab")
		)
		(fp_line
			(start -0.67945 -0.305054)
			(end -0.12065 -0.305054)
			(stroke
				(width 0.1)
				(type default)
			)
			(layer "F.Fab")
		)
		(pad "1" smd circle
			(at -0.40005 0 180)
			(size 0 0)
			(layers "F.Cu" "F.Mask" "F.Paste")
			(net "CLK_100M_GPU_FPGA_DP_R")
		)
		(pad "2" smd circle
			(at 0.40005 0 180)
			(size 0 0)
			(layers "F.Cu" "F.Mask" "F.Paste")
			(net "CLK_100M_GPU_FPGA_DP")
		)
	)
	(footprint ""
		(layer "F.Cu")
		(at 299.02023 -49.320196 180)
		(property "Reference" "R2241"
			(at 0 0 180)
			(layer "F.SilkS")
			(hide yes)
			(effects
				(font
					(size 1.27 1.27)
				)
			)
		)
		(property "Value" ""
			(at 0 0 180)
			(layer "F.Fab")
			(effects
				(font
					(size 1.27 1.27)
				)
			)
		)
		(duplicate_pad_numbers_are_jumpers no)
		(fp_line
			(start 0.7874 0.4064)
			(end -0.7874 0.4064)
			(stroke
				(width 0.1524)
				(type default)
			)
			(layer "F.SilkS")
		)
		(fp_line
			(start 0.7874 -0.4064)
			(end 0.7874 0.4064)
			(stroke
				(width 0.1524)
				(type default)
			)
			(layer "F.SilkS")
		)
		(fp_line
			(start -0.7874 0.4064)
			(end -0.7874 -0.4064)
			(stroke
				(width 0.1524)
				(type default)
			)
			(layer "F.SilkS")
		)
		(fp_line
			(start -0.7874 -0.4064)
			(end 0.7874 -0.4064)
			(stroke
				(width 0.1524)
				(type default)
			)
			(layer "F.SilkS")
		)
		(fp_line
			(start 0.67945 0.3048)
			(end 0.120396 0.3048)
			(stroke
				(width 0.1)
				(type default)
			)
			(layer "F.Fab")
		)
		(fp_line
			(start 0.67945 -0.3048)
			(end 0.67945 0.3048)
			(stroke
				(width 0.1)
				(type default)
			)
			(layer "F.Fab")
		)
		(fp_line
			(start 0.12065 -0.2794)
			(end 0.12065 -0.3048)
			(stroke
				(width 0.1)
				(type default)
			)
			(layer "F.Fab")
		)
		(fp_line
			(start 0.12065 -0.3048)
			(end 0.67945 -0.3048)
			(stroke
				(width 0.1)
				(type default)
			)
			(layer "F.Fab")
		)
		(fp_line
			(start 0.120396 0.3048)
			(end 0.120396 0.2794)
			(stroke
				(width 0.1)
				(type default)
			)
			(layer "F.Fab")
		)
		(fp_line
			(start 0.120396 0.2794)
			(end -0.12065 0.2794)
			(stroke
				(width 0.1)
				(type default)
			)
			(layer "F.Fab")
		)
		(fp_line
			(start -0.12065 0.3048)
			(end -0.67945 0.3048)
			(stroke
				(width 0.1)
				(type default)
			)
			(layer "F.Fab")
		)
		(fp_line
			(start -0.12065 0.2794)
			(end -0.12065 0.3048)
			(stroke
				(width 0.1)
				(type default)
			)
			(layer "F.Fab")
		)
		(fp_line
			(start -0.12065 -0.2794)
			(end 0.12065 -0.2794)
			(stroke
				(width 0.1)
				(type default)
			)
			(layer "F.Fab")
		)
		(fp_line
			(start -0.12065 -0.305054)
			(end -0.12065 -0.2794)
			(stroke
				(width 0.1)
				(type default)
			)
			(layer "F.Fab")
		)
		(fp_line
			(start -0.67945 0.3048)
			(end -0.67945 -0.305054)
			(stroke
				(width 0.1)
				(type default)
			)
			(layer "F.Fab")
		)
		(fp_line
			(start -0.67945 -0.305054)
			(end -0.12065 -0.305054)
			(stroke
				(width 0.1)
				(type default)
			)
			(layer "F.Fab")
		)
		(pad "1" smd circle
			(at -0.40005 0 180)
			(size 0 0)
			(layers "F.Cu" "F.Mask" "F.Paste")
			(net "FM_BOARD_SKU_ID1")
		)
		(pad "2" smd circle
			(at 0.40005 0 180)
			(size 0 0)
			(layers "F.Cu" "F.Mask" "F.Paste")
			(net "GND")
		)
	)
	(footprint ""
		(layer "F.Cu")
		(at 130.10388 -96.230948 -90)
		(property "Reference" "Q143"
			(at -2.479802 0.69088 0)
			(unlocked yes)
			(layer "F.SilkS")
			(effects
				(font
					(size 0.635 0.4064)
					(thickness 0.1524)
				)
			)
		)
		(property "Value" ""
			(at 0 0 270)
			(layer "F.Fab")
			(effects
				(font
					(size 1.27 1.27)
				)
			)
		)
		(duplicate_pad_numbers_are_jumpers no)
		(fp_line
			(start -1.376172 1.199896)
			(end -1.376172 -1.199896)
			(stroke
				(width 0.1524)
				(type default)
			)
			(layer "F.SilkS")
		)
		(fp_line
			(start 1.376172 1.199896)
			(end -1.376172 1.199896)
			(stroke
				(width 0.1524)
				(type default)
			)
			(layer "F.SilkS")
		)
		(fp_line
			(start 0 -0.762)
			(end 0.508 -1.199896)
			(stroke
				(width 0.1524)
				(type default)
			)
			(layer "F.SilkS")
		)
		(fp_line
			(start -1.376172 -1.199896)
			(end -0.508 -1.199896)
			(stroke
				(width 0.1524)
				(type default)
			)
			(layer "F.SilkS")
		)
		(fp_line
			(start -0.508 -1.199896)
			(end 0 -0.762)
			(stroke
				(width 0.1524)
				(type default)
			)
			(layer "F.SilkS")
		)
		(fp_line
			(start 0.508 -1.199896)
			(end 1.376172 -1.199896)
			(stroke
				(width 0.1524)
				(type default)
			)
			(layer "F.SilkS")
		)
		(fp_line
			(start 1.376172 -1.199896)
			(end 1.376172 1.199896)
			(stroke
				(width 0.1524)
				(type default)
			)
			(layer "F.SilkS")
		)
		(fp_poly
			(pts
				(xy -1.5875 -0.8763) (xy -2.3495 -1.2573) (xy -2.3495 -0.4953)
			)
			(stroke
				(width 0)
				(type default)
			)
			(fill yes)
			(layer "F.SilkS")
		)
		(fp_line
			(start -0.674878 1.100074)
			(end -0.674878 -1.100074)
			(stroke
				(width 0.1)
				(type default)
			)
			(layer "F.Fab")
		)
		(fp_line
			(start 0.674878 1.100074)
			(end -0.674878 1.100074)
			(stroke
				(width 0.1)
				(type default)
			)
			(layer "F.Fab")
		)
		(fp_line
			(start -0.674878 -1.100074)
			(end 0.674878 -1.100074)
			(stroke
				(width 0.1)
				(type default)
			)
			(layer "F.Fab")
		)
		(fp_line
			(start 0.674878 -1.100074)
			(end 0.674878 1.100074)
			(stroke
				(width 0.1)
				(type default)
			)
			(layer "F.Fab")
		)
		(fp_poly
			(pts
				(xy -1.4605 -0.7493) (xy -2.2225 -1.1303) (xy -2.2225 -0.3683)
			)
			(stroke
				(width 0)
				(type default)
			)
			(fill yes)
			(layer "F.Fab")
		)
		(pad "1" smd rect
			(at -0.899922 -0.750062 180)
			(size 0.6096 0.6096)
			(layers "F.Cu" "F.Mask" "F.Paste")
			(net "GND")
		)
		(pad "2" smd rect
			(at -0.899922 0 180)
			(size 0.4064 0.6096)
			(layers "F.Cu" "F.Mask" "F.Paste")
			(net "H_CPU0_MEMHOT_OUT_R")
		)
		(pad "3" smd rect
			(at -0.899922 0.750062 180)
			(size 0.6096 0.6096)
			(layers "F.Cu" "F.Mask" "F.Paste")
			(net "H_CPU0_MEMHOT_OUT")
		)
		(pad "4" smd rect
			(at 0.899922 0.750062 180)
			(size 0.6096 0.6096)
			(layers "F.Cu" "F.Mask" "F.Paste")
			(net "PVNN_TERM_CPU0")
		)
		(pad "5" smd rect
			(at 0.899922 0 180)
			(size 0.4064 0.6096)
			(layers "F.Cu" "F.Mask" "F.Paste")
			(net "H_CPU0_MEMHOT_OUT_VT_R_N")
		)
		(pad "6" smd rect
			(at 0.899922 -0.750062 180)
			(size 0.6096 0.6096)
			(layers "F.Cu" "F.Mask" "F.Paste")
			(net "H_CPU0_MEMHOT_OUT_VT_N")
		)
	)
	(footprint ""
		(layer "F.Cu")
		(at 225.171762 -71.192898 90)
		(property "Reference" "R3977"
			(at 0 0 90)
			(layer "F.SilkS")
			(hide yes)
			(effects
				(font
					(size 1.27 1.27)
				)
			)
		)
		(property "Value" ""
			(at 0 0 90)
			(layer "F.Fab")
			(effects
				(font
					(size 1.27 1.27)
				)
			)
		)
		(duplicate_pad_numbers_are_jumpers no)
		(fp_line
			(start 0.7874 -0.4064)
			(end 0.7874 0.4064)
			(stroke
				(width 0.1524)
				(type default)
			)
			(layer "F.SilkS")
		)
		(fp_line
			(start -0.7874 -0.4064)
			(end 0.7874 -0.4064)
			(stroke
				(width 0.1524)
				(type default)
			)
			(layer "F.SilkS")
		)
		(fp_line
			(start 0.7874 0.4064)
			(end -0.7874 0.4064)
			(stroke
				(width 0.1524)
				(type default)
			)
			(layer "F.SilkS")
		)
		(fp_line
			(start -0.7874 0.4064)
			(end -0.7874 -0.4064)
			(stroke
				(width 0.1524)
				(type default)
			)
			(layer "F.SilkS")
		)
		(fp_line
			(start -0.12065 -0.305054)
			(end -0.12065 -0.2794)
			(stroke
				(width 0.1)
				(type default)
			)
			(layer "F.Fab")
		)
		(fp_line
			(start -0.67945 -0.305054)
			(end -0.12065 -0.305054)
			(stroke
				(width 0.1)
				(type default)
			)
			(layer "F.Fab")
		)
		(fp_line
			(start 0.67945 -0.3048)
			(end 0.67945 0.3048)
			(stroke
				(width 0.1)
				(type default)
			)
			(layer "F.Fab")
		)
		(fp_line
			(start 0.12065 -0.3048)
			(end 0.67945 -0.3048)
			(stroke
				(width 0.1)
				(type default)
			)
			(layer "F.Fab")
		)
		(fp_line
			(start 0.12065 -0.2794)
			(end 0.12065 -0.3048)
			(stroke
				(width 0.1)
				(type default)
			)
			(layer "F.Fab")
		)
		(fp_line
			(start -0.12065 -0.2794)
			(end 0.12065 -0.2794)
			(stroke
				(width 0.1)
				(type default)
			)
			(layer "F.Fab")
		)
		(fp_line
			(start 0.120396 0.2794)
			(end -0.12065 0.2794)
			(stroke
				(width 0.1)
				(type default)
			)
			(layer "F.Fab")
		)
		(fp_line
			(start -0.12065 0.2794)
			(end -0.12065 0.3048)
			(stroke
				(width 0.1)
				(type default)
			)
			(layer "F.Fab")
		)
		(fp_line
			(start 0.67945 0.3048)
			(end 0.120396 0.3048)
			(stroke
				(width 0.1)
				(type default)
			)
			(layer "F.Fab")
		)
		(fp_line
			(start 0.120396 0.3048)
			(end 0.120396 0.2794)
			(stroke
				(width 0.1)
				(type default)
			)
			(layer "F.Fab")
		)
		(fp_line
			(start -0.12065 0.3048)
			(end -0.67945 0.3048)
			(stroke
				(width 0.1)
				(type default)
			)
			(layer "F.Fab")
		)
		(fp_line
			(start -0.67945 0.3048)
			(end -0.67945 -0.305054)
			(stroke
				(width 0.1)
				(type default)
			)
			(layer "F.Fab")
		)
		(pad "1" smd circle
			(at -0.40005 0 90)
			(size 0 0)
			(layers "F.Cu" "F.Mask" "F.Paste")
			(net "P3V3_AUX")
		)
		(pad "2" smd circle
			(at 0.40005 0 90)
			(size 0 0)
			(layers "F.Cu" "F.Mask" "F.Paste")
			(net "P3V3_E1S_FAULT_0")
		)
	)
	(footprint ""
		(layer "F.Cu")
		(at 152.075896 -38.575234 90)
		(property "Reference" "C2326"
			(at 0 0 90)
			(layer "F.SilkS")
			(hide yes)
			(effects
				(font
					(size 1.27 1.27)
				)
			)
		)
		(property "Value" ""
			(at 0 0 90)
			(layer "F.Fab")
			(effects
				(font
					(size 1.27 1.27)
				)
			)
		)
		(duplicate_pad_numbers_are_jumpers no)
		(fp_line
			(start 0.7874 -0.4064)
			(end 0.7874 0.4064)
			(stroke
				(width 0.1524)
				(type default)
			)
			(layer "F.SilkS")
		)
		(fp_line
			(start -0.7874 -0.4064)
			(end 0.7874 -0.4064)
			(stroke
				(width 0.1524)
				(type default)
			)
			(layer "F.SilkS")
		)
		(fp_line
			(start 0.7874 0.4064)
			(end -0.7874 0.4064)
			(stroke
				(width 0.1524)
				(type default)
			)
			(layer "F.SilkS")
		)
		(fp_line
			(start -0.7874 0.4064)
			(end -0.7874 -0.4064)
			(stroke
				(width 0.1524)
				(type default)
			)
			(layer "F.SilkS")
		)
		(fp_line
			(start -0.12065 -0.305054)
			(end -0.12065 -0.2794)
			(stroke
				(width 0.1)
				(type default)
			)
			(layer "F.Fab")
		)
		(fp_line
			(start -0.67945 -0.305054)
			(end -0.12065 -0.305054)
			(stroke
				(width 0.1)
				(type default)
			)
			(layer "F.Fab")
		)
		(fp_line
			(start 0.67945 -0.3048)
			(end 0.67945 0.3048)
			(stroke
				(width 0.1)
				(type default)
			)
			(layer "F.Fab")
		)
		(fp_line
			(start 0.12065 -0.3048)
			(end 0.67945 -0.3048)
			(stroke
				(width 0.1)
				(type default)
			)
			(layer "F.Fab")
		)
		(fp_line
			(start 0.12065 -0.2794)
			(end 0.12065 -0.3048)
			(stroke
				(width 0.1)
				(type default)
			)
			(layer "F.Fab")
		)
		(fp_line
			(start -0.12065 -0.2794)
			(end 0.12065 -0.2794)
			(stroke
				(width 0.1)
				(type default)
			)
			(layer "F.Fab")
		)
		(fp_line
			(start 0.120396 0.2794)
			(end -0.12065 0.2794)
			(stroke
				(width 0.1)
				(type default)
			)
			(layer "F.Fab")
		)
		(fp_line
			(start -0.12065 0.2794)
			(end -0.12065 0.3048)
			(stroke
				(width 0.1)
				(type default)
			)
			(layer "F.Fab")
		)
		(fp_line
			(start 0.67945 0.3048)
			(end 0.120396 0.3048)
			(stroke
				(width 0.1)
				(type default)
			)
			(layer "F.Fab")
		)
		(fp_line
			(start 0.120396 0.3048)
			(end 0.120396 0.2794)
			(stroke
				(width 0.1)
				(type default)
			)
			(layer "F.Fab")
		)
		(fp_line
			(start -0.12065 0.3048)
			(end -0.67945 0.3048)
			(stroke
				(width 0.1)
				(type default)
			)
			(layer "F.Fab")
		)
		(fp_line
			(start -0.67945 0.3048)
			(end -0.67945 -0.305054)
			(stroke
				(width 0.1)
				(type default)
			)
			(layer "F.Fab")
		)
		(pad "1" smd circle
			(at -0.40005 0 90)
			(size 0 0)
			(layers "F.Cu" "F.Mask" "F.Paste")
			(net "USB_HUB_2_XTAL_IN")
		)
		(pad "2" smd circle
			(at 0.40005 0 90)
			(size 0 0)
			(layers "F.Cu" "F.Mask" "F.Paste")
			(net "GND")
		)
	)
	(footprint ""
		(layer "F.Cu")
		(at 218.08948 -125.8062 180)
		(property "Reference" "R4807"
			(at 0 0 180)
			(layer "F.SilkS")
			(hide yes)
			(effects
				(font
					(size 1.27 1.27)
				)
			)
		)
		(property "Value" ""
			(at 0 0 180)
			(layer "F.Fab")
			(effects
				(font
					(size 1.27 1.27)
				)
			)
		)
		(duplicate_pad_numbers_are_jumpers no)
		(fp_line
			(start 0.7874 0.4064)
			(end -0.7874 0.4064)
			(stroke
				(width 0.1524)
				(type default)
			)
			(layer "F.SilkS")
		)
		(fp_line
			(start 0.7874 -0.4064)
			(end 0.7874 0.4064)
			(stroke
				(width 0.1524)
				(type default)
			)
			(layer "F.SilkS")
		)
		(fp_line
			(start -0.7874 0.4064)
			(end -0.7874 -0.4064)
			(stroke
				(width 0.1524)
				(type default)
			)
			(layer "F.SilkS")
		)
		(fp_line
			(start -0.7874 -0.4064)
			(end 0.7874 -0.4064)
			(stroke
				(width 0.1524)
				(type default)
			)
			(layer "F.SilkS")
		)
		(fp_line
			(start 0.67945 0.3048)
			(end 0.120396 0.3048)
			(stroke
				(width 0.1)
				(type default)
			)
			(layer "F.Fab")
		)
		(fp_line
			(start 0.67945 -0.3048)
			(end 0.67945 0.3048)
			(stroke
				(width 0.1)
				(type default)
			)
			(layer "F.Fab")
		)
		(fp_line
			(start 0.12065 -0.2794)
			(end 0.12065 -0.3048)
			(stroke
				(width 0.1)
				(type default)
			)
			(layer "F.Fab")
		)
		(fp_line
			(start 0.12065 -0.3048)
			(end 0.67945 -0.3048)
			(stroke
				(width 0.1)
				(type default)
			)
			(layer "F.Fab")
		)
		(fp_line
			(start 0.120396 0.3048)
			(end 0.120396 0.2794)
			(stroke
				(width 0.1)
				(type default)
			)
			(layer "F.Fab")
		)
		(fp_line
			(start 0.120396 0.2794)
			(end -0.12065 0.2794)
			(stroke
				(width 0.1)
				(type default)
			)
			(layer "F.Fab")
		)
		(fp_line
			(start -0.12065 0.3048)
			(end -0.67945 0.3048)
			(stroke
				(width 0.1)
				(type default)
			)
			(layer "F.Fab")
		)
		(fp_line
			(start -0.12065 0.2794)
			(end -0.12065 0.3048)
			(stroke
				(width 0.1)
				(type default)
			)
			(layer "F.Fab")
		)
		(fp_line
			(start -0.12065 -0.2794)
			(end 0.12065 -0.2794)
			(stroke
				(width 0.1)
				(type default)
			)
			(layer "F.Fab")
		)
		(fp_line
			(start -0.12065 -0.305054)
			(end -0.12065 -0.2794)
			(stroke
				(width 0.1)
				(type default)
			)
			(layer "F.Fab")
		)
		(fp_line
			(start -0.67945 0.3048)
			(end -0.67945 -0.305054)
			(stroke
				(width 0.1)
				(type default)
			)
			(layer "F.Fab")
		)
		(fp_line
			(start -0.67945 -0.305054)
			(end -0.12065 -0.305054)
			(stroke
				(width 0.1)
				(type default)
			)
			(layer "F.Fab")
		)
		(pad "1" smd circle
			(at -0.40005 0 180)
			(size 0 0)
			(layers "F.Cu" "F.Mask" "F.Paste")
			(net "PWRGD_DSW_PWROK_R1")
		)
		(pad "2" smd circle
			(at 0.40005 0 180)
			(size 0 0)
			(layers "F.Cu" "F.Mask" "F.Paste")
			(net "PWRGD_DSW_PWROK_R2")
		)
	)
	(footprint ""
		(layer "F.Cu")
		(at 113.494312 -137.799826 180)
		(property "Reference" "R539"
			(at 0 0 180)
			(layer "F.SilkS")
			(hide yes)
			(effects
				(font
					(size 1.27 1.27)
				)
			)
		)
		(property "Value" ""
			(at 0 0 180)
			(layer "F.Fab")
			(effects
				(font
					(size 1.27 1.27)
				)
			)
		)
		(duplicate_pad_numbers_are_jumpers no)
		(fp_line
			(start 0.7874 0.4064)
			(end -0.7874 0.4064)
			(stroke
				(width 0.1524)
				(type default)
			)
			(layer "F.SilkS")
		)
		(fp_line
			(start 0.7874 -0.4064)
			(end 0.7874 0.4064)
			(stroke
				(width 0.1524)
				(type default)
			)
			(layer "F.SilkS")
		)
		(fp_line
			(start -0.7874 0.4064)
			(end -0.7874 -0.4064)
			(stroke
				(width 0.1524)
				(type default)
			)
			(layer "F.SilkS")
		)
		(fp_line
			(start -0.7874 -0.4064)
			(end 0.7874 -0.4064)
			(stroke
				(width 0.1524)
				(type default)
			)
			(layer "F.SilkS")
		)
		(fp_line
			(start 0.67945 0.3048)
			(end 0.120396 0.3048)
			(stroke
				(width 0.1)
				(type default)
			)
			(layer "F.Fab")
		)
		(fp_line
			(start 0.67945 -0.3048)
			(end 0.67945 0.3048)
			(stroke
				(width 0.1)
				(type default)
			)
			(layer "F.Fab")
		)
		(fp_line
			(start 0.12065 -0.2794)
			(end 0.12065 -0.3048)
			(stroke
				(width 0.1)
				(type default)
			)
			(layer "F.Fab")
		)
		(fp_line
			(start 0.12065 -0.3048)
			(end 0.67945 -0.3048)
			(stroke
				(width 0.1)
				(type default)
			)
			(layer "F.Fab")
		)
		(fp_line
			(start 0.120396 0.3048)
			(end 0.120396 0.2794)
			(stroke
				(width 0.1)
				(type default)
			)
			(layer "F.Fab")
		)
		(fp_line
			(start 0.120396 0.2794)
			(end -0.12065 0.2794)
			(stroke
				(width 0.1)
				(type default)
			)
			(layer "F.Fab")
		)
		(fp_line
			(start -0.12065 0.3048)
			(end -0.67945 0.3048)
			(stroke
				(width 0.1)
				(type default)
			)
			(layer "F.Fab")
		)
		(fp_line
			(start -0.12065 0.2794)
			(end -0.12065 0.3048)
			(stroke
				(width 0.1)
				(type default)
			)
			(layer "F.Fab")
		)
		(fp_line
			(start -0.12065 -0.2794)
			(end 0.12065 -0.2794)
			(stroke
				(width 0.1)
				(type default)
			)
			(layer "F.Fab")
		)
		(fp_line
			(start -0.12065 -0.305054)
			(end -0.12065 -0.2794)
			(stroke
				(width 0.1)
				(type default)
			)
			(layer "F.Fab")
		)
		(fp_line
			(start -0.67945 0.3048)
			(end -0.67945 -0.305054)
			(stroke
				(width 0.1)
				(type default)
			)
			(layer "F.Fab")
		)
		(fp_line
			(start -0.67945 -0.305054)
			(end -0.12065 -0.305054)
			(stroke
				(width 0.1)
				(type default)
			)
			(layer "F.Fab")
		)
		(pad "1" smd circle
			(at -0.40005 0 180)
			(size 0 0)
			(layers "F.Cu" "F.Mask" "F.Paste")
			(net "PCA9548_PCIE3_ADDR1")
		)
		(pad "2" smd circle
			(at 0.40005 0 180)
			(size 0 0)
			(layers "F.Cu" "F.Mask" "F.Paste")
			(net "GND")
		)
	)
	(footprint ""
		(layer "F.Cu")
		(at 363.22 -415.889948 180)
		(property "Reference" "R4560"
			(at 0 0 180)
			(layer "F.SilkS")
			(hide yes)
			(effects
				(font
					(size 1.27 1.27)
				)
			)
		)
		(property "Value" ""
			(at 0 0 180)
			(layer "F.Fab")
			(effects
				(font
					(size 1.27 1.27)
				)
			)
		)
		(duplicate_pad_numbers_are_jumpers no)
		(fp_line
			(start 0.7874 0.4064)
			(end -0.7874 0.4064)
			(stroke
				(width 0.1524)
				(type default)
			)
			(layer "F.SilkS")
		)
		(fp_line
			(start 0.7874 -0.4064)
			(end 0.7874 0.4064)
			(stroke
				(width 0.1524)
				(type default)
			)
			(layer "F.SilkS")
		)
		(fp_line
			(start -0.7874 0.4064)
			(end -0.7874 -0.4064)
			(stroke
				(width 0.1524)
				(type default)
			)
			(layer "F.SilkS")
		)
		(fp_line
			(start -0.7874 -0.4064)
			(end 0.7874 -0.4064)
			(stroke
				(width 0.1524)
				(type default)
			)
			(layer "F.SilkS")
		)
		(fp_line
			(start 0.67945 0.3048)
			(end 0.120396 0.3048)
			(stroke
				(width 0.1)
				(type default)
			)
			(layer "F.Fab")
		)
		(fp_line
			(start 0.67945 -0.3048)
			(end 0.67945 0.3048)
			(stroke
				(width 0.1)
				(type default)
			)
			(layer "F.Fab")
		)
		(fp_line
			(start 0.12065 -0.2794)
			(end 0.12065 -0.3048)
			(stroke
				(width 0.1)
				(type default)
			)
			(layer "F.Fab")
		)
		(fp_line
			(start 0.12065 -0.3048)
			(end 0.67945 -0.3048)
			(stroke
				(width 0.1)
				(type default)
			)
			(layer "F.Fab")
		)
		(fp_line
			(start 0.120396 0.3048)
			(end 0.120396 0.2794)
			(stroke
				(width 0.1)
				(type default)
			)
			(layer "F.Fab")
		)
		(fp_line
			(start 0.120396 0.2794)
			(end -0.12065 0.2794)
			(stroke
				(width 0.1)
				(type default)
			)
			(layer "F.Fab")
		)
		(fp_line
			(start -0.12065 0.3048)
			(end -0.67945 0.3048)
			(stroke
				(width 0.1)
				(type default)
			)
			(layer "F.Fab")
		)
		(fp_line
			(start -0.12065 0.2794)
			(end -0.12065 0.3048)
			(stroke
				(width 0.1)
				(type default)
			)
			(layer "F.Fab")
		)
		(fp_line
			(start -0.12065 -0.2794)
			(end 0.12065 -0.2794)
			(stroke
				(width 0.1)
				(type default)
			)
			(layer "F.Fab")
		)
		(fp_line
			(start -0.12065 -0.305054)
			(end -0.12065 -0.2794)
			(stroke
				(width 0.1)
				(type default)
			)
			(layer "F.Fab")
		)
		(fp_line
			(start -0.67945 0.3048)
			(end -0.67945 -0.305054)
			(stroke
				(width 0.1)
				(type default)
			)
			(layer "F.Fab")
		)
		(fp_line
			(start -0.67945 -0.305054)
			(end -0.12065 -0.305054)
			(stroke
				(width 0.1)
				(type default)
			)
			(layer "F.Fab")
		)
		(pad "1" smd circle
			(at -0.40005 0 180)
			(size 0 0)
			(layers "F.Cu" "F.Mask" "F.Paste")
			(net "P3V3_AUX")
		)
		(pad "2" smd circle
			(at 0.40005 0 180)
			(size 0 0)
			(layers "F.Cu" "F.Mask" "F.Paste")
			(net "SWB_HSC_PWRGD_N")
		)
	)
	(footprint ""
		(layer "F.Cu")
		(at 445.090296 -51.305968 -90)
		(property "Reference" "C1332"
			(at 0 0 270)
			(layer "F.SilkS")
			(hide yes)
			(effects
				(font
					(size 1.27 1.27)
				)
			)
		)
		(property "Value" ""
			(at 0 0 270)
			(layer "F.Fab")
			(effects
				(font
					(size 1.27 1.27)
				)
			)
		)
		(duplicate_pad_numbers_are_jumpers no)
		(fp_line
			(start -0.7874 0.4064)
			(end -0.7874 -0.4064)
			(stroke
				(width 0.1524)
				(type default)
			)
			(layer "F.SilkS")
		)
		(fp_line
			(start 0.7874 0.4064)
			(end -0.7874 0.4064)
			(stroke
				(width 0.1524)
				(type default)
			)
			(layer "F.SilkS")
		)
		(fp_line
			(start -0.7874 -0.4064)
			(end 0.7874 -0.4064)
			(stroke
				(width 0.1524)
				(type default)
			)
			(layer "F.SilkS")
		)
		(fp_line
			(start 0.7874 -0.4064)
			(end 0.7874 0.4064)
			(stroke
				(width 0.1524)
				(type default)
			)
			(layer "F.SilkS")
		)
		(fp_line
			(start -0.67945 0.3048)
			(end -0.67945 -0.305054)
			(stroke
				(width 0.1)
				(type default)
			)
			(layer "F.Fab")
		)
		(fp_line
			(start -0.12065 0.3048)
			(end -0.67945 0.3048)
			(stroke
				(width 0.1)
				(type default)
			)
			(layer "F.Fab")
		)
		(fp_line
			(start 0.120396 0.3048)
			(end 0.120396 0.2794)
			(stroke
				(width 0.1)
				(type default)
			)
			(layer "F.Fab")
		)
		(fp_line
			(start 0.67945 0.3048)
			(end 0.120396 0.3048)
			(stroke
				(width 0.1)
				(type default)
			)
			(layer "F.Fab")
		)
		(fp_line
			(start -0.12065 0.2794)
			(end -0.12065 0.3048)
			(stroke
				(width 0.1)
				(type default)
			)
			(layer "F.Fab")
		)
		(fp_line
			(start 0.120396 0.2794)
			(end -0.12065 0.2794)
			(stroke
				(width 0.1)
				(type default)
			)
			(layer "F.Fab")
		)
		(fp_line
			(start -0.12065 -0.2794)
			(end 0.12065 -0.2794)
			(stroke
				(width 0.1)
				(type default)
			)
			(layer "F.Fab")
		)
		(fp_line
			(start 0.12065 -0.2794)
			(end 0.12065 -0.3048)
			(stroke
				(width 0.1)
				(type default)
			)
			(layer "F.Fab")
		)
		(fp_line
			(start 0.12065 -0.3048)
			(end 0.67945 -0.3048)
			(stroke
				(width 0.1)
				(type default)
			)
			(layer "F.Fab")
		)
		(fp_line
			(start 0.67945 -0.3048)
			(end 0.67945 0.3048)
			(stroke
				(width 0.1)
				(type default)
			)
			(layer "F.Fab")
		)
		(fp_line
			(start -0.67945 -0.305054)
			(end -0.12065 -0.305054)
			(stroke
				(width 0.1)
				(type default)
			)
			(layer "F.Fab")
		)
		(fp_line
			(start -0.12065 -0.305054)
			(end -0.12065 -0.2794)
			(stroke
				(width 0.1)
				(type default)
			)
			(layer "F.Fab")
		)
		(pad "1" smd circle
			(at -0.40005 0 270)
			(size 0 0)
			(layers "F.Cu" "F.Mask" "F.Paste")
			(net "P3V3_AUX")
		)
		(pad "2" smd circle
			(at 0.40005 0 270)
			(size 0 0)
			(layers "F.Cu" "F.Mask" "F.Paste")
			(net "GND")
		)
	)
	(footprint ""
		(layer "F.Cu")
		(at 134.2136 -125.758448)
		(property "Reference" "R3151"
			(at 0 0 0)
			(layer "F.SilkS")
			(hide yes)
			(effects
				(font
					(size 1.27 1.27)
				)
			)
		)
		(property "Value" ""
			(at 0 0 0)
			(layer "F.Fab")
			(effects
				(font
					(size 1.27 1.27)
				)
			)
		)
		(duplicate_pad_numbers_are_jumpers no)
		(fp_line
			(start -0.7874 -0.4064)
			(end 0.7874 -0.4064)
			(stroke
				(width 0.1524)
				(type default)
			)
			(layer "F.SilkS")
		)
		(fp_line
			(start -0.7874 0.4064)
			(end -0.7874 -0.4064)
			(stroke
				(width 0.1524)
				(type default)
			)
			(layer "F.SilkS")
		)
		(fp_line
			(start 0.7874 -0.4064)
			(end 0.7874 0.4064)
			(stroke
				(width 0.1524)
				(type default)
			)
			(layer "F.SilkS")
		)
		(fp_line
			(start 0.7874 0.4064)
			(end -0.7874 0.4064)
			(stroke
				(width 0.1524)
				(type default)
			)
			(layer "F.SilkS")
		)
		(fp_line
			(start -0.67945 -0.305054)
			(end -0.12065 -0.305054)
			(stroke
				(width 0.1)
				(type default)
			)
			(layer "F.Fab")
		)
		(fp_line
			(start -0.67945 0.3048)
			(end -0.67945 -0.305054)
			(stroke
				(width 0.1)
				(type default)
			)
			(layer "F.Fab")
		)
		(fp_line
			(start -0.12065 -0.305054)
			(end -0.12065 -0.2794)
			(stroke
				(width 0.1)
				(type default)
			)
			(layer "F.Fab")
		)
		(fp_line
			(start -0.12065 -0.2794)
			(end 0.12065 -0.2794)
			(stroke
				(width 0.1)
				(type default)
			)
			(layer "F.Fab")
		)
		(fp_line
			(start -0.12065 0.2794)
			(end -0.12065 0.3048)
			(stroke
				(width 0.1)
				(type default)
			)
			(layer "F.Fab")
		)
		(fp_line
			(start -0.12065 0.3048)
			(end -0.67945 0.3048)
			(stroke
				(width 0.1)
				(type default)
			)
			(layer "F.Fab")
		)
		(fp_line
			(start 0.120396 0.2794)
			(end -0.12065 0.2794)
			(stroke
				(width 0.1)
				(type default)
			)
			(layer "F.Fab")
		)
		(fp_line
			(start 0.120396 0.3048)
			(end 0.120396 0.2794)
			(stroke
				(width 0.1)
				(type default)
			)
			(layer "F.Fab")
		)
		(fp_line
			(start 0.12065 -0.3048)
			(end 0.67945 -0.3048)
			(stroke
				(width 0.1)
				(type default)
			)
			(layer "F.Fab")
		)
		(fp_line
			(start 0.12065 -0.2794)
			(end 0.12065 -0.3048)
			(stroke
				(width 0.1)
				(type default)
			)
			(layer "F.Fab")
		)
		(fp_line
			(start 0.67945 -0.3048)
			(end 0.67945 0.3048)
			(stroke
				(width 0.1)
				(type default)
			)
			(layer "F.Fab")
		)
		(fp_line
			(start 0.67945 0.3048)
			(end 0.120396 0.3048)
			(stroke
				(width 0.1)
				(type default)
			)
			(layer "F.Fab")
		)
		(pad "1" smd circle
			(at -0.40005 0)
			(size 0 0)
			(layers "F.Cu" "F.Mask" "F.Paste")
			(net "P3V3_AUX")
		)
		(pad "2" smd circle
			(at 0.40005 0)
			(size 0 0)
			(layers "F.Cu" "F.Mask" "F.Paste")
			(net "PD_SMB_OCP2_HP_ADD1")
		)
	)
	(footprint ""
		(layer "F.Cu")
		(at 266.032234 -94.192598 90)
		(property "Reference" "C172"
			(at 0 0 90)
			(layer "F.SilkS")
			(hide yes)
			(effects
				(font
					(size 1.27 1.27)
				)
			)
		)
		(property "Value" ""
			(at 0 0 90)
			(layer "F.Fab")
			(effects
				(font
					(size 1.27 1.27)
				)
			)
		)
		(duplicate_pad_numbers_are_jumpers no)
		(fp_line
			(start 1.2954 -0.5842)
			(end 1.2954 0.5842)
			(stroke
				(width 0.1524)
				(type default)
			)
			(layer "F.SilkS")
		)
		(fp_line
			(start 0 -0.5842)
			(end 0 0.5842)
			(stroke
				(width 0.1524)
				(type default)
			)
			(layer "F.SilkS")
		)
		(fp_line
			(start -1.2954 -0.5842)
			(end 1.2954 -0.5842)
			(stroke
				(width 0.1524)
				(type default)
			)
			(layer "F.SilkS")
		)
		(fp_line
			(start 1.2954 0.5842)
			(end -1.2954 0.5842)
			(stroke
				(width 0.1524)
				(type default)
			)
			(layer "F.SilkS")
		)
		(fp_line
			(start -1.2954 0.5842)
			(end -1.2954 -0.5842)
			(stroke
				(width 0.1524)
				(type default)
			)
			(layer "F.SilkS")
		)
		(fp_line
			(start 0.8636 -0.4572)
			(end 0.8636 -0.4064)
			(stroke
				(width 0.1)
				(type default)
			)
			(layer "F.Fab")
		)
		(fp_line
			(start -0.8636 -0.4572)
			(end 0.8636 -0.4572)
			(stroke
				(width 0.1)
				(type default)
			)
			(layer "F.Fab")
		)
		(fp_line
			(start 1.1938 -0.4064)
			(end 1.1938 0.4064)
			(stroke
				(width 0.1)
				(type default)
			)
			(layer "F.Fab")
		)
		(fp_line
			(start 0.8636 -0.4064)
			(end 1.1938 -0.4064)
			(stroke
				(width 0.1)
				(type default)
			)
			(layer "F.Fab")
		)
		(fp_line
			(start -0.8636 -0.4064)
			(end -0.8636 -0.4572)
			(stroke
				(width 0.1)
				(type default)
			)
			(layer "F.Fab")
		)
		(fp_line
			(start -1.1938 -0.4064)
			(end -0.8636 -0.4064)
			(stroke
				(width 0.1)
				(type default)
			)
			(layer "F.Fab")
		)
		(fp_line
			(start 1.1938 0.4064)
			(end 0.8636 0.4064)
			(stroke
				(width 0.1)
				(type default)
			)
			(layer "F.Fab")
		)
		(fp_line
			(start 0.8636 0.4064)
			(end 0.8636 0.4572)
			(stroke
				(width 0.1)
				(type default)
			)
			(layer "F.Fab")
		)
		(fp_line
			(start -0.8636 0.4064)
			(end -1.1938 0.4064)
			(stroke
				(width 0.1)
				(type default)
			)
			(layer "F.Fab")
		)
		(fp_line
			(start -1.1938 0.4064)
			(end -1.1938 -0.4064)
			(stroke
				(width 0.1)
				(type default)
			)
			(layer "F.Fab")
		)
		(fp_line
			(start 0.8636 0.4572)
			(end -0.8636 0.4572)
			(stroke
				(width 0.1)
				(type default)
			)
			(layer "F.Fab")
		)
		(fp_line
			(start -0.8636 0.4572)
			(end -0.8636 0.4064)
			(stroke
				(width 0.1)
				(type default)
			)
			(layer "F.Fab")
		)
		(pad "1" smd rect
			(at -0.7366 0)
			(size 0.7112 0.8128)
			(layers "F.Cu" "F.Mask" "F.Paste")
			(net "P3V3_AUX_CLK_GEN_VDDA100M_CK440")
		)
		(pad "2" smd rect
			(at 0.7366 0)
			(size 0.7112 0.8128)
			(layers "F.Cu" "F.Mask" "F.Paste")
			(net "GND")
		)
	)
	(footprint ""
		(layer "F.Cu")
		(at 298.66082 -421.41521 90)
		(property "Reference" "R4141"
			(at 0 0 90)
			(layer "F.SilkS")
			(hide yes)
			(effects
				(font
					(size 1.27 1.27)
				)
			)
		)
		(property "Value" ""
			(at 0 0 90)
			(layer "F.Fab")
			(effects
				(font
					(size 1.27 1.27)
				)
			)
		)
		(duplicate_pad_numbers_are_jumpers no)
		(fp_line
			(start 0.7874 -0.4064)
			(end 0.7874 0.4064)
			(stroke
				(width 0.1524)
				(type default)
			)
			(layer "F.SilkS")
		)
		(fp_line
			(start -0.7874 -0.4064)
			(end 0.7874 -0.4064)
			(stroke
				(width 0.1524)
				(type default)
			)
			(layer "F.SilkS")
		)
		(fp_line
			(start 0.7874 0.4064)
			(end -0.7874 0.4064)
			(stroke
				(width 0.1524)
				(type default)
			)
			(layer "F.SilkS")
		)
		(fp_line
			(start -0.7874 0.4064)
			(end -0.7874 -0.4064)
			(stroke
				(width 0.1524)
				(type default)
			)
			(layer "F.SilkS")
		)
		(fp_line
			(start -0.12065 -0.305054)
			(end -0.12065 -0.2794)
			(stroke
				(width 0.1)
				(type default)
			)
			(layer "F.Fab")
		)
		(fp_line
			(start -0.67945 -0.305054)
			(end -0.12065 -0.305054)
			(stroke
				(width 0.1)
				(type default)
			)
			(layer "F.Fab")
		)
		(fp_line
			(start 0.67945 -0.3048)
			(end 0.67945 0.3048)
			(stroke
				(width 0.1)
				(type default)
			)
			(layer "F.Fab")
		)
		(fp_line
			(start 0.12065 -0.3048)
			(end 0.67945 -0.3048)
			(stroke
				(width 0.1)
				(type default)
			)
			(layer "F.Fab")
		)
		(fp_line
			(start 0.12065 -0.2794)
			(end 0.12065 -0.3048)
			(stroke
				(width 0.1)
				(type default)
			)
			(layer "F.Fab")
		)
		(fp_line
			(start -0.12065 -0.2794)
			(end 0.12065 -0.2794)
			(stroke
				(width 0.1)
				(type default)
			)
			(layer "F.Fab")
		)
		(fp_line
			(start 0.120396 0.2794)
			(end -0.12065 0.2794)
			(stroke
				(width 0.1)
				(type default)
			)
			(layer "F.Fab")
		)
		(fp_line
			(start -0.12065 0.2794)
			(end -0.12065 0.3048)
			(stroke
				(width 0.1)
				(type default)
			)
			(layer "F.Fab")
		)
		(fp_line
			(start 0.67945 0.3048)
			(end 0.120396 0.3048)
			(stroke
				(width 0.1)
				(type default)
			)
			(layer "F.Fab")
		)
		(fp_line
			(start 0.120396 0.3048)
			(end 0.120396 0.2794)
			(stroke
				(width 0.1)
				(type default)
			)
			(layer "F.Fab")
		)
		(fp_line
			(start -0.12065 0.3048)
			(end -0.67945 0.3048)
			(stroke
				(width 0.1)
				(type default)
			)
			(layer "F.Fab")
		)
		(fp_line
			(start -0.67945 0.3048)
			(end -0.67945 -0.305054)
			(stroke
				(width 0.1)
				(type default)
			)
			(layer "F.Fab")
		)
		(pad "1" smd circle
			(at -0.40005 0 90)
			(size 0 0)
			(layers "F.Cu" "F.Mask" "F.Paste")
			(net "P3V3_AUX")
		)
		(pad "2" smd circle
			(at 0.40005 0 90)
			(size 0 0)
			(layers "F.Cu" "F.Mask" "F.Paste")
			(net "GPU_3V3IO_RSVD5_FFU_ISO")
		)
	)
	(footprint ""
		(layer "F.Cu")
		(at 15.436596 -387.119876 180)
		(property "Reference" "R3293"
			(at 0 0 180)
			(layer "F.SilkS")
			(hide yes)
			(effects
				(font
					(size 1.27 1.27)
				)
			)
		)
		(property "Value" ""
			(at 0 0 180)
			(layer "F.Fab")
			(effects
				(font
					(size 1.27 1.27)
				)
			)
		)
		(duplicate_pad_numbers_are_jumpers no)
		(fp_line
			(start 0.7874 0.4064)
			(end -0.7874 0.4064)
			(stroke
				(width 0.1524)
				(type default)
			)
			(layer "F.SilkS")
		)
		(fp_line
			(start 0.7874 -0.4064)
			(end 0.7874 0.4064)
			(stroke
				(width 0.1524)
				(type default)
			)
			(layer "F.SilkS")
		)
		(fp_line
			(start -0.7874 0.4064)
			(end -0.7874 -0.4064)
			(stroke
				(width 0.1524)
				(type default)
			)
			(layer "F.SilkS")
		)
		(fp_line
			(start -0.7874 -0.4064)
			(end 0.7874 -0.4064)
			(stroke
				(width 0.1524)
				(type default)
			)
			(layer "F.SilkS")
		)
		(fp_line
			(start 0.67945 0.3048)
			(end 0.120396 0.3048)
			(stroke
				(width 0.1)
				(type default)
			)
			(layer "F.Fab")
		)
		(fp_line
			(start 0.67945 -0.3048)
			(end 0.67945 0.3048)
			(stroke
				(width 0.1)
				(type default)
			)
			(layer "F.Fab")
		)
		(fp_line
			(start 0.12065 -0.2794)
			(end 0.12065 -0.3048)
			(stroke
				(width 0.1)
				(type default)
			)
			(layer "F.Fab")
		)
		(fp_line
			(start 0.12065 -0.3048)
			(end 0.67945 -0.3048)
			(stroke
				(width 0.1)
				(type default)
			)
			(layer "F.Fab")
		)
		(fp_line
			(start 0.120396 0.3048)
			(end 0.120396 0.2794)
			(stroke
				(width 0.1)
				(type default)
			)
			(layer "F.Fab")
		)
		(fp_line
			(start 0.120396 0.2794)
			(end -0.12065 0.2794)
			(stroke
				(width 0.1)
				(type default)
			)
			(layer "F.Fab")
		)
		(fp_line
			(start -0.12065 0.3048)
			(end -0.67945 0.3048)
			(stroke
				(width 0.1)
				(type default)
			)
			(layer "F.Fab")
		)
		(fp_line
			(start -0.12065 0.2794)
			(end -0.12065 0.3048)
			(stroke
				(width 0.1)
				(type default)
			)
			(layer "F.Fab")
		)
		(fp_line
			(start -0.12065 -0.2794)
			(end 0.12065 -0.2794)
			(stroke
				(width 0.1)
				(type default)
			)
			(layer "F.Fab")
		)
		(fp_line
			(start -0.12065 -0.305054)
			(end -0.12065 -0.2794)
			(stroke
				(width 0.1)
				(type default)
			)
			(layer "F.Fab")
		)
		(fp_line
			(start -0.67945 0.3048)
			(end -0.67945 -0.305054)
			(stroke
				(width 0.1)
				(type default)
			)
			(layer "F.Fab")
		)
		(fp_line
			(start -0.67945 -0.305054)
			(end -0.12065 -0.305054)
			(stroke
				(width 0.1)
				(type default)
			)
			(layer "F.Fab")
		)
		(pad "1" smd circle
			(at -0.40005 0 180)
			(size 0 0)
			(layers "F.Cu" "F.Mask" "F.Paste")
			(net "FM_P2E_MODE")
		)
		(pad "2" smd circle
			(at 0.40005 0 180)
			(size 0 0)
			(layers "F.Cu" "F.Mask" "F.Paste")
			(net "GND")
		)
	)
	(footprint ""
		(layer "F.Cu")
		(at 81.8896 -41.036748 180)
		(property "Reference" "C2347"
			(at 0 0 180)
			(layer "F.SilkS")
			(hide yes)
			(effects
				(font
					(size 1.27 1.27)
				)
			)
		)
		(property "Value" ""
			(at 0 0 180)
			(layer "F.Fab")
			(effects
				(font
					(size 1.27 1.27)
				)
			)
		)
		(duplicate_pad_numbers_are_jumpers no)
		(fp_line
			(start 0.7874 0.4064)
			(end -0.7874 0.4064)
			(stroke
				(width 0.1524)
				(type default)
			)
			(layer "F.SilkS")
		)
		(fp_line
			(start 0.7874 -0.4064)
			(end 0.7874 0.4064)
			(stroke
				(width 0.1524)
				(type default)
			)
			(layer "F.SilkS")
		)
		(fp_line
			(start -0.7874 0.4064)
			(end -0.7874 -0.4064)
			(stroke
				(width 0.1524)
				(type default)
			)
			(layer "F.SilkS")
		)
		(fp_line
			(start -0.7874 -0.4064)
			(end 0.7874 -0.4064)
			(stroke
				(width 0.1524)
				(type default)
			)
			(layer "F.SilkS")
		)
		(fp_line
			(start 0.67945 0.3048)
			(end 0.120396 0.3048)
			(stroke
				(width 0.1)
				(type default)
			)
			(layer "F.Fab")
		)
		(fp_line
			(start 0.67945 -0.3048)
			(end 0.67945 0.3048)
			(stroke
				(width 0.1)
				(type default)
			)
			(layer "F.Fab")
		)
		(fp_line
			(start 0.12065 -0.2794)
			(end 0.12065 -0.3048)
			(stroke
				(width 0.1)
				(type default)
			)
			(layer "F.Fab")
		)
		(fp_line
			(start 0.12065 -0.3048)
			(end 0.67945 -0.3048)
			(stroke
				(width 0.1)
				(type default)
			)
			(layer "F.Fab")
		)
		(fp_line
			(start 0.120396 0.3048)
			(end 0.120396 0.2794)
			(stroke
				(width 0.1)
				(type default)
			)
			(layer "F.Fab")
		)
		(fp_line
			(start 0.120396 0.2794)
			(end -0.12065 0.2794)
			(stroke
				(width 0.1)
				(type default)
			)
			(layer "F.Fab")
		)
		(fp_line
			(start -0.12065 0.3048)
			(end -0.67945 0.3048)
			(stroke
				(width 0.1)
				(type default)
			)
			(layer "F.Fab")
		)
		(fp_line
			(start -0.12065 0.2794)
			(end -0.12065 0.3048)
			(stroke
				(width 0.1)
				(type default)
			)
			(layer "F.Fab")
		)
		(fp_line
			(start -0.12065 -0.2794)
			(end 0.12065 -0.2794)
			(stroke
				(width 0.1)
				(type default)
			)
			(layer "F.Fab")
		)
		(fp_line
			(start -0.12065 -0.305054)
			(end -0.12065 -0.2794)
			(stroke
				(width 0.1)
				(type default)
			)
			(layer "F.Fab")
		)
		(fp_line
			(start -0.67945 0.3048)
			(end -0.67945 -0.305054)
			(stroke
				(width 0.1)
				(type default)
			)
			(layer "F.Fab")
		)
		(fp_line
			(start -0.67945 -0.305054)
			(end -0.12065 -0.305054)
			(stroke
				(width 0.1)
				(type default)
			)
			(layer "F.Fab")
		)
		(pad "1" smd circle
			(at -0.40005 0 180)
			(size 0 0)
			(layers "F.Cu" "F.Mask" "F.Paste")
			(net "P3V3_AUX")
		)
		(pad "2" smd circle
			(at 0.40005 0 180)
			(size 0 0)
			(layers "F.Cu" "F.Mask" "F.Paste")
			(net "GND")
		)
	)
	(footprint ""
		(layer "F.Cu")
		(at 299.02023 -50.336196)
		(property "Reference" "R2240"
			(at 0 0 0)
			(layer "F.SilkS")
			(hide yes)
			(effects
				(font
					(size 1.27 1.27)
				)
			)
		)
		(property "Value" ""
			(at 0 0 0)
			(layer "F.Fab")
			(effects
				(font
					(size 1.27 1.27)
				)
			)
		)
		(duplicate_pad_numbers_are_jumpers no)
		(fp_line
			(start -0.7874 -0.4064)
			(end 0.7874 -0.4064)
			(stroke
				(width 0.1524)
				(type default)
			)
			(layer "F.SilkS")
		)
		(fp_line
			(start -0.7874 0.4064)
			(end -0.7874 -0.4064)
			(stroke
				(width 0.1524)
				(type default)
			)
			(layer "F.SilkS")
		)
		(fp_line
			(start 0.7874 -0.4064)
			(end 0.7874 0.4064)
			(stroke
				(width 0.1524)
				(type default)
			)
			(layer "F.SilkS")
		)
		(fp_line
			(start 0.7874 0.4064)
			(end -0.7874 0.4064)
			(stroke
				(width 0.1524)
				(type default)
			)
			(layer "F.SilkS")
		)
		(fp_line
			(start -0.67945 -0.305054)
			(end -0.12065 -0.305054)
			(stroke
				(width 0.1)
				(type default)
			)
			(layer "F.Fab")
		)
		(fp_line
			(start -0.67945 0.3048)
			(end -0.67945 -0.305054)
			(stroke
				(width 0.1)
				(type default)
			)
			(layer "F.Fab")
		)
		(fp_line
			(start -0.12065 -0.305054)
			(end -0.12065 -0.2794)
			(stroke
				(width 0.1)
				(type default)
			)
			(layer "F.Fab")
		)
		(fp_line
			(start -0.12065 -0.2794)
			(end 0.12065 -0.2794)
			(stroke
				(width 0.1)
				(type default)
			)
			(layer "F.Fab")
		)
		(fp_line
			(start -0.12065 0.2794)
			(end -0.12065 0.3048)
			(stroke
				(width 0.1)
				(type default)
			)
			(layer "F.Fab")
		)
		(fp_line
			(start -0.12065 0.3048)
			(end -0.67945 0.3048)
			(stroke
				(width 0.1)
				(type default)
			)
			(layer "F.Fab")
		)
		(fp_line
			(start 0.120396 0.2794)
			(end -0.12065 0.2794)
			(stroke
				(width 0.1)
				(type default)
			)
			(layer "F.Fab")
		)
		(fp_line
			(start 0.120396 0.3048)
			(end 0.120396 0.2794)
			(stroke
				(width 0.1)
				(type default)
			)
			(layer "F.Fab")
		)
		(fp_line
			(start 0.12065 -0.3048)
			(end 0.67945 -0.3048)
			(stroke
				(width 0.1)
				(type default)
			)
			(layer "F.Fab")
		)
		(fp_line
			(start 0.12065 -0.2794)
			(end 0.12065 -0.3048)
			(stroke
				(width 0.1)
				(type default)
			)
			(layer "F.Fab")
		)
		(fp_line
			(start 0.67945 -0.3048)
			(end 0.67945 0.3048)
			(stroke
				(width 0.1)
				(type default)
			)
			(layer "F.Fab")
		)
		(fp_line
			(start 0.67945 0.3048)
			(end 0.120396 0.3048)
			(stroke
				(width 0.1)
				(type default)
			)
			(layer "F.Fab")
		)
		(pad "1" smd circle
			(at -0.40005 0)
			(size 0 0)
			(layers "F.Cu" "F.Mask" "F.Paste")
			(net "P1V05_PCH_AUX")
		)
		(pad "2" smd circle
			(at 0.40005 0)
			(size 0 0)
			(layers "F.Cu" "F.Mask" "F.Paste")
			(net "FM_BOARD_SKU_ID1")
		)
	)
	(footprint ""
		(layer "F.Cu")
		(at 346.465652 -315.66739 90)
		(property "Reference" "PC325"
			(at 0 0 90)
			(layer "F.SilkS")
			(hide yes)
			(effects
				(font
					(size 1.27 1.27)
				)
			)
		)
		(property "Value" ""
			(at 0 0 90)
			(layer "F.Fab")
			(effects
				(font
					(size 1.27 1.27)
				)
			)
		)
		(duplicate_pad_numbers_are_jumpers no)
		(fp_line
			(start 2.750058 0.999998)
			(end -2.750058 0.999998)
			(stroke
				(width 0.1524)
				(type default)
			)
			(layer "F.SilkS")
		)
		(fp_circle
			(center 0 0.999998)
			(end 0 3.750056)
			(stroke
				(width 0.1524)
				(type default)
			)
			(fill no)
			(layer "F.SilkS")
		)
		(fp_poly
			(pts
				(arc
					(start 2.750058 0.999998)
					(mid 0 3.750056)
					(end -2.750058 0.999998)
				)
			)
			(stroke
				(width 0)
				(type default)
			)
			(fill yes)
			(layer "F.SilkS")
		)
		(fp_circle
			(center 0 0.999998)
			(end 0 3.750056)
			(stroke
				(width 0.1)
				(type default)
			)
			(fill no)
			(layer "F.Fab")
		)
		(pad "1" thru_hole rect
			(at 0 0 90)
			(size 1.5748 1.5748)
			(drill 1.0668)
			(layers "*.Cu" "*.Mask")
			(remove_unused_layers no)
			(net "PVCCIN_CPU0")
			(clearance 0)
			(padstack
				(mode front_inner_back)
				(layer "Inner"
					(shape circle)
					(size 1.5748 1.5748)
					(clearance 0)
				)
				(layer "B.Cu"
					(shape rect)
					(size 1.5748 1.5748)
					(clearance 0)
				)
			)
		)
		(pad "2" thru_hole circle
			(at 0 1.999996 90)
			(size 1.5748 1.5748)
			(drill 1.0668)
			(layers "*.Cu" "*.Mask")
			(remove_unused_layers no)
			(net "GND")
			(clearance 0)
		)
	)
	(footprint ""
		(layer "F.Cu")
		(at 104.8258 -409.2702)
		(property "Reference" "R4727"
			(at 0 0 0)
			(layer "F.SilkS")
			(hide yes)
			(effects
				(font
					(size 1.27 1.27)
				)
			)
		)
		(property "Value" ""
			(at 0 0 0)
			(layer "F.Fab")
			(effects
				(font
					(size 1.27 1.27)
				)
			)
		)
		(duplicate_pad_numbers_are_jumpers no)
		(fp_line
			(start -0.7874 -0.4064)
			(end 0.7874 -0.4064)
			(stroke
				(width 0.1524)
				(type default)
			)
			(layer "F.SilkS")
		)
		(fp_line
			(start -0.7874 0.4064)
			(end -0.7874 -0.4064)
			(stroke
				(width 0.1524)
				(type default)
			)
			(layer "F.SilkS")
		)
		(fp_line
			(start 0.7874 -0.4064)
			(end 0.7874 0.4064)
			(stroke
				(width 0.1524)
				(type default)
			)
			(layer "F.SilkS")
		)
		(fp_line
			(start 0.7874 0.4064)
			(end -0.7874 0.4064)
			(stroke
				(width 0.1524)
				(type default)
			)
			(layer "F.SilkS")
		)
		(fp_line
			(start -0.67945 -0.305054)
			(end -0.12065 -0.305054)
			(stroke
				(width 0.1)
				(type default)
			)
			(layer "F.Fab")
		)
		(fp_line
			(start -0.67945 0.3048)
			(end -0.67945 -0.305054)
			(stroke
				(width 0.1)
				(type default)
			)
			(layer "F.Fab")
		)
		(fp_line
			(start -0.12065 -0.305054)
			(end -0.12065 -0.2794)
			(stroke
				(width 0.1)
				(type default)
			)
			(layer "F.Fab")
		)
		(fp_line
			(start -0.12065 -0.2794)
			(end 0.12065 -0.2794)
			(stroke
				(width 0.1)
				(type default)
			)
			(layer "F.Fab")
		)
		(fp_line
			(start -0.12065 0.2794)
			(end -0.12065 0.3048)
			(stroke
				(width 0.1)
				(type default)
			)
			(layer "F.Fab")
		)
		(fp_line
			(start -0.12065 0.3048)
			(end -0.67945 0.3048)
			(stroke
				(width 0.1)
				(type default)
			)
			(layer "F.Fab")
		)
		(fp_line
			(start 0.120396 0.2794)
			(end -0.12065 0.2794)
			(stroke
				(width 0.1)
				(type default)
			)
			(layer "F.Fab")
		)
		(fp_line
			(start 0.120396 0.3048)
			(end 0.120396 0.2794)
			(stroke
				(width 0.1)
				(type default)
			)
			(layer "F.Fab")
		)
		(fp_line
			(start 0.12065 -0.3048)
			(end 0.67945 -0.3048)
			(stroke
				(width 0.1)
				(type default)
			)
			(layer "F.Fab")
		)
		(fp_line
			(start 0.12065 -0.2794)
			(end 0.12065 -0.3048)
			(stroke
				(width 0.1)
				(type default)
			)
			(layer "F.Fab")
		)
		(fp_line
			(start 0.67945 -0.3048)
			(end 0.67945 0.3048)
			(stroke
				(width 0.1)
				(type default)
			)
			(layer "F.Fab")
		)
		(fp_line
			(start 0.67945 0.3048)
			(end 0.120396 0.3048)
			(stroke
				(width 0.1)
				(type default)
			)
			(layer "F.Fab")
		)
		(pad "1" smd circle
			(at -0.40005 0)
			(size 0 0)
			(layers "F.Cu" "F.Mask" "F.Paste")
			(net "P3V3_AUX")
		)
		(pad "2" smd circle
			(at 0.40005 0)
			(size 0 0)
			(layers "F.Cu" "F.Mask" "F.Paste")
			(net "PRSNT_SWB_N")
		)
	)
	(footprint ""
		(layer "F.Cu")
		(at 114.706654 -360.83875)
		(property "Reference" "PC548"
			(at 0 0 0)
			(layer "F.SilkS")
			(hide yes)
			(effects
				(font
					(size 1.27 1.27)
				)
			)
		)
		(property "Value" ""
			(at 0 0 0)
			(layer "F.Fab")
			(effects
				(font
					(size 1.27 1.27)
				)
			)
		)
		(duplicate_pad_numbers_are_jumpers no)
		(fp_line
			(start -0.7874 -0.4064)
			(end 0.7874 -0.4064)
			(stroke
				(width 0.1524)
				(type default)
			)
			(layer "F.SilkS")
		)
		(fp_line
			(start -0.7874 0.4064)
			(end -0.7874 -0.4064)
			(stroke
				(width 0.1524)
				(type default)
			)
			(layer "F.SilkS")
		)
		(fp_line
			(start 0.7874 -0.4064)
			(end 0.7874 0.4064)
			(stroke
				(width 0.1524)
				(type default)
			)
			(layer "F.SilkS")
		)
		(fp_line
			(start 0.7874 0.4064)
			(end -0.7874 0.4064)
			(stroke
				(width 0.1524)
				(type default)
			)
			(layer "F.SilkS")
		)
		(fp_line
			(start -0.67945 -0.305054)
			(end -0.12065 -0.305054)
			(stroke
				(width 0.1)
				(type default)
			)
			(layer "F.Fab")
		)
		(fp_line
			(start -0.67945 0.3048)
			(end -0.67945 -0.305054)
			(stroke
				(width 0.1)
				(type default)
			)
			(layer "F.Fab")
		)
		(fp_line
			(start -0.12065 -0.305054)
			(end -0.12065 -0.2794)
			(stroke
				(width 0.1)
				(type default)
			)
			(layer "F.Fab")
		)
		(fp_line
			(start -0.12065 -0.2794)
			(end 0.12065 -0.2794)
			(stroke
				(width 0.1)
				(type default)
			)
			(layer "F.Fab")
		)
		(fp_line
			(start -0.12065 0.2794)
			(end -0.12065 0.3048)
			(stroke
				(width 0.1)
				(type default)
			)
			(layer "F.Fab")
		)
		(fp_line
			(start -0.12065 0.3048)
			(end -0.67945 0.3048)
			(stroke
				(width 0.1)
				(type default)
			)
			(layer "F.Fab")
		)
		(fp_line
			(start 0.120396 0.2794)
			(end -0.12065 0.2794)
			(stroke
				(width 0.1)
				(type default)
			)
			(layer "F.Fab")
		)
		(fp_line
			(start 0.120396 0.3048)
			(end 0.120396 0.2794)
			(stroke
				(width 0.1)
				(type default)
			)
			(layer "F.Fab")
		)
		(fp_line
			(start 0.12065 -0.3048)
			(end 0.67945 -0.3048)
			(stroke
				(width 0.1)
				(type default)
			)
			(layer "F.Fab")
		)
		(fp_line
			(start 0.12065 -0.2794)
			(end 0.12065 -0.3048)
			(stroke
				(width 0.1)
				(type default)
			)
			(layer "F.Fab")
		)
		(fp_line
			(start 0.67945 -0.3048)
			(end 0.67945 0.3048)
			(stroke
				(width 0.1)
				(type default)
			)
			(layer "F.Fab")
		)
		(fp_line
			(start 0.67945 0.3048)
			(end 0.120396 0.3048)
			(stroke
				(width 0.1)
				(type default)
			)
			(layer "F.Fab")
		)
		(pad "1" smd circle
			(at -0.40005 0)
			(size 0 0)
			(layers "F.Cu" "F.Mask" "F.Paste")
			(net "PVCCIN_CPU1_VIN_CSNIN")
		)
		(pad "2" smd circle
			(at 0.40005 0)
			(size 0 0)
			(layers "F.Cu" "F.Mask" "F.Paste")
			(net "GND")
		)
	)
	(footprint ""
		(layer "F.Cu")
		(at 466.5345 -96.007682 -90)
		(property "Reference" "R1289"
			(at 0 0 270)
			(layer "F.SilkS")
			(hide yes)
			(effects
				(font
					(size 1.27 1.27)
				)
			)
		)
		(property "Value" ""
			(at 0 0 270)
			(layer "F.Fab")
			(effects
				(font
					(size 1.27 1.27)
				)
			)
		)
		(duplicate_pad_numbers_are_jumpers no)
		(fp_line
			(start -0.7874 0.4064)
			(end -0.7874 -0.4064)
			(stroke
				(width 0.1524)
				(type default)
			)
			(layer "F.SilkS")
		)
		(fp_line
			(start 0.7874 0.4064)
			(end -0.7874 0.4064)
			(stroke
				(width 0.1524)
				(type default)
			)
			(layer "F.SilkS")
		)
		(fp_line
			(start -0.7874 -0.4064)
			(end 0.7874 -0.4064)
			(stroke
				(width 0.1524)
				(type default)
			)
			(layer "F.SilkS")
		)
		(fp_line
			(start 0.7874 -0.4064)
			(end 0.7874 0.4064)
			(stroke
				(width 0.1524)
				(type default)
			)
			(layer "F.SilkS")
		)
		(fp_line
			(start -0.67945 0.3048)
			(end -0.67945 -0.305054)
			(stroke
				(width 0.1)
				(type default)
			)
			(layer "F.Fab")
		)
		(fp_line
			(start -0.12065 0.3048)
			(end -0.67945 0.3048)
			(stroke
				(width 0.1)
				(type default)
			)
			(layer "F.Fab")
		)
		(fp_line
			(start 0.120396 0.3048)
			(end 0.120396 0.2794)
			(stroke
				(width 0.1)
				(type default)
			)
			(layer "F.Fab")
		)
		(fp_line
			(start 0.67945 0.3048)
			(end 0.120396 0.3048)
			(stroke
				(width 0.1)
				(type default)
			)
			(layer "F.Fab")
		)
		(fp_line
			(start -0.12065 0.2794)
			(end -0.12065 0.3048)
			(stroke
				(width 0.1)
				(type default)
			)
			(layer "F.Fab")
		)
		(fp_line
			(start 0.120396 0.2794)
			(end -0.12065 0.2794)
			(stroke
				(width 0.1)
				(type default)
			)
			(layer "F.Fab")
		)
		(fp_line
			(start -0.12065 -0.2794)
			(end 0.12065 -0.2794)
			(stroke
				(width 0.1)
				(type default)
			)
			(layer "F.Fab")
		)
		(fp_line
			(start 0.12065 -0.2794)
			(end 0.12065 -0.3048)
			(stroke
				(width 0.1)
				(type default)
			)
			(layer "F.Fab")
		)
		(fp_line
			(start 0.12065 -0.3048)
			(end 0.67945 -0.3048)
			(stroke
				(width 0.1)
				(type default)
			)
			(layer "F.Fab")
		)
		(fp_line
			(start 0.67945 -0.3048)
			(end 0.67945 0.3048)
			(stroke
				(width 0.1)
				(type default)
			)
			(layer "F.Fab")
		)
		(fp_line
			(start -0.67945 -0.305054)
			(end -0.12065 -0.305054)
			(stroke
				(width 0.1)
				(type default)
			)
			(layer "F.Fab")
		)
		(fp_line
			(start -0.12065 -0.305054)
			(end -0.12065 -0.2794)
			(stroke
				(width 0.1)
				(type default)
			)
			(layer "F.Fab")
		)
		(pad "1" smd circle
			(at -0.40005 0 270)
			(size 0 0)
			(layers "F.Cu" "F.Mask" "F.Paste")
			(net "FB_BMC_ISOLATE")
		)
		(pad "2" smd circle
			(at 0.40005 0 270)
			(size 0 0)
			(layers "F.Cu" "F.Mask" "F.Paste")
			(net "GND")
		)
	)
	(footprint ""
		(layer "F.Cu")
		(at 114.91722 -294.01008)
		(property "Reference" "C235"
			(at 0 0 0)
			(layer "F.SilkS")
			(hide yes)
			(effects
				(font
					(size 1.27 1.27)
				)
			)
		)
		(property "Value" ""
			(at 0 0 0)
			(layer "F.Fab")
			(effects
				(font
					(size 1.27 1.27)
				)
			)
		)
		(duplicate_pad_numbers_are_jumpers no)
		(fp_line
			(start -1.524 -0.762)
			(end 1.524 -0.762)
			(stroke
				(width 0.1524)
				(type default)
			)
			(layer "F.SilkS")
		)
		(fp_line
			(start -1.524 0.762)
			(end -1.524 -0.762)
			(stroke
				(width 0.1524)
				(type default)
			)
			(layer "F.SilkS")
		)
		(fp_line
			(start 1.524 -0.762)
			(end 1.524 0.762)
			(stroke
				(width 0.1524)
				(type default)
			)
			(layer "F.SilkS")
		)
		(fp_line
			(start 1.524 0.762)
			(end -1.524 0.762)
			(stroke
				(width 0.1524)
				(type default)
			)
			(layer "F.SilkS")
		)
		(fp_line
			(start -1.1049 -0.724916)
			(end -1.1049 0.724916)
			(stroke
				(width 0.1)
				(type default)
			)
			(layer "F.Fab")
		)
		(fp_line
			(start -1.1049 0.724916)
			(end 1.1049 0.724916)
			(stroke
				(width 0.1)
				(type default)
			)
			(layer "F.Fab")
		)
		(fp_line
			(start 1.1049 -0.724916)
			(end -1.1049 -0.724916)
			(stroke
				(width 0.1)
				(type default)
			)
			(layer "F.Fab")
		)
		(fp_line
			(start 1.1049 0.724916)
			(end 1.1049 -0.724916)
			(stroke
				(width 0.1)
				(type default)
			)
			(layer "F.Fab")
		)
		(pad "1" smd rect
			(at -0.889 0 180)
			(size 1.016 1.27)
			(layers "F.Cu" "F.Mask" "F.Paste")
			(net "PVCCIN_CPU1")
		)
		(pad "2" smd rect
			(at 0.889 0 180)
			(size 1.016 1.27)
			(layers "F.Cu" "F.Mask" "F.Paste")
			(net "GND")
		)
	)
	(footprint ""
		(layer "F.Cu")
		(at 432.636676 -93.922342)
		(property "Reference" "R3602"
			(at 0 0 0)
			(layer "F.SilkS")
			(hide yes)
			(effects
				(font
					(size 1.27 1.27)
				)
			)
		)
		(property "Value" ""
			(at 0 0 0)
			(layer "F.Fab")
			(effects
				(font
					(size 1.27 1.27)
				)
			)
		)
		(duplicate_pad_numbers_are_jumpers no)
		(fp_line
			(start -0.7874 -0.4064)
			(end 0.7874 -0.4064)
			(stroke
				(width 0.1524)
				(type default)
			)
			(layer "F.SilkS")
		)
		(fp_line
			(start -0.7874 0.4064)
			(end -0.7874 -0.4064)
			(stroke
				(width 0.1524)
				(type default)
			)
			(layer "F.SilkS")
		)
		(fp_line
			(start 0.7874 -0.4064)
			(end 0.7874 0.4064)
			(stroke
				(width 0.1524)
				(type default)
			)
			(layer "F.SilkS")
		)
		(fp_line
			(start 0.7874 0.4064)
			(end -0.7874 0.4064)
			(stroke
				(width 0.1524)
				(type default)
			)
			(layer "F.SilkS")
		)
		(fp_line
			(start -0.67945 -0.305054)
			(end -0.12065 -0.305054)
			(stroke
				(width 0.1)
				(type default)
			)
			(layer "F.Fab")
		)
		(fp_line
			(start -0.67945 0.3048)
			(end -0.67945 -0.305054)
			(stroke
				(width 0.1)
				(type default)
			)
			(layer "F.Fab")
		)
		(fp_line
			(start -0.12065 -0.305054)
			(end -0.12065 -0.2794)
			(stroke
				(width 0.1)
				(type default)
			)
			(layer "F.Fab")
		)
		(fp_line
			(start -0.12065 -0.2794)
			(end 0.12065 -0.2794)
			(stroke
				(width 0.1)
				(type default)
			)
			(layer "F.Fab")
		)
		(fp_line
			(start -0.12065 0.2794)
			(end -0.12065 0.3048)
			(stroke
				(width 0.1)
				(type default)
			)
			(layer "F.Fab")
		)
		(fp_line
			(start -0.12065 0.3048)
			(end -0.67945 0.3048)
			(stroke
				(width 0.1)
				(type default)
			)
			(layer "F.Fab")
		)
		(fp_line
			(start 0.120396 0.2794)
			(end -0.12065 0.2794)
			(stroke
				(width 0.1)
				(type default)
			)
			(layer "F.Fab")
		)
		(fp_line
			(start 0.120396 0.3048)
			(end 0.120396 0.2794)
			(stroke
				(width 0.1)
				(type default)
			)
			(layer "F.Fab")
		)
		(fp_line
			(start 0.12065 -0.3048)
			(end 0.67945 -0.3048)
			(stroke
				(width 0.1)
				(type default)
			)
			(layer "F.Fab")
		)
		(fp_line
			(start 0.12065 -0.2794)
			(end 0.12065 -0.3048)
			(stroke
				(width 0.1)
				(type default)
			)
			(layer "F.Fab")
		)
		(fp_line
			(start 0.67945 -0.3048)
			(end 0.67945 0.3048)
			(stroke
				(width 0.1)
				(type default)
			)
			(layer "F.Fab")
		)
		(fp_line
			(start 0.67945 0.3048)
			(end 0.120396 0.3048)
			(stroke
				(width 0.1)
				(type default)
			)
			(layer "F.Fab")
		)
		(pad "1" smd circle
			(at -0.40005 0)
			(size 0 0)
			(layers "F.Cu" "F.Mask" "F.Paste")
			(net "P3V3_OCP_SFF_R")
		)
		(pad "2" smd circle
			(at 0.40005 0)
			(size 0 0)
			(layers "F.Cu" "F.Mask" "F.Paste")
			(net "VSENSE_P3V3_INA230_1_INP")
		)
	)
	(footprint ""
		(layer "F.Cu")
		(at 219.974922 -73.484994 180)
		(property "Reference" "PC2210"
			(at 0 0 180)
			(layer "F.SilkS")
			(hide yes)
			(effects
				(font
					(size 1.27 1.27)
				)
			)
		)
		(property "Value" ""
			(at 0 0 180)
			(layer "F.Fab")
			(effects
				(font
					(size 1.27 1.27)
				)
			)
		)
		(duplicate_pad_numbers_are_jumpers no)
		(fp_line
			(start 0.7874 0.4064)
			(end -0.7874 0.4064)
			(stroke
				(width 0.1524)
				(type default)
			)
			(layer "F.SilkS")
		)
		(fp_line
			(start 0.7874 -0.4064)
			(end 0.7874 0.4064)
			(stroke
				(width 0.1524)
				(type default)
			)
			(layer "F.SilkS")
		)
		(fp_line
			(start -0.7874 0.4064)
			(end -0.7874 -0.4064)
			(stroke
				(width 0.1524)
				(type default)
			)
			(layer "F.SilkS")
		)
		(fp_line
			(start -0.7874 -0.4064)
			(end 0.7874 -0.4064)
			(stroke
				(width 0.1524)
				(type default)
			)
			(layer "F.SilkS")
		)
		(fp_line
			(start 0.67945 0.3048)
			(end 0.120396 0.3048)
			(stroke
				(width 0.1)
				(type default)
			)
			(layer "F.Fab")
		)
		(fp_line
			(start 0.67945 -0.3048)
			(end 0.67945 0.3048)
			(stroke
				(width 0.1)
				(type default)
			)
			(layer "F.Fab")
		)
		(fp_line
			(start 0.12065 -0.2794)
			(end 0.12065 -0.3048)
			(stroke
				(width 0.1)
				(type default)
			)
			(layer "F.Fab")
		)
		(fp_line
			(start 0.12065 -0.3048)
			(end 0.67945 -0.3048)
			(stroke
				(width 0.1)
				(type default)
			)
			(layer "F.Fab")
		)
		(fp_line
			(start 0.120396 0.3048)
			(end 0.120396 0.2794)
			(stroke
				(width 0.1)
				(type default)
			)
			(layer "F.Fab")
		)
		(fp_line
			(start 0.120396 0.2794)
			(end -0.12065 0.2794)
			(stroke
				(width 0.1)
				(type default)
			)
			(layer "F.Fab")
		)
		(fp_line
			(start -0.12065 0.3048)
			(end -0.67945 0.3048)
			(stroke
				(width 0.1)
				(type default)
			)
			(layer "F.Fab")
		)
		(fp_line
			(start -0.12065 0.2794)
			(end -0.12065 0.3048)
			(stroke
				(width 0.1)
				(type default)
			)
			(layer "F.Fab")
		)
		(fp_line
			(start -0.12065 -0.2794)
			(end 0.12065 -0.2794)
			(stroke
				(width 0.1)
				(type default)
			)
			(layer "F.Fab")
		)
		(fp_line
			(start -0.12065 -0.305054)
			(end -0.12065 -0.2794)
			(stroke
				(width 0.1)
				(type default)
			)
			(layer "F.Fab")
		)
		(fp_line
			(start -0.67945 0.3048)
			(end -0.67945 -0.305054)
			(stroke
				(width 0.1)
				(type default)
			)
			(layer "F.Fab")
		)
		(fp_line
			(start -0.67945 -0.305054)
			(end -0.12065 -0.305054)
			(stroke
				(width 0.1)
				(type default)
			)
			(layer "F.Fab")
		)
		(pad "1" smd circle
			(at -0.40005 0 180)
			(size 0 0)
			(layers "F.Cu" "F.Mask" "F.Paste")
			(net "P3V3_E1S_VCC_0")
		)
		(pad "2" smd circle
			(at 0.40005 0 180)
			(size 0 0)
			(layers "F.Cu" "F.Mask" "F.Paste")
			(net "GND")
		)
	)
	(footprint ""
		(layer "F.Cu")
		(at 354.264214 -252.956314 -90)
		(property "Reference" "C1006"
			(at 0 0 270)
			(layer "F.SilkS")
			(hide yes)
			(effects
				(font
					(size 1.27 1.27)
				)
			)
		)
		(property "Value" ""
			(at 0 0 270)
			(layer "F.Fab")
			(effects
				(font
					(size 1.27 1.27)
				)
			)
		)
		(duplicate_pad_numbers_are_jumpers no)
		(fp_line
			(start -0.7874 0.4064)
			(end -0.7874 -0.4064)
			(stroke
				(width 0.1524)
				(type default)
			)
			(layer "F.SilkS")
		)
		(fp_line
			(start 0.7874 0.4064)
			(end -0.7874 0.4064)
			(stroke
				(width 0.1524)
				(type default)
			)
			(layer "F.SilkS")
		)
		(fp_line
			(start -0.7874 -0.4064)
			(end 0.7874 -0.4064)
			(stroke
				(width 0.1524)
				(type default)
			)
			(layer "F.SilkS")
		)
		(fp_line
			(start 0.7874 -0.4064)
			(end 0.7874 0.4064)
			(stroke
				(width 0.1524)
				(type default)
			)
			(layer "F.SilkS")
		)
		(fp_line
			(start -0.67945 0.3048)
			(end -0.67945 -0.305054)
			(stroke
				(width 0.1)
				(type default)
			)
			(layer "F.Fab")
		)
		(fp_line
			(start -0.12065 0.3048)
			(end -0.67945 0.3048)
			(stroke
				(width 0.1)
				(type default)
			)
			(layer "F.Fab")
		)
		(fp_line
			(start 0.120396 0.3048)
			(end 0.120396 0.2794)
			(stroke
				(width 0.1)
				(type default)
			)
			(layer "F.Fab")
		)
		(fp_line
			(start 0.67945 0.3048)
			(end 0.120396 0.3048)
			(stroke
				(width 0.1)
				(type default)
			)
			(layer "F.Fab")
		)
		(fp_line
			(start -0.12065 0.2794)
			(end -0.12065 0.3048)
			(stroke
				(width 0.1)
				(type default)
			)
			(layer "F.Fab")
		)
		(fp_line
			(start 0.120396 0.2794)
			(end -0.12065 0.2794)
			(stroke
				(width 0.1)
				(type default)
			)
			(layer "F.Fab")
		)
		(fp_line
			(start -0.12065 -0.2794)
			(end 0.12065 -0.2794)
			(stroke
				(width 0.1)
				(type default)
			)
			(layer "F.Fab")
		)
		(fp_line
			(start 0.12065 -0.2794)
			(end 0.12065 -0.3048)
			(stroke
				(width 0.1)
				(type default)
			)
			(layer "F.Fab")
		)
		(fp_line
			(start 0.12065 -0.3048)
			(end 0.67945 -0.3048)
			(stroke
				(width 0.1)
				(type default)
			)
			(layer "F.Fab")
		)
		(fp_line
			(start 0.67945 -0.3048)
			(end 0.67945 0.3048)
			(stroke
				(width 0.1)
				(type default)
			)
			(layer "F.Fab")
		)
		(fp_line
			(start -0.67945 -0.305054)
			(end -0.12065 -0.305054)
			(stroke
				(width 0.1)
				(type default)
			)
			(layer "F.Fab")
		)
		(fp_line
			(start -0.12065 -0.305054)
			(end -0.12065 -0.2794)
			(stroke
				(width 0.1)
				(type default)
			)
			(layer "F.Fab")
		)
		(pad "1" smd circle
			(at -0.40005 0 270)
			(size 0 0)
			(layers "F.Cu" "F.Mask" "F.Paste")
			(net "PVCCIN_CPU0")
		)
		(pad "2" smd circle
			(at 0.40005 0 270)
			(size 0 0)
			(layers "F.Cu" "F.Mask" "F.Paste")
			(net "GND")
		)
	)
	(footprint ""
		(layer "F.Cu")
		(at 302.641 -50.383948)
		(property "Reference" "C1249"
			(at 0 0 0)
			(layer "F.SilkS")
			(hide yes)
			(effects
				(font
					(size 1.27 1.27)
				)
			)
		)
		(property "Value" ""
			(at 0 0 0)
			(layer "F.Fab")
			(effects
				(font
					(size 1.27 1.27)
				)
			)
		)
		(duplicate_pad_numbers_are_jumpers no)
		(fp_line
			(start -1.524 -0.762)
			(end 1.524 -0.762)
			(stroke
				(width 0.1524)
				(type default)
			)
			(layer "F.SilkS")
		)
		(fp_line
			(start -1.524 0.762)
			(end -1.524 -0.762)
			(stroke
				(width 0.1524)
				(type default)
			)
			(layer "F.SilkS")
		)
		(fp_line
			(start 1.524 -0.762)
			(end 1.524 0.762)
			(stroke
				(width 0.1524)
				(type default)
			)
			(layer "F.SilkS")
		)
		(fp_line
			(start 1.524 0.762)
			(end -1.524 0.762)
			(stroke
				(width 0.1524)
				(type default)
			)
			(layer "F.SilkS")
		)
		(fp_line
			(start -1.1049 -0.724916)
			(end -1.1049 0.724916)
			(stroke
				(width 0.1)
				(type default)
			)
			(layer "F.Fab")
		)
		(fp_line
			(start -1.1049 0.724916)
			(end 1.1049 0.724916)
			(stroke
				(width 0.1)
				(type default)
			)
			(layer "F.Fab")
		)
		(fp_line
			(start 1.1049 -0.724916)
			(end -1.1049 -0.724916)
			(stroke
				(width 0.1)
				(type default)
			)
			(layer "F.Fab")
		)
		(fp_line
			(start 1.1049 0.724916)
			(end 1.1049 -0.724916)
			(stroke
				(width 0.1)
				(type default)
			)
			(layer "F.Fab")
		)
		(pad "1" smd rect
			(at -0.889 0 180)
			(size 1.016 1.27)
			(layers "F.Cu" "F.Mask" "F.Paste")
			(net "P1V05_PCH_AUX")
		)
		(pad "2" smd rect
			(at 0.889 0 180)
			(size 1.016 1.27)
			(layers "F.Cu" "F.Mask" "F.Paste")
			(net "GND")
		)
	)
	(footprint ""
		(layer "F.Cu")
		(at 177.9524 -93.538548 90)
		(property "Reference" "R4584"
			(at 0 0 90)
			(layer "F.SilkS")
			(hide yes)
			(effects
				(font
					(size 1.27 1.27)
				)
			)
		)
		(property "Value" ""
			(at 0 0 90)
			(layer "F.Fab")
			(effects
				(font
					(size 1.27 1.27)
				)
			)
		)
		(duplicate_pad_numbers_are_jumpers no)
		(fp_line
			(start 0.7874 -0.4064)
			(end 0.7874 0.4064)
			(stroke
				(width 0.1524)
				(type default)
			)
			(layer "F.SilkS")
		)
		(fp_line
			(start -0.7874 -0.4064)
			(end 0.7874 -0.4064)
			(stroke
				(width 0.1524)
				(type default)
			)
			(layer "F.SilkS")
		)
		(fp_line
			(start 0.7874 0.4064)
			(end -0.7874 0.4064)
			(stroke
				(width 0.1524)
				(type default)
			)
			(layer "F.SilkS")
		)
		(fp_line
			(start -0.7874 0.4064)
			(end -0.7874 -0.4064)
			(stroke
				(width 0.1524)
				(type default)
			)
			(layer "F.SilkS")
		)
		(fp_line
			(start -0.12065 -0.305054)
			(end -0.12065 -0.2794)
			(stroke
				(width 0.1)
				(type default)
			)
			(layer "F.Fab")
		)
		(fp_line
			(start -0.67945 -0.305054)
			(end -0.12065 -0.305054)
			(stroke
				(width 0.1)
				(type default)
			)
			(layer "F.Fab")
		)
		(fp_line
			(start 0.67945 -0.3048)
			(end 0.67945 0.3048)
			(stroke
				(width 0.1)
				(type default)
			)
			(layer "F.Fab")
		)
		(fp_line
			(start 0.12065 -0.3048)
			(end 0.67945 -0.3048)
			(stroke
				(width 0.1)
				(type default)
			)
			(layer "F.Fab")
		)
		(fp_line
			(start 0.12065 -0.2794)
			(end 0.12065 -0.3048)
			(stroke
				(width 0.1)
				(type default)
			)
			(layer "F.Fab")
		)
		(fp_line
			(start -0.12065 -0.2794)
			(end 0.12065 -0.2794)
			(stroke
				(width 0.1)
				(type default)
			)
			(layer "F.Fab")
		)
		(fp_line
			(start 0.120396 0.2794)
			(end -0.12065 0.2794)
			(stroke
				(width 0.1)
				(type default)
			)
			(layer "F.Fab")
		)
		(fp_line
			(start -0.12065 0.2794)
			(end -0.12065 0.3048)
			(stroke
				(width 0.1)
				(type default)
			)
			(layer "F.Fab")
		)
		(fp_line
			(start 0.67945 0.3048)
			(end 0.120396 0.3048)
			(stroke
				(width 0.1)
				(type default)
			)
			(layer "F.Fab")
		)
		(fp_line
			(start 0.120396 0.3048)
			(end 0.120396 0.2794)
			(stroke
				(width 0.1)
				(type default)
			)
			(layer "F.Fab")
		)
		(fp_line
			(start -0.12065 0.3048)
			(end -0.67945 0.3048)
			(stroke
				(width 0.1)
				(type default)
			)
			(layer "F.Fab")
		)
		(fp_line
			(start -0.67945 0.3048)
			(end -0.67945 -0.305054)
			(stroke
				(width 0.1)
				(type default)
			)
			(layer "F.Fab")
		)
		(pad "1" smd rect
			(at -0.40005 0 270)
			(size 0.4572 0.508)
			(layers "F.Cu" "F.Mask" "F.Paste")
			(net "P3V3_AUX")
		)
		(pad "2" smd rect
			(at 0.40005 0 270)
			(size 0.4572 0.508)
			(layers "F.Cu" "F.Mask" "F.Paste")
			(net "FM_BOARD_BMC_SKU_ID0")
		)
	)
	(footprint ""
		(layer "F.Cu")
		(at 413.408114 -366.66932 -90)
		(property "Reference" "PC1349"
			(at 0 0 270)
			(layer "F.SilkS")
			(hide yes)
			(effects
				(font
					(size 1.27 1.27)
				)
			)
		)
		(property "Value" ""
			(at 0 0 270)
			(layer "F.Fab")
			(effects
				(font
					(size 1.27 1.27)
				)
			)
		)
		(duplicate_pad_numbers_are_jumpers no)
		(fp_line
			(start -0.7874 0.4064)
			(end -0.7874 -0.4064)
			(stroke
				(width 0.1524)
				(type default)
			)
			(layer "F.SilkS")
		)
		(fp_line
			(start 0.7874 0.4064)
			(end -0.7874 0.4064)
			(stroke
				(width 0.1524)
				(type default)
			)
			(layer "F.SilkS")
		)
		(fp_line
			(start -0.7874 -0.4064)
			(end 0.7874 -0.4064)
			(stroke
				(width 0.1524)
				(type default)
			)
			(layer "F.SilkS")
		)
		(fp_line
			(start 0.7874 -0.4064)
			(end 0.7874 0.4064)
			(stroke
				(width 0.1524)
				(type default)
			)
			(layer "F.SilkS")
		)
		(fp_line
			(start -0.67945 0.3048)
			(end -0.67945 -0.305054)
			(stroke
				(width 0.1)
				(type default)
			)
			(layer "F.Fab")
		)
		(fp_line
			(start -0.12065 0.3048)
			(end -0.67945 0.3048)
			(stroke
				(width 0.1)
				(type default)
			)
			(layer "F.Fab")
		)
		(fp_line
			(start 0.120396 0.3048)
			(end 0.120396 0.2794)
			(stroke
				(width 0.1)
				(type default)
			)
			(layer "F.Fab")
		)
		(fp_line
			(start 0.67945 0.3048)
			(end 0.120396 0.3048)
			(stroke
				(width 0.1)
				(type default)
			)
			(layer "F.Fab")
		)
		(fp_line
			(start -0.12065 0.2794)
			(end -0.12065 0.3048)
			(stroke
				(width 0.1)
				(type default)
			)
			(layer "F.Fab")
		)
		(fp_line
			(start 0.120396 0.2794)
			(end -0.12065 0.2794)
			(stroke
				(width 0.1)
				(type default)
			)
			(layer "F.Fab")
		)
		(fp_line
			(start -0.12065 -0.2794)
			(end 0.12065 -0.2794)
			(stroke
				(width 0.1)
				(type default)
			)
			(layer "F.Fab")
		)
		(fp_line
			(start 0.12065 -0.2794)
			(end 0.12065 -0.3048)
			(stroke
				(width 0.1)
				(type default)
			)
			(layer "F.Fab")
		)
		(fp_line
			(start 0.12065 -0.3048)
			(end 0.67945 -0.3048)
			(stroke
				(width 0.1)
				(type default)
			)
			(layer "F.Fab")
		)
		(fp_line
			(start 0.67945 -0.3048)
			(end 0.67945 0.3048)
			(stroke
				(width 0.1)
				(type default)
			)
			(layer "F.Fab")
		)
		(fp_line
			(start -0.67945 -0.305054)
			(end -0.12065 -0.305054)
			(stroke
				(width 0.1)
				(type default)
			)
			(layer "F.Fab")
		)
		(fp_line
			(start -0.12065 -0.305054)
			(end -0.12065 -0.2794)
			(stroke
				(width 0.1)
				(type default)
			)
			(layer "F.Fab")
		)
		(pad "1" smd circle
			(at -0.40005 0 270)
			(size 0 0)
			(layers "F.Cu" "F.Mask" "F.Paste")
			(net "GND")
		)
		(pad "2" smd circle
			(at 0.40005 0 270)
			(size 0 0)
			(layers "F.Cu" "F.Mask" "F.Paste")
			(net "PVCCIN_CPU0_VREF")
		)
	)
	(footprint ""
		(layer "F.Cu")
		(at 24.050752 -405.858218)
		(property "Reference" "R3439"
			(at 0 0 0)
			(layer "F.SilkS")
			(hide yes)
			(effects
				(font
					(size 1.27 1.27)
				)
			)
		)
		(property "Value" ""
			(at 0 0 0)
			(layer "F.Fab")
			(effects
				(font
					(size 1.27 1.27)
				)
			)
		)
		(duplicate_pad_numbers_are_jumpers no)
		(fp_line
			(start -0.7874 -0.4064)
			(end 0.7874 -0.4064)
			(stroke
				(width 0.1524)
				(type default)
			)
			(layer "F.SilkS")
		)
		(fp_line
			(start -0.7874 0.4064)
			(end -0.7874 -0.4064)
			(stroke
				(width 0.1524)
				(type default)
			)
			(layer "F.SilkS")
		)
		(fp_line
			(start 0.7874 -0.4064)
			(end 0.7874 0.4064)
			(stroke
				(width 0.1524)
				(type default)
			)
			(layer "F.SilkS")
		)
		(fp_line
			(start 0.7874 0.4064)
			(end -0.7874 0.4064)
			(stroke
				(width 0.1524)
				(type default)
			)
			(layer "F.SilkS")
		)
		(fp_line
			(start -0.67945 -0.305054)
			(end -0.12065 -0.305054)
			(stroke
				(width 0.1)
				(type default)
			)
			(layer "F.Fab")
		)
		(fp_line
			(start -0.67945 0.3048)
			(end -0.67945 -0.305054)
			(stroke
				(width 0.1)
				(type default)
			)
			(layer "F.Fab")
		)
		(fp_line
			(start -0.12065 -0.305054)
			(end -0.12065 -0.2794)
			(stroke
				(width 0.1)
				(type default)
			)
			(layer "F.Fab")
		)
		(fp_line
			(start -0.12065 -0.2794)
			(end 0.12065 -0.2794)
			(stroke
				(width 0.1)
				(type default)
			)
			(layer "F.Fab")
		)
		(fp_line
			(start -0.12065 0.2794)
			(end -0.12065 0.3048)
			(stroke
				(width 0.1)
				(type default)
			)
			(layer "F.Fab")
		)
		(fp_line
			(start -0.12065 0.3048)
			(end -0.67945 0.3048)
			(stroke
				(width 0.1)
				(type default)
			)
			(layer "F.Fab")
		)
		(fp_line
			(start 0.120396 0.2794)
			(end -0.12065 0.2794)
			(stroke
				(width 0.1)
				(type default)
			)
			(layer "F.Fab")
		)
		(fp_line
			(start 0.120396 0.3048)
			(end 0.120396 0.2794)
			(stroke
				(width 0.1)
				(type default)
			)
			(layer "F.Fab")
		)
		(fp_line
			(start 0.12065 -0.3048)
			(end 0.67945 -0.3048)
			(stroke
				(width 0.1)
				(type default)
			)
			(layer "F.Fab")
		)
		(fp_line
			(start 0.12065 -0.2794)
			(end 0.12065 -0.3048)
			(stroke
				(width 0.1)
				(type default)
			)
			(layer "F.Fab")
		)
		(fp_line
			(start 0.67945 -0.3048)
			(end 0.67945 0.3048)
			(stroke
				(width 0.1)
				(type default)
			)
			(layer "F.Fab")
		)
		(fp_line
			(start 0.67945 0.3048)
			(end 0.120396 0.3048)
			(stroke
				(width 0.1)
				(type default)
			)
			(layer "F.Fab")
		)
		(pad "1" smd circle
			(at -0.40005 0)
			(size 0 0)
			(layers "F.Cu" "F.Mask" "F.Paste")
			(net "P3V3_AUX")
		)
		(pad "2" smd circle
			(at 0.40005 0)
			(size 0 0)
			(layers "F.Cu" "F.Mask" "F.Paste")
			(net "GPU_FPGA_THERM_OVERT_ISO_N")
		)
	)
	(footprint ""
		(layer "F.Cu")
		(at 304.53965 -62.151768 180)
		(property "Reference" "R2255"
			(at 0 0 180)
			(layer "F.SilkS")
			(hide yes)
			(effects
				(font
					(size 1.27 1.27)
				)
			)
		)
		(property "Value" ""
			(at 0 0 180)
			(layer "F.Fab")
			(effects
				(font
					(size 1.27 1.27)
				)
			)
		)
		(duplicate_pad_numbers_are_jumpers no)
		(fp_line
			(start 0.7874 0.4064)
			(end -0.7874 0.4064)
			(stroke
				(width 0.1524)
				(type default)
			)
			(layer "F.SilkS")
		)
		(fp_line
			(start 0.7874 -0.4064)
			(end 0.7874 0.4064)
			(stroke
				(width 0.1524)
				(type default)
			)
			(layer "F.SilkS")
		)
		(fp_line
			(start -0.7874 0.4064)
			(end -0.7874 -0.4064)
			(stroke
				(width 0.1524)
				(type default)
			)
			(layer "F.SilkS")
		)
		(fp_line
			(start -0.7874 -0.4064)
			(end 0.7874 -0.4064)
			(stroke
				(width 0.1524)
				(type default)
			)
			(layer "F.SilkS")
		)
		(fp_line
			(start 0.67945 0.3048)
			(end 0.120396 0.3048)
			(stroke
				(width 0.1)
				(type default)
			)
			(layer "F.Fab")
		)
		(fp_line
			(start 0.67945 -0.3048)
			(end 0.67945 0.3048)
			(stroke
				(width 0.1)
				(type default)
			)
			(layer "F.Fab")
		)
		(fp_line
			(start 0.12065 -0.2794)
			(end 0.12065 -0.3048)
			(stroke
				(width 0.1)
				(type default)
			)
			(layer "F.Fab")
		)
		(fp_line
			(start 0.12065 -0.3048)
			(end 0.67945 -0.3048)
			(stroke
				(width 0.1)
				(type default)
			)
			(layer "F.Fab")
		)
		(fp_line
			(start 0.120396 0.3048)
			(end 0.120396 0.2794)
			(stroke
				(width 0.1)
				(type default)
			)
			(layer "F.Fab")
		)
		(fp_line
			(start 0.120396 0.2794)
			(end -0.12065 0.2794)
			(stroke
				(width 0.1)
				(type default)
			)
			(layer "F.Fab")
		)
		(fp_line
			(start -0.12065 0.3048)
			(end -0.67945 0.3048)
			(stroke
				(width 0.1)
				(type default)
			)
			(layer "F.Fab")
		)
		(fp_line
			(start -0.12065 0.2794)
			(end -0.12065 0.3048)
			(stroke
				(width 0.1)
				(type default)
			)
			(layer "F.Fab")
		)
		(fp_line
			(start -0.12065 -0.2794)
			(end 0.12065 -0.2794)
			(stroke
				(width 0.1)
				(type default)
			)
			(layer "F.Fab")
		)
		(fp_line
			(start -0.12065 -0.305054)
			(end -0.12065 -0.2794)
			(stroke
				(width 0.1)
				(type default)
			)
			(layer "F.Fab")
		)
		(fp_line
			(start -0.67945 0.3048)
			(end -0.67945 -0.305054)
			(stroke
				(width 0.1)
				(type default)
			)
			(layer "F.Fab")
		)
		(fp_line
			(start -0.67945 -0.305054)
			(end -0.12065 -0.305054)
			(stroke
				(width 0.1)
				(type default)
			)
			(layer "F.Fab")
		)
		(pad "1" smd circle
			(at -0.40005 0 180)
			(size 0 0)
			(layers "F.Cu" "F.Mask" "F.Paste")
			(net "PECI_MUX_SEL_R")
		)
		(pad "2" smd circle
			(at 0.40005 0 180)
			(size 0 0)
			(layers "F.Cu" "F.Mask" "F.Paste")
			(net "FM_PECI_MUX_SEL_N")
		)
	)
	(footprint ""
		(layer "F.Cu")
		(at 98.33864 -30.434788 180)
		(property "Reference" "C1861"
			(at 0 0 180)
			(layer "F.SilkS")
			(hide yes)
			(effects
				(font
					(size 1.27 1.27)
				)
			)
		)
		(property "Value" ""
			(at 0 0 180)
			(layer "F.Fab")
			(effects
				(font
					(size 1.27 1.27)
				)
			)
		)
		(duplicate_pad_numbers_are_jumpers no)
		(fp_line
			(start 0.7874 0.4064)
			(end -0.7874 0.4064)
			(stroke
				(width 0.1524)
				(type default)
			)
			(layer "F.SilkS")
		)
		(fp_line
			(start 0.7874 -0.4064)
			(end 0.7874 0.4064)
			(stroke
				(width 0.1524)
				(type default)
			)
			(layer "F.SilkS")
		)
		(fp_line
			(start -0.7874 0.4064)
			(end -0.7874 -0.4064)
			(stroke
				(width 0.1524)
				(type default)
			)
			(layer "F.SilkS")
		)
		(fp_line
			(start -0.7874 -0.4064)
			(end 0.7874 -0.4064)
			(stroke
				(width 0.1524)
				(type default)
			)
			(layer "F.SilkS")
		)
		(fp_line
			(start 0.67945 0.3048)
			(end 0.120396 0.3048)
			(stroke
				(width 0.1)
				(type default)
			)
			(layer "F.Fab")
		)
		(fp_line
			(start 0.67945 -0.3048)
			(end 0.67945 0.3048)
			(stroke
				(width 0.1)
				(type default)
			)
			(layer "F.Fab")
		)
		(fp_line
			(start 0.12065 -0.2794)
			(end 0.12065 -0.3048)
			(stroke
				(width 0.1)
				(type default)
			)
			(layer "F.Fab")
		)
		(fp_line
			(start 0.12065 -0.3048)
			(end 0.67945 -0.3048)
			(stroke
				(width 0.1)
				(type default)
			)
			(layer "F.Fab")
		)
		(fp_line
			(start 0.120396 0.3048)
			(end 0.120396 0.2794)
			(stroke
				(width 0.1)
				(type default)
			)
			(layer "F.Fab")
		)
		(fp_line
			(start 0.120396 0.2794)
			(end -0.12065 0.2794)
			(stroke
				(width 0.1)
				(type default)
			)
			(layer "F.Fab")
		)
		(fp_line
			(start -0.12065 0.3048)
			(end -0.67945 0.3048)
			(stroke
				(width 0.1)
				(type default)
			)
			(layer "F.Fab")
		)
		(fp_line
			(start -0.12065 0.2794)
			(end -0.12065 0.3048)
			(stroke
				(width 0.1)
				(type default)
			)
			(layer "F.Fab")
		)
		(fp_line
			(start -0.12065 -0.2794)
			(end 0.12065 -0.2794)
			(stroke
				(width 0.1)
				(type default)
			)
			(layer "F.Fab")
		)
		(fp_line
			(start -0.12065 -0.305054)
			(end -0.12065 -0.2794)
			(stroke
				(width 0.1)
				(type default)
			)
			(layer "F.Fab")
		)
		(fp_line
			(start -0.67945 0.3048)
			(end -0.67945 -0.305054)
			(stroke
				(width 0.1)
				(type default)
			)
			(layer "F.Fab")
		)
		(fp_line
			(start -0.67945 -0.305054)
			(end -0.12065 -0.305054)
			(stroke
				(width 0.1)
				(type default)
			)
			(layer "F.Fab")
		)
		(pad "1" smd circle
			(at -0.40005 0 180)
			(size 0 0)
			(layers "F.Cu" "F.Mask" "F.Paste")
			(net "P3V3_OCP_V3_2")
		)
		(pad "2" smd circle
			(at 0.40005 0 180)
			(size 0 0)
			(layers "F.Cu" "F.Mask" "F.Paste")
			(net "GND")
		)
	)
	(footprint ""
		(layer "F.Cu")
		(at 366.431322 -425.18457)
		(property "Reference" "R4183"
			(at 0 0 0)
			(layer "F.SilkS")
			(hide yes)
			(effects
				(font
					(size 1.27 1.27)
				)
			)
		)
		(property "Value" ""
			(at 0 0 0)
			(layer "F.Fab")
			(effects
				(font
					(size 1.27 1.27)
				)
			)
		)
		(duplicate_pad_numbers_are_jumpers no)
		(fp_line
			(start -0.7874 -0.4064)
			(end 0.7874 -0.4064)
			(stroke
				(width 0.1524)
				(type default)
			)
			(layer "F.SilkS")
		)
		(fp_line
			(start -0.7874 0.4064)
			(end -0.7874 -0.4064)
			(stroke
				(width 0.1524)
				(type default)
			)
			(layer "F.SilkS")
		)
		(fp_line
			(start 0.7874 -0.4064)
			(end 0.7874 0.4064)
			(stroke
				(width 0.1524)
				(type default)
			)
			(layer "F.SilkS")
		)
		(fp_line
			(start 0.7874 0.4064)
			(end -0.7874 0.4064)
			(stroke
				(width 0.1524)
				(type default)
			)
			(layer "F.SilkS")
		)
		(fp_line
			(start -0.67945 -0.305054)
			(end -0.12065 -0.305054)
			(stroke
				(width 0.1)
				(type default)
			)
			(layer "F.Fab")
		)
		(fp_line
			(start -0.67945 0.3048)
			(end -0.67945 -0.305054)
			(stroke
				(width 0.1)
				(type default)
			)
			(layer "F.Fab")
		)
		(fp_line
			(start -0.12065 -0.305054)
			(end -0.12065 -0.2794)
			(stroke
				(width 0.1)
				(type default)
			)
			(layer "F.Fab")
		)
		(fp_line
			(start -0.12065 -0.2794)
			(end 0.12065 -0.2794)
			(stroke
				(width 0.1)
				(type default)
			)
			(layer "F.Fab")
		)
		(fp_line
			(start -0.12065 0.2794)
			(end -0.12065 0.3048)
			(stroke
				(width 0.1)
				(type default)
			)
			(layer "F.Fab")
		)
		(fp_line
			(start -0.12065 0.3048)
			(end -0.67945 0.3048)
			(stroke
				(width 0.1)
				(type default)
			)
			(layer "F.Fab")
		)
		(fp_line
			(start 0.120396 0.2794)
			(end -0.12065 0.2794)
			(stroke
				(width 0.1)
				(type default)
			)
			(layer "F.Fab")
		)
		(fp_line
			(start 0.120396 0.3048)
			(end 0.120396 0.2794)
			(stroke
				(width 0.1)
				(type default)
			)
			(layer "F.Fab")
		)
		(fp_line
			(start 0.12065 -0.3048)
			(end 0.67945 -0.3048)
			(stroke
				(width 0.1)
				(type default)
			)
			(layer "F.Fab")
		)
		(fp_line
			(start 0.12065 -0.2794)
			(end 0.12065 -0.3048)
			(stroke
				(width 0.1)
				(type default)
			)
			(layer "F.Fab")
		)
		(fp_line
			(start 0.67945 -0.3048)
			(end 0.67945 0.3048)
			(stroke
				(width 0.1)
				(type default)
			)
			(layer "F.Fab")
		)
		(fp_line
			(start 0.67945 0.3048)
			(end 0.120396 0.3048)
			(stroke
				(width 0.1)
				(type default)
			)
			(layer "F.Fab")
		)
		(pad "1" smd circle
			(at -0.40005 0)
			(size 0 0)
			(layers "F.Cu" "F.Mask" "F.Paste")
			(net "SMB_LM75_0_3V3AUX_SDA")
		)
		(pad "2" smd circle
			(at 0.40005 0)
			(size 0 0)
			(layers "F.Cu" "F.Mask" "F.Paste")
			(net "SMB_LM75_0_3V3AUX_SDA_R1")
		)
	)
	(footprint ""
		(layer "F.Cu")
		(at 100.66655 -359.059226)
		(property "Reference" "R2525"
			(at 0 0 0)
			(layer "F.SilkS")
			(hide yes)
			(effects
				(font
					(size 1.27 1.27)
				)
			)
		)
		(property "Value" ""
			(at 0 0 0)
			(layer "F.Fab")
			(effects
				(font
					(size 1.27 1.27)
				)
			)
		)
		(duplicate_pad_numbers_are_jumpers no)
		(fp_line
			(start -0.7874 -0.4064)
			(end 0.7874 -0.4064)
			(stroke
				(width 0.1524)
				(type default)
			)
			(layer "F.SilkS")
		)
		(fp_line
			(start -0.7874 0.4064)
			(end -0.7874 -0.4064)
			(stroke
				(width 0.1524)
				(type default)
			)
			(layer "F.SilkS")
		)
		(fp_line
			(start 0.7874 -0.4064)
			(end 0.7874 0.4064)
			(stroke
				(width 0.1524)
				(type default)
			)
			(layer "F.SilkS")
		)
		(fp_line
			(start 0.7874 0.4064)
			(end -0.7874 0.4064)
			(stroke
				(width 0.1524)
				(type default)
			)
			(layer "F.SilkS")
		)
		(fp_line
			(start -0.67945 -0.305054)
			(end -0.12065 -0.305054)
			(stroke
				(width 0.1)
				(type default)
			)
			(layer "F.Fab")
		)
		(fp_line
			(start -0.67945 0.3048)
			(end -0.67945 -0.305054)
			(stroke
				(width 0.1)
				(type default)
			)
			(layer "F.Fab")
		)
		(fp_line
			(start -0.12065 -0.305054)
			(end -0.12065 -0.2794)
			(stroke
				(width 0.1)
				(type default)
			)
			(layer "F.Fab")
		)
		(fp_line
			(start -0.12065 -0.2794)
			(end 0.12065 -0.2794)
			(stroke
				(width 0.1)
				(type default)
			)
			(layer "F.Fab")
		)
		(fp_line
			(start -0.12065 0.2794)
			(end -0.12065 0.3048)
			(stroke
				(width 0.1)
				(type default)
			)
			(layer "F.Fab")
		)
		(fp_line
			(start -0.12065 0.3048)
			(end -0.67945 0.3048)
			(stroke
				(width 0.1)
				(type default)
			)
			(layer "F.Fab")
		)
		(fp_line
			(start 0.120396 0.2794)
			(end -0.12065 0.2794)
			(stroke
				(width 0.1)
				(type default)
			)
			(layer "F.Fab")
		)
		(fp_line
			(start 0.120396 0.3048)
			(end 0.120396 0.2794)
			(stroke
				(width 0.1)
				(type default)
			)
			(layer "F.Fab")
		)
		(fp_line
			(start 0.12065 -0.3048)
			(end 0.67945 -0.3048)
			(stroke
				(width 0.1)
				(type default)
			)
			(layer "F.Fab")
		)
		(fp_line
			(start 0.12065 -0.2794)
			(end 0.12065 -0.3048)
			(stroke
				(width 0.1)
				(type default)
			)
			(layer "F.Fab")
		)
		(fp_line
			(start 0.67945 -0.3048)
			(end 0.67945 0.3048)
			(stroke
				(width 0.1)
				(type default)
			)
			(layer "F.Fab")
		)
		(fp_line
			(start 0.67945 0.3048)
			(end 0.120396 0.3048)
			(stroke
				(width 0.1)
				(type default)
			)
			(layer "F.Fab")
		)
		(pad "1" smd circle
			(at -0.40005 0)
			(size 0 0)
			(layers "F.Cu" "F.Mask" "F.Paste")
			(net "P3V3_AUX")
		)
		(pad "2" smd circle
			(at 0.40005 0)
			(size 0 0)
			(layers "F.Cu" "F.Mask" "F.Paste")
			(net "PVCCIN_CPU1_PIN_ALERT")
		)
	)
	(footprint ""
		(layer "F.Cu")
		(at 311.427368 -408.517344 -90)
		(property "Reference" "C906"
			(at 0 0 270)
			(layer "F.SilkS")
			(hide yes)
			(effects
				(font
					(size 1.27 1.27)
				)
			)
		)
		(property "Value" ""
			(at 0 0 270)
			(layer "F.Fab")
			(effects
				(font
					(size 1.27 1.27)
				)
			)
		)
		(duplicate_pad_numbers_are_jumpers no)
		(fp_line
			(start -0.299974 0.150114)
			(end -0.299974 -0.150114)
			(stroke
				(width 0.1)
				(type default)
			)
			(layer "F.Fab")
		)
		(fp_line
			(start 0.299974 0.150114)
			(end -0.299974 0.150114)
			(stroke
				(width 0.1)
				(type default)
			)
			(layer "F.Fab")
		)
		(fp_line
			(start -0.299974 -0.150114)
			(end 0.299974 -0.150114)
			(stroke
				(width 0.1)
				(type default)
			)
			(layer "F.Fab")
		)
		(fp_line
			(start 0.299974 -0.150114)
			(end 0.299974 0.150114)
			(stroke
				(width 0.1)
				(type default)
			)
			(layer "F.Fab")
		)
		(pad "1" smd rect
			(at -0.2667 0 270)
			(size 0.3048 0.381)
			(layers "F.Cu" "F.Mask" "F.Paste")
			(net "P5E_CPU0_PE0_TX_C_DN<13>")
		)
		(pad "2" smd rect
			(at 0.2667 0 270)
			(size 0.3048 0.381)
			(layers "F.Cu" "F.Mask" "F.Paste")
			(net "P5E_CPU0_PE0_TX_DN<13>")
		)
	)
	(footprint ""
		(layer "F.Cu")
		(at 155.63596 -45.452538 -90)
		(property "Reference" "R4460"
			(at 0 0 270)
			(layer "F.SilkS")
			(hide yes)
			(effects
				(font
					(size 1.27 1.27)
				)
			)
		)
		(property "Value" ""
			(at 0 0 270)
			(layer "F.Fab")
			(effects
				(font
					(size 1.27 1.27)
				)
			)
		)
		(duplicate_pad_numbers_are_jumpers no)
		(fp_line
			(start 0.7874 0.4064)
			(end -0.7874 0.4064)
			(stroke
				(width 0.1524)
				(type default)
			)
			(layer "F.SilkS")
		)
		(fp_line
			(start 0.7874 -0.4064)
			(end 0.7874 0.4064)
			(stroke
				(width 0.1524)
				(type default)
			)
			(layer "F.SilkS")
		)
		(fp_line
			(start -0.67945 0.3048)
			(end -0.67945 -0.305054)
			(stroke
				(width 0.1)
				(type default)
			)
			(layer "F.Fab")
		)
		(fp_line
			(start -0.12065 0.3048)
			(end -0.67945 0.3048)
			(stroke
				(width 0.1)
				(type default)
			)
			(layer "F.Fab")
		)
		(fp_line
			(start 0.120396 0.3048)
			(end 0.120396 0.2794)
			(stroke
				(width 0.1)
				(type default)
			)
			(layer "F.Fab")
		)
		(fp_line
			(start 0.67945 0.3048)
			(end 0.120396 0.3048)
			(stroke
				(width 0.1)
				(type default)
			)
			(layer "F.Fab")
		)
		(fp_line
			(start -0.12065 0.2794)
			(end -0.12065 0.3048)
			(stroke
				(width 0.1)
				(type default)
			)
			(layer "F.Fab")
		)
		(fp_line
			(start 0.120396 0.2794)
			(end -0.12065 0.2794)
			(stroke
				(width 0.1)
				(type default)
			)
			(layer "F.Fab")
		)
		(fp_line
			(start -0.12065 -0.2794)
			(end 0.12065 -0.2794)
			(stroke
				(width 0.1)
				(type default)
			)
			(layer "F.Fab")
		)
		(fp_line
			(start 0.12065 -0.2794)
			(end 0.12065 -0.3048)
			(stroke
				(width 0.1)
				(type default)
			)
			(layer "F.Fab")
		)
		(fp_line
			(start 0.12065 -0.3048)
			(end 0.67945 -0.3048)
			(stroke
				(width 0.1)
				(type default)
			)
			(layer "F.Fab")
		)
		(fp_line
			(start 0.67945 -0.3048)
			(end 0.67945 0.3048)
			(stroke
				(width 0.1)
				(type default)
			)
			(layer "F.Fab")
		)
		(fp_line
			(start -0.67945 -0.305054)
			(end -0.12065 -0.305054)
			(stroke
				(width 0.1)
				(type default)
			)
			(layer "F.Fab")
		)
		(fp_line
			(start -0.12065 -0.305054)
			(end -0.12065 -0.2794)
			(stroke
				(width 0.1)
				(type default)
			)
			(layer "F.Fab")
		)
		(pad "1" smd rect
			(at -0.40005 0 90)
			(size 0.4572 0.508)
			(layers "F.Cu" "F.Mask" "F.Paste")
			(net "USB2_HOST_PCH_0_DP")
		)
		(pad "2" smd rect
			(at 0.40005 0 90)
			(size 0.4572 0.508)
			(layers "F.Cu" "F.Mask" "F.Paste")
			(net "USB2_HUB_2_BUF_EXT_R_DP")
		)
	)
	(footprint ""
		(layer "F.Cu")
		(at 36.956238 -126.69774)
		(property "Reference" "C2450"
			(at 0 0 0)
			(layer "F.SilkS")
			(hide yes)
			(effects
				(font
					(size 1.27 1.27)
				)
			)
		)
		(property "Value" ""
			(at 0 0 0)
			(layer "F.Fab")
			(effects
				(font
					(size 1.27 1.27)
				)
			)
		)
		(duplicate_pad_numbers_are_jumpers no)
		(fp_line
			(start -0.7874 -0.4064)
			(end 0.7874 -0.4064)
			(stroke
				(width 0.1524)
				(type default)
			)
			(layer "F.SilkS")
		)
		(fp_line
			(start -0.7874 0.4064)
			(end -0.7874 -0.4064)
			(stroke
				(width 0.1524)
				(type default)
			)
			(layer "F.SilkS")
		)
		(fp_line
			(start 0.7874 -0.4064)
			(end 0.7874 0.4064)
			(stroke
				(width 0.1524)
				(type default)
			)
			(layer "F.SilkS")
		)
		(fp_line
			(start 0.7874 0.4064)
			(end -0.7874 0.4064)
			(stroke
				(width 0.1524)
				(type default)
			)
			(layer "F.SilkS")
		)
		(fp_line
			(start -0.67945 -0.305054)
			(end -0.12065 -0.305054)
			(stroke
				(width 0.1)
				(type default)
			)
			(layer "F.Fab")
		)
		(fp_line
			(start -0.67945 0.3048)
			(end -0.67945 -0.305054)
			(stroke
				(width 0.1)
				(type default)
			)
			(layer "F.Fab")
		)
		(fp_line
			(start -0.12065 -0.305054)
			(end -0.12065 -0.2794)
			(stroke
				(width 0.1)
				(type default)
			)
			(layer "F.Fab")
		)
		(fp_line
			(start -0.12065 -0.2794)
			(end 0.12065 -0.2794)
			(stroke
				(width 0.1)
				(type default)
			)
			(layer "F.Fab")
		)
		(fp_line
			(start -0.12065 0.2794)
			(end -0.12065 0.3048)
			(stroke
				(width 0.1)
				(type default)
			)
			(layer "F.Fab")
		)
		(fp_line
			(start -0.12065 0.3048)
			(end -0.67945 0.3048)
			(stroke
				(width 0.1)
				(type default)
			)
			(layer "F.Fab")
		)
		(fp_line
			(start 0.120396 0.2794)
			(end -0.12065 0.2794)
			(stroke
				(width 0.1)
				(type default)
			)
			(layer "F.Fab")
		)
		(fp_line
			(start 0.120396 0.3048)
			(end 0.120396 0.2794)
			(stroke
				(width 0.1)
				(type default)
			)
			(layer "F.Fab")
		)
		(fp_line
			(start 0.12065 -0.3048)
			(end 0.67945 -0.3048)
			(stroke
				(width 0.1)
				(type default)
			)
			(layer "F.Fab")
		)
		(fp_line
			(start 0.12065 -0.2794)
			(end 0.12065 -0.3048)
			(stroke
				(width 0.1)
				(type default)
			)
			(layer "F.Fab")
		)
		(fp_line
			(start 0.67945 -0.3048)
			(end 0.67945 0.3048)
			(stroke
				(width 0.1)
				(type default)
			)
			(layer "F.Fab")
		)
		(fp_line
			(start 0.67945 0.3048)
			(end 0.120396 0.3048)
			(stroke
				(width 0.1)
				(type default)
			)
			(layer "F.Fab")
		)
		(pad "1" smd circle
			(at -0.40005 0)
			(size 0 0)
			(layers "F.Cu" "F.Mask" "F.Paste")
			(net "PWRGD_PVCCINFAON_CPU1_R")
		)
		(pad "2" smd circle
			(at 0.40005 0)
			(size 0 0)
			(layers "F.Cu" "F.Mask" "F.Paste")
			(net "GND")
		)
	)
	(footprint ""
		(layer "F.Cu")
		(at 294.045894 -412.07436)
		(property "Reference" "R4690"
			(at 0 0 0)
			(layer "F.SilkS")
			(hide yes)
			(effects
				(font
					(size 1.27 1.27)
				)
			)
		)
		(property "Value" ""
			(at 0 0 0)
			(layer "F.Fab")
			(effects
				(font
					(size 1.27 1.27)
				)
			)
		)
		(duplicate_pad_numbers_are_jumpers no)
		(fp_line
			(start -0.7874 -0.4064)
			(end 0.7874 -0.4064)
			(stroke
				(width 0.1524)
				(type default)
			)
			(layer "F.SilkS")
		)
		(fp_line
			(start -0.7874 0.4064)
			(end -0.7874 -0.4064)
			(stroke
				(width 0.1524)
				(type default)
			)
			(layer "F.SilkS")
		)
		(fp_line
			(start 0.7874 -0.4064)
			(end 0.7874 0.4064)
			(stroke
				(width 0.1524)
				(type default)
			)
			(layer "F.SilkS")
		)
		(fp_line
			(start 0.7874 0.4064)
			(end -0.7874 0.4064)
			(stroke
				(width 0.1524)
				(type default)
			)
			(layer "F.SilkS")
		)
		(fp_line
			(start -0.67945 -0.305054)
			(end -0.12065 -0.305054)
			(stroke
				(width 0.1)
				(type default)
			)
			(layer "F.Fab")
		)
		(fp_line
			(start -0.67945 0.3048)
			(end -0.67945 -0.305054)
			(stroke
				(width 0.1)
				(type default)
			)
			(layer "F.Fab")
		)
		(fp_line
			(start -0.12065 -0.305054)
			(end -0.12065 -0.2794)
			(stroke
				(width 0.1)
				(type default)
			)
			(layer "F.Fab")
		)
		(fp_line
			(start -0.12065 -0.2794)
			(end 0.12065 -0.2794)
			(stroke
				(width 0.1)
				(type default)
			)
			(layer "F.Fab")
		)
		(fp_line
			(start -0.12065 0.2794)
			(end -0.12065 0.3048)
			(stroke
				(width 0.1)
				(type default)
			)
			(layer "F.Fab")
		)
		(fp_line
			(start -0.12065 0.3048)
			(end -0.67945 0.3048)
			(stroke
				(width 0.1)
				(type default)
			)
			(layer "F.Fab")
		)
		(fp_line
			(start 0.120396 0.2794)
			(end -0.12065 0.2794)
			(stroke
				(width 0.1)
				(type default)
			)
			(layer "F.Fab")
		)
		(fp_line
			(start 0.120396 0.3048)
			(end 0.120396 0.2794)
			(stroke
				(width 0.1)
				(type default)
			)
			(layer "F.Fab")
		)
		(fp_line
			(start 0.12065 -0.3048)
			(end 0.67945 -0.3048)
			(stroke
				(width 0.1)
				(type default)
			)
			(layer "F.Fab")
		)
		(fp_line
			(start 0.12065 -0.2794)
			(end 0.12065 -0.3048)
			(stroke
				(width 0.1)
				(type default)
			)
			(layer "F.Fab")
		)
		(fp_line
			(start 0.67945 -0.3048)
			(end 0.67945 0.3048)
			(stroke
				(width 0.1)
				(type default)
			)
			(layer "F.Fab")
		)
		(fp_line
			(start 0.67945 0.3048)
			(end 0.120396 0.3048)
			(stroke
				(width 0.1)
				(type default)
			)
			(layer "F.Fab")
		)
		(pad "1" smd circle
			(at -0.40005 0)
			(size 0 0)
			(layers "F.Cu" "F.Mask" "F.Paste")
			(net "SMB_LM75_0_3V3AUX_SDA")
		)
		(pad "2" smd circle
			(at 0.40005 0)
			(size 0 0)
			(layers "F.Cu" "F.Mask" "F.Paste")
			(net "SMB_HSC_TYPE_ADC_SDA")
		)
	)
	(footprint ""
		(layer "F.Cu")
		(at 392.363198 -161.07791)
		(property "Reference" "R971"
			(at 0 0 0)
			(layer "F.SilkS")
			(hide yes)
			(effects
				(font
					(size 1.27 1.27)
				)
			)
		)
		(property "Value" ""
			(at 0 0 0)
			(layer "F.Fab")
			(effects
				(font
					(size 1.27 1.27)
				)
			)
		)
		(duplicate_pad_numbers_are_jumpers no)
		(fp_line
			(start -0.7874 -0.4064)
			(end 0.7874 -0.4064)
			(stroke
				(width 0.1524)
				(type default)
			)
			(layer "F.SilkS")
		)
		(fp_line
			(start -0.7874 0.4064)
			(end -0.7874 -0.4064)
			(stroke
				(width 0.1524)
				(type default)
			)
			(layer "F.SilkS")
		)
		(fp_line
			(start 0.7874 -0.4064)
			(end 0.7874 0.4064)
			(stroke
				(width 0.1524)
				(type default)
			)
			(layer "F.SilkS")
		)
		(fp_line
			(start 0.7874 0.4064)
			(end -0.7874 0.4064)
			(stroke
				(width 0.1524)
				(type default)
			)
			(layer "F.SilkS")
		)
		(fp_line
			(start -0.67945 -0.305054)
			(end -0.12065 -0.305054)
			(stroke
				(width 0.1)
				(type default)
			)
			(layer "F.Fab")
		)
		(fp_line
			(start -0.67945 0.3048)
			(end -0.67945 -0.305054)
			(stroke
				(width 0.1)
				(type default)
			)
			(layer "F.Fab")
		)
		(fp_line
			(start -0.12065 -0.305054)
			(end -0.12065 -0.2794)
			(stroke
				(width 0.1)
				(type default)
			)
			(layer "F.Fab")
		)
		(fp_line
			(start -0.12065 -0.2794)
			(end 0.12065 -0.2794)
			(stroke
				(width 0.1)
				(type default)
			)
			(layer "F.Fab")
		)
		(fp_line
			(start -0.12065 0.2794)
			(end -0.12065 0.3048)
			(stroke
				(width 0.1)
				(type default)
			)
			(layer "F.Fab")
		)
		(fp_line
			(start -0.12065 0.3048)
			(end -0.67945 0.3048)
			(stroke
				(width 0.1)
				(type default)
			)
			(layer "F.Fab")
		)
		(fp_line
			(start 0.120396 0.2794)
			(end -0.12065 0.2794)
			(stroke
				(width 0.1)
				(type default)
			)
			(layer "F.Fab")
		)
		(fp_line
			(start 0.120396 0.3048)
			(end 0.120396 0.2794)
			(stroke
				(width 0.1)
				(type default)
			)
			(layer "F.Fab")
		)
		(fp_line
			(start 0.12065 -0.3048)
			(end 0.67945 -0.3048)
			(stroke
				(width 0.1)
				(type default)
			)
			(layer "F.Fab")
		)
		(fp_line
			(start 0.12065 -0.2794)
			(end 0.12065 -0.3048)
			(stroke
				(width 0.1)
				(type default)
			)
			(layer "F.Fab")
		)
		(fp_line
			(start 0.67945 -0.3048)
			(end 0.67945 0.3048)
			(stroke
				(width 0.1)
				(type default)
			)
			(layer "F.Fab")
		)
		(fp_line
			(start 0.67945 0.3048)
			(end 0.120396 0.3048)
			(stroke
				(width 0.1)
				(type default)
			)
			(layer "F.Fab")
		)
		(pad "1" smd circle
			(at -0.40005 0)
			(size 0 0)
			(layers "F.Cu" "F.Mask" "F.Paste")
			(net "PVNN_TERM_CPU0")
		)
		(pad "2" smd circle
			(at 0.40005 0)
			(size 0 0)
			(layers "F.Cu" "F.Mask" "F.Paste")
			(net "SMB_S3M_CPU0_R_SDA")
		)
	)
	(footprint ""
		(layer "F.Cu")
		(at 228.125782 -65.08496 180)
		(property "Reference" "PD113"
			(at 4.123944 -2.386076 0)
			(unlocked yes)
			(layer "F.SilkS")
			(effects
				(font
					(size 0.7874 0.5842)
					(thickness 0.1524)
				)
				(justify left)
			)
		)
		(property "Value" ""
			(at 0 0 180)
			(layer "F.Fab")
			(effects
				(font
					(size 1.27 1.27)
				)
			)
		)
		(duplicate_pad_numbers_are_jumpers no)
		(fp_line
			(start 4.107942 1.459992)
			(end -3.400044 1.459992)
			(stroke
				(width 0.1524)
				(type default)
			)
			(layer "F.SilkS")
		)
		(fp_line
			(start 4.107942 -1.459992)
			(end 4.107942 1.459992)
			(stroke
				(width 0.1524)
				(type default)
			)
			(layer "F.SilkS")
		)
		(fp_line
			(start -3.400044 1.459992)
			(end -3.400044 -1.459992)
			(stroke
				(width 0.1524)
				(type default)
			)
			(layer "F.SilkS")
		)
		(fp_line
			(start -3.400044 -1.459992)
			(end 4.107942 -1.459992)
			(stroke
				(width 0.1524)
				(type default)
			)
			(layer "F.SilkS")
		)
		(fp_rect
			(start 4.107942 -1.459992)
			(end 3.308096 1.459992)
			(stroke
				(width 0)
				(type default)
			)
			(fill yes)
			(layer "F.SilkS")
		)
		(fp_line
			(start 2.29997 1.459992)
			(end -2.29997 1.459992)
			(stroke
				(width 0.1)
				(type default)
			)
			(layer "F.Fab")
		)
		(fp_line
			(start 2.29997 -1.459992)
			(end 2.29997 1.459992)
			(stroke
				(width 0.1)
				(type default)
			)
			(layer "F.Fab")
		)
		(fp_line
			(start -2.29997 1.459992)
			(end -2.29997 -1.459992)
			(stroke
				(width 0.1)
				(type default)
			)
			(layer "F.Fab")
		)
		(fp_line
			(start -2.29997 -1.459992)
			(end 2.29997 -1.459992)
			(stroke
				(width 0.1)
				(type default)
			)
			(layer "F.Fab")
		)
		(fp_text user "-"
			(at 5.4102 0.29845 0)
			(unlocked yes)
			(layer "F.SilkS")
			(effects
				(font
					(size 1.905 1.4224)
					(thickness 0.1524)
				)
				(justify left)
			)
		)
		(fp_text user "+"
			(at -4.7752 -0.12065 180)
			(unlocked yes)
			(layer "F.SilkS")
			(effects
				(font
					(size 1.905 1.4224)
					(thickness 0.1524)
				)
				(justify left)
			)
		)
		(fp_text user "-"
			(at 5.4102 0.29845 0)
			(unlocked yes)
			(layer "F.Fab")
			(effects
				(font
					(size 1.905 1.4224)
					(thickness 0.1524)
				)
				(justify left)
			)
		)
		(fp_text user "+"
			(at -4.7752 -0.12065 180)
			(unlocked yes)
			(layer "F.Fab")
			(effects
				(font
					(size 1.905 1.4224)
					(thickness 0.1524)
				)
				(justify left)
			)
		)
		(pad "A" smd rect
			(at -1.999996 0 270)
			(size 1.7018 2.5146)
			(layers "F.Cu" "F.Mask" "F.Paste")
			(net "GND")
		)
		(pad "C" smd rect
			(at 1.999996 0 270)
			(size 1.7018 2.5146)
			(layers "F.Cu" "F.Mask" "F.Paste")
			(net "P3V3_E1S_0_R")
		)
	)
	(footprint ""
		(layer "F.Cu")
		(at 119.508016 -241.97691 -90)
		(property "Reference" "C269"
			(at 0 0 270)
			(layer "F.SilkS")
			(hide yes)
			(effects
				(font
					(size 1.27 1.27)
				)
			)
		)
		(property "Value" ""
			(at 0 0 270)
			(layer "F.Fab")
			(effects
				(font
					(size 1.27 1.27)
				)
			)
		)
		(duplicate_pad_numbers_are_jumpers no)
		(fp_line
			(start -0.7874 0.4064)
			(end -0.7874 -0.4064)
			(stroke
				(width 0.1524)
				(type default)
			)
			(layer "F.SilkS")
		)
		(fp_line
			(start 0.7874 0.4064)
			(end -0.7874 0.4064)
			(stroke
				(width 0.1524)
				(type default)
			)
			(layer "F.SilkS")
		)
		(fp_line
			(start -0.7874 -0.4064)
			(end 0.7874 -0.4064)
			(stroke
				(width 0.1524)
				(type default)
			)
			(layer "F.SilkS")
		)
		(fp_line
			(start 0.7874 -0.4064)
			(end 0.7874 0.4064)
			(stroke
				(width 0.1524)
				(type default)
			)
			(layer "F.SilkS")
		)
		(fp_line
			(start -0.67945 0.3048)
			(end -0.67945 -0.305054)
			(stroke
				(width 0.1)
				(type default)
			)
			(layer "F.Fab")
		)
		(fp_line
			(start -0.12065 0.3048)
			(end -0.67945 0.3048)
			(stroke
				(width 0.1)
				(type default)
			)
			(layer "F.Fab")
		)
		(fp_line
			(start 0.120396 0.3048)
			(end 0.120396 0.2794)
			(stroke
				(width 0.1)
				(type default)
			)
			(layer "F.Fab")
		)
		(fp_line
			(start 0.67945 0.3048)
			(end 0.120396 0.3048)
			(stroke
				(width 0.1)
				(type default)
			)
			(layer "F.Fab")
		)
		(fp_line
			(start -0.12065 0.2794)
			(end -0.12065 0.3048)
			(stroke
				(width 0.1)
				(type default)
			)
			(layer "F.Fab")
		)
		(fp_line
			(start 0.120396 0.2794)
			(end -0.12065 0.2794)
			(stroke
				(width 0.1)
				(type default)
			)
			(layer "F.Fab")
		)
		(fp_line
			(start -0.12065 -0.2794)
			(end 0.12065 -0.2794)
			(stroke
				(width 0.1)
				(type default)
			)
			(layer "F.Fab")
		)
		(fp_line
			(start 0.12065 -0.2794)
			(end 0.12065 -0.3048)
			(stroke
				(width 0.1)
				(type default)
			)
			(layer "F.Fab")
		)
		(fp_line
			(start 0.12065 -0.3048)
			(end 0.67945 -0.3048)
			(stroke
				(width 0.1)
				(type default)
			)
			(layer "F.Fab")
		)
		(fp_line
			(start 0.67945 -0.3048)
			(end 0.67945 0.3048)
			(stroke
				(width 0.1)
				(type default)
			)
			(layer "F.Fab")
		)
		(fp_line
			(start -0.67945 -0.305054)
			(end -0.12065 -0.305054)
			(stroke
				(width 0.1)
				(type default)
			)
			(layer "F.Fab")
		)
		(fp_line
			(start -0.12065 -0.305054)
			(end -0.12065 -0.2794)
			(stroke
				(width 0.1)
				(type default)
			)
			(layer "F.Fab")
		)
		(pad "1" smd circle
			(at -0.40005 0 270)
			(size 0 0)
			(layers "F.Cu" "F.Mask" "F.Paste")
			(net "PVCCIN_CPU1")
		)
		(pad "2" smd circle
			(at 0.40005 0 270)
			(size 0 0)
			(layers "F.Cu" "F.Mask" "F.Paste")
			(net "GND")
		)
	)
	(footprint ""
		(layer "F.Cu")
		(at 27.628596 -389.304276 180)
		(property "Reference" "R3286"
			(at 0 0 180)
			(layer "F.SilkS")
			(hide yes)
			(effects
				(font
					(size 1.27 1.27)
				)
			)
		)
		(property "Value" ""
			(at 0 0 180)
			(layer "F.Fab")
			(effects
				(font
					(size 1.27 1.27)
				)
			)
		)
		(duplicate_pad_numbers_are_jumpers no)
		(fp_line
			(start 0.7874 0.4064)
			(end -0.7874 0.4064)
			(stroke
				(width 0.1524)
				(type default)
			)
			(layer "F.SilkS")
		)
		(fp_line
			(start 0.7874 -0.4064)
			(end 0.7874 0.4064)
			(stroke
				(width 0.1524)
				(type default)
			)
			(layer "F.SilkS")
		)
		(fp_line
			(start -0.7874 0.4064)
			(end -0.7874 -0.4064)
			(stroke
				(width 0.1524)
				(type default)
			)
			(layer "F.SilkS")
		)
		(fp_line
			(start -0.7874 -0.4064)
			(end 0.7874 -0.4064)
			(stroke
				(width 0.1524)
				(type default)
			)
			(layer "F.SilkS")
		)
		(fp_line
			(start 0.67945 0.3048)
			(end 0.120396 0.3048)
			(stroke
				(width 0.1)
				(type default)
			)
			(layer "F.Fab")
		)
		(fp_line
			(start 0.67945 -0.3048)
			(end 0.67945 0.3048)
			(stroke
				(width 0.1)
				(type default)
			)
			(layer "F.Fab")
		)
		(fp_line
			(start 0.12065 -0.2794)
			(end 0.12065 -0.3048)
			(stroke
				(width 0.1)
				(type default)
			)
			(layer "F.Fab")
		)
		(fp_line
			(start 0.12065 -0.3048)
			(end 0.67945 -0.3048)
			(stroke
				(width 0.1)
				(type default)
			)
			(layer "F.Fab")
		)
		(fp_line
			(start 0.120396 0.3048)
			(end 0.120396 0.2794)
			(stroke
				(width 0.1)
				(type default)
			)
			(layer "F.Fab")
		)
		(fp_line
			(start 0.120396 0.2794)
			(end -0.12065 0.2794)
			(stroke
				(width 0.1)
				(type default)
			)
			(layer "F.Fab")
		)
		(fp_line
			(start -0.12065 0.3048)
			(end -0.67945 0.3048)
			(stroke
				(width 0.1)
				(type default)
			)
			(layer "F.Fab")
		)
		(fp_line
			(start -0.12065 0.2794)
			(end -0.12065 0.3048)
			(stroke
				(width 0.1)
				(type default)
			)
			(layer "F.Fab")
		)
		(fp_line
			(start -0.12065 -0.2794)
			(end 0.12065 -0.2794)
			(stroke
				(width 0.1)
				(type default)
			)
			(layer "F.Fab")
		)
		(fp_line
			(start -0.12065 -0.305054)
			(end -0.12065 -0.2794)
			(stroke
				(width 0.1)
				(type default)
			)
			(layer "F.Fab")
		)
		(fp_line
			(start -0.67945 0.3048)
			(end -0.67945 -0.305054)
			(stroke
				(width 0.1)
				(type default)
			)
			(layer "F.Fab")
		)
		(fp_line
			(start -0.67945 -0.305054)
			(end -0.12065 -0.305054)
			(stroke
				(width 0.1)
				(type default)
			)
			(layer "F.Fab")
		)
		(pad "1" smd circle
			(at -0.40005 0 180)
			(size 0 0)
			(layers "F.Cu" "F.Mask" "F.Paste")
			(net "P3V3_AUX")
		)
		(pad "2" smd circle
			(at 0.40005 0 180)
			(size 0 0)
			(layers "F.Cu" "F.Mask" "F.Paste")
			(net "FM_P2E_SWB")
		)
	)
	(footprint ""
		(layer "F.Cu")
		(at 240.61674 -253.345188 180)
		(property "Reference" "R4081"
			(at 0 0 180)
			(layer "F.SilkS")
			(hide yes)
			(effects
				(font
					(size 1.27 1.27)
				)
			)
		)
		(property "Value" ""
			(at 0 0 180)
			(layer "F.Fab")
			(effects
				(font
					(size 1.27 1.27)
				)
			)
		)
		(duplicate_pad_numbers_are_jumpers no)
		(fp_line
			(start 0.7874 0.4064)
			(end -0.7874 0.4064)
			(stroke
				(width 0.1524)
				(type default)
			)
			(layer "F.SilkS")
		)
		(fp_line
			(start 0.7874 -0.4064)
			(end 0.7874 0.4064)
			(stroke
				(width 0.1524)
				(type default)
			)
			(layer "F.SilkS")
		)
		(fp_line
			(start -0.7874 0.4064)
			(end -0.7874 -0.4064)
			(stroke
				(width 0.1524)
				(type default)
			)
			(layer "F.SilkS")
		)
		(fp_line
			(start -0.7874 -0.4064)
			(end 0.7874 -0.4064)
			(stroke
				(width 0.1524)
				(type default)
			)
			(layer "F.SilkS")
		)
		(fp_line
			(start 0.67945 0.3048)
			(end 0.120396 0.3048)
			(stroke
				(width 0.1)
				(type default)
			)
			(layer "F.Fab")
		)
		(fp_line
			(start 0.67945 -0.3048)
			(end 0.67945 0.3048)
			(stroke
				(width 0.1)
				(type default)
			)
			(layer "F.Fab")
		)
		(fp_line
			(start 0.12065 -0.2794)
			(end 0.12065 -0.3048)
			(stroke
				(width 0.1)
				(type default)
			)
			(layer "F.Fab")
		)
		(fp_line
			(start 0.12065 -0.3048)
			(end 0.67945 -0.3048)
			(stroke
				(width 0.1)
				(type default)
			)
			(layer "F.Fab")
		)
		(fp_line
			(start 0.120396 0.3048)
			(end 0.120396 0.2794)
			(stroke
				(width 0.1)
				(type default)
			)
			(layer "F.Fab")
		)
		(fp_line
			(start 0.120396 0.2794)
			(end -0.12065 0.2794)
			(stroke
				(width 0.1)
				(type default)
			)
			(layer "F.Fab")
		)
		(fp_line
			(start -0.12065 0.3048)
			(end -0.67945 0.3048)
			(stroke
				(width 0.1)
				(type default)
			)
			(layer "F.Fab")
		)
		(fp_line
			(start -0.12065 0.2794)
			(end -0.12065 0.3048)
			(stroke
				(width 0.1)
				(type default)
			)
			(layer "F.Fab")
		)
		(fp_line
			(start -0.12065 -0.2794)
			(end 0.12065 -0.2794)
			(stroke
				(width 0.1)
				(type default)
			)
			(layer "F.Fab")
		)
		(fp_line
			(start -0.12065 -0.305054)
			(end -0.12065 -0.2794)
			(stroke
				(width 0.1)
				(type default)
			)
			(layer "F.Fab")
		)
		(fp_line
			(start -0.67945 0.3048)
			(end -0.67945 -0.305054)
			(stroke
				(width 0.1)
				(type default)
			)
			(layer "F.Fab")
		)
		(fp_line
			(start -0.67945 -0.305054)
			(end -0.12065 -0.305054)
			(stroke
				(width 0.1)
				(type default)
			)
			(layer "F.Fab")
		)
		(pad "1" smd circle
			(at -0.40005 0 180)
			(size 0 0)
			(layers "F.Cu" "F.Mask" "F.Paste")
			(net "P3V3_AUX")
		)
		(pad "2" smd circle
			(at 0.40005 0 180)
			(size 0 0)
			(layers "F.Cu" "F.Mask" "F.Paste")
			(net "CLK_GEN2_SMB_SADR")
		)
	)
	(footprint ""
		(layer "F.Cu")
		(at 353.0981 -333.716122)
		(property "Reference" "PU12_P0_2"
			(at -2.87528 -6.13537 0)
			(unlocked yes)
			(layer "F.SilkS")
			(effects
				(font
					(size 0.7874 0.5842)
					(thickness 0.1524)
				)
				(justify left)
			)
		)
		(property "Value" ""
			(at 0 0 0)
			(layer "F.Fab")
			(effects
				(font
					(size 1.27 1.27)
				)
			)
		)
		(duplicate_pad_numbers_are_jumpers no)
		(fp_line
			(start -2.500122 -2.999994)
			(end -2.24409 -2.999994)
			(stroke
				(width 0.1524)
				(type default)
			)
			(layer "F.SilkS")
		)
		(fp_line
			(start -2.500122 -2.529078)
			(end -2.500122 -2.999994)
			(stroke
				(width 0.1524)
				(type default)
			)
			(layer "F.SilkS")
		)
		(fp_line
			(start -2.500122 0.6604)
			(end -2.500122 0.229108)
			(stroke
				(width 0.1524)
				(type default)
			)
			(layer "F.SilkS")
		)
		(fp_line
			(start -2.500122 2.999994)
			(end -2.500122 2.339594)
			(stroke
				(width 0.1524)
				(type default)
			)
			(layer "F.SilkS")
		)
		(fp_line
			(start -2.2987 2.999994)
			(end -2.500122 2.999994)
			(stroke
				(width 0.1524)
				(type default)
			)
			(layer "F.SilkS")
		)
		(fp_line
			(start 2.31394 -2.999994)
			(end 2.500122 -2.999994)
			(stroke
				(width 0.1524)
				(type default)
			)
			(layer "F.SilkS")
		)
		(fp_line
			(start 2.500122 -2.999994)
			(end 2.500122 -2.44348)
			(stroke
				(width 0.1524)
				(type default)
			)
			(layer "F.SilkS")
		)
		(fp_line
			(start 2.500122 2.339594)
			(end 2.500122 2.999994)
			(stroke
				(width 0.1524)
				(type default)
			)
			(layer "F.SilkS")
		)
		(fp_line
			(start 2.500122 2.999994)
			(end 2.2987 2.999994)
			(stroke
				(width 0.1524)
				(type default)
			)
			(layer "F.SilkS")
		)
		(fp_poly
			(pts
				(xy -2.210308 -3.613658) (xy -2.718308 -2.597658) (xy -3.226308 -3.613658)
			)
			(stroke
				(width 0)
				(type default)
			)
			(fill yes)
			(layer "F.SilkS")
		)
		(fp_line
			(start -2.500122 -2.999994)
			(end 2.500122 -2.999994)
			(stroke
				(width 0.1)
				(type default)
			)
			(layer "F.Fab")
		)
		(fp_line
			(start -2.500122 2.999994)
			(end -2.500122 -2.999994)
			(stroke
				(width 0.1)
				(type default)
			)
			(layer "F.Fab")
		)
		(fp_line
			(start 2.500122 -2.999994)
			(end 2.500122 2.999994)
			(stroke
				(width 0.1)
				(type default)
			)
			(layer "F.Fab")
		)
		(fp_line
			(start 2.500122 2.999994)
			(end -2.500122 2.999994)
			(stroke
				(width 0.1)
				(type default)
			)
			(layer "F.Fab")
		)
		(fp_poly
			(pts
				(xy -4.218432 -2.783078) (xy -4.218432 -1.767078) (xy -3.202432 -2.275078)
			)
			(stroke
				(width 0)
				(type default)
			)
			(fill yes)
			(layer "F.Fab")
		)
		(pad "1" smd rect
			(at -2.400046 -2.275078 90)
			(size 0.2286 0.6096)
			(layers "F.Cu" "F.Mask" "F.Paste")
			(net "PVCCIN_CPU0_VOS2")
		)
		(pad "2" smd rect
			(at -2.400046 -1.82499 90)
			(size 0.2286 0.6096)
			(layers "F.Cu" "F.Mask" "F.Paste")
			(net "GND")
		)
		(pad "3" smd rect
			(at -2.400046 -1.374902 90)
			(size 0.2286 0.6096)
			(layers "F.Cu" "F.Mask" "F.Paste")
			(net "PVCCIN_CPU0_VDD2")
		)
		(pad "4" smd rect
			(at -2.400046 -0.925068 90)
			(size 0.2286 0.6096)
			(layers "F.Cu" "F.Mask" "F.Paste")
			(net "PVCCIN_CPU0_PVCC")
		)
		(pad "5" smd rect
			(at -2.400046 -0.47498 90)
			(size 0.2286 0.6096)
			(layers "F.Cu" "F.Mask" "F.Paste")
			(net "GND")
		)
		(pad "6" smd rect
			(at -2.400046 -0.024892 90)
			(size 0.2286 0.6096)
			(layers "F.Cu" "F.Mask" "F.Paste")
			(net "Net_8547")
		)
		(pad "7_9-20_24" smd circle
			(at 0 1.150112 90)
			(size 0 0)
			(layers "F.Cu" "F.Mask" "F.Paste")
			(net "GND")
		)
		(pad "10_19" smd rect
			(at 0 2.899918 90)
			(size 0.6096 4.318)
			(layers "F.Cu" "F.Mask" "F.Paste")
			(net "SW_PVCCIN_CPU0_SW2")
		)
		(pad "25_29" smd rect
			(at 1.549908 -1.279906 270)
			(size 2.0574 2.3114)
			(layers "F.Cu" "F.Mask" "F.Paste")
			(net "SW_P12V_PVCCIN_CPU0_FLT")
		)
		(pad "30" smd rect
			(at 2.05994 -2.899918)
			(size 0.2286 0.6096)
			(layers "F.Cu" "F.Mask" "F.Paste")
			(net "SW_P12V_PVCCIN_CPU0_FLT")
		)
		(pad "31" smd rect
			(at 1.610106 -2.899918)
			(size 0.2286 0.6096)
			(layers "F.Cu" "F.Mask" "F.Paste")
			(net "Net_8548")
		)
		(pad "32" smd rect
			(at 1.160018 -2.899918)
			(size 0.2286 0.6096)
			(layers "F.Cu" "F.Mask" "F.Paste")
			(net "SW_PVCCIN_CPU0_BOOTR2")
		)
		(pad "33" smd rect
			(at 0.70993 -2.899918)
			(size 0.2286 0.6096)
			(layers "F.Cu" "F.Mask" "F.Paste")
			(net "SW_PVCCIN_CPU0_BOOT2")
		)
		(pad "34" smd rect
			(at 0.260096 -2.899918)
			(size 0.2286 0.6096)
			(layers "F.Cu" "F.Mask" "F.Paste")
			(net "PVCCIN_CPU0_PWM2")
		)
		(pad "35" smd rect
			(at -0.189992 -2.899918)
			(size 0.2286 0.6096)
			(layers "F.Cu" "F.Mask" "F.Paste")
			(net "PVCCIN_CPU0_VDD2")
		)
		(pad "36" smd rect
			(at -0.64008 -2.899918)
			(size 0.2286 0.6096)
			(layers "F.Cu" "F.Mask" "F.Paste")
			(net "PVCCIN_CPU0_ATSEN")
		)
		(pad "37" smd rect
			(at -1.089914 -2.899918)
			(size 0.2286 0.6096)
			(layers "F.Cu" "F.Mask" "F.Paste")
			(net "PVCCIN_CPU0_LSET2")
		)
		(pad "38" smd rect
			(at -1.540002 -2.899918)
			(size 0.2286 0.6096)
			(layers "F.Cu" "F.Mask" "F.Paste")
			(net "PVCCIN_CPU0_IMON2")
		)
		(pad "39" smd rect
			(at -1.99009 -2.899918)
			(size 0.2286 0.6096)
			(layers "F.Cu" "F.Mask" "F.Paste")
			(net "PVCCIN_CPU0_VREF")
		)
		(pad "40" smd rect
			(at -0.87503 -1.27508)
			(size 1.7526 1.9558)
			(layers "F.Cu" "F.Mask" "F.Paste")
			(net "GND")
		)
		(pad "41" smd rect
			(at -1.525016 0.249936 270)
			(size 0.3048 0.4572)
			(layers "F.Cu" "F.Mask" "F.Paste")
			(net "Net_8546")
		)
		(zone
			(layer "F.Cu")
			(hatch none 0.5)
			(connect_pads
				(clearance 0)
			)
			(min_thickness 0.25)
			(keepout
				(tracks not_allowed)
				(vias allowed)
				(pads allowed)
				(copperpour not_allowed)
				(footprints allowed)
			)
			(placement
				(enabled no)
				(sheetname "")
			)
			(fill
				(thermal_gap 0.5)
				(thermal_bridge_width 0.5)
				(island_removal_mode 0)
			)
			(polygon
				(pts
					(xy 350.597978 -330.716128) (xy 350.597978 -331.465428) (xy 355.598222 -331.465428) (xy 355.598222 -330.716128)
					(xy 355.3079 -330.716128) (xy 355.3079 -331.171804) (xy 350.8883 -331.171804) (xy 350.8883 -330.716128)
				)
			)
		)
		(zone
			(layer "F.Cu")
			(hatch none 0.5)
			(connect_pads
				(clearance 0)
			)
			(min_thickness 0.25)
			(keepout
				(tracks not_allowed)
				(vias allowed)
				(pads allowed)
				(copperpour not_allowed)
				(footprints allowed)
			)
			(placement
				(enabled no)
				(sheetname "")
			)
			(fill
				(thermal_gap 0.5)
				(thermal_bridge_width 0.5)
				(island_removal_mode 0)
			)
			(polygon
				(pts
					(xy 351.053654 -334.038448) (xy 351.29597 -334.038448) (xy 351.29597 -333.962502) (xy 351.81794 -333.962502)
					(xy 351.81794 -333.855568) (xy 351.92462 -333.855568) (xy 351.92462 -333.789528) (xy 351.99066 -333.789528)
					(xy 351.99066 -333.647288) (xy 352.147378 -333.647288) (xy 352.147378 -332.966822) (xy 350.597978 -332.966822)
					(xy 350.597978 -333.423514) (xy 351.293684 -333.423514) (xy 351.293684 -333.262986) (xy 351.852484 -333.262986)
					(xy 351.852484 -333.669386) (xy 351.293684 -333.669386) (xy 351.293684 -333.448914) (xy 350.597978 -333.448914)
					(xy 350.597978 -333.575914) (xy 351.053654 -333.575914)
				)
			)
		)
	)
	(footprint ""
		(layer "F.Cu")
		(at 129.46888 -106.898948)
		(property "Reference" "R4409"
			(at 0 0 0)
			(layer "F.SilkS")
			(hide yes)
			(effects
				(font
					(size 1.27 1.27)
				)
			)
		)
		(property "Value" ""
			(at 0 0 0)
			(layer "F.Fab")
			(effects
				(font
					(size 1.27 1.27)
				)
			)
		)
		(duplicate_pad_numbers_are_jumpers no)
		(fp_line
			(start -0.7874 -0.4064)
			(end 0.7874 -0.4064)
			(stroke
				(width 0.1524)
				(type default)
			)
			(layer "F.SilkS")
		)
		(fp_line
			(start -0.7874 0.4064)
			(end -0.7874 -0.4064)
			(stroke
				(width 0.1524)
				(type default)
			)
			(layer "F.SilkS")
		)
		(fp_line
			(start 0.7874 -0.4064)
			(end 0.7874 0.4064)
			(stroke
				(width 0.1524)
				(type default)
			)
			(layer "F.SilkS")
		)
		(fp_line
			(start 0.7874 0.4064)
			(end -0.7874 0.4064)
			(stroke
				(width 0.1524)
				(type default)
			)
			(layer "F.SilkS")
		)
		(fp_line
			(start -0.67945 -0.305054)
			(end -0.12065 -0.305054)
			(stroke
				(width 0.1)
				(type default)
			)
			(layer "F.Fab")
		)
		(fp_line
			(start -0.67945 0.3048)
			(end -0.67945 -0.305054)
			(stroke
				(width 0.1)
				(type default)
			)
			(layer "F.Fab")
		)
		(fp_line
			(start -0.12065 -0.305054)
			(end -0.12065 -0.2794)
			(stroke
				(width 0.1)
				(type default)
			)
			(layer "F.Fab")
		)
		(fp_line
			(start -0.12065 -0.2794)
			(end 0.12065 -0.2794)
			(stroke
				(width 0.1)
				(type default)
			)
			(layer "F.Fab")
		)
		(fp_line
			(start -0.12065 0.2794)
			(end -0.12065 0.3048)
			(stroke
				(width 0.1)
				(type default)
			)
			(layer "F.Fab")
		)
		(fp_line
			(start -0.12065 0.3048)
			(end -0.67945 0.3048)
			(stroke
				(width 0.1)
				(type default)
			)
			(layer "F.Fab")
		)
		(fp_line
			(start 0.120396 0.2794)
			(end -0.12065 0.2794)
			(stroke
				(width 0.1)
				(type default)
			)
			(layer "F.Fab")
		)
		(fp_line
			(start 0.120396 0.3048)
			(end 0.120396 0.2794)
			(stroke
				(width 0.1)
				(type default)
			)
			(layer "F.Fab")
		)
		(fp_line
			(start 0.12065 -0.3048)
			(end 0.67945 -0.3048)
			(stroke
				(width 0.1)
				(type default)
			)
			(layer "F.Fab")
		)
		(fp_line
			(start 0.12065 -0.2794)
			(end 0.12065 -0.3048)
			(stroke
				(width 0.1)
				(type default)
			)
			(layer "F.Fab")
		)
		(fp_line
			(start 0.67945 -0.3048)
			(end 0.67945 0.3048)
			(stroke
				(width 0.1)
				(type default)
			)
			(layer "F.Fab")
		)
		(fp_line
			(start 0.67945 0.3048)
			(end 0.120396 0.3048)
			(stroke
				(width 0.1)
				(type default)
			)
			(layer "F.Fab")
		)
		(pad "1" smd circle
			(at -0.40005 0)
			(size 0 0)
			(layers "F.Cu" "F.Mask" "F.Paste")
			(net "H_CPU0_MEMTRIP")
		)
		(pad "2" smd circle
			(at 0.40005 0)
			(size 0 0)
			(layers "F.Cu" "F.Mask" "F.Paste")
			(net "H_CPU0_MEMTRIP_R")
		)
	)
	(footprint ""
		(layer "F.Cu")
		(at 205.397608 -401.775422 180)
		(property "Reference" "PR3915"
			(at 0 0 180)
			(layer "F.SilkS")
			(hide yes)
			(effects
				(font
					(size 1.27 1.27)
				)
			)
		)
		(property "Value" ""
			(at 0 0 180)
			(layer "F.Fab")
			(effects
				(font
					(size 1.27 1.27)
				)
			)
		)
		(duplicate_pad_numbers_are_jumpers no)
		(fp_line
			(start 0.7874 0.4064)
			(end -0.7874 0.4064)
			(stroke
				(width 0.1524)
				(type default)
			)
			(layer "F.SilkS")
		)
		(fp_line
			(start 0.7874 -0.4064)
			(end 0.7874 0.4064)
			(stroke
				(width 0.1524)
				(type default)
			)
			(layer "F.SilkS")
		)
		(fp_line
			(start -0.7874 0.4064)
			(end -0.7874 -0.4064)
			(stroke
				(width 0.1524)
				(type default)
			)
			(layer "F.SilkS")
		)
		(fp_line
			(start -0.7874 -0.4064)
			(end 0.7874 -0.4064)
			(stroke
				(width 0.1524)
				(type default)
			)
			(layer "F.SilkS")
		)
		(fp_line
			(start 0.67945 0.3048)
			(end 0.120396 0.3048)
			(stroke
				(width 0.1)
				(type default)
			)
			(layer "F.Fab")
		)
		(fp_line
			(start 0.67945 -0.3048)
			(end 0.67945 0.3048)
			(stroke
				(width 0.1)
				(type default)
			)
			(layer "F.Fab")
		)
		(fp_line
			(start 0.12065 -0.2794)
			(end 0.12065 -0.3048)
			(stroke
				(width 0.1)
				(type default)
			)
			(layer "F.Fab")
		)
		(fp_line
			(start 0.12065 -0.3048)
			(end 0.67945 -0.3048)
			(stroke
				(width 0.1)
				(type default)
			)
			(layer "F.Fab")
		)
		(fp_line
			(start 0.120396 0.3048)
			(end 0.120396 0.2794)
			(stroke
				(width 0.1)
				(type default)
			)
			(layer "F.Fab")
		)
		(fp_line
			(start 0.120396 0.2794)
			(end -0.12065 0.2794)
			(stroke
				(width 0.1)
				(type default)
			)
			(layer "F.Fab")
		)
		(fp_line
			(start -0.12065 0.3048)
			(end -0.67945 0.3048)
			(stroke
				(width 0.1)
				(type default)
			)
			(layer "F.Fab")
		)
		(fp_line
			(start -0.12065 0.2794)
			(end -0.12065 0.3048)
			(stroke
				(width 0.1)
				(type default)
			)
			(layer "F.Fab")
		)
		(fp_line
			(start -0.12065 -0.2794)
			(end 0.12065 -0.2794)
			(stroke
				(width 0.1)
				(type default)
			)
			(layer "F.Fab")
		)
		(fp_line
			(start -0.12065 -0.305054)
			(end -0.12065 -0.2794)
			(stroke
				(width 0.1)
				(type default)
			)
			(layer "F.Fab")
		)
		(fp_line
			(start -0.67945 0.3048)
			(end -0.67945 -0.305054)
			(stroke
				(width 0.1)
				(type default)
			)
			(layer "F.Fab")
		)
		(fp_line
			(start -0.67945 -0.305054)
			(end -0.12065 -0.305054)
			(stroke
				(width 0.1)
				(type default)
			)
			(layer "F.Fab")
		)
		(pad "1" smd circle
			(at -0.40005 0 180)
			(size 0 0)
			(layers "F.Cu" "F.Mask" "F.Paste")
			(net "HSC_CS_2")
		)
		(pad "2" smd circle
			(at 0.40005 0 180)
			(size 0 0)
			(layers "F.Cu" "F.Mask" "F.Paste")
			(net "AGND_HSC")
		)
	)
	(footprint ""
		(layer "F.Cu")
		(at 72.708262 -39.319962)
		(property "Reference" "U263"
			(at 2.341626 -3.780282 0)
			(unlocked yes)
			(layer "F.SilkS")
			(effects
				(font
					(size 0.7874 0.5842)
					(thickness 0.1524)
				)
			)
		)
		(property "Value" ""
			(at 0 0 0)
			(layer "F.Fab")
			(effects
				(font
					(size 1.27 1.27)
				)
			)
		)
		(duplicate_pad_numbers_are_jumpers no)
		(fp_line
			(start -1.500124 -1.500124)
			(end -1.004062 -1.500124)
			(stroke
				(width 0.1524)
				(type default)
			)
			(layer "F.SilkS")
		)
		(fp_line
			(start -1.500124 -1.004062)
			(end -1.500124 -1.500124)
			(stroke
				(width 0.1524)
				(type default)
			)
			(layer "F.SilkS")
		)
		(fp_line
			(start -1.500124 1.500124)
			(end -1.500124 1.004062)
			(stroke
				(width 0.1524)
				(type default)
			)
			(layer "F.SilkS")
		)
		(fp_line
			(start -1.004062 1.500124)
			(end -1.500124 1.500124)
			(stroke
				(width 0.1524)
				(type default)
			)
			(layer "F.SilkS")
		)
		(fp_line
			(start 1.004062 -1.500124)
			(end 1.500124 -1.500124)
			(stroke
				(width 0.1524)
				(type default)
			)
			(layer "F.SilkS")
		)
		(fp_line
			(start 1.500124 -1.500124)
			(end 1.500124 -1.004062)
			(stroke
				(width 0.1524)
				(type default)
			)
			(layer "F.SilkS")
		)
		(fp_line
			(start 1.500124 1.004062)
			(end 1.500124 1.500124)
			(stroke
				(width 0.1524)
				(type default)
			)
			(layer "F.SilkS")
		)
		(fp_line
			(start 1.500124 1.500124)
			(end 1.004062 1.500124)
			(stroke
				(width 0.1524)
				(type default)
			)
			(layer "F.SilkS")
		)
		(fp_poly
			(pts
				(xy -1.50241 -2.181098) (xy -1.894586 -1.396492) (xy -2.286762 -2.181098)
			)
			(stroke
				(width 0)
				(type default)
			)
			(fill yes)
			(layer "F.SilkS")
		)
		(fp_line
			(start -1.500124 -1.500124)
			(end 1.500124 -1.500124)
			(stroke
				(width 0.1)
				(type default)
			)
			(layer "F.Fab")
		)
		(fp_line
			(start -1.500124 1.500124)
			(end -1.500124 -1.500124)
			(stroke
				(width 0.1)
				(type default)
			)
			(layer "F.Fab")
		)
		(fp_line
			(start 1.500124 -1.500124)
			(end 1.500124 1.500124)
			(stroke
				(width 0.1)
				(type default)
			)
			(layer "F.Fab")
		)
		(fp_line
			(start 1.500124 1.500124)
			(end -1.500124 1.500124)
			(stroke
				(width 0.1)
				(type default)
			)
			(layer "F.Fab")
		)
		(fp_poly
			(pts
				(xy -2.847848 -1.258062) (xy -2.847848 -0.242062) (xy -1.831848 -0.750062)
			)
			(stroke
				(width 0)
				(type default)
			)
			(fill yes)
			(layer "F.Fab")
		)
		(pad "1" smd rect
			(at -1.400048 -0.750062 270)
			(size 0.2286 0.6096)
			(layers "F.Cu" "F.Mask" "F.Paste")
			(net "INA230_3_A1")
		)
		(pad "2" smd rect
			(at -1.400048 -0.249936 270)
			(size 0.2286 0.6096)
			(layers "F.Cu" "F.Mask" "F.Paste")
			(net "INA230_3_A0")
		)
		(pad "3" smd rect
			(at -1.400048 0.249936 270)
			(size 0.2286 0.6096)
			(layers "F.Cu" "F.Mask" "F.Paste")
			(net "OCP_V3_2_P3V3_ADC_ALERT_R")
		)
		(pad "4" smd rect
			(at -1.400048 0.750062 270)
			(size 0.2286 0.6096)
			(layers "F.Cu" "F.Mask" "F.Paste")
			(net "SMB_INA230_3_3V3AUX_SDA_R1")
		)
		(pad "5" smd rect
			(at -0.750062 1.400048)
			(size 0.2286 0.6096)
			(layers "F.Cu" "F.Mask" "F.Paste")
			(net "SMB_INA230_3_3V3AUX_SCL_R1")
		)
		(pad "6" smd rect
			(at -0.249936 1.400048)
			(size 0.2286 0.6096)
			(layers "F.Cu" "F.Mask" "F.Paste")
			(net "NC_INA230_3_NC0")
		)
		(pad "7" smd rect
			(at 0.249936 1.400048)
			(size 0.2286 0.6096)
			(layers "F.Cu" "F.Mask" "F.Paste")
			(net "NC_INA230_3_NC1")
		)
		(pad "8" smd rect
			(at 0.750062 1.400048)
			(size 0.2286 0.6096)
			(layers "F.Cu" "F.Mask" "F.Paste")
			(net "NC_INA230_3_NC2")
		)
		(pad "9" smd rect
			(at 1.400048 0.750062 270)
			(size 0.2286 0.6096)
			(layers "F.Cu" "F.Mask" "F.Paste")
			(net "P3V3_AUX")
		)
		(pad "10" smd rect
			(at 1.400048 0.249936 270)
			(size 0.2286 0.6096)
			(layers "F.Cu" "F.Mask" "F.Paste")
			(net "GND")
		)
		(pad "11" smd rect
			(at 1.400048 -0.249936 270)
			(size 0.2286 0.6096)
			(layers "F.Cu" "F.Mask" "F.Paste")
			(net "P3V3_OCP_V3_2_R")
		)
		(pad "12" smd rect
			(at 1.400048 -0.750062 270)
			(size 0.2286 0.6096)
			(layers "F.Cu" "F.Mask" "F.Paste")
			(net "VSENSE_P12V_INA230_3_INN")
		)
		(pad "13" smd rect
			(at 0.750062 -1.400048)
			(size 0.2286 0.6096)
			(layers "F.Cu" "F.Mask" "F.Paste")
			(net "VSENSE_P12V_INA230_3_INP")
		)
		(pad "14" smd rect
			(at 0.249936 -1.400048)
			(size 0.2286 0.6096)
			(layers "F.Cu" "F.Mask" "F.Paste")
			(net "NC_INA230_3_NC3")
		)
		(pad "15" smd rect
			(at -0.249936 -1.400048)
			(size 0.2286 0.6096)
			(layers "F.Cu" "F.Mask" "F.Paste")
			(net "NC_INA230_3_NC4")
		)
		(pad "16" smd rect
			(at -0.750062 -1.400048)
			(size 0.2286 0.6096)
			(layers "F.Cu" "F.Mask" "F.Paste")
			(net "NC_INA230_3_NC5")
		)
		(pad "TH" smd rect
			(at 0 0)
			(size 1.7018 1.7018)
			(layers "F.Cu" "F.Mask" "F.Paste")
			(net "GND")
		)
		(zone
			(layer "F.Cu")
			(hatch none 0.5)
			(connect_pads
				(clearance 0)
			)
			(min_thickness 0.25)
			(keepout
				(tracks not_allowed)
				(vias allowed)
				(pads allowed)
				(copperpour not_allowed)
				(footprints allowed)
			)
			(placement
				(enabled no)
				(sheetname "")
			)
			(fill
				(thermal_gap 0.5)
				(thermal_bridge_width 0.5)
				(island_removal_mode 0)
			)
			(polygon
				(pts
					(xy 71.663814 -39.345362) (xy 71.663814 -40.36441) (xy 73.75271 -40.36441) (xy 73.75271 -38.275514)
					(xy 71.663814 -38.275514) (xy 71.663814 -39.319962) (xy 71.806562 -39.319962) (xy 71.806562 -38.418262)
					(xy 73.609962 -38.418262) (xy 73.609962 -40.221662) (xy 71.806562 -40.221662) (xy 71.806562 -39.345362)
				)
			)
		)
	)
	(footprint ""
		(layer "F.Cu")
		(at 20.485608 -385.866894 90)
		(property "Reference" "R4660"
			(at 0 0 90)
			(layer "F.SilkS")
			(hide yes)
			(effects
				(font
					(size 1.27 1.27)
				)
			)
		)
		(property "Value" ""
			(at 0 0 90)
			(layer "F.Fab")
			(effects
				(font
					(size 1.27 1.27)
				)
			)
		)
		(duplicate_pad_numbers_are_jumpers no)
		(fp_line
			(start -0.015494 -0.4064)
			(end 0.7874 -0.4064)
			(stroke
				(width 0.1524)
				(type default)
			)
			(layer "F.SilkS")
		)
		(fp_line
			(start 0.7874 0.4064)
			(end -0.7874 0.4064)
			(stroke
				(width 0.1524)
				(type default)
			)
			(layer "F.SilkS")
		)
		(fp_line
			(start -0.7874 0.4064)
			(end -0.7874 -0.4064)
			(stroke
				(width 0.1524)
				(type default)
			)
			(layer "F.SilkS")
		)
		(fp_line
			(start -0.12065 -0.305054)
			(end -0.12065 -0.2794)
			(stroke
				(width 0.1)
				(type default)
			)
			(layer "F.Fab")
		)
		(fp_line
			(start -0.67945 -0.305054)
			(end -0.12065 -0.305054)
			(stroke
				(width 0.1)
				(type default)
			)
			(layer "F.Fab")
		)
		(fp_line
			(start 0.67945 -0.3048)
			(end 0.67945 0.3048)
			(stroke
				(width 0.1)
				(type default)
			)
			(layer "F.Fab")
		)
		(fp_line
			(start 0.12065 -0.3048)
			(end 0.67945 -0.3048)
			(stroke
				(width 0.1)
				(type default)
			)
			(layer "F.Fab")
		)
		(fp_line
			(start 0.12065 -0.2794)
			(end 0.12065 -0.3048)
			(stroke
				(width 0.1)
				(type default)
			)
			(layer "F.Fab")
		)
		(fp_line
			(start -0.12065 -0.2794)
			(end 0.12065 -0.2794)
			(stroke
				(width 0.1)
				(type default)
			)
			(layer "F.Fab")
		)
		(fp_line
			(start 0.120396 0.2794)
			(end -0.12065 0.2794)
			(stroke
				(width 0.1)
				(type default)
			)
			(layer "F.Fab")
		)
		(fp_line
			(start -0.12065 0.2794)
			(end -0.12065 0.3048)
			(stroke
				(width 0.1)
				(type default)
			)
			(layer "F.Fab")
		)
		(fp_line
			(start 0.67945 0.3048)
			(end 0.120396 0.3048)
			(stroke
				(width 0.1)
				(type default)
			)
			(layer "F.Fab")
		)
		(fp_line
			(start 0.120396 0.3048)
			(end 0.120396 0.2794)
			(stroke
				(width 0.1)
				(type default)
			)
			(layer "F.Fab")
		)
		(fp_line
			(start -0.12065 0.3048)
			(end -0.67945 0.3048)
			(stroke
				(width 0.1)
				(type default)
			)
			(layer "F.Fab")
		)
		(fp_line
			(start -0.67945 0.3048)
			(end -0.67945 -0.305054)
			(stroke
				(width 0.1)
				(type default)
			)
			(layer "F.Fab")
		)
		(pad "1" smd rect
			(at -0.40005 0 270)
			(size 0.4572 0.508)
			(layers "F.Cu" "F.Mask" "F.Paste")
			(net "P2E_MB_BMC_TX_C_DN<0>")
		)
		(pad "2" smd rect
			(at 0.40005 0 270)
			(size 0.4572 0.508)
			(layers "F.Cu" "F.Mask" "F.Paste")
			(net "P2E_MB_BMC_TX_C_R1_DN<0>")
		)
	)
	(footprint ""
		(layer "F.Cu")
		(at 206.7052 -97.6884 90)
		(property "Reference" "R4782"
			(at 0 0 90)
			(layer "F.SilkS")
			(hide yes)
			(effects
				(font
					(size 1.27 1.27)
				)
			)
		)
		(property "Value" ""
			(at 0 0 90)
			(layer "F.Fab")
			(effects
				(font
					(size 1.27 1.27)
				)
			)
		)
		(duplicate_pad_numbers_are_jumpers no)
		(fp_line
			(start 0.7874 -0.4064)
			(end 0.7874 0.4064)
			(stroke
				(width 0.1524)
				(type default)
			)
			(layer "F.SilkS")
		)
		(fp_line
			(start -0.7874 -0.4064)
			(end 0.7874 -0.4064)
			(stroke
				(width 0.1524)
				(type default)
			)
			(layer "F.SilkS")
		)
		(fp_line
			(start 0.7874 0.4064)
			(end -0.7874 0.4064)
			(stroke
				(width 0.1524)
				(type default)
			)
			(layer "F.SilkS")
		)
		(fp_line
			(start -0.7874 0.4064)
			(end -0.7874 -0.4064)
			(stroke
				(width 0.1524)
				(type default)
			)
			(layer "F.SilkS")
		)
		(fp_line
			(start -0.12065 -0.305054)
			(end -0.12065 -0.2794)
			(stroke
				(width 0.1)
				(type default)
			)
			(layer "F.Fab")
		)
		(fp_line
			(start -0.67945 -0.305054)
			(end -0.12065 -0.305054)
			(stroke
				(width 0.1)
				(type default)
			)
			(layer "F.Fab")
		)
		(fp_line
			(start 0.67945 -0.3048)
			(end 0.67945 0.3048)
			(stroke
				(width 0.1)
				(type default)
			)
			(layer "F.Fab")
		)
		(fp_line
			(start 0.12065 -0.3048)
			(end 0.67945 -0.3048)
			(stroke
				(width 0.1)
				(type default)
			)
			(layer "F.Fab")
		)
		(fp_line
			(start 0.12065 -0.2794)
			(end 0.12065 -0.3048)
			(stroke
				(width 0.1)
				(type default)
			)
			(layer "F.Fab")
		)
		(fp_line
			(start -0.12065 -0.2794)
			(end 0.12065 -0.2794)
			(stroke
				(width 0.1)
				(type default)
			)
			(layer "F.Fab")
		)
		(fp_line
			(start 0.120396 0.2794)
			(end -0.12065 0.2794)
			(stroke
				(width 0.1)
				(type default)
			)
			(layer "F.Fab")
		)
		(fp_line
			(start -0.12065 0.2794)
			(end -0.12065 0.3048)
			(stroke
				(width 0.1)
				(type default)
			)
			(layer "F.Fab")
		)
		(fp_line
			(start 0.67945 0.3048)
			(end 0.120396 0.3048)
			(stroke
				(width 0.1)
				(type default)
			)
			(layer "F.Fab")
		)
		(fp_line
			(start 0.120396 0.3048)
			(end 0.120396 0.2794)
			(stroke
				(width 0.1)
				(type default)
			)
			(layer "F.Fab")
		)
		(fp_line
			(start -0.12065 0.3048)
			(end -0.67945 0.3048)
			(stroke
				(width 0.1)
				(type default)
			)
			(layer "F.Fab")
		)
		(fp_line
			(start -0.67945 0.3048)
			(end -0.67945 -0.305054)
			(stroke
				(width 0.1)
				(type default)
			)
			(layer "F.Fab")
		)
		(pad "1" smd circle
			(at -0.40005 0 90)
			(size 0 0)
			(layers "F.Cu" "F.Mask" "F.Paste")
			(net "FM_UV_ADR_TRIGGER_N_R2")
		)
		(pad "2" smd circle
			(at 0.40005 0 90)
			(size 0 0)
			(layers "F.Cu" "F.Mask" "F.Paste")
			(net "FM_UV_ADR_TRIGGER_N")
		)
	)
	(footprint ""
		(layer "F.Cu")
		(at 93.422978 -336.192368 90)
		(property "Reference" "PC557"
			(at 0 0 90)
			(layer "F.SilkS")
			(hide yes)
			(effects
				(font
					(size 1.27 1.27)
				)
			)
		)
		(property "Value" ""
			(at 0 0 90)
			(layer "F.Fab")
			(effects
				(font
					(size 1.27 1.27)
				)
			)
		)
		(duplicate_pad_numbers_are_jumpers no)
		(fp_line
			(start 0.7874 -0.4064)
			(end 0.7874 0.4064)
			(stroke
				(width 0.1524)
				(type default)
			)
			(layer "F.SilkS")
		)
		(fp_line
			(start -0.7874 -0.4064)
			(end 0.7874 -0.4064)
			(stroke
				(width 0.1524)
				(type default)
			)
			(layer "F.SilkS")
		)
		(fp_line
			(start 0.7874 0.4064)
			(end -0.7874 0.4064)
			(stroke
				(width 0.1524)
				(type default)
			)
			(layer "F.SilkS")
		)
		(fp_line
			(start -0.7874 0.4064)
			(end -0.7874 -0.4064)
			(stroke
				(width 0.1524)
				(type default)
			)
			(layer "F.SilkS")
		)
		(fp_line
			(start -0.12065 -0.305054)
			(end -0.12065 -0.2794)
			(stroke
				(width 0.1)
				(type default)
			)
			(layer "F.Fab")
		)
		(fp_line
			(start -0.67945 -0.305054)
			(end -0.12065 -0.305054)
			(stroke
				(width 0.1)
				(type default)
			)
			(layer "F.Fab")
		)
		(fp_line
			(start 0.67945 -0.3048)
			(end 0.67945 0.3048)
			(stroke
				(width 0.1)
				(type default)
			)
			(layer "F.Fab")
		)
		(fp_line
			(start 0.12065 -0.3048)
			(end 0.67945 -0.3048)
			(stroke
				(width 0.1)
				(type default)
			)
			(layer "F.Fab")
		)
		(fp_line
			(start 0.12065 -0.2794)
			(end 0.12065 -0.3048)
			(stroke
				(width 0.1)
				(type default)
			)
			(layer "F.Fab")
		)
		(fp_line
			(start -0.12065 -0.2794)
			(end 0.12065 -0.2794)
			(stroke
				(width 0.1)
				(type default)
			)
			(layer "F.Fab")
		)
		(fp_line
			(start 0.120396 0.2794)
			(end -0.12065 0.2794)
			(stroke
				(width 0.1)
				(type default)
			)
			(layer "F.Fab")
		)
		(fp_line
			(start -0.12065 0.2794)
			(end -0.12065 0.3048)
			(stroke
				(width 0.1)
				(type default)
			)
			(layer "F.Fab")
		)
		(fp_line
			(start 0.67945 0.3048)
			(end 0.120396 0.3048)
			(stroke
				(width 0.1)
				(type default)
			)
			(layer "F.Fab")
		)
		(fp_line
			(start 0.120396 0.3048)
			(end 0.120396 0.2794)
			(stroke
				(width 0.1)
				(type default)
			)
			(layer "F.Fab")
		)
		(fp_line
			(start -0.12065 0.3048)
			(end -0.67945 0.3048)
			(stroke
				(width 0.1)
				(type default)
			)
			(layer "F.Fab")
		)
		(fp_line
			(start -0.67945 0.3048)
			(end -0.67945 -0.305054)
			(stroke
				(width 0.1)
				(type default)
			)
			(layer "F.Fab")
		)
		(pad "1" smd circle
			(at -0.40005 0 90)
			(size 0 0)
			(layers "F.Cu" "F.Mask" "F.Paste")
			(net "PVCCIN_CPU1_VDD1")
		)
		(pad "2" smd circle
			(at 0.40005 0 90)
			(size 0 0)
			(layers "F.Cu" "F.Mask" "F.Paste")
			(net "GND")
		)
	)
	(footprint ""
		(layer "F.Cu")
		(at 17.864582 -410.802836 -90)
		(property "Reference" "R2848"
			(at 0 0 270)
			(layer "F.SilkS")
			(hide yes)
			(effects
				(font
					(size 1.27 1.27)
				)
			)
		)
		(property "Value" ""
			(at 0 0 270)
			(layer "F.Fab")
			(effects
				(font
					(size 1.27 1.27)
				)
			)
		)
		(duplicate_pad_numbers_are_jumpers no)
		(fp_line
			(start -0.7874 0.4064)
			(end -0.7874 -0.4064)
			(stroke
				(width 0.1524)
				(type default)
			)
			(layer "F.SilkS")
		)
		(fp_line
			(start 0.7874 0.4064)
			(end -0.7874 0.4064)
			(stroke
				(width 0.1524)
				(type default)
			)
			(layer "F.SilkS")
		)
		(fp_line
			(start -0.7874 -0.4064)
			(end 0.7874 -0.4064)
			(stroke
				(width 0.1524)
				(type default)
			)
			(layer "F.SilkS")
		)
		(fp_line
			(start 0.7874 -0.4064)
			(end 0.7874 0.4064)
			(stroke
				(width 0.1524)
				(type default)
			)
			(layer "F.SilkS")
		)
		(fp_line
			(start -0.67945 0.3048)
			(end -0.67945 -0.305054)
			(stroke
				(width 0.1)
				(type default)
			)
			(layer "F.Fab")
		)
		(fp_line
			(start -0.12065 0.3048)
			(end -0.67945 0.3048)
			(stroke
				(width 0.1)
				(type default)
			)
			(layer "F.Fab")
		)
		(fp_line
			(start 0.120396 0.3048)
			(end 0.120396 0.2794)
			(stroke
				(width 0.1)
				(type default)
			)
			(layer "F.Fab")
		)
		(fp_line
			(start 0.67945 0.3048)
			(end 0.120396 0.3048)
			(stroke
				(width 0.1)
				(type default)
			)
			(layer "F.Fab")
		)
		(fp_line
			(start -0.12065 0.2794)
			(end -0.12065 0.3048)
			(stroke
				(width 0.1)
				(type default)
			)
			(layer "F.Fab")
		)
		(fp_line
			(start 0.120396 0.2794)
			(end -0.12065 0.2794)
			(stroke
				(width 0.1)
				(type default)
			)
			(layer "F.Fab")
		)
		(fp_line
			(start -0.12065 -0.2794)
			(end 0.12065 -0.2794)
			(stroke
				(width 0.1)
				(type default)
			)
			(layer "F.Fab")
		)
		(fp_line
			(start 0.12065 -0.2794)
			(end 0.12065 -0.3048)
			(stroke
				(width 0.1)
				(type default)
			)
			(layer "F.Fab")
		)
		(fp_line
			(start 0.12065 -0.3048)
			(end 0.67945 -0.3048)
			(stroke
				(width 0.1)
				(type default)
			)
			(layer "F.Fab")
		)
		(fp_line
			(start 0.67945 -0.3048)
			(end 0.67945 0.3048)
			(stroke
				(width 0.1)
				(type default)
			)
			(layer "F.Fab")
		)
		(fp_line
			(start -0.67945 -0.305054)
			(end -0.12065 -0.305054)
			(stroke
				(width 0.1)
				(type default)
			)
			(layer "F.Fab")
		)
		(fp_line
			(start -0.12065 -0.305054)
			(end -0.12065 -0.2794)
			(stroke
				(width 0.1)
				(type default)
			)
			(layer "F.Fab")
		)
		(pad "1" smd circle
			(at -0.40005 0 270)
			(size 0 0)
			(layers "F.Cu" "F.Mask" "F.Paste")
			(net "RST_SWB_BIC_N")
		)
		(pad "2" smd circle
			(at 0.40005 0 270)
			(size 0 0)
			(layers "F.Cu" "F.Mask" "F.Paste")
			(net "RST_SWB_BIC_R_N")
		)
	)
	(footprint ""
		(layer "F.Cu")
		(at 298.66082 -419.02761 -90)
		(property "Reference" "C2268"
			(at 0 0 270)
			(layer "F.SilkS")
			(hide yes)
			(effects
				(font
					(size 1.27 1.27)
				)
			)
		)
		(property "Value" ""
			(at 0 0 270)
			(layer "F.Fab")
			(effects
				(font
					(size 1.27 1.27)
				)
			)
		)
		(duplicate_pad_numbers_are_jumpers no)
		(fp_line
			(start -0.7874 0.4064)
			(end -0.7874 -0.4064)
			(stroke
				(width 0.1524)
				(type default)
			)
			(layer "F.SilkS")
		)
		(fp_line
			(start 0.7874 0.4064)
			(end -0.7874 0.4064)
			(stroke
				(width 0.1524)
				(type default)
			)
			(layer "F.SilkS")
		)
		(fp_line
			(start -0.7874 -0.4064)
			(end 0.7874 -0.4064)
			(stroke
				(width 0.1524)
				(type default)
			)
			(layer "F.SilkS")
		)
		(fp_line
			(start 0.7874 -0.4064)
			(end 0.7874 0.4064)
			(stroke
				(width 0.1524)
				(type default)
			)
			(layer "F.SilkS")
		)
		(fp_line
			(start -0.67945 0.3048)
			(end -0.67945 -0.305054)
			(stroke
				(width 0.1)
				(type default)
			)
			(layer "F.Fab")
		)
		(fp_line
			(start -0.12065 0.3048)
			(end -0.67945 0.3048)
			(stroke
				(width 0.1)
				(type default)
			)
			(layer "F.Fab")
		)
		(fp_line
			(start 0.120396 0.3048)
			(end 0.120396 0.2794)
			(stroke
				(width 0.1)
				(type default)
			)
			(layer "F.Fab")
		)
		(fp_line
			(start 0.67945 0.3048)
			(end 0.120396 0.3048)
			(stroke
				(width 0.1)
				(type default)
			)
			(layer "F.Fab")
		)
		(fp_line
			(start -0.12065 0.2794)
			(end -0.12065 0.3048)
			(stroke
				(width 0.1)
				(type default)
			)
			(layer "F.Fab")
		)
		(fp_line
			(start 0.120396 0.2794)
			(end -0.12065 0.2794)
			(stroke
				(width 0.1)
				(type default)
			)
			(layer "F.Fab")
		)
		(fp_line
			(start -0.12065 -0.2794)
			(end 0.12065 -0.2794)
			(stroke
				(width 0.1)
				(type default)
			)
			(layer "F.Fab")
		)
		(fp_line
			(start 0.12065 -0.2794)
			(end 0.12065 -0.3048)
			(stroke
				(width 0.1)
				(type default)
			)
			(layer "F.Fab")
		)
		(fp_line
			(start 0.12065 -0.3048)
			(end 0.67945 -0.3048)
			(stroke
				(width 0.1)
				(type default)
			)
			(layer "F.Fab")
		)
		(fp_line
			(start 0.67945 -0.3048)
			(end 0.67945 0.3048)
			(stroke
				(width 0.1)
				(type default)
			)
			(layer "F.Fab")
		)
		(fp_line
			(start -0.67945 -0.305054)
			(end -0.12065 -0.305054)
			(stroke
				(width 0.1)
				(type default)
			)
			(layer "F.Fab")
		)
		(fp_line
			(start -0.12065 -0.305054)
			(end -0.12065 -0.2794)
			(stroke
				(width 0.1)
				(type default)
			)
			(layer "F.Fab")
		)
		(pad "1" smd circle
			(at -0.40005 0 270)
			(size 0 0)
			(layers "F.Cu" "F.Mask" "F.Paste")
			(net "GPU_3V3IO_RSVD5_FFU_ISO")
		)
		(pad "2" smd circle
			(at 0.40005 0 270)
			(size 0 0)
			(layers "F.Cu" "F.Mask" "F.Paste")
			(net "GND")
		)
	)
	(footprint ""
		(layer "F.Cu")
		(at 80.795876 -79.078836)
		(property "Reference" "D80"
			(at -41.50741 34.331402 90)
			(unlocked yes)
			(layer "F.SilkS")
			(effects
				(font
					(size 0.635 0.4064)
					(thickness 0.1524)
				)
				(justify left)
			)
		)
		(property "Value" ""
			(at 0 0 0)
			(layer "F.Fab")
			(effects
				(font
					(size 1.27 1.27)
				)
			)
		)
		(duplicate_pad_numbers_are_jumpers no)
		(fp_line
			(start -0.90678 0.4826)
			(end -0.90678 -0.4699)
			(stroke
				(width 0.1524)
				(type default)
			)
			(layer "F.SilkS")
		)
		(fp_line
			(start -0.89408 -0.4826)
			(end 0.90678 -0.4826)
			(stroke
				(width 0.1524)
				(type default)
			)
			(layer "F.SilkS")
		)
		(fp_line
			(start -0.79248 -0.4826)
			(end 1.03378 -0.4826)
			(stroke
				(width 0.1524)
				(type default)
			)
			(layer "F.SilkS")
		)
		(fp_line
			(start -0.64008 -0.4826)
			(end 1.16078 -0.4826)
			(stroke
				(width 0.1524)
				(type default)
			)
			(layer "F.SilkS")
		)
		(fp_line
			(start 0.90678 -0.4826)
			(end 0.90678 0.4826)
			(stroke
				(width 0.1524)
				(type default)
			)
			(layer "F.SilkS")
		)
		(fp_line
			(start 0.90678 0.4826)
			(end -0.90678 0.4826)
			(stroke
				(width 0.1524)
				(type default)
			)
			(layer "F.SilkS")
		)
		(fp_line
			(start 1.03378 -0.4826)
			(end 1.03378 0.4826)
			(stroke
				(width 0.1524)
				(type default)
			)
			(layer "F.SilkS")
		)
		(fp_line
			(start 1.03378 0.4826)
			(end -0.79248 0.4826)
			(stroke
				(width 0.1524)
				(type default)
			)
			(layer "F.SilkS")
		)
		(fp_line
			(start 1.16078 -0.4826)
			(end 1.16078 0.4826)
			(stroke
				(width 0.1524)
				(type default)
			)
			(layer "F.SilkS")
		)
		(fp_line
			(start 1.16078 0.4826)
			(end -0.64008 0.4826)
			(stroke
				(width 0.1524)
				(type default)
			)
			(layer "F.SilkS")
		)
		(fp_line
			(start -0.499872 -0.249936)
			(end 0.499872 -0.249936)
			(stroke
				(width 0.1)
				(type default)
			)
			(layer "F.Fab")
		)
		(fp_line
			(start -0.499872 0.249936)
			(end -0.499872 -0.249936)
			(stroke
				(width 0.1)
				(type default)
			)
			(layer "F.Fab")
		)
		(fp_line
			(start 0.499872 -0.249936)
			(end 0.499872 0.249936)
			(stroke
				(width 0.1)
				(type default)
			)
			(layer "F.Fab")
		)
		(fp_line
			(start 0.499872 0.249936)
			(end -0.499872 0.249936)
			(stroke
				(width 0.1)
				(type default)
			)
			(layer "F.Fab")
		)
		(pad "A" smd rect
			(at -0.47498 0)
			(size 0.6096 0.7112)
			(layers "F.Cu" "F.Mask" "F.Paste")
			(net "LED_PWRGD_PVCCD_HV_CPU1")
		)
		(pad "C" smd rect
			(at 0.47498 0)
			(size 0.6096 0.7112)
			(layers "F.Cu" "F.Mask" "F.Paste")
			(net "LED_PWRGD_PVCCD_HV_CPU1_D")
		)
	)
	(footprint ""
		(layer "F.Cu")
		(at 429.183038 -181.53507 90)
		(property "Reference" "PC1272"
			(at 0 0 90)
			(layer "F.SilkS")
			(hide yes)
			(effects
				(font
					(size 1.27 1.27)
				)
			)
		)
		(property "Value" ""
			(at 0 0 90)
			(layer "F.Fab")
			(effects
				(font
					(size 1.27 1.27)
				)
			)
		)
		(duplicate_pad_numbers_are_jumpers no)
		(fp_line
			(start 1.524 -0.762)
			(end 1.524 0.762)
			(stroke
				(width 0.1524)
				(type default)
			)
			(layer "F.SilkS")
		)
		(fp_line
			(start -1.524 -0.762)
			(end 1.524 -0.762)
			(stroke
				(width 0.1524)
				(type default)
			)
			(layer "F.SilkS")
		)
		(fp_line
			(start 1.524 0.762)
			(end -1.524 0.762)
			(stroke
				(width 0.1524)
				(type default)
			)
			(layer "F.SilkS")
		)
		(fp_line
			(start -1.524 0.762)
			(end -1.524 -0.762)
			(stroke
				(width 0.1524)
				(type default)
			)
			(layer "F.SilkS")
		)
		(fp_line
			(start 1.1049 -0.724916)
			(end -1.1049 -0.724916)
			(stroke
				(width 0.1)
				(type default)
			)
			(layer "F.Fab")
		)
		(fp_line
			(start -1.1049 -0.724916)
			(end -1.1049 0.724916)
			(stroke
				(width 0.1)
				(type default)
			)
			(layer "F.Fab")
		)
		(fp_line
			(start 1.1049 0.724916)
			(end 1.1049 -0.724916)
			(stroke
				(width 0.1)
				(type default)
			)
			(layer "F.Fab")
		)
		(fp_line
			(start -1.1049 0.724916)
			(end 1.1049 0.724916)
			(stroke
				(width 0.1)
				(type default)
			)
			(layer "F.Fab")
		)
		(pad "1" smd rect
			(at -0.889 0 270)
			(size 1.016 1.27)
			(layers "F.Cu" "F.Mask" "F.Paste")
			(net "SW_P12V_PVCCINFAON_CPU0_FLT")
		)
		(pad "2" smd rect
			(at 0.889 0 270)
			(size 1.016 1.27)
			(layers "F.Cu" "F.Mask" "F.Paste")
			(net "GND")
		)
	)
	(footprint ""
		(layer "F.Cu")
		(at 349.903288 -402.371052 -90)
		(property "Reference" "C1548"
			(at 0 0 270)
			(layer "F.SilkS")
			(hide yes)
			(effects
				(font
					(size 1.27 1.27)
				)
			)
		)
		(property "Value" ""
			(at 0 0 270)
			(layer "F.Fab")
			(effects
				(font
					(size 1.27 1.27)
				)
			)
		)
		(duplicate_pad_numbers_are_jumpers no)
		(fp_line
			(start -0.299974 0.150114)
			(end -0.299974 -0.150114)
			(stroke
				(width 0.1)
				(type default)
			)
			(layer "F.Fab")
		)
		(fp_line
			(start 0.299974 0.150114)
			(end -0.299974 0.150114)
			(stroke
				(width 0.1)
				(type default)
			)
			(layer "F.Fab")
		)
		(fp_line
			(start -0.299974 -0.150114)
			(end 0.299974 -0.150114)
			(stroke
				(width 0.1)
				(type default)
			)
			(layer "F.Fab")
		)
		(fp_line
			(start 0.299974 -0.150114)
			(end 0.299974 0.150114)
			(stroke
				(width 0.1)
				(type default)
			)
			(layer "F.Fab")
		)
		(pad "1" smd rect
			(at -0.2667 0 270)
			(size 0.3048 0.381)
			(layers "F.Cu" "F.Mask" "F.Paste")
			(net "P5E_CPU0_PE4_TX_C_DN<15>")
		)
		(pad "2" smd rect
			(at 0.2667 0 270)
			(size 0.3048 0.381)
			(layers "F.Cu" "F.Mask" "F.Paste")
			(net "P5E_CPU0_PE4_TX_DN<15>")
		)
	)
	(footprint ""
		(layer "F.Cu")
		(at 99.999546 -356.625652 -90)
		(property "Reference" "C2449"
			(at 0 0 270)
			(layer "F.SilkS")
			(hide yes)
			(effects
				(font
					(size 1.27 1.27)
				)
			)
		)
		(property "Value" ""
			(at 0 0 270)
			(layer "F.Fab")
			(effects
				(font
					(size 1.27 1.27)
				)
			)
		)
		(duplicate_pad_numbers_are_jumpers no)
		(fp_line
			(start -0.7874 0.4064)
			(end -0.7874 -0.4064)
			(stroke
				(width 0.1524)
				(type default)
			)
			(layer "F.SilkS")
		)
		(fp_line
			(start 0.7874 0.4064)
			(end -0.7874 0.4064)
			(stroke
				(width 0.1524)
				(type default)
			)
			(layer "F.SilkS")
		)
		(fp_line
			(start -0.7874 -0.4064)
			(end 0.7874 -0.4064)
			(stroke
				(width 0.1524)
				(type default)
			)
			(layer "F.SilkS")
		)
		(fp_line
			(start 0.7874 -0.4064)
			(end 0.7874 0.4064)
			(stroke
				(width 0.1524)
				(type default)
			)
			(layer "F.SilkS")
		)
		(fp_line
			(start -0.67945 0.3048)
			(end -0.67945 -0.305054)
			(stroke
				(width 0.1)
				(type default)
			)
			(layer "F.Fab")
		)
		(fp_line
			(start -0.12065 0.3048)
			(end -0.67945 0.3048)
			(stroke
				(width 0.1)
				(type default)
			)
			(layer "F.Fab")
		)
		(fp_line
			(start 0.120396 0.3048)
			(end 0.120396 0.2794)
			(stroke
				(width 0.1)
				(type default)
			)
			(layer "F.Fab")
		)
		(fp_line
			(start 0.67945 0.3048)
			(end 0.120396 0.3048)
			(stroke
				(width 0.1)
				(type default)
			)
			(layer "F.Fab")
		)
		(fp_line
			(start -0.12065 0.2794)
			(end -0.12065 0.3048)
			(stroke
				(width 0.1)
				(type default)
			)
			(layer "F.Fab")
		)
		(fp_line
			(start 0.120396 0.2794)
			(end -0.12065 0.2794)
			(stroke
				(width 0.1)
				(type default)
			)
			(layer "F.Fab")
		)
		(fp_line
			(start -0.12065 -0.2794)
			(end 0.12065 -0.2794)
			(stroke
				(width 0.1)
				(type default)
			)
			(layer "F.Fab")
		)
		(fp_line
			(start 0.12065 -0.2794)
			(end 0.12065 -0.3048)
			(stroke
				(width 0.1)
				(type default)
			)
			(layer "F.Fab")
		)
		(fp_line
			(start 0.12065 -0.3048)
			(end 0.67945 -0.3048)
			(stroke
				(width 0.1)
				(type default)
			)
			(layer "F.Fab")
		)
		(fp_line
			(start 0.67945 -0.3048)
			(end 0.67945 0.3048)
			(stroke
				(width 0.1)
				(type default)
			)
			(layer "F.Fab")
		)
		(fp_line
			(start -0.67945 -0.305054)
			(end -0.12065 -0.305054)
			(stroke
				(width 0.1)
				(type default)
			)
			(layer "F.Fab")
		)
		(fp_line
			(start -0.12065 -0.305054)
			(end -0.12065 -0.2794)
			(stroke
				(width 0.1)
				(type default)
			)
			(layer "F.Fab")
		)
		(pad "1" smd circle
			(at -0.40005 0 270)
			(size 0 0)
			(layers "F.Cu" "F.Mask" "F.Paste")
			(net "PVNN_TERM_CPU1")
		)
		(pad "2" smd circle
			(at 0.40005 0 270)
			(size 0 0)
			(layers "F.Cu" "F.Mask" "F.Paste")
			(net "GND")
		)
	)
	(footprint ""
		(layer "F.Cu")
		(at 432.41468 -174.78502)
		(property "Reference" "PC237"
			(at 0 0 0)
			(layer "F.SilkS")
			(hide yes)
			(effects
				(font
					(size 1.27 1.27)
				)
			)
		)
		(property "Value" ""
			(at 0 0 0)
			(layer "F.Fab")
			(effects
				(font
					(size 1.27 1.27)
				)
			)
		)
		(duplicate_pad_numbers_are_jumpers no)
		(fp_line
			(start -0.7874 -0.4064)
			(end 0.7874 -0.4064)
			(stroke
				(width 0.1524)
				(type default)
			)
			(layer "F.SilkS")
		)
		(fp_line
			(start -0.7874 0.4064)
			(end -0.7874 -0.4064)
			(stroke
				(width 0.1524)
				(type default)
			)
			(layer "F.SilkS")
		)
		(fp_line
			(start 0.7874 -0.4064)
			(end 0.7874 0.4064)
			(stroke
				(width 0.1524)
				(type default)
			)
			(layer "F.SilkS")
		)
		(fp_line
			(start 0.7874 0.4064)
			(end -0.7874 0.4064)
			(stroke
				(width 0.1524)
				(type default)
			)
			(layer "F.SilkS")
		)
		(fp_line
			(start -0.67945 -0.305054)
			(end -0.12065 -0.305054)
			(stroke
				(width 0.1)
				(type default)
			)
			(layer "F.Fab")
		)
		(fp_line
			(start -0.67945 0.3048)
			(end -0.67945 -0.305054)
			(stroke
				(width 0.1)
				(type default)
			)
			(layer "F.Fab")
		)
		(fp_line
			(start -0.12065 -0.305054)
			(end -0.12065 -0.2794)
			(stroke
				(width 0.1)
				(type default)
			)
			(layer "F.Fab")
		)
		(fp_line
			(start -0.12065 -0.2794)
			(end 0.12065 -0.2794)
			(stroke
				(width 0.1)
				(type default)
			)
			(layer "F.Fab")
		)
		(fp_line
			(start -0.12065 0.2794)
			(end -0.12065 0.3048)
			(stroke
				(width 0.1)
				(type default)
			)
			(layer "F.Fab")
		)
		(fp_line
			(start -0.12065 0.3048)
			(end -0.67945 0.3048)
			(stroke
				(width 0.1)
				(type default)
			)
			(layer "F.Fab")
		)
		(fp_line
			(start 0.120396 0.2794)
			(end -0.12065 0.2794)
			(stroke
				(width 0.1)
				(type default)
			)
			(layer "F.Fab")
		)
		(fp_line
			(start 0.120396 0.3048)
			(end 0.120396 0.2794)
			(stroke
				(width 0.1)
				(type default)
			)
			(layer "F.Fab")
		)
		(fp_line
			(start 0.12065 -0.3048)
			(end 0.67945 -0.3048)
			(stroke
				(width 0.1)
				(type default)
			)
			(layer "F.Fab")
		)
		(fp_line
			(start 0.12065 -0.2794)
			(end 0.12065 -0.3048)
			(stroke
				(width 0.1)
				(type default)
			)
			(layer "F.Fab")
		)
		(fp_line
			(start 0.67945 -0.3048)
			(end 0.67945 0.3048)
			(stroke
				(width 0.1)
				(type default)
			)
			(layer "F.Fab")
		)
		(fp_line
			(start 0.67945 0.3048)
			(end 0.120396 0.3048)
			(stroke
				(width 0.1)
				(type default)
			)
			(layer "F.Fab")
		)
		(pad "1" smd circle
			(at -0.40005 0)
			(size 0 0)
			(layers "F.Cu" "F.Mask" "F.Paste")
			(net "PVNN_MAIN_CPU0_FB")
		)
		(pad "2" smd circle
			(at 0.40005 0)
			(size 0 0)
			(layers "F.Cu" "F.Mask" "F.Paste")
			(net "PVNN_MAIN_CPU0_FB_RC")
		)
	)
	(footprint ""
		(layer "F.Cu")
		(at 151.676354 -402.371052 -90)
		(property "Reference" "C762"
			(at 0 0 270)
			(layer "F.SilkS")
			(hide yes)
			(effects
				(font
					(size 1.27 1.27)
				)
			)
		)
		(property "Value" ""
			(at 0 0 270)
			(layer "F.Fab")
			(effects
				(font
					(size 1.27 1.27)
				)
			)
		)
		(duplicate_pad_numbers_are_jumpers no)
		(fp_line
			(start -0.299974 0.150114)
			(end -0.299974 -0.150114)
			(stroke
				(width 0.1)
				(type default)
			)
			(layer "F.Fab")
		)
		(fp_line
			(start 0.299974 0.150114)
			(end -0.299974 0.150114)
			(stroke
				(width 0.1)
				(type default)
			)
			(layer "F.Fab")
		)
		(fp_line
			(start -0.299974 -0.150114)
			(end 0.299974 -0.150114)
			(stroke
				(width 0.1)
				(type default)
			)
			(layer "F.Fab")
		)
		(fp_line
			(start 0.299974 -0.150114)
			(end 0.299974 0.150114)
			(stroke
				(width 0.1)
				(type default)
			)
			(layer "F.Fab")
		)
		(pad "1" smd rect
			(at -0.2667 0 270)
			(size 0.3048 0.381)
			(layers "F.Cu" "F.Mask" "F.Paste")
			(net "P5E_CPU1_PE2_TX_C_DN<5>")
		)
		(pad "2" smd rect
			(at 0.2667 0 270)
			(size 0.3048 0.381)
			(layers "F.Cu" "F.Mask" "F.Paste")
			(net "P5E_CPU1_PE2_TX_DN<5>")
		)
	)
	(footprint ""
		(layer "F.Cu")
		(at 44.848018 -437.792368 180)
		(property "Reference" "R2992"
			(at 0 0 180)
			(layer "F.SilkS")
			(hide yes)
			(effects
				(font
					(size 1.27 1.27)
				)
			)
		)
		(property "Value" ""
			(at 0 0 180)
			(layer "F.Fab")
			(effects
				(font
					(size 1.27 1.27)
				)
			)
		)
		(duplicate_pad_numbers_are_jumpers no)
		(fp_line
			(start 0.7874 0.4064)
			(end -0.7874 0.4064)
			(stroke
				(width 0.1524)
				(type default)
			)
			(layer "F.SilkS")
		)
		(fp_line
			(start 0.7874 -0.4064)
			(end 0.7874 0.4064)
			(stroke
				(width 0.1524)
				(type default)
			)
			(layer "F.SilkS")
		)
		(fp_line
			(start -0.7874 0.4064)
			(end -0.7874 -0.4064)
			(stroke
				(width 0.1524)
				(type default)
			)
			(layer "F.SilkS")
		)
		(fp_line
			(start -0.7874 -0.4064)
			(end 0.7874 -0.4064)
			(stroke
				(width 0.1524)
				(type default)
			)
			(layer "F.SilkS")
		)
		(fp_line
			(start 0.67945 0.3048)
			(end 0.120396 0.3048)
			(stroke
				(width 0.1)
				(type default)
			)
			(layer "F.Fab")
		)
		(fp_line
			(start 0.67945 -0.3048)
			(end 0.67945 0.3048)
			(stroke
				(width 0.1)
				(type default)
			)
			(layer "F.Fab")
		)
		(fp_line
			(start 0.12065 -0.2794)
			(end 0.12065 -0.3048)
			(stroke
				(width 0.1)
				(type default)
			)
			(layer "F.Fab")
		)
		(fp_line
			(start 0.12065 -0.3048)
			(end 0.67945 -0.3048)
			(stroke
				(width 0.1)
				(type default)
			)
			(layer "F.Fab")
		)
		(fp_line
			(start 0.120396 0.3048)
			(end 0.120396 0.2794)
			(stroke
				(width 0.1)
				(type default)
			)
			(layer "F.Fab")
		)
		(fp_line
			(start 0.120396 0.2794)
			(end -0.12065 0.2794)
			(stroke
				(width 0.1)
				(type default)
			)
			(layer "F.Fab")
		)
		(fp_line
			(start -0.12065 0.3048)
			(end -0.67945 0.3048)
			(stroke
				(width 0.1)
				(type default)
			)
			(layer "F.Fab")
		)
		(fp_line
			(start -0.12065 0.2794)
			(end -0.12065 0.3048)
			(stroke
				(width 0.1)
				(type default)
			)
			(layer "F.Fab")
		)
		(fp_line
			(start -0.12065 -0.2794)
			(end 0.12065 -0.2794)
			(stroke
				(width 0.1)
				(type default)
			)
			(layer "F.Fab")
		)
		(fp_line
			(start -0.12065 -0.305054)
			(end -0.12065 -0.2794)
			(stroke
				(width 0.1)
				(type default)
			)
			(layer "F.Fab")
		)
		(fp_line
			(start -0.67945 0.3048)
			(end -0.67945 -0.305054)
			(stroke
				(width 0.1)
				(type default)
			)
			(layer "F.Fab")
		)
		(fp_line
			(start -0.67945 -0.305054)
			(end -0.12065 -0.305054)
			(stroke
				(width 0.1)
				(type default)
			)
			(layer "F.Fab")
		)
		(pad "1" smd circle
			(at -0.40005 0 180)
			(size 0 0)
			(layers "F.Cu" "F.Mask" "F.Paste")
			(net "SMB_BMC_GPU_EN")
		)
		(pad "2" smd circle
			(at 0.40005 0 180)
			(size 0 0)
			(layers "F.Cu" "F.Mask" "F.Paste")
			(net "SMB_BMC_GPU_EN_R3")
		)
	)
	(footprint ""
		(layer "F.Cu")
		(at 303.821084 -426.557186 -90)
		(property "Reference" "R4125"
			(at 0 0 270)
			(layer "F.SilkS")
			(hide yes)
			(effects
				(font
					(size 1.27 1.27)
				)
			)
		)
		(property "Value" ""
			(at 0 0 270)
			(layer "F.Fab")
			(effects
				(font
					(size 1.27 1.27)
				)
			)
		)
		(duplicate_pad_numbers_are_jumpers no)
		(fp_line
			(start -0.7874 0.4064)
			(end -0.7874 -0.4064)
			(stroke
				(width 0.1524)
				(type default)
			)
			(layer "F.SilkS")
		)
		(fp_line
			(start 0.7874 0.4064)
			(end -0.7874 0.4064)
			(stroke
				(width 0.1524)
				(type default)
			)
			(layer "F.SilkS")
		)
		(fp_line
			(start -0.7874 -0.4064)
			(end 0.7874 -0.4064)
			(stroke
				(width 0.1524)
				(type default)
			)
			(layer "F.SilkS")
		)
		(fp_line
			(start 0.7874 -0.4064)
			(end 0.7874 0.4064)
			(stroke
				(width 0.1524)
				(type default)
			)
			(layer "F.SilkS")
		)
		(fp_line
			(start -0.67945 0.3048)
			(end -0.67945 -0.305054)
			(stroke
				(width 0.1)
				(type default)
			)
			(layer "F.Fab")
		)
		(fp_line
			(start -0.12065 0.3048)
			(end -0.67945 0.3048)
			(stroke
				(width 0.1)
				(type default)
			)
			(layer "F.Fab")
		)
		(fp_line
			(start 0.120396 0.3048)
			(end 0.120396 0.2794)
			(stroke
				(width 0.1)
				(type default)
			)
			(layer "F.Fab")
		)
		(fp_line
			(start 0.67945 0.3048)
			(end 0.120396 0.3048)
			(stroke
				(width 0.1)
				(type default)
			)
			(layer "F.Fab")
		)
		(fp_line
			(start -0.12065 0.2794)
			(end -0.12065 0.3048)
			(stroke
				(width 0.1)
				(type default)
			)
			(layer "F.Fab")
		)
		(fp_line
			(start 0.120396 0.2794)
			(end -0.12065 0.2794)
			(stroke
				(width 0.1)
				(type default)
			)
			(layer "F.Fab")
		)
		(fp_line
			(start -0.12065 -0.2794)
			(end 0.12065 -0.2794)
			(stroke
				(width 0.1)
				(type default)
			)
			(layer "F.Fab")
		)
		(fp_line
			(start 0.12065 -0.2794)
			(end 0.12065 -0.3048)
			(stroke
				(width 0.1)
				(type default)
			)
			(layer "F.Fab")
		)
		(fp_line
			(start 0.12065 -0.3048)
			(end 0.67945 -0.3048)
			(stroke
				(width 0.1)
				(type default)
			)
			(layer "F.Fab")
		)
		(fp_line
			(start 0.67945 -0.3048)
			(end 0.67945 0.3048)
			(stroke
				(width 0.1)
				(type default)
			)
			(layer "F.Fab")
		)
		(fp_line
			(start -0.67945 -0.305054)
			(end -0.12065 -0.305054)
			(stroke
				(width 0.1)
				(type default)
			)
			(layer "F.Fab")
		)
		(fp_line
			(start -0.12065 -0.305054)
			(end -0.12065 -0.2794)
			(stroke
				(width 0.1)
				(type default)
			)
			(layer "F.Fab")
		)
		(pad "1" smd circle
			(at -0.40005 0 270)
			(size 0 0)
			(layers "F.Cu" "F.Mask" "F.Paste")
			(net "P3V3_AUX")
		)
		(pad "2" smd circle
			(at 0.40005 0 270)
			(size 0 0)
			(layers "F.Cu" "F.Mask" "F.Paste")
			(net "GPU_3V3IO_RSVD0_FFU_N")
		)
	)
	(footprint ""
		(layer "F.Cu")
		(at 306.22367 -428.86249)
		(property "Reference" "R4578"
			(at 0 0 0)
			(layer "F.SilkS")
			(hide yes)
			(effects
				(font
					(size 1.27 1.27)
				)
			)
		)
		(property "Value" ""
			(at 0 0 0)
			(layer "F.Fab")
			(effects
				(font
					(size 1.27 1.27)
				)
			)
		)
		(duplicate_pad_numbers_are_jumpers no)
		(fp_line
			(start -0.7874 -0.4064)
			(end 0.7874 -0.4064)
			(stroke
				(width 0.1524)
				(type default)
			)
			(layer "F.SilkS")
		)
		(fp_line
			(start -0.7874 0.4064)
			(end -0.7874 -0.4064)
			(stroke
				(width 0.1524)
				(type default)
			)
			(layer "F.SilkS")
		)
		(fp_line
			(start 0.7874 -0.4064)
			(end 0.7874 0.4064)
			(stroke
				(width 0.1524)
				(type default)
			)
			(layer "F.SilkS")
		)
		(fp_line
			(start 0.7874 0.4064)
			(end -0.7874 0.4064)
			(stroke
				(width 0.1524)
				(type default)
			)
			(layer "F.SilkS")
		)
		(fp_line
			(start -0.67945 -0.305054)
			(end -0.12065 -0.305054)
			(stroke
				(width 0.1)
				(type default)
			)
			(layer "F.Fab")
		)
		(fp_line
			(start -0.67945 0.3048)
			(end -0.67945 -0.305054)
			(stroke
				(width 0.1)
				(type default)
			)
			(layer "F.Fab")
		)
		(fp_line
			(start -0.12065 -0.305054)
			(end -0.12065 -0.2794)
			(stroke
				(width 0.1)
				(type default)
			)
			(layer "F.Fab")
		)
		(fp_line
			(start -0.12065 -0.2794)
			(end 0.12065 -0.2794)
			(stroke
				(width 0.1)
				(type default)
			)
			(layer "F.Fab")
		)
		(fp_line
			(start -0.12065 0.2794)
			(end -0.12065 0.3048)
			(stroke
				(width 0.1)
				(type default)
			)
			(layer "F.Fab")
		)
		(fp_line
			(start -0.12065 0.3048)
			(end -0.67945 0.3048)
			(stroke
				(width 0.1)
				(type default)
			)
			(layer "F.Fab")
		)
		(fp_line
			(start 0.120396 0.2794)
			(end -0.12065 0.2794)
			(stroke
				(width 0.1)
				(type default)
			)
			(layer "F.Fab")
		)
		(fp_line
			(start 0.120396 0.3048)
			(end 0.120396 0.2794)
			(stroke
				(width 0.1)
				(type default)
			)
			(layer "F.Fab")
		)
		(fp_line
			(start 0.12065 -0.3048)
			(end 0.67945 -0.3048)
			(stroke
				(width 0.1)
				(type default)
			)
			(layer "F.Fab")
		)
		(fp_line
			(start 0.12065 -0.2794)
			(end 0.12065 -0.3048)
			(stroke
				(width 0.1)
				(type default)
			)
			(layer "F.Fab")
		)
		(fp_line
			(start 0.67945 -0.3048)
			(end 0.67945 0.3048)
			(stroke
				(width 0.1)
				(type default)
			)
			(layer "F.Fab")
		)
		(fp_line
			(start 0.67945 0.3048)
			(end 0.120396 0.3048)
			(stroke
				(width 0.1)
				(type default)
			)
			(layer "F.Fab")
		)
		(pad "1" smd circle
			(at -0.40005 0)
			(size 0 0)
			(layers "F.Cu" "F.Mask" "F.Paste")
			(net "PRSNT_CABLE_GPU_A2_N")
		)
		(pad "2" smd circle
			(at 0.40005 0)
			(size 0 0)
			(layers "F.Cu" "F.Mask" "F.Paste")
			(net "PRSNT_CABLE_GPU_A2_ISO_N")
		)
	)
	(footprint ""
		(layer "F.Cu")
		(at 374.46077 -402.371052 -90)
		(property "Reference" "C937"
			(at 0 0 270)
			(layer "F.SilkS")
			(hide yes)
			(effects
				(font
					(size 1.27 1.27)
				)
			)
		)
		(property "Value" ""
			(at 0 0 270)
			(layer "F.Fab")
			(effects
				(font
					(size 1.27 1.27)
				)
			)
		)
		(duplicate_pad_numbers_are_jumpers no)
		(fp_line
			(start -0.299974 0.150114)
			(end -0.299974 -0.150114)
			(stroke
				(width 0.1)
				(type default)
			)
			(layer "F.Fab")
		)
		(fp_line
			(start 0.299974 0.150114)
			(end -0.299974 0.150114)
			(stroke
				(width 0.1)
				(type default)
			)
			(layer "F.Fab")
		)
		(fp_line
			(start -0.299974 -0.150114)
			(end 0.299974 -0.150114)
			(stroke
				(width 0.1)
				(type default)
			)
			(layer "F.Fab")
		)
		(fp_line
			(start 0.299974 -0.150114)
			(end 0.299974 0.150114)
			(stroke
				(width 0.1)
				(type default)
			)
			(layer "F.Fab")
		)
		(pad "1" smd rect
			(at -0.2667 0 270)
			(size 0.3048 0.381)
			(layers "F.Cu" "F.Mask" "F.Paste")
			(net "P5E_CPU0_PE2_TX_C_DP<14>")
		)
		(pad "2" smd rect
			(at 0.2667 0 270)
			(size 0.3048 0.381)
			(layers "F.Cu" "F.Mask" "F.Paste")
			(net "P5E_CPU0_PE2_TX_DP<14>")
		)
	)
	(footprint ""
		(layer "F.Cu")
		(at 197.104 -92.801948 90)
		(property "Reference" "R4610"
			(at 0 0 90)
			(layer "F.SilkS")
			(hide yes)
			(effects
				(font
					(size 1.27 1.27)
				)
			)
		)
		(property "Value" ""
			(at 0 0 90)
			(layer "F.Fab")
			(effects
				(font
					(size 1.27 1.27)
				)
			)
		)
		(duplicate_pad_numbers_are_jumpers no)
		(fp_line
			(start 0.7874 -0.4064)
			(end 0.7874 0.4064)
			(stroke
				(width 0.1524)
				(type default)
			)
			(layer "F.SilkS")
		)
		(fp_line
			(start -0.7874 -0.4064)
			(end 0.7874 -0.4064)
			(stroke
				(width 0.1524)
				(type default)
			)
			(layer "F.SilkS")
		)
		(fp_line
			(start 0.7874 0.4064)
			(end -0.7874 0.4064)
			(stroke
				(width 0.1524)
				(type default)
			)
			(layer "F.SilkS")
		)
		(fp_line
			(start -0.7874 0.4064)
			(end -0.7874 -0.4064)
			(stroke
				(width 0.1524)
				(type default)
			)
			(layer "F.SilkS")
		)
		(fp_line
			(start -0.12065 -0.305054)
			(end -0.12065 -0.2794)
			(stroke
				(width 0.1)
				(type default)
			)
			(layer "F.Fab")
		)
		(fp_line
			(start -0.67945 -0.305054)
			(end -0.12065 -0.305054)
			(stroke
				(width 0.1)
				(type default)
			)
			(layer "F.Fab")
		)
		(fp_line
			(start 0.67945 -0.3048)
			(end 0.67945 0.3048)
			(stroke
				(width 0.1)
				(type default)
			)
			(layer "F.Fab")
		)
		(fp_line
			(start 0.12065 -0.3048)
			(end 0.67945 -0.3048)
			(stroke
				(width 0.1)
				(type default)
			)
			(layer "F.Fab")
		)
		(fp_line
			(start 0.12065 -0.2794)
			(end 0.12065 -0.3048)
			(stroke
				(width 0.1)
				(type default)
			)
			(layer "F.Fab")
		)
		(fp_line
			(start -0.12065 -0.2794)
			(end 0.12065 -0.2794)
			(stroke
				(width 0.1)
				(type default)
			)
			(layer "F.Fab")
		)
		(fp_line
			(start 0.120396 0.2794)
			(end -0.12065 0.2794)
			(stroke
				(width 0.1)
				(type default)
			)
			(layer "F.Fab")
		)
		(fp_line
			(start -0.12065 0.2794)
			(end -0.12065 0.3048)
			(stroke
				(width 0.1)
				(type default)
			)
			(layer "F.Fab")
		)
		(fp_line
			(start 0.67945 0.3048)
			(end 0.120396 0.3048)
			(stroke
				(width 0.1)
				(type default)
			)
			(layer "F.Fab")
		)
		(fp_line
			(start 0.120396 0.3048)
			(end 0.120396 0.2794)
			(stroke
				(width 0.1)
				(type default)
			)
			(layer "F.Fab")
		)
		(fp_line
			(start -0.12065 0.3048)
			(end -0.67945 0.3048)
			(stroke
				(width 0.1)
				(type default)
			)
			(layer "F.Fab")
		)
		(fp_line
			(start -0.67945 0.3048)
			(end -0.67945 -0.305054)
			(stroke
				(width 0.1)
				(type default)
			)
			(layer "F.Fab")
		)
		(pad "1" smd circle
			(at -0.40005 0 90)
			(size 0 0)
			(layers "F.Cu" "F.Mask" "F.Paste")
			(net "CLK_GEN2_GPU_FPGA_OE_R_N")
		)
		(pad "2" smd circle
			(at 0.40005 0 90)
			(size 0 0)
			(layers "F.Cu" "F.Mask" "F.Paste")
			(net "CLK_GEN2_GPU_FPGA_OE_N")
		)
	)
	(footprint ""
		(layer "F.Cu")
		(at 112.024922 -431.360072 180)
		(property "Reference" "J122"
			(at -4.893056 2.08026 0)
			(unlocked yes)
			(layer "F.SilkS")
			(effects
				(font
					(size 0.7874 0.5842)
					(thickness 0.1524)
				)
				(justify left)
			)
		)
		(property "Value" ""
			(at 0 0 180)
			(layer "F.Fab")
			(effects
				(font
					(size 1.27 1.27)
				)
			)
		)
		(duplicate_pad_numbers_are_jumpers no)
		(fp_line
			(start 3.525012 21.310092)
			(end 3.525012 7.151116)
			(stroke
				(width 0.1524)
				(type default)
			)
			(layer "F.SilkS")
		)
		(fp_line
			(start 3.525012 2.340356)
			(end 3.525012 -10.489946)
			(stroke
				(width 0.1524)
				(type default)
			)
			(layer "F.SilkS")
		)
		(fp_line
			(start 3.525012 -10.489946)
			(end -3.525012 -10.489946)
			(stroke
				(width 0.1524)
				(type default)
			)
			(layer "F.SilkS")
		)
		(fp_line
			(start -3.525012 21.310092)
			(end 3.525012 21.310092)
			(stroke
				(width 0.1524)
				(type default)
			)
			(layer "F.SilkS")
		)
		(fp_line
			(start -3.525012 10.6299)
			(end 3.525012 10.6299)
			(stroke
				(width 0.1524)
				(type default)
			)
			(layer "F.SilkS")
		)
		(fp_line
			(start -3.525012 -10.489946)
			(end -3.525012 21.310092)
			(stroke
				(width 0.1524)
				(type default)
			)
			(layer "F.SilkS")
		)
		(fp_line
			(start 3.525012 21.310092)
			(end 3.525012 -10.489946)
			(stroke
				(width 0.1)
				(type default)
			)
			(layer "F.Fab")
		)
		(fp_line
			(start 3.525012 -10.489946)
			(end -3.525012 -10.489946)
			(stroke
				(width 0.1)
				(type default)
			)
			(layer "F.Fab")
		)
		(fp_line
			(start -3.525012 21.310092)
			(end 3.525012 21.310092)
			(stroke
				(width 0.1)
				(type default)
			)
			(layer "F.Fab")
		)
		(fp_line
			(start -3.525012 -10.489946)
			(end -3.525012 21.310092)
			(stroke
				(width 0.1)
				(type default)
			)
			(layer "F.Fab")
		)
		(pad "" np_thru_hole circle
			(at 0 -6.620002 180)
			(size 3.175 3.175)
			(drill 3.175)
			(layers "*.Cu" "*.Mask")
			(clearance 0.381)
			(thermal_gap 0.381)
		)
		(pad "" np_thru_hole circle
			(at 0 0 180)
			(size 0 0)
			(drill 3.175)
			(layers "*.Cu" "*.Mask")
			(clearance 0)
		)
		(pad "" np_thru_hole circle
			(at 0 5.130038 180)
			(size 3.175 3.175)
			(drill 3.175)
			(layers "*.Cu" "*.Mask")
			(clearance 0.381)
			(thermal_gap 0.381)
		)
		(zone
			(layers "F.Cu" "B.Cu" "In1.Cu" "In2.Cu" "In3.Cu" "In4.Cu" "In5.Cu" "In6.Cu"
				"In7.Cu" "In8.Cu" "In9.Cu" "In10.Cu" "In11.Cu" "In12.Cu" "In13.Cu" "In14.Cu"
				"In15.Cu" "In16.Cu"
			)
			(hatch none 0.5)
			(connect_pads
				(clearance 0)
			)
			(min_thickness 0.25)
			(keepout
				(tracks not_allowed)
				(vias allowed)
				(pads allowed)
				(copperpour not_allowed)
				(footprints allowed)
			)
			(placement
				(enabled no)
				(sheetname "")
			)
			(fill
				(thermal_gap 0.5)
				(thermal_bridge_width 0.5)
				(island_removal_mode 0)
			)
			(polygon
				(pts
					(arc
						(start 114.120422 -436.49011)
						(mid 109.929422 -436.49011)
						(end 114.120422 -436.49011)
					)
				)
			)
		)
		(zone
			(layers "F.Cu" "B.Cu" "In1.Cu" "In2.Cu" "In3.Cu" "In4.Cu" "In5.Cu" "In6.Cu"
				"In7.Cu" "In8.Cu" "In9.Cu" "In10.Cu" "In11.Cu" "In12.Cu" "In13.Cu" "In14.Cu"
				"In15.Cu" "In16.Cu"
			)
			(hatch none 0.5)
			(connect_pads
				(clearance 0)
			)
			(min_thickness 0.25)
			(keepout
				(tracks not_allowed)
				(vias allowed)
				(pads allowed)
				(copperpour not_allowed)
				(footprints allowed)
			)
			(placement
				(enabled no)
				(sheetname "")
			)
			(fill
				(thermal_gap 0.5)
				(thermal_bridge_width 0.5)
				(island_removal_mode 0)
			)
			(polygon
				(pts
					(arc
						(start 114.120422 -424.74007)
						(mid 109.929422 -424.74007)
						(end 114.120422 -424.74007)
					)
				)
			)
		)
		(zone
			(layers "F.Cu" "B.Cu" "In1.Cu" "In2.Cu" "In3.Cu" "In4.Cu" "In5.Cu" "In6.Cu"
				"In7.Cu" "In8.Cu" "In9.Cu" "In10.Cu" "In11.Cu" "In12.Cu" "In13.Cu" "In14.Cu"
				"In15.Cu" "In16.Cu"
			)
			(hatch none 0.5)
			(connect_pads
				(clearance 0)
			)
			(min_thickness 0.25)
			(keepout
				(tracks not_allowed)
				(vias allowed)
				(pads allowed)
				(copperpour not_allowed)
				(footprints allowed)
			)
			(placement
				(enabled no)
				(sheetname "")
			)
			(fill
				(thermal_gap 0.5)
				(thermal_bridge_width 0.5)
				(island_removal_mode 0)
			)
			(polygon
				(pts
					(arc
						(start 115.644422 -431.360072)
						(mid 108.405422 -431.360072)
						(end 115.644422 -431.360072)
					)
				)
			)
		)
	)
	(footprint ""
		(layer "F.Cu")
		(at 152.32888 -47.970948 90)
		(property "Reference" "R3572"
			(at 0 0 90)
			(layer "F.SilkS")
			(hide yes)
			(effects
				(font
					(size 1.27 1.27)
				)
			)
		)
		(property "Value" ""
			(at 0 0 90)
			(layer "F.Fab")
			(effects
				(font
					(size 1.27 1.27)
				)
			)
		)
		(duplicate_pad_numbers_are_jumpers no)
		(fp_line
			(start 0.7874 -0.4064)
			(end 0.7874 0.4064)
			(stroke
				(width 0.1524)
				(type default)
			)
			(layer "F.SilkS")
		)
		(fp_line
			(start -0.7874 -0.4064)
			(end 0.7874 -0.4064)
			(stroke
				(width 0.1524)
				(type default)
			)
			(layer "F.SilkS")
		)
		(fp_line
			(start 0.7874 0.4064)
			(end -0.7874 0.4064)
			(stroke
				(width 0.1524)
				(type default)
			)
			(layer "F.SilkS")
		)
		(fp_line
			(start -0.7874 0.4064)
			(end -0.7874 -0.4064)
			(stroke
				(width 0.1524)
				(type default)
			)
			(layer "F.SilkS")
		)
		(fp_line
			(start -0.12065 -0.305054)
			(end -0.12065 -0.2794)
			(stroke
				(width 0.1)
				(type default)
			)
			(layer "F.Fab")
		)
		(fp_line
			(start -0.67945 -0.305054)
			(end -0.12065 -0.305054)
			(stroke
				(width 0.1)
				(type default)
			)
			(layer "F.Fab")
		)
		(fp_line
			(start 0.67945 -0.3048)
			(end 0.67945 0.3048)
			(stroke
				(width 0.1)
				(type default)
			)
			(layer "F.Fab")
		)
		(fp_line
			(start 0.12065 -0.3048)
			(end 0.67945 -0.3048)
			(stroke
				(width 0.1)
				(type default)
			)
			(layer "F.Fab")
		)
		(fp_line
			(start 0.12065 -0.2794)
			(end 0.12065 -0.3048)
			(stroke
				(width 0.1)
				(type default)
			)
			(layer "F.Fab")
		)
		(fp_line
			(start -0.12065 -0.2794)
			(end 0.12065 -0.2794)
			(stroke
				(width 0.1)
				(type default)
			)
			(layer "F.Fab")
		)
		(fp_line
			(start 0.120396 0.2794)
			(end -0.12065 0.2794)
			(stroke
				(width 0.1)
				(type default)
			)
			(layer "F.Fab")
		)
		(fp_line
			(start -0.12065 0.2794)
			(end -0.12065 0.3048)
			(stroke
				(width 0.1)
				(type default)
			)
			(layer "F.Fab")
		)
		(fp_line
			(start 0.67945 0.3048)
			(end 0.120396 0.3048)
			(stroke
				(width 0.1)
				(type default)
			)
			(layer "F.Fab")
		)
		(fp_line
			(start 0.120396 0.3048)
			(end 0.120396 0.2794)
			(stroke
				(width 0.1)
				(type default)
			)
			(layer "F.Fab")
		)
		(fp_line
			(start -0.12065 0.3048)
			(end -0.67945 0.3048)
			(stroke
				(width 0.1)
				(type default)
			)
			(layer "F.Fab")
		)
		(fp_line
			(start -0.67945 0.3048)
			(end -0.67945 -0.305054)
			(stroke
				(width 0.1)
				(type default)
			)
			(layer "F.Fab")
		)
		(pad "1" smd circle
			(at -0.40005 0 90)
			(size 0 0)
			(layers "F.Cu" "F.Mask" "F.Paste")
			(net "SMB_INA230_4_3V3AUX_SCL_R")
		)
		(pad "2" smd circle
			(at 0.40005 0 90)
			(size 0 0)
			(layers "F.Cu" "F.Mask" "F.Paste")
			(net "SMB_INA230_4_3V3AUX_SCL_R1")
		)
	)
	(footprint ""
		(layer "F.Cu")
		(at 105.21188 -424.779948 180)
		(property "Reference" "R4181"
			(at 0 0 180)
			(layer "F.SilkS")
			(hide yes)
			(effects
				(font
					(size 1.27 1.27)
				)
			)
		)
		(property "Value" ""
			(at 0 0 180)
			(layer "F.Fab")
			(effects
				(font
					(size 1.27 1.27)
				)
			)
		)
		(duplicate_pad_numbers_are_jumpers no)
		(fp_line
			(start 0.7874 0.4064)
			(end -0.7874 0.4064)
			(stroke
				(width 0.1524)
				(type default)
			)
			(layer "F.SilkS")
		)
		(fp_line
			(start 0.7874 -0.4064)
			(end 0.7874 0.4064)
			(stroke
				(width 0.1524)
				(type default)
			)
			(layer "F.SilkS")
		)
		(fp_line
			(start -0.7874 0.4064)
			(end -0.7874 -0.4064)
			(stroke
				(width 0.1524)
				(type default)
			)
			(layer "F.SilkS")
		)
		(fp_line
			(start -0.7874 -0.4064)
			(end 0.7874 -0.4064)
			(stroke
				(width 0.1524)
				(type default)
			)
			(layer "F.SilkS")
		)
		(fp_line
			(start 0.67945 0.3048)
			(end 0.120396 0.3048)
			(stroke
				(width 0.1)
				(type default)
			)
			(layer "F.Fab")
		)
		(fp_line
			(start 0.67945 -0.3048)
			(end 0.67945 0.3048)
			(stroke
				(width 0.1)
				(type default)
			)
			(layer "F.Fab")
		)
		(fp_line
			(start 0.12065 -0.2794)
			(end 0.12065 -0.3048)
			(stroke
				(width 0.1)
				(type default)
			)
			(layer "F.Fab")
		)
		(fp_line
			(start 0.12065 -0.3048)
			(end 0.67945 -0.3048)
			(stroke
				(width 0.1)
				(type default)
			)
			(layer "F.Fab")
		)
		(fp_line
			(start 0.120396 0.3048)
			(end 0.120396 0.2794)
			(stroke
				(width 0.1)
				(type default)
			)
			(layer "F.Fab")
		)
		(fp_line
			(start 0.120396 0.2794)
			(end -0.12065 0.2794)
			(stroke
				(width 0.1)
				(type default)
			)
			(layer "F.Fab")
		)
		(fp_line
			(start -0.12065 0.3048)
			(end -0.67945 0.3048)
			(stroke
				(width 0.1)
				(type default)
			)
			(layer "F.Fab")
		)
		(fp_line
			(start -0.12065 0.2794)
			(end -0.12065 0.3048)
			(stroke
				(width 0.1)
				(type default)
			)
			(layer "F.Fab")
		)
		(fp_line
			(start -0.12065 -0.2794)
			(end 0.12065 -0.2794)
			(stroke
				(width 0.1)
				(type default)
			)
			(layer "F.Fab")
		)
		(fp_line
			(start -0.12065 -0.305054)
			(end -0.12065 -0.2794)
			(stroke
				(width 0.1)
				(type default)
			)
			(layer "F.Fab")
		)
		(fp_line
			(start -0.67945 0.3048)
			(end -0.67945 -0.305054)
			(stroke
				(width 0.1)
				(type default)
			)
			(layer "F.Fab")
		)
		(fp_line
			(start -0.67945 -0.305054)
			(end -0.12065 -0.305054)
			(stroke
				(width 0.1)
				(type default)
			)
			(layer "F.Fab")
		)
		(pad "1" smd circle
			(at -0.40005 0 180)
			(size 0 0)
			(layers "F.Cu" "F.Mask" "F.Paste")
			(net "SMB_LM75_2_3V3AUX_SDA")
		)
		(pad "2" smd circle
			(at 0.40005 0 180)
			(size 0 0)
			(layers "F.Cu" "F.Mask" "F.Paste")
			(net "SMB_LM75_2_3V3AUX_SDA_R1")
		)
	)
	(footprint ""
		(layer "F.Cu")
		(at 435.43728 -179.390548 90)
		(property "Reference" "PR4271"
			(at 0 0 90)
			(layer "F.SilkS")
			(hide yes)
			(effects
				(font
					(size 1.27 1.27)
				)
			)
		)
		(property "Value" ""
			(at 0 0 90)
			(layer "F.Fab")
			(effects
				(font
					(size 1.27 1.27)
				)
			)
		)
		(duplicate_pad_numbers_are_jumpers no)
		(fp_line
			(start 0.7874 -0.4064)
			(end 0.7874 0.4064)
			(stroke
				(width 0.1524)
				(type default)
			)
			(layer "F.SilkS")
		)
		(fp_line
			(start -0.7874 -0.4064)
			(end 0.7874 -0.4064)
			(stroke
				(width 0.1524)
				(type default)
			)
			(layer "F.SilkS")
		)
		(fp_line
			(start 0.7874 0.4064)
			(end -0.7874 0.4064)
			(stroke
				(width 0.1524)
				(type default)
			)
			(layer "F.SilkS")
		)
		(fp_line
			(start -0.7874 0.4064)
			(end -0.7874 -0.4064)
			(stroke
				(width 0.1524)
				(type default)
			)
			(layer "F.SilkS")
		)
		(fp_line
			(start -0.12065 -0.305054)
			(end -0.12065 -0.2794)
			(stroke
				(width 0.1)
				(type default)
			)
			(layer "F.Fab")
		)
		(fp_line
			(start -0.67945 -0.305054)
			(end -0.12065 -0.305054)
			(stroke
				(width 0.1)
				(type default)
			)
			(layer "F.Fab")
		)
		(fp_line
			(start 0.67945 -0.3048)
			(end 0.67945 0.3048)
			(stroke
				(width 0.1)
				(type default)
			)
			(layer "F.Fab")
		)
		(fp_line
			(start 0.12065 -0.3048)
			(end 0.67945 -0.3048)
			(stroke
				(width 0.1)
				(type default)
			)
			(layer "F.Fab")
		)
		(fp_line
			(start 0.12065 -0.2794)
			(end 0.12065 -0.3048)
			(stroke
				(width 0.1)
				(type default)
			)
			(layer "F.Fab")
		)
		(fp_line
			(start -0.12065 -0.2794)
			(end 0.12065 -0.2794)
			(stroke
				(width 0.1)
				(type default)
			)
			(layer "F.Fab")
		)
		(fp_line
			(start 0.120396 0.2794)
			(end -0.12065 0.2794)
			(stroke
				(width 0.1)
				(type default)
			)
			(layer "F.Fab")
		)
		(fp_line
			(start -0.12065 0.2794)
			(end -0.12065 0.3048)
			(stroke
				(width 0.1)
				(type default)
			)
			(layer "F.Fab")
		)
		(fp_line
			(start 0.67945 0.3048)
			(end 0.120396 0.3048)
			(stroke
				(width 0.1)
				(type default)
			)
			(layer "F.Fab")
		)
		(fp_line
			(start 0.120396 0.3048)
			(end 0.120396 0.2794)
			(stroke
				(width 0.1)
				(type default)
			)
			(layer "F.Fab")
		)
		(fp_line
			(start -0.12065 0.3048)
			(end -0.67945 0.3048)
			(stroke
				(width 0.1)
				(type default)
			)
			(layer "F.Fab")
		)
		(fp_line
			(start -0.67945 0.3048)
			(end -0.67945 -0.305054)
			(stroke
				(width 0.1)
				(type default)
			)
			(layer "F.Fab")
		)
		(pad "1" smd circle
			(at -0.40005 0 90)
			(size 0 0)
			(layers "F.Cu" "F.Mask" "F.Paste")
			(net "SW_PVNN_MAIN_CPU0_BST")
		)
		(pad "2" smd circle
			(at 0.40005 0 90)
			(size 0 0)
			(layers "F.Cu" "F.Mask" "F.Paste")
			(net "SW_PVNN_MAIN_CPU0_BST_R")
		)
	)
	(footprint ""
		(layer "F.Cu")
		(at 211.99729 -71.13143)
		(property "Reference" "R1354"
			(at 0 0 0)
			(layer "F.SilkS")
			(hide yes)
			(effects
				(font
					(size 1.27 1.27)
				)
			)
		)
		(property "Value" ""
			(at 0 0 0)
			(layer "F.Fab")
			(effects
				(font
					(size 1.27 1.27)
				)
			)
		)
		(duplicate_pad_numbers_are_jumpers no)
		(fp_line
			(start -0.7874 -0.4064)
			(end 0.7874 -0.4064)
			(stroke
				(width 0.1524)
				(type default)
			)
			(layer "F.SilkS")
		)
		(fp_line
			(start -0.7874 0.4064)
			(end -0.7874 -0.4064)
			(stroke
				(width 0.1524)
				(type default)
			)
			(layer "F.SilkS")
		)
		(fp_line
			(start 0.7874 -0.4064)
			(end 0.7874 0.4064)
			(stroke
				(width 0.1524)
				(type default)
			)
			(layer "F.SilkS")
		)
		(fp_line
			(start 0.7874 0.4064)
			(end -0.7874 0.4064)
			(stroke
				(width 0.1524)
				(type default)
			)
			(layer "F.SilkS")
		)
		(fp_line
			(start -0.67945 -0.305054)
			(end -0.12065 -0.305054)
			(stroke
				(width 0.1)
				(type default)
			)
			(layer "F.Fab")
		)
		(fp_line
			(start -0.67945 0.3048)
			(end -0.67945 -0.305054)
			(stroke
				(width 0.1)
				(type default)
			)
			(layer "F.Fab")
		)
		(fp_line
			(start -0.12065 -0.305054)
			(end -0.12065 -0.2794)
			(stroke
				(width 0.1)
				(type default)
			)
			(layer "F.Fab")
		)
		(fp_line
			(start -0.12065 -0.2794)
			(end 0.12065 -0.2794)
			(stroke
				(width 0.1)
				(type default)
			)
			(layer "F.Fab")
		)
		(fp_line
			(start -0.12065 0.2794)
			(end -0.12065 0.3048)
			(stroke
				(width 0.1)
				(type default)
			)
			(layer "F.Fab")
		)
		(fp_line
			(start -0.12065 0.3048)
			(end -0.67945 0.3048)
			(stroke
				(width 0.1)
				(type default)
			)
			(layer "F.Fab")
		)
		(fp_line
			(start 0.120396 0.2794)
			(end -0.12065 0.2794)
			(stroke
				(width 0.1)
				(type default)
			)
			(layer "F.Fab")
		)
		(fp_line
			(start 0.120396 0.3048)
			(end 0.120396 0.2794)
			(stroke
				(width 0.1)
				(type default)
			)
			(layer "F.Fab")
		)
		(fp_line
			(start 0.12065 -0.3048)
			(end 0.67945 -0.3048)
			(stroke
				(width 0.1)
				(type default)
			)
			(layer "F.Fab")
		)
		(fp_line
			(start 0.12065 -0.2794)
			(end 0.12065 -0.3048)
			(stroke
				(width 0.1)
				(type default)
			)
			(layer "F.Fab")
		)
		(fp_line
			(start 0.67945 -0.3048)
			(end 0.67945 0.3048)
			(stroke
				(width 0.1)
				(type default)
			)
			(layer "F.Fab")
		)
		(fp_line
			(start 0.67945 0.3048)
			(end 0.120396 0.3048)
			(stroke
				(width 0.1)
				(type default)
			)
			(layer "F.Fab")
		)
		(pad "1" smd circle
			(at -0.40005 0)
			(size 0 0)
			(layers "F.Cu" "F.Mask" "F.Paste")
			(net "RMII_BMC_OCP_TXD_0")
		)
		(pad "2" smd circle
			(at 0.40005 0)
			(size 0 0)
			(layers "F.Cu" "F.Mask" "F.Paste")
			(net "GND")
		)
	)
	(footprint ""
		(layer "F.Cu")
		(at 374.03151 -413.918908 90)
		(property "Reference" "R4515"
			(at 0 0 90)
			(layer "F.SilkS")
			(hide yes)
			(effects
				(font
					(size 1.27 1.27)
				)
			)
		)
		(property "Value" ""
			(at 0 0 90)
			(layer "F.Fab")
			(effects
				(font
					(size 1.27 1.27)
				)
			)
		)
		(duplicate_pad_numbers_are_jumpers no)
		(fp_line
			(start 0.7874 -0.4064)
			(end 0.7874 0.4064)
			(stroke
				(width 0.1524)
				(type default)
			)
			(layer "F.SilkS")
		)
		(fp_line
			(start -0.7874 -0.4064)
			(end 0.7874 -0.4064)
			(stroke
				(width 0.1524)
				(type default)
			)
			(layer "F.SilkS")
		)
		(fp_line
			(start 0.7874 0.4064)
			(end -0.7874 0.4064)
			(stroke
				(width 0.1524)
				(type default)
			)
			(layer "F.SilkS")
		)
		(fp_line
			(start -0.7874 0.4064)
			(end -0.7874 -0.4064)
			(stroke
				(width 0.1524)
				(type default)
			)
			(layer "F.SilkS")
		)
		(fp_line
			(start -0.12065 -0.305054)
			(end -0.12065 -0.2794)
			(stroke
				(width 0.1)
				(type default)
			)
			(layer "F.Fab")
		)
		(fp_line
			(start -0.67945 -0.305054)
			(end -0.12065 -0.305054)
			(stroke
				(width 0.1)
				(type default)
			)
			(layer "F.Fab")
		)
		(fp_line
			(start 0.67945 -0.3048)
			(end 0.67945 0.3048)
			(stroke
				(width 0.1)
				(type default)
			)
			(layer "F.Fab")
		)
		(fp_line
			(start 0.12065 -0.3048)
			(end 0.67945 -0.3048)
			(stroke
				(width 0.1)
				(type default)
			)
			(layer "F.Fab")
		)
		(fp_line
			(start 0.12065 -0.2794)
			(end 0.12065 -0.3048)
			(stroke
				(width 0.1)
				(type default)
			)
			(layer "F.Fab")
		)
		(fp_line
			(start -0.12065 -0.2794)
			(end 0.12065 -0.2794)
			(stroke
				(width 0.1)
				(type default)
			)
			(layer "F.Fab")
		)
		(fp_line
			(start 0.120396 0.2794)
			(end -0.12065 0.2794)
			(stroke
				(width 0.1)
				(type default)
			)
			(layer "F.Fab")
		)
		(fp_line
			(start -0.12065 0.2794)
			(end -0.12065 0.3048)
			(stroke
				(width 0.1)
				(type default)
			)
			(layer "F.Fab")
		)
		(fp_line
			(start 0.67945 0.3048)
			(end 0.120396 0.3048)
			(stroke
				(width 0.1)
				(type default)
			)
			(layer "F.Fab")
		)
		(fp_line
			(start 0.120396 0.3048)
			(end 0.120396 0.2794)
			(stroke
				(width 0.1)
				(type default)
			)
			(layer "F.Fab")
		)
		(fp_line
			(start -0.12065 0.3048)
			(end -0.67945 0.3048)
			(stroke
				(width 0.1)
				(type default)
			)
			(layer "F.Fab")
		)
		(fp_line
			(start -0.67945 0.3048)
			(end -0.67945 -0.305054)
			(stroke
				(width 0.1)
				(type default)
			)
			(layer "F.Fab")
		)
		(pad "1" smd circle
			(at -0.40005 0 90)
			(size 0 0)
			(layers "F.Cu" "F.Mask" "F.Paste")
			(net "P3V3_AUX")
		)
		(pad "2" smd circle
			(at 0.40005 0 90)
			(size 0 0)
			(layers "F.Cu" "F.Mask" "F.Paste")
			(net "UART_BMC_BIC_RX")
		)
	)
	(footprint ""
		(layer "F.Cu")
		(at 483.281228 -343.22893)
		(property "Reference" "DB7"
			(at 2.576068 2.020062 90)
			(unlocked yes)
			(layer "F.SilkS")
			(effects
				(font
					(size 0.7874 0.5842)
					(thickness 0.1524)
				)
				(justify left)
			)
		)
		(property "Value" ""
			(at 0 0 0)
			(layer "F.Fab")
			(effects
				(font
					(size 1.27 1.27)
				)
			)
		)
		(duplicate_pad_numbers_are_jumpers no)
		(fp_line
			(start -3.330702 -4.771136)
			(end 3.330702 -4.771136)
			(stroke
				(width 0.1524)
				(type default)
			)
			(layer "F.SilkS")
		)
		(fp_line
			(start 0 4.011168)
			(end -3.330702 -4.771136)
			(stroke
				(width 0.1524)
				(type default)
			)
			(layer "F.SilkS")
		)
		(fp_line
			(start 3.330702 -4.771136)
			(end 0 4.011168)
			(stroke
				(width 0.1524)
				(type default)
			)
			(layer "F.SilkS")
		)
		(fp_line
			(start -3.330702 -4.771136)
			(end 3.330702 -4.771136)
			(stroke
				(width 0.1)
				(type default)
			)
			(layer "F.Fab")
		)
		(fp_line
			(start 0 4.011168)
			(end -3.330702 -4.771136)
			(stroke
				(width 0.1)
				(type default)
			)
			(layer "F.Fab")
		)
		(fp_line
			(start 3.330702 -4.771136)
			(end 0 4.011168)
			(stroke
				(width 0.1)
				(type default)
			)
			(layer "F.Fab")
		)
		(pad "1" thru_hole circle
			(at 0 0)
			(size 2.159 2.159)
			(drill 1.7018)
			(layers "*.Cu" "*.Mask")
			(remove_unused_layers no)
			(net "T1_GND")
			(clearance 0.0254)
			(thermal_gap 0.0254)
		)
		(pad "2" thru_hole circle
			(at -1.27 -3.348736)
			(size 2.159 2.159)
			(drill 1.7018)
			(layers "*.Cu" "*.Mask")
			(remove_unused_layers no)
			(net "TDR_SE_50_OHM_TOP")
			(clearance 0.0254)
			(thermal_gap 0.0254)
		)
		(pad "3" thru_hole circle
			(at 1.27 -3.348736)
			(size 2.159 2.159)
			(drill 1.7018)
			(layers "*.Cu" "*.Mask")
			(remove_unused_layers no)
			(net "TDR_SE_50_OHM_TOP")
			(clearance 0.0254)
			(thermal_gap 0.0254)
		)
	)
	(footprint ""
		(layer "F.Cu")
		(at 340.033864 -354.332032 -90)
		(property "Reference" "PL15"
			(at -8.8011 1.901698 0)
			(unlocked yes)
			(layer "F.SilkS")
			(effects
				(font
					(size 0.7874 0.5842)
					(thickness 0.1524)
				)
				(justify left)
			)
		)
		(property "Value" ""
			(at 0 0 270)
			(layer "F.Fab")
			(effects
				(font
					(size 1.27 1.27)
				)
			)
		)
		(duplicate_pad_numbers_are_jumpers no)
		(fp_line
			(start -4.99999 4.150106)
			(end 4.99999 4.150106)
			(stroke
				(width 0.1524)
				(type default)
			)
			(layer "F.SilkS")
		)
		(fp_line
			(start 4.99999 4.150106)
			(end 4.99999 2.4892)
			(stroke
				(width 0.1524)
				(type default)
			)
			(layer "F.SilkS")
		)
		(fp_line
			(start -4.99999 2.4892)
			(end -4.99999 4.150106)
			(stroke
				(width 0.1524)
				(type default)
			)
			(layer "F.SilkS")
		)
		(fp_line
			(start 4.99999 -2.4892)
			(end 4.99999 -4.150106)
			(stroke
				(width 0.1524)
				(type default)
			)
			(layer "F.SilkS")
		)
		(fp_line
			(start -4.99999 -4.150106)
			(end -4.99999 -2.4892)
			(stroke
				(width 0.1524)
				(type default)
			)
			(layer "F.SilkS")
		)
		(fp_line
			(start 4.99999 -4.150106)
			(end -4.99999 -4.150106)
			(stroke
				(width 0.1524)
				(type default)
			)
			(layer "F.SilkS")
		)
		(fp_line
			(start -4.99999 4.150106)
			(end 4.99999 4.150106)
			(stroke
				(width 0.1)
				(type default)
			)
			(layer "F.Fab")
		)
		(fp_line
			(start 4.99999 4.150106)
			(end 4.99999 -4.150106)
			(stroke
				(width 0.1)
				(type default)
			)
			(layer "F.Fab")
		)
		(fp_line
			(start -4.99999 -4.150106)
			(end -4.99999 4.150106)
			(stroke
				(width 0.1)
				(type default)
			)
			(layer "F.Fab")
		)
		(fp_line
			(start 4.99999 -4.150106)
			(end -4.99999 -4.150106)
			(stroke
				(width 0.1)
				(type default)
			)
			(layer "F.Fab")
		)
		(pad "1" smd rect
			(at -4.174998 0 270)
			(size 2.159 4.699)
			(layers "F.Cu" "F.Mask" "F.Paste")
			(net "P12V_AUX")
		)
		(pad "2" smd rect
			(at 4.174998 0 270)
			(size 2.159 4.699)
			(layers "F.Cu" "F.Mask" "F.Paste")
			(net "SW_P12V_PVCCIN_CPU0_FLT")
		)
	)
	(footprint ""
		(layer "F.Cu")
		(at 285.211266 -365.251746 90)
		(property "Reference" "PC1172"
			(at 0 0 90)
			(layer "F.SilkS")
			(hide yes)
			(effects
				(font
					(size 1.27 1.27)
				)
			)
		)
		(property "Value" ""
			(at 0 0 90)
			(layer "F.Fab")
			(effects
				(font
					(size 1.27 1.27)
				)
			)
		)
		(duplicate_pad_numbers_are_jumpers no)
		(fp_line
			(start 0.7874 -0.4064)
			(end 0.7874 0.4064)
			(stroke
				(width 0.1524)
				(type default)
			)
			(layer "F.SilkS")
		)
		(fp_line
			(start -0.7874 -0.4064)
			(end 0.7874 -0.4064)
			(stroke
				(width 0.1524)
				(type default)
			)
			(layer "F.SilkS")
		)
		(fp_line
			(start 0.7874 0.4064)
			(end -0.7874 0.4064)
			(stroke
				(width 0.1524)
				(type default)
			)
			(layer "F.SilkS")
		)
		(fp_line
			(start -0.7874 0.4064)
			(end -0.7874 -0.4064)
			(stroke
				(width 0.1524)
				(type default)
			)
			(layer "F.SilkS")
		)
		(fp_line
			(start -0.12065 -0.305054)
			(end -0.12065 -0.2794)
			(stroke
				(width 0.1)
				(type default)
			)
			(layer "F.Fab")
		)
		(fp_line
			(start -0.67945 -0.305054)
			(end -0.12065 -0.305054)
			(stroke
				(width 0.1)
				(type default)
			)
			(layer "F.Fab")
		)
		(fp_line
			(start 0.67945 -0.3048)
			(end 0.67945 0.3048)
			(stroke
				(width 0.1)
				(type default)
			)
			(layer "F.Fab")
		)
		(fp_line
			(start 0.12065 -0.3048)
			(end 0.67945 -0.3048)
			(stroke
				(width 0.1)
				(type default)
			)
			(layer "F.Fab")
		)
		(fp_line
			(start 0.12065 -0.2794)
			(end 0.12065 -0.3048)
			(stroke
				(width 0.1)
				(type default)
			)
			(layer "F.Fab")
		)
		(fp_line
			(start -0.12065 -0.2794)
			(end 0.12065 -0.2794)
			(stroke
				(width 0.1)
				(type default)
			)
			(layer "F.Fab")
		)
		(fp_line
			(start 0.120396 0.2794)
			(end -0.12065 0.2794)
			(stroke
				(width 0.1)
				(type default)
			)
			(layer "F.Fab")
		)
		(fp_line
			(start -0.12065 0.2794)
			(end -0.12065 0.3048)
			(stroke
				(width 0.1)
				(type default)
			)
			(layer "F.Fab")
		)
		(fp_line
			(start 0.67945 0.3048)
			(end 0.120396 0.3048)
			(stroke
				(width 0.1)
				(type default)
			)
			(layer "F.Fab")
		)
		(fp_line
			(start 0.120396 0.3048)
			(end 0.120396 0.2794)
			(stroke
				(width 0.1)
				(type default)
			)
			(layer "F.Fab")
		)
		(fp_line
			(start -0.12065 0.3048)
			(end -0.67945 0.3048)
			(stroke
				(width 0.1)
				(type default)
			)
			(layer "F.Fab")
		)
		(fp_line
			(start -0.67945 0.3048)
			(end -0.67945 -0.305054)
			(stroke
				(width 0.1)
				(type default)
			)
			(layer "F.Fab")
		)
		(pad "1" smd circle
			(at -0.40005 0 90)
			(size 0 0)
			(layers "F.Cu" "F.Mask" "F.Paste")
			(net "PVCCFA_EHV_FIVRA_CPU0_VDD4")
		)
		(pad "2" smd circle
			(at 0.40005 0 90)
			(size 0 0)
			(layers "F.Cu" "F.Mask" "F.Paste")
			(net "GND")
		)
	)
	(footprint ""
		(layer "F.Cu")
		(at 428.63008 -118.34876 180)
		(property "Reference" "PC2365"
			(at 0 0 180)
			(layer "F.SilkS")
			(hide yes)
			(effects
				(font
					(size 1.27 1.27)
				)
			)
		)
		(property "Value" ""
			(at 0 0 180)
			(layer "F.Fab")
			(effects
				(font
					(size 1.27 1.27)
				)
			)
		)
		(duplicate_pad_numbers_are_jumpers no)
		(fp_line
			(start 0.7874 0.4064)
			(end -0.7874 0.4064)
			(stroke
				(width 0.1524)
				(type default)
			)
			(layer "F.SilkS")
		)
		(fp_line
			(start 0.7874 -0.4064)
			(end 0.7874 0.4064)
			(stroke
				(width 0.1524)
				(type default)
			)
			(layer "F.SilkS")
		)
		(fp_line
			(start -0.7874 0.4064)
			(end -0.7874 -0.4064)
			(stroke
				(width 0.1524)
				(type default)
			)
			(layer "F.SilkS")
		)
		(fp_line
			(start -0.7874 -0.4064)
			(end 0.7874 -0.4064)
			(stroke
				(width 0.1524)
				(type default)
			)
			(layer "F.SilkS")
		)
		(fp_line
			(start 0.67945 0.3048)
			(end 0.120396 0.3048)
			(stroke
				(width 0.1)
				(type default)
			)
			(layer "F.Fab")
		)
		(fp_line
			(start 0.67945 -0.3048)
			(end 0.67945 0.3048)
			(stroke
				(width 0.1)
				(type default)
			)
			(layer "F.Fab")
		)
		(fp_line
			(start 0.12065 -0.2794)
			(end 0.12065 -0.3048)
			(stroke
				(width 0.1)
				(type default)
			)
			(layer "F.Fab")
		)
		(fp_line
			(start 0.12065 -0.3048)
			(end 0.67945 -0.3048)
			(stroke
				(width 0.1)
				(type default)
			)
			(layer "F.Fab")
		)
		(fp_line
			(start 0.120396 0.3048)
			(end 0.120396 0.2794)
			(stroke
				(width 0.1)
				(type default)
			)
			(layer "F.Fab")
		)
		(fp_line
			(start 0.120396 0.2794)
			(end -0.12065 0.2794)
			(stroke
				(width 0.1)
				(type default)
			)
			(layer "F.Fab")
		)
		(fp_line
			(start -0.12065 0.3048)
			(end -0.67945 0.3048)
			(stroke
				(width 0.1)
				(type default)
			)
			(layer "F.Fab")
		)
		(fp_line
			(start -0.12065 0.2794)
			(end -0.12065 0.3048)
			(stroke
				(width 0.1)
				(type default)
			)
			(layer "F.Fab")
		)
		(fp_line
			(start -0.12065 -0.2794)
			(end 0.12065 -0.2794)
			(stroke
				(width 0.1)
				(type default)
			)
			(layer "F.Fab")
		)
		(fp_line
			(start -0.12065 -0.305054)
			(end -0.12065 -0.2794)
			(stroke
				(width 0.1)
				(type default)
			)
			(layer "F.Fab")
		)
		(fp_line
			(start -0.67945 0.3048)
			(end -0.67945 -0.305054)
			(stroke
				(width 0.1)
				(type default)
			)
			(layer "F.Fab")
		)
		(fp_line
			(start -0.67945 -0.305054)
			(end -0.12065 -0.305054)
			(stroke
				(width 0.1)
				(type default)
			)
			(layer "F.Fab")
		)
		(pad "1" smd circle
			(at -0.40005 0 180)
			(size 0 0)
			(layers "F.Cu" "F.Mask" "F.Paste")
			(net "PVCCD_HV_CPU0_VCC")
		)
		(pad "2" smd circle
			(at 0.40005 0 180)
			(size 0 0)
			(layers "F.Cu" "F.Mask" "F.Paste")
			(net "GND")
		)
	)
	(footprint ""
		(layer "F.Cu")
		(at 106.70921 -414.741868 180)
		(property "Reference" "R3353"
			(at 0 0 180)
			(layer "F.SilkS")
			(hide yes)
			(effects
				(font
					(size 1.27 1.27)
				)
			)
		)
		(property "Value" ""
			(at 0 0 180)
			(layer "F.Fab")
			(effects
				(font
					(size 1.27 1.27)
				)
			)
		)
		(duplicate_pad_numbers_are_jumpers no)
		(fp_line
			(start 0.7874 -0.4064)
			(end 0.7874 0.09144)
			(stroke
				(width 0.1524)
				(type default)
			)
			(layer "F.SilkS")
		)
		(fp_line
			(start 0.42799 0.4064)
			(end -0.41275 0.4064)
			(stroke
				(width 0.1524)
				(type default)
			)
			(layer "F.SilkS")
		)
		(fp_line
			(start -0.7874 0.03302)
			(end -0.7874 -0.4064)
			(stroke
				(width 0.1524)
				(type default)
			)
			(layer "F.SilkS")
		)
		(fp_line
			(start -0.7874 -0.4064)
			(end 0.7874 -0.4064)
			(stroke
				(width 0.1524)
				(type default)
			)
			(layer "F.SilkS")
		)
		(fp_line
			(start 0.67945 0.3048)
			(end 0.120396 0.3048)
			(stroke
				(width 0.1)
				(type default)
			)
			(layer "F.Fab")
		)
		(fp_line
			(start 0.67945 -0.3048)
			(end 0.67945 0.3048)
			(stroke
				(width 0.1)
				(type default)
			)
			(layer "F.Fab")
		)
		(fp_line
			(start 0.12065 -0.2794)
			(end 0.12065 -0.3048)
			(stroke
				(width 0.1)
				(type default)
			)
			(layer "F.Fab")
		)
		(fp_line
			(start 0.12065 -0.3048)
			(end 0.67945 -0.3048)
			(stroke
				(width 0.1)
				(type default)
			)
			(layer "F.Fab")
		)
		(fp_line
			(start 0.120396 0.3048)
			(end 0.120396 0.2794)
			(stroke
				(width 0.1)
				(type default)
			)
			(layer "F.Fab")
		)
		(fp_line
			(start 0.120396 0.2794)
			(end -0.12065 0.2794)
			(stroke
				(width 0.1)
				(type default)
			)
			(layer "F.Fab")
		)
		(fp_line
			(start -0.12065 0.3048)
			(end -0.67945 0.3048)
			(stroke
				(width 0.1)
				(type default)
			)
			(layer "F.Fab")
		)
		(fp_line
			(start -0.12065 0.2794)
			(end -0.12065 0.3048)
			(stroke
				(width 0.1)
				(type default)
			)
			(layer "F.Fab")
		)
		(fp_line
			(start -0.12065 -0.2794)
			(end 0.12065 -0.2794)
			(stroke
				(width 0.1)
				(type default)
			)
			(layer "F.Fab")
		)
		(fp_line
			(start -0.12065 -0.305054)
			(end -0.12065 -0.2794)
			(stroke
				(width 0.1)
				(type default)
			)
			(layer "F.Fab")
		)
		(fp_line
			(start -0.67945 0.3048)
			(end -0.67945 -0.305054)
			(stroke
				(width 0.1)
				(type default)
			)
			(layer "F.Fab")
		)
		(fp_line
			(start -0.67945 -0.305054)
			(end -0.12065 -0.305054)
			(stroke
				(width 0.1)
				(type default)
			)
			(layer "F.Fab")
		)
		(pad "1" smd circle
			(at -0.40005 0 180)
			(size 0 0)
			(layers "F.Cu" "F.Mask" "F.Paste")
			(net "CLK_100M_GPU_1_R_DN")
		)
		(pad "2" smd circle
			(at 0.40005 0 180)
			(size 0 0)
			(layers "F.Cu" "F.Mask" "F.Paste")
			(net "CLK_100M_GPU_1_DN")
		)
	)
	(footprint ""
		(layer "F.Cu")
		(at 130.665474 -408.517344 -90)
		(property "Reference" "C1522"
			(at 0 0 270)
			(layer "F.SilkS")
			(hide yes)
			(effects
				(font
					(size 1.27 1.27)
				)
			)
		)
		(property "Value" ""
			(at 0 0 270)
			(layer "F.Fab")
			(effects
				(font
					(size 1.27 1.27)
				)
			)
		)
		(duplicate_pad_numbers_are_jumpers no)
		(fp_line
			(start -0.299974 0.150114)
			(end -0.299974 -0.150114)
			(stroke
				(width 0.1)
				(type default)
			)
			(layer "F.Fab")
		)
		(fp_line
			(start 0.299974 0.150114)
			(end -0.299974 0.150114)
			(stroke
				(width 0.1)
				(type default)
			)
			(layer "F.Fab")
		)
		(fp_line
			(start -0.299974 -0.150114)
			(end 0.299974 -0.150114)
			(stroke
				(width 0.1)
				(type default)
			)
			(layer "F.Fab")
		)
		(fp_line
			(start 0.299974 -0.150114)
			(end 0.299974 0.150114)
			(stroke
				(width 0.1)
				(type default)
			)
			(layer "F.Fab")
		)
		(pad "1" smd rect
			(at -0.2667 0 270)
			(size 0.3048 0.381)
			(layers "F.Cu" "F.Mask" "F.Paste")
			(net "P5E_CPU1_PE3_TX_C_DN<12>")
		)
		(pad "2" smd rect
			(at 0.2667 0 270)
			(size 0.3048 0.381)
			(layers "F.Cu" "F.Mask" "F.Paste")
			(net "P5E_CPU1_PE3_TX_DN<12>")
		)
	)
	(footprint ""
		(layer "F.Cu")
		(at 112.40008 -119.846598 -90)
		(property "Reference" "R852"
			(at 0 0 270)
			(layer "F.SilkS")
			(hide yes)
			(effects
				(font
					(size 1.27 1.27)
				)
			)
		)
		(property "Value" ""
			(at 0 0 270)
			(layer "F.Fab")
			(effects
				(font
					(size 1.27 1.27)
				)
			)
		)
		(duplicate_pad_numbers_are_jumpers no)
		(fp_line
			(start -0.7874 0.4064)
			(end -0.7874 -0.4064)
			(stroke
				(width 0.1524)
				(type default)
			)
			(layer "F.SilkS")
		)
		(fp_line
			(start 0.7874 0.4064)
			(end -0.7874 0.4064)
			(stroke
				(width 0.1524)
				(type default)
			)
			(layer "F.SilkS")
		)
		(fp_line
			(start -0.7874 -0.4064)
			(end 0.7874 -0.4064)
			(stroke
				(width 0.1524)
				(type default)
			)
			(layer "F.SilkS")
		)
		(fp_line
			(start 0.7874 -0.4064)
			(end 0.7874 0.4064)
			(stroke
				(width 0.1524)
				(type default)
			)
			(layer "F.SilkS")
		)
		(fp_line
			(start -0.67945 0.3048)
			(end -0.67945 -0.305054)
			(stroke
				(width 0.1)
				(type default)
			)
			(layer "F.Fab")
		)
		(fp_line
			(start -0.12065 0.3048)
			(end -0.67945 0.3048)
			(stroke
				(width 0.1)
				(type default)
			)
			(layer "F.Fab")
		)
		(fp_line
			(start 0.120396 0.3048)
			(end 0.120396 0.2794)
			(stroke
				(width 0.1)
				(type default)
			)
			(layer "F.Fab")
		)
		(fp_line
			(start 0.67945 0.3048)
			(end 0.120396 0.3048)
			(stroke
				(width 0.1)
				(type default)
			)
			(layer "F.Fab")
		)
		(fp_line
			(start -0.12065 0.2794)
			(end -0.12065 0.3048)
			(stroke
				(width 0.1)
				(type default)
			)
			(layer "F.Fab")
		)
		(fp_line
			(start 0.120396 0.2794)
			(end -0.12065 0.2794)
			(stroke
				(width 0.1)
				(type default)
			)
			(layer "F.Fab")
		)
		(fp_line
			(start -0.12065 -0.2794)
			(end 0.12065 -0.2794)
			(stroke
				(width 0.1)
				(type default)
			)
			(layer "F.Fab")
		)
		(fp_line
			(start 0.12065 -0.2794)
			(end 0.12065 -0.3048)
			(stroke
				(width 0.1)
				(type default)
			)
			(layer "F.Fab")
		)
		(fp_line
			(start 0.12065 -0.3048)
			(end 0.67945 -0.3048)
			(stroke
				(width 0.1)
				(type default)
			)
			(layer "F.Fab")
		)
		(fp_line
			(start 0.67945 -0.3048)
			(end 0.67945 0.3048)
			(stroke
				(width 0.1)
				(type default)
			)
			(layer "F.Fab")
		)
		(fp_line
			(start -0.67945 -0.305054)
			(end -0.12065 -0.305054)
			(stroke
				(width 0.1)
				(type default)
			)
			(layer "F.Fab")
		)
		(fp_line
			(start -0.12065 -0.305054)
			(end -0.12065 -0.2794)
			(stroke
				(width 0.1)
				(type default)
			)
			(layer "F.Fab")
		)
		(pad "1" smd circle
			(at -0.40005 0 270)
			(size 0 0)
			(layers "F.Cu" "F.Mask" "F.Paste")
			(net "RST_CPU0_DRAM_CD_N")
		)
		(pad "2" smd circle
			(at 0.40005 0 270)
			(size 0 0)
			(layers "F.Cu" "F.Mask" "F.Paste")
			(net "RST_CPU0_DRAM_CD_PLD_N")
		)
	)
	(footprint ""
		(layer "F.Cu")
		(at 365.46663 -260.364986 -90)
		(property "Reference" "C411"
			(at 0 0 270)
			(layer "F.SilkS")
			(hide yes)
			(effects
				(font
					(size 1.27 1.27)
				)
			)
		)
		(property "Value" ""
			(at 0 0 270)
			(layer "F.Fab")
			(effects
				(font
					(size 1.27 1.27)
				)
			)
		)
		(duplicate_pad_numbers_are_jumpers no)
		(fp_line
			(start -0.7874 0.4064)
			(end -0.7874 -0.4064)
			(stroke
				(width 0.1524)
				(type default)
			)
			(layer "F.SilkS")
		)
		(fp_line
			(start 0.7874 0.4064)
			(end -0.7874 0.4064)
			(stroke
				(width 0.1524)
				(type default)
			)
			(layer "F.SilkS")
		)
		(fp_line
			(start -0.7874 -0.4064)
			(end 0.7874 -0.4064)
			(stroke
				(width 0.1524)
				(type default)
			)
			(layer "F.SilkS")
		)
		(fp_line
			(start 0.7874 -0.4064)
			(end 0.7874 0.4064)
			(stroke
				(width 0.1524)
				(type default)
			)
			(layer "F.SilkS")
		)
		(fp_line
			(start -0.67945 0.3048)
			(end -0.67945 -0.305054)
			(stroke
				(width 0.1)
				(type default)
			)
			(layer "F.Fab")
		)
		(fp_line
			(start -0.12065 0.3048)
			(end -0.67945 0.3048)
			(stroke
				(width 0.1)
				(type default)
			)
			(layer "F.Fab")
		)
		(fp_line
			(start 0.120396 0.3048)
			(end 0.120396 0.2794)
			(stroke
				(width 0.1)
				(type default)
			)
			(layer "F.Fab")
		)
		(fp_line
			(start 0.67945 0.3048)
			(end 0.120396 0.3048)
			(stroke
				(width 0.1)
				(type default)
			)
			(layer "F.Fab")
		)
		(fp_line
			(start -0.12065 0.2794)
			(end -0.12065 0.3048)
			(stroke
				(width 0.1)
				(type default)
			)
			(layer "F.Fab")
		)
		(fp_line
			(start 0.120396 0.2794)
			(end -0.12065 0.2794)
			(stroke
				(width 0.1)
				(type default)
			)
			(layer "F.Fab")
		)
		(fp_line
			(start -0.12065 -0.2794)
			(end 0.12065 -0.2794)
			(stroke
				(width 0.1)
				(type default)
			)
			(layer "F.Fab")
		)
		(fp_line
			(start 0.12065 -0.2794)
			(end 0.12065 -0.3048)
			(stroke
				(width 0.1)
				(type default)
			)
			(layer "F.Fab")
		)
		(fp_line
			(start 0.12065 -0.3048)
			(end 0.67945 -0.3048)
			(stroke
				(width 0.1)
				(type default)
			)
			(layer "F.Fab")
		)
		(fp_line
			(start 0.67945 -0.3048)
			(end 0.67945 0.3048)
			(stroke
				(width 0.1)
				(type default)
			)
			(layer "F.Fab")
		)
		(fp_line
			(start -0.67945 -0.305054)
			(end -0.12065 -0.305054)
			(stroke
				(width 0.1)
				(type default)
			)
			(layer "F.Fab")
		)
		(fp_line
			(start -0.12065 -0.305054)
			(end -0.12065 -0.2794)
			(stroke
				(width 0.1)
				(type default)
			)
			(layer "F.Fab")
		)
		(pad "1" smd circle
			(at -0.40005 0 270)
			(size 0 0)
			(layers "F.Cu" "F.Mask" "F.Paste")
			(net "PVCCFA_EHV_FIVRA_CPU0")
		)
		(pad "2" smd circle
			(at 0.40005 0 270)
			(size 0 0)
			(layers "F.Cu" "F.Mask" "F.Paste")
			(net "GND")
		)
	)
	(footprint ""
		(layer "F.Cu")
		(at 12.982956 -92.687648 90)
		(property "Reference" "R3660"
			(at 0 0 90)
			(layer "F.SilkS")
			(hide yes)
			(effects
				(font
					(size 1.27 1.27)
				)
			)
		)
		(property "Value" ""
			(at 0 0 90)
			(layer "F.Fab")
			(effects
				(font
					(size 1.27 1.27)
				)
			)
		)
		(duplicate_pad_numbers_are_jumpers no)
		(fp_line
			(start 0.7874 -0.4064)
			(end 0.7874 0.4064)
			(stroke
				(width 0.1524)
				(type default)
			)
			(layer "F.SilkS")
		)
		(fp_line
			(start -0.7874 -0.4064)
			(end 0.7874 -0.4064)
			(stroke
				(width 0.1524)
				(type default)
			)
			(layer "F.SilkS")
		)
		(fp_line
			(start 0.7874 0.4064)
			(end -0.7874 0.4064)
			(stroke
				(width 0.1524)
				(type default)
			)
			(layer "F.SilkS")
		)
		(fp_line
			(start -0.7874 0.4064)
			(end -0.7874 -0.4064)
			(stroke
				(width 0.1524)
				(type default)
			)
			(layer "F.SilkS")
		)
		(fp_line
			(start -0.12065 -0.305054)
			(end -0.12065 -0.2794)
			(stroke
				(width 0.1)
				(type default)
			)
			(layer "F.Fab")
		)
		(fp_line
			(start -0.67945 -0.305054)
			(end -0.12065 -0.305054)
			(stroke
				(width 0.1)
				(type default)
			)
			(layer "F.Fab")
		)
		(fp_line
			(start 0.67945 -0.3048)
			(end 0.67945 0.3048)
			(stroke
				(width 0.1)
				(type default)
			)
			(layer "F.Fab")
		)
		(fp_line
			(start 0.12065 -0.3048)
			(end 0.67945 -0.3048)
			(stroke
				(width 0.1)
				(type default)
			)
			(layer "F.Fab")
		)
		(fp_line
			(start 0.12065 -0.2794)
			(end 0.12065 -0.3048)
			(stroke
				(width 0.1)
				(type default)
			)
			(layer "F.Fab")
		)
		(fp_line
			(start -0.12065 -0.2794)
			(end 0.12065 -0.2794)
			(stroke
				(width 0.1)
				(type default)
			)
			(layer "F.Fab")
		)
		(fp_line
			(start 0.120396 0.2794)
			(end -0.12065 0.2794)
			(stroke
				(width 0.1)
				(type default)
			)
			(layer "F.Fab")
		)
		(fp_line
			(start -0.12065 0.2794)
			(end -0.12065 0.3048)
			(stroke
				(width 0.1)
				(type default)
			)
			(layer "F.Fab")
		)
		(fp_line
			(start 0.67945 0.3048)
			(end 0.120396 0.3048)
			(stroke
				(width 0.1)
				(type default)
			)
			(layer "F.Fab")
		)
		(fp_line
			(start 0.120396 0.3048)
			(end 0.120396 0.2794)
			(stroke
				(width 0.1)
				(type default)
			)
			(layer "F.Fab")
		)
		(fp_line
			(start -0.12065 0.3048)
			(end -0.67945 0.3048)
			(stroke
				(width 0.1)
				(type default)
			)
			(layer "F.Fab")
		)
		(fp_line
			(start -0.67945 0.3048)
			(end -0.67945 -0.305054)
			(stroke
				(width 0.1)
				(type default)
			)
			(layer "F.Fab")
		)
		(pad "1" smd circle
			(at -0.40005 0 90)
			(size 0 0)
			(layers "F.Cu" "F.Mask" "F.Paste")
			(net "P3V3_AUX")
		)
		(pad "2" smd circle
			(at 0.40005 0 90)
			(size 0 0)
			(layers "F.Cu" "F.Mask" "F.Paste")
			(net "RST_USB_HUB_R_N")
		)
	)
	(footprint ""
		(layer "F.Cu")
		(at 116.4844 -350.434148 90)
		(property "Reference" "PC2346"
			(at 0 0 90)
			(layer "F.SilkS")
			(hide yes)
			(effects
				(font
					(size 1.27 1.27)
				)
			)
		)
		(property "Value" ""
			(at 0 0 90)
			(layer "F.Fab")
			(effects
				(font
					(size 1.27 1.27)
				)
			)
		)
		(duplicate_pad_numbers_are_jumpers no)
		(fp_line
			(start -3.400044 1.249934)
			(end 3.400044 1.249934)
			(stroke
				(width 0.1524)
				(type default)
			)
			(layer "F.SilkS")
		)
		(fp_circle
			(center 0 1.249934)
			(end 0 4.649978)
			(stroke
				(width 0.1524)
				(type default)
			)
			(fill no)
			(layer "F.SilkS")
		)
		(fp_poly
			(pts
				(arc
					(start -3.400044 1.249934)
					(mid 0 4.649978)
					(end 3.400044 1.249934)
				)
			)
			(stroke
				(width 0)
				(type default)
			)
			(fill yes)
			(layer "F.SilkS")
		)
		(fp_circle
			(center 0 1.249934)
			(end 0 4.649978)
			(stroke
				(width 0.1)
				(type default)
			)
			(fill no)
			(layer "F.Fab")
		)
		(pad "1" thru_hole rect
			(at 0 0 90)
			(size 1.524 1.524)
			(drill 1.016)
			(layers "*.Cu" "*.Mask")
			(remove_unused_layers no)
			(net "SW_P12V_PVCCIN_CPU1_FLT")
			(clearance 0)
			(padstack
				(mode front_inner_back)
				(layer "Inner"
					(shape circle)
					(size 1.524 1.524)
					(clearance 0)
				)
				(layer "B.Cu"
					(shape rect)
					(size 1.524 1.524)
					(clearance 0)
				)
			)
		)
		(pad "2" thru_hole circle
			(at 0 2.500122 90)
			(size 1.524 1.524)
			(drill 1.016)
			(layers "*.Cu" "*.Mask")
			(remove_unused_layers no)
			(net "GND")
			(clearance 0)
		)
	)
	(footprint ""
		(layer "F.Cu")
		(at 320.190622 -57.267348)
		(property "Reference" "R619"
			(at 0 0 0)
			(layer "F.SilkS")
			(hide yes)
			(effects
				(font
					(size 1.27 1.27)
				)
			)
		)
		(property "Value" ""
			(at 0 0 0)
			(layer "F.Fab")
			(effects
				(font
					(size 1.27 1.27)
				)
			)
		)
		(duplicate_pad_numbers_are_jumpers no)
		(fp_line
			(start -0.7874 -0.4064)
			(end 0.7874 -0.4064)
			(stroke
				(width 0.1524)
				(type default)
			)
			(layer "F.SilkS")
		)
		(fp_line
			(start -0.7874 0.4064)
			(end -0.7874 -0.4064)
			(stroke
				(width 0.1524)
				(type default)
			)
			(layer "F.SilkS")
		)
		(fp_line
			(start 0.7874 -0.4064)
			(end 0.7874 0.4064)
			(stroke
				(width 0.1524)
				(type default)
			)
			(layer "F.SilkS")
		)
		(fp_line
			(start 0.7874 0.4064)
			(end -0.7874 0.4064)
			(stroke
				(width 0.1524)
				(type default)
			)
			(layer "F.SilkS")
		)
		(fp_line
			(start -0.67945 -0.305054)
			(end -0.12065 -0.305054)
			(stroke
				(width 0.1)
				(type default)
			)
			(layer "F.Fab")
		)
		(fp_line
			(start -0.67945 0.3048)
			(end -0.67945 -0.305054)
			(stroke
				(width 0.1)
				(type default)
			)
			(layer "F.Fab")
		)
		(fp_line
			(start -0.12065 -0.305054)
			(end -0.12065 -0.2794)
			(stroke
				(width 0.1)
				(type default)
			)
			(layer "F.Fab")
		)
		(fp_line
			(start -0.12065 -0.2794)
			(end 0.12065 -0.2794)
			(stroke
				(width 0.1)
				(type default)
			)
			(layer "F.Fab")
		)
		(fp_line
			(start -0.12065 0.2794)
			(end -0.12065 0.3048)
			(stroke
				(width 0.1)
				(type default)
			)
			(layer "F.Fab")
		)
		(fp_line
			(start -0.12065 0.3048)
			(end -0.67945 0.3048)
			(stroke
				(width 0.1)
				(type default)
			)
			(layer "F.Fab")
		)
		(fp_line
			(start 0.120396 0.2794)
			(end -0.12065 0.2794)
			(stroke
				(width 0.1)
				(type default)
			)
			(layer "F.Fab")
		)
		(fp_line
			(start 0.120396 0.3048)
			(end 0.120396 0.2794)
			(stroke
				(width 0.1)
				(type default)
			)
			(layer "F.Fab")
		)
		(fp_line
			(start 0.12065 -0.3048)
			(end 0.67945 -0.3048)
			(stroke
				(width 0.1)
				(type default)
			)
			(layer "F.Fab")
		)
		(fp_line
			(start 0.12065 -0.2794)
			(end 0.12065 -0.3048)
			(stroke
				(width 0.1)
				(type default)
			)
			(layer "F.Fab")
		)
		(fp_line
			(start 0.67945 -0.3048)
			(end 0.67945 0.3048)
			(stroke
				(width 0.1)
				(type default)
			)
			(layer "F.Fab")
		)
		(fp_line
			(start 0.67945 0.3048)
			(end 0.120396 0.3048)
			(stroke
				(width 0.1)
				(type default)
			)
			(layer "F.Fab")
		)
		(pad "1" smd circle
			(at -0.40005 0)
			(size 0 0)
			(layers "F.Cu" "F.Mask" "F.Paste")
			(net "P3V3_AUX")
		)
		(pad "2" smd circle
			(at 0.40005 0)
			(size 0 0)
			(layers "F.Cu" "F.Mask" "F.Paste")
			(net "FM_LT_KEY_DOWNGRADE_N")
		)
	)
	(footprint ""
		(layer "F.Cu")
		(at 68.147438 -32.776922 90)
		(property "Reference" "PR3847"
			(at 0 0 90)
			(layer "F.SilkS")
			(hide yes)
			(effects
				(font
					(size 1.27 1.27)
				)
			)
		)
		(property "Value" ""
			(at 0 0 90)
			(layer "F.Fab")
			(effects
				(font
					(size 1.27 1.27)
				)
			)
		)
		(duplicate_pad_numbers_are_jumpers no)
		(fp_line
			(start 0.7874 -0.4064)
			(end 0.7874 0.4064)
			(stroke
				(width 0.1524)
				(type default)
			)
			(layer "F.SilkS")
		)
		(fp_line
			(start -0.7874 -0.4064)
			(end 0.7874 -0.4064)
			(stroke
				(width 0.1524)
				(type default)
			)
			(layer "F.SilkS")
		)
		(fp_line
			(start 0.7874 0.4064)
			(end -0.7874 0.4064)
			(stroke
				(width 0.1524)
				(type default)
			)
			(layer "F.SilkS")
		)
		(fp_line
			(start -0.7874 0.4064)
			(end -0.7874 -0.4064)
			(stroke
				(width 0.1524)
				(type default)
			)
			(layer "F.SilkS")
		)
		(fp_line
			(start -0.12065 -0.305054)
			(end -0.12065 -0.2794)
			(stroke
				(width 0.1)
				(type default)
			)
			(layer "F.Fab")
		)
		(fp_line
			(start -0.67945 -0.305054)
			(end -0.12065 -0.305054)
			(stroke
				(width 0.1)
				(type default)
			)
			(layer "F.Fab")
		)
		(fp_line
			(start 0.67945 -0.3048)
			(end 0.67945 0.3048)
			(stroke
				(width 0.1)
				(type default)
			)
			(layer "F.Fab")
		)
		(fp_line
			(start 0.12065 -0.3048)
			(end 0.67945 -0.3048)
			(stroke
				(width 0.1)
				(type default)
			)
			(layer "F.Fab")
		)
		(fp_line
			(start 0.12065 -0.2794)
			(end 0.12065 -0.3048)
			(stroke
				(width 0.1)
				(type default)
			)
			(layer "F.Fab")
		)
		(fp_line
			(start -0.12065 -0.2794)
			(end 0.12065 -0.2794)
			(stroke
				(width 0.1)
				(type default)
			)
			(layer "F.Fab")
		)
		(fp_line
			(start 0.120396 0.2794)
			(end -0.12065 0.2794)
			(stroke
				(width 0.1)
				(type default)
			)
			(layer "F.Fab")
		)
		(fp_line
			(start -0.12065 0.2794)
			(end -0.12065 0.3048)
			(stroke
				(width 0.1)
				(type default)
			)
			(layer "F.Fab")
		)
		(fp_line
			(start 0.67945 0.3048)
			(end 0.120396 0.3048)
			(stroke
				(width 0.1)
				(type default)
			)
			(layer "F.Fab")
		)
		(fp_line
			(start 0.120396 0.3048)
			(end 0.120396 0.2794)
			(stroke
				(width 0.1)
				(type default)
			)
			(layer "F.Fab")
		)
		(fp_line
			(start -0.12065 0.3048)
			(end -0.67945 0.3048)
			(stroke
				(width 0.1)
				(type default)
			)
			(layer "F.Fab")
		)
		(fp_line
			(start -0.67945 0.3048)
			(end -0.67945 -0.305054)
			(stroke
				(width 0.1)
				(type default)
			)
			(layer "F.Fab")
		)
		(pad "1" smd circle
			(at -0.40005 0 90)
			(size 0 0)
			(layers "F.Cu" "F.Mask" "F.Paste")
			(net "P12V_OCP_ISET_2")
		)
		(pad "2" smd circle
			(at 0.40005 0 90)
			(size 0 0)
			(layers "F.Cu" "F.Mask" "F.Paste")
			(net "GND")
		)
	)
	(footprint ""
		(layer "F.Cu")
		(at 70.228714 -65.082674 -90)
		(property "Reference" "R3084"
			(at 0 0 270)
			(layer "F.SilkS")
			(hide yes)
			(effects
				(font
					(size 1.27 1.27)
				)
			)
		)
		(property "Value" ""
			(at 0 0 270)
			(layer "F.Fab")
			(effects
				(font
					(size 1.27 1.27)
				)
			)
		)
		(duplicate_pad_numbers_are_jumpers no)
		(fp_line
			(start -0.7874 0.4064)
			(end -0.7874 -0.4064)
			(stroke
				(width 0.1524)
				(type default)
			)
			(layer "F.SilkS")
		)
		(fp_line
			(start 0.7874 0.4064)
			(end -0.7874 0.4064)
			(stroke
				(width 0.1524)
				(type default)
			)
			(layer "F.SilkS")
		)
		(fp_line
			(start -0.7874 -0.4064)
			(end 0.7874 -0.4064)
			(stroke
				(width 0.1524)
				(type default)
			)
			(layer "F.SilkS")
		)
		(fp_line
			(start 0.7874 -0.4064)
			(end 0.7874 0.4064)
			(stroke
				(width 0.1524)
				(type default)
			)
			(layer "F.SilkS")
		)
		(fp_line
			(start -0.67945 0.3048)
			(end -0.67945 -0.305054)
			(stroke
				(width 0.1)
				(type default)
			)
			(layer "F.Fab")
		)
		(fp_line
			(start -0.12065 0.3048)
			(end -0.67945 0.3048)
			(stroke
				(width 0.1)
				(type default)
			)
			(layer "F.Fab")
		)
		(fp_line
			(start 0.120396 0.3048)
			(end 0.120396 0.2794)
			(stroke
				(width 0.1)
				(type default)
			)
			(layer "F.Fab")
		)
		(fp_line
			(start 0.67945 0.3048)
			(end 0.120396 0.3048)
			(stroke
				(width 0.1)
				(type default)
			)
			(layer "F.Fab")
		)
		(fp_line
			(start -0.12065 0.2794)
			(end -0.12065 0.3048)
			(stroke
				(width 0.1)
				(type default)
			)
			(layer "F.Fab")
		)
		(fp_line
			(start 0.120396 0.2794)
			(end -0.12065 0.2794)
			(stroke
				(width 0.1)
				(type default)
			)
			(layer "F.Fab")
		)
		(fp_line
			(start -0.12065 -0.2794)
			(end 0.12065 -0.2794)
			(stroke
				(width 0.1)
				(type default)
			)
			(layer "F.Fab")
		)
		(fp_line
			(start 0.12065 -0.2794)
			(end 0.12065 -0.3048)
			(stroke
				(width 0.1)
				(type default)
			)
			(layer "F.Fab")
		)
		(fp_line
			(start 0.12065 -0.3048)
			(end 0.67945 -0.3048)
			(stroke
				(width 0.1)
				(type default)
			)
			(layer "F.Fab")
		)
		(fp_line
			(start 0.67945 -0.3048)
			(end 0.67945 0.3048)
			(stroke
				(width 0.1)
				(type default)
			)
			(layer "F.Fab")
		)
		(fp_line
			(start -0.67945 -0.305054)
			(end -0.12065 -0.305054)
			(stroke
				(width 0.1)
				(type default)
			)
			(layer "F.Fab")
		)
		(fp_line
			(start -0.12065 -0.305054)
			(end -0.12065 -0.2794)
			(stroke
				(width 0.1)
				(type default)
			)
			(layer "F.Fab")
		)
		(pad "1" smd circle
			(at -0.40005 0 270)
			(size 0 0)
			(layers "F.Cu" "F.Mask" "F.Paste")
			(net "LED_RST_PLD_CPU1_DRAM_CD_N")
		)
		(pad "2" smd circle
			(at 0.40005 0 270)
			(size 0 0)
			(layers "F.Cu" "F.Mask" "F.Paste")
			(net "P3V3_AUX")
		)
	)
	(footprint ""
		(layer "F.Cu")
		(at 47.462694 -17.623536 90)
		(property "Reference" "C829"
			(at 0 0 90)
			(layer "F.SilkS")
			(hide yes)
			(effects
				(font
					(size 1.27 1.27)
				)
			)
		)
		(property "Value" ""
			(at 0 0 90)
			(layer "F.Fab")
			(effects
				(font
					(size 1.27 1.27)
				)
			)
		)
		(duplicate_pad_numbers_are_jumpers no)
		(fp_line
			(start 0.299974 -0.150114)
			(end 0.299974 0.150114)
			(stroke
				(width 0.1)
				(type default)
			)
			(layer "F.Fab")
		)
		(fp_line
			(start -0.299974 -0.150114)
			(end 0.299974 -0.150114)
			(stroke
				(width 0.1)
				(type default)
			)
			(layer "F.Fab")
		)
		(fp_line
			(start 0.299974 0.150114)
			(end -0.299974 0.150114)
			(stroke
				(width 0.1)
				(type default)
			)
			(layer "F.Fab")
		)
		(fp_line
			(start -0.299974 0.150114)
			(end -0.299974 -0.150114)
			(stroke
				(width 0.1)
				(type default)
			)
			(layer "F.Fab")
		)
		(pad "1" smd rect
			(at -0.2667 0 90)
			(size 0.3048 0.381)
			(layers "F.Cu" "F.Mask" "F.Paste")
			(net "P5E_CPU1_PE1_TX_C_DP<4>")
		)
		(pad "2" smd rect
			(at 0.2667 0 90)
			(size 0.3048 0.381)
			(layers "F.Cu" "F.Mask" "F.Paste")
			(net "P5E_CPU1_PE1_TX_DP<4>")
		)
	)
	(footprint ""
		(layer "F.Cu")
		(at 88.925146 -206.024734)
		(property "Reference" "H20"
			(at -0.34036 3.860292 0)
			(unlocked yes)
			(layer "F.SilkS")
			(effects
				(font
					(size 0.7874 0.5842)
					(thickness 0.1524)
				)
				(justify left)
			)
		)
		(property "Value" ""
			(at 0 0 0)
			(layer "F.Fab")
			(effects
				(font
					(size 1.27 1.27)
				)
			)
		)
		(duplicate_pad_numbers_are_jumpers no)
		(fp_circle
			(center 0 0)
			(end 2.5273 0)
			(stroke
				(width 0.1524)
				(type default)
			)
			(fill no)
			(layer "F.SilkS")
		)
		(fp_circle
			(center 0 0)
			(end 2.5273 0)
			(stroke
				(width 0.1524)
				(type default)
			)
			(fill no)
			(layer "B.SilkS")
		)
		(fp_circle
			(center 0 0)
			(end 2.5273 0)
			(stroke
				(width 0.1)
				(type default)
			)
			(fill no)
			(layer "B.Fab")
		)
		(fp_circle
			(center 0 0)
			(end 2.5273 0)
			(stroke
				(width 0.1)
				(type default)
			)
			(fill no)
			(layer "F.Fab")
		)
		(pad "" np_thru_hole circle
			(at 0 0)
			(size 3.429 3.429)
			(drill 3.429)
			(layers "*.Cu" "*.Mask")
			(clearance 0.381)
			(thermal_gap 0.381)
		)
	)
	(footprint ""
		(layer "F.Cu")
		(at 379.443996 -92.887292 -90)
		(property "Reference" "R1382"
			(at 0 0 270)
			(layer "F.SilkS")
			(hide yes)
			(effects
				(font
					(size 1.27 1.27)
				)
			)
		)
		(property "Value" ""
			(at 0 0 270)
			(layer "F.Fab")
			(effects
				(font
					(size 1.27 1.27)
				)
			)
		)
		(duplicate_pad_numbers_are_jumpers no)
		(fp_line
			(start -0.7874 0.4064)
			(end -0.7874 -0.4064)
			(stroke
				(width 0.1524)
				(type default)
			)
			(layer "F.SilkS")
		)
		(fp_line
			(start 0.7874 0.4064)
			(end -0.7874 0.4064)
			(stroke
				(width 0.1524)
				(type default)
			)
			(layer "F.SilkS")
		)
		(fp_line
			(start -0.7874 -0.4064)
			(end 0.7874 -0.4064)
			(stroke
				(width 0.1524)
				(type default)
			)
			(layer "F.SilkS")
		)
		(fp_line
			(start 0.7874 -0.4064)
			(end 0.7874 0.4064)
			(stroke
				(width 0.1524)
				(type default)
			)
			(layer "F.SilkS")
		)
		(fp_line
			(start -0.67945 0.3048)
			(end -0.67945 -0.305054)
			(stroke
				(width 0.1)
				(type default)
			)
			(layer "F.Fab")
		)
		(fp_line
			(start -0.12065 0.3048)
			(end -0.67945 0.3048)
			(stroke
				(width 0.1)
				(type default)
			)
			(layer "F.Fab")
		)
		(fp_line
			(start 0.120396 0.3048)
			(end 0.120396 0.2794)
			(stroke
				(width 0.1)
				(type default)
			)
			(layer "F.Fab")
		)
		(fp_line
			(start 0.67945 0.3048)
			(end 0.120396 0.3048)
			(stroke
				(width 0.1)
				(type default)
			)
			(layer "F.Fab")
		)
		(fp_line
			(start -0.12065 0.2794)
			(end -0.12065 0.3048)
			(stroke
				(width 0.1)
				(type default)
			)
			(layer "F.Fab")
		)
		(fp_line
			(start 0.120396 0.2794)
			(end -0.12065 0.2794)
			(stroke
				(width 0.1)
				(type default)
			)
			(layer "F.Fab")
		)
		(fp_line
			(start -0.12065 -0.2794)
			(end 0.12065 -0.2794)
			(stroke
				(width 0.1)
				(type default)
			)
			(layer "F.Fab")
		)
		(fp_line
			(start 0.12065 -0.2794)
			(end 0.12065 -0.3048)
			(stroke
				(width 0.1)
				(type default)
			)
			(layer "F.Fab")
		)
		(fp_line
			(start 0.12065 -0.3048)
			(end 0.67945 -0.3048)
			(stroke
				(width 0.1)
				(type default)
			)
			(layer "F.Fab")
		)
		(fp_line
			(start 0.67945 -0.3048)
			(end 0.67945 0.3048)
			(stroke
				(width 0.1)
				(type default)
			)
			(layer "F.Fab")
		)
		(fp_line
			(start -0.67945 -0.305054)
			(end -0.12065 -0.305054)
			(stroke
				(width 0.1)
				(type default)
			)
			(layer "F.Fab")
		)
		(fp_line
			(start -0.12065 -0.305054)
			(end -0.12065 -0.2794)
			(stroke
				(width 0.1)
				(type default)
			)
			(layer "F.Fab")
		)
		(pad "1" smd circle
			(at -0.40005 0 270)
			(size 0 0)
			(layers "F.Cu" "F.Mask" "F.Paste")
			(net "P3V3_AUX")
		)
		(pad "2" smd circle
			(at 0.40005 0 270)
			(size 0 0)
			(layers "F.Cu" "F.Mask" "F.Paste")
			(net "JTAG_DBP_BMC_PRDY_N")
		)
	)
	(footprint ""
		(layer "F.Cu")
		(at 354.282248 -249.320304 -90)
		(property "Reference" "C1038"
			(at 0 0 270)
			(layer "F.SilkS")
			(hide yes)
			(effects
				(font
					(size 1.27 1.27)
				)
			)
		)
		(property "Value" ""
			(at 0 0 270)
			(layer "F.Fab")
			(effects
				(font
					(size 1.27 1.27)
				)
			)
		)
		(duplicate_pad_numbers_are_jumpers no)
		(fp_line
			(start -0.7874 0.4064)
			(end -0.7874 -0.4064)
			(stroke
				(width 0.1524)
				(type default)
			)
			(layer "F.SilkS")
		)
		(fp_line
			(start 0.7874 0.4064)
			(end -0.7874 0.4064)
			(stroke
				(width 0.1524)
				(type default)
			)
			(layer "F.SilkS")
		)
		(fp_line
			(start -0.7874 -0.4064)
			(end 0.7874 -0.4064)
			(stroke
				(width 0.1524)
				(type default)
			)
			(layer "F.SilkS")
		)
		(fp_line
			(start 0.7874 -0.4064)
			(end 0.7874 0.4064)
			(stroke
				(width 0.1524)
				(type default)
			)
			(layer "F.SilkS")
		)
		(fp_line
			(start -0.67945 0.3048)
			(end -0.67945 -0.305054)
			(stroke
				(width 0.1)
				(type default)
			)
			(layer "F.Fab")
		)
		(fp_line
			(start -0.12065 0.3048)
			(end -0.67945 0.3048)
			(stroke
				(width 0.1)
				(type default)
			)
			(layer "F.Fab")
		)
		(fp_line
			(start 0.120396 0.3048)
			(end 0.120396 0.2794)
			(stroke
				(width 0.1)
				(type default)
			)
			(layer "F.Fab")
		)
		(fp_line
			(start 0.67945 0.3048)
			(end 0.120396 0.3048)
			(stroke
				(width 0.1)
				(type default)
			)
			(layer "F.Fab")
		)
		(fp_line
			(start -0.12065 0.2794)
			(end -0.12065 0.3048)
			(stroke
				(width 0.1)
				(type default)
			)
			(layer "F.Fab")
		)
		(fp_line
			(start 0.120396 0.2794)
			(end -0.12065 0.2794)
			(stroke
				(width 0.1)
				(type default)
			)
			(layer "F.Fab")
		)
		(fp_line
			(start -0.12065 -0.2794)
			(end 0.12065 -0.2794)
			(stroke
				(width 0.1)
				(type default)
			)
			(layer "F.Fab")
		)
		(fp_line
			(start 0.12065 -0.2794)
			(end 0.12065 -0.3048)
			(stroke
				(width 0.1)
				(type default)
			)
			(layer "F.Fab")
		)
		(fp_line
			(start 0.12065 -0.3048)
			(end 0.67945 -0.3048)
			(stroke
				(width 0.1)
				(type default)
			)
			(layer "F.Fab")
		)
		(fp_line
			(start 0.67945 -0.3048)
			(end 0.67945 0.3048)
			(stroke
				(width 0.1)
				(type default)
			)
			(layer "F.Fab")
		)
		(fp_line
			(start -0.67945 -0.305054)
			(end -0.12065 -0.305054)
			(stroke
				(width 0.1)
				(type default)
			)
			(layer "F.Fab")
		)
		(fp_line
			(start -0.12065 -0.305054)
			(end -0.12065 -0.2794)
			(stroke
				(width 0.1)
				(type default)
			)
			(layer "F.Fab")
		)
		(pad "1" smd circle
			(at -0.40005 0 270)
			(size 0 0)
			(layers "F.Cu" "F.Mask" "F.Paste")
			(net "PVCCIN_CPU0")
		)
		(pad "2" smd circle
			(at 0.40005 0 270)
			(size 0 0)
			(layers "F.Cu" "F.Mask" "F.Paste")
			(net "GND")
		)
	)
	(footprint ""
		(layer "F.Cu")
		(at 109.580934 -394.15974 180)
		(property "Reference" "R3488"
			(at 0 0 180)
			(layer "F.SilkS")
			(hide yes)
			(effects
				(font
					(size 1.27 1.27)
				)
			)
		)
		(property "Value" ""
			(at 0 0 180)
			(layer "F.Fab")
			(effects
				(font
					(size 1.27 1.27)
				)
			)
		)
		(duplicate_pad_numbers_are_jumpers no)
		(fp_line
			(start 0.7874 0.4064)
			(end -0.7874 0.4064)
			(stroke
				(width 0.1524)
				(type default)
			)
			(layer "F.SilkS")
		)
		(fp_line
			(start 0.7874 -0.4064)
			(end 0.7874 0.4064)
			(stroke
				(width 0.1524)
				(type default)
			)
			(layer "F.SilkS")
		)
		(fp_line
			(start -0.7874 0.4064)
			(end -0.7874 -0.4064)
			(stroke
				(width 0.1524)
				(type default)
			)
			(layer "F.SilkS")
		)
		(fp_line
			(start -0.7874 -0.4064)
			(end 0.7874 -0.4064)
			(stroke
				(width 0.1524)
				(type default)
			)
			(layer "F.SilkS")
		)
		(fp_line
			(start 0.67945 0.3048)
			(end 0.120396 0.3048)
			(stroke
				(width 0.1)
				(type default)
			)
			(layer "F.Fab")
		)
		(fp_line
			(start 0.67945 -0.3048)
			(end 0.67945 0.3048)
			(stroke
				(width 0.1)
				(type default)
			)
			(layer "F.Fab")
		)
		(fp_line
			(start 0.12065 -0.2794)
			(end 0.12065 -0.3048)
			(stroke
				(width 0.1)
				(type default)
			)
			(layer "F.Fab")
		)
		(fp_line
			(start 0.12065 -0.3048)
			(end 0.67945 -0.3048)
			(stroke
				(width 0.1)
				(type default)
			)
			(layer "F.Fab")
		)
		(fp_line
			(start 0.120396 0.3048)
			(end 0.120396 0.2794)
			(stroke
				(width 0.1)
				(type default)
			)
			(layer "F.Fab")
		)
		(fp_line
			(start 0.120396 0.2794)
			(end -0.12065 0.2794)
			(stroke
				(width 0.1)
				(type default)
			)
			(layer "F.Fab")
		)
		(fp_line
			(start -0.12065 0.3048)
			(end -0.67945 0.3048)
			(stroke
				(width 0.1)
				(type default)
			)
			(layer "F.Fab")
		)
		(fp_line
			(start -0.12065 0.2794)
			(end -0.12065 0.3048)
			(stroke
				(width 0.1)
				(type default)
			)
			(layer "F.Fab")
		)
		(fp_line
			(start -0.12065 -0.2794)
			(end 0.12065 -0.2794)
			(stroke
				(width 0.1)
				(type default)
			)
			(layer "F.Fab")
		)
		(fp_line
			(start -0.12065 -0.305054)
			(end -0.12065 -0.2794)
			(stroke
				(width 0.1)
				(type default)
			)
			(layer "F.Fab")
		)
		(fp_line
			(start -0.67945 0.3048)
			(end -0.67945 -0.305054)
			(stroke
				(width 0.1)
				(type default)
			)
			(layer "F.Fab")
		)
		(fp_line
			(start -0.67945 -0.305054)
			(end -0.12065 -0.305054)
			(stroke
				(width 0.1)
				(type default)
			)
			(layer "F.Fab")
		)
		(pad "1" smd circle
			(at -0.40005 0 180)
			(size 0 0)
			(layers "F.Cu" "F.Mask" "F.Paste")
			(net "P3V3_AUX")
		)
		(pad "2" smd circle
			(at 0.40005 0 180)
			(size 0 0)
			(layers "F.Cu" "F.Mask" "F.Paste")
			(net "GPU_FPGA_EROT_RST_N")
		)
	)
	(footprint ""
		(layer "F.Cu")
		(at 16.51 -426.1358 -90)
		(property "Reference" "R4742"
			(at 0 0 270)
			(layer "F.SilkS")
			(hide yes)
			(effects
				(font
					(size 1.27 1.27)
				)
			)
		)
		(property "Value" ""
			(at 0 0 270)
			(layer "F.Fab")
			(effects
				(font
					(size 1.27 1.27)
				)
			)
		)
		(duplicate_pad_numbers_are_jumpers no)
		(fp_line
			(start -0.7874 0.4064)
			(end -0.7874 -0.4064)
			(stroke
				(width 0.1524)
				(type default)
			)
			(layer "F.SilkS")
		)
		(fp_line
			(start 0.7874 0.4064)
			(end -0.7874 0.4064)
			(stroke
				(width 0.1524)
				(type default)
			)
			(layer "F.SilkS")
		)
		(fp_line
			(start -0.7874 -0.4064)
			(end 0.7874 -0.4064)
			(stroke
				(width 0.1524)
				(type default)
			)
			(layer "F.SilkS")
		)
		(fp_line
			(start 0.7874 -0.4064)
			(end 0.7874 0.4064)
			(stroke
				(width 0.1524)
				(type default)
			)
			(layer "F.SilkS")
		)
		(fp_line
			(start -0.67945 0.3048)
			(end -0.67945 -0.305054)
			(stroke
				(width 0.1)
				(type default)
			)
			(layer "F.Fab")
		)
		(fp_line
			(start -0.12065 0.3048)
			(end -0.67945 0.3048)
			(stroke
				(width 0.1)
				(type default)
			)
			(layer "F.Fab")
		)
		(fp_line
			(start 0.120396 0.3048)
			(end 0.120396 0.2794)
			(stroke
				(width 0.1)
				(type default)
			)
			(layer "F.Fab")
		)
		(fp_line
			(start 0.67945 0.3048)
			(end 0.120396 0.3048)
			(stroke
				(width 0.1)
				(type default)
			)
			(layer "F.Fab")
		)
		(fp_line
			(start -0.12065 0.2794)
			(end -0.12065 0.3048)
			(stroke
				(width 0.1)
				(type default)
			)
			(layer "F.Fab")
		)
		(fp_line
			(start 0.120396 0.2794)
			(end -0.12065 0.2794)
			(stroke
				(width 0.1)
				(type default)
			)
			(layer "F.Fab")
		)
		(fp_line
			(start -0.12065 -0.2794)
			(end 0.12065 -0.2794)
			(stroke
				(width 0.1)
				(type default)
			)
			(layer "F.Fab")
		)
		(fp_line
			(start 0.12065 -0.2794)
			(end 0.12065 -0.3048)
			(stroke
				(width 0.1)
				(type default)
			)
			(layer "F.Fab")
		)
		(fp_line
			(start 0.12065 -0.3048)
			(end 0.67945 -0.3048)
			(stroke
				(width 0.1)
				(type default)
			)
			(layer "F.Fab")
		)
		(fp_line
			(start 0.67945 -0.3048)
			(end 0.67945 0.3048)
			(stroke
				(width 0.1)
				(type default)
			)
			(layer "F.Fab")
		)
		(fp_line
			(start -0.67945 -0.305054)
			(end -0.12065 -0.305054)
			(stroke
				(width 0.1)
				(type default)
			)
			(layer "F.Fab")
		)
		(fp_line
			(start -0.12065 -0.305054)
			(end -0.12065 -0.2794)
			(stroke
				(width 0.1)
				(type default)
			)
			(layer "F.Fab")
		)
		(pad "1" smd circle
			(at -0.40005 0 270)
			(size 0 0)
			(layers "F.Cu" "F.Mask" "F.Paste")
			(net "PRSNT_CABLE_GPU_A1_ISO_N")
		)
		(pad "2" smd circle
			(at 0.40005 0 270)
			(size 0 0)
			(layers "F.Cu" "F.Mask" "F.Paste")
			(net "PRSNT_CABLE_GPU_A1_ISO_R1_N")
		)
	)
	(footprint ""
		(layer "F.Cu")
		(at 164.64788 -105.755948)
		(property "Reference" "R2844"
			(at 0 0 0)
			(layer "F.SilkS")
			(hide yes)
			(effects
				(font
					(size 1.27 1.27)
				)
			)
		)
		(property "Value" ""
			(at 0 0 0)
			(layer "F.Fab")
			(effects
				(font
					(size 1.27 1.27)
				)
			)
		)
		(duplicate_pad_numbers_are_jumpers no)
		(fp_line
			(start -0.7874 -0.4064)
			(end 0.7874 -0.4064)
			(stroke
				(width 0.1524)
				(type default)
			)
			(layer "F.SilkS")
		)
		(fp_line
			(start -0.7874 0.4064)
			(end -0.7874 -0.4064)
			(stroke
				(width 0.1524)
				(type default)
			)
			(layer "F.SilkS")
		)
		(fp_line
			(start 0.7874 -0.4064)
			(end 0.7874 0.4064)
			(stroke
				(width 0.1524)
				(type default)
			)
			(layer "F.SilkS")
		)
		(fp_line
			(start 0.7874 0.4064)
			(end -0.7874 0.4064)
			(stroke
				(width 0.1524)
				(type default)
			)
			(layer "F.SilkS")
		)
		(fp_line
			(start -0.67945 -0.305054)
			(end -0.12065 -0.305054)
			(stroke
				(width 0.1)
				(type default)
			)
			(layer "F.Fab")
		)
		(fp_line
			(start -0.67945 0.3048)
			(end -0.67945 -0.305054)
			(stroke
				(width 0.1)
				(type default)
			)
			(layer "F.Fab")
		)
		(fp_line
			(start -0.12065 -0.305054)
			(end -0.12065 -0.2794)
			(stroke
				(width 0.1)
				(type default)
			)
			(layer "F.Fab")
		)
		(fp_line
			(start -0.12065 -0.2794)
			(end 0.12065 -0.2794)
			(stroke
				(width 0.1)
				(type default)
			)
			(layer "F.Fab")
		)
		(fp_line
			(start -0.12065 0.2794)
			(end -0.12065 0.3048)
			(stroke
				(width 0.1)
				(type default)
			)
			(layer "F.Fab")
		)
		(fp_line
			(start -0.12065 0.3048)
			(end -0.67945 0.3048)
			(stroke
				(width 0.1)
				(type default)
			)
			(layer "F.Fab")
		)
		(fp_line
			(start 0.120396 0.2794)
			(end -0.12065 0.2794)
			(stroke
				(width 0.1)
				(type default)
			)
			(layer "F.Fab")
		)
		(fp_line
			(start 0.120396 0.3048)
			(end 0.120396 0.2794)
			(stroke
				(width 0.1)
				(type default)
			)
			(layer "F.Fab")
		)
		(fp_line
			(start 0.12065 -0.3048)
			(end 0.67945 -0.3048)
			(stroke
				(width 0.1)
				(type default)
			)
			(layer "F.Fab")
		)
		(fp_line
			(start 0.12065 -0.2794)
			(end 0.12065 -0.3048)
			(stroke
				(width 0.1)
				(type default)
			)
			(layer "F.Fab")
		)
		(fp_line
			(start 0.67945 -0.3048)
			(end 0.67945 0.3048)
			(stroke
				(width 0.1)
				(type default)
			)
			(layer "F.Fab")
		)
		(fp_line
			(start 0.67945 0.3048)
			(end 0.120396 0.3048)
			(stroke
				(width 0.1)
				(type default)
			)
			(layer "F.Fab")
		)
		(pad "1" smd circle
			(at -0.40005 0)
			(size 0 0)
			(layers "F.Cu" "F.Mask" "F.Paste")
			(net "FM_SWB_BIC_READY_ISO_N")
		)
		(pad "2" smd circle
			(at 0.40005 0)
			(size 0 0)
			(layers "F.Cu" "F.Mask" "F.Paste")
			(net "FM_SWB_BIC_READY_ISO_R_N")
		)
	)
	(footprint ""
		(layer "F.Cu")
		(at 108.05668 -59.070748)
		(property "Reference" "C1289"
			(at 0 0 0)
			(layer "F.SilkS")
			(hide yes)
			(effects
				(font
					(size 1.27 1.27)
				)
			)
		)
		(property "Value" ""
			(at 0 0 0)
			(layer "F.Fab")
			(effects
				(font
					(size 1.27 1.27)
				)
			)
		)
		(duplicate_pad_numbers_are_jumpers no)
		(fp_line
			(start -0.7874 -0.4064)
			(end 0.7874 -0.4064)
			(stroke
				(width 0.1524)
				(type default)
			)
			(layer "F.SilkS")
		)
		(fp_line
			(start -0.7874 0.4064)
			(end -0.7874 -0.4064)
			(stroke
				(width 0.1524)
				(type default)
			)
			(layer "F.SilkS")
		)
		(fp_line
			(start 0.7874 -0.4064)
			(end 0.7874 0.4064)
			(stroke
				(width 0.1524)
				(type default)
			)
			(layer "F.SilkS")
		)
		(fp_line
			(start 0.7874 0.4064)
			(end -0.7874 0.4064)
			(stroke
				(width 0.1524)
				(type default)
			)
			(layer "F.SilkS")
		)
		(fp_line
			(start -0.67945 -0.305054)
			(end -0.12065 -0.305054)
			(stroke
				(width 0.1)
				(type default)
			)
			(layer "F.Fab")
		)
		(fp_line
			(start -0.67945 0.3048)
			(end -0.67945 -0.305054)
			(stroke
				(width 0.1)
				(type default)
			)
			(layer "F.Fab")
		)
		(fp_line
			(start -0.12065 -0.305054)
			(end -0.12065 -0.2794)
			(stroke
				(width 0.1)
				(type default)
			)
			(layer "F.Fab")
		)
		(fp_line
			(start -0.12065 -0.2794)
			(end 0.12065 -0.2794)
			(stroke
				(width 0.1)
				(type default)
			)
			(layer "F.Fab")
		)
		(fp_line
			(start -0.12065 0.2794)
			(end -0.12065 0.3048)
			(stroke
				(width 0.1)
				(type default)
			)
			(layer "F.Fab")
		)
		(fp_line
			(start -0.12065 0.3048)
			(end -0.67945 0.3048)
			(stroke
				(width 0.1)
				(type default)
			)
			(layer "F.Fab")
		)
		(fp_line
			(start 0.120396 0.2794)
			(end -0.12065 0.2794)
			(stroke
				(width 0.1)
				(type default)
			)
			(layer "F.Fab")
		)
		(fp_line
			(start 0.120396 0.3048)
			(end 0.120396 0.2794)
			(stroke
				(width 0.1)
				(type default)
			)
			(layer "F.Fab")
		)
		(fp_line
			(start 0.12065 -0.3048)
			(end 0.67945 -0.3048)
			(stroke
				(width 0.1)
				(type default)
			)
			(layer "F.Fab")
		)
		(fp_line
			(start 0.12065 -0.2794)
			(end 0.12065 -0.3048)
			(stroke
				(width 0.1)
				(type default)
			)
			(layer "F.Fab")
		)
		(fp_line
			(start 0.67945 -0.3048)
			(end 0.67945 0.3048)
			(stroke
				(width 0.1)
				(type default)
			)
			(layer "F.Fab")
		)
		(fp_line
			(start 0.67945 0.3048)
			(end 0.120396 0.3048)
			(stroke
				(width 0.1)
				(type default)
			)
			(layer "F.Fab")
		)
		(pad "1" smd circle
			(at -0.40005 0)
			(size 0 0)
			(layers "F.Cu" "F.Mask" "F.Paste")
			(net "P3V3_AUX")
		)
		(pad "2" smd circle
			(at 0.40005 0)
			(size 0 0)
			(layers "F.Cu" "F.Mask" "F.Paste")
			(net "GND")
		)
	)
	(footprint ""
		(layer "F.Cu")
		(at 308.508654 -13.68044 180)
		(property "Reference" "C1663"
			(at 0 0 180)
			(layer "F.SilkS")
			(hide yes)
			(effects
				(font
					(size 1.27 1.27)
				)
			)
		)
		(property "Value" ""
			(at 0 0 180)
			(layer "F.Fab")
			(effects
				(font
					(size 1.27 1.27)
				)
			)
		)
		(duplicate_pad_numbers_are_jumpers no)
		(fp_line
			(start 0.7874 0.4064)
			(end -0.7874 0.4064)
			(stroke
				(width 0.1524)
				(type default)
			)
			(layer "F.SilkS")
		)
		(fp_line
			(start 0.7874 -0.4064)
			(end 0.7874 0.4064)
			(stroke
				(width 0.1524)
				(type default)
			)
			(layer "F.SilkS")
		)
		(fp_line
			(start -0.7874 0.4064)
			(end -0.7874 -0.4064)
			(stroke
				(width 0.1524)
				(type default)
			)
			(layer "F.SilkS")
		)
		(fp_line
			(start -0.7874 -0.4064)
			(end 0.7874 -0.4064)
			(stroke
				(width 0.1524)
				(type default)
			)
			(layer "F.SilkS")
		)
		(fp_line
			(start 0.67945 0.3048)
			(end 0.120396 0.3048)
			(stroke
				(width 0.1)
				(type default)
			)
			(layer "F.Fab")
		)
		(fp_line
			(start 0.67945 -0.3048)
			(end 0.67945 0.3048)
			(stroke
				(width 0.1)
				(type default)
			)
			(layer "F.Fab")
		)
		(fp_line
			(start 0.12065 -0.2794)
			(end 0.12065 -0.3048)
			(stroke
				(width 0.1)
				(type default)
			)
			(layer "F.Fab")
		)
		(fp_line
			(start 0.12065 -0.3048)
			(end 0.67945 -0.3048)
			(stroke
				(width 0.1)
				(type default)
			)
			(layer "F.Fab")
		)
		(fp_line
			(start 0.120396 0.3048)
			(end 0.120396 0.2794)
			(stroke
				(width 0.1)
				(type default)
			)
			(layer "F.Fab")
		)
		(fp_line
			(start 0.120396 0.2794)
			(end -0.12065 0.2794)
			(stroke
				(width 0.1)
				(type default)
			)
			(layer "F.Fab")
		)
		(fp_line
			(start -0.12065 0.3048)
			(end -0.67945 0.3048)
			(stroke
				(width 0.1)
				(type default)
			)
			(layer "F.Fab")
		)
		(fp_line
			(start -0.12065 0.2794)
			(end -0.12065 0.3048)
			(stroke
				(width 0.1)
				(type default)
			)
			(layer "F.Fab")
		)
		(fp_line
			(start -0.12065 -0.2794)
			(end 0.12065 -0.2794)
			(stroke
				(width 0.1)
				(type default)
			)
			(layer "F.Fab")
		)
		(fp_line
			(start -0.12065 -0.305054)
			(end -0.12065 -0.2794)
			(stroke
				(width 0.1)
				(type default)
			)
			(layer "F.Fab")
		)
		(fp_line
			(start -0.67945 0.3048)
			(end -0.67945 -0.305054)
			(stroke
				(width 0.1)
				(type default)
			)
			(layer "F.Fab")
		)
		(fp_line
			(start -0.67945 -0.305054)
			(end -0.12065 -0.305054)
			(stroke
				(width 0.1)
				(type default)
			)
			(layer "F.Fab")
		)
		(pad "1" smd circle
			(at -0.40005 0 180)
			(size 0 0)
			(layers "F.Cu" "F.Mask" "F.Paste")
			(net "P3V3_AUX")
		)
		(pad "2" smd circle
			(at 0.40005 0 180)
			(size 0 0)
			(layers "F.Cu" "F.Mask" "F.Paste")
			(net "GND")
		)
	)
	(footprint ""
		(layer "F.Cu")
		(at 193.60388 -99.875848)
		(property "Reference" "R700"
			(at 0 0 0)
			(layer "F.SilkS")
			(hide yes)
			(effects
				(font
					(size 1.27 1.27)
				)
			)
		)
		(property "Value" ""
			(at 0 0 0)
			(layer "F.Fab")
			(effects
				(font
					(size 1.27 1.27)
				)
			)
		)
		(duplicate_pad_numbers_are_jumpers no)
		(fp_line
			(start -0.7874 -0.4064)
			(end 0.7874 -0.4064)
			(stroke
				(width 0.1524)
				(type default)
			)
			(layer "F.SilkS")
		)
		(fp_line
			(start -0.7874 0.4064)
			(end -0.7874 -0.4064)
			(stroke
				(width 0.1524)
				(type default)
			)
			(layer "F.SilkS")
		)
		(fp_line
			(start 0.7874 -0.4064)
			(end 0.7874 0.4064)
			(stroke
				(width 0.1524)
				(type default)
			)
			(layer "F.SilkS")
		)
		(fp_line
			(start 0.7874 0.4064)
			(end -0.7874 0.4064)
			(stroke
				(width 0.1524)
				(type default)
			)
			(layer "F.SilkS")
		)
		(fp_line
			(start -0.67945 -0.305054)
			(end -0.12065 -0.305054)
			(stroke
				(width 0.1)
				(type default)
			)
			(layer "F.Fab")
		)
		(fp_line
			(start -0.67945 0.3048)
			(end -0.67945 -0.305054)
			(stroke
				(width 0.1)
				(type default)
			)
			(layer "F.Fab")
		)
		(fp_line
			(start -0.12065 -0.305054)
			(end -0.12065 -0.2794)
			(stroke
				(width 0.1)
				(type default)
			)
			(layer "F.Fab")
		)
		(fp_line
			(start -0.12065 -0.2794)
			(end 0.12065 -0.2794)
			(stroke
				(width 0.1)
				(type default)
			)
			(layer "F.Fab")
		)
		(fp_line
			(start -0.12065 0.2794)
			(end -0.12065 0.3048)
			(stroke
				(width 0.1)
				(type default)
			)
			(layer "F.Fab")
		)
		(fp_line
			(start -0.12065 0.3048)
			(end -0.67945 0.3048)
			(stroke
				(width 0.1)
				(type default)
			)
			(layer "F.Fab")
		)
		(fp_line
			(start 0.120396 0.2794)
			(end -0.12065 0.2794)
			(stroke
				(width 0.1)
				(type default)
			)
			(layer "F.Fab")
		)
		(fp_line
			(start 0.120396 0.3048)
			(end 0.120396 0.2794)
			(stroke
				(width 0.1)
				(type default)
			)
			(layer "F.Fab")
		)
		(fp_line
			(start 0.12065 -0.3048)
			(end 0.67945 -0.3048)
			(stroke
				(width 0.1)
				(type default)
			)
			(layer "F.Fab")
		)
		(fp_line
			(start 0.12065 -0.2794)
			(end 0.12065 -0.3048)
			(stroke
				(width 0.1)
				(type default)
			)
			(layer "F.Fab")
		)
		(fp_line
			(start 0.67945 -0.3048)
			(end 0.67945 0.3048)
			(stroke
				(width 0.1)
				(type default)
			)
			(layer "F.Fab")
		)
		(fp_line
			(start 0.67945 0.3048)
			(end 0.120396 0.3048)
			(stroke
				(width 0.1)
				(type default)
			)
			(layer "F.Fab")
		)
		(pad "1" smd circle
			(at -0.40005 0)
			(size 0 0)
			(layers "F.Cu" "F.Mask" "F.Paste")
			(net "FM_ADR_ACK_R")
		)
		(pad "2" smd circle
			(at 0.40005 0)
			(size 0 0)
			(layers "F.Cu" "F.Mask" "F.Paste")
			(net "FM_ADR_ACK")
		)
	)
	(footprint ""
		(layer "F.Cu")
		(at 367.44783 -260.364986 -90)
		(property "Reference" "C414"
			(at 0 0 270)
			(layer "F.SilkS")
			(hide yes)
			(effects
				(font
					(size 1.27 1.27)
				)
			)
		)
		(property "Value" ""
			(at 0 0 270)
			(layer "F.Fab")
			(effects
				(font
					(size 1.27 1.27)
				)
			)
		)
		(duplicate_pad_numbers_are_jumpers no)
		(fp_line
			(start -0.7874 0.4064)
			(end -0.7874 -0.4064)
			(stroke
				(width 0.1524)
				(type default)
			)
			(layer "F.SilkS")
		)
		(fp_line
			(start 0.7874 0.4064)
			(end -0.7874 0.4064)
			(stroke
				(width 0.1524)
				(type default)
			)
			(layer "F.SilkS")
		)
		(fp_line
			(start -0.7874 -0.4064)
			(end 0.7874 -0.4064)
			(stroke
				(width 0.1524)
				(type default)
			)
			(layer "F.SilkS")
		)
		(fp_line
			(start 0.7874 -0.4064)
			(end 0.7874 0.4064)
			(stroke
				(width 0.1524)
				(type default)
			)
			(layer "F.SilkS")
		)
		(fp_line
			(start -0.67945 0.3048)
			(end -0.67945 -0.305054)
			(stroke
				(width 0.1)
				(type default)
			)
			(layer "F.Fab")
		)
		(fp_line
			(start -0.12065 0.3048)
			(end -0.67945 0.3048)
			(stroke
				(width 0.1)
				(type default)
			)
			(layer "F.Fab")
		)
		(fp_line
			(start 0.120396 0.3048)
			(end 0.120396 0.2794)
			(stroke
				(width 0.1)
				(type default)
			)
			(layer "F.Fab")
		)
		(fp_line
			(start 0.67945 0.3048)
			(end 0.120396 0.3048)
			(stroke
				(width 0.1)
				(type default)
			)
			(layer "F.Fab")
		)
		(fp_line
			(start -0.12065 0.2794)
			(end -0.12065 0.3048)
			(stroke
				(width 0.1)
				(type default)
			)
			(layer "F.Fab")
		)
		(fp_line
			(start 0.120396 0.2794)
			(end -0.12065 0.2794)
			(stroke
				(width 0.1)
				(type default)
			)
			(layer "F.Fab")
		)
		(fp_line
			(start -0.12065 -0.2794)
			(end 0.12065 -0.2794)
			(stroke
				(width 0.1)
				(type default)
			)
			(layer "F.Fab")
		)
		(fp_line
			(start 0.12065 -0.2794)
			(end 0.12065 -0.3048)
			(stroke
				(width 0.1)
				(type default)
			)
			(layer "F.Fab")
		)
		(fp_line
			(start 0.12065 -0.3048)
			(end 0.67945 -0.3048)
			(stroke
				(width 0.1)
				(type default)
			)
			(layer "F.Fab")
		)
		(fp_line
			(start 0.67945 -0.3048)
			(end 0.67945 0.3048)
			(stroke
				(width 0.1)
				(type default)
			)
			(layer "F.Fab")
		)
		(fp_line
			(start -0.67945 -0.305054)
			(end -0.12065 -0.305054)
			(stroke
				(width 0.1)
				(type default)
			)
			(layer "F.Fab")
		)
		(fp_line
			(start -0.12065 -0.305054)
			(end -0.12065 -0.2794)
			(stroke
				(width 0.1)
				(type default)
			)
			(layer "F.Fab")
		)
		(pad "1" smd circle
			(at -0.40005 0 270)
			(size 0 0)
			(layers "F.Cu" "F.Mask" "F.Paste")
			(net "PVCCINFAON_CPU0")
		)
		(pad "2" smd circle
			(at 0.40005 0 270)
			(size 0 0)
			(layers "F.Cu" "F.Mask" "F.Paste")
			(net "GND")
		)
	)
	(footprint ""
		(layer "F.Cu")
		(at 159.181546 -31.341568 90)
		(property "Reference" "R4458"
			(at 0 0 90)
			(layer "F.SilkS")
			(hide yes)
			(effects
				(font
					(size 1.27 1.27)
				)
			)
		)
		(property "Value" ""
			(at 0 0 90)
			(layer "F.Fab")
			(effects
				(font
					(size 1.27 1.27)
				)
			)
		)
		(duplicate_pad_numbers_are_jumpers no)
		(fp_line
			(start 0.7874 -0.4064)
			(end 0.7874 0.4064)
			(stroke
				(width 0.1524)
				(type default)
			)
			(layer "F.SilkS")
		)
		(fp_line
			(start -0.7874 -0.4064)
			(end 0.7874 -0.4064)
			(stroke
				(width 0.1524)
				(type default)
			)
			(layer "F.SilkS")
		)
		(fp_line
			(start 0.7874 0.4064)
			(end -0.7874 0.4064)
			(stroke
				(width 0.1524)
				(type default)
			)
			(layer "F.SilkS")
		)
		(fp_line
			(start -0.7874 0.4064)
			(end -0.7874 -0.4064)
			(stroke
				(width 0.1524)
				(type default)
			)
			(layer "F.SilkS")
		)
		(fp_line
			(start -0.12065 -0.305054)
			(end -0.12065 -0.2794)
			(stroke
				(width 0.1)
				(type default)
			)
			(layer "F.Fab")
		)
		(fp_line
			(start -0.67945 -0.305054)
			(end -0.12065 -0.305054)
			(stroke
				(width 0.1)
				(type default)
			)
			(layer "F.Fab")
		)
		(fp_line
			(start 0.67945 -0.3048)
			(end 0.67945 0.3048)
			(stroke
				(width 0.1)
				(type default)
			)
			(layer "F.Fab")
		)
		(fp_line
			(start 0.12065 -0.3048)
			(end 0.67945 -0.3048)
			(stroke
				(width 0.1)
				(type default)
			)
			(layer "F.Fab")
		)
		(fp_line
			(start 0.12065 -0.2794)
			(end 0.12065 -0.3048)
			(stroke
				(width 0.1)
				(type default)
			)
			(layer "F.Fab")
		)
		(fp_line
			(start -0.12065 -0.2794)
			(end 0.12065 -0.2794)
			(stroke
				(width 0.1)
				(type default)
			)
			(layer "F.Fab")
		)
		(fp_line
			(start 0.120396 0.2794)
			(end -0.12065 0.2794)
			(stroke
				(width 0.1)
				(type default)
			)
			(layer "F.Fab")
		)
		(fp_line
			(start -0.12065 0.2794)
			(end -0.12065 0.3048)
			(stroke
				(width 0.1)
				(type default)
			)
			(layer "F.Fab")
		)
		(fp_line
			(start 0.67945 0.3048)
			(end 0.120396 0.3048)
			(stroke
				(width 0.1)
				(type default)
			)
			(layer "F.Fab")
		)
		(fp_line
			(start 0.120396 0.3048)
			(end 0.120396 0.2794)
			(stroke
				(width 0.1)
				(type default)
			)
			(layer "F.Fab")
		)
		(fp_line
			(start -0.12065 0.3048)
			(end -0.67945 0.3048)
			(stroke
				(width 0.1)
				(type default)
			)
			(layer "F.Fab")
		)
		(fp_line
			(start -0.67945 0.3048)
			(end -0.67945 -0.305054)
			(stroke
				(width 0.1)
				(type default)
			)
			(layer "F.Fab")
		)
		(pad "1" smd circle
			(at -0.40005 0 90)
			(size 0 0)
			(layers "F.Cu" "F.Mask" "F.Paste")
			(net "P3V3_AUX")
		)
		(pad "2" smd circle
			(at 0.40005 0 90)
			(size 0 0)
			(layers "F.Cu" "F.Mask" "F.Paste")
			(net "USB_HUB_2_OVCUR3")
		)
	)
	(footprint ""
		(layer "F.Cu")
		(at 170.23588 -433.923948)
		(property "Reference" "R3457"
			(at 0 0 0)
			(layer "F.SilkS")
			(hide yes)
			(effects
				(font
					(size 1.27 1.27)
				)
			)
		)
		(property "Value" ""
			(at 0 0 0)
			(layer "F.Fab")
			(effects
				(font
					(size 1.27 1.27)
				)
			)
		)
		(duplicate_pad_numbers_are_jumpers no)
		(fp_line
			(start -0.7874 -0.4064)
			(end 0.7874 -0.4064)
			(stroke
				(width 0.1524)
				(type default)
			)
			(layer "F.SilkS")
		)
		(fp_line
			(start -0.7874 0.4064)
			(end -0.7874 -0.4064)
			(stroke
				(width 0.1524)
				(type default)
			)
			(layer "F.SilkS")
		)
		(fp_line
			(start 0.7874 -0.4064)
			(end 0.7874 0.4064)
			(stroke
				(width 0.1524)
				(type default)
			)
			(layer "F.SilkS")
		)
		(fp_line
			(start 0.7874 0.4064)
			(end -0.7874 0.4064)
			(stroke
				(width 0.1524)
				(type default)
			)
			(layer "F.SilkS")
		)
		(fp_line
			(start -0.67945 -0.305054)
			(end -0.12065 -0.305054)
			(stroke
				(width 0.1)
				(type default)
			)
			(layer "F.Fab")
		)
		(fp_line
			(start -0.67945 0.3048)
			(end -0.67945 -0.305054)
			(stroke
				(width 0.1)
				(type default)
			)
			(layer "F.Fab")
		)
		(fp_line
			(start -0.12065 -0.305054)
			(end -0.12065 -0.2794)
			(stroke
				(width 0.1)
				(type default)
			)
			(layer "F.Fab")
		)
		(fp_line
			(start -0.12065 -0.2794)
			(end 0.12065 -0.2794)
			(stroke
				(width 0.1)
				(type default)
			)
			(layer "F.Fab")
		)
		(fp_line
			(start -0.12065 0.2794)
			(end -0.12065 0.3048)
			(stroke
				(width 0.1)
				(type default)
			)
			(layer "F.Fab")
		)
		(fp_line
			(start -0.12065 0.3048)
			(end -0.67945 0.3048)
			(stroke
				(width 0.1)
				(type default)
			)
			(layer "F.Fab")
		)
		(fp_line
			(start 0.120396 0.2794)
			(end -0.12065 0.2794)
			(stroke
				(width 0.1)
				(type default)
			)
			(layer "F.Fab")
		)
		(fp_line
			(start 0.120396 0.3048)
			(end 0.120396 0.2794)
			(stroke
				(width 0.1)
				(type default)
			)
			(layer "F.Fab")
		)
		(fp_line
			(start 0.12065 -0.3048)
			(end 0.67945 -0.3048)
			(stroke
				(width 0.1)
				(type default)
			)
			(layer "F.Fab")
		)
		(fp_line
			(start 0.12065 -0.2794)
			(end 0.12065 -0.3048)
			(stroke
				(width 0.1)
				(type default)
			)
			(layer "F.Fab")
		)
		(fp_line
			(start 0.67945 -0.3048)
			(end 0.67945 0.3048)
			(stroke
				(width 0.1)
				(type default)
			)
			(layer "F.Fab")
		)
		(fp_line
			(start 0.67945 0.3048)
			(end 0.120396 0.3048)
			(stroke
				(width 0.1)
				(type default)
			)
			(layer "F.Fab")
		)
		(pad "1" smd circle
			(at -0.40005 0)
			(size 0 0)
			(layers "F.Cu" "F.Mask" "F.Paste")
			(net "GPU_BASE_STBY_EN_BUF_R")
		)
		(pad "2" smd circle
			(at 0.40005 0)
			(size 0 0)
			(layers "F.Cu" "F.Mask" "F.Paste")
			(net "GND")
		)
	)
	(footprint ""
		(layer "F.Cu")
		(at 83.30057 -55.432706 -90)
		(property "Reference" "PU200"
			(at 0.436626 7.02818 0)
			(unlocked yes)
			(layer "F.SilkS")
			(effects
				(font
					(size 0.7874 0.5842)
					(thickness 0.1524)
				)
				(justify left)
			)
		)
		(property "Value" ""
			(at 0 0 270)
			(layer "F.Fab")
			(effects
				(font
					(size 1.27 1.27)
				)
			)
		)
		(duplicate_pad_numbers_are_jumpers no)
		(fp_line
			(start -1.774952 1.039876)
			(end 1.774952 1.039876)
			(stroke
				(width 0.1524)
				(type default)
			)
			(layer "F.SilkS")
		)
		(fp_line
			(start 1.774952 1.039876)
			(end 1.774952 -1.039876)
			(stroke
				(width 0.1524)
				(type default)
			)
			(layer "F.SilkS")
		)
		(fp_line
			(start -1.774952 -1.039876)
			(end -1.774952 1.039876)
			(stroke
				(width 0.1524)
				(type default)
			)
			(layer "F.SilkS")
		)
		(fp_line
			(start 1.774952 -1.039876)
			(end -1.774952 -1.039876)
			(stroke
				(width 0.1524)
				(type default)
			)
			(layer "F.SilkS")
		)
		(fp_poly
			(pts
				(xy -1.769872 -1.039876) (xy -1.769872 -0.249936) (xy -2.531872 -0.249936) (xy -2.531872 -1.801876)
				(xy -0.999998 -1.801876) (xy -0.999998 -1.039876)
			)
			(stroke
				(width 0)
				(type default)
			)
			(fill yes)
			(layer "F.SilkS")
		)
		(fp_line
			(start -1.769872 1.039876)
			(end 1.769872 1.039876)
			(stroke
				(width 0.1)
				(type default)
			)
			(layer "F.Fab")
		)
		(fp_line
			(start 1.769872 1.039876)
			(end 1.769872 -1.039876)
			(stroke
				(width 0.1)
				(type default)
			)
			(layer "F.Fab")
		)
		(fp_line
			(start -1.769872 -1.039876)
			(end -1.769872 1.039876)
			(stroke
				(width 0.1)
				(type default)
			)
			(layer "F.Fab")
		)
		(fp_line
			(start 1.769872 -1.039876)
			(end -1.769872 -1.039876)
			(stroke
				(width 0.1)
				(type default)
			)
			(layer "F.Fab")
		)
		(fp_poly
			(pts
				(xy -1.769872 -1.039876) (xy -0.999998 -1.039876) (xy -0.999998 -1.801876) (xy -2.531872 -1.801876)
				(xy -2.531872 -0.249936) (xy -1.769872 -0.249936)
			)
			(stroke
				(width 0)
				(type default)
			)
			(fill yes)
			(layer "F.Fab")
		)
		(pad "A1" smd circle
			(at -1.500124 -0.750062 270)
			(size 0.2286 0.2286)
			(layers "F.Cu" "F.Mask" "F.Paste")
			(net "P3V3_OCP_SENSE_2")
		)
		(pad "A2" smd circle
			(at -0.999998 -0.750062 270)
			(size 0.2286 0.2286)
			(layers "F.Cu" "F.Mask" "F.Paste")
			(net "P3V3_OCP_VCC_2")
		)
		(pad "A3" smd circle
			(at -0.499872 -0.750062 270)
			(size 0.2286 0.2286)
			(layers "F.Cu" "F.Mask" "F.Paste")
			(net "P3V3_AUX")
		)
		(pad "A4" smd circle
			(at 0 -0.750062 270)
			(size 0.2286 0.2286)
			(layers "F.Cu" "F.Mask" "F.Paste")
			(net "P3V3_OCP_V3_2_R")
		)
		(pad "A5" smd circle
			(at 0.499872 -0.750062 270)
			(size 0.2286 0.2286)
			(layers "F.Cu" "F.Mask" "F.Paste")
			(net "P3V3_AUX")
		)
		(pad "A6" smd circle
			(at 0.999998 -0.750062 270)
			(size 0.2286 0.2286)
			(layers "F.Cu" "F.Mask" "F.Paste")
			(net "P3V3_OCP_GATE_2")
		)
		(pad "A7" smd circle
			(at 1.500124 -0.750062 270)
			(size 0.2286 0.2286)
			(layers "F.Cu" "F.Mask" "F.Paste")
			(net "GND")
		)
		(pad "B1" smd circle
			(at -1.500124 -0.249936 270)
			(size 0.2286 0.2286)
			(layers "F.Cu" "F.Mask" "F.Paste")
			(net "P3V3_OCP_CB_2")
		)
		(pad "B2" smd circle
			(at -0.999998 -0.249936 270)
			(size 0.2286 0.2286)
			(layers "F.Cu" "F.Mask" "F.Paste")
			(net "GND")
		)
		(pad "B3" smd circle
			(at -0.499872 -0.249936 270)
			(size 0.2286 0.2286)
			(layers "F.Cu" "F.Mask" "F.Paste")
			(net "P3V3_AUX")
		)
		(pad "B4" smd circle
			(at 0 -0.249936 270)
			(size 0.2286 0.2286)
			(layers "F.Cu" "F.Mask" "F.Paste")
			(net "P3V3_OCP_V3_2_R")
		)
		(pad "B5" smd circle
			(at 0.499872 -0.249936 270)
			(size 0.2286 0.2286)
			(layers "F.Cu" "F.Mask" "F.Paste")
			(net "P3V3_AUX")
		)
		(pad "B6" smd circle
			(at 0.999998 -0.249936 270)
			(size 0.2286 0.2286)
			(layers "F.Cu" "F.Mask" "F.Paste")
			(net "P3V3_OCP_V3_2_R")
		)
		(pad "B7" smd circle
			(at 1.500124 -0.249936 270)
			(size 0.2286 0.2286)
			(layers "F.Cu" "F.Mask" "F.Paste")
			(net "GND")
		)
		(pad "C1" smd circle
			(at -1.500124 0.249936 270)
			(size 0.2286 0.2286)
			(layers "F.Cu" "F.Mask" "F.Paste")
			(net "GND")
		)
		(pad "C2" smd circle
			(at -0.999998 0.249936 270)
			(size 0.2286 0.2286)
			(layers "F.Cu" "F.Mask" "F.Paste")
			(net "GND")
		)
		(pad "C3" smd circle
			(at -0.499872 0.249936 270)
			(size 0.2286 0.2286)
			(layers "F.Cu" "F.Mask" "F.Paste")
			(net "P3V3_AUX")
		)
		(pad "C4" smd circle
			(at 0 0.249936 270)
			(size 0.2286 0.2286)
			(layers "F.Cu" "F.Mask" "F.Paste")
			(net "P3V3_OCP_V3_2_R")
		)
		(pad "C5" smd circle
			(at 0.499872 0.249936 270)
			(size 0.2286 0.2286)
			(layers "F.Cu" "F.Mask" "F.Paste")
			(net "P3V3_AUX")
		)
		(pad "C6" smd circle
			(at 0.999998 0.249936 270)
			(size 0.2286 0.2286)
			(layers "F.Cu" "F.Mask" "F.Paste")
			(net "P3V3_OCP_V3_2_R")
		)
		(pad "C7" smd circle
			(at 1.500124 0.249936 270)
			(size 0.2286 0.2286)
			(layers "F.Cu" "F.Mask" "F.Paste")
			(net "P3V3_OCP_FAULT_2")
		)
		(pad "D1" smd circle
			(at -1.500124 0.750062 270)
			(size 0.2286 0.2286)
			(layers "F.Cu" "F.Mask" "F.Paste")
			(net "P3V3_OCP_REG_2")
		)
		(pad "D2" smd circle
			(at -0.999998 0.750062 270)
			(size 0.2286 0.2286)
			(layers "F.Cu" "F.Mask" "F.Paste")
			(net "P3V3_OCP_UV_2")
		)
		(pad "D3" smd circle
			(at -0.499872 0.750062 270)
			(size 0.2286 0.2286)
			(layers "F.Cu" "F.Mask" "F.Paste")
			(net "P3V3_OCP_OV_2")
		)
		(pad "D4" smd circle
			(at 0 0.750062 270)
			(size 0.2286 0.2286)
			(layers "F.Cu" "F.Mask" "F.Paste")
			(net "P3V3_OCP_V3_2_R")
		)
		(pad "D5" smd circle
			(at 0.499872 0.750062 270)
			(size 0.2286 0.2286)
			(layers "F.Cu" "F.Mask" "F.Paste")
			(net "P3V3_AUX")
		)
		(pad "D6" smd circle
			(at 0.999998 0.750062 270)
			(size 0.2286 0.2286)
			(layers "F.Cu" "F.Mask" "F.Paste")
			(net "P3V3_OCP_V3_2_R")
		)
		(pad "D7" smd circle
			(at 1.500124 0.750062 270)
			(size 0.2286 0.2286)
			(layers "F.Cu" "F.Mask" "F.Paste")
			(net "P3V3_OCP_PWRGD_2")
		)
	)
	(footprint ""
		(layer "F.Cu")
		(at 134.04088 -92.674948 90)
		(property "Reference" "R204"
			(at 0 0 90)
			(layer "F.SilkS")
			(hide yes)
			(effects
				(font
					(size 1.27 1.27)
				)
			)
		)
		(property "Value" ""
			(at 0 0 90)
			(layer "F.Fab")
			(effects
				(font
					(size 1.27 1.27)
				)
			)
		)
		(duplicate_pad_numbers_are_jumpers no)
		(fp_line
			(start 0.7874 -0.4064)
			(end 0.7874 0.4064)
			(stroke
				(width 0.1524)
				(type default)
			)
			(layer "F.SilkS")
		)
		(fp_line
			(start -0.7874 -0.4064)
			(end 0.7874 -0.4064)
			(stroke
				(width 0.1524)
				(type default)
			)
			(layer "F.SilkS")
		)
		(fp_line
			(start 0.7874 0.4064)
			(end -0.7874 0.4064)
			(stroke
				(width 0.1524)
				(type default)
			)
			(layer "F.SilkS")
		)
		(fp_line
			(start -0.7874 0.4064)
			(end -0.7874 -0.4064)
			(stroke
				(width 0.1524)
				(type default)
			)
			(layer "F.SilkS")
		)
		(fp_line
			(start -0.12065 -0.305054)
			(end -0.12065 -0.2794)
			(stroke
				(width 0.1)
				(type default)
			)
			(layer "F.Fab")
		)
		(fp_line
			(start -0.67945 -0.305054)
			(end -0.12065 -0.305054)
			(stroke
				(width 0.1)
				(type default)
			)
			(layer "F.Fab")
		)
		(fp_line
			(start 0.67945 -0.3048)
			(end 0.67945 0.3048)
			(stroke
				(width 0.1)
				(type default)
			)
			(layer "F.Fab")
		)
		(fp_line
			(start 0.12065 -0.3048)
			(end 0.67945 -0.3048)
			(stroke
				(width 0.1)
				(type default)
			)
			(layer "F.Fab")
		)
		(fp_line
			(start 0.12065 -0.2794)
			(end 0.12065 -0.3048)
			(stroke
				(width 0.1)
				(type default)
			)
			(layer "F.Fab")
		)
		(fp_line
			(start -0.12065 -0.2794)
			(end 0.12065 -0.2794)
			(stroke
				(width 0.1)
				(type default)
			)
			(layer "F.Fab")
		)
		(fp_line
			(start 0.120396 0.2794)
			(end -0.12065 0.2794)
			(stroke
				(width 0.1)
				(type default)
			)
			(layer "F.Fab")
		)
		(fp_line
			(start -0.12065 0.2794)
			(end -0.12065 0.3048)
			(stroke
				(width 0.1)
				(type default)
			)
			(layer "F.Fab")
		)
		(fp_line
			(start 0.67945 0.3048)
			(end 0.120396 0.3048)
			(stroke
				(width 0.1)
				(type default)
			)
			(layer "F.Fab")
		)
		(fp_line
			(start 0.120396 0.3048)
			(end 0.120396 0.2794)
			(stroke
				(width 0.1)
				(type default)
			)
			(layer "F.Fab")
		)
		(fp_line
			(start -0.12065 0.3048)
			(end -0.67945 0.3048)
			(stroke
				(width 0.1)
				(type default)
			)
			(layer "F.Fab")
		)
		(fp_line
			(start -0.67945 0.3048)
			(end -0.67945 -0.305054)
			(stroke
				(width 0.1)
				(type default)
			)
			(layer "F.Fab")
		)
		(pad "1" smd circle
			(at -0.40005 0 90)
			(size 0 0)
			(layers "F.Cu" "F.Mask" "F.Paste")
			(net "H_CPU1_MEMHOT_OUT_LVC1_R_N")
		)
		(pad "2" smd circle
			(at 0.40005 0 90)
			(size 0 0)
			(layers "F.Cu" "F.Mask" "F.Paste")
			(net "H_CPU1_MEMHOT_OUT_VT_R_N")
		)
	)
	(footprint ""
		(layer "F.Cu")
		(at 16.645382 -105.56621 90)
		(property "Reference" "R2791"
			(at 0 0 90)
			(layer "F.SilkS")
			(hide yes)
			(effects
				(font
					(size 1.27 1.27)
				)
			)
		)
		(property "Value" ""
			(at 0 0 90)
			(layer "F.Fab")
			(effects
				(font
					(size 1.27 1.27)
				)
			)
		)
		(duplicate_pad_numbers_are_jumpers no)
		(fp_line
			(start -0.01651 -0.4064)
			(end 0.7874 -0.4064)
			(stroke
				(width 0.1524)
				(type default)
			)
			(layer "F.SilkS")
		)
		(fp_line
			(start 0.7874 0.4064)
			(end -0.02921 0.4064)
			(stroke
				(width 0.1524)
				(type default)
			)
			(layer "F.SilkS")
		)
		(fp_line
			(start -0.7874 0.4064)
			(end -0.7874 -0.4064)
			(stroke
				(width 0.1524)
				(type default)
			)
			(layer "F.SilkS")
		)
		(fp_line
			(start -0.12065 -0.305054)
			(end -0.12065 -0.2794)
			(stroke
				(width 0.1)
				(type default)
			)
			(layer "F.Fab")
		)
		(fp_line
			(start -0.67945 -0.305054)
			(end -0.12065 -0.305054)
			(stroke
				(width 0.1)
				(type default)
			)
			(layer "F.Fab")
		)
		(fp_line
			(start 0.67945 -0.3048)
			(end 0.67945 0.3048)
			(stroke
				(width 0.1)
				(type default)
			)
			(layer "F.Fab")
		)
		(fp_line
			(start 0.12065 -0.3048)
			(end 0.67945 -0.3048)
			(stroke
				(width 0.1)
				(type default)
			)
			(layer "F.Fab")
		)
		(fp_line
			(start 0.12065 -0.2794)
			(end 0.12065 -0.3048)
			(stroke
				(width 0.1)
				(type default)
			)
			(layer "F.Fab")
		)
		(fp_line
			(start -0.12065 -0.2794)
			(end 0.12065 -0.2794)
			(stroke
				(width 0.1)
				(type default)
			)
			(layer "F.Fab")
		)
		(fp_line
			(start 0.120396 0.2794)
			(end -0.12065 0.2794)
			(stroke
				(width 0.1)
				(type default)
			)
			(layer "F.Fab")
		)
		(fp_line
			(start -0.12065 0.2794)
			(end -0.12065 0.3048)
			(stroke
				(width 0.1)
				(type default)
			)
			(layer "F.Fab")
		)
		(fp_line
			(start 0.67945 0.3048)
			(end 0.120396 0.3048)
			(stroke
				(width 0.1)
				(type default)
			)
			(layer "F.Fab")
		)
		(fp_line
			(start 0.120396 0.3048)
			(end 0.120396 0.2794)
			(stroke
				(width 0.1)
				(type default)
			)
			(layer "F.Fab")
		)
		(fp_line
			(start -0.12065 0.3048)
			(end -0.67945 0.3048)
			(stroke
				(width 0.1)
				(type default)
			)
			(layer "F.Fab")
		)
		(fp_line
			(start -0.67945 0.3048)
			(end -0.67945 -0.305054)
			(stroke
				(width 0.1)
				(type default)
			)
			(layer "F.Fab")
		)
		(pad "1" smd rect
			(at -0.40005 0 270)
			(size 0.4572 0.508)
			(layers "F.Cu" "F.Mask" "F.Paste")
			(net "USB2_HOST_BMC_B_DN")
		)
		(pad "2" smd rect
			(at 0.40005 0 270)
			(size 0.4572 0.508)
			(layers "F.Cu" "F.Mask" "F.Paste")
			(net "USB2_HOST_BMC_B_BUF_DN")
		)
	)
	(footprint ""
		(layer "F.Cu")
		(at 118.804944 -77.748892 180)
		(property "Reference" "U97"
			(at 0.831088 2.72542 0)
			(unlocked yes)
			(layer "F.SilkS")
			(effects
				(font
					(size 0.7874 0.5842)
					(thickness 0.1524)
				)
				(justify left)
			)
		)
		(property "Value" ""
			(at 0 0 180)
			(layer "F.Fab")
			(effects
				(font
					(size 1.27 1.27)
				)
			)
		)
		(duplicate_pad_numbers_are_jumpers no)
		(fp_line
			(start 0.824992 1.050036)
			(end 0.254 1.050036)
			(stroke
				(width 0.1524)
				(type default)
			)
			(layer "F.SilkS")
		)
		(fp_line
			(start 0.824992 1.00584)
			(end 0.824992 1.050036)
			(stroke
				(width 0.1524)
				(type default)
			)
			(layer "F.SilkS")
		)
		(fp_line
			(start 0.824992 -1.050036)
			(end 0.824992 -1.00584)
			(stroke
				(width 0.1524)
				(type default)
			)
			(layer "F.SilkS")
		)
		(fp_line
			(start 0.254 -1.050036)
			(end 0.824992 -1.050036)
			(stroke
				(width 0.1524)
				(type default)
			)
			(layer "F.SilkS")
		)
		(fp_line
			(start -0.254 1.050036)
			(end -0.824992 1.050036)
			(stroke
				(width 0.1524)
				(type default)
			)
			(layer "F.SilkS")
		)
		(fp_line
			(start -0.824992 1.050036)
			(end -0.824992 1.00584)
			(stroke
				(width 0.1524)
				(type default)
			)
			(layer "F.SilkS")
		)
		(fp_line
			(start -0.824992 -1.01854)
			(end -0.824992 -1.050036)
			(stroke
				(width 0.1524)
				(type default)
			)
			(layer "F.SilkS")
		)
		(fp_line
			(start -0.824992 -1.050036)
			(end -0.254 -1.050036)
			(stroke
				(width 0.1524)
				(type default)
			)
			(layer "F.SilkS")
		)
		(fp_poly
			(pts
				(xy -2.027428 -0.399034) (xy -2.027428 -1.10109) (xy -1.325372 -0.750062)
			)
			(stroke
				(width 0)
				(type default)
			)
			(fill yes)
			(layer "F.SilkS")
		)
		(fp_line
			(start 0.824992 1.050036)
			(end -0.824992 1.050036)
			(stroke
				(width 0.1)
				(type default)
			)
			(layer "F.Fab")
		)
		(fp_line
			(start 0.824992 -1.050036)
			(end 0.824992 1.050036)
			(stroke
				(width 0.1)
				(type default)
			)
			(layer "F.Fab")
		)
		(fp_line
			(start -0.824992 1.050036)
			(end -0.824992 -1.050036)
			(stroke
				(width 0.1)
				(type default)
			)
			(layer "F.Fab")
		)
		(fp_line
			(start -0.824992 -1.050036)
			(end 0.824992 -1.050036)
			(stroke
				(width 0.1)
				(type default)
			)
			(layer "F.Fab")
		)
		(fp_poly
			(pts
				(xy -1.325372 -0.750062) (xy -2.027428 -0.399034) (xy -2.027428 -1.10109)
			)
			(stroke
				(width 0)
				(type default)
			)
			(fill yes)
			(layer "F.Fab")
		)
		(pad "1" smd rect
			(at -0.741172 -0.750062 270)
			(size 0.2794 0.8128)
			(layers "F.Cu" "F.Mask" "F.Paste")
			(net "JTAG_BMC_PLD_TMS")
		)
		(pad "2" smd rect
			(at -0.741172 -0.249936 270)
			(size 0.254 0.8128)
			(layers "F.Cu" "F.Mask" "F.Paste")
			(net "JTAG_BMC_DBP_TMS")
		)
		(pad "3" smd rect
			(at -0.741172 0.249936 270)
			(size 0.254 0.8128)
			(layers "F.Cu" "F.Mask" "F.Paste")
			(net "JTAG_BMC_PLD_TCK")
		)
		(pad "4" smd rect
			(at -0.741172 0.750062 270)
			(size 0.254 0.8128)
			(layers "F.Cu" "F.Mask" "F.Paste")
			(net "JTAG_BMC_DBP_TCK")
		)
		(pad "5" smd rect
			(at 0 0.94996 180)
			(size 0.254 0.8128)
			(layers "F.Cu" "F.Mask" "F.Paste")
			(net "GND")
		)
		(pad "6" smd rect
			(at 0.741172 0.750062 270)
			(size 0.254 0.8128)
			(layers "F.Cu" "F.Mask" "F.Paste")
			(net "JTAG_BMC_SW_TCK")
		)
		(pad "7" smd rect
			(at 0.741172 0.249936 270)
			(size 0.254 0.8128)
			(layers "F.Cu" "F.Mask" "F.Paste")
			(net "FM_JTAG_BMC_MUX_SEL")
		)
		(pad "8" smd rect
			(at 0.741172 -0.249936 270)
			(size 0.254 0.8128)
			(layers "F.Cu" "F.Mask" "F.Paste")
			(net "FM_JTAG_BMC_MUX_SEL")
		)
		(pad "9" smd rect
			(at 0.741172 -0.750062 270)
			(size 0.254 0.8128)
			(layers "F.Cu" "F.Mask" "F.Paste")
			(net "JTAG_BMC_SW_TMS")
		)
		(pad "10" smd rect
			(at 0 -0.94996 180)
			(size 0.254 0.8128)
			(layers "F.Cu" "F.Mask" "F.Paste")
			(net "P3V3_AUX")
		)
		(zone
			(layer "F.Cu")
			(hatch none 0.5)
			(connect_pads
				(clearance 0)
			)
			(min_thickness 0.25)
			(keepout
				(tracks not_allowed)
				(vias allowed)
				(pads allowed)
				(copperpour not_allowed)
				(footprints allowed)
			)
			(placement
				(enabled no)
				(sheetname "")
			)
			(fill
				(thermal_gap 0.5)
				(thermal_bridge_width 0.5)
				(island_removal_mode 0)
			)
			(polygon
				(pts
					(xy 119.630444 -76.809092) (xy 119.630444 -76.694792) (xy 119.084344 -76.694792) (xy 119.084344 -76.809092)
				)
			)
		)
	)
	(footprint ""
		(layer "F.Cu")
		(at 113.20653 -15.879064)
		(property "Reference" "U273"
			(at -2.57937 -5.227574 0)
			(unlocked yes)
			(layer "F.SilkS")
			(effects
				(font
					(size 0.7874 0.5842)
					(thickness 0.1524)
				)
				(justify left)
			)
		)
		(property "Value" ""
			(at 0 0 0)
			(layer "F.Fab")
			(effects
				(font
					(size 1.27 1.27)
				)
			)
		)
		(duplicate_pad_numbers_are_jumpers no)
		(fp_line
			(start -3.447796 -2.500122)
			(end -3.447796 2.500122)
			(stroke
				(width 0.1524)
				(type default)
			)
			(layer "F.SilkS")
		)
		(fp_line
			(start -3.447796 2.500122)
			(end 3.447796 2.500122)
			(stroke
				(width 0.1524)
				(type default)
			)
			(layer "F.SilkS")
		)
		(fp_line
			(start -1.484122 -2.500122)
			(end -3.447796 -2.500122)
			(stroke
				(width 0.1524)
				(type default)
			)
			(layer "F.SilkS")
		)
		(fp_line
			(start 0 -1.016)
			(end -1.484122 -2.500122)
			(stroke
				(width 0.1524)
				(type default)
			)
			(layer "F.SilkS")
		)
		(fp_line
			(start 1.484122 -2.500122)
			(end 0 -1.016)
			(stroke
				(width 0.1524)
				(type default)
			)
			(layer "F.SilkS")
		)
		(fp_line
			(start 3.447796 -2.500122)
			(end 1.484122 -2.500122)
			(stroke
				(width 0.1524)
				(type default)
			)
			(layer "F.SilkS")
		)
		(fp_line
			(start 3.447796 2.500122)
			(end 3.447796 -2.500122)
			(stroke
				(width 0.1524)
				(type default)
			)
			(layer "F.SilkS")
		)
		(fp_poly
			(pts
				(xy -2.309114 -3.855974) (xy -2.817114 -2.839974) (xy -3.325114 -3.855974)
			)
			(stroke
				(width 0)
				(type default)
			)
			(fill yes)
			(layer "F.SilkS")
		)
		(fp_line
			(start -1.999996 -2.500122)
			(end -1.999996 2.500122)
			(stroke
				(width 0.1)
				(type default)
			)
			(layer "F.Fab")
		)
		(fp_line
			(start -1.999996 2.500122)
			(end 1.999996 2.500122)
			(stroke
				(width 0.1)
				(type default)
			)
			(layer "F.Fab")
		)
		(fp_line
			(start 1.999996 -2.500122)
			(end -1.999996 -2.500122)
			(stroke
				(width 0.1)
				(type default)
			)
			(layer "F.Fab")
		)
		(fp_line
			(start 1.999996 2.500122)
			(end 1.999996 -2.500122)
			(stroke
				(width 0.1)
				(type default)
			)
			(layer "F.Fab")
		)
		(fp_poly
			(pts
				(xy -4.5974 -2.413) (xy -4.5974 -1.397) (xy -3.5814 -1.905)
			)
			(stroke
				(width 0)
				(type default)
			)
			(fill yes)
			(layer "F.Fab")
		)
		(pad "1" smd rect
			(at -2.649982 -1.905 270)
			(size 0.6096 1.3208)
			(layers "F.Cu" "F.Mask" "F.Paste")
			(net "SMB_LM75_3_3V3AUX_SDA_R1")
		)
		(pad "2" smd rect
			(at -2.649982 -0.635 270)
			(size 0.6096 1.3208)
			(layers "F.Cu" "F.Mask" "F.Paste")
			(net "SMB_LM75_3_3V3AUX_SCL_R1")
		)
		(pad "3" smd rect
			(at -2.649982 0.635 270)
			(size 0.6096 1.3208)
			(layers "F.Cu" "F.Mask" "F.Paste")
			(net "FM_LM75_3_ALERT_N")
		)
		(pad "4" smd rect
			(at -2.649982 1.905 270)
			(size 0.6096 1.3208)
			(layers "F.Cu" "F.Mask" "F.Paste")
			(net "GND")
		)
		(pad "5" smd rect
			(at 2.649982 1.905 270)
			(size 0.6096 1.3208)
			(layers "F.Cu" "F.Mask" "F.Paste")
			(net "U273_3_ADD2")
		)
		(pad "6" smd rect
			(at 2.649982 0.635 270)
			(size 0.6096 1.3208)
			(layers "F.Cu" "F.Mask" "F.Paste")
			(net "U273_3_ADD1")
		)
		(pad "7" smd rect
			(at 2.649982 -0.635 270)
			(size 0.6096 1.3208)
			(layers "F.Cu" "F.Mask" "F.Paste")
			(net "U273_3_ADD0")
		)
		(pad "8" smd rect
			(at 2.649982 -1.905 270)
			(size 0.6096 1.3208)
			(layers "F.Cu" "F.Mask" "F.Paste")
			(net "P3V3_AUX")
		)
	)
	(footprint ""
		(layer "F.Cu")
		(at 31.29788 -429.859948)
		(property "Reference" "R2932"
			(at 0 0 0)
			(layer "F.SilkS")
			(hide yes)
			(effects
				(font
					(size 1.27 1.27)
				)
			)
		)
		(property "Value" ""
			(at 0 0 0)
			(layer "F.Fab")
			(effects
				(font
					(size 1.27 1.27)
				)
			)
		)
		(duplicate_pad_numbers_are_jumpers no)
		(fp_line
			(start -0.7874 -0.4064)
			(end 0.7874 -0.4064)
			(stroke
				(width 0.1524)
				(type default)
			)
			(layer "F.SilkS")
		)
		(fp_line
			(start -0.7874 0.4064)
			(end -0.7874 -0.4064)
			(stroke
				(width 0.1524)
				(type default)
			)
			(layer "F.SilkS")
		)
		(fp_line
			(start 0.7874 -0.4064)
			(end 0.7874 0.4064)
			(stroke
				(width 0.1524)
				(type default)
			)
			(layer "F.SilkS")
		)
		(fp_line
			(start 0.7874 0.4064)
			(end -0.7874 0.4064)
			(stroke
				(width 0.1524)
				(type default)
			)
			(layer "F.SilkS")
		)
		(fp_line
			(start -0.67945 -0.305054)
			(end -0.12065 -0.305054)
			(stroke
				(width 0.1)
				(type default)
			)
			(layer "F.Fab")
		)
		(fp_line
			(start -0.67945 0.3048)
			(end -0.67945 -0.305054)
			(stroke
				(width 0.1)
				(type default)
			)
			(layer "F.Fab")
		)
		(fp_line
			(start -0.12065 -0.305054)
			(end -0.12065 -0.2794)
			(stroke
				(width 0.1)
				(type default)
			)
			(layer "F.Fab")
		)
		(fp_line
			(start -0.12065 -0.2794)
			(end 0.12065 -0.2794)
			(stroke
				(width 0.1)
				(type default)
			)
			(layer "F.Fab")
		)
		(fp_line
			(start -0.12065 0.2794)
			(end -0.12065 0.3048)
			(stroke
				(width 0.1)
				(type default)
			)
			(layer "F.Fab")
		)
		(fp_line
			(start -0.12065 0.3048)
			(end -0.67945 0.3048)
			(stroke
				(width 0.1)
				(type default)
			)
			(layer "F.Fab")
		)
		(fp_line
			(start 0.120396 0.2794)
			(end -0.12065 0.2794)
			(stroke
				(width 0.1)
				(type default)
			)
			(layer "F.Fab")
		)
		(fp_line
			(start 0.120396 0.3048)
			(end 0.120396 0.2794)
			(stroke
				(width 0.1)
				(type default)
			)
			(layer "F.Fab")
		)
		(fp_line
			(start 0.12065 -0.3048)
			(end 0.67945 -0.3048)
			(stroke
				(width 0.1)
				(type default)
			)
			(layer "F.Fab")
		)
		(fp_line
			(start 0.12065 -0.2794)
			(end 0.12065 -0.3048)
			(stroke
				(width 0.1)
				(type default)
			)
			(layer "F.Fab")
		)
		(fp_line
			(start 0.67945 -0.3048)
			(end 0.67945 0.3048)
			(stroke
				(width 0.1)
				(type default)
			)
			(layer "F.Fab")
		)
		(fp_line
			(start 0.67945 0.3048)
			(end 0.120396 0.3048)
			(stroke
				(width 0.1)
				(type default)
			)
			(layer "F.Fab")
		)
		(pad "1" smd circle
			(at -0.40005 0)
			(size 0 0)
			(layers "F.Cu" "F.Mask" "F.Paste")
			(net "FM_SWB_PWR_EN_R1_BUF")
		)
		(pad "2" smd circle
			(at 0.40005 0)
			(size 0 0)
			(layers "F.Cu" "F.Mask" "F.Paste")
			(net "GND")
		)
	)
	(footprint ""
		(layer "F.Cu")
		(at 54.89956 -147.84197 90)
		(property "Reference" "PU51_P1_2"
			(at -5.795772 -4.134358 0)
			(unlocked yes)
			(layer "F.SilkS")
			(effects
				(font
					(size 0.7874 0.5842)
					(thickness 0.1524)
				)
				(justify left)
			)
		)
		(property "Value" ""
			(at 0 0 90)
			(layer "F.Fab")
			(effects
				(font
					(size 1.27 1.27)
				)
			)
		)
		(duplicate_pad_numbers_are_jumpers no)
		(fp_line
			(start 2.500122 -2.999994)
			(end 2.500122 -2.44348)
			(stroke
				(width 0.1524)
				(type default)
			)
			(layer "F.SilkS")
		)
		(fp_line
			(start 2.31394 -2.999994)
			(end 2.500122 -2.999994)
			(stroke
				(width 0.1524)
				(type default)
			)
			(layer "F.SilkS")
		)
		(fp_line
			(start -2.500122 -2.999994)
			(end -2.24409 -2.999994)
			(stroke
				(width 0.1524)
				(type default)
			)
			(layer "F.SilkS")
		)
		(fp_line
			(start -2.500122 -2.529078)
			(end -2.500122 -2.999994)
			(stroke
				(width 0.1524)
				(type default)
			)
			(layer "F.SilkS")
		)
		(fp_line
			(start -2.500122 0.6604)
			(end -2.500122 0.229108)
			(stroke
				(width 0.1524)
				(type default)
			)
			(layer "F.SilkS")
		)
		(fp_line
			(start 2.500122 2.339594)
			(end 2.500122 2.999994)
			(stroke
				(width 0.1524)
				(type default)
			)
			(layer "F.SilkS")
		)
		(fp_line
			(start 2.500122 2.999994)
			(end 2.2987 2.999994)
			(stroke
				(width 0.1524)
				(type default)
			)
			(layer "F.SilkS")
		)
		(fp_line
			(start -2.2987 2.999994)
			(end -2.500122 2.999994)
			(stroke
				(width 0.1524)
				(type default)
			)
			(layer "F.SilkS")
		)
		(fp_line
			(start -2.500122 2.999994)
			(end -2.500122 2.339594)
			(stroke
				(width 0.1524)
				(type default)
			)
			(layer "F.SilkS")
		)
		(fp_poly
			(pts
				(xy -5.099812 -2.818638) (xy -4.083812 -2.310638) (xy -5.099812 -1.802638)
			)
			(stroke
				(width 0)
				(type default)
			)
			(fill yes)
			(layer "F.SilkS")
		)
		(fp_line
			(start 2.500122 -2.999994)
			(end 2.500122 2.999994)
			(stroke
				(width 0.1)
				(type default)
			)
			(layer "F.Fab")
		)
		(fp_line
			(start -2.500122 -2.999994)
			(end 2.500122 -2.999994)
			(stroke
				(width 0.1)
				(type default)
			)
			(layer "F.Fab")
		)
		(fp_line
			(start 2.500122 2.999994)
			(end -2.500122 2.999994)
			(stroke
				(width 0.1)
				(type default)
			)
			(layer "F.Fab")
		)
		(fp_line
			(start -2.500122 2.999994)
			(end -2.500122 -2.999994)
			(stroke
				(width 0.1)
				(type default)
			)
			(layer "F.Fab")
		)
		(fp_poly
			(pts
				(xy -4.218432 -2.783078) (xy -4.218432 -1.767078) (xy -3.202432 -2.275078)
			)
			(stroke
				(width 0)
				(type default)
			)
			(fill yes)
			(layer "F.Fab")
		)
		(pad "1" smd rect
			(at -2.400046 -2.275078 180)
			(size 0.2286 0.6096)
			(layers "F.Cu" "F.Mask" "F.Paste")
			(net "PVCCINFAON_CPU1_VOS2")
		)
		(pad "2" smd rect
			(at -2.400046 -1.82499 180)
			(size 0.2286 0.6096)
			(layers "F.Cu" "F.Mask" "F.Paste")
			(net "GND")
		)
		(pad "3" smd rect
			(at -2.400046 -1.374902 180)
			(size 0.2286 0.6096)
			(layers "F.Cu" "F.Mask" "F.Paste")
			(net "PVCCINFAON_CPU1_VDD2")
		)
		(pad "4" smd rect
			(at -2.400046 -0.925068 180)
			(size 0.2286 0.6096)
			(layers "F.Cu" "F.Mask" "F.Paste")
			(net "PVCCFA_EHV_CPU1_PVCC")
		)
		(pad "5" smd rect
			(at -2.400046 -0.47498 180)
			(size 0.2286 0.6096)
			(layers "F.Cu" "F.Mask" "F.Paste")
			(net "GND")
		)
		(pad "6" smd rect
			(at -2.400046 -0.024892 180)
			(size 0.2286 0.6096)
			(layers "F.Cu" "F.Mask" "F.Paste")
			(net "Net_1932")
		)
		(pad "7_9-20_24" smd circle
			(at 0 1.150112 180)
			(size 0 0)
			(layers "F.Cu" "F.Mask" "F.Paste")
			(net "GND")
		)
		(pad "10_19" smd rect
			(at 0 2.899918 180)
			(size 0.6096 4.318)
			(layers "F.Cu" "F.Mask" "F.Paste")
			(net "SW_PVCCINFAON_CPU1_SW2")
		)
		(pad "25_29" smd rect
			(at 1.549908 -1.279906)
			(size 2.0574 2.3114)
			(layers "F.Cu" "F.Mask" "F.Paste")
			(net "SW_P12V_PVCCINFAON_CPU1_FLT")
		)
		(pad "30" smd rect
			(at 2.05994 -2.899918 90)
			(size 0.2286 0.6096)
			(layers "F.Cu" "F.Mask" "F.Paste")
			(net "SW_P12V_PVCCINFAON_CPU1_FLT")
		)
		(pad "31" smd rect
			(at 1.610106 -2.899918 90)
			(size 0.2286 0.6096)
			(layers "F.Cu" "F.Mask" "F.Paste")
			(net "Net_1931")
		)
		(pad "32" smd rect
			(at 1.160018 -2.899918 90)
			(size 0.2286 0.6096)
			(layers "F.Cu" "F.Mask" "F.Paste")
			(net "SW_PVCCINFAON_CPU1_BOOTR2")
		)
		(pad "33" smd rect
			(at 0.70993 -2.899918 90)
			(size 0.2286 0.6096)
			(layers "F.Cu" "F.Mask" "F.Paste")
			(net "SW_PVCCINFAON_CPU1_BOOT2")
		)
		(pad "34" smd rect
			(at 0.260096 -2.899918 90)
			(size 0.2286 0.6096)
			(layers "F.Cu" "F.Mask" "F.Paste")
			(net "PVCCINFAON_CPU1_APWM2")
		)
		(pad "35" smd rect
			(at -0.189992 -2.899918 90)
			(size 0.2286 0.6096)
			(layers "F.Cu" "F.Mask" "F.Paste")
			(net "PVCCINFAON_CPU1_VDD2")
		)
		(pad "36" smd rect
			(at -0.64008 -2.899918 90)
			(size 0.2286 0.6096)
			(layers "F.Cu" "F.Mask" "F.Paste")
			(net "PVCCINFAON_CPU1_ATSEN")
		)
		(pad "37" smd rect
			(at -1.089914 -2.899918 90)
			(size 0.2286 0.6096)
			(layers "F.Cu" "F.Mask" "F.Paste")
			(net "PVCCINFAON_CPU1_LSET2")
		)
		(pad "38" smd rect
			(at -1.540002 -2.899918 90)
			(size 0.2286 0.6096)
			(layers "F.Cu" "F.Mask" "F.Paste")
			(net "PVCCINFAON_CPU1_ACSP2")
		)
		(pad "39" smd rect
			(at -1.99009 -2.899918 90)
			(size 0.2286 0.6096)
			(layers "F.Cu" "F.Mask" "F.Paste")
			(net "PVCCINFAON_CPU1_VREF")
		)
		(pad "40" smd rect
			(at -0.87503 -1.27508 90)
			(size 1.7526 1.9558)
			(layers "F.Cu" "F.Mask" "F.Paste")
			(net "GND")
		)
		(pad "41" smd rect
			(at -1.525016 0.249936)
			(size 0.3048 0.4572)
			(layers "F.Cu" "F.Mask" "F.Paste")
			(net "Net_1933")
		)
		(zone
			(layer "F.Cu")
			(hatch none 0.5)
			(connect_pads
				(clearance 0)
			)
			(min_thickness 0.25)
			(keepout
				(tracks not_allowed)
				(vias allowed)
				(pads allowed)
				(copperpour not_allowed)
				(footprints allowed)
			)
			(placement
				(enabled no)
				(sheetname "")
			)
			(fill
				(thermal_gap 0.5)
				(thermal_bridge_width 0.5)
				(island_removal_mode 0)
			)
			(polygon
				(pts
					(xy 53.19268 -146.03984) (xy 54.3052 -146.03984) (xy 54.3052 -145.797524) (xy 53.19268 -145.797524)
				)
			)
		)
		(zone
			(layer "F.Cu")
			(hatch none 0.5)
			(connect_pads
				(clearance 0)
			)
			(min_thickness 0.25)
			(keepout
				(tracks not_allowed)
				(vias allowed)
				(pads allowed)
				(copperpour not_allowed)
				(footprints allowed)
			)
			(placement
				(enabled no)
				(sheetname "")
			)
			(fill
				(thermal_gap 0.5)
				(thermal_bridge_width 0.5)
				(island_removal_mode 0)
			)
			(polygon
				(pts
					(xy 57.899554 -145.341848) (xy 57.3786 -145.341848) (xy 57.150254 -145.570194) (xy 57.150254 -150.139146)
					(xy 57.3532 -150.342092) (xy 57.899554 -150.342092) (xy 57.899554 -150.05177) (xy 57.443878 -150.05177)
					(xy 57.443878 -145.63217) (xy 57.899554 -145.63217)
				)
			)
		)
	)
	(footprint ""
		(layer "F.Cu")
		(at 63.575438 -31.887922 90)
		(property "Reference" "PR3849"
			(at 0 0 90)
			(layer "F.SilkS")
			(hide yes)
			(effects
				(font
					(size 1.27 1.27)
				)
			)
		)
		(property "Value" ""
			(at 0 0 90)
			(layer "F.Fab")
			(effects
				(font
					(size 1.27 1.27)
				)
			)
		)
		(duplicate_pad_numbers_are_jumpers no)
		(fp_line
			(start 0.7874 -0.4064)
			(end 0.7874 0.4064)
			(stroke
				(width 0.1524)
				(type default)
			)
			(layer "F.SilkS")
		)
		(fp_line
			(start -0.7874 -0.4064)
			(end 0.7874 -0.4064)
			(stroke
				(width 0.1524)
				(type default)
			)
			(layer "F.SilkS")
		)
		(fp_line
			(start 0.7874 0.4064)
			(end -0.7874 0.4064)
			(stroke
				(width 0.1524)
				(type default)
			)
			(layer "F.SilkS")
		)
		(fp_line
			(start -0.7874 0.4064)
			(end -0.7874 -0.4064)
			(stroke
				(width 0.1524)
				(type default)
			)
			(layer "F.SilkS")
		)
		(fp_line
			(start -0.12065 -0.305054)
			(end -0.12065 -0.2794)
			(stroke
				(width 0.1)
				(type default)
			)
			(layer "F.Fab")
		)
		(fp_line
			(start -0.67945 -0.305054)
			(end -0.12065 -0.305054)
			(stroke
				(width 0.1)
				(type default)
			)
			(layer "F.Fab")
		)
		(fp_line
			(start 0.67945 -0.3048)
			(end 0.67945 0.3048)
			(stroke
				(width 0.1)
				(type default)
			)
			(layer "F.Fab")
		)
		(fp_line
			(start 0.12065 -0.3048)
			(end 0.67945 -0.3048)
			(stroke
				(width 0.1)
				(type default)
			)
			(layer "F.Fab")
		)
		(fp_line
			(start 0.12065 -0.2794)
			(end 0.12065 -0.3048)
			(stroke
				(width 0.1)
				(type default)
			)
			(layer "F.Fab")
		)
		(fp_line
			(start -0.12065 -0.2794)
			(end 0.12065 -0.2794)
			(stroke
				(width 0.1)
				(type default)
			)
			(layer "F.Fab")
		)
		(fp_line
			(start 0.120396 0.2794)
			(end -0.12065 0.2794)
			(stroke
				(width 0.1)
				(type default)
			)
			(layer "F.Fab")
		)
		(fp_line
			(start -0.12065 0.2794)
			(end -0.12065 0.3048)
			(stroke
				(width 0.1)
				(type default)
			)
			(layer "F.Fab")
		)
		(fp_line
			(start 0.67945 0.3048)
			(end 0.120396 0.3048)
			(stroke
				(width 0.1)
				(type default)
			)
			(layer "F.Fab")
		)
		(fp_line
			(start 0.120396 0.3048)
			(end 0.120396 0.2794)
			(stroke
				(width 0.1)
				(type default)
			)
			(layer "F.Fab")
		)
		(fp_line
			(start -0.12065 0.3048)
			(end -0.67945 0.3048)
			(stroke
				(width 0.1)
				(type default)
			)
			(layer "F.Fab")
		)
		(fp_line
			(start -0.67945 0.3048)
			(end -0.67945 -0.305054)
			(stroke
				(width 0.1)
				(type default)
			)
			(layer "F.Fab")
		)
		(pad "1" smd circle
			(at -0.40005 0 90)
			(size 0 0)
			(layers "F.Cu" "F.Mask" "F.Paste")
			(net "P12V_OCP_IMON_2")
		)
		(pad "2" smd circle
			(at 0.40005 0 90)
			(size 0 0)
			(layers "F.Cu" "F.Mask" "F.Paste")
			(net "GND")
		)
	)
	(footprint ""
		(layer "F.Cu")
		(at 430.600104 -138.558778 180)
		(property "Reference" "R2389"
			(at 0 0 180)
			(layer "F.SilkS")
			(hide yes)
			(effects
				(font
					(size 1.27 1.27)
				)
			)
		)
		(property "Value" ""
			(at 0 0 180)
			(layer "F.Fab")
			(effects
				(font
					(size 1.27 1.27)
				)
			)
		)
		(duplicate_pad_numbers_are_jumpers no)
		(fp_line
			(start 0.7874 0.4064)
			(end -0.7874 0.4064)
			(stroke
				(width 0.1524)
				(type default)
			)
			(layer "F.SilkS")
		)
		(fp_line
			(start 0.7874 -0.4064)
			(end 0.7874 0.4064)
			(stroke
				(width 0.1524)
				(type default)
			)
			(layer "F.SilkS")
		)
		(fp_line
			(start -0.7874 0.4064)
			(end -0.7874 -0.4064)
			(stroke
				(width 0.1524)
				(type default)
			)
			(layer "F.SilkS")
		)
		(fp_line
			(start -0.7874 -0.4064)
			(end 0.7874 -0.4064)
			(stroke
				(width 0.1524)
				(type default)
			)
			(layer "F.SilkS")
		)
		(fp_line
			(start 0.67945 0.3048)
			(end 0.120396 0.3048)
			(stroke
				(width 0.1)
				(type default)
			)
			(layer "F.Fab")
		)
		(fp_line
			(start 0.67945 -0.3048)
			(end 0.67945 0.3048)
			(stroke
				(width 0.1)
				(type default)
			)
			(layer "F.Fab")
		)
		(fp_line
			(start 0.12065 -0.2794)
			(end 0.12065 -0.3048)
			(stroke
				(width 0.1)
				(type default)
			)
			(layer "F.Fab")
		)
		(fp_line
			(start 0.12065 -0.3048)
			(end 0.67945 -0.3048)
			(stroke
				(width 0.1)
				(type default)
			)
			(layer "F.Fab")
		)
		(fp_line
			(start 0.120396 0.3048)
			(end 0.120396 0.2794)
			(stroke
				(width 0.1)
				(type default)
			)
			(layer "F.Fab")
		)
		(fp_line
			(start 0.120396 0.2794)
			(end -0.12065 0.2794)
			(stroke
				(width 0.1)
				(type default)
			)
			(layer "F.Fab")
		)
		(fp_line
			(start -0.12065 0.3048)
			(end -0.67945 0.3048)
			(stroke
				(width 0.1)
				(type default)
			)
			(layer "F.Fab")
		)
		(fp_line
			(start -0.12065 0.2794)
			(end -0.12065 0.3048)
			(stroke
				(width 0.1)
				(type default)
			)
			(layer "F.Fab")
		)
		(fp_line
			(start -0.12065 -0.2794)
			(end 0.12065 -0.2794)
			(stroke
				(width 0.1)
				(type default)
			)
			(layer "F.Fab")
		)
		(fp_line
			(start -0.12065 -0.305054)
			(end -0.12065 -0.2794)
			(stroke
				(width 0.1)
				(type default)
			)
			(layer "F.Fab")
		)
		(fp_line
			(start -0.67945 0.3048)
			(end -0.67945 -0.305054)
			(stroke
				(width 0.1)
				(type default)
			)
			(layer "F.Fab")
		)
		(fp_line
			(start -0.67945 -0.305054)
			(end -0.12065 -0.305054)
			(stroke
				(width 0.1)
				(type default)
			)
			(layer "F.Fab")
		)
		(pad "1" smd circle
			(at -0.40005 0 180)
			(size 0 0)
			(layers "F.Cu" "F.Mask" "F.Paste")
			(net "SVID_ALERT0_CPU0_R_N")
		)
		(pad "2" smd circle
			(at 0.40005 0 180)
			(size 0 0)
			(layers "F.Cu" "F.Mask" "F.Paste")
			(net "SVID_ALERT_PVCCINFAON_CPU0_R")
		)
	)
	(footprint ""
		(layer "F.Cu")
		(at 246.14505 -40.259762 90)
		(property "Reference" "PD112"
			(at 7.442454 -2.35839 0)
			(unlocked yes)
			(layer "F.SilkS")
			(effects
				(font
					(size 0.7874 0.5842)
					(thickness 0.1524)
				)
				(justify left)
			)
		)
		(property "Value" ""
			(at 0 0 90)
			(layer "F.Fab")
			(effects
				(font
					(size 1.27 1.27)
				)
			)
		)
		(duplicate_pad_numbers_are_jumpers no)
		(fp_line
			(start 4.107942 -1.459992)
			(end 4.107942 1.459992)
			(stroke
				(width 0.1524)
				(type default)
			)
			(layer "F.SilkS")
		)
		(fp_line
			(start -3.400044 -1.459992)
			(end 4.107942 -1.459992)
			(stroke
				(width 0.1524)
				(type default)
			)
			(layer "F.SilkS")
		)
		(fp_line
			(start 4.107942 1.459992)
			(end -3.400044 1.459992)
			(stroke
				(width 0.1524)
				(type default)
			)
			(layer "F.SilkS")
		)
		(fp_line
			(start -3.400044 1.459992)
			(end -3.400044 -1.459992)
			(stroke
				(width 0.1524)
				(type default)
			)
			(layer "F.SilkS")
		)
		(fp_rect
			(start 3.308096 -1.459992)
			(end 4.107942 1.459992)
			(stroke
				(width 0)
				(type default)
			)
			(fill yes)
			(layer "F.SilkS")
		)
		(fp_line
			(start 2.29997 -1.459992)
			(end 2.29997 1.459992)
			(stroke
				(width 0.1)
				(type default)
			)
			(layer "F.Fab")
		)
		(fp_line
			(start -2.29997 -1.459992)
			(end 2.29997 -1.459992)
			(stroke
				(width 0.1)
				(type default)
			)
			(layer "F.Fab")
		)
		(fp_line
			(start 2.29997 1.459992)
			(end -2.29997 1.459992)
			(stroke
				(width 0.1)
				(type default)
			)
			(layer "F.Fab")
		)
		(fp_line
			(start -2.29997 1.459992)
			(end -2.29997 -1.459992)
			(stroke
				(width 0.1)
				(type default)
			)
			(layer "F.Fab")
		)
		(fp_text user "+"
			(at -4.7752 -0.12065 90)
			(unlocked yes)
			(layer "F.SilkS")
			(effects
				(font
					(size 1.905 1.4224)
					(thickness 0.1524)
				)
				(justify left)
			)
		)
		(fp_text user "-"
			(at 5.4102 0.29845 270)
			(unlocked yes)
			(layer "F.SilkS")
			(effects
				(font
					(size 1.905 1.4224)
					(thickness 0.1524)
				)
				(justify left)
			)
		)
		(fp_text user "+"
			(at -4.7752 -0.12065 90)
			(unlocked yes)
			(layer "F.Fab")
			(effects
				(font
					(size 1.905 1.4224)
					(thickness 0.1524)
				)
				(justify left)
			)
		)
		(fp_text user "-"
			(at 5.4102 0.29845 270)
			(unlocked yes)
			(layer "F.Fab")
			(effects
				(font
					(size 1.905 1.4224)
					(thickness 0.1524)
				)
				(justify left)
			)
		)
		(pad "A" smd rect
			(at -1.999996 0 180)
			(size 1.7018 2.5146)
			(layers "F.Cu" "F.Mask" "F.Paste")
			(net "GND")
		)
		(pad "C" smd rect
			(at 1.999996 0 180)
			(size 1.7018 2.5146)
			(layers "F.Cu" "F.Mask" "F.Paste")
			(net "P12V_E1S_0")
		)
	)
	(footprint ""
		(layer "F.Cu")
		(at 492.16437 -470.73439)
		(property "Reference" "U1_BP"
			(at -0.18669 -3.567938 0)
			(unlocked yes)
			(layer "F.SilkS")
			(effects
				(font
					(size 0.7874 0.5842)
					(thickness 0.1524)
				)
				(justify left)
			)
		)
		(property "Value" ""
			(at 0 0 0)
			(layer "F.Fab")
			(effects
				(font
					(size 1.27 1.27)
				)
			)
		)
		(duplicate_pad_numbers_are_jumpers no)
		(pad "1" smd circle
			(at 0 0)
			(size 0.762 0.762)
			(layers "F.Cu" "F.Mask" "F.Paste")
			(net "Net_8487")
		)
	)
	(footprint ""
		(layer "F.Cu")
		(at 361.258612 -333.716122)
		(property "Reference" "PU11_P0_3"
			(at -2.211832 -6.254496 0)
			(unlocked yes)
			(layer "F.SilkS")
			(effects
				(font
					(size 0.7874 0.5842)
					(thickness 0.1524)
				)
				(justify left)
			)
		)
		(property "Value" ""
			(at 0 0 0)
			(layer "F.Fab")
			(effects
				(font
					(size 1.27 1.27)
				)
			)
		)
		(duplicate_pad_numbers_are_jumpers no)
		(fp_line
			(start -2.500122 -2.999994)
			(end -2.24409 -2.999994)
			(stroke
				(width 0.1524)
				(type default)
			)
			(layer "F.SilkS")
		)
		(fp_line
			(start -2.500122 -2.529078)
			(end -2.500122 -2.999994)
			(stroke
				(width 0.1524)
				(type default)
			)
			(layer "F.SilkS")
		)
		(fp_line
			(start -2.500122 0.6604)
			(end -2.500122 0.229108)
			(stroke
				(width 0.1524)
				(type default)
			)
			(layer "F.SilkS")
		)
		(fp_line
			(start -2.500122 2.999994)
			(end -2.500122 2.339594)
			(stroke
				(width 0.1524)
				(type default)
			)
			(layer "F.SilkS")
		)
		(fp_line
			(start -2.2987 2.999994)
			(end -2.500122 2.999994)
			(stroke
				(width 0.1524)
				(type default)
			)
			(layer "F.SilkS")
		)
		(fp_line
			(start 2.31394 -2.999994)
			(end 2.500122 -2.999994)
			(stroke
				(width 0.1524)
				(type default)
			)
			(layer "F.SilkS")
		)
		(fp_line
			(start 2.500122 -2.999994)
			(end 2.500122 -2.44348)
			(stroke
				(width 0.1524)
				(type default)
			)
			(layer "F.SilkS")
		)
		(fp_line
			(start 2.500122 2.339594)
			(end 2.500122 2.999994)
			(stroke
				(width 0.1524)
				(type default)
			)
			(layer "F.SilkS")
		)
		(fp_line
			(start 2.500122 2.999994)
			(end 2.2987 2.999994)
			(stroke
				(width 0.1524)
				(type default)
			)
			(layer "F.SilkS")
		)
		(fp_poly
			(pts
				(xy -2.2479 -3.591306) (xy -2.7559 -2.575306) (xy -3.2639 -3.591306)
			)
			(stroke
				(width 0)
				(type default)
			)
			(fill yes)
			(layer "F.SilkS")
		)
		(fp_line
			(start -2.500122 -2.999994)
			(end 2.500122 -2.999994)
			(stroke
				(width 0.1)
				(type default)
			)
			(layer "F.Fab")
		)
		(fp_line
			(start -2.500122 2.999994)
			(end -2.500122 -2.999994)
			(stroke
				(width 0.1)
				(type default)
			)
			(layer "F.Fab")
		)
		(fp_line
			(start 2.500122 -2.999994)
			(end 2.500122 2.999994)
			(stroke
				(width 0.1)
				(type default)
			)
			(layer "F.Fab")
		)
		(fp_line
			(start 2.500122 2.999994)
			(end -2.500122 2.999994)
			(stroke
				(width 0.1)
				(type default)
			)
			(layer "F.Fab")
		)
		(fp_poly
			(pts
				(xy -4.218432 -2.783078) (xy -4.218432 -1.767078) (xy -3.202432 -2.275078)
			)
			(stroke
				(width 0)
				(type default)
			)
			(fill yes)
			(layer "F.Fab")
		)
		(pad "1" smd rect
			(at -2.400046 -2.275078 90)
			(size 0.2286 0.6096)
			(layers "F.Cu" "F.Mask" "F.Paste")
			(net "PVCCIN_CPU0_VOS3")
		)
		(pad "2" smd rect
			(at -2.400046 -1.82499 90)
			(size 0.2286 0.6096)
			(layers "F.Cu" "F.Mask" "F.Paste")
			(net "GND")
		)
		(pad "3" smd rect
			(at -2.400046 -1.374902 90)
			(size 0.2286 0.6096)
			(layers "F.Cu" "F.Mask" "F.Paste")
			(net "PVCCIN_CPU0_VDD3")
		)
		(pad "4" smd rect
			(at -2.400046 -0.925068 90)
			(size 0.2286 0.6096)
			(layers "F.Cu" "F.Mask" "F.Paste")
			(net "PVCCIN_CPU0_PVCC")
		)
		(pad "5" smd rect
			(at -2.400046 -0.47498 90)
			(size 0.2286 0.6096)
			(layers "F.Cu" "F.Mask" "F.Paste")
			(net "GND")
		)
		(pad "6" smd rect
			(at -2.400046 -0.024892 90)
			(size 0.2286 0.6096)
			(layers "F.Cu" "F.Mask" "F.Paste")
			(net "Net_8550")
		)
		(pad "7_9-20_24" smd circle
			(at 0 1.150112 90)
			(size 0 0)
			(layers "F.Cu" "F.Mask" "F.Paste")
			(net "GND")
		)
		(pad "10_19" smd rect
			(at 0 2.899918 90)
			(size 0.6096 4.318)
			(layers "F.Cu" "F.Mask" "F.Paste")
			(net "SW_PVCCIN_CPU0_SW3")
		)
		(pad "25_29" smd rect
			(at 1.549908 -1.279906 270)
			(size 2.0574 2.3114)
			(layers "F.Cu" "F.Mask" "F.Paste")
			(net "SW_P12V_PVCCIN_CPU0_FLT")
		)
		(pad "30" smd rect
			(at 2.05994 -2.899918)
			(size 0.2286 0.6096)
			(layers "F.Cu" "F.Mask" "F.Paste")
			(net "SW_P12V_PVCCIN_CPU0_FLT")
		)
		(pad "31" smd rect
			(at 1.610106 -2.899918)
			(size 0.2286 0.6096)
			(layers "F.Cu" "F.Mask" "F.Paste")
			(net "Net_8551")
		)
		(pad "32" smd rect
			(at 1.160018 -2.899918)
			(size 0.2286 0.6096)
			(layers "F.Cu" "F.Mask" "F.Paste")
			(net "SW_PVCCIN_CPU0_BOOTR3")
		)
		(pad "33" smd rect
			(at 0.70993 -2.899918)
			(size 0.2286 0.6096)
			(layers "F.Cu" "F.Mask" "F.Paste")
			(net "SW_PVCCIN_CPU0_BOOT3")
		)
		(pad "34" smd rect
			(at 0.260096 -2.899918)
			(size 0.2286 0.6096)
			(layers "F.Cu" "F.Mask" "F.Paste")
			(net "PVCCIN_CPU0_PWM3")
		)
		(pad "35" smd rect
			(at -0.189992 -2.899918)
			(size 0.2286 0.6096)
			(layers "F.Cu" "F.Mask" "F.Paste")
			(net "PVCCIN_CPU0_VDD3")
		)
		(pad "36" smd rect
			(at -0.64008 -2.899918)
			(size 0.2286 0.6096)
			(layers "F.Cu" "F.Mask" "F.Paste")
			(net "PVCCIN_CPU0_ATSEN")
		)
		(pad "37" smd rect
			(at -1.089914 -2.899918)
			(size 0.2286 0.6096)
			(layers "F.Cu" "F.Mask" "F.Paste")
			(net "PVCCIN_CPU0_LSET3")
		)
		(pad "38" smd rect
			(at -1.540002 -2.899918)
			(size 0.2286 0.6096)
			(layers "F.Cu" "F.Mask" "F.Paste")
			(net "PVCCIN_CPU0_IMON3")
		)
		(pad "39" smd rect
			(at -1.99009 -2.899918)
			(size 0.2286 0.6096)
			(layers "F.Cu" "F.Mask" "F.Paste")
			(net "PVCCIN_CPU0_VREF")
		)
		(pad "40" smd rect
			(at -0.87503 -1.27508)
			(size 1.7526 1.9558)
			(layers "F.Cu" "F.Mask" "F.Paste")
			(net "GND")
		)
		(pad "41" smd rect
			(at -1.525016 0.249936 270)
			(size 0.3048 0.4572)
			(layers "F.Cu" "F.Mask" "F.Paste")
			(net "Net_8549")
		)
		(zone
			(layer "F.Cu")
			(hatch none 0.5)
			(connect_pads
				(clearance 0)
			)
			(min_thickness 0.25)
			(keepout
				(tracks not_allowed)
				(vias allowed)
				(pads allowed)
				(copperpour not_allowed)
				(footprints allowed)
			)
			(placement
				(enabled no)
				(sheetname "")
			)
			(fill
				(thermal_gap 0.5)
				(thermal_bridge_width 0.5)
				(island_removal_mode 0)
			)
			(polygon
				(pts
					(xy 358.75849 -330.716128) (xy 358.75849 -331.465428) (xy 363.758734 -331.465428) (xy 363.758734 -330.716128)
					(xy 363.468412 -330.716128) (xy 363.468412 -331.171804) (xy 359.048812 -331.171804) (xy 359.048812 -330.716128)
				)
			)
		)
		(zone
			(layer "F.Cu")
			(hatch none 0.5)
			(connect_pads
				(clearance 0)
			)
			(min_thickness 0.25)
			(keepout
				(tracks not_allowed)
				(vias allowed)
				(pads allowed)
				(copperpour not_allowed)
				(footprints allowed)
			)
			(placement
				(enabled no)
				(sheetname "")
			)
			(fill
				(thermal_gap 0.5)
				(thermal_bridge_width 0.5)
				(island_removal_mode 0)
			)
			(polygon
				(pts
					(xy 359.214166 -334.028288) (xy 359.456482 -334.028288) (xy 359.456482 -333.962502) (xy 360.09072 -333.962502)
					(xy 360.09072 -333.647288) (xy 360.30789 -333.647288) (xy 360.30789 -332.966822) (xy 358.75849 -332.966822)
					(xy 358.75849 -333.423514) (xy 359.454196 -333.423514) (xy 359.454196 -333.262986) (xy 360.012996 -333.262986)
					(xy 360.012996 -333.669386) (xy 359.454196 -333.669386) (xy 359.454196 -333.448914) (xy 358.75849 -333.448914)
					(xy 358.75849 -333.575914) (xy 359.214166 -333.575914)
				)
			)
		)
	)
	(footprint ""
		(layer "F.Cu")
		(at 193.38036 -115.534948 180)
		(property "Reference" "R1812"
			(at 0 0 180)
			(layer "F.SilkS")
			(hide yes)
			(effects
				(font
					(size 1.27 1.27)
				)
			)
		)
		(property "Value" ""
			(at 0 0 180)
			(layer "F.Fab")
			(effects
				(font
					(size 1.27 1.27)
				)
			)
		)
		(duplicate_pad_numbers_are_jumpers no)
		(fp_line
			(start 0.7874 0.4064)
			(end -0.7874 0.4064)
			(stroke
				(width 0.1524)
				(type default)
			)
			(layer "F.SilkS")
		)
		(fp_line
			(start 0.7874 -0.4064)
			(end 0.7874 0.4064)
			(stroke
				(width 0.1524)
				(type default)
			)
			(layer "F.SilkS")
		)
		(fp_line
			(start -0.7874 0.4064)
			(end -0.7874 -0.4064)
			(stroke
				(width 0.1524)
				(type default)
			)
			(layer "F.SilkS")
		)
		(fp_line
			(start -0.7874 -0.4064)
			(end 0.7874 -0.4064)
			(stroke
				(width 0.1524)
				(type default)
			)
			(layer "F.SilkS")
		)
		(fp_line
			(start 0.67945 0.3048)
			(end 0.120396 0.3048)
			(stroke
				(width 0.1)
				(type default)
			)
			(layer "F.Fab")
		)
		(fp_line
			(start 0.67945 -0.3048)
			(end 0.67945 0.3048)
			(stroke
				(width 0.1)
				(type default)
			)
			(layer "F.Fab")
		)
		(fp_line
			(start 0.12065 -0.2794)
			(end 0.12065 -0.3048)
			(stroke
				(width 0.1)
				(type default)
			)
			(layer "F.Fab")
		)
		(fp_line
			(start 0.12065 -0.3048)
			(end 0.67945 -0.3048)
			(stroke
				(width 0.1)
				(type default)
			)
			(layer "F.Fab")
		)
		(fp_line
			(start 0.120396 0.3048)
			(end 0.120396 0.2794)
			(stroke
				(width 0.1)
				(type default)
			)
			(layer "F.Fab")
		)
		(fp_line
			(start 0.120396 0.2794)
			(end -0.12065 0.2794)
			(stroke
				(width 0.1)
				(type default)
			)
			(layer "F.Fab")
		)
		(fp_line
			(start -0.12065 0.3048)
			(end -0.67945 0.3048)
			(stroke
				(width 0.1)
				(type default)
			)
			(layer "F.Fab")
		)
		(fp_line
			(start -0.12065 0.2794)
			(end -0.12065 0.3048)
			(stroke
				(width 0.1)
				(type default)
			)
			(layer "F.Fab")
		)
		(fp_line
			(start -0.12065 -0.2794)
			(end 0.12065 -0.2794)
			(stroke
				(width 0.1)
				(type default)
			)
			(layer "F.Fab")
		)
		(fp_line
			(start -0.12065 -0.305054)
			(end -0.12065 -0.2794)
			(stroke
				(width 0.1)
				(type default)
			)
			(layer "F.Fab")
		)
		(fp_line
			(start -0.67945 0.3048)
			(end -0.67945 -0.305054)
			(stroke
				(width 0.1)
				(type default)
			)
			(layer "F.Fab")
		)
		(fp_line
			(start -0.67945 -0.305054)
			(end -0.12065 -0.305054)
			(stroke
				(width 0.1)
				(type default)
			)
			(layer "F.Fab")
		)
		(pad "1" smd circle
			(at -0.40005 0 180)
			(size 0 0)
			(layers "F.Cu" "F.Mask" "F.Paste")
			(net "IRQ_SGPIO_INTR_N")
		)
		(pad "2" smd circle
			(at 0.40005 0 180)
			(size 0 0)
			(layers "F.Cu" "F.Mask" "F.Paste")
			(net "IRQ_SGPIO_INTR_N_R")
		)
	)
	(footprint ""
		(layer "F.Cu")
		(at 22.809454 -111.383826)
		(property "Reference" "R3672"
			(at 0 0 0)
			(layer "F.SilkS")
			(hide yes)
			(effects
				(font
					(size 1.27 1.27)
				)
			)
		)
		(property "Value" ""
			(at 0 0 0)
			(layer "F.Fab")
			(effects
				(font
					(size 1.27 1.27)
				)
			)
		)
		(duplicate_pad_numbers_are_jumpers no)
		(fp_line
			(start -0.7874 -0.4064)
			(end 0.7874 -0.4064)
			(stroke
				(width 0.1524)
				(type default)
			)
			(layer "F.SilkS")
		)
		(fp_line
			(start -0.7874 0.4064)
			(end -0.7874 -0.4064)
			(stroke
				(width 0.1524)
				(type default)
			)
			(layer "F.SilkS")
		)
		(fp_line
			(start 0.7874 -0.4064)
			(end 0.7874 0.4064)
			(stroke
				(width 0.1524)
				(type default)
			)
			(layer "F.SilkS")
		)
		(fp_line
			(start 0.7874 0.4064)
			(end -0.7874 0.4064)
			(stroke
				(width 0.1524)
				(type default)
			)
			(layer "F.SilkS")
		)
		(fp_line
			(start -0.67945 -0.305054)
			(end -0.12065 -0.305054)
			(stroke
				(width 0.1)
				(type default)
			)
			(layer "F.Fab")
		)
		(fp_line
			(start -0.67945 0.3048)
			(end -0.67945 -0.305054)
			(stroke
				(width 0.1)
				(type default)
			)
			(layer "F.Fab")
		)
		(fp_line
			(start -0.12065 -0.305054)
			(end -0.12065 -0.2794)
			(stroke
				(width 0.1)
				(type default)
			)
			(layer "F.Fab")
		)
		(fp_line
			(start -0.12065 -0.2794)
			(end 0.12065 -0.2794)
			(stroke
				(width 0.1)
				(type default)
			)
			(layer "F.Fab")
		)
		(fp_line
			(start -0.12065 0.2794)
			(end -0.12065 0.3048)
			(stroke
				(width 0.1)
				(type default)
			)
			(layer "F.Fab")
		)
		(fp_line
			(start -0.12065 0.3048)
			(end -0.67945 0.3048)
			(stroke
				(width 0.1)
				(type default)
			)
			(layer "F.Fab")
		)
		(fp_line
			(start 0.120396 0.2794)
			(end -0.12065 0.2794)
			(stroke
				(width 0.1)
				(type default)
			)
			(layer "F.Fab")
		)
		(fp_line
			(start 0.120396 0.3048)
			(end 0.120396 0.2794)
			(stroke
				(width 0.1)
				(type default)
			)
			(layer "F.Fab")
		)
		(fp_line
			(start 0.12065 -0.3048)
			(end 0.67945 -0.3048)
			(stroke
				(width 0.1)
				(type default)
			)
			(layer "F.Fab")
		)
		(fp_line
			(start 0.12065 -0.2794)
			(end 0.12065 -0.3048)
			(stroke
				(width 0.1)
				(type default)
			)
			(layer "F.Fab")
		)
		(fp_line
			(start 0.67945 -0.3048)
			(end 0.67945 0.3048)
			(stroke
				(width 0.1)
				(type default)
			)
			(layer "F.Fab")
		)
		(fp_line
			(start 0.67945 0.3048)
			(end 0.120396 0.3048)
			(stroke
				(width 0.1)
				(type default)
			)
			(layer "F.Fab")
		)
		(pad "1" smd circle
			(at -0.40005 0)
			(size 0 0)
			(layers "F.Cu" "F.Mask" "F.Paste")
			(net "SMB_VR_3V3AUX_SCL_R1")
		)
		(pad "2" smd circle
			(at 0.40005 0)
			(size 0 0)
			(layers "F.Cu" "F.Mask" "F.Paste")
			(net "SMB_SEN_TIC_3V3AUX_SCL")
		)
	)
	(footprint ""
		(layer "F.Cu")
		(at 371.204998 -338.17814 -90)
		(property "Reference" "PC278"
			(at 0 0 270)
			(layer "F.SilkS")
			(hide yes)
			(effects
				(font
					(size 1.27 1.27)
				)
			)
		)
		(property "Value" ""
			(at 0 0 270)
			(layer "F.Fab")
			(effects
				(font
					(size 1.27 1.27)
				)
			)
		)
		(duplicate_pad_numbers_are_jumpers no)
		(fp_line
			(start -0.7874 0.4064)
			(end -0.7874 -0.4064)
			(stroke
				(width 0.1524)
				(type default)
			)
			(layer "F.SilkS")
		)
		(fp_line
			(start 0.7874 0.4064)
			(end -0.7874 0.4064)
			(stroke
				(width 0.1524)
				(type default)
			)
			(layer "F.SilkS")
		)
		(fp_line
			(start -0.7874 -0.4064)
			(end 0.7874 -0.4064)
			(stroke
				(width 0.1524)
				(type default)
			)
			(layer "F.SilkS")
		)
		(fp_line
			(start 0.7874 -0.4064)
			(end 0.7874 0.4064)
			(stroke
				(width 0.1524)
				(type default)
			)
			(layer "F.SilkS")
		)
		(fp_line
			(start -0.67945 0.3048)
			(end -0.67945 -0.305054)
			(stroke
				(width 0.1)
				(type default)
			)
			(layer "F.Fab")
		)
		(fp_line
			(start -0.12065 0.3048)
			(end -0.67945 0.3048)
			(stroke
				(width 0.1)
				(type default)
			)
			(layer "F.Fab")
		)
		(fp_line
			(start 0.120396 0.3048)
			(end 0.120396 0.2794)
			(stroke
				(width 0.1)
				(type default)
			)
			(layer "F.Fab")
		)
		(fp_line
			(start 0.67945 0.3048)
			(end 0.120396 0.3048)
			(stroke
				(width 0.1)
				(type default)
			)
			(layer "F.Fab")
		)
		(fp_line
			(start -0.12065 0.2794)
			(end -0.12065 0.3048)
			(stroke
				(width 0.1)
				(type default)
			)
			(layer "F.Fab")
		)
		(fp_line
			(start 0.120396 0.2794)
			(end -0.12065 0.2794)
			(stroke
				(width 0.1)
				(type default)
			)
			(layer "F.Fab")
		)
		(fp_line
			(start -0.12065 -0.2794)
			(end 0.12065 -0.2794)
			(stroke
				(width 0.1)
				(type default)
			)
			(layer "F.Fab")
		)
		(fp_line
			(start 0.12065 -0.2794)
			(end 0.12065 -0.3048)
			(stroke
				(width 0.1)
				(type default)
			)
			(layer "F.Fab")
		)
		(fp_line
			(start 0.12065 -0.3048)
			(end 0.67945 -0.3048)
			(stroke
				(width 0.1)
				(type default)
			)
			(layer "F.Fab")
		)
		(fp_line
			(start 0.67945 -0.3048)
			(end 0.67945 0.3048)
			(stroke
				(width 0.1)
				(type default)
			)
			(layer "F.Fab")
		)
		(fp_line
			(start -0.67945 -0.305054)
			(end -0.12065 -0.305054)
			(stroke
				(width 0.1)
				(type default)
			)
			(layer "F.Fab")
		)
		(fp_line
			(start -0.12065 -0.305054)
			(end -0.12065 -0.2794)
			(stroke
				(width 0.1)
				(type default)
			)
			(layer "F.Fab")
		)
		(pad "1" smd circle
			(at -0.40005 0 270)
			(size 0 0)
			(layers "F.Cu" "F.Mask" "F.Paste")
			(net "SW_PVCCIN_CPU0_BOOT4_R")
		)
		(pad "2" smd circle
			(at 0.40005 0 270)
			(size 0 0)
			(layers "F.Cu" "F.Mask" "F.Paste")
			(net "SW_PVCCIN_CPU0_BOOTR4")
		)
	)
	(footprint ""
		(layer "F.Cu")
		(at 118.542816 -252.956568 -90)
		(property "Reference" "C243"
			(at 0 0 270)
			(layer "F.SilkS")
			(hide yes)
			(effects
				(font
					(size 1.27 1.27)
				)
			)
		)
		(property "Value" ""
			(at 0 0 270)
			(layer "F.Fab")
			(effects
				(font
					(size 1.27 1.27)
				)
			)
		)
		(duplicate_pad_numbers_are_jumpers no)
		(fp_line
			(start -0.7874 0.4064)
			(end -0.7874 -0.4064)
			(stroke
				(width 0.1524)
				(type default)
			)
			(layer "F.SilkS")
		)
		(fp_line
			(start 0.7874 0.4064)
			(end -0.7874 0.4064)
			(stroke
				(width 0.1524)
				(type default)
			)
			(layer "F.SilkS")
		)
		(fp_line
			(start -0.7874 -0.4064)
			(end 0.7874 -0.4064)
			(stroke
				(width 0.1524)
				(type default)
			)
			(layer "F.SilkS")
		)
		(fp_line
			(start 0.7874 -0.4064)
			(end 0.7874 0.4064)
			(stroke
				(width 0.1524)
				(type default)
			)
			(layer "F.SilkS")
		)
		(fp_line
			(start -0.67945 0.3048)
			(end -0.67945 -0.305054)
			(stroke
				(width 0.1)
				(type default)
			)
			(layer "F.Fab")
		)
		(fp_line
			(start -0.12065 0.3048)
			(end -0.67945 0.3048)
			(stroke
				(width 0.1)
				(type default)
			)
			(layer "F.Fab")
		)
		(fp_line
			(start 0.120396 0.3048)
			(end 0.120396 0.2794)
			(stroke
				(width 0.1)
				(type default)
			)
			(layer "F.Fab")
		)
		(fp_line
			(start 0.67945 0.3048)
			(end 0.120396 0.3048)
			(stroke
				(width 0.1)
				(type default)
			)
			(layer "F.Fab")
		)
		(fp_line
			(start -0.12065 0.2794)
			(end -0.12065 0.3048)
			(stroke
				(width 0.1)
				(type default)
			)
			(layer "F.Fab")
		)
		(fp_line
			(start 0.120396 0.2794)
			(end -0.12065 0.2794)
			(stroke
				(width 0.1)
				(type default)
			)
			(layer "F.Fab")
		)
		(fp_line
			(start -0.12065 -0.2794)
			(end 0.12065 -0.2794)
			(stroke
				(width 0.1)
				(type default)
			)
			(layer "F.Fab")
		)
		(fp_line
			(start 0.12065 -0.2794)
			(end 0.12065 -0.3048)
			(stroke
				(width 0.1)
				(type default)
			)
			(layer "F.Fab")
		)
		(fp_line
			(start 0.12065 -0.3048)
			(end 0.67945 -0.3048)
			(stroke
				(width 0.1)
				(type default)
			)
			(layer "F.Fab")
		)
		(fp_line
			(start 0.67945 -0.3048)
			(end 0.67945 0.3048)
			(stroke
				(width 0.1)
				(type default)
			)
			(layer "F.Fab")
		)
		(fp_line
			(start -0.67945 -0.305054)
			(end -0.12065 -0.305054)
			(stroke
				(width 0.1)
				(type default)
			)
			(layer "F.Fab")
		)
		(fp_line
			(start -0.12065 -0.305054)
			(end -0.12065 -0.2794)
			(stroke
				(width 0.1)
				(type default)
			)
			(layer "F.Fab")
		)
		(pad "1" smd circle
			(at -0.40005 0 270)
			(size 0 0)
			(layers "F.Cu" "F.Mask" "F.Paste")
			(net "PVCCIN_CPU1")
		)
		(pad "2" smd circle
			(at 0.40005 0 270)
			(size 0 0)
			(layers "F.Cu" "F.Mask" "F.Paste")
			(net "GND")
		)
	)
	(footprint ""
		(layer "F.Cu")
		(at 307.3146 -62.375542 90)
		(property "Reference" "C1612"
			(at 0 0 90)
			(layer "F.SilkS")
			(hide yes)
			(effects
				(font
					(size 1.27 1.27)
				)
			)
		)
		(property "Value" ""
			(at 0 0 90)
			(layer "F.Fab")
			(effects
				(font
					(size 1.27 1.27)
				)
			)
		)
		(duplicate_pad_numbers_are_jumpers no)
		(fp_line
			(start 0.7874 -0.4064)
			(end 0.7874 0.4064)
			(stroke
				(width 0.1524)
				(type default)
			)
			(layer "F.SilkS")
		)
		(fp_line
			(start -0.7874 -0.4064)
			(end 0.7874 -0.4064)
			(stroke
				(width 0.1524)
				(type default)
			)
			(layer "F.SilkS")
		)
		(fp_line
			(start 0.7874 0.4064)
			(end -0.7874 0.4064)
			(stroke
				(width 0.1524)
				(type default)
			)
			(layer "F.SilkS")
		)
		(fp_line
			(start -0.7874 0.4064)
			(end -0.7874 -0.4064)
			(stroke
				(width 0.1524)
				(type default)
			)
			(layer "F.SilkS")
		)
		(fp_line
			(start -0.12065 -0.305054)
			(end -0.12065 -0.2794)
			(stroke
				(width 0.1)
				(type default)
			)
			(layer "F.Fab")
		)
		(fp_line
			(start -0.67945 -0.305054)
			(end -0.12065 -0.305054)
			(stroke
				(width 0.1)
				(type default)
			)
			(layer "F.Fab")
		)
		(fp_line
			(start 0.67945 -0.3048)
			(end 0.67945 0.3048)
			(stroke
				(width 0.1)
				(type default)
			)
			(layer "F.Fab")
		)
		(fp_line
			(start 0.12065 -0.3048)
			(end 0.67945 -0.3048)
			(stroke
				(width 0.1)
				(type default)
			)
			(layer "F.Fab")
		)
		(fp_line
			(start 0.12065 -0.2794)
			(end 0.12065 -0.3048)
			(stroke
				(width 0.1)
				(type default)
			)
			(layer "F.Fab")
		)
		(fp_line
			(start -0.12065 -0.2794)
			(end 0.12065 -0.2794)
			(stroke
				(width 0.1)
				(type default)
			)
			(layer "F.Fab")
		)
		(fp_line
			(start 0.120396 0.2794)
			(end -0.12065 0.2794)
			(stroke
				(width 0.1)
				(type default)
			)
			(layer "F.Fab")
		)
		(fp_line
			(start -0.12065 0.2794)
			(end -0.12065 0.3048)
			(stroke
				(width 0.1)
				(type default)
			)
			(layer "F.Fab")
		)
		(fp_line
			(start 0.67945 0.3048)
			(end 0.120396 0.3048)
			(stroke
				(width 0.1)
				(type default)
			)
			(layer "F.Fab")
		)
		(fp_line
			(start 0.120396 0.3048)
			(end 0.120396 0.2794)
			(stroke
				(width 0.1)
				(type default)
			)
			(layer "F.Fab")
		)
		(fp_line
			(start -0.12065 0.3048)
			(end -0.67945 0.3048)
			(stroke
				(width 0.1)
				(type default)
			)
			(layer "F.Fab")
		)
		(fp_line
			(start -0.67945 0.3048)
			(end -0.67945 -0.305054)
			(stroke
				(width 0.1)
				(type default)
			)
			(layer "F.Fab")
		)
		(pad "1" smd circle
			(at -0.40005 0 90)
			(size 0 0)
			(layers "F.Cu" "F.Mask" "F.Paste")
			(net "P3V3_AUX")
		)
		(pad "2" smd circle
			(at 0.40005 0 90)
			(size 0 0)
			(layers "F.Cu" "F.Mask" "F.Paste")
			(net "GND")
		)
	)
	(footprint ""
		(layer "F.Cu")
		(at 31.891732 -416.016948 180)
		(property "Reference" "R2842"
			(at 0 0 180)
			(layer "F.SilkS")
			(hide yes)
			(effects
				(font
					(size 1.27 1.27)
				)
			)
		)
		(property "Value" ""
			(at 0 0 180)
			(layer "F.Fab")
			(effects
				(font
					(size 1.27 1.27)
				)
			)
		)
		(duplicate_pad_numbers_are_jumpers no)
		(fp_line
			(start 0.7874 0.4064)
			(end -0.7874 0.4064)
			(stroke
				(width 0.1524)
				(type default)
			)
			(layer "F.SilkS")
		)
		(fp_line
			(start 0.7874 -0.4064)
			(end 0.7874 0.4064)
			(stroke
				(width 0.1524)
				(type default)
			)
			(layer "F.SilkS")
		)
		(fp_line
			(start -0.7874 0.4064)
			(end -0.7874 -0.4064)
			(stroke
				(width 0.1524)
				(type default)
			)
			(layer "F.SilkS")
		)
		(fp_line
			(start -0.7874 -0.4064)
			(end 0.7874 -0.4064)
			(stroke
				(width 0.1524)
				(type default)
			)
			(layer "F.SilkS")
		)
		(fp_line
			(start 0.67945 0.3048)
			(end 0.120396 0.3048)
			(stroke
				(width 0.1)
				(type default)
			)
			(layer "F.Fab")
		)
		(fp_line
			(start 0.67945 -0.3048)
			(end 0.67945 0.3048)
			(stroke
				(width 0.1)
				(type default)
			)
			(layer "F.Fab")
		)
		(fp_line
			(start 0.12065 -0.2794)
			(end 0.12065 -0.3048)
			(stroke
				(width 0.1)
				(type default)
			)
			(layer "F.Fab")
		)
		(fp_line
			(start 0.12065 -0.3048)
			(end 0.67945 -0.3048)
			(stroke
				(width 0.1)
				(type default)
			)
			(layer "F.Fab")
		)
		(fp_line
			(start 0.120396 0.3048)
			(end 0.120396 0.2794)
			(stroke
				(width 0.1)
				(type default)
			)
			(layer "F.Fab")
		)
		(fp_line
			(start 0.120396 0.2794)
			(end -0.12065 0.2794)
			(stroke
				(width 0.1)
				(type default)
			)
			(layer "F.Fab")
		)
		(fp_line
			(start -0.12065 0.3048)
			(end -0.67945 0.3048)
			(stroke
				(width 0.1)
				(type default)
			)
			(layer "F.Fab")
		)
		(fp_line
			(start -0.12065 0.2794)
			(end -0.12065 0.3048)
			(stroke
				(width 0.1)
				(type default)
			)
			(layer "F.Fab")
		)
		(fp_line
			(start -0.12065 -0.2794)
			(end 0.12065 -0.2794)
			(stroke
				(width 0.1)
				(type default)
			)
			(layer "F.Fab")
		)
		(fp_line
			(start -0.12065 -0.305054)
			(end -0.12065 -0.2794)
			(stroke
				(width 0.1)
				(type default)
			)
			(layer "F.Fab")
		)
		(fp_line
			(start -0.67945 0.3048)
			(end -0.67945 -0.305054)
			(stroke
				(width 0.1)
				(type default)
			)
			(layer "F.Fab")
		)
		(fp_line
			(start -0.67945 -0.305054)
			(end -0.12065 -0.305054)
			(stroke
				(width 0.1)
				(type default)
			)
			(layer "F.Fab")
		)
		(pad "1" smd circle
			(at -0.40005 0 180)
			(size 0 0)
			(layers "F.Cu" "F.Mask" "F.Paste")
			(net "P3V3_AUX")
		)
		(pad "2" smd circle
			(at 0.40005 0 180)
			(size 0 0)
			(layers "F.Cu" "F.Mask" "F.Paste")
			(net "FM_GPU_PWRGD_N")
		)
	)
	(footprint ""
		(layer "F.Cu")
		(at 416.009582 -179.457858 -90)
		(property "Reference" "PU44_P0_2"
			(at 4.08051 7.755382 0)
			(unlocked yes)
			(layer "F.SilkS")
			(effects
				(font
					(size 0.7874 0.5842)
					(thickness 0.1524)
				)
				(justify left)
			)
		)
		(property "Value" ""
			(at 0 0 270)
			(layer "F.Fab")
			(effects
				(font
					(size 1.27 1.27)
				)
			)
		)
		(duplicate_pad_numbers_are_jumpers no)
		(fp_line
			(start -2.500122 2.999994)
			(end -2.500122 2.339594)
			(stroke
				(width 0.1524)
				(type default)
			)
			(layer "F.SilkS")
		)
		(fp_line
			(start -2.2987 2.999994)
			(end -2.500122 2.999994)
			(stroke
				(width 0.1524)
				(type default)
			)
			(layer "F.SilkS")
		)
		(fp_line
			(start 2.500122 2.999994)
			(end 2.2987 2.999994)
			(stroke
				(width 0.1524)
				(type default)
			)
			(layer "F.SilkS")
		)
		(fp_line
			(start 2.500122 2.339594)
			(end 2.500122 2.999994)
			(stroke
				(width 0.1524)
				(type default)
			)
			(layer "F.SilkS")
		)
		(fp_line
			(start -2.500122 0.6604)
			(end -2.500122 0.229108)
			(stroke
				(width 0.1524)
				(type default)
			)
			(layer "F.SilkS")
		)
		(fp_line
			(start -2.500122 -2.529078)
			(end -2.500122 -2.999994)
			(stroke
				(width 0.1524)
				(type default)
			)
			(layer "F.SilkS")
		)
		(fp_line
			(start -2.500122 -2.999994)
			(end -2.24409 -2.999994)
			(stroke
				(width 0.1524)
				(type default)
			)
			(layer "F.SilkS")
		)
		(fp_line
			(start 2.31394 -2.999994)
			(end 2.500122 -2.999994)
			(stroke
				(width 0.1524)
				(type default)
			)
			(layer "F.SilkS")
		)
		(fp_line
			(start 2.500122 -2.999994)
			(end 2.500122 -2.44348)
			(stroke
				(width 0.1524)
				(type default)
			)
			(layer "F.SilkS")
		)
		(fp_poly
			(pts
				(xy -4.93395 -2.65811) (xy -4.218432 -2.300478) (xy -4.93395 -1.942846)
			)
			(stroke
				(width 0)
				(type default)
			)
			(fill yes)
			(layer "F.SilkS")
		)
		(fp_line
			(start -2.500122 2.999994)
			(end -2.500122 -2.999994)
			(stroke
				(width 0.1)
				(type default)
			)
			(layer "F.Fab")
		)
		(fp_line
			(start 2.500122 2.999994)
			(end -2.500122 2.999994)
			(stroke
				(width 0.1)
				(type default)
			)
			(layer "F.Fab")
		)
		(fp_line
			(start -2.500122 -2.999994)
			(end 2.500122 -2.999994)
			(stroke
				(width 0.1)
				(type default)
			)
			(layer "F.Fab")
		)
		(fp_line
			(start 2.500122 -2.999994)
			(end 2.500122 2.999994)
			(stroke
				(width 0.1)
				(type default)
			)
			(layer "F.Fab")
		)
		(fp_poly
			(pts
				(xy -4.218432 -2.783078) (xy -4.218432 -1.767078) (xy -3.202432 -2.275078)
			)
			(stroke
				(width 0)
				(type default)
			)
			(fill yes)
			(layer "F.Fab")
		)
		(pad "1" smd rect
			(at -2.400046 -2.275078)
			(size 0.2286 0.6096)
			(layers "F.Cu" "F.Mask" "F.Paste")
			(net "PVCCINFAON_CPU0_VOS2")
		)
		(pad "2" smd rect
			(at -2.400046 -1.82499)
			(size 0.2286 0.6096)
			(layers "F.Cu" "F.Mask" "F.Paste")
			(net "GND")
		)
		(pad "3" smd rect
			(at -2.400046 -1.374902)
			(size 0.2286 0.6096)
			(layers "F.Cu" "F.Mask" "F.Paste")
			(net "PVCCINFAON_CPU0_VDD2")
		)
		(pad "4" smd rect
			(at -2.400046 -0.925068)
			(size 0.2286 0.6096)
			(layers "F.Cu" "F.Mask" "F.Paste")
			(net "PVCCFA_EHV_CPU0_PVCC")
		)
		(pad "5" smd rect
			(at -2.400046 -0.47498)
			(size 0.2286 0.6096)
			(layers "F.Cu" "F.Mask" "F.Paste")
			(net "GND")
		)
		(pad "6" smd rect
			(at -2.400046 -0.024892)
			(size 0.2286 0.6096)
			(layers "F.Cu" "F.Mask" "F.Paste")
			(net "Net_1926")
		)
		(pad "7_9-20_24" smd circle
			(at 0 1.150112)
			(size 0 0)
			(layers "F.Cu" "F.Mask" "F.Paste")
			(net "GND")
		)
		(pad "10_19" smd rect
			(at 0 2.899918)
			(size 0.6096 4.318)
			(layers "F.Cu" "F.Mask" "F.Paste")
			(net "SW_PVCCINFAON_CPU0_SW2")
		)
		(pad "25_29" smd rect
			(at 1.549908 -1.279906 180)
			(size 2.0574 2.3114)
			(layers "F.Cu" "F.Mask" "F.Paste")
			(net "SW_P12V_PVCCINFAON_CPU0_FLT")
		)
		(pad "30" smd rect
			(at 2.05994 -2.899918 270)
			(size 0.2286 0.6096)
			(layers "F.Cu" "F.Mask" "F.Paste")
			(net "SW_P12V_PVCCINFAON_CPU0_FLT")
		)
		(pad "31" smd rect
			(at 1.610106 -2.899918 270)
			(size 0.2286 0.6096)
			(layers "F.Cu" "F.Mask" "F.Paste")
			(net "Net_1925")
		)
		(pad "32" smd rect
			(at 1.160018 -2.899918 270)
			(size 0.2286 0.6096)
			(layers "F.Cu" "F.Mask" "F.Paste")
			(net "SW_PVCCINFAON_CPU0_BOOTR2")
		)
		(pad "33" smd rect
			(at 0.70993 -2.899918 270)
			(size 0.2286 0.6096)
			(layers "F.Cu" "F.Mask" "F.Paste")
			(net "SW_PVCCINFAON_CPU0_BOOT2")
		)
		(pad "34" smd rect
			(at 0.260096 -2.899918 270)
			(size 0.2286 0.6096)
			(layers "F.Cu" "F.Mask" "F.Paste")
			(net "PVCCINFAON_CPU0_APWM2")
		)
		(pad "35" smd rect
			(at -0.189992 -2.899918 270)
			(size 0.2286 0.6096)
			(layers "F.Cu" "F.Mask" "F.Paste")
			(net "PVCCINFAON_CPU0_VDD2")
		)
		(pad "36" smd rect
			(at -0.64008 -2.899918 270)
			(size 0.2286 0.6096)
			(layers "F.Cu" "F.Mask" "F.Paste")
			(net "PVCCINFAON_CPU0_ATSEN")
		)
		(pad "37" smd rect
			(at -1.089914 -2.899918 270)
			(size 0.2286 0.6096)
			(layers "F.Cu" "F.Mask" "F.Paste")
			(net "PVCCINFAON_CPU0_LSET2")
		)
		(pad "38" smd rect
			(at -1.540002 -2.899918 270)
			(size 0.2286 0.6096)
			(layers "F.Cu" "F.Mask" "F.Paste")
			(net "PVCCINFAON_CPU0_ACSP2")
		)
		(pad "39" smd rect
			(at -1.99009 -2.899918 270)
			(size 0.2286 0.6096)
			(layers "F.Cu" "F.Mask" "F.Paste")
			(net "PVCCINFAON_CPU0_VREF")
		)
		(pad "40" smd rect
			(at -0.87503 -1.27508 270)
			(size 1.7526 1.9558)
			(layers "F.Cu" "F.Mask" "F.Paste")
			(net "GND")
		)
		(pad "41" smd rect
			(at -1.525016 0.249936 180)
			(size 0.3048 0.4572)
			(layers "F.Cu" "F.Mask" "F.Paste")
			(net "Net_1927")
		)
		(zone
			(layer "F.Cu")
			(hatch none 0.5)
			(connect_pads
				(clearance 0)
			)
			(min_thickness 0.25)
			(keepout
				(tracks not_allowed)
				(vias allowed)
				(pads allowed)
				(copperpour not_allowed)
				(footprints allowed)
			)
			(placement
				(enabled no)
				(sheetname "")
			)
			(fill
				(thermal_gap 0.5)
				(thermal_bridge_width 0.5)
				(island_removal_mode 0)
			)
			(polygon
				(pts
					(xy 413.009588 -181.95798) (xy 413.540956 -181.95798) (xy 413.758888 -181.740048) (xy 413.758888 -177.168048)
					(xy 413.548576 -176.957736) (xy 413.009588 -176.957736) (xy 413.009588 -177.248058) (xy 413.465264 -177.248058)
					(xy 413.465264 -181.667658) (xy 413.009588 -181.667658)
				)
			)
		)
	)
	(footprint ""
		(layer "F.Cu")
		(at 344.691208 -402.371052 -90)
		(property "Reference" "C1553"
			(at 0 0 270)
			(layer "F.SilkS")
			(hide yes)
			(effects
				(font
					(size 1.27 1.27)
				)
			)
		)
		(property "Value" ""
			(at 0 0 270)
			(layer "F.Fab")
			(effects
				(font
					(size 1.27 1.27)
				)
			)
		)
		(duplicate_pad_numbers_are_jumpers no)
		(fp_line
			(start -0.299974 0.150114)
			(end -0.299974 -0.150114)
			(stroke
				(width 0.1)
				(type default)
			)
			(layer "F.Fab")
		)
		(fp_line
			(start 0.299974 0.150114)
			(end -0.299974 0.150114)
			(stroke
				(width 0.1)
				(type default)
			)
			(layer "F.Fab")
		)
		(fp_line
			(start -0.299974 -0.150114)
			(end 0.299974 -0.150114)
			(stroke
				(width 0.1)
				(type default)
			)
			(layer "F.Fab")
		)
		(fp_line
			(start 0.299974 -0.150114)
			(end 0.299974 0.150114)
			(stroke
				(width 0.1)
				(type default)
			)
			(layer "F.Fab")
		)
		(pad "1" smd rect
			(at -0.2667 0 270)
			(size 0.3048 0.381)
			(layers "F.Cu" "F.Mask" "F.Paste")
			(net "P5E_CPU0_PE4_TX_C_DP<13>")
		)
		(pad "2" smd rect
			(at 0.2667 0 270)
			(size 0.3048 0.381)
			(layers "F.Cu" "F.Mask" "F.Paste")
			(net "P5E_CPU0_PE4_TX_DP<13>")
		)
	)
	(footprint ""
		(layer "F.Cu")
		(at 44.169584 -108.047282)
		(property "Reference" "R2843"
			(at 0 0 0)
			(layer "F.SilkS")
			(hide yes)
			(effects
				(font
					(size 1.27 1.27)
				)
			)
		)
		(property "Value" ""
			(at 0 0 0)
			(layer "F.Fab")
			(effects
				(font
					(size 1.27 1.27)
				)
			)
		)
		(duplicate_pad_numbers_are_jumpers no)
		(fp_line
			(start -0.7874 -0.4064)
			(end 0.7874 -0.4064)
			(stroke
				(width 0.1524)
				(type default)
			)
			(layer "F.SilkS")
		)
		(fp_line
			(start -0.7874 0.4064)
			(end -0.7874 -0.4064)
			(stroke
				(width 0.1524)
				(type default)
			)
			(layer "F.SilkS")
		)
		(fp_line
			(start 0.7874 -0.4064)
			(end 0.7874 0.4064)
			(stroke
				(width 0.1524)
				(type default)
			)
			(layer "F.SilkS")
		)
		(fp_line
			(start 0.7874 0.4064)
			(end -0.7874 0.4064)
			(stroke
				(width 0.1524)
				(type default)
			)
			(layer "F.SilkS")
		)
		(fp_line
			(start -0.67945 -0.305054)
			(end -0.12065 -0.305054)
			(stroke
				(width 0.1)
				(type default)
			)
			(layer "F.Fab")
		)
		(fp_line
			(start -0.67945 0.3048)
			(end -0.67945 -0.305054)
			(stroke
				(width 0.1)
				(type default)
			)
			(layer "F.Fab")
		)
		(fp_line
			(start -0.12065 -0.305054)
			(end -0.12065 -0.2794)
			(stroke
				(width 0.1)
				(type default)
			)
			(layer "F.Fab")
		)
		(fp_line
			(start -0.12065 -0.2794)
			(end 0.12065 -0.2794)
			(stroke
				(width 0.1)
				(type default)
			)
			(layer "F.Fab")
		)
		(fp_line
			(start -0.12065 0.2794)
			(end -0.12065 0.3048)
			(stroke
				(width 0.1)
				(type default)
			)
			(layer "F.Fab")
		)
		(fp_line
			(start -0.12065 0.3048)
			(end -0.67945 0.3048)
			(stroke
				(width 0.1)
				(type default)
			)
			(layer "F.Fab")
		)
		(fp_line
			(start 0.120396 0.2794)
			(end -0.12065 0.2794)
			(stroke
				(width 0.1)
				(type default)
			)
			(layer "F.Fab")
		)
		(fp_line
			(start 0.120396 0.3048)
			(end 0.120396 0.2794)
			(stroke
				(width 0.1)
				(type default)
			)
			(layer "F.Fab")
		)
		(fp_line
			(start 0.12065 -0.3048)
			(end 0.67945 -0.3048)
			(stroke
				(width 0.1)
				(type default)
			)
			(layer "F.Fab")
		)
		(fp_line
			(start 0.12065 -0.2794)
			(end 0.12065 -0.3048)
			(stroke
				(width 0.1)
				(type default)
			)
			(layer "F.Fab")
		)
		(fp_line
			(start 0.67945 -0.3048)
			(end 0.67945 0.3048)
			(stroke
				(width 0.1)
				(type default)
			)
			(layer "F.Fab")
		)
		(fp_line
			(start 0.67945 0.3048)
			(end 0.120396 0.3048)
			(stroke
				(width 0.1)
				(type default)
			)
			(layer "F.Fab")
		)
		(pad "1" smd circle
			(at -0.40005 0)
			(size 0 0)
			(layers "F.Cu" "F.Mask" "F.Paste")
			(net "P3V3_ADC")
		)
		(pad "2" smd circle
			(at 0.40005 0)
			(size 0 0)
			(layers "F.Cu" "F.Mask" "F.Paste")
			(net "GND")
		)
	)
	(footprint ""
		(layer "F.Cu")
		(at 488.85729 -470.49817)
		(property "Reference" "U1_BL"
			(at -1.46685 -1.175258 0)
			(unlocked yes)
			(layer "F.SilkS")
			(effects
				(font
					(size 0.7874 0.5842)
					(thickness 0.1524)
				)
				(justify left)
			)
		)
		(property "Value" ""
			(at 0 0 0)
			(layer "F.Fab")
			(effects
				(font
					(size 1.27 1.27)
				)
			)
		)
		(duplicate_pad_numbers_are_jumpers no)
		(pad "1" smd circle
			(at 0 0)
			(size 0.762 0.762)
			(layers "F.Cu" "F.Mask" "F.Paste")
			(net "Net_8488")
		)
	)
	(footprint ""
		(layer "F.Cu")
		(at 430.600104 -140.595858 180)
		(property "Reference" "R2394"
			(at 0 0 180)
			(layer "F.SilkS")
			(hide yes)
			(effects
				(font
					(size 1.27 1.27)
				)
			)
		)
		(property "Value" ""
			(at 0 0 180)
			(layer "F.Fab")
			(effects
				(font
					(size 1.27 1.27)
				)
			)
		)
		(duplicate_pad_numbers_are_jumpers no)
		(fp_line
			(start 0.7874 0.4064)
			(end -0.7874 0.4064)
			(stroke
				(width 0.1524)
				(type default)
			)
			(layer "F.SilkS")
		)
		(fp_line
			(start 0.7874 -0.4064)
			(end 0.7874 0.4064)
			(stroke
				(width 0.1524)
				(type default)
			)
			(layer "F.SilkS")
		)
		(fp_line
			(start -0.7874 0.4064)
			(end -0.7874 -0.4064)
			(stroke
				(width 0.1524)
				(type default)
			)
			(layer "F.SilkS")
		)
		(fp_line
			(start -0.7874 -0.4064)
			(end 0.7874 -0.4064)
			(stroke
				(width 0.1524)
				(type default)
			)
			(layer "F.SilkS")
		)
		(fp_line
			(start 0.67945 0.3048)
			(end 0.120396 0.3048)
			(stroke
				(width 0.1)
				(type default)
			)
			(layer "F.Fab")
		)
		(fp_line
			(start 0.67945 -0.3048)
			(end 0.67945 0.3048)
			(stroke
				(width 0.1)
				(type default)
			)
			(layer "F.Fab")
		)
		(fp_line
			(start 0.12065 -0.2794)
			(end 0.12065 -0.3048)
			(stroke
				(width 0.1)
				(type default)
			)
			(layer "F.Fab")
		)
		(fp_line
			(start 0.12065 -0.3048)
			(end 0.67945 -0.3048)
			(stroke
				(width 0.1)
				(type default)
			)
			(layer "F.Fab")
		)
		(fp_line
			(start 0.120396 0.3048)
			(end 0.120396 0.2794)
			(stroke
				(width 0.1)
				(type default)
			)
			(layer "F.Fab")
		)
		(fp_line
			(start 0.120396 0.2794)
			(end -0.12065 0.2794)
			(stroke
				(width 0.1)
				(type default)
			)
			(layer "F.Fab")
		)
		(fp_line
			(start -0.12065 0.3048)
			(end -0.67945 0.3048)
			(stroke
				(width 0.1)
				(type default)
			)
			(layer "F.Fab")
		)
		(fp_line
			(start -0.12065 0.2794)
			(end -0.12065 0.3048)
			(stroke
				(width 0.1)
				(type default)
			)
			(layer "F.Fab")
		)
		(fp_line
			(start -0.12065 -0.2794)
			(end 0.12065 -0.2794)
			(stroke
				(width 0.1)
				(type default)
			)
			(layer "F.Fab")
		)
		(fp_line
			(start -0.12065 -0.305054)
			(end -0.12065 -0.2794)
			(stroke
				(width 0.1)
				(type default)
			)
			(layer "F.Fab")
		)
		(fp_line
			(start -0.67945 0.3048)
			(end -0.67945 -0.305054)
			(stroke
				(width 0.1)
				(type default)
			)
			(layer "F.Fab")
		)
		(fp_line
			(start -0.67945 -0.305054)
			(end -0.12065 -0.305054)
			(stroke
				(width 0.1)
				(type default)
			)
			(layer "F.Fab")
		)
		(pad "1" smd circle
			(at -0.40005 0 180)
			(size 0 0)
			(layers "F.Cu" "F.Mask" "F.Paste")
			(net "FM_PVCCFA_EHV_CPU0_EN")
		)
		(pad "2" smd circle
			(at 0.40005 0 180)
			(size 0 0)
			(layers "F.Cu" "F.Mask" "F.Paste")
			(net "PVCCFA_EHV_CPU0_EN_R")
		)
	)
	(footprint ""
		(layer "F.Cu")
		(at 210.560158 -102.93604 180)
		(property "Reference" "C2392"
			(at 0 0 180)
			(layer "F.SilkS")
			(hide yes)
			(effects
				(font
					(size 1.27 1.27)
				)
			)
		)
		(property "Value" ""
			(at 0 0 180)
			(layer "F.Fab")
			(effects
				(font
					(size 1.27 1.27)
				)
			)
		)
		(duplicate_pad_numbers_are_jumpers no)
		(fp_line
			(start 0.7874 0.4064)
			(end -0.7874 0.4064)
			(stroke
				(width 0.1524)
				(type default)
			)
			(layer "F.SilkS")
		)
		(fp_line
			(start 0.7874 -0.4064)
			(end 0.7874 0.4064)
			(stroke
				(width 0.1524)
				(type default)
			)
			(layer "F.SilkS")
		)
		(fp_line
			(start -0.7874 0.4064)
			(end -0.7874 -0.4064)
			(stroke
				(width 0.1524)
				(type default)
			)
			(layer "F.SilkS")
		)
		(fp_line
			(start -0.7874 -0.4064)
			(end 0.7874 -0.4064)
			(stroke
				(width 0.1524)
				(type default)
			)
			(layer "F.SilkS")
		)
		(fp_line
			(start 0.67945 0.3048)
			(end 0.120396 0.3048)
			(stroke
				(width 0.1)
				(type default)
			)
			(layer "F.Fab")
		)
		(fp_line
			(start 0.67945 -0.3048)
			(end 0.67945 0.3048)
			(stroke
				(width 0.1)
				(type default)
			)
			(layer "F.Fab")
		)
		(fp_line
			(start 0.12065 -0.2794)
			(end 0.12065 -0.3048)
			(stroke
				(width 0.1)
				(type default)
			)
			(layer "F.Fab")
		)
		(fp_line
			(start 0.12065 -0.3048)
			(end 0.67945 -0.3048)
			(stroke
				(width 0.1)
				(type default)
			)
			(layer "F.Fab")
		)
		(fp_line
			(start 0.120396 0.3048)
			(end 0.120396 0.2794)
			(stroke
				(width 0.1)
				(type default)
			)
			(layer "F.Fab")
		)
		(fp_line
			(start 0.120396 0.2794)
			(end -0.12065 0.2794)
			(stroke
				(width 0.1)
				(type default)
			)
			(layer "F.Fab")
		)
		(fp_line
			(start -0.12065 0.3048)
			(end -0.67945 0.3048)
			(stroke
				(width 0.1)
				(type default)
			)
			(layer "F.Fab")
		)
		(fp_line
			(start -0.12065 0.2794)
			(end -0.12065 0.3048)
			(stroke
				(width 0.1)
				(type default)
			)
			(layer "F.Fab")
		)
		(fp_line
			(start -0.12065 -0.2794)
			(end 0.12065 -0.2794)
			(stroke
				(width 0.1)
				(type default)
			)
			(layer "F.Fab")
		)
		(fp_line
			(start -0.12065 -0.305054)
			(end -0.12065 -0.2794)
			(stroke
				(width 0.1)
				(type default)
			)
			(layer "F.Fab")
		)
		(fp_line
			(start -0.67945 0.3048)
			(end -0.67945 -0.305054)
			(stroke
				(width 0.1)
				(type default)
			)
			(layer "F.Fab")
		)
		(fp_line
			(start -0.67945 -0.305054)
			(end -0.12065 -0.305054)
			(stroke
				(width 0.1)
				(type default)
			)
			(layer "F.Fab")
		)
		(pad "1" smd circle
			(at -0.40005 0 180)
			(size 0 0)
			(layers "F.Cu" "F.Mask" "F.Paste")
			(net "U205_VDD")
		)
		(pad "2" smd circle
			(at 0.40005 0 180)
			(size 0 0)
			(layers "F.Cu" "F.Mask" "F.Paste")
			(net "GND")
		)
	)
	(footprint ""
		(layer "F.Cu")
		(at 179.2224 -94.338648 90)
		(property "Reference" "R4592"
			(at 0 0 90)
			(layer "F.SilkS")
			(hide yes)
			(effects
				(font
					(size 1.27 1.27)
				)
			)
		)
		(property "Value" ""
			(at 0 0 90)
			(layer "F.Fab")
			(effects
				(font
					(size 1.27 1.27)
				)
			)
		)
		(duplicate_pad_numbers_are_jumpers no)
		(fp_line
			(start 0.7874 -0.4064)
			(end 0.7874 0.4064)
			(stroke
				(width 0.1524)
				(type default)
			)
			(layer "F.SilkS")
		)
		(fp_line
			(start -0.7874 -0.4064)
			(end 0.7874 -0.4064)
			(stroke
				(width 0.1524)
				(type default)
			)
			(layer "F.SilkS")
		)
		(fp_line
			(start 0.7874 0.4064)
			(end -0.7874 0.4064)
			(stroke
				(width 0.1524)
				(type default)
			)
			(layer "F.SilkS")
		)
		(fp_line
			(start -0.7874 0.4064)
			(end -0.7874 -0.4064)
			(stroke
				(width 0.1524)
				(type default)
			)
			(layer "F.SilkS")
		)
		(fp_line
			(start -0.12065 -0.305054)
			(end -0.12065 -0.2794)
			(stroke
				(width 0.1)
				(type default)
			)
			(layer "F.Fab")
		)
		(fp_line
			(start -0.67945 -0.305054)
			(end -0.12065 -0.305054)
			(stroke
				(width 0.1)
				(type default)
			)
			(layer "F.Fab")
		)
		(fp_line
			(start 0.67945 -0.3048)
			(end 0.67945 0.3048)
			(stroke
				(width 0.1)
				(type default)
			)
			(layer "F.Fab")
		)
		(fp_line
			(start 0.12065 -0.3048)
			(end 0.67945 -0.3048)
			(stroke
				(width 0.1)
				(type default)
			)
			(layer "F.Fab")
		)
		(fp_line
			(start 0.12065 -0.2794)
			(end 0.12065 -0.3048)
			(stroke
				(width 0.1)
				(type default)
			)
			(layer "F.Fab")
		)
		(fp_line
			(start -0.12065 -0.2794)
			(end 0.12065 -0.2794)
			(stroke
				(width 0.1)
				(type default)
			)
			(layer "F.Fab")
		)
		(fp_line
			(start 0.120396 0.2794)
			(end -0.12065 0.2794)
			(stroke
				(width 0.1)
				(type default)
			)
			(layer "F.Fab")
		)
		(fp_line
			(start -0.12065 0.2794)
			(end -0.12065 0.3048)
			(stroke
				(width 0.1)
				(type default)
			)
			(layer "F.Fab")
		)
		(fp_line
			(start 0.67945 0.3048)
			(end 0.120396 0.3048)
			(stroke
				(width 0.1)
				(type default)
			)
			(layer "F.Fab")
		)
		(fp_line
			(start 0.120396 0.3048)
			(end 0.120396 0.2794)
			(stroke
				(width 0.1)
				(type default)
			)
			(layer "F.Fab")
		)
		(fp_line
			(start -0.12065 0.3048)
			(end -0.67945 0.3048)
			(stroke
				(width 0.1)
				(type default)
			)
			(layer "F.Fab")
		)
		(fp_line
			(start -0.67945 0.3048)
			(end -0.67945 -0.305054)
			(stroke
				(width 0.1)
				(type default)
			)
			(layer "F.Fab")
		)
		(pad "1" smd rect
			(at -0.40005 0 270)
			(size 0.4572 0.508)
			(layers "F.Cu" "F.Mask" "F.Paste")
			(net "FM_BOARD_BMC_SKU_ID3")
		)
		(pad "2" smd rect
			(at 0.40005 0 270)
			(size 0.4572 0.508)
			(layers "F.Cu" "F.Mask" "F.Paste")
			(net "GND")
		)
	)
	(footprint ""
		(layer "F.Cu")
		(at 285.268162 -16.39443)
		(property "Reference" "R4182"
			(at 0 0 0)
			(layer "F.SilkS")
			(hide yes)
			(effects
				(font
					(size 1.27 1.27)
				)
			)
		)
		(property "Value" ""
			(at 0 0 0)
			(layer "F.Fab")
			(effects
				(font
					(size 1.27 1.27)
				)
			)
		)
		(duplicate_pad_numbers_are_jumpers no)
		(fp_line
			(start -0.7874 -0.4064)
			(end 0.7874 -0.4064)
			(stroke
				(width 0.1524)
				(type default)
			)
			(layer "F.SilkS")
		)
		(fp_line
			(start -0.7874 0.4064)
			(end -0.7874 -0.4064)
			(stroke
				(width 0.1524)
				(type default)
			)
			(layer "F.SilkS")
		)
		(fp_line
			(start 0.7874 -0.4064)
			(end 0.7874 0.4064)
			(stroke
				(width 0.1524)
				(type default)
			)
			(layer "F.SilkS")
		)
		(fp_line
			(start 0.7874 0.4064)
			(end -0.7874 0.4064)
			(stroke
				(width 0.1524)
				(type default)
			)
			(layer "F.SilkS")
		)
		(fp_line
			(start -0.67945 -0.305054)
			(end -0.12065 -0.305054)
			(stroke
				(width 0.1)
				(type default)
			)
			(layer "F.Fab")
		)
		(fp_line
			(start -0.67945 0.3048)
			(end -0.67945 -0.305054)
			(stroke
				(width 0.1)
				(type default)
			)
			(layer "F.Fab")
		)
		(fp_line
			(start -0.12065 -0.305054)
			(end -0.12065 -0.2794)
			(stroke
				(width 0.1)
				(type default)
			)
			(layer "F.Fab")
		)
		(fp_line
			(start -0.12065 -0.2794)
			(end 0.12065 -0.2794)
			(stroke
				(width 0.1)
				(type default)
			)
			(layer "F.Fab")
		)
		(fp_line
			(start -0.12065 0.2794)
			(end -0.12065 0.3048)
			(stroke
				(width 0.1)
				(type default)
			)
			(layer "F.Fab")
		)
		(fp_line
			(start -0.12065 0.3048)
			(end -0.67945 0.3048)
			(stroke
				(width 0.1)
				(type default)
			)
			(layer "F.Fab")
		)
		(fp_line
			(start 0.120396 0.2794)
			(end -0.12065 0.2794)
			(stroke
				(width 0.1)
				(type default)
			)
			(layer "F.Fab")
		)
		(fp_line
			(start 0.120396 0.3048)
			(end 0.120396 0.2794)
			(stroke
				(width 0.1)
				(type default)
			)
			(layer "F.Fab")
		)
		(fp_line
			(start 0.12065 -0.3048)
			(end 0.67945 -0.3048)
			(stroke
				(width 0.1)
				(type default)
			)
			(layer "F.Fab")
		)
		(fp_line
			(start 0.12065 -0.2794)
			(end 0.12065 -0.3048)
			(stroke
				(width 0.1)
				(type default)
			)
			(layer "F.Fab")
		)
		(fp_line
			(start 0.67945 -0.3048)
			(end 0.67945 0.3048)
			(stroke
				(width 0.1)
				(type default)
			)
			(layer "F.Fab")
		)
		(fp_line
			(start 0.67945 0.3048)
			(end 0.120396 0.3048)
			(stroke
				(width 0.1)
				(type default)
			)
			(layer "F.Fab")
		)
		(pad "1" smd circle
			(at -0.40005 0)
			(size 0 0)
			(layers "F.Cu" "F.Mask" "F.Paste")
			(net "SMB_LM75_1_3V3AUX_SDA")
		)
		(pad "2" smd circle
			(at 0.40005 0)
			(size 0 0)
			(layers "F.Cu" "F.Mask" "F.Paste")
			(net "SMB_LM75_1_3V3AUX_SDA_R1")
		)
	)
	(footprint ""
		(layer "F.Cu")
		(at 119.508016 -244.032024 90)
		(property "Reference" "C239"
			(at 0 0 90)
			(layer "F.SilkS")
			(hide yes)
			(effects
				(font
					(size 1.27 1.27)
				)
			)
		)
		(property "Value" ""
			(at 0 0 90)
			(layer "F.Fab")
			(effects
				(font
					(size 1.27 1.27)
				)
			)
		)
		(duplicate_pad_numbers_are_jumpers no)
		(fp_line
			(start 0.7874 -0.4064)
			(end 0.7874 0.4064)
			(stroke
				(width 0.1524)
				(type default)
			)
			(layer "F.SilkS")
		)
		(fp_line
			(start -0.7874 -0.4064)
			(end 0.7874 -0.4064)
			(stroke
				(width 0.1524)
				(type default)
			)
			(layer "F.SilkS")
		)
		(fp_line
			(start 0.7874 0.4064)
			(end -0.7874 0.4064)
			(stroke
				(width 0.1524)
				(type default)
			)
			(layer "F.SilkS")
		)
		(fp_line
			(start -0.7874 0.4064)
			(end -0.7874 -0.4064)
			(stroke
				(width 0.1524)
				(type default)
			)
			(layer "F.SilkS")
		)
		(fp_line
			(start -0.12065 -0.305054)
			(end -0.12065 -0.2794)
			(stroke
				(width 0.1)
				(type default)
			)
			(layer "F.Fab")
		)
		(fp_line
			(start -0.67945 -0.305054)
			(end -0.12065 -0.305054)
			(stroke
				(width 0.1)
				(type default)
			)
			(layer "F.Fab")
		)
		(fp_line
			(start 0.67945 -0.3048)
			(end 0.67945 0.3048)
			(stroke
				(width 0.1)
				(type default)
			)
			(layer "F.Fab")
		)
		(fp_line
			(start 0.12065 -0.3048)
			(end 0.67945 -0.3048)
			(stroke
				(width 0.1)
				(type default)
			)
			(layer "F.Fab")
		)
		(fp_line
			(start 0.12065 -0.2794)
			(end 0.12065 -0.3048)
			(stroke
				(width 0.1)
				(type default)
			)
			(layer "F.Fab")
		)
		(fp_line
			(start -0.12065 -0.2794)
			(end 0.12065 -0.2794)
			(stroke
				(width 0.1)
				(type default)
			)
			(layer "F.Fab")
		)
		(fp_line
			(start 0.120396 0.2794)
			(end -0.12065 0.2794)
			(stroke
				(width 0.1)
				(type default)
			)
			(layer "F.Fab")
		)
		(fp_line
			(start -0.12065 0.2794)
			(end -0.12065 0.3048)
			(stroke
				(width 0.1)
				(type default)
			)
			(layer "F.Fab")
		)
		(fp_line
			(start 0.67945 0.3048)
			(end 0.120396 0.3048)
			(stroke
				(width 0.1)
				(type default)
			)
			(layer "F.Fab")
		)
		(fp_line
			(start 0.120396 0.3048)
			(end 0.120396 0.2794)
			(stroke
				(width 0.1)
				(type default)
			)
			(layer "F.Fab")
		)
		(fp_line
			(start -0.12065 0.3048)
			(end -0.67945 0.3048)
			(stroke
				(width 0.1)
				(type default)
			)
			(layer "F.Fab")
		)
		(fp_line
			(start -0.67945 0.3048)
			(end -0.67945 -0.305054)
			(stroke
				(width 0.1)
				(type default)
			)
			(layer "F.Fab")
		)
		(pad "1" smd circle
			(at -0.40005 0 90)
			(size 0 0)
			(layers "F.Cu" "F.Mask" "F.Paste")
			(net "PVCCIN_CPU1")
		)
		(pad "2" smd circle
			(at 0.40005 0 90)
			(size 0 0)
			(layers "F.Cu" "F.Mask" "F.Paste")
			(net "GND")
		)
	)
	(footprint ""
		(layer "F.Cu")
		(at 451.327012 -30.397958 -90)
		(property "Reference" "PD101"
			(at -0.14224 -1.991868 0)
			(unlocked yes)
			(layer "F.SilkS")
			(effects
				(font
					(size 0.7874 0.5842)
					(thickness 0.1524)
				)
				(justify left)
			)
		)
		(property "Value" ""
			(at 0 0 270)
			(layer "F.Fab")
			(effects
				(font
					(size 1.27 1.27)
				)
			)
		)
		(duplicate_pad_numbers_are_jumpers no)
		(fp_line
			(start -2.250186 0.999998)
			(end 2.631186 0.999998)
			(stroke
				(width 0.1524)
				(type default)
			)
			(layer "F.SilkS")
		)
		(fp_line
			(start 2.631186 0.999998)
			(end 2.631186 -0.999998)
			(stroke
				(width 0.1524)
				(type default)
			)
			(layer "F.SilkS")
		)
		(fp_line
			(start -0.381 0.3302)
			(end -0.381 -0.4318)
			(stroke
				(width 0.1524)
				(type default)
			)
			(layer "F.SilkS")
		)
		(fp_line
			(start -0.381 -0.0508)
			(end -0.6604 -0.0508)
			(stroke
				(width 0.1524)
				(type default)
			)
			(layer "F.SilkS")
		)
		(fp_line
			(start 0.381 -0.0508)
			(end -0.381 0.3302)
			(stroke
				(width 0.1524)
				(type default)
			)
			(layer "F.SilkS")
		)
		(fp_line
			(start 0.381 -0.0508)
			(end 0.635 -0.0508)
			(stroke
				(width 0.1524)
				(type default)
			)
			(layer "F.SilkS")
		)
		(fp_line
			(start -0.381 -0.4318)
			(end 0.381 -0.0508)
			(stroke
				(width 0.1524)
				(type default)
			)
			(layer "F.SilkS")
		)
		(fp_line
			(start 0.381 -0.4318)
			(end 0.381 0.3302)
			(stroke
				(width 0.1524)
				(type default)
			)
			(layer "F.SilkS")
		)
		(fp_line
			(start -2.250186 -0.999998)
			(end -2.250186 0.999998)
			(stroke
				(width 0.1524)
				(type default)
			)
			(layer "F.SilkS")
		)
		(fp_line
			(start 2.631186 -0.999998)
			(end -2.250186 -0.999998)
			(stroke
				(width 0.1524)
				(type default)
			)
			(layer "F.SilkS")
		)
		(fp_rect
			(start 2.6162 1.016)
			(end 2.1844 -0.9652)
			(stroke
				(width 0)
				(type default)
			)
			(fill yes)
			(layer "F.SilkS")
		)
		(fp_line
			(start -1.450086 0.999998)
			(end 1.450086 0.999998)
			(stroke
				(width 0.1)
				(type default)
			)
			(layer "F.Fab")
		)
		(fp_line
			(start 1.450086 0.999998)
			(end 1.450086 -0.999998)
			(stroke
				(width 0.1)
				(type default)
			)
			(layer "F.Fab")
		)
		(fp_line
			(start -1.450086 -0.999998)
			(end -1.450086 0.999998)
			(stroke
				(width 0.1)
				(type default)
			)
			(layer "F.Fab")
		)
		(fp_line
			(start 1.450086 -0.999998)
			(end -1.450086 -0.999998)
			(stroke
				(width 0.1)
				(type default)
			)
			(layer "F.Fab")
		)
		(fp_text user "+"
			(at -4.56057 -0.126238 270)
			(unlocked yes)
			(layer "F.SilkS")
			(effects
				(font
					(size 1.905 1.4224)
					(thickness 0.1524)
				)
				(justify left)
			)
		)
		(fp_text user "-"
			(at 2.4384 -0.22225 270)
			(unlocked yes)
			(layer "F.SilkS")
			(effects
				(font
					(size 1.905 1.4224)
					(thickness 0.1524)
				)
				(justify left)
			)
		)
		(fp_text user "+"
			(at -3.4798 -0.22225 270)
			(unlocked yes)
			(layer "F.Fab")
			(effects
				(font
					(size 1.905 1.4224)
					(thickness 0.1524)
				)
				(justify left)
			)
		)
		(fp_text user "-"
			(at 2.4384 -0.22225 270)
			(unlocked yes)
			(layer "F.Fab")
			(effects
				(font
					(size 1.905 1.4224)
					(thickness 0.1524)
				)
				(justify left)
			)
		)
		(pad "A" smd rect
			(at -1.450086 0 270)
			(size 1.3208 1.4224)
			(layers "F.Cu" "F.Mask" "F.Paste")
			(net "GND")
		)
		(pad "C" smd rect
			(at 1.450086 0 270)
			(size 1.3208 1.4224)
			(layers "F.Cu" "F.Mask" "F.Paste")
			(net "P12V_AUX")
		)
	)
	(footprint ""
		(layer "F.Cu")
		(at 334.174846 -18.79727 -90)
		(property "Reference" "C608"
			(at 0 0 270)
			(layer "F.SilkS")
			(hide yes)
			(effects
				(font
					(size 1.27 1.27)
				)
			)
		)
		(property "Value" ""
			(at 0 0 270)
			(layer "F.Fab")
			(effects
				(font
					(size 1.27 1.27)
				)
			)
		)
		(duplicate_pad_numbers_are_jumpers no)
		(fp_line
			(start -0.7874 0.4064)
			(end -0.7874 -0.4064)
			(stroke
				(width 0.1524)
				(type default)
			)
			(layer "F.SilkS")
		)
		(fp_line
			(start 0.7874 0.4064)
			(end -0.7874 0.4064)
			(stroke
				(width 0.1524)
				(type default)
			)
			(layer "F.SilkS")
		)
		(fp_line
			(start -0.7874 -0.4064)
			(end 0.7874 -0.4064)
			(stroke
				(width 0.1524)
				(type default)
			)
			(layer "F.SilkS")
		)
		(fp_line
			(start 0.7874 -0.4064)
			(end 0.7874 0.4064)
			(stroke
				(width 0.1524)
				(type default)
			)
			(layer "F.SilkS")
		)
		(fp_line
			(start -0.67945 0.3048)
			(end -0.67945 -0.305054)
			(stroke
				(width 0.1)
				(type default)
			)
			(layer "F.Fab")
		)
		(fp_line
			(start -0.12065 0.3048)
			(end -0.67945 0.3048)
			(stroke
				(width 0.1)
				(type default)
			)
			(layer "F.Fab")
		)
		(fp_line
			(start 0.120396 0.3048)
			(end 0.120396 0.2794)
			(stroke
				(width 0.1)
				(type default)
			)
			(layer "F.Fab")
		)
		(fp_line
			(start 0.67945 0.3048)
			(end 0.120396 0.3048)
			(stroke
				(width 0.1)
				(type default)
			)
			(layer "F.Fab")
		)
		(fp_line
			(start -0.12065 0.2794)
			(end -0.12065 0.3048)
			(stroke
				(width 0.1)
				(type default)
			)
			(layer "F.Fab")
		)
		(fp_line
			(start 0.120396 0.2794)
			(end -0.12065 0.2794)
			(stroke
				(width 0.1)
				(type default)
			)
			(layer "F.Fab")
		)
		(fp_line
			(start -0.12065 -0.2794)
			(end 0.12065 -0.2794)
			(stroke
				(width 0.1)
				(type default)
			)
			(layer "F.Fab")
		)
		(fp_line
			(start 0.12065 -0.2794)
			(end 0.12065 -0.3048)
			(stroke
				(width 0.1)
				(type default)
			)
			(layer "F.Fab")
		)
		(fp_line
			(start 0.12065 -0.3048)
			(end 0.67945 -0.3048)
			(stroke
				(width 0.1)
				(type default)
			)
			(layer "F.Fab")
		)
		(fp_line
			(start 0.67945 -0.3048)
			(end 0.67945 0.3048)
			(stroke
				(width 0.1)
				(type default)
			)
			(layer "F.Fab")
		)
		(fp_line
			(start -0.67945 -0.305054)
			(end -0.12065 -0.305054)
			(stroke
				(width 0.1)
				(type default)
			)
			(layer "F.Fab")
		)
		(fp_line
			(start -0.12065 -0.305054)
			(end -0.12065 -0.2794)
			(stroke
				(width 0.1)
				(type default)
			)
			(layer "F.Fab")
		)
		(pad "1" smd circle
			(at -0.40005 0 270)
			(size 0 0)
			(layers "F.Cu" "F.Mask" "F.Paste")
			(net "PGPPA_AUX")
		)
		(pad "2" smd circle
			(at 0.40005 0 270)
			(size 0 0)
			(layers "F.Cu" "F.Mask" "F.Paste")
			(net "GND")
		)
	)
	(footprint ""
		(layer "F.Cu")
		(at 174.635922 -24.601932)
		(property "Reference" "PR4014"
			(at 0 0 0)
			(layer "F.SilkS")
			(hide yes)
			(effects
				(font
					(size 1.27 1.27)
				)
			)
		)
		(property "Value" ""
			(at 0 0 0)
			(layer "F.Fab")
			(effects
				(font
					(size 1.27 1.27)
				)
			)
		)
		(duplicate_pad_numbers_are_jumpers no)
		(fp_line
			(start -1.2954 -0.5842)
			(end 1.2954 -0.5842)
			(stroke
				(width 0.1524)
				(type default)
			)
			(layer "F.SilkS")
		)
		(fp_line
			(start -1.2954 0.5842)
			(end -1.2954 -0.5842)
			(stroke
				(width 0.1524)
				(type default)
			)
			(layer "F.SilkS")
		)
		(fp_line
			(start 1.2954 -0.5842)
			(end 1.2954 0.5842)
			(stroke
				(width 0.1524)
				(type default)
			)
			(layer "F.SilkS")
		)
		(fp_line
			(start 1.2954 0.5842)
			(end -1.2954 0.5842)
			(stroke
				(width 0.1524)
				(type default)
			)
			(layer "F.SilkS")
		)
		(fp_line
			(start -1.1938 -0.406654)
			(end -0.8636 -0.406654)
			(stroke
				(width 0.1)
				(type default)
			)
			(layer "F.Fab")
		)
		(fp_line
			(start -1.1938 0.4064)
			(end -1.1938 -0.406654)
			(stroke
				(width 0.1)
				(type default)
			)
			(layer "F.Fab")
		)
		(fp_line
			(start -0.8636 -0.4572)
			(end 0.8636 -0.4572)
			(stroke
				(width 0.1)
				(type default)
			)
			(layer "F.Fab")
		)
		(fp_line
			(start -0.8636 -0.406654)
			(end -0.8636 -0.4572)
			(stroke
				(width 0.1)
				(type default)
			)
			(layer "F.Fab")
		)
		(fp_line
			(start -0.8636 0.4064)
			(end -1.1938 0.4064)
			(stroke
				(width 0.1)
				(type default)
			)
			(layer "F.Fab")
		)
		(fp_line
			(start -0.8636 0.4318)
			(end -0.8636 0.4064)
			(stroke
				(width 0.1)
				(type default)
			)
			(layer "F.Fab")
		)
		(fp_line
			(start -0.8636 0.4572)
			(end -0.8636 0.4318)
			(stroke
				(width 0.1)
				(type default)
			)
			(layer "F.Fab")
		)
		(fp_line
			(start 0.8636 -0.4572)
			(end 0.8636 -0.406654)
			(stroke
				(width 0.1)
				(type default)
			)
			(layer "F.Fab")
		)
		(fp_line
			(start 0.8636 -0.406654)
			(end 1.1938 -0.406654)
			(stroke
				(width 0.1)
				(type default)
			)
			(layer "F.Fab")
		)
		(fp_line
			(start 0.8636 0.4064)
			(end 0.8636 0.4572)
			(stroke
				(width 0.1)
				(type default)
			)
			(layer "F.Fab")
		)
		(fp_line
			(start 0.8636 0.4572)
			(end -0.8636 0.4572)
			(stroke
				(width 0.1)
				(type default)
			)
			(layer "F.Fab")
		)
		(fp_line
			(start 1.1938 -0.406654)
			(end 1.1938 0.4064)
			(stroke
				(width 0.1)
				(type default)
			)
			(layer "F.Fab")
		)
		(fp_line
			(start 1.1938 0.4064)
			(end 0.8636 0.4064)
			(stroke
				(width 0.1)
				(type default)
			)
			(layer "F.Fab")
		)
		(pad "1" smd rect
			(at -0.7366 0 270)
			(size 0.7112 0.8128)
			(layers "F.Cu" "F.Mask" "F.Paste")
			(net "P12V_AUX")
		)
		(pad "2" smd rect
			(at 0.7366 0 270)
			(size 0.7112 0.8128)
			(layers "F.Cu" "F.Mask" "F.Paste")
			(net "P12V_SCM_AVIN_PD")
		)
	)
	(footprint ""
		(layer "F.Cu")
		(at 226.733608 -408.887422)
		(property "Reference" "PR3989"
			(at 0 0 0)
			(layer "F.SilkS")
			(hide yes)
			(effects
				(font
					(size 1.27 1.27)
				)
			)
		)
		(property "Value" ""
			(at 0 0 0)
			(layer "F.Fab")
			(effects
				(font
					(size 1.27 1.27)
				)
			)
		)
		(duplicate_pad_numbers_are_jumpers no)
		(fp_line
			(start -0.7874 -0.4064)
			(end 0.7874 -0.4064)
			(stroke
				(width 0.1524)
				(type default)
			)
			(layer "F.SilkS")
		)
		(fp_line
			(start -0.7874 0.4064)
			(end -0.7874 -0.4064)
			(stroke
				(width 0.1524)
				(type default)
			)
			(layer "F.SilkS")
		)
		(fp_line
			(start 0.7874 -0.4064)
			(end 0.7874 0.4064)
			(stroke
				(width 0.1524)
				(type default)
			)
			(layer "F.SilkS")
		)
		(fp_line
			(start 0.7874 0.4064)
			(end -0.7874 0.4064)
			(stroke
				(width 0.1524)
				(type default)
			)
			(layer "F.SilkS")
		)
		(fp_line
			(start -0.67945 -0.305054)
			(end -0.12065 -0.305054)
			(stroke
				(width 0.1)
				(type default)
			)
			(layer "F.Fab")
		)
		(fp_line
			(start -0.67945 0.3048)
			(end -0.67945 -0.305054)
			(stroke
				(width 0.1)
				(type default)
			)
			(layer "F.Fab")
		)
		(fp_line
			(start -0.12065 -0.305054)
			(end -0.12065 -0.2794)
			(stroke
				(width 0.1)
				(type default)
			)
			(layer "F.Fab")
		)
		(fp_line
			(start -0.12065 -0.2794)
			(end 0.12065 -0.2794)
			(stroke
				(width 0.1)
				(type default)
			)
			(layer "F.Fab")
		)
		(fp_line
			(start -0.12065 0.2794)
			(end -0.12065 0.3048)
			(stroke
				(width 0.1)
				(type default)
			)
			(layer "F.Fab")
		)
		(fp_line
			(start -0.12065 0.3048)
			(end -0.67945 0.3048)
			(stroke
				(width 0.1)
				(type default)
			)
			(layer "F.Fab")
		)
		(fp_line
			(start 0.120396 0.2794)
			(end -0.12065 0.2794)
			(stroke
				(width 0.1)
				(type default)
			)
			(layer "F.Fab")
		)
		(fp_line
			(start 0.120396 0.3048)
			(end 0.120396 0.2794)
			(stroke
				(width 0.1)
				(type default)
			)
			(layer "F.Fab")
		)
		(fp_line
			(start 0.12065 -0.3048)
			(end 0.67945 -0.3048)
			(stroke
				(width 0.1)
				(type default)
			)
			(layer "F.Fab")
		)
		(fp_line
			(start 0.12065 -0.2794)
			(end 0.12065 -0.3048)
			(stroke
				(width 0.1)
				(type default)
			)
			(layer "F.Fab")
		)
		(fp_line
			(start 0.67945 -0.3048)
			(end 0.67945 0.3048)
			(stroke
				(width 0.1)
				(type default)
			)
			(layer "F.Fab")
		)
		(fp_line
			(start 0.67945 0.3048)
			(end 0.120396 0.3048)
			(stroke
				(width 0.1)
				(type default)
			)
			(layer "F.Fab")
		)
		(pad "1" smd circle
			(at -0.40005 0)
			(size 0 0)
			(layers "F.Cu" "F.Mask" "F.Paste")
			(net "HSC_SCREF")
		)
		(pad "2" smd circle
			(at 0.40005 0)
			(size 0 0)
			(layers "F.Cu" "F.Mask" "F.Paste")
			(net "HSC_SCREF_4")
		)
	)
	(footprint ""
		(layer "F.Cu")
		(at 36.947348 -128.659382)
		(property "Reference" "R2574"
			(at 0 0 0)
			(layer "F.SilkS")
			(hide yes)
			(effects
				(font
					(size 1.27 1.27)
				)
			)
		)
		(property "Value" ""
			(at 0 0 0)
			(layer "F.Fab")
			(effects
				(font
					(size 1.27 1.27)
				)
			)
		)
		(duplicate_pad_numbers_are_jumpers no)
		(fp_line
			(start -0.7874 -0.4064)
			(end 0.7874 -0.4064)
			(stroke
				(width 0.1524)
				(type default)
			)
			(layer "F.SilkS")
		)
		(fp_line
			(start -0.7874 0.4064)
			(end -0.7874 -0.4064)
			(stroke
				(width 0.1524)
				(type default)
			)
			(layer "F.SilkS")
		)
		(fp_line
			(start 0.7874 -0.4064)
			(end 0.7874 0.4064)
			(stroke
				(width 0.1524)
				(type default)
			)
			(layer "F.SilkS")
		)
		(fp_line
			(start 0.7874 0.4064)
			(end -0.7874 0.4064)
			(stroke
				(width 0.1524)
				(type default)
			)
			(layer "F.SilkS")
		)
		(fp_line
			(start -0.67945 -0.305054)
			(end -0.12065 -0.305054)
			(stroke
				(width 0.1)
				(type default)
			)
			(layer "F.Fab")
		)
		(fp_line
			(start -0.67945 0.3048)
			(end -0.67945 -0.305054)
			(stroke
				(width 0.1)
				(type default)
			)
			(layer "F.Fab")
		)
		(fp_line
			(start -0.12065 -0.305054)
			(end -0.12065 -0.2794)
			(stroke
				(width 0.1)
				(type default)
			)
			(layer "F.Fab")
		)
		(fp_line
			(start -0.12065 -0.2794)
			(end 0.12065 -0.2794)
			(stroke
				(width 0.1)
				(type default)
			)
			(layer "F.Fab")
		)
		(fp_line
			(start -0.12065 0.2794)
			(end -0.12065 0.3048)
			(stroke
				(width 0.1)
				(type default)
			)
			(layer "F.Fab")
		)
		(fp_line
			(start -0.12065 0.3048)
			(end -0.67945 0.3048)
			(stroke
				(width 0.1)
				(type default)
			)
			(layer "F.Fab")
		)
		(fp_line
			(start 0.120396 0.2794)
			(end -0.12065 0.2794)
			(stroke
				(width 0.1)
				(type default)
			)
			(layer "F.Fab")
		)
		(fp_line
			(start 0.120396 0.3048)
			(end 0.120396 0.2794)
			(stroke
				(width 0.1)
				(type default)
			)
			(layer "F.Fab")
		)
		(fp_line
			(start 0.12065 -0.3048)
			(end 0.67945 -0.3048)
			(stroke
				(width 0.1)
				(type default)
			)
			(layer "F.Fab")
		)
		(fp_line
			(start 0.12065 -0.2794)
			(end 0.12065 -0.3048)
			(stroke
				(width 0.1)
				(type default)
			)
			(layer "F.Fab")
		)
		(fp_line
			(start 0.67945 -0.3048)
			(end 0.67945 0.3048)
			(stroke
				(width 0.1)
				(type default)
			)
			(layer "F.Fab")
		)
		(fp_line
			(start 0.67945 0.3048)
			(end 0.120396 0.3048)
			(stroke
				(width 0.1)
				(type default)
			)
			(layer "F.Fab")
		)
		(pad "1" smd circle
			(at -0.40005 0)
			(size 0 0)
			(layers "F.Cu" "F.Mask" "F.Paste")
			(net "IRQ_PVCCFA_CPU1_VRHOT_N")
		)
		(pad "2" smd circle
			(at 0.40005 0)
			(size 0 0)
			(layers "F.Cu" "F.Mask" "F.Paste")
			(net "IRQ_PVCCFA_CPU1_VRHOT_R_N")
		)
	)
	(footprint ""
		(layer "F.Cu")
		(at 424.204892 -381.345948)
		(property "Reference" "R2828"
			(at 0 0 0)
			(layer "F.SilkS")
			(hide yes)
			(effects
				(font
					(size 1.27 1.27)
				)
			)
		)
		(property "Value" ""
			(at 0 0 0)
			(layer "F.Fab")
			(effects
				(font
					(size 1.27 1.27)
				)
			)
		)
		(duplicate_pad_numbers_are_jumpers no)
		(fp_line
			(start -0.7874 -0.4064)
			(end 0.7874 -0.4064)
			(stroke
				(width 0.1524)
				(type default)
			)
			(layer "F.SilkS")
		)
		(fp_line
			(start -0.7874 0.4064)
			(end -0.7874 -0.4064)
			(stroke
				(width 0.1524)
				(type default)
			)
			(layer "F.SilkS")
		)
		(fp_line
			(start 0.7874 -0.4064)
			(end 0.7874 0.4064)
			(stroke
				(width 0.1524)
				(type default)
			)
			(layer "F.SilkS")
		)
		(fp_line
			(start 0.7874 0.4064)
			(end -0.7874 0.4064)
			(stroke
				(width 0.1524)
				(type default)
			)
			(layer "F.SilkS")
		)
		(fp_line
			(start -0.67945 -0.305054)
			(end -0.12065 -0.305054)
			(stroke
				(width 0.1)
				(type default)
			)
			(layer "F.Fab")
		)
		(fp_line
			(start -0.67945 0.3048)
			(end -0.67945 -0.305054)
			(stroke
				(width 0.1)
				(type default)
			)
			(layer "F.Fab")
		)
		(fp_line
			(start -0.12065 -0.305054)
			(end -0.12065 -0.2794)
			(stroke
				(width 0.1)
				(type default)
			)
			(layer "F.Fab")
		)
		(fp_line
			(start -0.12065 -0.2794)
			(end 0.12065 -0.2794)
			(stroke
				(width 0.1)
				(type default)
			)
			(layer "F.Fab")
		)
		(fp_line
			(start -0.12065 0.2794)
			(end -0.12065 0.3048)
			(stroke
				(width 0.1)
				(type default)
			)
			(layer "F.Fab")
		)
		(fp_line
			(start -0.12065 0.3048)
			(end -0.67945 0.3048)
			(stroke
				(width 0.1)
				(type default)
			)
			(layer "F.Fab")
		)
		(fp_line
			(start 0.120396 0.2794)
			(end -0.12065 0.2794)
			(stroke
				(width 0.1)
				(type default)
			)
			(layer "F.Fab")
		)
		(fp_line
			(start 0.120396 0.3048)
			(end 0.120396 0.2794)
			(stroke
				(width 0.1)
				(type default)
			)
			(layer "F.Fab")
		)
		(fp_line
			(start 0.12065 -0.3048)
			(end 0.67945 -0.3048)
			(stroke
				(width 0.1)
				(type default)
			)
			(layer "F.Fab")
		)
		(fp_line
			(start 0.12065 -0.2794)
			(end 0.12065 -0.3048)
			(stroke
				(width 0.1)
				(type default)
			)
			(layer "F.Fab")
		)
		(fp_line
			(start 0.67945 -0.3048)
			(end 0.67945 0.3048)
			(stroke
				(width 0.1)
				(type default)
			)
			(layer "F.Fab")
		)
		(fp_line
			(start 0.67945 0.3048)
			(end 0.120396 0.3048)
			(stroke
				(width 0.1)
				(type default)
			)
			(layer "F.Fab")
		)
		(pad "1" smd circle
			(at -0.40005 0)
			(size 0 0)
			(layers "F.Cu" "F.Mask" "F.Paste")
			(net "P3V3_AUX")
		)
		(pad "2" smd circle
			(at 0.40005 0)
			(size 0 0)
			(layers "F.Cu" "F.Mask" "F.Paste")
			(net "RST_BMC_FROM_SWB_N")
		)
	)
	(footprint ""
		(layer "F.Cu")
		(at 300.260258 -367.378996 -90)
		(property "Reference" "PC607"
			(at 0 0 270)
			(layer "F.SilkS")
			(hide yes)
			(effects
				(font
					(size 1.27 1.27)
				)
			)
		)
		(property "Value" ""
			(at 0 0 270)
			(layer "F.Fab")
			(effects
				(font
					(size 1.27 1.27)
				)
			)
		)
		(duplicate_pad_numbers_are_jumpers no)
		(fp_line
			(start -0.7874 0.4064)
			(end -0.7874 -0.4064)
			(stroke
				(width 0.1524)
				(type default)
			)
			(layer "F.SilkS")
		)
		(fp_line
			(start 0.7874 0.4064)
			(end -0.7874 0.4064)
			(stroke
				(width 0.1524)
				(type default)
			)
			(layer "F.SilkS")
		)
		(fp_line
			(start -0.7874 -0.4064)
			(end 0.7874 -0.4064)
			(stroke
				(width 0.1524)
				(type default)
			)
			(layer "F.SilkS")
		)
		(fp_line
			(start 0.7874 -0.4064)
			(end 0.7874 0.4064)
			(stroke
				(width 0.1524)
				(type default)
			)
			(layer "F.SilkS")
		)
		(fp_line
			(start -0.67945 0.3048)
			(end -0.67945 -0.305054)
			(stroke
				(width 0.1)
				(type default)
			)
			(layer "F.Fab")
		)
		(fp_line
			(start -0.12065 0.3048)
			(end -0.67945 0.3048)
			(stroke
				(width 0.1)
				(type default)
			)
			(layer "F.Fab")
		)
		(fp_line
			(start 0.120396 0.3048)
			(end 0.120396 0.2794)
			(stroke
				(width 0.1)
				(type default)
			)
			(layer "F.Fab")
		)
		(fp_line
			(start 0.67945 0.3048)
			(end 0.120396 0.3048)
			(stroke
				(width 0.1)
				(type default)
			)
			(layer "F.Fab")
		)
		(fp_line
			(start -0.12065 0.2794)
			(end -0.12065 0.3048)
			(stroke
				(width 0.1)
				(type default)
			)
			(layer "F.Fab")
		)
		(fp_line
			(start 0.120396 0.2794)
			(end -0.12065 0.2794)
			(stroke
				(width 0.1)
				(type default)
			)
			(layer "F.Fab")
		)
		(fp_line
			(start -0.12065 -0.2794)
			(end 0.12065 -0.2794)
			(stroke
				(width 0.1)
				(type default)
			)
			(layer "F.Fab")
		)
		(fp_line
			(start 0.12065 -0.2794)
			(end 0.12065 -0.3048)
			(stroke
				(width 0.1)
				(type default)
			)
			(layer "F.Fab")
		)
		(fp_line
			(start 0.12065 -0.3048)
			(end 0.67945 -0.3048)
			(stroke
				(width 0.1)
				(type default)
			)
			(layer "F.Fab")
		)
		(fp_line
			(start 0.67945 -0.3048)
			(end 0.67945 0.3048)
			(stroke
				(width 0.1)
				(type default)
			)
			(layer "F.Fab")
		)
		(fp_line
			(start -0.67945 -0.305054)
			(end -0.12065 -0.305054)
			(stroke
				(width 0.1)
				(type default)
			)
			(layer "F.Fab")
		)
		(fp_line
			(start -0.12065 -0.305054)
			(end -0.12065 -0.2794)
			(stroke
				(width 0.1)
				(type default)
			)
			(layer "F.Fab")
		)
		(pad "1" smd circle
			(at -0.40005 0 270)
			(size 0 0)
			(layers "F.Cu" "F.Mask" "F.Paste")
			(net "SW_PVCCFA_EHV_FIVRA_CPU0_BOOT2_")
		)
		(pad "2" smd circle
			(at 0.40005 0 270)
			(size 0 0)
			(layers "F.Cu" "F.Mask" "F.Paste")
			(net "SW_PVCCFA_EHV_FIVRA_CPU0_BOOTR2")
		)
	)
	(footprint ""
		(layer "F.Cu")
		(at 425.163488 -109.12983 90)
		(property "Reference" "PC2091"
			(at 0 0 90)
			(layer "F.SilkS")
			(hide yes)
			(effects
				(font
					(size 1.27 1.27)
				)
			)
		)
		(property "Value" ""
			(at 0 0 90)
			(layer "F.Fab")
			(effects
				(font
					(size 1.27 1.27)
				)
			)
		)
		(duplicate_pad_numbers_are_jumpers no)
		(fp_line
			(start 0.7874 -0.4064)
			(end 0.7874 0.4064)
			(stroke
				(width 0.1524)
				(type default)
			)
			(layer "F.SilkS")
		)
		(fp_line
			(start -0.7874 -0.4064)
			(end 0.7874 -0.4064)
			(stroke
				(width 0.1524)
				(type default)
			)
			(layer "F.SilkS")
		)
		(fp_line
			(start 0.7874 0.4064)
			(end -0.7874 0.4064)
			(stroke
				(width 0.1524)
				(type default)
			)
			(layer "F.SilkS")
		)
		(fp_line
			(start -0.7874 0.4064)
			(end -0.7874 -0.4064)
			(stroke
				(width 0.1524)
				(type default)
			)
			(layer "F.SilkS")
		)
		(fp_line
			(start -0.12065 -0.305054)
			(end -0.12065 -0.2794)
			(stroke
				(width 0.1)
				(type default)
			)
			(layer "F.Fab")
		)
		(fp_line
			(start -0.67945 -0.305054)
			(end -0.12065 -0.305054)
			(stroke
				(width 0.1)
				(type default)
			)
			(layer "F.Fab")
		)
		(fp_line
			(start 0.67945 -0.3048)
			(end 0.67945 0.3048)
			(stroke
				(width 0.1)
				(type default)
			)
			(layer "F.Fab")
		)
		(fp_line
			(start 0.12065 -0.3048)
			(end 0.67945 -0.3048)
			(stroke
				(width 0.1)
				(type default)
			)
			(layer "F.Fab")
		)
		(fp_line
			(start 0.12065 -0.2794)
			(end 0.12065 -0.3048)
			(stroke
				(width 0.1)
				(type default)
			)
			(layer "F.Fab")
		)
		(fp_line
			(start -0.12065 -0.2794)
			(end 0.12065 -0.2794)
			(stroke
				(width 0.1)
				(type default)
			)
			(layer "F.Fab")
		)
		(fp_line
			(start 0.120396 0.2794)
			(end -0.12065 0.2794)
			(stroke
				(width 0.1)
				(type default)
			)
			(layer "F.Fab")
		)
		(fp_line
			(start -0.12065 0.2794)
			(end -0.12065 0.3048)
			(stroke
				(width 0.1)
				(type default)
			)
			(layer "F.Fab")
		)
		(fp_line
			(start 0.67945 0.3048)
			(end 0.120396 0.3048)
			(stroke
				(width 0.1)
				(type default)
			)
			(layer "F.Fab")
		)
		(fp_line
			(start 0.120396 0.3048)
			(end 0.120396 0.2794)
			(stroke
				(width 0.1)
				(type default)
			)
			(layer "F.Fab")
		)
		(fp_line
			(start -0.12065 0.3048)
			(end -0.67945 0.3048)
			(stroke
				(width 0.1)
				(type default)
			)
			(layer "F.Fab")
		)
		(fp_line
			(start -0.67945 0.3048)
			(end -0.67945 -0.305054)
			(stroke
				(width 0.1)
				(type default)
			)
			(layer "F.Fab")
		)
		(pad "1" smd circle
			(at -0.40005 0 90)
			(size 0 0)
			(layers "F.Cu" "F.Mask" "F.Paste")
			(net "P3V3_OCP_SFF_R")
		)
		(pad "2" smd circle
			(at 0.40005 0 90)
			(size 0 0)
			(layers "F.Cu" "F.Mask" "F.Paste")
			(net "GND")
		)
	)
	(footprint ""
		(layer "F.Cu")
		(at 150.83028 -31.829756 180)
		(property "Reference" "R3305"
			(at 0 0 180)
			(layer "F.SilkS")
			(hide yes)
			(effects
				(font
					(size 1.27 1.27)
				)
			)
		)
		(property "Value" ""
			(at 0 0 180)
			(layer "F.Fab")
			(effects
				(font
					(size 1.27 1.27)
				)
			)
		)
		(duplicate_pad_numbers_are_jumpers no)
		(fp_line
			(start 0.7874 0.4064)
			(end -0.7874 0.4064)
			(stroke
				(width 0.1524)
				(type default)
			)
			(layer "F.SilkS")
		)
		(fp_line
			(start 0.7874 -0.4064)
			(end 0.7874 0.4064)
			(stroke
				(width 0.1524)
				(type default)
			)
			(layer "F.SilkS")
		)
		(fp_line
			(start -0.7874 0.4064)
			(end -0.7874 -0.4064)
			(stroke
				(width 0.1524)
				(type default)
			)
			(layer "F.SilkS")
		)
		(fp_line
			(start -0.7874 -0.4064)
			(end 0.7874 -0.4064)
			(stroke
				(width 0.1524)
				(type default)
			)
			(layer "F.SilkS")
		)
		(fp_line
			(start 0.67945 0.3048)
			(end 0.120396 0.3048)
			(stroke
				(width 0.1)
				(type default)
			)
			(layer "F.Fab")
		)
		(fp_line
			(start 0.67945 -0.3048)
			(end 0.67945 0.3048)
			(stroke
				(width 0.1)
				(type default)
			)
			(layer "F.Fab")
		)
		(fp_line
			(start 0.12065 -0.2794)
			(end 0.12065 -0.3048)
			(stroke
				(width 0.1)
				(type default)
			)
			(layer "F.Fab")
		)
		(fp_line
			(start 0.12065 -0.3048)
			(end 0.67945 -0.3048)
			(stroke
				(width 0.1)
				(type default)
			)
			(layer "F.Fab")
		)
		(fp_line
			(start 0.120396 0.3048)
			(end 0.120396 0.2794)
			(stroke
				(width 0.1)
				(type default)
			)
			(layer "F.Fab")
		)
		(fp_line
			(start 0.120396 0.2794)
			(end -0.12065 0.2794)
			(stroke
				(width 0.1)
				(type default)
			)
			(layer "F.Fab")
		)
		(fp_line
			(start -0.12065 0.3048)
			(end -0.67945 0.3048)
			(stroke
				(width 0.1)
				(type default)
			)
			(layer "F.Fab")
		)
		(fp_line
			(start -0.12065 0.2794)
			(end -0.12065 0.3048)
			(stroke
				(width 0.1)
				(type default)
			)
			(layer "F.Fab")
		)
		(fp_line
			(start -0.12065 -0.2794)
			(end 0.12065 -0.2794)
			(stroke
				(width 0.1)
				(type default)
			)
			(layer "F.Fab")
		)
		(fp_line
			(start -0.12065 -0.305054)
			(end -0.12065 -0.2794)
			(stroke
				(width 0.1)
				(type default)
			)
			(layer "F.Fab")
		)
		(fp_line
			(start -0.67945 0.3048)
			(end -0.67945 -0.305054)
			(stroke
				(width 0.1)
				(type default)
			)
			(layer "F.Fab")
		)
		(fp_line
			(start -0.67945 -0.305054)
			(end -0.12065 -0.305054)
			(stroke
				(width 0.1)
				(type default)
			)
			(layer "F.Fab")
		)
		(pad "1" smd circle
			(at -0.40005 0 180)
			(size 0 0)
			(layers "F.Cu" "F.Mask" "F.Paste")
			(net "OCP_SFF_RBT_ARB_IN_MUX1")
		)
		(pad "2" smd circle
			(at 0.40005 0 180)
			(size 0 0)
			(layers "F.Cu" "F.Mask" "F.Paste")
			(net "OCP_SFF_RBT_ARB_IN_MUX1_R")
		)
	)
	(footprint ""
		(layer "F.Cu")
		(at 110.901226 -315.66739 90)
		(property "Reference" "PC586"
			(at 0 0 90)
			(layer "F.SilkS")
			(hide yes)
			(effects
				(font
					(size 1.27 1.27)
				)
			)
		)
		(property "Value" ""
			(at 0 0 90)
			(layer "F.Fab")
			(effects
				(font
					(size 1.27 1.27)
				)
			)
		)
		(duplicate_pad_numbers_are_jumpers no)
		(fp_line
			(start 2.750058 0.999998)
			(end -2.750058 0.999998)
			(stroke
				(width 0.1524)
				(type default)
			)
			(layer "F.SilkS")
		)
		(fp_circle
			(center 0 0.999998)
			(end 0 3.750056)
			(stroke
				(width 0.1524)
				(type default)
			)
			(fill no)
			(layer "F.SilkS")
		)
		(fp_poly
			(pts
				(arc
					(start 2.750058 0.999998)
					(mid 0 3.750056)
					(end -2.750058 0.999998)
				)
			)
			(stroke
				(width 0)
				(type default)
			)
			(fill yes)
			(layer "F.SilkS")
		)
		(fp_circle
			(center 0 0.999998)
			(end 0 3.750056)
			(stroke
				(width 0.1)
				(type default)
			)
			(fill no)
			(layer "F.Fab")
		)
		(pad "1" thru_hole rect
			(at 0 0 90)
			(size 1.5748 1.5748)
			(drill 1.0668)
			(layers "*.Cu" "*.Mask")
			(remove_unused_layers no)
			(net "PVCCIN_CPU1")
			(clearance 0)
			(padstack
				(mode front_inner_back)
				(layer "Inner"
					(shape circle)
					(size 1.5748 1.5748)
					(clearance 0)
				)
				(layer "B.Cu"
					(shape rect)
					(size 1.5748 1.5748)
					(clearance 0)
				)
			)
		)
		(pad "2" thru_hole circle
			(at 0 1.999996 90)
			(size 1.5748 1.5748)
			(drill 1.0668)
			(layers "*.Cu" "*.Mask")
			(remove_unused_layers no)
			(net "GND")
			(clearance 0)
		)
	)
	(footprint ""
		(layer "F.Cu")
		(at 111.332772 -137.854182)
		(property "Reference" "R1822"
			(at 0 0 0)
			(layer "F.SilkS")
			(hide yes)
			(effects
				(font
					(size 1.27 1.27)
				)
			)
		)
		(property "Value" ""
			(at 0 0 0)
			(layer "F.Fab")
			(effects
				(font
					(size 1.27 1.27)
				)
			)
		)
		(duplicate_pad_numbers_are_jumpers no)
		(fp_line
			(start -0.7874 -0.4064)
			(end 0.7874 -0.4064)
			(stroke
				(width 0.1524)
				(type default)
			)
			(layer "F.SilkS")
		)
		(fp_line
			(start -0.7874 0.4064)
			(end -0.7874 -0.4064)
			(stroke
				(width 0.1524)
				(type default)
			)
			(layer "F.SilkS")
		)
		(fp_line
			(start 0.7874 -0.4064)
			(end 0.7874 0.4064)
			(stroke
				(width 0.1524)
				(type default)
			)
			(layer "F.SilkS")
		)
		(fp_line
			(start 0.7874 0.4064)
			(end -0.7874 0.4064)
			(stroke
				(width 0.1524)
				(type default)
			)
			(layer "F.SilkS")
		)
		(fp_line
			(start -0.67945 -0.305054)
			(end -0.12065 -0.305054)
			(stroke
				(width 0.1)
				(type default)
			)
			(layer "F.Fab")
		)
		(fp_line
			(start -0.67945 0.3048)
			(end -0.67945 -0.305054)
			(stroke
				(width 0.1)
				(type default)
			)
			(layer "F.Fab")
		)
		(fp_line
			(start -0.12065 -0.305054)
			(end -0.12065 -0.2794)
			(stroke
				(width 0.1)
				(type default)
			)
			(layer "F.Fab")
		)
		(fp_line
			(start -0.12065 -0.2794)
			(end 0.12065 -0.2794)
			(stroke
				(width 0.1)
				(type default)
			)
			(layer "F.Fab")
		)
		(fp_line
			(start -0.12065 0.2794)
			(end -0.12065 0.3048)
			(stroke
				(width 0.1)
				(type default)
			)
			(layer "F.Fab")
		)
		(fp_line
			(start -0.12065 0.3048)
			(end -0.67945 0.3048)
			(stroke
				(width 0.1)
				(type default)
			)
			(layer "F.Fab")
		)
		(fp_line
			(start 0.120396 0.2794)
			(end -0.12065 0.2794)
			(stroke
				(width 0.1)
				(type default)
			)
			(layer "F.Fab")
		)
		(fp_line
			(start 0.120396 0.3048)
			(end 0.120396 0.2794)
			(stroke
				(width 0.1)
				(type default)
			)
			(layer "F.Fab")
		)
		(fp_line
			(start 0.12065 -0.3048)
			(end 0.67945 -0.3048)
			(stroke
				(width 0.1)
				(type default)
			)
			(layer "F.Fab")
		)
		(fp_line
			(start 0.12065 -0.2794)
			(end 0.12065 -0.3048)
			(stroke
				(width 0.1)
				(type default)
			)
			(layer "F.Fab")
		)
		(fp_line
			(start 0.67945 -0.3048)
			(end 0.67945 0.3048)
			(stroke
				(width 0.1)
				(type default)
			)
			(layer "F.Fab")
		)
		(fp_line
			(start 0.67945 0.3048)
			(end 0.120396 0.3048)
			(stroke
				(width 0.1)
				(type default)
			)
			(layer "F.Fab")
		)
		(pad "1" smd circle
			(at -0.40005 0)
			(size 0 0)
			(layers "F.Cu" "F.Mask" "F.Paste")
			(net "P3V3_AUX")
		)
		(pad "2" smd circle
			(at 0.40005 0)
			(size 0 0)
			(layers "F.Cu" "F.Mask" "F.Paste")
			(net "RST_SMB_SWITCH_N")
		)
	)
	(footprint ""
		(layer "F.Cu")
		(at 129.159 -56.733948 180)
		(property "Reference" "R4626"
			(at 0 0 180)
			(layer "F.SilkS")
			(hide yes)
			(effects
				(font
					(size 1.27 1.27)
				)
			)
		)
		(property "Value" ""
			(at 0 0 180)
			(layer "F.Fab")
			(effects
				(font
					(size 1.27 1.27)
				)
			)
		)
		(duplicate_pad_numbers_are_jumpers no)
		(fp_line
			(start 0.7874 0.4064)
			(end -0.7874 0.4064)
			(stroke
				(width 0.1524)
				(type default)
			)
			(layer "F.SilkS")
		)
		(fp_line
			(start 0.7874 -0.4064)
			(end 0.7874 0.4064)
			(stroke
				(width 0.1524)
				(type default)
			)
			(layer "F.SilkS")
		)
		(fp_line
			(start -0.7874 0.4064)
			(end -0.7874 -0.4064)
			(stroke
				(width 0.1524)
				(type default)
			)
			(layer "F.SilkS")
		)
		(fp_line
			(start -0.7874 -0.4064)
			(end 0.7874 -0.4064)
			(stroke
				(width 0.1524)
				(type default)
			)
			(layer "F.SilkS")
		)
		(fp_line
			(start 0.67945 0.3048)
			(end 0.120396 0.3048)
			(stroke
				(width 0.1)
				(type default)
			)
			(layer "F.Fab")
		)
		(fp_line
			(start 0.67945 -0.3048)
			(end 0.67945 0.3048)
			(stroke
				(width 0.1)
				(type default)
			)
			(layer "F.Fab")
		)
		(fp_line
			(start 0.12065 -0.2794)
			(end 0.12065 -0.3048)
			(stroke
				(width 0.1)
				(type default)
			)
			(layer "F.Fab")
		)
		(fp_line
			(start 0.12065 -0.3048)
			(end 0.67945 -0.3048)
			(stroke
				(width 0.1)
				(type default)
			)
			(layer "F.Fab")
		)
		(fp_line
			(start 0.120396 0.3048)
			(end 0.120396 0.2794)
			(stroke
				(width 0.1)
				(type default)
			)
			(layer "F.Fab")
		)
		(fp_line
			(start 0.120396 0.2794)
			(end -0.12065 0.2794)
			(stroke
				(width 0.1)
				(type default)
			)
			(layer "F.Fab")
		)
		(fp_line
			(start -0.12065 0.3048)
			(end -0.67945 0.3048)
			(stroke
				(width 0.1)
				(type default)
			)
			(layer "F.Fab")
		)
		(fp_line
			(start -0.12065 0.2794)
			(end -0.12065 0.3048)
			(stroke
				(width 0.1)
				(type default)
			)
			(layer "F.Fab")
		)
		(fp_line
			(start -0.12065 -0.2794)
			(end 0.12065 -0.2794)
			(stroke
				(width 0.1)
				(type default)
			)
			(layer "F.Fab")
		)
		(fp_line
			(start -0.12065 -0.305054)
			(end -0.12065 -0.2794)
			(stroke
				(width 0.1)
				(type default)
			)
			(layer "F.Fab")
		)
		(fp_line
			(start -0.67945 0.3048)
			(end -0.67945 -0.305054)
			(stroke
				(width 0.1)
				(type default)
			)
			(layer "F.Fab")
		)
		(fp_line
			(start -0.67945 -0.305054)
			(end -0.12065 -0.305054)
			(stroke
				(width 0.1)
				(type default)
			)
			(layer "F.Fab")
		)
		(pad "1" smd circle
			(at -0.40005 0 180)
			(size 0 0)
			(layers "F.Cu" "F.Mask" "F.Paste")
			(net "JTAG_BMC_TDO")
		)
		(pad "2" smd circle
			(at 0.40005 0 180)
			(size 0 0)
			(layers "F.Cu" "F.Mask" "F.Paste")
			(net "JTAG_BMC_TDO_R")
		)
	)
	(footprint ""
		(layer "F.Cu")
		(at 9.739884 -360.76382)
		(property "Reference" "H125"
			(at -2.056384 -8.033258 0)
			(unlocked yes)
			(layer "F.SilkS")
			(effects
				(font
					(size 0.7874 0.5842)
					(thickness 0.1524)
				)
				(justify left)
			)
		)
		(property "Value" ""
			(at 0 0 0)
			(layer "F.Fab")
			(effects
				(font
					(size 1.27 1.27)
				)
			)
		)
		(duplicate_pad_numbers_are_jumpers no)
		(fp_circle
			(center 0 0)
			(end 5.8166 0)
			(stroke
				(width 0.1524)
				(type default)
			)
			(fill no)
			(layer "F.SilkS")
		)
		(fp_circle
			(center 0 0)
			(end 5.8166 0)
			(stroke
				(width 0.1524)
				(type default)
			)
			(fill no)
			(layer "B.SilkS")
		)
		(fp_circle
			(center 0 0)
			(end 5.8166 0)
			(stroke
				(width 0.1)
				(type default)
			)
			(fill no)
			(layer "B.Fab")
		)
		(fp_circle
			(center 0 0)
			(end 5.8166 0)
			(stroke
				(width 0.1)
				(type default)
			)
			(fill no)
			(layer "F.Fab")
		)
		(pad "" np_thru_hole circle
			(at 0 0)
			(size 10.0076 10.0076)
			(drill 10.0076)
			(layers "*.Cu" "*.Mask")
			(clearance 0.381)
			(thermal_gap 0.381)
		)
		(zone
			(layers "F.Cu" "B.Cu" "In1.Cu" "In2.Cu" "In3.Cu" "In4.Cu" "In5.Cu" "In6.Cu"
				"In7.Cu" "In8.Cu" "In9.Cu" "In10.Cu" "In11.Cu" "In12.Cu" "In13.Cu" "In14.Cu"
				"In15.Cu" "In16.Cu"
			)
			(hatch none 0.5)
			(connect_pads
				(clearance 0)
			)
			(min_thickness 0.25)
			(keepout
				(tracks not_allowed)
				(vias allowed)
				(pads allowed)
				(copperpour not_allowed)
				(footprints allowed)
			)
			(placement
				(enabled no)
				(sheetname "")
			)
			(fill
				(thermal_gap 0.5)
				(thermal_bridge_width 0.5)
				(island_removal_mode 0)
			)
			(polygon
				(pts
					(arc
						(start 15.251684 -360.76382)
						(mid 4.228084 -360.76382)
						(end 15.251684 -360.76382)
					)
				)
			)
		)
	)
	(footprint ""
		(layer "F.Cu")
		(at 15.436596 -390.167876)
		(property "Reference" "R3289"
			(at 0 0 0)
			(layer "F.SilkS")
			(hide yes)
			(effects
				(font
					(size 1.27 1.27)
				)
			)
		)
		(property "Value" ""
			(at 0 0 0)
			(layer "F.Fab")
			(effects
				(font
					(size 1.27 1.27)
				)
			)
		)
		(duplicate_pad_numbers_are_jumpers no)
		(fp_line
			(start -0.7874 -0.4064)
			(end 0.7874 -0.4064)
			(stroke
				(width 0.1524)
				(type default)
			)
			(layer "F.SilkS")
		)
		(fp_line
			(start -0.7874 0.4064)
			(end -0.7874 -0.4064)
			(stroke
				(width 0.1524)
				(type default)
			)
			(layer "F.SilkS")
		)
		(fp_line
			(start 0.7874 -0.4064)
			(end 0.7874 0.4064)
			(stroke
				(width 0.1524)
				(type default)
			)
			(layer "F.SilkS")
		)
		(fp_line
			(start 0.7874 0.4064)
			(end -0.7874 0.4064)
			(stroke
				(width 0.1524)
				(type default)
			)
			(layer "F.SilkS")
		)
		(fp_line
			(start -0.67945 -0.305054)
			(end -0.12065 -0.305054)
			(stroke
				(width 0.1)
				(type default)
			)
			(layer "F.Fab")
		)
		(fp_line
			(start -0.67945 0.3048)
			(end -0.67945 -0.305054)
			(stroke
				(width 0.1)
				(type default)
			)
			(layer "F.Fab")
		)
		(fp_line
			(start -0.12065 -0.305054)
			(end -0.12065 -0.2794)
			(stroke
				(width 0.1)
				(type default)
			)
			(layer "F.Fab")
		)
		(fp_line
			(start -0.12065 -0.2794)
			(end 0.12065 -0.2794)
			(stroke
				(width 0.1)
				(type default)
			)
			(layer "F.Fab")
		)
		(fp_line
			(start -0.12065 0.2794)
			(end -0.12065 0.3048)
			(stroke
				(width 0.1)
				(type default)
			)
			(layer "F.Fab")
		)
		(fp_line
			(start -0.12065 0.3048)
			(end -0.67945 0.3048)
			(stroke
				(width 0.1)
				(type default)
			)
			(layer "F.Fab")
		)
		(fp_line
			(start 0.120396 0.2794)
			(end -0.12065 0.2794)
			(stroke
				(width 0.1)
				(type default)
			)
			(layer "F.Fab")
		)
		(fp_line
			(start 0.120396 0.3048)
			(end 0.120396 0.2794)
			(stroke
				(width 0.1)
				(type default)
			)
			(layer "F.Fab")
		)
		(fp_line
			(start 0.12065 -0.3048)
			(end 0.67945 -0.3048)
			(stroke
				(width 0.1)
				(type default)
			)
			(layer "F.Fab")
		)
		(fp_line
			(start 0.12065 -0.2794)
			(end 0.12065 -0.3048)
			(stroke
				(width 0.1)
				(type default)
			)
			(layer "F.Fab")
		)
		(fp_line
			(start 0.67945 -0.3048)
			(end 0.67945 0.3048)
			(stroke
				(width 0.1)
				(type default)
			)
			(layer "F.Fab")
		)
		(fp_line
			(start 0.67945 0.3048)
			(end 0.120396 0.3048)
			(stroke
				(width 0.1)
				(type default)
			)
			(layer "F.Fab")
		)
		(pad "1" smd circle
			(at -0.40005 0)
			(size 0 0)
			(layers "F.Cu" "F.Mask" "F.Paste")
			(net "P3V3_AUX")
		)
		(pad "2" smd circle
			(at 0.40005 0)
			(size 0 0)
			(layers "F.Cu" "F.Mask" "F.Paste")
			(net "FM_P2E_SWA")
		)
	)
	(footprint ""
		(layer "F.Cu")
		(at 381.360172 -297.514772)
		(property "Reference" "H17"
			(at -1.122172 -5.826506 0)
			(unlocked yes)
			(layer "F.SilkS")
			(effects
				(font
					(size 0.7874 0.5842)
					(thickness 0.1524)
				)
				(justify left)
			)
		)
		(property "Value" ""
			(at 0 0 0)
			(layer "F.Fab")
			(effects
				(font
					(size 1.27 1.27)
				)
			)
		)
		(duplicate_pad_numbers_are_jumpers no)
		(fp_circle
			(center 0 0)
			(end 2.5273 0)
			(stroke
				(width 0.1524)
				(type default)
			)
			(fill no)
			(layer "F.SilkS")
		)
		(fp_circle
			(center 0 0)
			(end 2.5273 0)
			(stroke
				(width 0.1524)
				(type default)
			)
			(fill no)
			(layer "B.SilkS")
		)
		(fp_circle
			(center 0 0)
			(end 2.5273 0)
			(stroke
				(width 0.1)
				(type default)
			)
			(fill no)
			(layer "B.Fab")
		)
		(fp_circle
			(center 0 0)
			(end 2.5273 0)
			(stroke
				(width 0.1)
				(type default)
			)
			(fill no)
			(layer "F.Fab")
		)
		(pad "" np_thru_hole circle
			(at 0 0)
			(size 3.429 3.429)
			(drill 3.429)
			(layers "*.Cu" "*.Mask")
			(clearance 0.381)
			(thermal_gap 0.381)
		)
	)
	(footprint ""
		(layer "F.Cu")
		(at 279.262078 -417.2839 -90)
		(property "Reference" "R4668"
			(at 0 0 270)
			(layer "F.SilkS")
			(hide yes)
			(effects
				(font
					(size 1.27 1.27)
				)
			)
		)
		(property "Value" ""
			(at 0 0 270)
			(layer "F.Fab")
			(effects
				(font
					(size 1.27 1.27)
				)
			)
		)
		(duplicate_pad_numbers_are_jumpers no)
		(fp_line
			(start -0.7874 0.4064)
			(end -0.7874 -0.4064)
			(stroke
				(width 0.1524)
				(type default)
			)
			(layer "F.SilkS")
		)
		(fp_line
			(start 0.7874 0.4064)
			(end -0.7874 0.4064)
			(stroke
				(width 0.1524)
				(type default)
			)
			(layer "F.SilkS")
		)
		(fp_line
			(start -0.7874 -0.4064)
			(end 0.7874 -0.4064)
			(stroke
				(width 0.1524)
				(type default)
			)
			(layer "F.SilkS")
		)
		(fp_line
			(start 0.7874 -0.4064)
			(end 0.7874 0.4064)
			(stroke
				(width 0.1524)
				(type default)
			)
			(layer "F.SilkS")
		)
		(fp_line
			(start -0.67945 0.3048)
			(end -0.67945 -0.305054)
			(stroke
				(width 0.1)
				(type default)
			)
			(layer "F.Fab")
		)
		(fp_line
			(start -0.12065 0.3048)
			(end -0.67945 0.3048)
			(stroke
				(width 0.1)
				(type default)
			)
			(layer "F.Fab")
		)
		(fp_line
			(start 0.120396 0.3048)
			(end 0.120396 0.2794)
			(stroke
				(width 0.1)
				(type default)
			)
			(layer "F.Fab")
		)
		(fp_line
			(start 0.67945 0.3048)
			(end 0.120396 0.3048)
			(stroke
				(width 0.1)
				(type default)
			)
			(layer "F.Fab")
		)
		(fp_line
			(start -0.12065 0.2794)
			(end -0.12065 0.3048)
			(stroke
				(width 0.1)
				(type default)
			)
			(layer "F.Fab")
		)
		(fp_line
			(start 0.120396 0.2794)
			(end -0.12065 0.2794)
			(stroke
				(width 0.1)
				(type default)
			)
			(layer "F.Fab")
		)
		(fp_line
			(start -0.12065 -0.2794)
			(end 0.12065 -0.2794)
			(stroke
				(width 0.1)
				(type default)
			)
			(layer "F.Fab")
		)
		(fp_line
			(start 0.12065 -0.2794)
			(end 0.12065 -0.3048)
			(stroke
				(width 0.1)
				(type default)
			)
			(layer "F.Fab")
		)
		(fp_line
			(start 0.12065 -0.3048)
			(end 0.67945 -0.3048)
			(stroke
				(width 0.1)
				(type default)
			)
			(layer "F.Fab")
		)
		(fp_line
			(start 0.67945 -0.3048)
			(end 0.67945 0.3048)
			(stroke
				(width 0.1)
				(type default)
			)
			(layer "F.Fab")
		)
		(fp_line
			(start -0.67945 -0.305054)
			(end -0.12065 -0.305054)
			(stroke
				(width 0.1)
				(type default)
			)
			(layer "F.Fab")
		)
		(fp_line
			(start -0.12065 -0.305054)
			(end -0.12065 -0.2794)
			(stroke
				(width 0.1)
				(type default)
			)
			(layer "F.Fab")
		)
		(pad "1" smd circle
			(at -0.40005 0 270)
			(size 0 0)
			(layers "F.Cu" "F.Mask" "F.Paste")
			(net "A_HSC_LOW")
		)
		(pad "2" smd circle
			(at 0.40005 0 270)
			(size 0 0)
			(layers "F.Cu" "F.Mask" "F.Paste")
			(net "GND")
		)
	)
	(footprint ""
		(layer "F.Cu")
		(at 211.572094 -14.892528)
		(property "Reference" "C1275"
			(at 0 0 0)
			(layer "F.SilkS")
			(hide yes)
			(effects
				(font
					(size 1.27 1.27)
				)
			)
		)
		(property "Value" ""
			(at 0 0 0)
			(layer "F.Fab")
			(effects
				(font
					(size 1.27 1.27)
				)
			)
		)
		(duplicate_pad_numbers_are_jumpers no)
		(fp_line
			(start -0.7874 -0.4064)
			(end 0.7874 -0.4064)
			(stroke
				(width 0.1524)
				(type default)
			)
			(layer "F.SilkS")
		)
		(fp_line
			(start -0.7874 0.4064)
			(end -0.7874 -0.4064)
			(stroke
				(width 0.1524)
				(type default)
			)
			(layer "F.SilkS")
		)
		(fp_line
			(start 0.7874 -0.4064)
			(end 0.7874 0.4064)
			(stroke
				(width 0.1524)
				(type default)
			)
			(layer "F.SilkS")
		)
		(fp_line
			(start 0.7874 0.4064)
			(end -0.7874 0.4064)
			(stroke
				(width 0.1524)
				(type default)
			)
			(layer "F.SilkS")
		)
		(fp_line
			(start -0.67945 -0.305054)
			(end -0.12065 -0.305054)
			(stroke
				(width 0.1)
				(type default)
			)
			(layer "F.Fab")
		)
		(fp_line
			(start -0.67945 0.3048)
			(end -0.67945 -0.305054)
			(stroke
				(width 0.1)
				(type default)
			)
			(layer "F.Fab")
		)
		(fp_line
			(start -0.12065 -0.305054)
			(end -0.12065 -0.2794)
			(stroke
				(width 0.1)
				(type default)
			)
			(layer "F.Fab")
		)
		(fp_line
			(start -0.12065 -0.2794)
			(end 0.12065 -0.2794)
			(stroke
				(width 0.1)
				(type default)
			)
			(layer "F.Fab")
		)
		(fp_line
			(start -0.12065 0.2794)
			(end -0.12065 0.3048)
			(stroke
				(width 0.1)
				(type default)
			)
			(layer "F.Fab")
		)
		(fp_line
			(start -0.12065 0.3048)
			(end -0.67945 0.3048)
			(stroke
				(width 0.1)
				(type default)
			)
			(layer "F.Fab")
		)
		(fp_line
			(start 0.120396 0.2794)
			(end -0.12065 0.2794)
			(stroke
				(width 0.1)
				(type default)
			)
			(layer "F.Fab")
		)
		(fp_line
			(start 0.120396 0.3048)
			(end 0.120396 0.2794)
			(stroke
				(width 0.1)
				(type default)
			)
			(layer "F.Fab")
		)
		(fp_line
			(start 0.12065 -0.3048)
			(end 0.67945 -0.3048)
			(stroke
				(width 0.1)
				(type default)
			)
			(layer "F.Fab")
		)
		(fp_line
			(start 0.12065 -0.2794)
			(end 0.12065 -0.3048)
			(stroke
				(width 0.1)
				(type default)
			)
			(layer "F.Fab")
		)
		(fp_line
			(start 0.67945 -0.3048)
			(end 0.67945 0.3048)
			(stroke
				(width 0.1)
				(type default)
			)
			(layer "F.Fab")
		)
		(fp_line
			(start 0.67945 0.3048)
			(end 0.120396 0.3048)
			(stroke
				(width 0.1)
				(type default)
			)
			(layer "F.Fab")
		)
		(pad "1" smd circle
			(at -0.40005 0)
			(size 0 0)
			(layers "F.Cu" "F.Mask" "F.Paste")
			(net "P3V3_AUX")
		)
		(pad "2" smd circle
			(at 0.40005 0)
			(size 0 0)
			(layers "F.Cu" "F.Mask" "F.Paste")
			(net "GND")
		)
	)
	(footprint ""
		(layer "F.Cu")
		(at 365.2012 -412.623 180)
		(property "Reference" "R4798"
			(at 0 0 180)
			(layer "F.SilkS")
			(hide yes)
			(effects
				(font
					(size 1.27 1.27)
				)
			)
		)
		(property "Value" ""
			(at 0 0 180)
			(layer "F.Fab")
			(effects
				(font
					(size 1.27 1.27)
				)
			)
		)
		(duplicate_pad_numbers_are_jumpers no)
		(fp_line
			(start 0.7874 0.4064)
			(end -0.7874 0.4064)
			(stroke
				(width 0.1524)
				(type default)
			)
			(layer "F.SilkS")
		)
		(fp_line
			(start 0.7874 -0.4064)
			(end 0.7874 0.4064)
			(stroke
				(width 0.1524)
				(type default)
			)
			(layer "F.SilkS")
		)
		(fp_line
			(start -0.7874 0.4064)
			(end -0.7874 -0.4064)
			(stroke
				(width 0.1524)
				(type default)
			)
			(layer "F.SilkS")
		)
		(fp_line
			(start -0.7874 -0.4064)
			(end 0.7874 -0.4064)
			(stroke
				(width 0.1524)
				(type default)
			)
			(layer "F.SilkS")
		)
		(fp_line
			(start 0.67945 0.3048)
			(end 0.120396 0.3048)
			(stroke
				(width 0.1)
				(type default)
			)
			(layer "F.Fab")
		)
		(fp_line
			(start 0.67945 -0.3048)
			(end 0.67945 0.3048)
			(stroke
				(width 0.1)
				(type default)
			)
			(layer "F.Fab")
		)
		(fp_line
			(start 0.12065 -0.2794)
			(end 0.12065 -0.3048)
			(stroke
				(width 0.1)
				(type default)
			)
			(layer "F.Fab")
		)
		(fp_line
			(start 0.12065 -0.3048)
			(end 0.67945 -0.3048)
			(stroke
				(width 0.1)
				(type default)
			)
			(layer "F.Fab")
		)
		(fp_line
			(start 0.120396 0.3048)
			(end 0.120396 0.2794)
			(stroke
				(width 0.1)
				(type default)
			)
			(layer "F.Fab")
		)
		(fp_line
			(start 0.120396 0.2794)
			(end -0.12065 0.2794)
			(stroke
				(width 0.1)
				(type default)
			)
			(layer "F.Fab")
		)
		(fp_line
			(start -0.12065 0.3048)
			(end -0.67945 0.3048)
			(stroke
				(width 0.1)
				(type default)
			)
			(layer "F.Fab")
		)
		(fp_line
			(start -0.12065 0.2794)
			(end -0.12065 0.3048)
			(stroke
				(width 0.1)
				(type default)
			)
			(layer "F.Fab")
		)
		(fp_line
			(start -0.12065 -0.2794)
			(end 0.12065 -0.2794)
			(stroke
				(width 0.1)
				(type default)
			)
			(layer "F.Fab")
		)
		(fp_line
			(start -0.12065 -0.305054)
			(end -0.12065 -0.2794)
			(stroke
				(width 0.1)
				(type default)
			)
			(layer "F.Fab")
		)
		(fp_line
			(start -0.67945 0.3048)
			(end -0.67945 -0.305054)
			(stroke
				(width 0.1)
				(type default)
			)
			(layer "F.Fab")
		)
		(fp_line
			(start -0.67945 -0.305054)
			(end -0.12065 -0.305054)
			(stroke
				(width 0.1)
				(type default)
			)
			(layer "F.Fab")
		)
		(pad "1" smd circle
			(at -0.40005 0 180)
			(size 0 0)
			(layers "F.Cu" "F.Mask" "F.Paste")
			(net "P3V3_AUX")
		)
		(pad "2" smd circle
			(at 0.40005 0 180)
			(size 0 0)
			(layers "F.Cu" "F.Mask" "F.Paste")
			(net "PRSNT_CABLE_GPU_A3_N")
		)
	)
	(footprint ""
		(layer "F.Cu")
		(at 176.059338 -415.713418 180)
		(property "Reference" "R3465"
			(at 0 0 180)
			(layer "F.SilkS")
			(hide yes)
			(effects
				(font
					(size 1.27 1.27)
				)
			)
		)
		(property "Value" ""
			(at 0 0 180)
			(layer "F.Fab")
			(effects
				(font
					(size 1.27 1.27)
				)
			)
		)
		(duplicate_pad_numbers_are_jumpers no)
		(fp_line
			(start 0.7874 0.4064)
			(end -0.7874 0.4064)
			(stroke
				(width 0.1524)
				(type default)
			)
			(layer "F.SilkS")
		)
		(fp_line
			(start 0.7874 -0.4064)
			(end 0.7874 0.4064)
			(stroke
				(width 0.1524)
				(type default)
			)
			(layer "F.SilkS")
		)
		(fp_line
			(start -0.7874 0.4064)
			(end -0.7874 -0.4064)
			(stroke
				(width 0.1524)
				(type default)
			)
			(layer "F.SilkS")
		)
		(fp_line
			(start -0.7874 -0.4064)
			(end 0.7874 -0.4064)
			(stroke
				(width 0.1524)
				(type default)
			)
			(layer "F.SilkS")
		)
		(fp_line
			(start 0.67945 0.3048)
			(end 0.120396 0.3048)
			(stroke
				(width 0.1)
				(type default)
			)
			(layer "F.Fab")
		)
		(fp_line
			(start 0.67945 -0.3048)
			(end 0.67945 0.3048)
			(stroke
				(width 0.1)
				(type default)
			)
			(layer "F.Fab")
		)
		(fp_line
			(start 0.12065 -0.2794)
			(end 0.12065 -0.3048)
			(stroke
				(width 0.1)
				(type default)
			)
			(layer "F.Fab")
		)
		(fp_line
			(start 0.12065 -0.3048)
			(end 0.67945 -0.3048)
			(stroke
				(width 0.1)
				(type default)
			)
			(layer "F.Fab")
		)
		(fp_line
			(start 0.120396 0.3048)
			(end 0.120396 0.2794)
			(stroke
				(width 0.1)
				(type default)
			)
			(layer "F.Fab")
		)
		(fp_line
			(start 0.120396 0.2794)
			(end -0.12065 0.2794)
			(stroke
				(width 0.1)
				(type default)
			)
			(layer "F.Fab")
		)
		(fp_line
			(start -0.12065 0.3048)
			(end -0.67945 0.3048)
			(stroke
				(width 0.1)
				(type default)
			)
			(layer "F.Fab")
		)
		(fp_line
			(start -0.12065 0.2794)
			(end -0.12065 0.3048)
			(stroke
				(width 0.1)
				(type default)
			)
			(layer "F.Fab")
		)
		(fp_line
			(start -0.12065 -0.2794)
			(end 0.12065 -0.2794)
			(stroke
				(width 0.1)
				(type default)
			)
			(layer "F.Fab")
		)
		(fp_line
			(start -0.12065 -0.305054)
			(end -0.12065 -0.2794)
			(stroke
				(width 0.1)
				(type default)
			)
			(layer "F.Fab")
		)
		(fp_line
			(start -0.67945 0.3048)
			(end -0.67945 -0.305054)
			(stroke
				(width 0.1)
				(type default)
			)
			(layer "F.Fab")
		)
		(fp_line
			(start -0.67945 -0.305054)
			(end -0.12065 -0.305054)
			(stroke
				(width 0.1)
				(type default)
			)
			(layer "F.Fab")
		)
		(pad "1" smd circle
			(at -0.40005 0 180)
			(size 0 0)
			(layers "F.Cu" "F.Mask" "F.Paste")
			(net "P3V3_AUX")
		)
		(pad "2" smd circle
			(at 0.40005 0 180)
			(size 0 0)
			(layers "F.Cu" "F.Mask" "F.Paste")
			(net "GPU_HMC_PRSNT_N")
		)
	)
	(footprint ""
		(layer "F.Cu")
		(at 251.35967 -44.971462 -90)
		(property "Reference" "PC2211"
			(at 0 0 270)
			(layer "F.SilkS")
			(hide yes)
			(effects
				(font
					(size 1.27 1.27)
				)
			)
		)
		(property "Value" ""
			(at 0 0 270)
			(layer "F.Fab")
			(effects
				(font
					(size 1.27 1.27)
				)
			)
		)
		(duplicate_pad_numbers_are_jumpers no)
		(fp_line
			(start -0.7874 0.4064)
			(end -0.7874 -0.4064)
			(stroke
				(width 0.1524)
				(type default)
			)
			(layer "F.SilkS")
		)
		(fp_line
			(start 0.7874 0.4064)
			(end -0.7874 0.4064)
			(stroke
				(width 0.1524)
				(type default)
			)
			(layer "F.SilkS")
		)
		(fp_line
			(start -0.7874 -0.4064)
			(end 0.7874 -0.4064)
			(stroke
				(width 0.1524)
				(type default)
			)
			(layer "F.SilkS")
		)
		(fp_line
			(start 0.7874 -0.4064)
			(end 0.7874 0.4064)
			(stroke
				(width 0.1524)
				(type default)
			)
			(layer "F.SilkS")
		)
		(fp_line
			(start -0.67945 0.3048)
			(end -0.67945 -0.305054)
			(stroke
				(width 0.1)
				(type default)
			)
			(layer "F.Fab")
		)
		(fp_line
			(start -0.12065 0.3048)
			(end -0.67945 0.3048)
			(stroke
				(width 0.1)
				(type default)
			)
			(layer "F.Fab")
		)
		(fp_line
			(start 0.120396 0.3048)
			(end 0.120396 0.2794)
			(stroke
				(width 0.1)
				(type default)
			)
			(layer "F.Fab")
		)
		(fp_line
			(start 0.67945 0.3048)
			(end 0.120396 0.3048)
			(stroke
				(width 0.1)
				(type default)
			)
			(layer "F.Fab")
		)
		(fp_line
			(start -0.12065 0.2794)
			(end -0.12065 0.3048)
			(stroke
				(width 0.1)
				(type default)
			)
			(layer "F.Fab")
		)
		(fp_line
			(start 0.120396 0.2794)
			(end -0.12065 0.2794)
			(stroke
				(width 0.1)
				(type default)
			)
			(layer "F.Fab")
		)
		(fp_line
			(start -0.12065 -0.2794)
			(end 0.12065 -0.2794)
			(stroke
				(width 0.1)
				(type default)
			)
			(layer "F.Fab")
		)
		(fp_line
			(start 0.12065 -0.2794)
			(end 0.12065 -0.3048)
			(stroke
				(width 0.1)
				(type default)
			)
			(layer "F.Fab")
		)
		(fp_line
			(start 0.12065 -0.3048)
			(end 0.67945 -0.3048)
			(stroke
				(width 0.1)
				(type default)
			)
			(layer "F.Fab")
		)
		(fp_line
			(start 0.67945 -0.3048)
			(end 0.67945 0.3048)
			(stroke
				(width 0.1)
				(type default)
			)
			(layer "F.Fab")
		)
		(fp_line
			(start -0.67945 -0.305054)
			(end -0.12065 -0.305054)
			(stroke
				(width 0.1)
				(type default)
			)
			(layer "F.Fab")
		)
		(fp_line
			(start -0.12065 -0.305054)
			(end -0.12065 -0.2794)
			(stroke
				(width 0.1)
				(type default)
			)
			(layer "F.Fab")
		)
		(pad "1" smd circle
			(at -0.40005 0 270)
			(size 0 0)
			(layers "F.Cu" "F.Mask" "F.Paste")
			(net "GND")
		)
		(pad "2" smd circle
			(at 0.40005 0 270)
			(size 0 0)
			(layers "F.Cu" "F.Mask" "F.Paste")
			(net "P12V_E1S_REG_0")
		)
	)
	(footprint ""
		(layer "F.Cu")
		(at 348.390464 -356.478332 180)
		(property "Reference" "R2590"
			(at 0 0 180)
			(layer "F.SilkS")
			(hide yes)
			(effects
				(font
					(size 1.27 1.27)
				)
			)
		)
		(property "Value" ""
			(at 0 0 180)
			(layer "F.Fab")
			(effects
				(font
					(size 1.27 1.27)
				)
			)
		)
		(duplicate_pad_numbers_are_jumpers no)
		(fp_line
			(start 0.7874 0.4064)
			(end -0.7874 0.4064)
			(stroke
				(width 0.1524)
				(type default)
			)
			(layer "F.SilkS")
		)
		(fp_line
			(start 0.7874 -0.4064)
			(end 0.7874 0.4064)
			(stroke
				(width 0.1524)
				(type default)
			)
			(layer "F.SilkS")
		)
		(fp_line
			(start -0.7874 0.4064)
			(end -0.7874 -0.4064)
			(stroke
				(width 0.1524)
				(type default)
			)
			(layer "F.SilkS")
		)
		(fp_line
			(start -0.7874 -0.4064)
			(end 0.7874 -0.4064)
			(stroke
				(width 0.1524)
				(type default)
			)
			(layer "F.SilkS")
		)
		(fp_line
			(start 0.67945 0.3048)
			(end 0.120396 0.3048)
			(stroke
				(width 0.1)
				(type default)
			)
			(layer "F.Fab")
		)
		(fp_line
			(start 0.67945 -0.3048)
			(end 0.67945 0.3048)
			(stroke
				(width 0.1)
				(type default)
			)
			(layer "F.Fab")
		)
		(fp_line
			(start 0.12065 -0.2794)
			(end 0.12065 -0.3048)
			(stroke
				(width 0.1)
				(type default)
			)
			(layer "F.Fab")
		)
		(fp_line
			(start 0.12065 -0.3048)
			(end 0.67945 -0.3048)
			(stroke
				(width 0.1)
				(type default)
			)
			(layer "F.Fab")
		)
		(fp_line
			(start 0.120396 0.3048)
			(end 0.120396 0.2794)
			(stroke
				(width 0.1)
				(type default)
			)
			(layer "F.Fab")
		)
		(fp_line
			(start 0.120396 0.2794)
			(end -0.12065 0.2794)
			(stroke
				(width 0.1)
				(type default)
			)
			(layer "F.Fab")
		)
		(fp_line
			(start -0.12065 0.3048)
			(end -0.67945 0.3048)
			(stroke
				(width 0.1)
				(type default)
			)
			(layer "F.Fab")
		)
		(fp_line
			(start -0.12065 0.2794)
			(end -0.12065 0.3048)
			(stroke
				(width 0.1)
				(type default)
			)
			(layer "F.Fab")
		)
		(fp_line
			(start -0.12065 -0.2794)
			(end 0.12065 -0.2794)
			(stroke
				(width 0.1)
				(type default)
			)
			(layer "F.Fab")
		)
		(fp_line
			(start -0.12065 -0.305054)
			(end -0.12065 -0.2794)
			(stroke
				(width 0.1)
				(type default)
			)
			(layer "F.Fab")
		)
		(fp_line
			(start -0.67945 0.3048)
			(end -0.67945 -0.305054)
			(stroke
				(width 0.1)
				(type default)
			)
			(layer "F.Fab")
		)
		(fp_line
			(start -0.67945 -0.305054)
			(end -0.12065 -0.305054)
			(stroke
				(width 0.1)
				(type default)
			)
			(layer "F.Fab")
		)
		(pad "1" smd circle
			(at -0.40005 0 180)
			(size 0 0)
			(layers "F.Cu" "F.Mask" "F.Paste")
			(net "SVID_DIO0_CPU0_R")
		)
		(pad "2" smd circle
			(at 0.40005 0 180)
			(size 0 0)
			(layers "F.Cu" "F.Mask" "F.Paste")
			(net "PVNN_TERM_CPU0")
		)
	)
	(footprint ""
		(layer "F.Cu")
		(at 262.450072 -127.965708 -90)
		(property "Reference" "R4480"
			(at 0 0 270)
			(layer "F.SilkS")
			(hide yes)
			(effects
				(font
					(size 1.27 1.27)
				)
			)
		)
		(property "Value" ""
			(at 0 0 270)
			(layer "F.Fab")
			(effects
				(font
					(size 1.27 1.27)
				)
			)
		)
		(duplicate_pad_numbers_are_jumpers no)
		(fp_line
			(start -0.7874 0.4064)
			(end -0.7874 -0.4064)
			(stroke
				(width 0.1524)
				(type default)
			)
			(layer "F.SilkS")
		)
		(fp_line
			(start 0.7874 0.4064)
			(end -0.7874 0.4064)
			(stroke
				(width 0.1524)
				(type default)
			)
			(layer "F.SilkS")
		)
		(fp_line
			(start -0.7874 -0.4064)
			(end 0.7874 -0.4064)
			(stroke
				(width 0.1524)
				(type default)
			)
			(layer "F.SilkS")
		)
		(fp_line
			(start 0.7874 -0.4064)
			(end 0.7874 0.4064)
			(stroke
				(width 0.1524)
				(type default)
			)
			(layer "F.SilkS")
		)
		(fp_line
			(start -0.67945 0.3048)
			(end -0.67945 -0.305054)
			(stroke
				(width 0.1)
				(type default)
			)
			(layer "F.Fab")
		)
		(fp_line
			(start -0.12065 0.3048)
			(end -0.67945 0.3048)
			(stroke
				(width 0.1)
				(type default)
			)
			(layer "F.Fab")
		)
		(fp_line
			(start 0.120396 0.3048)
			(end 0.120396 0.2794)
			(stroke
				(width 0.1)
				(type default)
			)
			(layer "F.Fab")
		)
		(fp_line
			(start 0.67945 0.3048)
			(end 0.120396 0.3048)
			(stroke
				(width 0.1)
				(type default)
			)
			(layer "F.Fab")
		)
		(fp_line
			(start -0.12065 0.2794)
			(end -0.12065 0.3048)
			(stroke
				(width 0.1)
				(type default)
			)
			(layer "F.Fab")
		)
		(fp_line
			(start 0.120396 0.2794)
			(end -0.12065 0.2794)
			(stroke
				(width 0.1)
				(type default)
			)
			(layer "F.Fab")
		)
		(fp_line
			(start -0.12065 -0.2794)
			(end 0.12065 -0.2794)
			(stroke
				(width 0.1)
				(type default)
			)
			(layer "F.Fab")
		)
		(fp_line
			(start 0.12065 -0.2794)
			(end 0.12065 -0.3048)
			(stroke
				(width 0.1)
				(type default)
			)
			(layer "F.Fab")
		)
		(fp_line
			(start 0.12065 -0.3048)
			(end 0.67945 -0.3048)
			(stroke
				(width 0.1)
				(type default)
			)
			(layer "F.Fab")
		)
		(fp_line
			(start 0.67945 -0.3048)
			(end 0.67945 0.3048)
			(stroke
				(width 0.1)
				(type default)
			)
			(layer "F.Fab")
		)
		(fp_line
			(start -0.67945 -0.305054)
			(end -0.12065 -0.305054)
			(stroke
				(width 0.1)
				(type default)
			)
			(layer "F.Fab")
		)
		(fp_line
			(start -0.12065 -0.305054)
			(end -0.12065 -0.2794)
			(stroke
				(width 0.1)
				(type default)
			)
			(layer "F.Fab")
		)
		(pad "1" smd circle
			(at -0.40005 0 270)
			(size 0 0)
			(layers "F.Cu" "F.Mask" "F.Paste")
			(net "SMB_HOST_CLK_BUF_ISO_3V3AUX_SCL")
		)
		(pad "2" smd circle
			(at 0.40005 0 270)
			(size 0 0)
			(layers "F.Cu" "F.Mask" "F.Paste")
			(net "SMB_HOST_9ZXL045_3V3AUX_SCL")
		)
	)
	(footprint ""
		(layer "F.Cu")
		(at 421.92448 -156.327348 -90)
		(property "Reference" "PR442"
			(at 0 0 270)
			(layer "F.SilkS")
			(hide yes)
			(effects
				(font
					(size 1.27 1.27)
				)
			)
		)
		(property "Value" ""
			(at 0 0 270)
			(layer "F.Fab")
			(effects
				(font
					(size 1.27 1.27)
				)
			)
		)
		(duplicate_pad_numbers_are_jumpers no)
		(fp_line
			(start -0.7874 0.4064)
			(end -0.7874 -0.4064)
			(stroke
				(width 0.1524)
				(type default)
			)
			(layer "F.SilkS")
		)
		(fp_line
			(start 0.7874 0.4064)
			(end -0.7874 0.4064)
			(stroke
				(width 0.1524)
				(type default)
			)
			(layer "F.SilkS")
		)
		(fp_line
			(start -0.7874 -0.4064)
			(end 0.7874 -0.4064)
			(stroke
				(width 0.1524)
				(type default)
			)
			(layer "F.SilkS")
		)
		(fp_line
			(start 0.7874 -0.4064)
			(end 0.7874 0.4064)
			(stroke
				(width 0.1524)
				(type default)
			)
			(layer "F.SilkS")
		)
		(fp_line
			(start -0.67945 0.3048)
			(end -0.67945 -0.305054)
			(stroke
				(width 0.1)
				(type default)
			)
			(layer "F.Fab")
		)
		(fp_line
			(start -0.12065 0.3048)
			(end -0.67945 0.3048)
			(stroke
				(width 0.1)
				(type default)
			)
			(layer "F.Fab")
		)
		(fp_line
			(start 0.120396 0.3048)
			(end 0.120396 0.2794)
			(stroke
				(width 0.1)
				(type default)
			)
			(layer "F.Fab")
		)
		(fp_line
			(start 0.67945 0.3048)
			(end 0.120396 0.3048)
			(stroke
				(width 0.1)
				(type default)
			)
			(layer "F.Fab")
		)
		(fp_line
			(start -0.12065 0.2794)
			(end -0.12065 0.3048)
			(stroke
				(width 0.1)
				(type default)
			)
			(layer "F.Fab")
		)
		(fp_line
			(start 0.120396 0.2794)
			(end -0.12065 0.2794)
			(stroke
				(width 0.1)
				(type default)
			)
			(layer "F.Fab")
		)
		(fp_line
			(start -0.12065 -0.2794)
			(end 0.12065 -0.2794)
			(stroke
				(width 0.1)
				(type default)
			)
			(layer "F.Fab")
		)
		(fp_line
			(start 0.12065 -0.2794)
			(end 0.12065 -0.3048)
			(stroke
				(width 0.1)
				(type default)
			)
			(layer "F.Fab")
		)
		(fp_line
			(start 0.12065 -0.3048)
			(end 0.67945 -0.3048)
			(stroke
				(width 0.1)
				(type default)
			)
			(layer "F.Fab")
		)
		(fp_line
			(start 0.67945 -0.3048)
			(end 0.67945 0.3048)
			(stroke
				(width 0.1)
				(type default)
			)
			(layer "F.Fab")
		)
		(fp_line
			(start -0.67945 -0.305054)
			(end -0.12065 -0.305054)
			(stroke
				(width 0.1)
				(type default)
			)
			(layer "F.Fab")
		)
		(fp_line
			(start -0.12065 -0.305054)
			(end -0.12065 -0.2794)
			(stroke
				(width 0.1)
				(type default)
			)
			(layer "F.Fab")
		)
		(pad "1" smd circle
			(at -0.40005 0 270)
			(size 0 0)
			(layers "F.Cu" "F.Mask" "F.Paste")
			(net "P5V")
		)
		(pad "2" smd circle
			(at 0.40005 0 270)
			(size 0 0)
			(layers "F.Cu" "F.Mask" "F.Paste")
			(net "PVCCFA_EHV_CPU0_PVCC")
		)
	)
	(footprint ""
		(layer "F.Cu")
		(at 355.229414 -252.956314 -90)
		(property "Reference" "C1010"
			(at 0 0 270)
			(layer "F.SilkS")
			(hide yes)
			(effects
				(font
					(size 1.27 1.27)
				)
			)
		)
		(property "Value" ""
			(at 0 0 270)
			(layer "F.Fab")
			(effects
				(font
					(size 1.27 1.27)
				)
			)
		)
		(duplicate_pad_numbers_are_jumpers no)
		(fp_line
			(start -0.7874 0.4064)
			(end -0.7874 -0.4064)
			(stroke
				(width 0.1524)
				(type default)
			)
			(layer "F.SilkS")
		)
		(fp_line
			(start 0.7874 0.4064)
			(end -0.7874 0.4064)
			(stroke
				(width 0.1524)
				(type default)
			)
			(layer "F.SilkS")
		)
		(fp_line
			(start -0.7874 -0.4064)
			(end 0.7874 -0.4064)
			(stroke
				(width 0.1524)
				(type default)
			)
			(layer "F.SilkS")
		)
		(fp_line
			(start 0.7874 -0.4064)
			(end 0.7874 0.4064)
			(stroke
				(width 0.1524)
				(type default)
			)
			(layer "F.SilkS")
		)
		(fp_line
			(start -0.67945 0.3048)
			(end -0.67945 -0.305054)
			(stroke
				(width 0.1)
				(type default)
			)
			(layer "F.Fab")
		)
		(fp_line
			(start -0.12065 0.3048)
			(end -0.67945 0.3048)
			(stroke
				(width 0.1)
				(type default)
			)
			(layer "F.Fab")
		)
		(fp_line
			(start 0.120396 0.3048)
			(end 0.120396 0.2794)
			(stroke
				(width 0.1)
				(type default)
			)
			(layer "F.Fab")
		)
		(fp_line
			(start 0.67945 0.3048)
			(end 0.120396 0.3048)
			(stroke
				(width 0.1)
				(type default)
			)
			(layer "F.Fab")
		)
		(fp_line
			(start -0.12065 0.2794)
			(end -0.12065 0.3048)
			(stroke
				(width 0.1)
				(type default)
			)
			(layer "F.Fab")
		)
		(fp_line
			(start 0.120396 0.2794)
			(end -0.12065 0.2794)
			(stroke
				(width 0.1)
				(type default)
			)
			(layer "F.Fab")
		)
		(fp_line
			(start -0.12065 -0.2794)
			(end 0.12065 -0.2794)
			(stroke
				(width 0.1)
				(type default)
			)
			(layer "F.Fab")
		)
		(fp_line
			(start 0.12065 -0.2794)
			(end 0.12065 -0.3048)
			(stroke
				(width 0.1)
				(type default)
			)
			(layer "F.Fab")
		)
		(fp_line
			(start 0.12065 -0.3048)
			(end 0.67945 -0.3048)
			(stroke
				(width 0.1)
				(type default)
			)
			(layer "F.Fab")
		)
		(fp_line
			(start 0.67945 -0.3048)
			(end 0.67945 0.3048)
			(stroke
				(width 0.1)
				(type default)
			)
			(layer "F.Fab")
		)
		(fp_line
			(start -0.67945 -0.305054)
			(end -0.12065 -0.305054)
			(stroke
				(width 0.1)
				(type default)
			)
			(layer "F.Fab")
		)
		(fp_line
			(start -0.12065 -0.305054)
			(end -0.12065 -0.2794)
			(stroke
				(width 0.1)
				(type default)
			)
			(layer "F.Fab")
		)
		(pad "1" smd circle
			(at -0.40005 0 270)
			(size 0 0)
			(layers "F.Cu" "F.Mask" "F.Paste")
			(net "PVCCIN_CPU0")
		)
		(pad "2" smd circle
			(at 0.40005 0 270)
			(size 0 0)
			(layers "F.Cu" "F.Mask" "F.Paste")
			(net "GND")
		)
	)
	(footprint ""
		(layer "F.Cu")
		(at 112.33531 -74.908156 -90)
		(property "Reference" "R3101"
			(at 0 0 270)
			(layer "F.SilkS")
			(hide yes)
			(effects
				(font
					(size 1.27 1.27)
				)
			)
		)
		(property "Value" ""
			(at 0 0 270)
			(layer "F.Fab")
			(effects
				(font
					(size 1.27 1.27)
				)
			)
		)
		(duplicate_pad_numbers_are_jumpers no)
		(fp_line
			(start -0.7874 0.4064)
			(end -0.7874 -0.4064)
			(stroke
				(width 0.1524)
				(type default)
			)
			(layer "F.SilkS")
		)
		(fp_line
			(start 0.7874 0.4064)
			(end -0.7874 0.4064)
			(stroke
				(width 0.1524)
				(type default)
			)
			(layer "F.SilkS")
		)
		(fp_line
			(start -0.7874 -0.4064)
			(end 0.7874 -0.4064)
			(stroke
				(width 0.1524)
				(type default)
			)
			(layer "F.SilkS")
		)
		(fp_line
			(start 0.7874 -0.4064)
			(end 0.7874 0.4064)
			(stroke
				(width 0.1524)
				(type default)
			)
			(layer "F.SilkS")
		)
		(fp_line
			(start -0.67945 0.3048)
			(end -0.67945 -0.305054)
			(stroke
				(width 0.1)
				(type default)
			)
			(layer "F.Fab")
		)
		(fp_line
			(start -0.12065 0.3048)
			(end -0.67945 0.3048)
			(stroke
				(width 0.1)
				(type default)
			)
			(layer "F.Fab")
		)
		(fp_line
			(start 0.120396 0.3048)
			(end 0.120396 0.2794)
			(stroke
				(width 0.1)
				(type default)
			)
			(layer "F.Fab")
		)
		(fp_line
			(start 0.67945 0.3048)
			(end 0.120396 0.3048)
			(stroke
				(width 0.1)
				(type default)
			)
			(layer "F.Fab")
		)
		(fp_line
			(start -0.12065 0.2794)
			(end -0.12065 0.3048)
			(stroke
				(width 0.1)
				(type default)
			)
			(layer "F.Fab")
		)
		(fp_line
			(start 0.120396 0.2794)
			(end -0.12065 0.2794)
			(stroke
				(width 0.1)
				(type default)
			)
			(layer "F.Fab")
		)
		(fp_line
			(start -0.12065 -0.2794)
			(end 0.12065 -0.2794)
			(stroke
				(width 0.1)
				(type default)
			)
			(layer "F.Fab")
		)
		(fp_line
			(start 0.12065 -0.2794)
			(end 0.12065 -0.3048)
			(stroke
				(width 0.1)
				(type default)
			)
			(layer "F.Fab")
		)
		(fp_line
			(start 0.12065 -0.3048)
			(end 0.67945 -0.3048)
			(stroke
				(width 0.1)
				(type default)
			)
			(layer "F.Fab")
		)
		(fp_line
			(start 0.67945 -0.3048)
			(end 0.67945 0.3048)
			(stroke
				(width 0.1)
				(type default)
			)
			(layer "F.Fab")
		)
		(fp_line
			(start -0.67945 -0.305054)
			(end -0.12065 -0.305054)
			(stroke
				(width 0.1)
				(type default)
			)
			(layer "F.Fab")
		)
		(fp_line
			(start -0.12065 -0.305054)
			(end -0.12065 -0.2794)
			(stroke
				(width 0.1)
				(type default)
			)
			(layer "F.Fab")
		)
		(pad "1" smd circle
			(at -0.40005 0 270)
			(size 0 0)
			(layers "F.Cu" "F.Mask" "F.Paste")
			(net "LED_P5V_AUX")
		)
		(pad "2" smd circle
			(at 0.40005 0 270)
			(size 0 0)
			(layers "F.Cu" "F.Mask" "F.Paste")
			(net "P5V_AUX")
		)
	)
	(footprint ""
		(layer "F.Cu")
		(at 352.281744 -241.976656 -90)
		(property "Reference" "C1011"
			(at 0 0 270)
			(layer "F.SilkS")
			(hide yes)
			(effects
				(font
					(size 1.27 1.27)
				)
			)
		)
		(property "Value" ""
			(at 0 0 270)
			(layer "F.Fab")
			(effects
				(font
					(size 1.27 1.27)
				)
			)
		)
		(duplicate_pad_numbers_are_jumpers no)
		(fp_line
			(start -0.7874 0.4064)
			(end -0.7874 -0.4064)
			(stroke
				(width 0.1524)
				(type default)
			)
			(layer "F.SilkS")
		)
		(fp_line
			(start 0.7874 0.4064)
			(end -0.7874 0.4064)
			(stroke
				(width 0.1524)
				(type default)
			)
			(layer "F.SilkS")
		)
		(fp_line
			(start -0.7874 -0.4064)
			(end 0.7874 -0.4064)
			(stroke
				(width 0.1524)
				(type default)
			)
			(layer "F.SilkS")
		)
		(fp_line
			(start 0.7874 -0.4064)
			(end 0.7874 0.4064)
			(stroke
				(width 0.1524)
				(type default)
			)
			(layer "F.SilkS")
		)
		(fp_line
			(start -0.67945 0.3048)
			(end -0.67945 -0.305054)
			(stroke
				(width 0.1)
				(type default)
			)
			(layer "F.Fab")
		)
		(fp_line
			(start -0.12065 0.3048)
			(end -0.67945 0.3048)
			(stroke
				(width 0.1)
				(type default)
			)
			(layer "F.Fab")
		)
		(fp_line
			(start 0.120396 0.3048)
			(end 0.120396 0.2794)
			(stroke
				(width 0.1)
				(type default)
			)
			(layer "F.Fab")
		)
		(fp_line
			(start 0.67945 0.3048)
			(end 0.120396 0.3048)
			(stroke
				(width 0.1)
				(type default)
			)
			(layer "F.Fab")
		)
		(fp_line
			(start -0.12065 0.2794)
			(end -0.12065 0.3048)
			(stroke
				(width 0.1)
				(type default)
			)
			(layer "F.Fab")
		)
		(fp_line
			(start 0.120396 0.2794)
			(end -0.12065 0.2794)
			(stroke
				(width 0.1)
				(type default)
			)
			(layer "F.Fab")
		)
		(fp_line
			(start -0.12065 -0.2794)
			(end 0.12065 -0.2794)
			(stroke
				(width 0.1)
				(type default)
			)
			(layer "F.Fab")
		)
		(fp_line
			(start 0.12065 -0.2794)
			(end 0.12065 -0.3048)
			(stroke
				(width 0.1)
				(type default)
			)
			(layer "F.Fab")
		)
		(fp_line
			(start 0.12065 -0.3048)
			(end 0.67945 -0.3048)
			(stroke
				(width 0.1)
				(type default)
			)
			(layer "F.Fab")
		)
		(fp_line
			(start 0.67945 -0.3048)
			(end 0.67945 0.3048)
			(stroke
				(width 0.1)
				(type default)
			)
			(layer "F.Fab")
		)
		(fp_line
			(start -0.67945 -0.305054)
			(end -0.12065 -0.305054)
			(stroke
				(width 0.1)
				(type default)
			)
			(layer "F.Fab")
		)
		(fp_line
			(start -0.12065 -0.305054)
			(end -0.12065 -0.2794)
			(stroke
				(width 0.1)
				(type default)
			)
			(layer "F.Fab")
		)
		(pad "1" smd circle
			(at -0.40005 0 270)
			(size 0 0)
			(layers "F.Cu" "F.Mask" "F.Paste")
			(net "PVCCIN_CPU0")
		)
		(pad "2" smd circle
			(at 0.40005 0 270)
			(size 0 0)
			(layers "F.Cu" "F.Mask" "F.Paste")
			(net "GND")
		)
	)
	(footprint ""
		(layer "F.Cu")
		(at 226.503738 -220.815916 90)
		(property "Reference" "R996"
			(at 0 0 90)
			(layer "F.SilkS")
			(hide yes)
			(effects
				(font
					(size 1.27 1.27)
				)
			)
		)
		(property "Value" ""
			(at 0 0 90)
			(layer "F.Fab")
			(effects
				(font
					(size 1.27 1.27)
				)
			)
		)
		(duplicate_pad_numbers_are_jumpers no)
		(fp_line
			(start 0.7874 -0.4064)
			(end 0.7874 0.4064)
			(stroke
				(width 0.1524)
				(type default)
			)
			(layer "F.SilkS")
		)
		(fp_line
			(start -0.7874 -0.4064)
			(end 0.7874 -0.4064)
			(stroke
				(width 0.1524)
				(type default)
			)
			(layer "F.SilkS")
		)
		(fp_line
			(start 0.7874 0.4064)
			(end -0.7874 0.4064)
			(stroke
				(width 0.1524)
				(type default)
			)
			(layer "F.SilkS")
		)
		(fp_line
			(start -0.7874 0.4064)
			(end -0.7874 -0.4064)
			(stroke
				(width 0.1524)
				(type default)
			)
			(layer "F.SilkS")
		)
		(fp_line
			(start -0.12065 -0.305054)
			(end -0.12065 -0.2794)
			(stroke
				(width 0.1)
				(type default)
			)
			(layer "F.Fab")
		)
		(fp_line
			(start -0.67945 -0.305054)
			(end -0.12065 -0.305054)
			(stroke
				(width 0.1)
				(type default)
			)
			(layer "F.Fab")
		)
		(fp_line
			(start 0.67945 -0.3048)
			(end 0.67945 0.3048)
			(stroke
				(width 0.1)
				(type default)
			)
			(layer "F.Fab")
		)
		(fp_line
			(start 0.12065 -0.3048)
			(end 0.67945 -0.3048)
			(stroke
				(width 0.1)
				(type default)
			)
			(layer "F.Fab")
		)
		(fp_line
			(start 0.12065 -0.2794)
			(end 0.12065 -0.3048)
			(stroke
				(width 0.1)
				(type default)
			)
			(layer "F.Fab")
		)
		(fp_line
			(start -0.12065 -0.2794)
			(end 0.12065 -0.2794)
			(stroke
				(width 0.1)
				(type default)
			)
			(layer "F.Fab")
		)
		(fp_line
			(start 0.120396 0.2794)
			(end -0.12065 0.2794)
			(stroke
				(width 0.1)
				(type default)
			)
			(layer "F.Fab")
		)
		(fp_line
			(start -0.12065 0.2794)
			(end -0.12065 0.3048)
			(stroke
				(width 0.1)
				(type default)
			)
			(layer "F.Fab")
		)
		(fp_line
			(start 0.67945 0.3048)
			(end 0.120396 0.3048)
			(stroke
				(width 0.1)
				(type default)
			)
			(layer "F.Fab")
		)
		(fp_line
			(start 0.120396 0.3048)
			(end 0.120396 0.2794)
			(stroke
				(width 0.1)
				(type default)
			)
			(layer "F.Fab")
		)
		(fp_line
			(start -0.12065 0.3048)
			(end -0.67945 0.3048)
			(stroke
				(width 0.1)
				(type default)
			)
			(layer "F.Fab")
		)
		(fp_line
			(start -0.67945 0.3048)
			(end -0.67945 -0.305054)
			(stroke
				(width 0.1)
				(type default)
			)
			(layer "F.Fab")
		)
		(pad "1" smd circle
			(at -0.40005 0 90)
			(size 0 0)
			(layers "F.Cu" "F.Mask" "F.Paste")
			(net "SMB_S3M_CPU1_SDA")
		)
		(pad "2" smd circle
			(at 0.40005 0 90)
			(size 0 0)
			(layers "F.Cu" "F.Mask" "F.Paste")
			(net "SMB_S3M_CPU1_R_SDA")
		)
	)
	(footprint ""
		(layer "F.Cu")
		(at 120.438926 -119.810784 -90)
		(property "Reference" "R859"
			(at 0 0 270)
			(layer "F.SilkS")
			(hide yes)
			(effects
				(font
					(size 1.27 1.27)
				)
			)
		)
		(property "Value" ""
			(at 0 0 270)
			(layer "F.Fab")
			(effects
				(font
					(size 1.27 1.27)
				)
			)
		)
		(duplicate_pad_numbers_are_jumpers no)
		(fp_line
			(start -0.7874 0.4064)
			(end -0.7874 -0.4064)
			(stroke
				(width 0.1524)
				(type default)
			)
			(layer "F.SilkS")
		)
		(fp_line
			(start 0.7874 0.4064)
			(end -0.7874 0.4064)
			(stroke
				(width 0.1524)
				(type default)
			)
			(layer "F.SilkS")
		)
		(fp_line
			(start -0.7874 -0.4064)
			(end 0.7874 -0.4064)
			(stroke
				(width 0.1524)
				(type default)
			)
			(layer "F.SilkS")
		)
		(fp_line
			(start 0.7874 -0.4064)
			(end 0.7874 0.4064)
			(stroke
				(width 0.1524)
				(type default)
			)
			(layer "F.SilkS")
		)
		(fp_line
			(start -0.67945 0.3048)
			(end -0.67945 -0.305054)
			(stroke
				(width 0.1)
				(type default)
			)
			(layer "F.Fab")
		)
		(fp_line
			(start -0.12065 0.3048)
			(end -0.67945 0.3048)
			(stroke
				(width 0.1)
				(type default)
			)
			(layer "F.Fab")
		)
		(fp_line
			(start 0.120396 0.3048)
			(end 0.120396 0.2794)
			(stroke
				(width 0.1)
				(type default)
			)
			(layer "F.Fab")
		)
		(fp_line
			(start 0.67945 0.3048)
			(end 0.120396 0.3048)
			(stroke
				(width 0.1)
				(type default)
			)
			(layer "F.Fab")
		)
		(fp_line
			(start -0.12065 0.2794)
			(end -0.12065 0.3048)
			(stroke
				(width 0.1)
				(type default)
			)
			(layer "F.Fab")
		)
		(fp_line
			(start 0.120396 0.2794)
			(end -0.12065 0.2794)
			(stroke
				(width 0.1)
				(type default)
			)
			(layer "F.Fab")
		)
		(fp_line
			(start -0.12065 -0.2794)
			(end 0.12065 -0.2794)
			(stroke
				(width 0.1)
				(type default)
			)
			(layer "F.Fab")
		)
		(fp_line
			(start 0.12065 -0.2794)
			(end 0.12065 -0.3048)
			(stroke
				(width 0.1)
				(type default)
			)
			(layer "F.Fab")
		)
		(fp_line
			(start 0.12065 -0.3048)
			(end 0.67945 -0.3048)
			(stroke
				(width 0.1)
				(type default)
			)
			(layer "F.Fab")
		)
		(fp_line
			(start 0.67945 -0.3048)
			(end 0.67945 0.3048)
			(stroke
				(width 0.1)
				(type default)
			)
			(layer "F.Fab")
		)
		(fp_line
			(start -0.67945 -0.305054)
			(end -0.12065 -0.305054)
			(stroke
				(width 0.1)
				(type default)
			)
			(layer "F.Fab")
		)
		(fp_line
			(start -0.12065 -0.305054)
			(end -0.12065 -0.2794)
			(stroke
				(width 0.1)
				(type default)
			)
			(layer "F.Fab")
		)
		(pad "1" smd circle
			(at -0.40005 0 270)
			(size 0 0)
			(layers "F.Cu" "F.Mask" "F.Paste")
			(net "RST_CPU1_DRAM_AB_N")
		)
		(pad "2" smd circle
			(at 0.40005 0 270)
			(size 0 0)
			(layers "F.Cu" "F.Mask" "F.Paste")
			(net "RST_CPU1_DRAM_AB_PLD_N")
		)
	)
	(footprint ""
		(layer "F.Cu")
		(at 186.23788 -99.659948 -90)
		(property "Reference" "R992"
			(at 0 0 270)
			(layer "F.SilkS")
			(hide yes)
			(effects
				(font
					(size 1.27 1.27)
				)
			)
		)
		(property "Value" ""
			(at 0 0 270)
			(layer "F.Fab")
			(effects
				(font
					(size 1.27 1.27)
				)
			)
		)
		(duplicate_pad_numbers_are_jumpers no)
		(fp_line
			(start -0.7874 0.4064)
			(end -0.7874 -0.4064)
			(stroke
				(width 0.1524)
				(type default)
			)
			(layer "F.SilkS")
		)
		(fp_line
			(start 0.7874 0.4064)
			(end -0.7874 0.4064)
			(stroke
				(width 0.1524)
				(type default)
			)
			(layer "F.SilkS")
		)
		(fp_line
			(start -0.7874 -0.4064)
			(end 0.7874 -0.4064)
			(stroke
				(width 0.1524)
				(type default)
			)
			(layer "F.SilkS")
		)
		(fp_line
			(start 0.7874 -0.4064)
			(end 0.7874 0.4064)
			(stroke
				(width 0.1524)
				(type default)
			)
			(layer "F.SilkS")
		)
		(fp_line
			(start -0.67945 0.3048)
			(end -0.67945 -0.305054)
			(stroke
				(width 0.1)
				(type default)
			)
			(layer "F.Fab")
		)
		(fp_line
			(start -0.12065 0.3048)
			(end -0.67945 0.3048)
			(stroke
				(width 0.1)
				(type default)
			)
			(layer "F.Fab")
		)
		(fp_line
			(start 0.120396 0.3048)
			(end 0.120396 0.2794)
			(stroke
				(width 0.1)
				(type default)
			)
			(layer "F.Fab")
		)
		(fp_line
			(start 0.67945 0.3048)
			(end 0.120396 0.3048)
			(stroke
				(width 0.1)
				(type default)
			)
			(layer "F.Fab")
		)
		(fp_line
			(start -0.12065 0.2794)
			(end -0.12065 0.3048)
			(stroke
				(width 0.1)
				(type default)
			)
			(layer "F.Fab")
		)
		(fp_line
			(start 0.120396 0.2794)
			(end -0.12065 0.2794)
			(stroke
				(width 0.1)
				(type default)
			)
			(layer "F.Fab")
		)
		(fp_line
			(start -0.12065 -0.2794)
			(end 0.12065 -0.2794)
			(stroke
				(width 0.1)
				(type default)
			)
			(layer "F.Fab")
		)
		(fp_line
			(start 0.12065 -0.2794)
			(end 0.12065 -0.3048)
			(stroke
				(width 0.1)
				(type default)
			)
			(layer "F.Fab")
		)
		(fp_line
			(start 0.12065 -0.3048)
			(end 0.67945 -0.3048)
			(stroke
				(width 0.1)
				(type default)
			)
			(layer "F.Fab")
		)
		(fp_line
			(start 0.67945 -0.3048)
			(end 0.67945 0.3048)
			(stroke
				(width 0.1)
				(type default)
			)
			(layer "F.Fab")
		)
		(fp_line
			(start -0.67945 -0.305054)
			(end -0.12065 -0.305054)
			(stroke
				(width 0.1)
				(type default)
			)
			(layer "F.Fab")
		)
		(fp_line
			(start -0.12065 -0.305054)
			(end -0.12065 -0.2794)
			(stroke
				(width 0.1)
				(type default)
			)
			(layer "F.Fab")
		)
		(pad "1" smd circle
			(at -0.40005 0 270)
			(size 0 0)
			(layers "F.Cu" "F.Mask" "F.Paste")
			(net "PWRGD_CPU0_LVC1_R")
		)
		(pad "2" smd circle
			(at 0.40005 0 270)
			(size 0 0)
			(layers "F.Cu" "F.Mask" "F.Paste")
			(net "GND")
		)
	)
	(footprint ""
		(layer "F.Cu")
		(at 14.01826 -92.687648 -90)
		(property "Reference" "R3666"
			(at 0 0 270)
			(layer "F.SilkS")
			(hide yes)
			(effects
				(font
					(size 1.27 1.27)
				)
			)
		)
		(property "Value" ""
			(at 0 0 270)
			(layer "F.Fab")
			(effects
				(font
					(size 1.27 1.27)
				)
			)
		)
		(duplicate_pad_numbers_are_jumpers no)
		(fp_line
			(start -0.7874 0.4064)
			(end -0.7874 -0.4064)
			(stroke
				(width 0.1524)
				(type default)
			)
			(layer "F.SilkS")
		)
		(fp_line
			(start 0.7874 0.4064)
			(end -0.7874 0.4064)
			(stroke
				(width 0.1524)
				(type default)
			)
			(layer "F.SilkS")
		)
		(fp_line
			(start -0.7874 -0.4064)
			(end 0.7874 -0.4064)
			(stroke
				(width 0.1524)
				(type default)
			)
			(layer "F.SilkS")
		)
		(fp_line
			(start 0.7874 -0.4064)
			(end 0.7874 0.4064)
			(stroke
				(width 0.1524)
				(type default)
			)
			(layer "F.SilkS")
		)
		(fp_line
			(start -0.67945 0.3048)
			(end -0.67945 -0.305054)
			(stroke
				(width 0.1)
				(type default)
			)
			(layer "F.Fab")
		)
		(fp_line
			(start -0.12065 0.3048)
			(end -0.67945 0.3048)
			(stroke
				(width 0.1)
				(type default)
			)
			(layer "F.Fab")
		)
		(fp_line
			(start 0.120396 0.3048)
			(end 0.120396 0.2794)
			(stroke
				(width 0.1)
				(type default)
			)
			(layer "F.Fab")
		)
		(fp_line
			(start 0.67945 0.3048)
			(end 0.120396 0.3048)
			(stroke
				(width 0.1)
				(type default)
			)
			(layer "F.Fab")
		)
		(fp_line
			(start -0.12065 0.2794)
			(end -0.12065 0.3048)
			(stroke
				(width 0.1)
				(type default)
			)
			(layer "F.Fab")
		)
		(fp_line
			(start 0.120396 0.2794)
			(end -0.12065 0.2794)
			(stroke
				(width 0.1)
				(type default)
			)
			(layer "F.Fab")
		)
		(fp_line
			(start -0.12065 -0.2794)
			(end 0.12065 -0.2794)
			(stroke
				(width 0.1)
				(type default)
			)
			(layer "F.Fab")
		)
		(fp_line
			(start 0.12065 -0.2794)
			(end 0.12065 -0.3048)
			(stroke
				(width 0.1)
				(type default)
			)
			(layer "F.Fab")
		)
		(fp_line
			(start 0.12065 -0.3048)
			(end 0.67945 -0.3048)
			(stroke
				(width 0.1)
				(type default)
			)
			(layer "F.Fab")
		)
		(fp_line
			(start 0.67945 -0.3048)
			(end 0.67945 0.3048)
			(stroke
				(width 0.1)
				(type default)
			)
			(layer "F.Fab")
		)
		(fp_line
			(start -0.67945 -0.305054)
			(end -0.12065 -0.305054)
			(stroke
				(width 0.1)
				(type default)
			)
			(layer "F.Fab")
		)
		(fp_line
			(start -0.12065 -0.305054)
			(end -0.12065 -0.2794)
			(stroke
				(width 0.1)
				(type default)
			)
			(layer "F.Fab")
		)
		(pad "1" smd circle
			(at -0.40005 0 270)
			(size 0 0)
			(layers "F.Cu" "F.Mask" "F.Paste")
			(net "USB_HUB_TEST")
		)
		(pad "2" smd circle
			(at 0.40005 0 270)
			(size 0 0)
			(layers "F.Cu" "F.Mask" "F.Paste")
			(net "GND")
		)
	)
	(footprint ""
		(layer "F.Cu")
		(at 282.73756 -424.558714 90)
		(property "Reference" "R4693"
			(at 0 0 90)
			(layer "F.SilkS")
			(hide yes)
			(effects
				(font
					(size 1.27 1.27)
				)
			)
		)
		(property "Value" ""
			(at 0 0 90)
			(layer "F.Fab")
			(effects
				(font
					(size 1.27 1.27)
				)
			)
		)
		(duplicate_pad_numbers_are_jumpers no)
		(fp_line
			(start 0.7874 -0.4064)
			(end 0.7874 0.4064)
			(stroke
				(width 0.1524)
				(type default)
			)
			(layer "F.SilkS")
		)
		(fp_line
			(start -0.7874 -0.4064)
			(end 0.7874 -0.4064)
			(stroke
				(width 0.1524)
				(type default)
			)
			(layer "F.SilkS")
		)
		(fp_line
			(start 0.7874 0.4064)
			(end -0.7874 0.4064)
			(stroke
				(width 0.1524)
				(type default)
			)
			(layer "F.SilkS")
		)
		(fp_line
			(start -0.7874 0.4064)
			(end -0.7874 -0.4064)
			(stroke
				(width 0.1524)
				(type default)
			)
			(layer "F.SilkS")
		)
		(fp_line
			(start -0.12065 -0.305054)
			(end -0.12065 -0.2794)
			(stroke
				(width 0.1)
				(type default)
			)
			(layer "F.Fab")
		)
		(fp_line
			(start -0.67945 -0.305054)
			(end -0.12065 -0.305054)
			(stroke
				(width 0.1)
				(type default)
			)
			(layer "F.Fab")
		)
		(fp_line
			(start 0.67945 -0.3048)
			(end 0.67945 0.3048)
			(stroke
				(width 0.1)
				(type default)
			)
			(layer "F.Fab")
		)
		(fp_line
			(start 0.12065 -0.3048)
			(end 0.67945 -0.3048)
			(stroke
				(width 0.1)
				(type default)
			)
			(layer "F.Fab")
		)
		(fp_line
			(start 0.12065 -0.2794)
			(end 0.12065 -0.3048)
			(stroke
				(width 0.1)
				(type default)
			)
			(layer "F.Fab")
		)
		(fp_line
			(start -0.12065 -0.2794)
			(end 0.12065 -0.2794)
			(stroke
				(width 0.1)
				(type default)
			)
			(layer "F.Fab")
		)
		(fp_line
			(start 0.120396 0.2794)
			(end -0.12065 0.2794)
			(stroke
				(width 0.1)
				(type default)
			)
			(layer "F.Fab")
		)
		(fp_line
			(start -0.12065 0.2794)
			(end -0.12065 0.3048)
			(stroke
				(width 0.1)
				(type default)
			)
			(layer "F.Fab")
		)
		(fp_line
			(start 0.67945 0.3048)
			(end 0.120396 0.3048)
			(stroke
				(width 0.1)
				(type default)
			)
			(layer "F.Fab")
		)
		(fp_line
			(start 0.120396 0.3048)
			(end 0.120396 0.2794)
			(stroke
				(width 0.1)
				(type default)
			)
			(layer "F.Fab")
		)
		(fp_line
			(start -0.12065 0.3048)
			(end -0.67945 0.3048)
			(stroke
				(width 0.1)
				(type default)
			)
			(layer "F.Fab")
		)
		(fp_line
			(start -0.67945 0.3048)
			(end -0.67945 -0.305054)
			(stroke
				(width 0.1)
				(type default)
			)
			(layer "F.Fab")
		)
		(pad "1" smd circle
			(at -0.40005 0 90)
			(size 0 0)
			(layers "F.Cu" "F.Mask" "F.Paste")
			(net "HSC_CSOUT")
		)
		(pad "2" smd circle
			(at 0.40005 0 90)
			(size 0 0)
			(layers "F.Cu" "F.Mask" "F.Paste")
			(net "HSC_D_OC")
		)
	)
	(footprint ""
		(layer "F.Cu")
		(at 231.976422 -117.710712 -90)
		(property "Reference" "R1276"
			(at 0 0 270)
			(layer "F.SilkS")
			(hide yes)
			(effects
				(font
					(size 1.27 1.27)
				)
			)
		)
		(property "Value" ""
			(at 0 0 270)
			(layer "F.Fab")
			(effects
				(font
					(size 1.27 1.27)
				)
			)
		)
		(duplicate_pad_numbers_are_jumpers no)
		(fp_line
			(start 0.418592 0.4064)
			(end -0.373888 0.4064)
			(stroke
				(width 0.1524)
				(type default)
			)
			(layer "F.SilkS")
		)
		(fp_line
			(start -0.7874 -0.006858)
			(end -0.7874 -0.4064)
			(stroke
				(width 0.1524)
				(type default)
			)
			(layer "F.SilkS")
		)
		(fp_line
			(start -0.7874 -0.4064)
			(end 0.7874 -0.4064)
			(stroke
				(width 0.1524)
				(type default)
			)
			(layer "F.SilkS")
		)
		(fp_line
			(start 0.7874 -0.4064)
			(end 0.7874 0.079502)
			(stroke
				(width 0.1524)
				(type default)
			)
			(layer "F.SilkS")
		)
		(fp_line
			(start -0.67945 0.3048)
			(end -0.67945 -0.305054)
			(stroke
				(width 0.1)
				(type default)
			)
			(layer "F.Fab")
		)
		(fp_line
			(start -0.12065 0.3048)
			(end -0.67945 0.3048)
			(stroke
				(width 0.1)
				(type default)
			)
			(layer "F.Fab")
		)
		(fp_line
			(start 0.120396 0.3048)
			(end 0.120396 0.2794)
			(stroke
				(width 0.1)
				(type default)
			)
			(layer "F.Fab")
		)
		(fp_line
			(start 0.67945 0.3048)
			(end 0.120396 0.3048)
			(stroke
				(width 0.1)
				(type default)
			)
			(layer "F.Fab")
		)
		(fp_line
			(start -0.12065 0.2794)
			(end -0.12065 0.3048)
			(stroke
				(width 0.1)
				(type default)
			)
			(layer "F.Fab")
		)
		(fp_line
			(start 0.120396 0.2794)
			(end -0.12065 0.2794)
			(stroke
				(width 0.1)
				(type default)
			)
			(layer "F.Fab")
		)
		(fp_line
			(start -0.12065 -0.2794)
			(end 0.12065 -0.2794)
			(stroke
				(width 0.1)
				(type default)
			)
			(layer "F.Fab")
		)
		(fp_line
			(start 0.12065 -0.2794)
			(end 0.12065 -0.3048)
			(stroke
				(width 0.1)
				(type default)
			)
			(layer "F.Fab")
		)
		(fp_line
			(start 0.12065 -0.3048)
			(end 0.67945 -0.3048)
			(stroke
				(width 0.1)
				(type default)
			)
			(layer "F.Fab")
		)
		(fp_line
			(start 0.67945 -0.3048)
			(end 0.67945 0.3048)
			(stroke
				(width 0.1)
				(type default)
			)
			(layer "F.Fab")
		)
		(fp_line
			(start -0.67945 -0.305054)
			(end -0.12065 -0.305054)
			(stroke
				(width 0.1)
				(type default)
			)
			(layer "F.Fab")
		)
		(fp_line
			(start -0.12065 -0.305054)
			(end -0.12065 -0.2794)
			(stroke
				(width 0.1)
				(type default)
			)
			(layer "F.Fab")
		)
		(pad "1" smd circle
			(at -0.40005 0 270)
			(size 0 0)
			(layers "F.Cu" "F.Mask" "F.Paste")
			(net "CLK_100M_OCP_SFF_3_R_DN")
		)
		(pad "2" smd circle
			(at 0.40005 0 270)
			(size 0 0)
			(layers "F.Cu" "F.Mask" "F.Paste")
			(net "CLK_100M_OCP_SFF_3_DN")
		)
	)
	(footprint ""
		(layer "F.Cu")
		(at 430.355756 -109.25937 -90)
		(property "Reference" "PC2093"
			(at 0 0 270)
			(layer "F.SilkS")
			(hide yes)
			(effects
				(font
					(size 1.27 1.27)
				)
			)
		)
		(property "Value" ""
			(at 0 0 270)
			(layer "F.Fab")
			(effects
				(font
					(size 1.27 1.27)
				)
			)
		)
		(duplicate_pad_numbers_are_jumpers no)
		(fp_line
			(start -0.7874 0.4064)
			(end -0.7874 -0.4064)
			(stroke
				(width 0.1524)
				(type default)
			)
			(layer "F.SilkS")
		)
		(fp_line
			(start 0.7874 0.4064)
			(end -0.7874 0.4064)
			(stroke
				(width 0.1524)
				(type default)
			)
			(layer "F.SilkS")
		)
		(fp_line
			(start -0.7874 -0.4064)
			(end 0.7874 -0.4064)
			(stroke
				(width 0.1524)
				(type default)
			)
			(layer "F.SilkS")
		)
		(fp_line
			(start 0.7874 -0.4064)
			(end 0.7874 0.4064)
			(stroke
				(width 0.1524)
				(type default)
			)
			(layer "F.SilkS")
		)
		(fp_line
			(start -0.67945 0.3048)
			(end -0.67945 -0.305054)
			(stroke
				(width 0.1)
				(type default)
			)
			(layer "F.Fab")
		)
		(fp_line
			(start -0.12065 0.3048)
			(end -0.67945 0.3048)
			(stroke
				(width 0.1)
				(type default)
			)
			(layer "F.Fab")
		)
		(fp_line
			(start 0.120396 0.3048)
			(end 0.120396 0.2794)
			(stroke
				(width 0.1)
				(type default)
			)
			(layer "F.Fab")
		)
		(fp_line
			(start 0.67945 0.3048)
			(end 0.120396 0.3048)
			(stroke
				(width 0.1)
				(type default)
			)
			(layer "F.Fab")
		)
		(fp_line
			(start -0.12065 0.2794)
			(end -0.12065 0.3048)
			(stroke
				(width 0.1)
				(type default)
			)
			(layer "F.Fab")
		)
		(fp_line
			(start 0.120396 0.2794)
			(end -0.12065 0.2794)
			(stroke
				(width 0.1)
				(type default)
			)
			(layer "F.Fab")
		)
		(fp_line
			(start -0.12065 -0.2794)
			(end 0.12065 -0.2794)
			(stroke
				(width 0.1)
				(type default)
			)
			(layer "F.Fab")
		)
		(fp_line
			(start 0.12065 -0.2794)
			(end 0.12065 -0.3048)
			(stroke
				(width 0.1)
				(type default)
			)
			(layer "F.Fab")
		)
		(fp_line
			(start 0.12065 -0.3048)
			(end 0.67945 -0.3048)
			(stroke
				(width 0.1)
				(type default)
			)
			(layer "F.Fab")
		)
		(fp_line
			(start 0.67945 -0.3048)
			(end 0.67945 0.3048)
			(stroke
				(width 0.1)
				(type default)
			)
			(layer "F.Fab")
		)
		(fp_line
			(start -0.67945 -0.305054)
			(end -0.12065 -0.305054)
			(stroke
				(width 0.1)
				(type default)
			)
			(layer "F.Fab")
		)
		(fp_line
			(start -0.12065 -0.305054)
			(end -0.12065 -0.2794)
			(stroke
				(width 0.1)
				(type default)
			)
			(layer "F.Fab")
		)
		(pad "1" smd circle
			(at -0.40005 0 270)
			(size 0 0)
			(layers "F.Cu" "F.Mask" "F.Paste")
			(net "GND")
		)
		(pad "2" smd circle
			(at 0.40005 0 270)
			(size 0 0)
			(layers "F.Cu" "F.Mask" "F.Paste")
			(net "P3V3_OCP_REG_1")
		)
	)
	(footprint ""
		(layer "F.Cu")
		(at 96.57588 -56.225948 180)
		(property "Reference" "R3027"
			(at 0 0 180)
			(layer "F.SilkS")
			(hide yes)
			(effects
				(font
					(size 1.27 1.27)
				)
			)
		)
		(property "Value" ""
			(at 0 0 180)
			(layer "F.Fab")
			(effects
				(font
					(size 1.27 1.27)
				)
			)
		)
		(duplicate_pad_numbers_are_jumpers no)
		(fp_line
			(start 0.7874 0.4064)
			(end -0.7874 0.4064)
			(stroke
				(width 0.1524)
				(type default)
			)
			(layer "F.SilkS")
		)
		(fp_line
			(start 0.7874 -0.4064)
			(end 0.7874 0.4064)
			(stroke
				(width 0.1524)
				(type default)
			)
			(layer "F.SilkS")
		)
		(fp_line
			(start -0.7874 0.4064)
			(end -0.7874 -0.4064)
			(stroke
				(width 0.1524)
				(type default)
			)
			(layer "F.SilkS")
		)
		(fp_line
			(start -0.7874 -0.4064)
			(end 0.7874 -0.4064)
			(stroke
				(width 0.1524)
				(type default)
			)
			(layer "F.SilkS")
		)
		(fp_line
			(start 0.67945 0.3048)
			(end 0.120396 0.3048)
			(stroke
				(width 0.1)
				(type default)
			)
			(layer "F.Fab")
		)
		(fp_line
			(start 0.67945 -0.3048)
			(end 0.67945 0.3048)
			(stroke
				(width 0.1)
				(type default)
			)
			(layer "F.Fab")
		)
		(fp_line
			(start 0.12065 -0.2794)
			(end 0.12065 -0.3048)
			(stroke
				(width 0.1)
				(type default)
			)
			(layer "F.Fab")
		)
		(fp_line
			(start 0.12065 -0.3048)
			(end 0.67945 -0.3048)
			(stroke
				(width 0.1)
				(type default)
			)
			(layer "F.Fab")
		)
		(fp_line
			(start 0.120396 0.3048)
			(end 0.120396 0.2794)
			(stroke
				(width 0.1)
				(type default)
			)
			(layer "F.Fab")
		)
		(fp_line
			(start 0.120396 0.2794)
			(end -0.12065 0.2794)
			(stroke
				(width 0.1)
				(type default)
			)
			(layer "F.Fab")
		)
		(fp_line
			(start -0.12065 0.3048)
			(end -0.67945 0.3048)
			(stroke
				(width 0.1)
				(type default)
			)
			(layer "F.Fab")
		)
		(fp_line
			(start -0.12065 0.2794)
			(end -0.12065 0.3048)
			(stroke
				(width 0.1)
				(type default)
			)
			(layer "F.Fab")
		)
		(fp_line
			(start -0.12065 -0.2794)
			(end 0.12065 -0.2794)
			(stroke
				(width 0.1)
				(type default)
			)
			(layer "F.Fab")
		)
		(fp_line
			(start -0.12065 -0.305054)
			(end -0.12065 -0.2794)
			(stroke
				(width 0.1)
				(type default)
			)
			(layer "F.Fab")
		)
		(fp_line
			(start -0.67945 0.3048)
			(end -0.67945 -0.305054)
			(stroke
				(width 0.1)
				(type default)
			)
			(layer "F.Fab")
		)
		(fp_line
			(start -0.67945 -0.305054)
			(end -0.12065 -0.305054)
			(stroke
				(width 0.1)
				(type default)
			)
			(layer "F.Fab")
		)
		(pad "1" smd circle
			(at -0.40005 0 180)
			(size 0 0)
			(layers "F.Cu" "F.Mask" "F.Paste")
			(net "JTAG_BMC_CPU_TCK")
		)
		(pad "2" smd circle
			(at 0.40005 0 180)
			(size 0 0)
			(layers "F.Cu" "F.Mask" "F.Paste")
			(net "GND")
		)
	)
	(footprint ""
		(layer "F.Cu")
		(at 77.8764 -37.262308 180)
		(property "Reference" "C1819"
			(at 0 0 180)
			(layer "F.SilkS")
			(hide yes)
			(effects
				(font
					(size 1.27 1.27)
				)
			)
		)
		(property "Value" ""
			(at 0 0 180)
			(layer "F.Fab")
			(effects
				(font
					(size 1.27 1.27)
				)
			)
		)
		(duplicate_pad_numbers_are_jumpers no)
		(fp_line
			(start 0.7874 0.4064)
			(end -0.7874 0.4064)
			(stroke
				(width 0.1524)
				(type default)
			)
			(layer "F.SilkS")
		)
		(fp_line
			(start 0.7874 -0.4064)
			(end 0.7874 0.4064)
			(stroke
				(width 0.1524)
				(type default)
			)
			(layer "F.SilkS")
		)
		(fp_line
			(start -0.7874 0.4064)
			(end -0.7874 -0.4064)
			(stroke
				(width 0.1524)
				(type default)
			)
			(layer "F.SilkS")
		)
		(fp_line
			(start -0.7874 -0.4064)
			(end 0.7874 -0.4064)
			(stroke
				(width 0.1524)
				(type default)
			)
			(layer "F.SilkS")
		)
		(fp_line
			(start 0.67945 0.3048)
			(end 0.120396 0.3048)
			(stroke
				(width 0.1)
				(type default)
			)
			(layer "F.Fab")
		)
		(fp_line
			(start 0.67945 -0.3048)
			(end 0.67945 0.3048)
			(stroke
				(width 0.1)
				(type default)
			)
			(layer "F.Fab")
		)
		(fp_line
			(start 0.12065 -0.2794)
			(end 0.12065 -0.3048)
			(stroke
				(width 0.1)
				(type default)
			)
			(layer "F.Fab")
		)
		(fp_line
			(start 0.12065 -0.3048)
			(end 0.67945 -0.3048)
			(stroke
				(width 0.1)
				(type default)
			)
			(layer "F.Fab")
		)
		(fp_line
			(start 0.120396 0.3048)
			(end 0.120396 0.2794)
			(stroke
				(width 0.1)
				(type default)
			)
			(layer "F.Fab")
		)
		(fp_line
			(start 0.120396 0.2794)
			(end -0.12065 0.2794)
			(stroke
				(width 0.1)
				(type default)
			)
			(layer "F.Fab")
		)
		(fp_line
			(start -0.12065 0.3048)
			(end -0.67945 0.3048)
			(stroke
				(width 0.1)
				(type default)
			)
			(layer "F.Fab")
		)
		(fp_line
			(start -0.12065 0.2794)
			(end -0.12065 0.3048)
			(stroke
				(width 0.1)
				(type default)
			)
			(layer "F.Fab")
		)
		(fp_line
			(start -0.12065 -0.2794)
			(end 0.12065 -0.2794)
			(stroke
				(width 0.1)
				(type default)
			)
			(layer "F.Fab")
		)
		(fp_line
			(start -0.12065 -0.305054)
			(end -0.12065 -0.2794)
			(stroke
				(width 0.1)
				(type default)
			)
			(layer "F.Fab")
		)
		(fp_line
			(start -0.67945 0.3048)
			(end -0.67945 -0.305054)
			(stroke
				(width 0.1)
				(type default)
			)
			(layer "F.Fab")
		)
		(fp_line
			(start -0.67945 -0.305054)
			(end -0.12065 -0.305054)
			(stroke
				(width 0.1)
				(type default)
			)
			(layer "F.Fab")
		)
		(pad "1" smd circle
			(at -0.40005 0 180)
			(size 0 0)
			(layers "F.Cu" "F.Mask" "F.Paste")
			(net "P3V3_OCP_V3_2")
		)
		(pad "2" smd circle
			(at 0.40005 0 180)
			(size 0 0)
			(layers "F.Cu" "F.Mask" "F.Paste")
			(net "GND")
		)
	)
	(footprint ""
		(layer "F.Cu")
		(at 382.165352 -342.726264 -90)
		(property "Reference" "PC228_P0_8"
			(at 0 0 270)
			(layer "F.SilkS")
			(hide yes)
			(effects
				(font
					(size 1.27 1.27)
				)
			)
		)
		(property "Value" ""
			(at 0 0 270)
			(layer "F.Fab")
			(effects
				(font
					(size 1.27 1.27)
				)
			)
		)
		(duplicate_pad_numbers_are_jumpers no)
		(fp_line
			(start -0.7874 0.4064)
			(end -0.7874 -0.4064)
			(stroke
				(width 0.1524)
				(type default)
			)
			(layer "F.SilkS")
		)
		(fp_line
			(start 0.7874 0.4064)
			(end -0.7874 0.4064)
			(stroke
				(width 0.1524)
				(type default)
			)
			(layer "F.SilkS")
		)
		(fp_line
			(start -0.7874 -0.4064)
			(end 0.7874 -0.4064)
			(stroke
				(width 0.1524)
				(type default)
			)
			(layer "F.SilkS")
		)
		(fp_line
			(start 0.7874 -0.4064)
			(end 0.7874 0.4064)
			(stroke
				(width 0.1524)
				(type default)
			)
			(layer "F.SilkS")
		)
		(fp_line
			(start -0.67945 0.3048)
			(end -0.67945 -0.305054)
			(stroke
				(width 0.1)
				(type default)
			)
			(layer "F.Fab")
		)
		(fp_line
			(start -0.12065 0.3048)
			(end -0.67945 0.3048)
			(stroke
				(width 0.1)
				(type default)
			)
			(layer "F.Fab")
		)
		(fp_line
			(start 0.120396 0.3048)
			(end 0.120396 0.2794)
			(stroke
				(width 0.1)
				(type default)
			)
			(layer "F.Fab")
		)
		(fp_line
			(start 0.67945 0.3048)
			(end 0.120396 0.3048)
			(stroke
				(width 0.1)
				(type default)
			)
			(layer "F.Fab")
		)
		(fp_line
			(start -0.12065 0.2794)
			(end -0.12065 0.3048)
			(stroke
				(width 0.1)
				(type default)
			)
			(layer "F.Fab")
		)
		(fp_line
			(start 0.120396 0.2794)
			(end -0.12065 0.2794)
			(stroke
				(width 0.1)
				(type default)
			)
			(layer "F.Fab")
		)
		(fp_line
			(start -0.12065 -0.2794)
			(end 0.12065 -0.2794)
			(stroke
				(width 0.1)
				(type default)
			)
			(layer "F.Fab")
		)
		(fp_line
			(start 0.12065 -0.2794)
			(end 0.12065 -0.3048)
			(stroke
				(width 0.1)
				(type default)
			)
			(layer "F.Fab")
		)
		(fp_line
			(start 0.12065 -0.3048)
			(end 0.67945 -0.3048)
			(stroke
				(width 0.1)
				(type default)
			)
			(layer "F.Fab")
		)
		(fp_line
			(start 0.67945 -0.3048)
			(end 0.67945 0.3048)
			(stroke
				(width 0.1)
				(type default)
			)
			(layer "F.Fab")
		)
		(fp_line
			(start -0.67945 -0.305054)
			(end -0.12065 -0.305054)
			(stroke
				(width 0.1)
				(type default)
			)
			(layer "F.Fab")
		)
		(fp_line
			(start -0.12065 -0.305054)
			(end -0.12065 -0.2794)
			(stroke
				(width 0.1)
				(type default)
			)
			(layer "F.Fab")
		)
		(pad "1" smd circle
			(at -0.40005 0 270)
			(size 0 0)
			(layers "F.Cu" "F.Mask" "F.Paste")
			(net "PVCCIN_CPU0_PVCC")
		)
		(pad "2" smd circle
			(at 0.40005 0 270)
			(size 0 0)
			(layers "F.Cu" "F.Mask" "F.Paste")
			(net "GND")
		)
	)
	(footprint ""
		(layer "F.Cu")
		(at 349.0849 -62.398148)
		(property "Reference" "C141"
			(at 0 0 0)
			(layer "F.SilkS")
			(hide yes)
			(effects
				(font
					(size 1.27 1.27)
				)
			)
		)
		(property "Value" ""
			(at 0 0 0)
			(layer "F.Fab")
			(effects
				(font
					(size 1.27 1.27)
				)
			)
		)
		(duplicate_pad_numbers_are_jumpers no)
		(fp_line
			(start -0.299974 -0.150114)
			(end 0.299974 -0.150114)
			(stroke
				(width 0.1)
				(type default)
			)
			(layer "F.Fab")
		)
		(fp_line
			(start -0.299974 0.150114)
			(end -0.299974 -0.150114)
			(stroke
				(width 0.1)
				(type default)
			)
			(layer "F.Fab")
		)
		(fp_line
			(start 0.299974 -0.150114)
			(end 0.299974 0.150114)
			(stroke
				(width 0.1)
				(type default)
			)
			(layer "F.Fab")
		)
		(fp_line
			(start 0.299974 0.150114)
			(end -0.299974 0.150114)
			(stroke
				(width 0.1)
				(type default)
			)
			(layer "F.Fab")
		)
		(pad "1" smd rect
			(at -0.2667 0)
			(size 0.3048 0.381)
			(layers "F.Cu" "F.Mask" "F.Paste")
			(net "DMI_CPU0_PCH_TX_C_DN<6>")
		)
		(pad "2" smd rect
			(at 0.2667 0)
			(size 0.3048 0.381)
			(layers "F.Cu" "F.Mask" "F.Paste")
			(net "DMI_CPU0_PCH_TX_DN<6>")
		)
		(zone
			(layer "In1.Cu")
			(hatch none 0.5)
			(connect_pads
				(clearance 0)
			)
			(min_thickness 0.25)
			(keepout
				(tracks not_allowed)
				(vias allowed)
				(pads allowed)
				(copperpour not_allowed)
				(footprints allowed)
			)
			(placement
				(enabled no)
				(sheetname "")
			)
			(fill
				(thermal_gap 0.5)
				(thermal_bridge_width 0.5)
				(island_removal_mode 0)
			)
			(polygon
				(pts
					(arc
						(start 348.6912 -62.156848)
						(mid 348.637318 -62.179166)
						(end 348.615 -62.233048)
					)
					(arc
						(start 348.615 -62.563248)
						(mid 348.637318 -62.61713)
						(end 348.6912 -62.639448)
					)
					(arc
						(start 348.9452 -62.639448)
						(mid 348.999082 -62.61713)
						(end 349.0214 -62.563248)
					)
					(arc
						(start 349.0214 -62.233048)
						(mid 348.999082 -62.179166)
						(end 348.9452 -62.156848)
					)
				)
			)
		)
		(zone
			(layer "In1.Cu")
			(hatch none 0.5)
			(connect_pads
				(clearance 0)
			)
			(min_thickness 0.25)
			(keepout
				(tracks not_allowed)
				(vias allowed)
				(pads allowed)
				(copperpour not_allowed)
				(footprints allowed)
			)
			(placement
				(enabled no)
				(sheetname "")
			)
			(fill
				(thermal_gap 0.5)
				(thermal_bridge_width 0.5)
				(island_removal_mode 0)
			)
			(polygon
				(pts
					(arc
						(start 349.2246 -62.156848)
						(mid 349.170718 -62.179166)
						(end 349.1484 -62.233048)
					)
					(arc
						(start 349.1484 -62.563248)
						(mid 349.170718 -62.61713)
						(end 349.2246 -62.639448)
					)
					(arc
						(start 349.4786 -62.639448)
						(mid 349.532482 -62.61713)
						(end 349.5548 -62.563248)
					)
					(arc
						(start 349.5548 -62.233048)
						(mid 349.532482 -62.179166)
						(end 349.4786 -62.156848)
					)
				)
			)
		)
	)
	(footprint ""
		(layer "F.Cu")
		(at 422.13403 -49.76749 180)
		(property "Reference" "R1706"
			(at 0 0 180)
			(layer "F.SilkS")
			(hide yes)
			(effects
				(font
					(size 1.27 1.27)
				)
			)
		)
		(property "Value" ""
			(at 0 0 180)
			(layer "F.Fab")
			(effects
				(font
					(size 1.27 1.27)
				)
			)
		)
		(duplicate_pad_numbers_are_jumpers no)
		(fp_line
			(start 0.7874 0.4064)
			(end -0.7874 0.4064)
			(stroke
				(width 0.1524)
				(type default)
			)
			(layer "F.SilkS")
		)
		(fp_line
			(start 0.7874 -0.4064)
			(end 0.7874 0.4064)
			(stroke
				(width 0.1524)
				(type default)
			)
			(layer "F.SilkS")
		)
		(fp_line
			(start -0.7874 0.4064)
			(end -0.7874 -0.4064)
			(stroke
				(width 0.1524)
				(type default)
			)
			(layer "F.SilkS")
		)
		(fp_line
			(start -0.7874 -0.4064)
			(end 0.7874 -0.4064)
			(stroke
				(width 0.1524)
				(type default)
			)
			(layer "F.SilkS")
		)
		(fp_line
			(start 0.67945 0.3048)
			(end 0.120396 0.3048)
			(stroke
				(width 0.1)
				(type default)
			)
			(layer "F.Fab")
		)
		(fp_line
			(start 0.67945 -0.3048)
			(end 0.67945 0.3048)
			(stroke
				(width 0.1)
				(type default)
			)
			(layer "F.Fab")
		)
		(fp_line
			(start 0.12065 -0.2794)
			(end 0.12065 -0.3048)
			(stroke
				(width 0.1)
				(type default)
			)
			(layer "F.Fab")
		)
		(fp_line
			(start 0.12065 -0.3048)
			(end 0.67945 -0.3048)
			(stroke
				(width 0.1)
				(type default)
			)
			(layer "F.Fab")
		)
		(fp_line
			(start 0.120396 0.3048)
			(end 0.120396 0.2794)
			(stroke
				(width 0.1)
				(type default)
			)
			(layer "F.Fab")
		)
		(fp_line
			(start 0.120396 0.2794)
			(end -0.12065 0.2794)
			(stroke
				(width 0.1)
				(type default)
			)
			(layer "F.Fab")
		)
		(fp_line
			(start -0.12065 0.3048)
			(end -0.67945 0.3048)
			(stroke
				(width 0.1)
				(type default)
			)
			(layer "F.Fab")
		)
		(fp_line
			(start -0.12065 0.2794)
			(end -0.12065 0.3048)
			(stroke
				(width 0.1)
				(type default)
			)
			(layer "F.Fab")
		)
		(fp_line
			(start -0.12065 -0.2794)
			(end 0.12065 -0.2794)
			(stroke
				(width 0.1)
				(type default)
			)
			(layer "F.Fab")
		)
		(fp_line
			(start -0.12065 -0.305054)
			(end -0.12065 -0.2794)
			(stroke
				(width 0.1)
				(type default)
			)
			(layer "F.Fab")
		)
		(fp_line
			(start -0.67945 0.3048)
			(end -0.67945 -0.305054)
			(stroke
				(width 0.1)
				(type default)
			)
			(layer "F.Fab")
		)
		(fp_line
			(start -0.67945 -0.305054)
			(end -0.12065 -0.305054)
			(stroke
				(width 0.1)
				(type default)
			)
			(layer "F.Fab")
		)
		(pad "1" smd circle
			(at -0.40005 0 180)
			(size 0 0)
			(layers "F.Cu" "F.Mask" "F.Paste")
			(net "P3V3")
		)
		(pad "2" smd circle
			(at 0.40005 0 180)
			(size 0 0)
			(layers "F.Cu" "F.Mask" "F.Paste")
			(net "PWRGD_P3V3_R1")
		)
	)
	(footprint ""
		(layer "F.Cu")
		(at 20.60956 -70.814692)
		(property "Reference" "R3136"
			(at 0 0 0)
			(layer "F.SilkS")
			(hide yes)
			(effects
				(font
					(size 1.27 1.27)
				)
			)
		)
		(property "Value" ""
			(at 0 0 0)
			(layer "F.Fab")
			(effects
				(font
					(size 1.27 1.27)
				)
			)
		)
		(duplicate_pad_numbers_are_jumpers no)
		(fp_line
			(start -0.7874 -0.4064)
			(end 0.7874 -0.4064)
			(stroke
				(width 0.1524)
				(type default)
			)
			(layer "F.SilkS")
		)
		(fp_line
			(start -0.7874 0.4064)
			(end -0.7874 -0.4064)
			(stroke
				(width 0.1524)
				(type default)
			)
			(layer "F.SilkS")
		)
		(fp_line
			(start 0.7874 -0.4064)
			(end 0.7874 0.4064)
			(stroke
				(width 0.1524)
				(type default)
			)
			(layer "F.SilkS")
		)
		(fp_line
			(start 0.7874 0.4064)
			(end -0.7874 0.4064)
			(stroke
				(width 0.1524)
				(type default)
			)
			(layer "F.SilkS")
		)
		(fp_line
			(start -0.67945 -0.305054)
			(end -0.12065 -0.305054)
			(stroke
				(width 0.1)
				(type default)
			)
			(layer "F.Fab")
		)
		(fp_line
			(start -0.67945 0.3048)
			(end -0.67945 -0.305054)
			(stroke
				(width 0.1)
				(type default)
			)
			(layer "F.Fab")
		)
		(fp_line
			(start -0.12065 -0.305054)
			(end -0.12065 -0.2794)
			(stroke
				(width 0.1)
				(type default)
			)
			(layer "F.Fab")
		)
		(fp_line
			(start -0.12065 -0.2794)
			(end 0.12065 -0.2794)
			(stroke
				(width 0.1)
				(type default)
			)
			(layer "F.Fab")
		)
		(fp_line
			(start -0.12065 0.2794)
			(end -0.12065 0.3048)
			(stroke
				(width 0.1)
				(type default)
			)
			(layer "F.Fab")
		)
		(fp_line
			(start -0.12065 0.3048)
			(end -0.67945 0.3048)
			(stroke
				(width 0.1)
				(type default)
			)
			(layer "F.Fab")
		)
		(fp_line
			(start 0.120396 0.2794)
			(end -0.12065 0.2794)
			(stroke
				(width 0.1)
				(type default)
			)
			(layer "F.Fab")
		)
		(fp_line
			(start 0.120396 0.3048)
			(end 0.120396 0.2794)
			(stroke
				(width 0.1)
				(type default)
			)
			(layer "F.Fab")
		)
		(fp_line
			(start 0.12065 -0.3048)
			(end 0.67945 -0.3048)
			(stroke
				(width 0.1)
				(type default)
			)
			(layer "F.Fab")
		)
		(fp_line
			(start 0.12065 -0.2794)
			(end 0.12065 -0.3048)
			(stroke
				(width 0.1)
				(type default)
			)
			(layer "F.Fab")
		)
		(fp_line
			(start 0.67945 -0.3048)
			(end 0.67945 0.3048)
			(stroke
				(width 0.1)
				(type default)
			)
			(layer "F.Fab")
		)
		(fp_line
			(start 0.67945 0.3048)
			(end 0.120396 0.3048)
			(stroke
				(width 0.1)
				(type default)
			)
			(layer "F.Fab")
		)
		(pad "1" smd circle
			(at -0.40005 0)
			(size 0 0)
			(layers "F.Cu" "F.Mask" "F.Paste")
			(net "P3V3_AUX")
		)
		(pad "2" smd circle
			(at 0.40005 0)
			(size 0 0)
			(layers "F.Cu" "F.Mask" "F.Paste")
			(net "OCP_V3_2_PRSNT3_R_N")
		)
	)
	(footprint ""
		(layer "F.Cu")
		(at 395.90345 -402.371052 -90)
		(property "Reference" "C951"
			(at 0 0 270)
			(layer "F.SilkS")
			(hide yes)
			(effects
				(font
					(size 1.27 1.27)
				)
			)
		)
		(property "Value" ""
			(at 0 0 270)
			(layer "F.Fab")
			(effects
				(font
					(size 1.27 1.27)
				)
			)
		)
		(duplicate_pad_numbers_are_jumpers no)
		(fp_line
			(start -0.299974 0.150114)
			(end -0.299974 -0.150114)
			(stroke
				(width 0.1)
				(type default)
			)
			(layer "F.Fab")
		)
		(fp_line
			(start 0.299974 0.150114)
			(end -0.299974 0.150114)
			(stroke
				(width 0.1)
				(type default)
			)
			(layer "F.Fab")
		)
		(fp_line
			(start -0.299974 -0.150114)
			(end 0.299974 -0.150114)
			(stroke
				(width 0.1)
				(type default)
			)
			(layer "F.Fab")
		)
		(fp_line
			(start 0.299974 -0.150114)
			(end 0.299974 0.150114)
			(stroke
				(width 0.1)
				(type default)
			)
			(layer "F.Fab")
		)
		(pad "1" smd rect
			(at -0.2667 0 270)
			(size 0.3048 0.381)
			(layers "F.Cu" "F.Mask" "F.Paste")
			(net "P5E_CPU0_PE2_TX_C_DP<7>")
		)
		(pad "2" smd rect
			(at 0.2667 0 270)
			(size 0.3048 0.381)
			(layers "F.Cu" "F.Mask" "F.Paste")
			(net "P5E_CPU0_PE2_TX_DP<7>")
		)
	)
	(footprint ""
		(layer "F.Cu")
		(at 437.542432 -27.275536 90)
		(property "Reference" "PR3841"
			(at 0 0 90)
			(layer "F.SilkS")
			(hide yes)
			(effects
				(font
					(size 1.27 1.27)
				)
			)
		)
		(property "Value" ""
			(at 0 0 90)
			(layer "F.Fab")
			(effects
				(font
					(size 1.27 1.27)
				)
			)
		)
		(duplicate_pad_numbers_are_jumpers no)
		(fp_line
			(start 0.7874 -0.4064)
			(end 0.7874 0.4064)
			(stroke
				(width 0.1524)
				(type default)
			)
			(layer "F.SilkS")
		)
		(fp_line
			(start -0.7874 -0.4064)
			(end 0.7874 -0.4064)
			(stroke
				(width 0.1524)
				(type default)
			)
			(layer "F.SilkS")
		)
		(fp_line
			(start 0.7874 0.4064)
			(end -0.7874 0.4064)
			(stroke
				(width 0.1524)
				(type default)
			)
			(layer "F.SilkS")
		)
		(fp_line
			(start -0.7874 0.4064)
			(end -0.7874 -0.4064)
			(stroke
				(width 0.1524)
				(type default)
			)
			(layer "F.SilkS")
		)
		(fp_line
			(start -0.12065 -0.305054)
			(end -0.12065 -0.2794)
			(stroke
				(width 0.1)
				(type default)
			)
			(layer "F.Fab")
		)
		(fp_line
			(start -0.67945 -0.305054)
			(end -0.12065 -0.305054)
			(stroke
				(width 0.1)
				(type default)
			)
			(layer "F.Fab")
		)
		(fp_line
			(start 0.67945 -0.3048)
			(end 0.67945 0.3048)
			(stroke
				(width 0.1)
				(type default)
			)
			(layer "F.Fab")
		)
		(fp_line
			(start 0.12065 -0.3048)
			(end 0.67945 -0.3048)
			(stroke
				(width 0.1)
				(type default)
			)
			(layer "F.Fab")
		)
		(fp_line
			(start 0.12065 -0.2794)
			(end 0.12065 -0.3048)
			(stroke
				(width 0.1)
				(type default)
			)
			(layer "F.Fab")
		)
		(fp_line
			(start -0.12065 -0.2794)
			(end 0.12065 -0.2794)
			(stroke
				(width 0.1)
				(type default)
			)
			(layer "F.Fab")
		)
		(fp_line
			(start 0.120396 0.2794)
			(end -0.12065 0.2794)
			(stroke
				(width 0.1)
				(type default)
			)
			(layer "F.Fab")
		)
		(fp_line
			(start -0.12065 0.2794)
			(end -0.12065 0.3048)
			(stroke
				(width 0.1)
				(type default)
			)
			(layer "F.Fab")
		)
		(fp_line
			(start 0.67945 0.3048)
			(end 0.120396 0.3048)
			(stroke
				(width 0.1)
				(type default)
			)
			(layer "F.Fab")
		)
		(fp_line
			(start 0.120396 0.3048)
			(end 0.120396 0.2794)
			(stroke
				(width 0.1)
				(type default)
			)
			(layer "F.Fab")
		)
		(fp_line
			(start -0.12065 0.3048)
			(end -0.67945 0.3048)
			(stroke
				(width 0.1)
				(type default)
			)
			(layer "F.Fab")
		)
		(fp_line
			(start -0.67945 0.3048)
			(end -0.67945 -0.305054)
			(stroke
				(width 0.1)
				(type default)
			)
			(layer "F.Fab")
		)
		(pad "1" smd circle
			(at -0.40005 0 90)
			(size 0 0)
			(layers "F.Cu" "F.Mask" "F.Paste")
			(net "P12V_AUX")
		)
		(pad "2" smd circle
			(at 0.40005 0 90)
			(size 0 0)
			(layers "F.Cu" "F.Mask" "F.Paste")
			(net "P12V_OCP_OV_FB_1")
		)
	)
	(footprint ""
		(layer "F.Cu")
		(at 455.434192 -38.938962)
		(property "Reference" "U75"
			(at -1.778 -1.819148 0)
			(unlocked yes)
			(layer "F.SilkS")
			(effects
				(font
					(size 0.7874 0.5842)
					(thickness 0.1524)
				)
				(justify left)
			)
		)
		(property "Value" ""
			(at 0 0 0)
			(layer "F.Fab")
			(effects
				(font
					(size 1.27 1.27)
				)
			)
		)
		(duplicate_pad_numbers_are_jumpers no)
		(fp_line
			(start -1.695958 -1.124966)
			(end 1.695958 -1.124966)
			(stroke
				(width 0.1524)
				(type default)
			)
			(layer "F.SilkS")
		)
		(fp_line
			(start -1.695958 1.124966)
			(end -1.695958 -1.124966)
			(stroke
				(width 0.1524)
				(type default)
			)
			(layer "F.SilkS")
		)
		(fp_line
			(start 1.695958 -1.124966)
			(end 1.695958 1.124966)
			(stroke
				(width 0.1524)
				(type default)
			)
			(layer "F.SilkS")
		)
		(fp_line
			(start 1.695958 1.124966)
			(end -1.695958 1.124966)
			(stroke
				(width 0.1524)
				(type default)
			)
			(layer "F.SilkS")
		)
		(fp_poly
			(pts
				(xy -2.4892 -0.340106) (xy -2.4892 -0.959866) (xy -1.86944 -0.649986)
			)
			(stroke
				(width 0)
				(type default)
			)
			(fill yes)
			(layer "F.SilkS")
		)
		(fp_line
			(start -0.674878 -1.124966)
			(end 0.674878 -1.124966)
			(stroke
				(width 0.1)
				(type default)
			)
			(layer "F.Fab")
		)
		(fp_line
			(start -0.674878 1.124966)
			(end -0.674878 -1.124966)
			(stroke
				(width 0.1)
				(type default)
			)
			(layer "F.Fab")
		)
		(fp_line
			(start 0.674878 -1.124966)
			(end 0.674878 1.124966)
			(stroke
				(width 0.1)
				(type default)
			)
			(layer "F.Fab")
		)
		(fp_line
			(start 0.674878 1.124966)
			(end -0.674878 1.124966)
			(stroke
				(width 0.1)
				(type default)
			)
			(layer "F.Fab")
		)
		(fp_poly
			(pts
				(xy -2.4892 -0.959866) (xy -1.86944 -0.649986) (xy -2.4892 -0.340106)
			)
			(stroke
				(width 0)
				(type default)
			)
			(fill yes)
			(layer "F.Fab")
		)
		(pad "1" smd rect
			(at -0.94488 -0.649986 90)
			(size 0.3556 1.2446)
			(layers "F.Cu" "F.Mask" "F.Paste")
			(net "Net_1914")
		)
		(pad "2" smd rect
			(at -0.94488 0 90)
			(size 0.3556 1.2446)
			(layers "F.Cu" "F.Mask" "F.Paste")
			(net "RST_HP_OCP_V3_1_N")
		)
		(pad "3" smd rect
			(at -0.94488 0.649986 90)
			(size 0.3556 1.2446)
			(layers "F.Cu" "F.Mask" "F.Paste")
			(net "GND")
		)
		(pad "4" smd rect
			(at 0.94488 0.649986 90)
			(size 0.3556 1.2446)
			(layers "F.Cu" "F.Mask" "F.Paste")
			(net "RST_OCP_V3_1_BUF_N")
		)
		(pad "5" smd rect
			(at 0.94488 -0.649986 90)
			(size 0.3556 1.2446)
			(layers "F.Cu" "F.Mask" "F.Paste")
			(net "P3V3_AUX")
		)
	)
	(footprint ""
		(layer "F.Cu")
		(at 346.964254 -24.66213 90)
		(property "Reference" "R1025"
			(at 0 0 90)
			(layer "F.SilkS")
			(hide yes)
			(effects
				(font
					(size 1.27 1.27)
				)
			)
		)
		(property "Value" ""
			(at 0 0 90)
			(layer "F.Fab")
			(effects
				(font
					(size 1.27 1.27)
				)
			)
		)
		(duplicate_pad_numbers_are_jumpers no)
		(fp_line
			(start 0.7874 -0.4064)
			(end 0.7874 0.4064)
			(stroke
				(width 0.1524)
				(type default)
			)
			(layer "F.SilkS")
		)
		(fp_line
			(start -0.7874 -0.4064)
			(end 0.7874 -0.4064)
			(stroke
				(width 0.1524)
				(type default)
			)
			(layer "F.SilkS")
		)
		(fp_line
			(start 0.7874 0.4064)
			(end -0.7874 0.4064)
			(stroke
				(width 0.1524)
				(type default)
			)
			(layer "F.SilkS")
		)
		(fp_line
			(start -0.7874 0.4064)
			(end -0.7874 -0.4064)
			(stroke
				(width 0.1524)
				(type default)
			)
			(layer "F.SilkS")
		)
		(fp_line
			(start -0.12065 -0.305054)
			(end -0.12065 -0.2794)
			(stroke
				(width 0.1)
				(type default)
			)
			(layer "F.Fab")
		)
		(fp_line
			(start -0.67945 -0.305054)
			(end -0.12065 -0.305054)
			(stroke
				(width 0.1)
				(type default)
			)
			(layer "F.Fab")
		)
		(fp_line
			(start 0.67945 -0.3048)
			(end 0.67945 0.3048)
			(stroke
				(width 0.1)
				(type default)
			)
			(layer "F.Fab")
		)
		(fp_line
			(start 0.12065 -0.3048)
			(end 0.67945 -0.3048)
			(stroke
				(width 0.1)
				(type default)
			)
			(layer "F.Fab")
		)
		(fp_line
			(start 0.12065 -0.2794)
			(end 0.12065 -0.3048)
			(stroke
				(width 0.1)
				(type default)
			)
			(layer "F.Fab")
		)
		(fp_line
			(start -0.12065 -0.2794)
			(end 0.12065 -0.2794)
			(stroke
				(width 0.1)
				(type default)
			)
			(layer "F.Fab")
		)
		(fp_line
			(start 0.120396 0.2794)
			(end -0.12065 0.2794)
			(stroke
				(width 0.1)
				(type default)
			)
			(layer "F.Fab")
		)
		(fp_line
			(start -0.12065 0.2794)
			(end -0.12065 0.3048)
			(stroke
				(width 0.1)
				(type default)
			)
			(layer "F.Fab")
		)
		(fp_line
			(start 0.67945 0.3048)
			(end 0.120396 0.3048)
			(stroke
				(width 0.1)
				(type default)
			)
			(layer "F.Fab")
		)
		(fp_line
			(start 0.120396 0.3048)
			(end 0.120396 0.2794)
			(stroke
				(width 0.1)
				(type default)
			)
			(layer "F.Fab")
		)
		(fp_line
			(start -0.12065 0.3048)
			(end -0.67945 0.3048)
			(stroke
				(width 0.1)
				(type default)
			)
			(layer "F.Fab")
		)
		(fp_line
			(start -0.67945 0.3048)
			(end -0.67945 -0.305054)
			(stroke
				(width 0.1)
				(type default)
			)
			(layer "F.Fab")
		)
		(pad "1" smd circle
			(at -0.40005 0 90)
			(size 0 0)
			(layers "F.Cu" "F.Mask" "F.Paste")
			(net "JTAG_DBP_CPU_GTL_TCK")
		)
		(pad "2" smd circle
			(at 0.40005 0 90)
			(size 0 0)
			(layers "F.Cu" "F.Mask" "F.Paste")
			(net "GND")
		)
	)
	(footprint ""
		(layer "F.Cu")
		(at 252.961648 -54.161182 180)
		(property "Reference" "PR3954"
			(at 0 0 180)
			(layer "F.SilkS")
			(hide yes)
			(effects
				(font
					(size 1.27 1.27)
				)
			)
		)
		(property "Value" ""
			(at 0 0 180)
			(layer "F.Fab")
			(effects
				(font
					(size 1.27 1.27)
				)
			)
		)
		(duplicate_pad_numbers_are_jumpers no)
		(fp_line
			(start 0.7874 0.4064)
			(end -0.7874 0.4064)
			(stroke
				(width 0.1524)
				(type default)
			)
			(layer "F.SilkS")
		)
		(fp_line
			(start 0.7874 -0.4064)
			(end 0.7874 0.4064)
			(stroke
				(width 0.1524)
				(type default)
			)
			(layer "F.SilkS")
		)
		(fp_line
			(start -0.7874 0.4064)
			(end -0.7874 -0.4064)
			(stroke
				(width 0.1524)
				(type default)
			)
			(layer "F.SilkS")
		)
		(fp_line
			(start -0.7874 -0.4064)
			(end 0.7874 -0.4064)
			(stroke
				(width 0.1524)
				(type default)
			)
			(layer "F.SilkS")
		)
		(fp_line
			(start 0.67945 0.3048)
			(end 0.120396 0.3048)
			(stroke
				(width 0.1)
				(type default)
			)
			(layer "F.Fab")
		)
		(fp_line
			(start 0.67945 -0.3048)
			(end 0.67945 0.3048)
			(stroke
				(width 0.1)
				(type default)
			)
			(layer "F.Fab")
		)
		(fp_line
			(start 0.12065 -0.2794)
			(end 0.12065 -0.3048)
			(stroke
				(width 0.1)
				(type default)
			)
			(layer "F.Fab")
		)
		(fp_line
			(start 0.12065 -0.3048)
			(end 0.67945 -0.3048)
			(stroke
				(width 0.1)
				(type default)
			)
			(layer "F.Fab")
		)
		(fp_line
			(start 0.120396 0.3048)
			(end 0.120396 0.2794)
			(stroke
				(width 0.1)
				(type default)
			)
			(layer "F.Fab")
		)
		(fp_line
			(start 0.120396 0.2794)
			(end -0.12065 0.2794)
			(stroke
				(width 0.1)
				(type default)
			)
			(layer "F.Fab")
		)
		(fp_line
			(start -0.12065 0.3048)
			(end -0.67945 0.3048)
			(stroke
				(width 0.1)
				(type default)
			)
			(layer "F.Fab")
		)
		(fp_line
			(start -0.12065 0.2794)
			(end -0.12065 0.3048)
			(stroke
				(width 0.1)
				(type default)
			)
			(layer "F.Fab")
		)
		(fp_line
			(start -0.12065 -0.2794)
			(end 0.12065 -0.2794)
			(stroke
				(width 0.1)
				(type default)
			)
			(layer "F.Fab")
		)
		(fp_line
			(start -0.12065 -0.305054)
			(end -0.12065 -0.2794)
			(stroke
				(width 0.1)
				(type default)
			)
			(layer "F.Fab")
		)
		(fp_line
			(start -0.67945 0.3048)
			(end -0.67945 -0.305054)
			(stroke
				(width 0.1)
				(type default)
			)
			(layer "F.Fab")
		)
		(fp_line
			(start -0.67945 -0.305054)
			(end -0.12065 -0.305054)
			(stroke
				(width 0.1)
				(type default)
			)
			(layer "F.Fab")
		)
		(pad "1" smd circle
			(at -0.40005 0 180)
			(size 0 0)
			(layers "F.Cu" "F.Mask" "F.Paste")
			(net "P12V_E1S_OV_FB_0")
		)
		(pad "2" smd circle
			(at 0.40005 0 180)
			(size 0 0)
			(layers "F.Cu" "F.Mask" "F.Paste")
			(net "GND")
		)
	)
	(footprint ""
		(layer "F.Cu")
		(at 309.01894 -56.045608 90)
		(property "Reference" "R147"
			(at 0 0 90)
			(layer "F.SilkS")
			(hide yes)
			(effects
				(font
					(size 1.27 1.27)
				)
			)
		)
		(property "Value" ""
			(at 0 0 90)
			(layer "F.Fab")
			(effects
				(font
					(size 1.27 1.27)
				)
			)
		)
		(duplicate_pad_numbers_are_jumpers no)
		(fp_line
			(start 0.7874 -0.4064)
			(end 0.7874 0.4064)
			(stroke
				(width 0.1524)
				(type default)
			)
			(layer "F.SilkS")
		)
		(fp_line
			(start -0.7874 -0.4064)
			(end 0.7874 -0.4064)
			(stroke
				(width 0.1524)
				(type default)
			)
			(layer "F.SilkS")
		)
		(fp_line
			(start 0.7874 0.4064)
			(end -0.7874 0.4064)
			(stroke
				(width 0.1524)
				(type default)
			)
			(layer "F.SilkS")
		)
		(fp_line
			(start -0.7874 0.4064)
			(end -0.7874 -0.4064)
			(stroke
				(width 0.1524)
				(type default)
			)
			(layer "F.SilkS")
		)
		(fp_line
			(start -0.12065 -0.305054)
			(end -0.12065 -0.2794)
			(stroke
				(width 0.1)
				(type default)
			)
			(layer "F.Fab")
		)
		(fp_line
			(start -0.67945 -0.305054)
			(end -0.12065 -0.305054)
			(stroke
				(width 0.1)
				(type default)
			)
			(layer "F.Fab")
		)
		(fp_line
			(start 0.67945 -0.3048)
			(end 0.67945 0.3048)
			(stroke
				(width 0.1)
				(type default)
			)
			(layer "F.Fab")
		)
		(fp_line
			(start 0.12065 -0.3048)
			(end 0.67945 -0.3048)
			(stroke
				(width 0.1)
				(type default)
			)
			(layer "F.Fab")
		)
		(fp_line
			(start 0.12065 -0.2794)
			(end 0.12065 -0.3048)
			(stroke
				(width 0.1)
				(type default)
			)
			(layer "F.Fab")
		)
		(fp_line
			(start -0.12065 -0.2794)
			(end 0.12065 -0.2794)
			(stroke
				(width 0.1)
				(type default)
			)
			(layer "F.Fab")
		)
		(fp_line
			(start 0.120396 0.2794)
			(end -0.12065 0.2794)
			(stroke
				(width 0.1)
				(type default)
			)
			(layer "F.Fab")
		)
		(fp_line
			(start -0.12065 0.2794)
			(end -0.12065 0.3048)
			(stroke
				(width 0.1)
				(type default)
			)
			(layer "F.Fab")
		)
		(fp_line
			(start 0.67945 0.3048)
			(end 0.120396 0.3048)
			(stroke
				(width 0.1)
				(type default)
			)
			(layer "F.Fab")
		)
		(fp_line
			(start 0.120396 0.3048)
			(end 0.120396 0.2794)
			(stroke
				(width 0.1)
				(type default)
			)
			(layer "F.Fab")
		)
		(fp_line
			(start -0.12065 0.3048)
			(end -0.67945 0.3048)
			(stroke
				(width 0.1)
				(type default)
			)
			(layer "F.Fab")
		)
		(fp_line
			(start -0.67945 0.3048)
			(end -0.67945 -0.305054)
			(stroke
				(width 0.1)
				(type default)
			)
			(layer "F.Fab")
		)
		(pad "1" smd circle
			(at -0.40005 0 90)
			(size 0 0)
			(layers "F.Cu" "F.Mask" "F.Paste")
			(net "PECI_PCH_R")
		)
		(pad "2" smd circle
			(at 0.40005 0 90)
			(size 0 0)
			(layers "F.Cu" "F.Mask" "F.Paste")
			(net "GND")
		)
	)
	(footprint ""
		(layer "F.Cu")
		(at 369.724178 -355.69779)
		(property "Reference" "R2407"
			(at 0 0 0)
			(layer "F.SilkS")
			(hide yes)
			(effects
				(font
					(size 1.27 1.27)
				)
			)
		)
		(property "Value" ""
			(at 0 0 0)
			(layer "F.Fab")
			(effects
				(font
					(size 1.27 1.27)
				)
			)
		)
		(duplicate_pad_numbers_are_jumpers no)
		(fp_line
			(start -0.7874 -0.4064)
			(end 0.7874 -0.4064)
			(stroke
				(width 0.1524)
				(type default)
			)
			(layer "F.SilkS")
		)
		(fp_line
			(start -0.7874 0.4064)
			(end -0.7874 -0.4064)
			(stroke
				(width 0.1524)
				(type default)
			)
			(layer "F.SilkS")
		)
		(fp_line
			(start 0.7874 -0.4064)
			(end 0.7874 0.4064)
			(stroke
				(width 0.1524)
				(type default)
			)
			(layer "F.SilkS")
		)
		(fp_line
			(start 0.7874 0.4064)
			(end -0.7874 0.4064)
			(stroke
				(width 0.1524)
				(type default)
			)
			(layer "F.SilkS")
		)
		(fp_line
			(start -0.67945 -0.305054)
			(end -0.12065 -0.305054)
			(stroke
				(width 0.1)
				(type default)
			)
			(layer "F.Fab")
		)
		(fp_line
			(start -0.67945 0.3048)
			(end -0.67945 -0.305054)
			(stroke
				(width 0.1)
				(type default)
			)
			(layer "F.Fab")
		)
		(fp_line
			(start -0.12065 -0.305054)
			(end -0.12065 -0.2794)
			(stroke
				(width 0.1)
				(type default)
			)
			(layer "F.Fab")
		)
		(fp_line
			(start -0.12065 -0.2794)
			(end 0.12065 -0.2794)
			(stroke
				(width 0.1)
				(type default)
			)
			(layer "F.Fab")
		)
		(fp_line
			(start -0.12065 0.2794)
			(end -0.12065 0.3048)
			(stroke
				(width 0.1)
				(type default)
			)
			(layer "F.Fab")
		)
		(fp_line
			(start -0.12065 0.3048)
			(end -0.67945 0.3048)
			(stroke
				(width 0.1)
				(type default)
			)
			(layer "F.Fab")
		)
		(fp_line
			(start 0.120396 0.2794)
			(end -0.12065 0.2794)
			(stroke
				(width 0.1)
				(type default)
			)
			(layer "F.Fab")
		)
		(fp_line
			(start 0.120396 0.3048)
			(end 0.120396 0.2794)
			(stroke
				(width 0.1)
				(type default)
			)
			(layer "F.Fab")
		)
		(fp_line
			(start 0.12065 -0.3048)
			(end 0.67945 -0.3048)
			(stroke
				(width 0.1)
				(type default)
			)
			(layer "F.Fab")
		)
		(fp_line
			(start 0.12065 -0.2794)
			(end 0.12065 -0.3048)
			(stroke
				(width 0.1)
				(type default)
			)
			(layer "F.Fab")
		)
		(fp_line
			(start 0.67945 -0.3048)
			(end 0.67945 0.3048)
			(stroke
				(width 0.1)
				(type default)
			)
			(layer "F.Fab")
		)
		(fp_line
			(start 0.67945 0.3048)
			(end 0.120396 0.3048)
			(stroke
				(width 0.1)
				(type default)
			)
			(layer "F.Fab")
		)
		(pad "1" smd circle
			(at -0.40005 0)
			(size 0 0)
			(layers "F.Cu" "F.Mask" "F.Paste")
			(net "P3V3_AUX")
		)
		(pad "2" smd circle
			(at 0.40005 0)
			(size 0 0)
			(layers "F.Cu" "F.Mask" "F.Paste")
			(net "PWRGD_PVPP_HBM_CPU0_R")
		)
	)
	(footprint ""
		(layer "F.Cu")
		(at 54.242716 -107.88269 180)
		(property "Reference" "R3720"
			(at 0 0 180)
			(layer "F.SilkS")
			(hide yes)
			(effects
				(font
					(size 1.27 1.27)
				)
			)
		)
		(property "Value" ""
			(at 0 0 180)
			(layer "F.Fab")
			(effects
				(font
					(size 1.27 1.27)
				)
			)
		)
		(duplicate_pad_numbers_are_jumpers no)
		(fp_line
			(start 0.7874 0.4064)
			(end -0.7874 0.4064)
			(stroke
				(width 0.1524)
				(type default)
			)
			(layer "F.SilkS")
		)
		(fp_line
			(start 0.7874 -0.4064)
			(end 0.7874 0.4064)
			(stroke
				(width 0.1524)
				(type default)
			)
			(layer "F.SilkS")
		)
		(fp_line
			(start -0.7874 0.4064)
			(end -0.7874 -0.4064)
			(stroke
				(width 0.1524)
				(type default)
			)
			(layer "F.SilkS")
		)
		(fp_line
			(start -0.7874 -0.4064)
			(end 0.7874 -0.4064)
			(stroke
				(width 0.1524)
				(type default)
			)
			(layer "F.SilkS")
		)
		(fp_line
			(start 0.67945 0.3048)
			(end 0.120396 0.3048)
			(stroke
				(width 0.1)
				(type default)
			)
			(layer "F.Fab")
		)
		(fp_line
			(start 0.67945 -0.3048)
			(end 0.67945 0.3048)
			(stroke
				(width 0.1)
				(type default)
			)
			(layer "F.Fab")
		)
		(fp_line
			(start 0.12065 -0.2794)
			(end 0.12065 -0.3048)
			(stroke
				(width 0.1)
				(type default)
			)
			(layer "F.Fab")
		)
		(fp_line
			(start 0.12065 -0.3048)
			(end 0.67945 -0.3048)
			(stroke
				(width 0.1)
				(type default)
			)
			(layer "F.Fab")
		)
		(fp_line
			(start 0.120396 0.3048)
			(end 0.120396 0.2794)
			(stroke
				(width 0.1)
				(type default)
			)
			(layer "F.Fab")
		)
		(fp_line
			(start 0.120396 0.2794)
			(end -0.12065 0.2794)
			(stroke
				(width 0.1)
				(type default)
			)
			(layer "F.Fab")
		)
		(fp_line
			(start -0.12065 0.3048)
			(end -0.67945 0.3048)
			(stroke
				(width 0.1)
				(type default)
			)
			(layer "F.Fab")
		)
		(fp_line
			(start -0.12065 0.2794)
			(end -0.12065 0.3048)
			(stroke
				(width 0.1)
				(type default)
			)
			(layer "F.Fab")
		)
		(fp_line
			(start -0.12065 -0.2794)
			(end 0.12065 -0.2794)
			(stroke
				(width 0.1)
				(type default)
			)
			(layer "F.Fab")
		)
		(fp_line
			(start -0.12065 -0.305054)
			(end -0.12065 -0.2794)
			(stroke
				(width 0.1)
				(type default)
			)
			(layer "F.Fab")
		)
		(fp_line
			(start -0.67945 0.3048)
			(end -0.67945 -0.305054)
			(stroke
				(width 0.1)
				(type default)
			)
			(layer "F.Fab")
		)
		(fp_line
			(start -0.67945 -0.305054)
			(end -0.12065 -0.305054)
			(stroke
				(width 0.1)
				(type default)
			)
			(layer "F.Fab")
		)
		(pad "1" smd circle
			(at -0.40005 0 180)
			(size 0 0)
			(layers "F.Cu" "F.Mask" "F.Paste")
			(net "SMB_LM75_2_3V3AUX_SDA_R")
		)
		(pad "2" smd circle
			(at 0.40005 0 180)
			(size 0 0)
			(layers "F.Cu" "F.Mask" "F.Paste")
			(net "SMB_LM75_2_3V3AUX_SDA")
		)
	)
	(footprint ""
		(layer "F.Cu")
		(at 127.602234 -408.517344 -90)
		(property "Reference" "C1520"
			(at 0 0 270)
			(layer "F.SilkS")
			(hide yes)
			(effects
				(font
					(size 1.27 1.27)
				)
			)
		)
		(property "Value" ""
			(at 0 0 270)
			(layer "F.Fab")
			(effects
				(font
					(size 1.27 1.27)
				)
			)
		)
		(duplicate_pad_numbers_are_jumpers no)
		(fp_line
			(start -0.299974 0.150114)
			(end -0.299974 -0.150114)
			(stroke
				(width 0.1)
				(type default)
			)
			(layer "F.Fab")
		)
		(fp_line
			(start 0.299974 0.150114)
			(end -0.299974 0.150114)
			(stroke
				(width 0.1)
				(type default)
			)
			(layer "F.Fab")
		)
		(fp_line
			(start -0.299974 -0.150114)
			(end 0.299974 -0.150114)
			(stroke
				(width 0.1)
				(type default)
			)
			(layer "F.Fab")
		)
		(fp_line
			(start 0.299974 -0.150114)
			(end 0.299974 0.150114)
			(stroke
				(width 0.1)
				(type default)
			)
			(layer "F.Fab")
		)
		(pad "1" smd rect
			(at -0.2667 0 270)
			(size 0.3048 0.381)
			(layers "F.Cu" "F.Mask" "F.Paste")
			(net "P5E_CPU1_PE3_TX_C_DN<13>")
		)
		(pad "2" smd rect
			(at 0.2667 0 270)
			(size 0.3048 0.381)
			(layers "F.Cu" "F.Mask" "F.Paste")
			(net "P5E_CPU1_PE3_TX_DN<13>")
		)
	)
	(footprint ""
		(layer "F.Cu")
		(at 400.558 -183.429148)
		(property "Reference" "PC1579"
			(at 0 0 0)
			(layer "F.SilkS")
			(hide yes)
			(effects
				(font
					(size 1.27 1.27)
				)
			)
		)
		(property "Value" ""
			(at 0 0 0)
			(layer "F.Fab")
			(effects
				(font
					(size 1.27 1.27)
				)
			)
		)
		(duplicate_pad_numbers_are_jumpers no)
		(fp_line
			(start 2.750058 0.999998)
			(end -2.750058 0.999998)
			(stroke
				(width 0.1524)
				(type default)
			)
			(layer "F.SilkS")
		)
		(fp_circle
			(center 0 0.999998)
			(end 2.750058 0.999998)
			(stroke
				(width 0.1524)
				(type default)
			)
			(fill no)
			(layer "F.SilkS")
		)
		(fp_poly
			(pts
				(arc
					(start 2.750058 0.999998)
					(mid 0 3.750056)
					(end -2.750058 0.999998)
				)
			)
			(stroke
				(width 0)
				(type default)
			)
			(fill yes)
			(layer "F.SilkS")
		)
		(fp_circle
			(center 0 0.999998)
			(end 2.750058 0.999998)
			(stroke
				(width 0.1)
				(type default)
			)
			(fill no)
			(layer "F.Fab")
		)
		(pad "1" thru_hole rect
			(at 0 0)
			(size 1.5748 1.5748)
			(drill 1.0668)
			(layers "*.Cu" "*.Mask")
			(remove_unused_layers no)
			(net "PVCCINFAON_CPU0")
			(clearance 0)
			(padstack
				(mode front_inner_back)
				(layer "Inner"
					(shape circle)
					(size 1.5748 1.5748)
					(clearance 0)
				)
				(layer "B.Cu"
					(shape rect)
					(size 1.5748 1.5748)
					(clearance 0)
				)
			)
		)
		(pad "2" thru_hole circle
			(at 0 1.999996)
			(size 1.5748 1.5748)
			(drill 1.0668)
			(layers "*.Cu" "*.Mask")
			(remove_unused_layers no)
			(net "GND")
			(clearance 0)
		)
	)
	(footprint ""
		(layer "F.Cu")
		(at 216.065608 -402.791422 180)
		(property "Reference" "PR3990"
			(at 0 0 180)
			(layer "F.SilkS")
			(hide yes)
			(effects
				(font
					(size 1.27 1.27)
				)
			)
		)
		(property "Value" ""
			(at 0 0 180)
			(layer "F.Fab")
			(effects
				(font
					(size 1.27 1.27)
				)
			)
		)
		(duplicate_pad_numbers_are_jumpers no)
		(fp_line
			(start 0.7874 0.4064)
			(end -0.7874 0.4064)
			(stroke
				(width 0.1524)
				(type default)
			)
			(layer "F.SilkS")
		)
		(fp_line
			(start 0.7874 -0.4064)
			(end 0.7874 0.4064)
			(stroke
				(width 0.1524)
				(type default)
			)
			(layer "F.SilkS")
		)
		(fp_line
			(start -0.7874 0.4064)
			(end -0.7874 -0.4064)
			(stroke
				(width 0.1524)
				(type default)
			)
			(layer "F.SilkS")
		)
		(fp_line
			(start -0.7874 -0.4064)
			(end 0.7874 -0.4064)
			(stroke
				(width 0.1524)
				(type default)
			)
			(layer "F.SilkS")
		)
		(fp_line
			(start 0.67945 0.3048)
			(end 0.120396 0.3048)
			(stroke
				(width 0.1)
				(type default)
			)
			(layer "F.Fab")
		)
		(fp_line
			(start 0.67945 -0.3048)
			(end 0.67945 0.3048)
			(stroke
				(width 0.1)
				(type default)
			)
			(layer "F.Fab")
		)
		(fp_line
			(start 0.12065 -0.2794)
			(end 0.12065 -0.3048)
			(stroke
				(width 0.1)
				(type default)
			)
			(layer "F.Fab")
		)
		(fp_line
			(start 0.12065 -0.3048)
			(end 0.67945 -0.3048)
			(stroke
				(width 0.1)
				(type default)
			)
			(layer "F.Fab")
		)
		(fp_line
			(start 0.120396 0.3048)
			(end 0.120396 0.2794)
			(stroke
				(width 0.1)
				(type default)
			)
			(layer "F.Fab")
		)
		(fp_line
			(start 0.120396 0.2794)
			(end -0.12065 0.2794)
			(stroke
				(width 0.1)
				(type default)
			)
			(layer "F.Fab")
		)
		(fp_line
			(start -0.12065 0.3048)
			(end -0.67945 0.3048)
			(stroke
				(width 0.1)
				(type default)
			)
			(layer "F.Fab")
		)
		(fp_line
			(start -0.12065 0.2794)
			(end -0.12065 0.3048)
			(stroke
				(width 0.1)
				(type default)
			)
			(layer "F.Fab")
		)
		(fp_line
			(start -0.12065 -0.2794)
			(end 0.12065 -0.2794)
			(stroke
				(width 0.1)
				(type default)
			)
			(layer "F.Fab")
		)
		(fp_line
			(start -0.12065 -0.305054)
			(end -0.12065 -0.2794)
			(stroke
				(width 0.1)
				(type default)
			)
			(layer "F.Fab")
		)
		(fp_line
			(start -0.67945 0.3048)
			(end -0.67945 -0.305054)
			(stroke
				(width 0.1)
				(type default)
			)
			(layer "F.Fab")
		)
		(fp_line
			(start -0.67945 -0.305054)
			(end -0.12065 -0.305054)
			(stroke
				(width 0.1)
				(type default)
			)
			(layer "F.Fab")
		)
		(pad "1" smd circle
			(at -0.40005 0 180)
			(size 0 0)
			(layers "F.Cu" "F.Mask" "F.Paste")
			(net "HSC_IMON")
		)
		(pad "2" smd circle
			(at 0.40005 0 180)
			(size 0 0)
			(layers "F.Cu" "F.Mask" "F.Paste")
			(net "AGND_HSC")
		)
	)
	(footprint ""
		(layer "F.Cu")
		(at 353.248214 -252.956314 -90)
		(property "Reference" "C1002"
			(at 0 0 270)
			(layer "F.SilkS")
			(hide yes)
			(effects
				(font
					(size 1.27 1.27)
				)
			)
		)
		(property "Value" ""
			(at 0 0 270)
			(layer "F.Fab")
			(effects
				(font
					(size 1.27 1.27)
				)
			)
		)
		(duplicate_pad_numbers_are_jumpers no)
		(fp_line
			(start -0.7874 0.4064)
			(end -0.7874 -0.4064)
			(stroke
				(width 0.1524)
				(type default)
			)
			(layer "F.SilkS")
		)
		(fp_line
			(start 0.7874 0.4064)
			(end -0.7874 0.4064)
			(stroke
				(width 0.1524)
				(type default)
			)
			(layer "F.SilkS")
		)
		(fp_line
			(start -0.7874 -0.4064)
			(end 0.7874 -0.4064)
			(stroke
				(width 0.1524)
				(type default)
			)
			(layer "F.SilkS")
		)
		(fp_line
			(start 0.7874 -0.4064)
			(end 0.7874 0.4064)
			(stroke
				(width 0.1524)
				(type default)
			)
			(layer "F.SilkS")
		)
		(fp_line
			(start -0.67945 0.3048)
			(end -0.67945 -0.305054)
			(stroke
				(width 0.1)
				(type default)
			)
			(layer "F.Fab")
		)
		(fp_line
			(start -0.12065 0.3048)
			(end -0.67945 0.3048)
			(stroke
				(width 0.1)
				(type default)
			)
			(layer "F.Fab")
		)
		(fp_line
			(start 0.120396 0.3048)
			(end 0.120396 0.2794)
			(stroke
				(width 0.1)
				(type default)
			)
			(layer "F.Fab")
		)
		(fp_line
			(start 0.67945 0.3048)
			(end 0.120396 0.3048)
			(stroke
				(width 0.1)
				(type default)
			)
			(layer "F.Fab")
		)
		(fp_line
			(start -0.12065 0.2794)
			(end -0.12065 0.3048)
			(stroke
				(width 0.1)
				(type default)
			)
			(layer "F.Fab")
		)
		(fp_line
			(start 0.120396 0.2794)
			(end -0.12065 0.2794)
			(stroke
				(width 0.1)
				(type default)
			)
			(layer "F.Fab")
		)
		(fp_line
			(start -0.12065 -0.2794)
			(end 0.12065 -0.2794)
			(stroke
				(width 0.1)
				(type default)
			)
			(layer "F.Fab")
		)
		(fp_line
			(start 0.12065 -0.2794)
			(end 0.12065 -0.3048)
			(stroke
				(width 0.1)
				(type default)
			)
			(layer "F.Fab")
		)
		(fp_line
			(start 0.12065 -0.3048)
			(end 0.67945 -0.3048)
			(stroke
				(width 0.1)
				(type default)
			)
			(layer "F.Fab")
		)
		(fp_line
			(start 0.67945 -0.3048)
			(end 0.67945 0.3048)
			(stroke
				(width 0.1)
				(type default)
			)
			(layer "F.Fab")
		)
		(fp_line
			(start -0.67945 -0.305054)
			(end -0.12065 -0.305054)
			(stroke
				(width 0.1)
				(type default)
			)
			(layer "F.Fab")
		)
		(fp_line
			(start -0.12065 -0.305054)
			(end -0.12065 -0.2794)
			(stroke
				(width 0.1)
				(type default)
			)
			(layer "F.Fab")
		)
		(pad "1" smd circle
			(at -0.40005 0 270)
			(size 0 0)
			(layers "F.Cu" "F.Mask" "F.Paste")
			(net "PVCCIN_CPU0")
		)
		(pad "2" smd circle
			(at 0.40005 0 270)
			(size 0 0)
			(layers "F.Cu" "F.Mask" "F.Paste")
			(net "GND")
		)
	)
	(footprint ""
		(layer "F.Cu")
		(at 403.941026 -64.040004)
		(property "Reference" "C549"
			(at 0 0 0)
			(layer "F.SilkS")
			(hide yes)
			(effects
				(font
					(size 1.27 1.27)
				)
			)
		)
		(property "Value" ""
			(at 0 0 0)
			(layer "F.Fab")
			(effects
				(font
					(size 1.27 1.27)
				)
			)
		)
		(duplicate_pad_numbers_are_jumpers no)
		(fp_line
			(start -0.7874 -0.4064)
			(end 0.7874 -0.4064)
			(stroke
				(width 0.1524)
				(type default)
			)
			(layer "F.SilkS")
		)
		(fp_line
			(start -0.7874 0.4064)
			(end -0.7874 -0.4064)
			(stroke
				(width 0.1524)
				(type default)
			)
			(layer "F.SilkS")
		)
		(fp_line
			(start 0.7874 -0.4064)
			(end 0.7874 0.4064)
			(stroke
				(width 0.1524)
				(type default)
			)
			(layer "F.SilkS")
		)
		(fp_line
			(start 0.7874 0.4064)
			(end -0.7874 0.4064)
			(stroke
				(width 0.1524)
				(type default)
			)
			(layer "F.SilkS")
		)
		(fp_line
			(start -0.67945 -0.305054)
			(end -0.12065 -0.305054)
			(stroke
				(width 0.1)
				(type default)
			)
			(layer "F.Fab")
		)
		(fp_line
			(start -0.67945 0.3048)
			(end -0.67945 -0.305054)
			(stroke
				(width 0.1)
				(type default)
			)
			(layer "F.Fab")
		)
		(fp_line
			(start -0.12065 -0.305054)
			(end -0.12065 -0.2794)
			(stroke
				(width 0.1)
				(type default)
			)
			(layer "F.Fab")
		)
		(fp_line
			(start -0.12065 -0.2794)
			(end 0.12065 -0.2794)
			(stroke
				(width 0.1)
				(type default)
			)
			(layer "F.Fab")
		)
		(fp_line
			(start -0.12065 0.2794)
			(end -0.12065 0.3048)
			(stroke
				(width 0.1)
				(type default)
			)
			(layer "F.Fab")
		)
		(fp_line
			(start -0.12065 0.3048)
			(end -0.67945 0.3048)
			(stroke
				(width 0.1)
				(type default)
			)
			(layer "F.Fab")
		)
		(fp_line
			(start 0.120396 0.2794)
			(end -0.12065 0.2794)
			(stroke
				(width 0.1)
				(type default)
			)
			(layer "F.Fab")
		)
		(fp_line
			(start 0.120396 0.3048)
			(end 0.120396 0.2794)
			(stroke
				(width 0.1)
				(type default)
			)
			(layer "F.Fab")
		)
		(fp_line
			(start 0.12065 -0.3048)
			(end 0.67945 -0.3048)
			(stroke
				(width 0.1)
				(type default)
			)
			(layer "F.Fab")
		)
		(fp_line
			(start 0.12065 -0.2794)
			(end 0.12065 -0.3048)
			(stroke
				(width 0.1)
				(type default)
			)
			(layer "F.Fab")
		)
		(fp_line
			(start 0.67945 -0.3048)
			(end 0.67945 0.3048)
			(stroke
				(width 0.1)
				(type default)
			)
			(layer "F.Fab")
		)
		(fp_line
			(start 0.67945 0.3048)
			(end 0.120396 0.3048)
			(stroke
				(width 0.1)
				(type default)
			)
			(layer "F.Fab")
		)
		(pad "1" smd circle
			(at -0.40005 0)
			(size 0 0)
			(layers "F.Cu" "F.Mask" "F.Paste")
			(net "JTAG_RST_DBP_RST_CO_N")
		)
		(pad "2" smd circle
			(at 0.40005 0)
			(size 0 0)
			(layers "F.Cu" "F.Mask" "F.Paste")
			(net "GND")
		)
	)
	(footprint ""
		(layer "F.Cu")
		(at 484.125016 -470.302844)
		(property "Reference" "J90_CON"
			(at -3.668776 -2.231644 0)
			(unlocked yes)
			(layer "F.SilkS")
			(effects
				(font
					(size 0.7874 0.5842)
					(thickness 0.1524)
				)
				(justify left)
			)
		)
		(property "Value" ""
			(at 0 0 0)
			(layer "F.Fab")
			(effects
				(font
					(size 1.27 1.27)
				)
			)
		)
		(duplicate_pad_numbers_are_jumpers no)
		(pad "1" smd circle
			(at 0 0)
			(size 0.762 0.762)
			(layers "F.Cu" "F.Mask" "F.Paste")
			(net "Net_8608")
		)
	)
	(footprint ""
		(layer "F.Cu")
		(at 20.906994 -180.682646 90)
		(property "Reference" "PC1282"
			(at 0 0 90)
			(layer "F.SilkS")
			(hide yes)
			(effects
				(font
					(size 1.27 1.27)
				)
			)
		)
		(property "Value" ""
			(at 0 0 90)
			(layer "F.Fab")
			(effects
				(font
					(size 1.27 1.27)
				)
			)
		)
		(duplicate_pad_numbers_are_jumpers no)
		(fp_line
			(start 0.7874 -0.4064)
			(end 0.7874 0.4064)
			(stroke
				(width 0.1524)
				(type default)
			)
			(layer "F.SilkS")
		)
		(fp_line
			(start -0.7874 -0.4064)
			(end 0.7874 -0.4064)
			(stroke
				(width 0.1524)
				(type default)
			)
			(layer "F.SilkS")
		)
		(fp_line
			(start 0.7874 0.4064)
			(end -0.7874 0.4064)
			(stroke
				(width 0.1524)
				(type default)
			)
			(layer "F.SilkS")
		)
		(fp_line
			(start -0.7874 0.4064)
			(end -0.7874 -0.4064)
			(stroke
				(width 0.1524)
				(type default)
			)
			(layer "F.SilkS")
		)
		(fp_line
			(start -0.12065 -0.305054)
			(end -0.12065 -0.2794)
			(stroke
				(width 0.1)
				(type default)
			)
			(layer "F.Fab")
		)
		(fp_line
			(start -0.67945 -0.305054)
			(end -0.12065 -0.305054)
			(stroke
				(width 0.1)
				(type default)
			)
			(layer "F.Fab")
		)
		(fp_line
			(start 0.67945 -0.3048)
			(end 0.67945 0.3048)
			(stroke
				(width 0.1)
				(type default)
			)
			(layer "F.Fab")
		)
		(fp_line
			(start 0.12065 -0.3048)
			(end 0.67945 -0.3048)
			(stroke
				(width 0.1)
				(type default)
			)
			(layer "F.Fab")
		)
		(fp_line
			(start 0.12065 -0.2794)
			(end 0.12065 -0.3048)
			(stroke
				(width 0.1)
				(type default)
			)
			(layer "F.Fab")
		)
		(fp_line
			(start -0.12065 -0.2794)
			(end 0.12065 -0.2794)
			(stroke
				(width 0.1)
				(type default)
			)
			(layer "F.Fab")
		)
		(fp_line
			(start 0.120396 0.2794)
			(end -0.12065 0.2794)
			(stroke
				(width 0.1)
				(type default)
			)
			(layer "F.Fab")
		)
		(fp_line
			(start -0.12065 0.2794)
			(end -0.12065 0.3048)
			(stroke
				(width 0.1)
				(type default)
			)
			(layer "F.Fab")
		)
		(fp_line
			(start 0.67945 0.3048)
			(end 0.120396 0.3048)
			(stroke
				(width 0.1)
				(type default)
			)
			(layer "F.Fab")
		)
		(fp_line
			(start 0.120396 0.3048)
			(end 0.120396 0.2794)
			(stroke
				(width 0.1)
				(type default)
			)
			(layer "F.Fab")
		)
		(fp_line
			(start -0.12065 0.3048)
			(end -0.67945 0.3048)
			(stroke
				(width 0.1)
				(type default)
			)
			(layer "F.Fab")
		)
		(fp_line
			(start -0.67945 0.3048)
			(end -0.67945 -0.305054)
			(stroke
				(width 0.1)
				(type default)
			)
			(layer "F.Fab")
		)
		(pad "1" smd circle
			(at -0.40005 0 90)
			(size 0 0)
			(layers "F.Cu" "F.Mask" "F.Paste")
			(net "SW_P12V_PVCCINFAON_CPU1_FLT")
		)
		(pad "2" smd circle
			(at 0.40005 0 90)
			(size 0 0)
			(layers "F.Cu" "F.Mask" "F.Paste")
			(net "GND")
		)
	)
	(footprint ""
		(layer "F.Cu")
		(at 109.580934 -395.17574)
		(property "Reference" "R3489"
			(at 0 0 0)
			(layer "F.SilkS")
			(hide yes)
			(effects
				(font
					(size 1.27 1.27)
				)
			)
		)
		(property "Value" ""
			(at 0 0 0)
			(layer "F.Fab")
			(effects
				(font
					(size 1.27 1.27)
				)
			)
		)
		(duplicate_pad_numbers_are_jumpers no)
		(fp_line
			(start -0.7874 -0.4064)
			(end 0.7874 -0.4064)
			(stroke
				(width 0.1524)
				(type default)
			)
			(layer "F.SilkS")
		)
		(fp_line
			(start -0.7874 0.4064)
			(end -0.7874 -0.4064)
			(stroke
				(width 0.1524)
				(type default)
			)
			(layer "F.SilkS")
		)
		(fp_line
			(start 0.7874 -0.4064)
			(end 0.7874 0.4064)
			(stroke
				(width 0.1524)
				(type default)
			)
			(layer "F.SilkS")
		)
		(fp_line
			(start 0.7874 0.4064)
			(end -0.7874 0.4064)
			(stroke
				(width 0.1524)
				(type default)
			)
			(layer "F.SilkS")
		)
		(fp_line
			(start -0.67945 -0.305054)
			(end -0.12065 -0.305054)
			(stroke
				(width 0.1)
				(type default)
			)
			(layer "F.Fab")
		)
		(fp_line
			(start -0.67945 0.3048)
			(end -0.67945 -0.305054)
			(stroke
				(width 0.1)
				(type default)
			)
			(layer "F.Fab")
		)
		(fp_line
			(start -0.12065 -0.305054)
			(end -0.12065 -0.2794)
			(stroke
				(width 0.1)
				(type default)
			)
			(layer "F.Fab")
		)
		(fp_line
			(start -0.12065 -0.2794)
			(end 0.12065 -0.2794)
			(stroke
				(width 0.1)
				(type default)
			)
			(layer "F.Fab")
		)
		(fp_line
			(start -0.12065 0.2794)
			(end -0.12065 0.3048)
			(stroke
				(width 0.1)
				(type default)
			)
			(layer "F.Fab")
		)
		(fp_line
			(start -0.12065 0.3048)
			(end -0.67945 0.3048)
			(stroke
				(width 0.1)
				(type default)
			)
			(layer "F.Fab")
		)
		(fp_line
			(start 0.120396 0.2794)
			(end -0.12065 0.2794)
			(stroke
				(width 0.1)
				(type default)
			)
			(layer "F.Fab")
		)
		(fp_line
			(start 0.120396 0.3048)
			(end 0.120396 0.2794)
			(stroke
				(width 0.1)
				(type default)
			)
			(layer "F.Fab")
		)
		(fp_line
			(start 0.12065 -0.3048)
			(end 0.67945 -0.3048)
			(stroke
				(width 0.1)
				(type default)
			)
			(layer "F.Fab")
		)
		(fp_line
			(start 0.12065 -0.2794)
			(end 0.12065 -0.3048)
			(stroke
				(width 0.1)
				(type default)
			)
			(layer "F.Fab")
		)
		(fp_line
			(start 0.67945 -0.3048)
			(end 0.67945 0.3048)
			(stroke
				(width 0.1)
				(type default)
			)
			(layer "F.Fab")
		)
		(fp_line
			(start 0.67945 0.3048)
			(end 0.120396 0.3048)
			(stroke
				(width 0.1)
				(type default)
			)
			(layer "F.Fab")
		)
		(pad "1" smd circle
			(at -0.40005 0)
			(size 0 0)
			(layers "F.Cu" "F.Mask" "F.Paste")
			(net "GPU_FPGA_EROT_RST_N")
		)
		(pad "2" smd circle
			(at 0.40005 0)
			(size 0 0)
			(layers "F.Cu" "F.Mask" "F.Paste")
			(net "GND")
		)
	)
	(footprint ""
		(layer "F.Cu")
		(at 341.133176 -339.51545 -90)
		(property "Reference" "PC252_P0_6"
			(at 0 0 270)
			(layer "F.SilkS")
			(hide yes)
			(effects
				(font
					(size 1.27 1.27)
				)
			)
		)
		(property "Value" ""
			(at 0 0 270)
			(layer "F.Fab")
			(effects
				(font
					(size 1.27 1.27)
				)
			)
		)
		(duplicate_pad_numbers_are_jumpers no)
		(fp_line
			(start -0.7874 0.4064)
			(end -0.7874 -0.4064)
			(stroke
				(width 0.1524)
				(type default)
			)
			(layer "F.SilkS")
		)
		(fp_line
			(start 0.7874 0.4064)
			(end -0.7874 0.4064)
			(stroke
				(width 0.1524)
				(type default)
			)
			(layer "F.SilkS")
		)
		(fp_line
			(start -0.7874 -0.4064)
			(end 0.7874 -0.4064)
			(stroke
				(width 0.1524)
				(type default)
			)
			(layer "F.SilkS")
		)
		(fp_line
			(start 0.7874 -0.4064)
			(end 0.7874 0.4064)
			(stroke
				(width 0.1524)
				(type default)
			)
			(layer "F.SilkS")
		)
		(fp_line
			(start -0.67945 0.3048)
			(end -0.67945 -0.305054)
			(stroke
				(width 0.1)
				(type default)
			)
			(layer "F.Fab")
		)
		(fp_line
			(start -0.12065 0.3048)
			(end -0.67945 0.3048)
			(stroke
				(width 0.1)
				(type default)
			)
			(layer "F.Fab")
		)
		(fp_line
			(start 0.120396 0.3048)
			(end 0.120396 0.2794)
			(stroke
				(width 0.1)
				(type default)
			)
			(layer "F.Fab")
		)
		(fp_line
			(start 0.67945 0.3048)
			(end 0.120396 0.3048)
			(stroke
				(width 0.1)
				(type default)
			)
			(layer "F.Fab")
		)
		(fp_line
			(start -0.12065 0.2794)
			(end -0.12065 0.3048)
			(stroke
				(width 0.1)
				(type default)
			)
			(layer "F.Fab")
		)
		(fp_line
			(start 0.120396 0.2794)
			(end -0.12065 0.2794)
			(stroke
				(width 0.1)
				(type default)
			)
			(layer "F.Fab")
		)
		(fp_line
			(start -0.12065 -0.2794)
			(end 0.12065 -0.2794)
			(stroke
				(width 0.1)
				(type default)
			)
			(layer "F.Fab")
		)
		(fp_line
			(start 0.12065 -0.2794)
			(end 0.12065 -0.3048)
			(stroke
				(width 0.1)
				(type default)
			)
			(layer "F.Fab")
		)
		(fp_line
			(start 0.12065 -0.3048)
			(end 0.67945 -0.3048)
			(stroke
				(width 0.1)
				(type default)
			)
			(layer "F.Fab")
		)
		(fp_line
			(start 0.67945 -0.3048)
			(end 0.67945 0.3048)
			(stroke
				(width 0.1)
				(type default)
			)
			(layer "F.Fab")
		)
		(fp_line
			(start -0.67945 -0.305054)
			(end -0.12065 -0.305054)
			(stroke
				(width 0.1)
				(type default)
			)
			(layer "F.Fab")
		)
		(fp_line
			(start -0.12065 -0.305054)
			(end -0.12065 -0.2794)
			(stroke
				(width 0.1)
				(type default)
			)
			(layer "F.Fab")
		)
		(pad "1" smd circle
			(at -0.40005 0 270)
			(size 0 0)
			(layers "F.Cu" "F.Mask" "F.Paste")
			(net "SW_P12V_PVCCIN_CPU0_FLT")
		)
		(pad "2" smd circle
			(at 0.40005 0 270)
			(size 0 0)
			(layers "F.Cu" "F.Mask" "F.Paste")
			(net "GND")
		)
	)
	(footprint ""
		(layer "F.Cu")
		(at 288.9377 -405.79802 180)
		(property "Reference" "R4686"
			(at 0 0 180)
			(layer "F.SilkS")
			(hide yes)
			(effects
				(font
					(size 1.27 1.27)
				)
			)
		)
		(property "Value" ""
			(at 0 0 180)
			(layer "F.Fab")
			(effects
				(font
					(size 1.27 1.27)
				)
			)
		)
		(duplicate_pad_numbers_are_jumpers no)
		(fp_line
			(start 0.7874 0.4064)
			(end -0.7874 0.4064)
			(stroke
				(width 0.1524)
				(type default)
			)
			(layer "F.SilkS")
		)
		(fp_line
			(start 0.7874 -0.4064)
			(end 0.7874 0.4064)
			(stroke
				(width 0.1524)
				(type default)
			)
			(layer "F.SilkS")
		)
		(fp_line
			(start -0.7874 0.4064)
			(end -0.7874 -0.4064)
			(stroke
				(width 0.1524)
				(type default)
			)
			(layer "F.SilkS")
		)
		(fp_line
			(start -0.7874 -0.4064)
			(end 0.7874 -0.4064)
			(stroke
				(width 0.1524)
				(type default)
			)
			(layer "F.SilkS")
		)
		(fp_line
			(start 0.67945 0.3048)
			(end 0.120396 0.3048)
			(stroke
				(width 0.1)
				(type default)
			)
			(layer "F.Fab")
		)
		(fp_line
			(start 0.67945 -0.3048)
			(end 0.67945 0.3048)
			(stroke
				(width 0.1)
				(type default)
			)
			(layer "F.Fab")
		)
		(fp_line
			(start 0.12065 -0.2794)
			(end 0.12065 -0.3048)
			(stroke
				(width 0.1)
				(type default)
			)
			(layer "F.Fab")
		)
		(fp_line
			(start 0.12065 -0.3048)
			(end 0.67945 -0.3048)
			(stroke
				(width 0.1)
				(type default)
			)
			(layer "F.Fab")
		)
		(fp_line
			(start 0.120396 0.3048)
			(end 0.120396 0.2794)
			(stroke
				(width 0.1)
				(type default)
			)
			(layer "F.Fab")
		)
		(fp_line
			(start 0.120396 0.2794)
			(end -0.12065 0.2794)
			(stroke
				(width 0.1)
				(type default)
			)
			(layer "F.Fab")
		)
		(fp_line
			(start -0.12065 0.3048)
			(end -0.67945 0.3048)
			(stroke
				(width 0.1)
				(type default)
			)
			(layer "F.Fab")
		)
		(fp_line
			(start -0.12065 0.2794)
			(end -0.12065 0.3048)
			(stroke
				(width 0.1)
				(type default)
			)
			(layer "F.Fab")
		)
		(fp_line
			(start -0.12065 -0.2794)
			(end 0.12065 -0.2794)
			(stroke
				(width 0.1)
				(type default)
			)
			(layer "F.Fab")
		)
		(fp_line
			(start -0.12065 -0.305054)
			(end -0.12065 -0.2794)
			(stroke
				(width 0.1)
				(type default)
			)
			(layer "F.Fab")
		)
		(fp_line
			(start -0.67945 0.3048)
			(end -0.67945 -0.305054)
			(stroke
				(width 0.1)
				(type default)
			)
			(layer "F.Fab")
		)
		(fp_line
			(start -0.67945 -0.305054)
			(end -0.12065 -0.305054)
			(stroke
				(width 0.1)
				(type default)
			)
			(layer "F.Fab")
		)
		(pad "1" smd circle
			(at -0.40005 0 180)
			(size 0 0)
			(layers "F.Cu" "F.Mask" "F.Paste")
			(net "P3V3_AUX")
		)
		(pad "2" smd circle
			(at 0.40005 0 180)
			(size 0 0)
			(layers "F.Cu" "F.Mask" "F.Paste")
			(net "P12V_HSC_T_CRIT_R_N")
		)
	)
	(footprint ""
		(layer "F.Cu")
		(at 164.465 -99.786948)
		(property "Reference" "R1758"
			(at 0 0 0)
			(layer "F.SilkS")
			(hide yes)
			(effects
				(font
					(size 1.27 1.27)
				)
			)
		)
		(property "Value" ""
			(at 0 0 0)
			(layer "F.Fab")
			(effects
				(font
					(size 1.27 1.27)
				)
			)
		)
		(duplicate_pad_numbers_are_jumpers no)
		(fp_line
			(start -0.7874 -0.4064)
			(end 0.7874 -0.4064)
			(stroke
				(width 0.1524)
				(type default)
			)
			(layer "F.SilkS")
		)
		(fp_line
			(start -0.7874 0.4064)
			(end -0.7874 -0.4064)
			(stroke
				(width 0.1524)
				(type default)
			)
			(layer "F.SilkS")
		)
		(fp_line
			(start 0.7874 -0.4064)
			(end 0.7874 0.4064)
			(stroke
				(width 0.1524)
				(type default)
			)
			(layer "F.SilkS")
		)
		(fp_line
			(start 0.7874 0.4064)
			(end -0.7874 0.4064)
			(stroke
				(width 0.1524)
				(type default)
			)
			(layer "F.SilkS")
		)
		(fp_line
			(start -0.67945 -0.305054)
			(end -0.12065 -0.305054)
			(stroke
				(width 0.1)
				(type default)
			)
			(layer "F.Fab")
		)
		(fp_line
			(start -0.67945 0.3048)
			(end -0.67945 -0.305054)
			(stroke
				(width 0.1)
				(type default)
			)
			(layer "F.Fab")
		)
		(fp_line
			(start -0.12065 -0.305054)
			(end -0.12065 -0.2794)
			(stroke
				(width 0.1)
				(type default)
			)
			(layer "F.Fab")
		)
		(fp_line
			(start -0.12065 -0.2794)
			(end 0.12065 -0.2794)
			(stroke
				(width 0.1)
				(type default)
			)
			(layer "F.Fab")
		)
		(fp_line
			(start -0.12065 0.2794)
			(end -0.12065 0.3048)
			(stroke
				(width 0.1)
				(type default)
			)
			(layer "F.Fab")
		)
		(fp_line
			(start -0.12065 0.3048)
			(end -0.67945 0.3048)
			(stroke
				(width 0.1)
				(type default)
			)
			(layer "F.Fab")
		)
		(fp_line
			(start 0.120396 0.2794)
			(end -0.12065 0.2794)
			(stroke
				(width 0.1)
				(type default)
			)
			(layer "F.Fab")
		)
		(fp_line
			(start 0.120396 0.3048)
			(end 0.120396 0.2794)
			(stroke
				(width 0.1)
				(type default)
			)
			(layer "F.Fab")
		)
		(fp_line
			(start 0.12065 -0.3048)
			(end 0.67945 -0.3048)
			(stroke
				(width 0.1)
				(type default)
			)
			(layer "F.Fab")
		)
		(fp_line
			(start 0.12065 -0.2794)
			(end 0.12065 -0.3048)
			(stroke
				(width 0.1)
				(type default)
			)
			(layer "F.Fab")
		)
		(fp_line
			(start 0.67945 -0.3048)
			(end 0.67945 0.3048)
			(stroke
				(width 0.1)
				(type default)
			)
			(layer "F.Fab")
		)
		(fp_line
			(start 0.67945 0.3048)
			(end 0.120396 0.3048)
			(stroke
				(width 0.1)
				(type default)
			)
			(layer "F.Fab")
		)
		(pad "1" smd circle
			(at -0.40005 0)
			(size 0 0)
			(layers "F.Cu" "F.Mask" "F.Paste")
			(net "SGPIO_LD_1")
		)
		(pad "2" smd circle
			(at 0.40005 0)
			(size 0 0)
			(layers "F.Cu" "F.Mask" "F.Paste")
			(net "SGPIO_BMC_LD_N")
		)
	)
	(footprint ""
		(layer "F.Cu")
		(at 234.998006 -126.767844 180)
		(property "Reference" "U38"
			(at -6.147308 -6.293104 0)
			(unlocked yes)
			(layer "F.SilkS")
			(effects
				(font
					(size 0.7874 0.5842)
					(thickness 0.1524)
				)
				(justify left)
			)
		)
		(property "Value" ""
			(at 0 0 180)
			(layer "F.Fab")
			(effects
				(font
					(size 1.27 1.27)
				)
			)
		)
		(duplicate_pad_numbers_are_jumpers no)
		(fp_line
			(start 3.050032 3.050032)
			(end 3.050032 2.320036)
			(stroke
				(width 0.1524)
				(type default)
			)
			(layer "F.SilkS")
		)
		(fp_line
			(start 3.050032 1.669796)
			(end 3.050032 1.382776)
			(stroke
				(width 0.1524)
				(type default)
			)
			(layer "F.SilkS")
		)
		(fp_line
			(start 3.050032 0.648716)
			(end 3.050032 0.343916)
			(stroke
				(width 0.1524)
				(type default)
			)
			(layer "F.SilkS")
		)
		(fp_line
			(start 3.050032 -0.354584)
			(end 3.050032 -1.195324)
			(stroke
				(width 0.1524)
				(type default)
			)
			(layer "F.SilkS")
		)
		(fp_line
			(start 3.050032 -1.825244)
			(end 3.050032 -2.145284)
			(stroke
				(width 0.1524)
				(type default)
			)
			(layer "F.SilkS")
		)
		(fp_line
			(start 3.050032 -2.836164)
			(end 3.050032 -3.050032)
			(stroke
				(width 0.1524)
				(type default)
			)
			(layer "F.SilkS")
		)
		(fp_line
			(start 3.050032 -3.050032)
			(end 2.331466 -3.050032)
			(stroke
				(width 0.1524)
				(type default)
			)
			(layer "F.SilkS")
		)
		(fp_line
			(start 2.892806 3.050032)
			(end 3.050032 3.050032)
			(stroke
				(width 0.1524)
				(type default)
			)
			(layer "F.SilkS")
		)
		(fp_line
			(start 1.787906 3.050032)
			(end 2.176526 3.050032)
			(stroke
				(width 0.1524)
				(type default)
			)
			(layer "F.SilkS")
		)
		(fp_line
			(start 1.615186 -3.050032)
			(end 0.373126 -3.050032)
			(stroke
				(width 0.1524)
				(type default)
			)
			(layer "F.SilkS")
		)
		(fp_line
			(start 0.799846 3.050032)
			(end 1.180846 3.050032)
			(stroke
				(width 0.1524)
				(type default)
			)
			(layer "F.SilkS")
		)
		(fp_line
			(start -0.360934 -3.050032)
			(end -0.696214 -3.050032)
			(stroke
				(width 0.1524)
				(type default)
			)
			(layer "F.SilkS")
		)
		(fp_line
			(start -0.683514 3.050032)
			(end 0.164846 3.050032)
			(stroke
				(width 0.1524)
				(type default)
			)
			(layer "F.SilkS")
		)
		(fp_line
			(start -1.315974 -3.050032)
			(end -1.615694 -3.050032)
			(stroke
				(width 0.1524)
				(type default)
			)
			(layer "F.SilkS")
		)
		(fp_line
			(start -1.750314 3.050032)
			(end -1.338834 3.050032)
			(stroke
				(width 0.1524)
				(type default)
			)
			(layer "F.SilkS")
		)
		(fp_line
			(start -2.304034 -3.050032)
			(end -3.050032 -3.050032)
			(stroke
				(width 0.1524)
				(type default)
			)
			(layer "F.SilkS")
		)
		(fp_line
			(start -3.050032 3.050032)
			(end -2.260854 3.050032)
			(stroke
				(width 0.1524)
				(type default)
			)
			(layer "F.SilkS")
		)
		(fp_line
			(start -3.050032 2.817876)
			(end -3.050032 3.050032)
			(stroke
				(width 0.1524)
				(type default)
			)
			(layer "F.SilkS")
		)
		(fp_line
			(start -3.050032 1.842516)
			(end -3.050032 2.185416)
			(stroke
				(width 0.1524)
				(type default)
			)
			(layer "F.SilkS")
		)
		(fp_line
			(start -3.050032 0.801116)
			(end -3.050032 1.184656)
			(stroke
				(width 0.1524)
				(type default)
			)
			(layer "F.SilkS")
		)
		(fp_line
			(start -3.050032 -2.198624)
			(end -3.050032 0.171196)
			(stroke
				(width 0.1524)
				(type default)
			)
			(layer "F.SilkS")
		)
		(fp_line
			(start -3.050032 -3.050032)
			(end -3.050032 -2.798064)
			(stroke
				(width 0.1524)
				(type default)
			)
			(layer "F.SilkS")
		)
		(fp_poly
			(pts
				(xy -3.441954 -4.229862) (xy -3.082798 -3.152394) (xy -4.160266 -3.51155)
			)
			(stroke
				(width 0)
				(type default)
			)
			(fill yes)
			(layer "F.SilkS")
		)
		(fp_line
			(start 3.050032 3.050032)
			(end 3.050032 -3.050032)
			(stroke
				(width 0.1)
				(type default)
			)
			(layer "F.Fab")
		)
		(fp_line
			(start 3.050032 -3.050032)
			(end -3.050032 -3.050032)
			(stroke
				(width 0.1)
				(type default)
			)
			(layer "F.Fab")
		)
		(fp_line
			(start -3.050032 3.050032)
			(end 3.050032 3.050032)
			(stroke
				(width 0.1)
				(type default)
			)
			(layer "F.Fab")
		)
		(fp_line
			(start -3.050032 -3.050032)
			(end -3.050032 3.050032)
			(stroke
				(width 0.1)
				(type default)
			)
			(layer "F.Fab")
		)
		(fp_poly
			(pts
				(xy -4.191 -3.258058) (xy -4.191 -2.242058) (xy -3.175 -2.750058)
			)
			(stroke
				(width 0)
				(type default)
			)
			(fill yes)
			(layer "F.Fab")
		)
		(pad "A1" smd circle
			(at -2.750058 -2.750058 180)
			(size 0.2286 0.2286)
			(layers "F.Cu" "F.Mask" "F.Paste")
			(net "CLK_100M_OCP_V3_2_D_R_DP")
		)
		(pad "A2" smd circle
			(at -2.249932 -2.750058 180)
			(size 0.2286 0.2286)
			(layers "F.Cu" "F.Mask" "F.Paste")
			(net "CLK_100M_OCP_V3_2_C_R_DN")
		)
		(pad "A3" smd circle
			(at -1.75006 -2.750058 180)
			(size 0.2286 0.2286)
			(layers "F.Cu" "F.Mask" "F.Paste")
			(net "CLK_100M_OCP_V3_2_C_R_DP")
		)
		(pad "A4" smd circle
			(at -1.249934 -2.750058 180)
			(size 0.2286 0.2286)
			(layers "F.Cu" "F.Mask" "F.Paste")
			(net "CLK_100M_OCP_V3_2_B_R_DN")
		)
		(pad "A5" smd circle
			(at -0.750062 -2.750058 180)
			(size 0.2286 0.2286)
			(layers "F.Cu" "F.Mask" "F.Paste")
			(net "CLK_100M_OCP_V3_2_B_R_DP")
		)
		(pad "A6" smd circle
			(at -0.249936 -2.750058 180)
			(size 0.2286 0.2286)
			(layers "F.Cu" "F.Mask" "F.Paste")
			(net "CLK_100M_OCP_V3_2_A_R_DN")
		)
		(pad "A7" smd circle
			(at 0.249936 -2.750058 180)
			(size 0.2286 0.2286)
			(layers "F.Cu" "F.Mask" "F.Paste")
			(net "CLK_100M_OCP_V3_2_A_R_DP")
		)
		(pad "A8" smd circle
			(at 0.750062 -2.750058 180)
			(size 0.2286 0.2286)
			(layers "F.Cu" "F.Mask" "F.Paste")
			(net "TP_CLK_100M_DIF13_DN")
		)
		(pad "A9" smd circle
			(at 1.249934 -2.750058 180)
			(size 0.2286 0.2286)
			(layers "F.Cu" "F.Mask" "F.Paste")
			(net "TP_CLK_100M_DIF13_DP")
		)
		(pad "A10" smd circle
			(at 1.75006 -2.750058 180)
			(size 0.2286 0.2286)
			(layers "F.Cu" "F.Mask" "F.Paste")
			(net "CLK_100M_OCP_SFF_3_R_DN")
		)
		(pad "A11" smd circle
			(at 2.249932 -2.750058 180)
			(size 0.2286 0.2286)
			(layers "F.Cu" "F.Mask" "F.Paste")
			(net "CLK_100M_OCP_SFF_3_R_DP")
		)
		(pad "A12" smd circle
			(at 2.750058 -2.750058 180)
			(size 0.2286 0.2286)
			(layers "F.Cu" "F.Mask" "F.Paste")
			(net "CLK_100M_OCP_SFF_2_R_DN")
		)
		(pad "B1" smd circle
			(at -2.750058 -2.249932 180)
			(size 0.2286 0.2286)
			(layers "F.Cu" "F.Mask" "F.Paste")
			(net "CLK_100M_OCP_V3_2_D_R_DN")
		)
		(pad "B2" smd circle
			(at -2.249932 -2.249932 180)
			(size 0.2286 0.2286)
			(layers "F.Cu" "F.Mask" "F.Paste")
			(net "P3V3_DB2000_VDD")
		)
		(pad "B3" smd circle
			(at -1.75006 -2.249932 180)
			(size 0.2286 0.2286)
			(layers "F.Cu" "F.Mask" "F.Paste")
			(net "NC_CLK_100M_DB2000_NC1")
		)
		(pad "B4" smd circle
			(at -1.249934 -2.249932 180)
			(size 0.2286 0.2286)
			(layers "F.Cu" "F.Mask" "F.Paste")
			(net "PD_DB2000_SMB_SA0")
		)
		(pad "B5" smd circle
			(at -0.750062 -2.249932 180)
			(size 0.2286 0.2286)
			(layers "F.Cu" "F.Mask" "F.Paste")
			(net "NC_CLK_100M_DB2000_NC2")
		)
		(pad "B6" smd circle
			(at -0.249936 -2.249932 180)
			(size 0.2286 0.2286)
			(layers "F.Cu" "F.Mask" "F.Paste")
			(net "P3V3_DB2000_VDDA")
		)
		(pad "B7" smd circle
			(at 0.249936 -2.249932 180)
			(size 0.2286 0.2286)
			(layers "F.Cu" "F.Mask" "F.Paste")
			(net "NC_CLK_100M_DB2000_NC3")
		)
		(pad "B8" smd circle
			(at 0.750062 -2.249932 180)
			(size 0.2286 0.2286)
			(layers "F.Cu" "F.Mask" "F.Paste")
			(net "PD_DB2000_SMB_SA1")
		)
		(pad "B9" smd circle
			(at 1.249934 -2.249932 180)
			(size 0.2286 0.2286)
			(layers "F.Cu" "F.Mask" "F.Paste")
			(net "NC_CLK_100M_DB2000_NC4")
		)
		(pad "B10" smd circle
			(at 1.75006 -2.249932 180)
			(size 0.2286 0.2286)
			(layers "F.Cu" "F.Mask" "F.Paste")
			(net "FM_DB2000_12_OE_N")
		)
		(pad "B11" smd circle
			(at 2.249932 -2.249932 180)
			(size 0.2286 0.2286)
			(layers "F.Cu" "F.Mask" "F.Paste")
			(net "P3V3_DB2000_VDD")
		)
		(pad "B12" smd circle
			(at 2.750058 -2.249932 180)
			(size 0.2286 0.2286)
			(layers "F.Cu" "F.Mask" "F.Paste")
			(net "CLK_100M_OCP_SFF_2_R_DP")
		)
		(pad "C1" smd circle
			(at -2.750058 -1.75006 180)
			(size 0.2286 0.2286)
			(layers "F.Cu" "F.Mask" "F.Paste")
			(net "TP_CLK_100M_DIF18_DP")
		)
		(pad "C2" smd circle
			(at -2.249932 -1.75006 180)
			(size 0.2286 0.2286)
			(layers "F.Cu" "F.Mask" "F.Paste")
			(net "NC_CLK_100M_DB2000_NC5")
		)
		(pad "C11" smd circle
			(at 2.249932 -1.75006 180)
			(size 0.2286 0.2286)
			(layers "F.Cu" "F.Mask" "F.Paste")
			(net "FM_DB2000_11_OE_N")
		)
		(pad "C12" smd circle
			(at 2.750058 -1.75006 180)
			(size 0.2286 0.2286)
			(layers "F.Cu" "F.Mask" "F.Paste")
			(net "CLK_100M_OCP_SFF_1_R_DN")
		)
		(pad "D1" smd circle
			(at -2.750058 -1.249934 180)
			(size 0.2286 0.2286)
			(layers "F.Cu" "F.Mask" "F.Paste")
			(net "TP_CLK_100M_DIF18_DN")
		)
		(pad "D2" smd circle
			(at -2.249932 -1.249934 180)
			(size 0.2286 0.2286)
			(layers "F.Cu" "F.Mask" "F.Paste")
			(net "NC_CLK_100M_DB2000_NC6")
		)
		(pad "D11" smd circle
			(at 2.249932 -1.249934 180)
			(size 0.2286 0.2286)
			(layers "F.Cu" "F.Mask" "F.Paste")
			(net "NC_CLK_100M_DB2000_NC7")
		)
		(pad "D12" smd circle
			(at 2.750058 -1.249934 180)
			(size 0.2286 0.2286)
			(layers "F.Cu" "F.Mask" "F.Paste")
			(net "CLK_100M_OCP_SFF_1_R_DP")
		)
		(pad "E1" smd circle
			(at -2.750058 -0.750062 180)
			(size 0.2286 0.2286)
			(layers "F.Cu" "F.Mask" "F.Paste")
			(net "TP_CLK_100M_DIF19_DP")
		)
		(pad "E2" smd circle
			(at -2.249932 -0.750062 180)
			(size 0.2286 0.2286)
			(layers "F.Cu" "F.Mask" "F.Paste")
			(net "FM_DB2000_VSBEN")
		)
		(pad "E11" smd circle
			(at 2.249932 -0.750062 180)
			(size 0.2286 0.2286)
			(layers "F.Cu" "F.Mask" "F.Paste")
			(net "FM_DB2000_10_OE_N")
		)
		(pad "E12" smd circle
			(at 2.750058 -0.750062 180)
			(size 0.2286 0.2286)
			(layers "F.Cu" "F.Mask" "F.Paste")
			(net "FM_DB2000_9_OE_N")
		)
		(pad "F1" smd circle
			(at -2.750058 -0.249936 180)
			(size 0.2286 0.2286)
			(layers "F.Cu" "F.Mask" "F.Paste")
			(net "TP_CLK_100M_DIF19_DN")
		)
		(pad "F2" smd circle
			(at -2.249932 -0.249936 180)
			(size 0.2286 0.2286)
			(layers "F.Cu" "F.Mask" "F.Paste")
			(net "NC_CLK_100M_DB2000_NC8")
		)
		(pad "F11" smd circle
			(at 2.249932 -0.249936 180)
			(size 0.2286 0.2286)
			(layers "F.Cu" "F.Mask" "F.Paste")
			(net "NC_CLK_100M_DB2000_NC9")
		)
		(pad "F12" smd circle
			(at 2.750058 -0.249936 180)
			(size 0.2286 0.2286)
			(layers "F.Cu" "F.Mask" "F.Paste")
			(net "CLK_100M_OCP_SFF_0_R_DN")
		)
		(pad "G1" smd circle
			(at -2.750058 0.249936 180)
			(size 0.2286 0.2286)
			(layers "F.Cu" "F.Mask" "F.Paste")
			(net "CLK_100M_DB2000_DP")
		)
		(pad "G2" smd circle
			(at -2.249932 0.249936 180)
			(size 0.2286 0.2286)
			(layers "F.Cu" "F.Mask" "F.Paste")
			(net "NC_CLK_100M_DB2000_NC10")
		)
		(pad "G11" smd circle
			(at 2.249932 0.249936 180)
			(size 0.2286 0.2286)
			(layers "F.Cu" "F.Mask" "F.Paste")
			(net "NC_CLK_100M_DB2000_NC11")
		)
		(pad "G12" smd circle
			(at 2.750058 0.249936 180)
			(size 0.2286 0.2286)
			(layers "F.Cu" "F.Mask" "F.Paste")
			(net "CLK_100M_OCP_SFF_0_R_DP")
		)
		(pad "H1" smd circle
			(at -2.750058 0.750062 180)
			(size 0.2286 0.2286)
			(layers "F.Cu" "F.Mask" "F.Paste")
			(net "CLK_100M_DB2000_DN")
		)
		(pad "H2" smd circle
			(at -2.249932 0.750062 180)
			(size 0.2286 0.2286)
			(layers "F.Cu" "F.Mask" "F.Paste")
			(net "P3V3_DB2000_VDDR")
		)
		(pad "H11" smd circle
			(at 2.249932 0.750062 180)
			(size 0.2286 0.2286)
			(layers "F.Cu" "F.Mask" "F.Paste")
			(net "FM_DB2000_8_OE_N")
		)
		(pad "H12" smd circle
			(at 2.750058 0.750062 180)
			(size 0.2286 0.2286)
			(layers "F.Cu" "F.Mask" "F.Paste")
			(net "CLK_100M_GPU_SWB_REF_DN")
		)
		(pad "J1" smd circle
			(at -2.750058 1.249934 180)
			(size 0.2286 0.2286)
			(layers "F.Cu" "F.Mask" "F.Paste")
			(net "CLK_100M_DB2000_CPU0_BCLK0_DP")
		)
		(pad "J2" smd circle
			(at -2.249932 1.249934 180)
			(size 0.2286 0.2286)
			(layers "F.Cu" "F.Mask" "F.Paste")
			(net "NC_CLK_100M_DB2000_NC12")
		)
		(pad "J11" smd circle
			(at 2.249932 1.249934 180)
			(size 0.2286 0.2286)
			(layers "F.Cu" "F.Mask" "F.Paste")
			(net "NC_CLK_100M_DB2000_NC13")
		)
		(pad "J12" smd circle
			(at 2.750058 1.249934 180)
			(size 0.2286 0.2286)
			(layers "F.Cu" "F.Mask" "F.Paste")
			(net "CLK_100M_GPU_SWB_REF_DP")
		)
		(pad "K1" smd circle
			(at -2.750058 1.75006 180)
			(size 0.2286 0.2286)
			(layers "F.Cu" "F.Mask" "F.Paste")
			(net "CLK_100M_DB2000_CPU0_BCLK0_DN")
		)
		(pad "K2" smd circle
			(at -2.249932 1.75006 180)
			(size 0.2286 0.2286)
			(layers "F.Cu" "F.Mask" "F.Paste")
			(net "NC_CLK_100M_DB2000_NC14")
		)
		(pad "K11" smd circle
			(at 2.249932 1.75006 180)
			(size 0.2286 0.2286)
			(layers "F.Cu" "F.Mask" "F.Paste")
			(net "FM_DB2000_1_OE_N")
		)
		(pad "K12" smd circle
			(at 2.750058 1.75006 180)
			(size 0.2286 0.2286)
			(layers "F.Cu" "F.Mask" "F.Paste")
			(net "CLK_100M_DB2000_CPU1_BCLK3_DN")
		)
		(pad "L1" smd circle
			(at -2.750058 2.249932 180)
			(size 0.2286 0.2286)
			(layers "F.Cu" "F.Mask" "F.Paste")
			(net "CLK_100M_DB2000_CPU0_BCLK1_DP")
		)
		(pad "L2" smd circle
			(at -2.249932 2.249932 180)
			(size 0.2286 0.2286)
			(layers "F.Cu" "F.Mask" "F.Paste")
			(net "P3V3_DB2000_VDD")
		)
		(pad "L3" smd circle
			(at -1.75006 2.249932 180)
			(size 0.2286 0.2286)
			(layers "F.Cu" "F.Mask" "F.Paste")
			(net "NC_CLK_100M_DB2000_NC17")
		)
		(pad "L4" smd circle
			(at -1.249934 2.249932 180)
			(size 0.2286 0.2286)
			(layers "F.Cu" "F.Mask" "F.Paste")
			(net "SMB_HOST_DB2000_3V3AUX_SDA")
		)
		(pad "L5" smd circle
			(at -0.750062 2.249932 180)
			(size 0.2286 0.2286)
			(layers "F.Cu" "F.Mask" "F.Paste")
			(net "SMB_HOST_DB2000_3V3AUX_SCL")
		)
		(pad "L6" smd circle
			(at -0.249936 2.249932 180)
			(size 0.2286 0.2286)
			(layers "F.Cu" "F.Mask" "F.Paste")
			(net "NC_CLK_100M_DB2000_NC15")
		)
		(pad "L7" smd circle
			(at 0.249936 2.249932 180)
			(size 0.2286 0.2286)
			(layers "F.Cu" "F.Mask" "F.Paste")
			(net "NC_CLK_100M_DB2000_NC16")
		)
		(pad "L8" smd circle
			(at 0.750062 2.249932 180)
			(size 0.2286 0.2286)
			(layers "F.Cu" "F.Mask" "F.Paste")
			(net "FM_DB2000_1_OE_N")
		)
		(pad "L9" smd circle
			(at 1.249934 2.249932 180)
			(size 0.2286 0.2286)
			(layers "F.Cu" "F.Mask" "F.Paste")
			(net "NC_CLK_100M_DB2000_NC18")
		)
		(pad "L10" smd circle
			(at 1.75006 2.249932 180)
			(size 0.2286 0.2286)
			(layers "F.Cu" "F.Mask" "F.Paste")
			(net "FM_DB2000_1_OE_N")
		)
		(pad "L11" smd circle
			(at 2.249932 2.249932 180)
			(size 0.2286 0.2286)
			(layers "F.Cu" "F.Mask" "F.Paste")
			(net "P3V3_DB2000_VDD")
		)
		(pad "L12" smd circle
			(at 2.750058 2.249932 180)
			(size 0.2286 0.2286)
			(layers "F.Cu" "F.Mask" "F.Paste")
			(net "CLK_100M_DB2000_CPU1_BCLK3_DP")
		)
		(pad "M1" smd circle
			(at -2.750058 2.750058 180)
			(size 0.2286 0.2286)
			(layers "F.Cu" "F.Mask" "F.Paste")
			(net "CLK_100M_DB2000_CPU0_BCLK1_DN")
		)
		(pad "M2" smd circle
			(at -2.249932 2.750058 180)
			(size 0.2286 0.2286)
			(layers "F.Cu" "F.Mask" "F.Paste")
			(net "CLK_100M_DB2000_CPU0_BCLK2_DP")
		)
		(pad "M3" smd circle
			(at -1.75006 2.750058 180)
			(size 0.2286 0.2286)
			(layers "F.Cu" "F.Mask" "F.Paste")
			(net "CLK_100M_DB2000_CPU0_BCLK2_DN")
		)
		(pad "M4" smd circle
			(at -1.249934 2.750058 180)
			(size 0.2286 0.2286)
			(layers "F.Cu" "F.Mask" "F.Paste")
			(net "CLK_100M_DB2000_CPU0_BCLK3_DP")
		)
		(pad "M5" smd circle
			(at -0.750062 2.750058 180)
			(size 0.2286 0.2286)
			(layers "F.Cu" "F.Mask" "F.Paste")
			(net "CLK_100M_DB2000_CPU0_BCLK3_DN")
		)
		(pad "M6" smd circle
			(at -0.249936 2.750058 180)
			(size 0.2286 0.2286)
			(layers "F.Cu" "F.Mask" "F.Paste")
			(net "FM_DB2000_DEV_EN")
		)
		(pad "M7" smd circle
			(at 0.249936 2.750058 180)
			(size 0.2286 0.2286)
			(layers "F.Cu" "F.Mask" "F.Paste")
			(net "CLK_100M_DB2000_CPU1_BCLK0_DP")
		)
		(pad "M8" smd circle
			(at 0.750062 2.750058 180)
			(size 0.2286 0.2286)
			(layers "F.Cu" "F.Mask" "F.Paste")
			(net "CLK_100M_DB2000_CPU1_BCLK0_DN")
		)
		(pad "M9" smd circle
			(at 1.249934 2.750058 180)
			(size 0.2286 0.2286)
			(layers "F.Cu" "F.Mask" "F.Paste")
			(net "CLK_100M_DB2000_CPU1_BCLK1_DP")
		)
		(pad "M10" smd circle
			(at 1.75006 2.750058 180)
			(size 0.2286 0.2286)
			(layers "F.Cu" "F.Mask" "F.Paste")
			(net "CLK_100M_DB2000_CPU1_BCLK1_DN")
		)
		(pad "M11" smd circle
			(at 2.249932 2.750058 180)
			(size 0.2286 0.2286)
			(layers "F.Cu" "F.Mask" "F.Paste")
			(net "CLK_100M_DB2000_CPU1_BCLK2_DP")
		)
		(pad "M12" smd circle
			(at 2.750058 2.750058 180)
			(size 0.2286 0.2286)
			(layers "F.Cu" "F.Mask" "F.Paste")
			(net "CLK_100M_DB2000_CPU1_BCLK2_DN")
		)
		(pad "TH" smd circle
			(at 0 0 180)
			(size 0 0)
			(layers "F.Cu" "F.Mask" "F.Paste")
			(net "GND")
		)
	)
	(footprint ""
		(layer "F.Cu")
		(at 319.668906 -26.651458 -90)
		(property "Reference" "R139"
			(at 0 0 270)
			(layer "F.SilkS")
			(hide yes)
			(effects
				(font
					(size 1.27 1.27)
				)
			)
		)
		(property "Value" ""
			(at 0 0 270)
			(layer "F.Fab")
			(effects
				(font
					(size 1.27 1.27)
				)
			)
		)
		(duplicate_pad_numbers_are_jumpers no)
		(fp_line
			(start -0.7874 0.4064)
			(end -0.7874 -0.4064)
			(stroke
				(width 0.1524)
				(type default)
			)
			(layer "F.SilkS")
		)
		(fp_line
			(start 0.7874 0.4064)
			(end -0.7874 0.4064)
			(stroke
				(width 0.1524)
				(type default)
			)
			(layer "F.SilkS")
		)
		(fp_line
			(start -0.7874 -0.4064)
			(end 0.7874 -0.4064)
			(stroke
				(width 0.1524)
				(type default)
			)
			(layer "F.SilkS")
		)
		(fp_line
			(start 0.7874 -0.4064)
			(end 0.7874 0.4064)
			(stroke
				(width 0.1524)
				(type default)
			)
			(layer "F.SilkS")
		)
		(fp_line
			(start -0.67945 0.3048)
			(end -0.67945 -0.305054)
			(stroke
				(width 0.1)
				(type default)
			)
			(layer "F.Fab")
		)
		(fp_line
			(start -0.12065 0.3048)
			(end -0.67945 0.3048)
			(stroke
				(width 0.1)
				(type default)
			)
			(layer "F.Fab")
		)
		(fp_line
			(start 0.120396 0.3048)
			(end 0.120396 0.2794)
			(stroke
				(width 0.1)
				(type default)
			)
			(layer "F.Fab")
		)
		(fp_line
			(start 0.67945 0.3048)
			(end 0.120396 0.3048)
			(stroke
				(width 0.1)
				(type default)
			)
			(layer "F.Fab")
		)
		(fp_line
			(start -0.12065 0.2794)
			(end -0.12065 0.3048)
			(stroke
				(width 0.1)
				(type default)
			)
			(layer "F.Fab")
		)
		(fp_line
			(start 0.120396 0.2794)
			(end -0.12065 0.2794)
			(stroke
				(width 0.1)
				(type default)
			)
			(layer "F.Fab")
		)
		(fp_line
			(start -0.12065 -0.2794)
			(end 0.12065 -0.2794)
			(stroke
				(width 0.1)
				(type default)
			)
			(layer "F.Fab")
		)
		(fp_line
			(start 0.12065 -0.2794)
			(end 0.12065 -0.3048)
			(stroke
				(width 0.1)
				(type default)
			)
			(layer "F.Fab")
		)
		(fp_line
			(start 0.12065 -0.3048)
			(end 0.67945 -0.3048)
			(stroke
				(width 0.1)
				(type default)
			)
			(layer "F.Fab")
		)
		(fp_line
			(start 0.67945 -0.3048)
			(end 0.67945 0.3048)
			(stroke
				(width 0.1)
				(type default)
			)
			(layer "F.Fab")
		)
		(fp_line
			(start -0.67945 -0.305054)
			(end -0.12065 -0.305054)
			(stroke
				(width 0.1)
				(type default)
			)
			(layer "F.Fab")
		)
		(fp_line
			(start -0.12065 -0.305054)
			(end -0.12065 -0.2794)
			(stroke
				(width 0.1)
				(type default)
			)
			(layer "F.Fab")
		)
		(pad "1" smd circle
			(at -0.40005 0 270)
			(size 0 0)
			(layers "F.Cu" "F.Mask" "F.Paste")
			(net "FM_BMC_PWRBTN_N")
		)
		(pad "2" smd circle
			(at 0.40005 0 270)
			(size 0 0)
			(layers "F.Cu" "F.Mask" "F.Paste")
			(net "P3V3_AUX")
		)
	)
	(footprint ""
		(layer "F.Cu")
		(at 103.198676 -79.078836)
		(property "Reference" "D93"
			(at -51.54041 38.649402 90)
			(unlocked yes)
			(layer "F.SilkS")
			(effects
				(font
					(size 0.635 0.4064)
					(thickness 0.1524)
				)
				(justify left)
			)
		)
		(property "Value" ""
			(at 0 0 0)
			(layer "F.Fab")
			(effects
				(font
					(size 1.27 1.27)
				)
			)
		)
		(duplicate_pad_numbers_are_jumpers no)
		(fp_line
			(start -0.90678 0.4826)
			(end -0.90678 -0.4699)
			(stroke
				(width 0.1524)
				(type default)
			)
			(layer "F.SilkS")
		)
		(fp_line
			(start -0.89408 -0.4826)
			(end 0.90678 -0.4826)
			(stroke
				(width 0.1524)
				(type default)
			)
			(layer "F.SilkS")
		)
		(fp_line
			(start -0.79248 -0.4826)
			(end 1.03378 -0.4826)
			(stroke
				(width 0.1524)
				(type default)
			)
			(layer "F.SilkS")
		)
		(fp_line
			(start -0.64008 -0.4826)
			(end 1.16078 -0.4826)
			(stroke
				(width 0.1524)
				(type default)
			)
			(layer "F.SilkS")
		)
		(fp_line
			(start 0.90678 -0.4826)
			(end 0.90678 0.4826)
			(stroke
				(width 0.1524)
				(type default)
			)
			(layer "F.SilkS")
		)
		(fp_line
			(start 0.90678 0.4826)
			(end -0.90678 0.4826)
			(stroke
				(width 0.1524)
				(type default)
			)
			(layer "F.SilkS")
		)
		(fp_line
			(start 1.03378 -0.4826)
			(end 1.03378 0.4826)
			(stroke
				(width 0.1524)
				(type default)
			)
			(layer "F.SilkS")
		)
		(fp_line
			(start 1.03378 0.4826)
			(end -0.79248 0.4826)
			(stroke
				(width 0.1524)
				(type default)
			)
			(layer "F.SilkS")
		)
		(fp_line
			(start 1.16078 -0.4826)
			(end 1.16078 0.4826)
			(stroke
				(width 0.1524)
				(type default)
			)
			(layer "F.SilkS")
		)
		(fp_line
			(start 1.16078 0.4826)
			(end -0.64008 0.4826)
			(stroke
				(width 0.1524)
				(type default)
			)
			(layer "F.SilkS")
		)
		(fp_line
			(start -0.499872 -0.249936)
			(end 0.499872 -0.249936)
			(stroke
				(width 0.1)
				(type default)
			)
			(layer "F.Fab")
		)
		(fp_line
			(start -0.499872 0.249936)
			(end -0.499872 -0.249936)
			(stroke
				(width 0.1)
				(type default)
			)
			(layer "F.Fab")
		)
		(fp_line
			(start 0.499872 -0.249936)
			(end 0.499872 0.249936)
			(stroke
				(width 0.1)
				(type default)
			)
			(layer "F.Fab")
		)
		(fp_line
			(start 0.499872 0.249936)
			(end -0.499872 0.249936)
			(stroke
				(width 0.1)
				(type default)
			)
			(layer "F.Fab")
		)
		(pad "A" smd rect
			(at -0.47498 0)
			(size 0.6096 0.7112)
			(layers "F.Cu" "F.Mask" "F.Paste")
			(net "LED_RST_RSMRST_PLD_R_N")
		)
		(pad "C" smd rect
			(at 0.47498 0)
			(size 0.6096 0.7112)
			(layers "F.Cu" "F.Mask" "F.Paste")
			(net "LED_RST_RSMRST_PLD_R_N_D")
		)
	)
	(footprint ""
		(layer "F.Cu")
		(at 116.13388 -403.35073 90)
		(property "Reference" "R2835"
			(at 0 0 90)
			(layer "F.SilkS")
			(hide yes)
			(effects
				(font
					(size 1.27 1.27)
				)
			)
		)
		(property "Value" ""
			(at 0 0 90)
			(layer "F.Fab")
			(effects
				(font
					(size 1.27 1.27)
				)
			)
		)
		(duplicate_pad_numbers_are_jumpers no)
		(fp_line
			(start 0.7874 -0.4064)
			(end 0.7874 0.4064)
			(stroke
				(width 0.1524)
				(type default)
			)
			(layer "F.SilkS")
		)
		(fp_line
			(start -0.7874 -0.4064)
			(end 0.7874 -0.4064)
			(stroke
				(width 0.1524)
				(type default)
			)
			(layer "F.SilkS")
		)
		(fp_line
			(start 0.7874 0.4064)
			(end -0.7874 0.4064)
			(stroke
				(width 0.1524)
				(type default)
			)
			(layer "F.SilkS")
		)
		(fp_line
			(start -0.7874 0.4064)
			(end -0.7874 -0.4064)
			(stroke
				(width 0.1524)
				(type default)
			)
			(layer "F.SilkS")
		)
		(fp_line
			(start -0.12065 -0.305054)
			(end -0.12065 -0.2794)
			(stroke
				(width 0.1)
				(type default)
			)
			(layer "F.Fab")
		)
		(fp_line
			(start -0.67945 -0.305054)
			(end -0.12065 -0.305054)
			(stroke
				(width 0.1)
				(type default)
			)
			(layer "F.Fab")
		)
		(fp_line
			(start 0.67945 -0.3048)
			(end 0.67945 0.3048)
			(stroke
				(width 0.1)
				(type default)
			)
			(layer "F.Fab")
		)
		(fp_line
			(start 0.12065 -0.3048)
			(end 0.67945 -0.3048)
			(stroke
				(width 0.1)
				(type default)
			)
			(layer "F.Fab")
		)
		(fp_line
			(start 0.12065 -0.2794)
			(end 0.12065 -0.3048)
			(stroke
				(width 0.1)
				(type default)
			)
			(layer "F.Fab")
		)
		(fp_line
			(start -0.12065 -0.2794)
			(end 0.12065 -0.2794)
			(stroke
				(width 0.1)
				(type default)
			)
			(layer "F.Fab")
		)
		(fp_line
			(start 0.120396 0.2794)
			(end -0.12065 0.2794)
			(stroke
				(width 0.1)
				(type default)
			)
			(layer "F.Fab")
		)
		(fp_line
			(start -0.12065 0.2794)
			(end -0.12065 0.3048)
			(stroke
				(width 0.1)
				(type default)
			)
			(layer "F.Fab")
		)
		(fp_line
			(start 0.67945 0.3048)
			(end 0.120396 0.3048)
			(stroke
				(width 0.1)
				(type default)
			)
			(layer "F.Fab")
		)
		(fp_line
			(start 0.120396 0.3048)
			(end 0.120396 0.2794)
			(stroke
				(width 0.1)
				(type default)
			)
			(layer "F.Fab")
		)
		(fp_line
			(start -0.12065 0.3048)
			(end -0.67945 0.3048)
			(stroke
				(width 0.1)
				(type default)
			)
			(layer "F.Fab")
		)
		(fp_line
			(start -0.67945 0.3048)
			(end -0.67945 -0.305054)
			(stroke
				(width 0.1)
				(type default)
			)
			(layer "F.Fab")
		)
		(pad "1" smd circle
			(at -0.40005 0 90)
			(size 0 0)
			(layers "F.Cu" "F.Mask" "F.Paste")
			(net "P3V3_AUX")
		)
		(pad "2" smd circle
			(at 0.40005 0 90)
			(size 0 0)
			(layers "F.Cu" "F.Mask" "F.Paste")
			(net "BIC_MONITER_N")
		)
	)
	(footprint ""
		(layer "F.Cu")
		(at 169.44848 -425.922948 180)
		(property "Reference" "R2915"
			(at 0 0 180)
			(layer "F.SilkS")
			(hide yes)
			(effects
				(font
					(size 1.27 1.27)
				)
			)
		)
		(property "Value" ""
			(at 0 0 180)
			(layer "F.Fab")
			(effects
				(font
					(size 1.27 1.27)
				)
			)
		)
		(duplicate_pad_numbers_are_jumpers no)
		(fp_line
			(start 0.7874 0.4064)
			(end -0.7874 0.4064)
			(stroke
				(width 0.1524)
				(type default)
			)
			(layer "F.SilkS")
		)
		(fp_line
			(start 0.7874 -0.4064)
			(end 0.7874 0.4064)
			(stroke
				(width 0.1524)
				(type default)
			)
			(layer "F.SilkS")
		)
		(fp_line
			(start -0.7874 0.4064)
			(end -0.7874 -0.4064)
			(stroke
				(width 0.1524)
				(type default)
			)
			(layer "F.SilkS")
		)
		(fp_line
			(start -0.7874 -0.4064)
			(end 0.7874 -0.4064)
			(stroke
				(width 0.1524)
				(type default)
			)
			(layer "F.SilkS")
		)
		(fp_line
			(start 0.67945 0.3048)
			(end 0.120396 0.3048)
			(stroke
				(width 0.1)
				(type default)
			)
			(layer "F.Fab")
		)
		(fp_line
			(start 0.67945 -0.3048)
			(end 0.67945 0.3048)
			(stroke
				(width 0.1)
				(type default)
			)
			(layer "F.Fab")
		)
		(fp_line
			(start 0.12065 -0.2794)
			(end 0.12065 -0.3048)
			(stroke
				(width 0.1)
				(type default)
			)
			(layer "F.Fab")
		)
		(fp_line
			(start 0.12065 -0.3048)
			(end 0.67945 -0.3048)
			(stroke
				(width 0.1)
				(type default)
			)
			(layer "F.Fab")
		)
		(fp_line
			(start 0.120396 0.3048)
			(end 0.120396 0.2794)
			(stroke
				(width 0.1)
				(type default)
			)
			(layer "F.Fab")
		)
		(fp_line
			(start 0.120396 0.2794)
			(end -0.12065 0.2794)
			(stroke
				(width 0.1)
				(type default)
			)
			(layer "F.Fab")
		)
		(fp_line
			(start -0.12065 0.3048)
			(end -0.67945 0.3048)
			(stroke
				(width 0.1)
				(type default)
			)
			(layer "F.Fab")
		)
		(fp_line
			(start -0.12065 0.2794)
			(end -0.12065 0.3048)
			(stroke
				(width 0.1)
				(type default)
			)
			(layer "F.Fab")
		)
		(fp_line
			(start -0.12065 -0.2794)
			(end 0.12065 -0.2794)
			(stroke
				(width 0.1)
				(type default)
			)
			(layer "F.Fab")
		)
		(fp_line
			(start -0.12065 -0.305054)
			(end -0.12065 -0.2794)
			(stroke
				(width 0.1)
				(type default)
			)
			(layer "F.Fab")
		)
		(fp_line
			(start -0.67945 0.3048)
			(end -0.67945 -0.305054)
			(stroke
				(width 0.1)
				(type default)
			)
			(layer "F.Fab")
		)
		(fp_line
			(start -0.67945 -0.305054)
			(end -0.12065 -0.305054)
			(stroke
				(width 0.1)
				(type default)
			)
			(layer "F.Fab")
		)
		(pad "1" smd circle
			(at -0.40005 0 180)
			(size 0 0)
			(layers "F.Cu" "F.Mask" "F.Paste")
			(net "BMC_MONITER_R")
		)
		(pad "2" smd circle
			(at 0.40005 0 180)
			(size 0 0)
			(layers "F.Cu" "F.Mask" "F.Paste")
			(net "GND")
		)
	)
	(footprint ""
		(layer "F.Cu")
		(at 224.771712 -67.921378)
		(property "Reference" "R3973"
			(at 0 0 0)
			(layer "F.SilkS")
			(hide yes)
			(effects
				(font
					(size 1.27 1.27)
				)
			)
		)
		(property "Value" ""
			(at 0 0 0)
			(layer "F.Fab")
			(effects
				(font
					(size 1.27 1.27)
				)
			)
		)
		(duplicate_pad_numbers_are_jumpers no)
		(fp_line
			(start -0.7874 -0.4064)
			(end 0.7874 -0.4064)
			(stroke
				(width 0.1524)
				(type default)
			)
			(layer "F.SilkS")
		)
		(fp_line
			(start -0.7874 0.4064)
			(end -0.7874 -0.4064)
			(stroke
				(width 0.1524)
				(type default)
			)
			(layer "F.SilkS")
		)
		(fp_line
			(start 0.7874 -0.4064)
			(end 0.7874 0.4064)
			(stroke
				(width 0.1524)
				(type default)
			)
			(layer "F.SilkS")
		)
		(fp_line
			(start 0.7874 0.4064)
			(end -0.7874 0.4064)
			(stroke
				(width 0.1524)
				(type default)
			)
			(layer "F.SilkS")
		)
		(fp_line
			(start -0.67945 -0.305054)
			(end -0.12065 -0.305054)
			(stroke
				(width 0.1)
				(type default)
			)
			(layer "F.Fab")
		)
		(fp_line
			(start -0.67945 0.3048)
			(end -0.67945 -0.305054)
			(stroke
				(width 0.1)
				(type default)
			)
			(layer "F.Fab")
		)
		(fp_line
			(start -0.12065 -0.305054)
			(end -0.12065 -0.2794)
			(stroke
				(width 0.1)
				(type default)
			)
			(layer "F.Fab")
		)
		(fp_line
			(start -0.12065 -0.2794)
			(end 0.12065 -0.2794)
			(stroke
				(width 0.1)
				(type default)
			)
			(layer "F.Fab")
		)
		(fp_line
			(start -0.12065 0.2794)
			(end -0.12065 0.3048)
			(stroke
				(width 0.1)
				(type default)
			)
			(layer "F.Fab")
		)
		(fp_line
			(start -0.12065 0.3048)
			(end -0.67945 0.3048)
			(stroke
				(width 0.1)
				(type default)
			)
			(layer "F.Fab")
		)
		(fp_line
			(start 0.120396 0.2794)
			(end -0.12065 0.2794)
			(stroke
				(width 0.1)
				(type default)
			)
			(layer "F.Fab")
		)
		(fp_line
			(start 0.120396 0.3048)
			(end 0.120396 0.2794)
			(stroke
				(width 0.1)
				(type default)
			)
			(layer "F.Fab")
		)
		(fp_line
			(start 0.12065 -0.3048)
			(end 0.67945 -0.3048)
			(stroke
				(width 0.1)
				(type default)
			)
			(layer "F.Fab")
		)
		(fp_line
			(start 0.12065 -0.2794)
			(end 0.12065 -0.3048)
			(stroke
				(width 0.1)
				(type default)
			)
			(layer "F.Fab")
		)
		(fp_line
			(start 0.67945 -0.3048)
			(end 0.67945 0.3048)
			(stroke
				(width 0.1)
				(type default)
			)
			(layer "F.Fab")
		)
		(fp_line
			(start 0.67945 0.3048)
			(end 0.120396 0.3048)
			(stroke
				(width 0.1)
				(type default)
			)
			(layer "F.Fab")
		)
		(pad "1" smd circle
			(at -0.40005 0)
			(size 0 0)
			(layers "F.Cu" "F.Mask" "F.Paste")
			(net "P3V3_E1S_PWRGD_0")
		)
		(pad "2" smd circle
			(at 0.40005 0)
			(size 0 0)
			(layers "F.Cu" "F.Mask" "F.Paste")
			(net "TP_P3V3_E1S_PWRGD_0")
		)
	)
	(footprint ""
		(layer "F.Cu")
		(at 117.86108 -400.414998 90)
		(property "Reference" "R3028"
			(at 0 0 90)
			(layer "F.SilkS")
			(hide yes)
			(effects
				(font
					(size 1.27 1.27)
				)
			)
		)
		(property "Value" ""
			(at 0 0 90)
			(layer "F.Fab")
			(effects
				(font
					(size 1.27 1.27)
				)
			)
		)
		(duplicate_pad_numbers_are_jumpers no)
		(fp_line
			(start 0.7874 -0.4064)
			(end 0.7874 0.4064)
			(stroke
				(width 0.1524)
				(type default)
			)
			(layer "F.SilkS")
		)
		(fp_line
			(start -0.7874 -0.4064)
			(end 0.7874 -0.4064)
			(stroke
				(width 0.1524)
				(type default)
			)
			(layer "F.SilkS")
		)
		(fp_line
			(start 0.7874 0.4064)
			(end -0.7874 0.4064)
			(stroke
				(width 0.1524)
				(type default)
			)
			(layer "F.SilkS")
		)
		(fp_line
			(start -0.7874 0.4064)
			(end -0.7874 -0.4064)
			(stroke
				(width 0.1524)
				(type default)
			)
			(layer "F.SilkS")
		)
		(fp_line
			(start -0.12065 -0.305054)
			(end -0.12065 -0.2794)
			(stroke
				(width 0.1)
				(type default)
			)
			(layer "F.Fab")
		)
		(fp_line
			(start -0.67945 -0.305054)
			(end -0.12065 -0.305054)
			(stroke
				(width 0.1)
				(type default)
			)
			(layer "F.Fab")
		)
		(fp_line
			(start 0.67945 -0.3048)
			(end 0.67945 0.3048)
			(stroke
				(width 0.1)
				(type default)
			)
			(layer "F.Fab")
		)
		(fp_line
			(start 0.12065 -0.3048)
			(end 0.67945 -0.3048)
			(stroke
				(width 0.1)
				(type default)
			)
			(layer "F.Fab")
		)
		(fp_line
			(start 0.12065 -0.2794)
			(end 0.12065 -0.3048)
			(stroke
				(width 0.1)
				(type default)
			)
			(layer "F.Fab")
		)
		(fp_line
			(start -0.12065 -0.2794)
			(end 0.12065 -0.2794)
			(stroke
				(width 0.1)
				(type default)
			)
			(layer "F.Fab")
		)
		(fp_line
			(start 0.120396 0.2794)
			(end -0.12065 0.2794)
			(stroke
				(width 0.1)
				(type default)
			)
			(layer "F.Fab")
		)
		(fp_line
			(start -0.12065 0.2794)
			(end -0.12065 0.3048)
			(stroke
				(width 0.1)
				(type default)
			)
			(layer "F.Fab")
		)
		(fp_line
			(start 0.67945 0.3048)
			(end 0.120396 0.3048)
			(stroke
				(width 0.1)
				(type default)
			)
			(layer "F.Fab")
		)
		(fp_line
			(start 0.120396 0.3048)
			(end 0.120396 0.2794)
			(stroke
				(width 0.1)
				(type default)
			)
			(layer "F.Fab")
		)
		(fp_line
			(start -0.12065 0.3048)
			(end -0.67945 0.3048)
			(stroke
				(width 0.1)
				(type default)
			)
			(layer "F.Fab")
		)
		(fp_line
			(start -0.67945 0.3048)
			(end -0.67945 -0.305054)
			(stroke
				(width 0.1)
				(type default)
			)
			(layer "F.Fab")
		)
		(pad "1" smd circle
			(at -0.40005 0 90)
			(size 0 0)
			(layers "F.Cu" "F.Mask" "F.Paste")
			(net "FM_SMB_1_ALERT_GPU_N")
		)
		(pad "2" smd circle
			(at 0.40005 0 90)
			(size 0 0)
			(layers "F.Cu" "F.Mask" "F.Paste")
			(net "GND")
		)
	)
	(footprint ""
		(layer "F.Cu")
		(at 378.87021 -408.517344 -90)
		(property "Reference" "C874"
			(at 0 0 270)
			(layer "F.SilkS")
			(hide yes)
			(effects
				(font
					(size 1.27 1.27)
				)
			)
		)
		(property "Value" ""
			(at 0 0 270)
			(layer "F.Fab")
			(effects
				(font
					(size 1.27 1.27)
				)
			)
		)
		(duplicate_pad_numbers_are_jumpers no)
		(fp_line
			(start -0.299974 0.150114)
			(end -0.299974 -0.150114)
			(stroke
				(width 0.1)
				(type default)
			)
			(layer "F.Fab")
		)
		(fp_line
			(start 0.299974 0.150114)
			(end -0.299974 0.150114)
			(stroke
				(width 0.1)
				(type default)
			)
			(layer "F.Fab")
		)
		(fp_line
			(start -0.299974 -0.150114)
			(end 0.299974 -0.150114)
			(stroke
				(width 0.1)
				(type default)
			)
			(layer "F.Fab")
		)
		(fp_line
			(start 0.299974 -0.150114)
			(end 0.299974 0.150114)
			(stroke
				(width 0.1)
				(type default)
			)
			(layer "F.Fab")
		)
		(pad "1" smd rect
			(at -0.2667 0 270)
			(size 0.3048 0.381)
			(layers "F.Cu" "F.Mask" "F.Paste")
			(net "P5E_CPU0_PE3_TX_C_DN<13>")
		)
		(pad "2" smd rect
			(at 0.2667 0 270)
			(size 0.3048 0.381)
			(layers "F.Cu" "F.Mask" "F.Paste")
			(net "P5E_CPU0_PE3_TX_DN<13>")
		)
	)
	(footprint ""
		(layer "F.Cu")
		(at 143.97355 -107.795568 180)
		(property "Reference" "C2254"
			(at 0 0 180)
			(layer "F.SilkS")
			(hide yes)
			(effects
				(font
					(size 1.27 1.27)
				)
			)
		)
		(property "Value" ""
			(at 0 0 180)
			(layer "F.Fab")
			(effects
				(font
					(size 1.27 1.27)
				)
			)
		)
		(duplicate_pad_numbers_are_jumpers no)
		(fp_line
			(start 0.7874 0.4064)
			(end -0.7874 0.4064)
			(stroke
				(width 0.1524)
				(type default)
			)
			(layer "F.SilkS")
		)
		(fp_line
			(start 0.7874 -0.4064)
			(end 0.7874 0.4064)
			(stroke
				(width 0.1524)
				(type default)
			)
			(layer "F.SilkS")
		)
		(fp_line
			(start -0.7874 0.4064)
			(end -0.7874 -0.4064)
			(stroke
				(width 0.1524)
				(type default)
			)
			(layer "F.SilkS")
		)
		(fp_line
			(start -0.7874 -0.4064)
			(end 0.7874 -0.4064)
			(stroke
				(width 0.1524)
				(type default)
			)
			(layer "F.SilkS")
		)
		(fp_line
			(start 0.67945 0.3048)
			(end 0.120396 0.3048)
			(stroke
				(width 0.1)
				(type default)
			)
			(layer "F.Fab")
		)
		(fp_line
			(start 0.67945 -0.3048)
			(end 0.67945 0.3048)
			(stroke
				(width 0.1)
				(type default)
			)
			(layer "F.Fab")
		)
		(fp_line
			(start 0.12065 -0.2794)
			(end 0.12065 -0.3048)
			(stroke
				(width 0.1)
				(type default)
			)
			(layer "F.Fab")
		)
		(fp_line
			(start 0.12065 -0.3048)
			(end 0.67945 -0.3048)
			(stroke
				(width 0.1)
				(type default)
			)
			(layer "F.Fab")
		)
		(fp_line
			(start 0.120396 0.3048)
			(end 0.120396 0.2794)
			(stroke
				(width 0.1)
				(type default)
			)
			(layer "F.Fab")
		)
		(fp_line
			(start 0.120396 0.2794)
			(end -0.12065 0.2794)
			(stroke
				(width 0.1)
				(type default)
			)
			(layer "F.Fab")
		)
		(fp_line
			(start -0.12065 0.3048)
			(end -0.67945 0.3048)
			(stroke
				(width 0.1)
				(type default)
			)
			(layer "F.Fab")
		)
		(fp_line
			(start -0.12065 0.2794)
			(end -0.12065 0.3048)
			(stroke
				(width 0.1)
				(type default)
			)
			(layer "F.Fab")
		)
		(fp_line
			(start -0.12065 -0.2794)
			(end 0.12065 -0.2794)
			(stroke
				(width 0.1)
				(type default)
			)
			(layer "F.Fab")
		)
		(fp_line
			(start -0.12065 -0.305054)
			(end -0.12065 -0.2794)
			(stroke
				(width 0.1)
				(type default)
			)
			(layer "F.Fab")
		)
		(fp_line
			(start -0.67945 0.3048)
			(end -0.67945 -0.305054)
			(stroke
				(width 0.1)
				(type default)
			)
			(layer "F.Fab")
		)
		(fp_line
			(start -0.67945 -0.305054)
			(end -0.12065 -0.305054)
			(stroke
				(width 0.1)
				(type default)
			)
			(layer "F.Fab")
		)
		(pad "1" smd circle
			(at -0.40005 0 180)
			(size 0 0)
			(layers "F.Cu" "F.Mask" "F.Paste")
			(net "P0V62_CPU0_ERRS_U306_VREF")
		)
		(pad "2" smd circle
			(at 0.40005 0 180)
			(size 0 0)
			(layers "F.Cu" "F.Mask" "F.Paste")
			(net "GND")
		)
	)
	(footprint ""
		(layer "F.Cu")
		(at 213.933786 -130.923538)
		(property "Reference" "U94"
			(at 1.224026 -1.897888 0)
			(unlocked yes)
			(layer "F.SilkS")
			(effects
				(font
					(size 0.7874 0.5842)
					(thickness 0.1524)
				)
			)
		)
		(property "Value" ""
			(at 0 0 0)
			(layer "F.Fab")
			(effects
				(font
					(size 1.27 1.27)
				)
			)
		)
		(duplicate_pad_numbers_are_jumpers no)
		(fp_line
			(start -1.640078 -1.100074)
			(end -1.640078 1.100074)
			(stroke
				(width 0.1524)
				(type default)
			)
			(layer "F.SilkS")
		)
		(fp_line
			(start -1.640078 1.100074)
			(end 1.640078 1.100074)
			(stroke
				(width 0.1524)
				(type default)
			)
			(layer "F.SilkS")
		)
		(fp_line
			(start 1.640078 -1.100074)
			(end -1.640078 -1.100074)
			(stroke
				(width 0.1524)
				(type default)
			)
			(layer "F.SilkS")
		)
		(fp_line
			(start 1.640078 1.100074)
			(end 1.640078 -1.100074)
			(stroke
				(width 0.1524)
				(type default)
			)
			(layer "F.SilkS")
		)
		(fp_poly
			(pts
				(xy -1.495044 -1.943354) (xy -0.725424 -1.943354) (xy -1.110234 -1.173734)
			)
			(stroke
				(width 0)
				(type default)
			)
			(fill yes)
			(layer "F.SilkS")
		)
		(fp_line
			(start -0.674878 -1.100074)
			(end -0.674878 1.100074)
			(stroke
				(width 0.1)
				(type default)
			)
			(layer "F.Fab")
		)
		(fp_line
			(start -0.674878 1.100074)
			(end 0.674878 1.100074)
			(stroke
				(width 0.1)
				(type default)
			)
			(layer "F.Fab")
		)
		(fp_line
			(start 0.674878 -1.100074)
			(end -0.674878 -1.100074)
			(stroke
				(width 0.1)
				(type default)
			)
			(layer "F.Fab")
		)
		(fp_line
			(start 0.674878 1.100074)
			(end 0.674878 -1.100074)
			(stroke
				(width 0.1)
				(type default)
			)
			(layer "F.Fab")
		)
		(fp_poly
			(pts
				(xy -1.74879 -0.649986) (xy -2.51841 -0.265176) (xy -2.51841 -1.034796)
			)
			(stroke
				(width 0)
				(type default)
			)
			(fill yes)
			(layer "F.Fab")
		)
		(pad "1" smd rect
			(at -0.818896 -0.649986 270)
			(size 0.3556 1.4732)
			(layers "F.Cu" "F.Mask" "F.Paste")
			(net "FM_COMP_P3V3_AUX_ENIN")
		)
		(pad "2" smd rect
			(at -0.818896 0 270)
			(size 0.3556 1.4732)
			(layers "F.Cu" "F.Mask" "F.Paste")
			(net "GND")
		)
		(pad "3" smd rect
			(at -0.818896 0.649986 270)
			(size 0.3556 1.4732)
			(layers "F.Cu" "F.Mask" "F.Paste")
			(net "FM_COMP_P3V3_AUX_VIN")
		)
		(pad "4" smd rect
			(at 0.818896 0.649986 270)
			(size 0.3556 1.4732)
			(layers "F.Cu" "F.Mask" "F.Paste")
			(net "PWRGD_DSW_PWROK_R1")
		)
		(pad "5" smd rect
			(at 0.818896 0 270)
			(size 0.3556 1.4732)
			(layers "F.Cu" "F.Mask" "F.Paste")
			(net "FM_COMP_P3V3_STBY_CEXT")
		)
		(pad "6" smd rect
			(at 0.818896 -0.649986 270)
			(size 0.3556 1.4732)
			(layers "F.Cu" "F.Mask" "F.Paste")
			(net "P3V3_AUX")
		)
	)
	(footprint ""
		(layer "F.Cu")
		(at 183.54802 -419.47338 90)
		(property "Reference" "R4795"
			(at 0 0 90)
			(layer "F.SilkS")
			(hide yes)
			(effects
				(font
					(size 1.27 1.27)
				)
			)
		)
		(property "Value" ""
			(at 0 0 90)
			(layer "F.Fab")
			(effects
				(font
					(size 1.27 1.27)
				)
			)
		)
		(duplicate_pad_numbers_are_jumpers no)
		(fp_line
			(start 0.7874 -0.4064)
			(end 0.7874 0.4064)
			(stroke
				(width 0.1524)
				(type default)
			)
			(layer "F.SilkS")
		)
		(fp_line
			(start -0.7874 -0.4064)
			(end 0.7874 -0.4064)
			(stroke
				(width 0.1524)
				(type default)
			)
			(layer "F.SilkS")
		)
		(fp_line
			(start 0.7874 0.4064)
			(end -0.7874 0.4064)
			(stroke
				(width 0.1524)
				(type default)
			)
			(layer "F.SilkS")
		)
		(fp_line
			(start -0.7874 0.4064)
			(end -0.7874 -0.4064)
			(stroke
				(width 0.1524)
				(type default)
			)
			(layer "F.SilkS")
		)
		(fp_line
			(start -0.12065 -0.305054)
			(end -0.12065 -0.2794)
			(stroke
				(width 0.1)
				(type default)
			)
			(layer "F.Fab")
		)
		(fp_line
			(start -0.67945 -0.305054)
			(end -0.12065 -0.305054)
			(stroke
				(width 0.1)
				(type default)
			)
			(layer "F.Fab")
		)
		(fp_line
			(start 0.67945 -0.3048)
			(end 0.67945 0.3048)
			(stroke
				(width 0.1)
				(type default)
			)
			(layer "F.Fab")
		)
		(fp_line
			(start 0.12065 -0.3048)
			(end 0.67945 -0.3048)
			(stroke
				(width 0.1)
				(type default)
			)
			(layer "F.Fab")
		)
		(fp_line
			(start 0.12065 -0.2794)
			(end 0.12065 -0.3048)
			(stroke
				(width 0.1)
				(type default)
			)
			(layer "F.Fab")
		)
		(fp_line
			(start -0.12065 -0.2794)
			(end 0.12065 -0.2794)
			(stroke
				(width 0.1)
				(type default)
			)
			(layer "F.Fab")
		)
		(fp_line
			(start 0.120396 0.2794)
			(end -0.12065 0.2794)
			(stroke
				(width 0.1)
				(type default)
			)
			(layer "F.Fab")
		)
		(fp_line
			(start -0.12065 0.2794)
			(end -0.12065 0.3048)
			(stroke
				(width 0.1)
				(type default)
			)
			(layer "F.Fab")
		)
		(fp_line
			(start 0.67945 0.3048)
			(end 0.120396 0.3048)
			(stroke
				(width 0.1)
				(type default)
			)
			(layer "F.Fab")
		)
		(fp_line
			(start 0.120396 0.3048)
			(end 0.120396 0.2794)
			(stroke
				(width 0.1)
				(type default)
			)
			(layer "F.Fab")
		)
		(fp_line
			(start -0.12065 0.3048)
			(end -0.67945 0.3048)
			(stroke
				(width 0.1)
				(type default)
			)
			(layer "F.Fab")
		)
		(fp_line
			(start -0.67945 0.3048)
			(end -0.67945 -0.305054)
			(stroke
				(width 0.1)
				(type default)
			)
			(layer "F.Fab")
		)
		(pad "1" smd circle
			(at -0.40005 0 90)
			(size 0 0)
			(layers "F.Cu" "F.Mask" "F.Paste")
			(net "HSC_CSOUT")
		)
		(pad "2" smd circle
			(at 0.40005 0 90)
			(size 0 0)
			(layers "F.Cu" "F.Mask" "F.Paste")
			(net "HSC_OC_VOL")
		)
	)
	(footprint ""
		(layer "F.Cu")
		(at 113.92408 -106.238548 -90)
		(property "Reference" "R4043"
			(at 0 0 270)
			(layer "F.SilkS")
			(hide yes)
			(effects
				(font
					(size 1.27 1.27)
				)
			)
		)
		(property "Value" ""
			(at 0 0 270)
			(layer "F.Fab")
			(effects
				(font
					(size 1.27 1.27)
				)
			)
		)
		(duplicate_pad_numbers_are_jumpers no)
		(fp_line
			(start -0.7874 0.4064)
			(end -0.7874 -0.4064)
			(stroke
				(width 0.1524)
				(type default)
			)
			(layer "F.SilkS")
		)
		(fp_line
			(start 0.7874 0.4064)
			(end -0.7874 0.4064)
			(stroke
				(width 0.1524)
				(type default)
			)
			(layer "F.SilkS")
		)
		(fp_line
			(start -0.7874 -0.4064)
			(end 0.7874 -0.4064)
			(stroke
				(width 0.1524)
				(type default)
			)
			(layer "F.SilkS")
		)
		(fp_line
			(start 0.7874 -0.4064)
			(end 0.7874 0.4064)
			(stroke
				(width 0.1524)
				(type default)
			)
			(layer "F.SilkS")
		)
		(fp_line
			(start -0.67945 0.3048)
			(end -0.67945 -0.305054)
			(stroke
				(width 0.1)
				(type default)
			)
			(layer "F.Fab")
		)
		(fp_line
			(start -0.12065 0.3048)
			(end -0.67945 0.3048)
			(stroke
				(width 0.1)
				(type default)
			)
			(layer "F.Fab")
		)
		(fp_line
			(start 0.120396 0.3048)
			(end 0.120396 0.2794)
			(stroke
				(width 0.1)
				(type default)
			)
			(layer "F.Fab")
		)
		(fp_line
			(start 0.67945 0.3048)
			(end 0.120396 0.3048)
			(stroke
				(width 0.1)
				(type default)
			)
			(layer "F.Fab")
		)
		(fp_line
			(start -0.12065 0.2794)
			(end -0.12065 0.3048)
			(stroke
				(width 0.1)
				(type default)
			)
			(layer "F.Fab")
		)
		(fp_line
			(start 0.120396 0.2794)
			(end -0.12065 0.2794)
			(stroke
				(width 0.1)
				(type default)
			)
			(layer "F.Fab")
		)
		(fp_line
			(start -0.12065 -0.2794)
			(end 0.12065 -0.2794)
			(stroke
				(width 0.1)
				(type default)
			)
			(layer "F.Fab")
		)
		(fp_line
			(start 0.12065 -0.2794)
			(end 0.12065 -0.3048)
			(stroke
				(width 0.1)
				(type default)
			)
			(layer "F.Fab")
		)
		(fp_line
			(start 0.12065 -0.3048)
			(end 0.67945 -0.3048)
			(stroke
				(width 0.1)
				(type default)
			)
			(layer "F.Fab")
		)
		(fp_line
			(start 0.67945 -0.3048)
			(end 0.67945 0.3048)
			(stroke
				(width 0.1)
				(type default)
			)
			(layer "F.Fab")
		)
		(fp_line
			(start -0.67945 -0.305054)
			(end -0.12065 -0.305054)
			(stroke
				(width 0.1)
				(type default)
			)
			(layer "F.Fab")
		)
		(fp_line
			(start -0.12065 -0.305054)
			(end -0.12065 -0.2794)
			(stroke
				(width 0.1)
				(type default)
			)
			(layer "F.Fab")
		)
		(pad "1" smd circle
			(at -0.40005 0 270)
			(size 0 0)
			(layers "F.Cu" "F.Mask" "F.Paste")
			(net "RST_CPU0_DRAM_CD_PLD_LVT3_R_N")
		)
		(pad "2" smd circle
			(at 0.40005 0 270)
			(size 0 0)
			(layers "F.Cu" "F.Mask" "F.Paste")
			(net "RST_CPU0_DRAM_CD_PLD_LVT3_N")
		)
	)
	(footprint ""
		(layer "F.Cu")
		(at 300.21022 -421.41521 90)
		(property "Reference" "R4121"
			(at 0 0 90)
			(layer "F.SilkS")
			(hide yes)
			(effects
				(font
					(size 1.27 1.27)
				)
			)
		)
		(property "Value" ""
			(at 0 0 90)
			(layer "F.Fab")
			(effects
				(font
					(size 1.27 1.27)
				)
			)
		)
		(duplicate_pad_numbers_are_jumpers no)
		(fp_line
			(start 0.7874 -0.4064)
			(end 0.7874 0.4064)
			(stroke
				(width 0.1524)
				(type default)
			)
			(layer "F.SilkS")
		)
		(fp_line
			(start -0.7874 -0.4064)
			(end 0.7874 -0.4064)
			(stroke
				(width 0.1524)
				(type default)
			)
			(layer "F.SilkS")
		)
		(fp_line
			(start 0.7874 0.4064)
			(end -0.7874 0.4064)
			(stroke
				(width 0.1524)
				(type default)
			)
			(layer "F.SilkS")
		)
		(fp_line
			(start -0.7874 0.4064)
			(end -0.7874 -0.4064)
			(stroke
				(width 0.1524)
				(type default)
			)
			(layer "F.SilkS")
		)
		(fp_line
			(start -0.12065 -0.305054)
			(end -0.12065 -0.2794)
			(stroke
				(width 0.1)
				(type default)
			)
			(layer "F.Fab")
		)
		(fp_line
			(start -0.67945 -0.305054)
			(end -0.12065 -0.305054)
			(stroke
				(width 0.1)
				(type default)
			)
			(layer "F.Fab")
		)
		(fp_line
			(start 0.67945 -0.3048)
			(end 0.67945 0.3048)
			(stroke
				(width 0.1)
				(type default)
			)
			(layer "F.Fab")
		)
		(fp_line
			(start 0.12065 -0.3048)
			(end 0.67945 -0.3048)
			(stroke
				(width 0.1)
				(type default)
			)
			(layer "F.Fab")
		)
		(fp_line
			(start 0.12065 -0.2794)
			(end 0.12065 -0.3048)
			(stroke
				(width 0.1)
				(type default)
			)
			(layer "F.Fab")
		)
		(fp_line
			(start -0.12065 -0.2794)
			(end 0.12065 -0.2794)
			(stroke
				(width 0.1)
				(type default)
			)
			(layer "F.Fab")
		)
		(fp_line
			(start 0.120396 0.2794)
			(end -0.12065 0.2794)
			(stroke
				(width 0.1)
				(type default)
			)
			(layer "F.Fab")
		)
		(fp_line
			(start -0.12065 0.2794)
			(end -0.12065 0.3048)
			(stroke
				(width 0.1)
				(type default)
			)
			(layer "F.Fab")
		)
		(fp_line
			(start 0.67945 0.3048)
			(end 0.120396 0.3048)
			(stroke
				(width 0.1)
				(type default)
			)
			(layer "F.Fab")
		)
		(fp_line
			(start 0.120396 0.3048)
			(end 0.120396 0.2794)
			(stroke
				(width 0.1)
				(type default)
			)
			(layer "F.Fab")
		)
		(fp_line
			(start -0.12065 0.3048)
			(end -0.67945 0.3048)
			(stroke
				(width 0.1)
				(type default)
			)
			(layer "F.Fab")
		)
		(fp_line
			(start -0.67945 0.3048)
			(end -0.67945 -0.305054)
			(stroke
				(width 0.1)
				(type default)
			)
			(layer "F.Fab")
		)
		(pad "1" smd circle
			(at -0.40005 0 90)
			(size 0 0)
			(layers "F.Cu" "F.Mask" "F.Paste")
			(net "P3V3_AUX")
		)
		(pad "2" smd circle
			(at 0.40005 0 90)
			(size 0 0)
			(layers "F.Cu" "F.Mask" "F.Paste")
			(net "PRSNT_CABLE_GPU_B3_N")
		)
	)
	(footprint ""
		(layer "F.Cu")
		(at 133.53288 -74.259948 90)
		(property "Reference" "C554"
			(at 0 0 90)
			(layer "F.SilkS")
			(hide yes)
			(effects
				(font
					(size 1.27 1.27)
				)
			)
		)
		(property "Value" ""
			(at 0 0 90)
			(layer "F.Fab")
			(effects
				(font
					(size 1.27 1.27)
				)
			)
		)
		(duplicate_pad_numbers_are_jumpers no)
		(fp_line
			(start 0.7874 -0.4064)
			(end 0.7874 0.4064)
			(stroke
				(width 0.1524)
				(type default)
			)
			(layer "F.SilkS")
		)
		(fp_line
			(start -0.7874 -0.4064)
			(end 0.7874 -0.4064)
			(stroke
				(width 0.1524)
				(type default)
			)
			(layer "F.SilkS")
		)
		(fp_line
			(start 0.7874 0.4064)
			(end -0.7874 0.4064)
			(stroke
				(width 0.1524)
				(type default)
			)
			(layer "F.SilkS")
		)
		(fp_line
			(start -0.7874 0.4064)
			(end -0.7874 -0.4064)
			(stroke
				(width 0.1524)
				(type default)
			)
			(layer "F.SilkS")
		)
		(fp_line
			(start -0.12065 -0.305054)
			(end -0.12065 -0.2794)
			(stroke
				(width 0.1)
				(type default)
			)
			(layer "F.Fab")
		)
		(fp_line
			(start -0.67945 -0.305054)
			(end -0.12065 -0.305054)
			(stroke
				(width 0.1)
				(type default)
			)
			(layer "F.Fab")
		)
		(fp_line
			(start 0.67945 -0.3048)
			(end 0.67945 0.3048)
			(stroke
				(width 0.1)
				(type default)
			)
			(layer "F.Fab")
		)
		(fp_line
			(start 0.12065 -0.3048)
			(end 0.67945 -0.3048)
			(stroke
				(width 0.1)
				(type default)
			)
			(layer "F.Fab")
		)
		(fp_line
			(start 0.12065 -0.2794)
			(end 0.12065 -0.3048)
			(stroke
				(width 0.1)
				(type default)
			)
			(layer "F.Fab")
		)
		(fp_line
			(start -0.12065 -0.2794)
			(end 0.12065 -0.2794)
			(stroke
				(width 0.1)
				(type default)
			)
			(layer "F.Fab")
		)
		(fp_line
			(start 0.120396 0.2794)
			(end -0.12065 0.2794)
			(stroke
				(width 0.1)
				(type default)
			)
			(layer "F.Fab")
		)
		(fp_line
			(start -0.12065 0.2794)
			(end -0.12065 0.3048)
			(stroke
				(width 0.1)
				(type default)
			)
			(layer "F.Fab")
		)
		(fp_line
			(start 0.67945 0.3048)
			(end 0.120396 0.3048)
			(stroke
				(width 0.1)
				(type default)
			)
			(layer "F.Fab")
		)
		(fp_line
			(start 0.120396 0.3048)
			(end 0.120396 0.2794)
			(stroke
				(width 0.1)
				(type default)
			)
			(layer "F.Fab")
		)
		(fp_line
			(start -0.12065 0.3048)
			(end -0.67945 0.3048)
			(stroke
				(width 0.1)
				(type default)
			)
			(layer "F.Fab")
		)
		(fp_line
			(start -0.67945 0.3048)
			(end -0.67945 -0.305054)
			(stroke
				(width 0.1)
				(type default)
			)
			(layer "F.Fab")
		)
		(pad "1" smd circle
			(at -0.40005 0 90)
			(size 0 0)
			(layers "F.Cu" "F.Mask" "F.Paste")
			(net "P3V3_AUX_BMC_D")
		)
		(pad "2" smd circle
			(at 0.40005 0 90)
			(size 0 0)
			(layers "F.Cu" "F.Mask" "F.Paste")
			(net "GND")
		)
	)
	(footprint ""
		(layer "F.Cu")
		(at 432.41468 -175.69942)
		(property "Reference" "PR501"
			(at 0 0 0)
			(layer "F.SilkS")
			(hide yes)
			(effects
				(font
					(size 1.27 1.27)
				)
			)
		)
		(property "Value" ""
			(at 0 0 0)
			(layer "F.Fab")
			(effects
				(font
					(size 1.27 1.27)
				)
			)
		)
		(duplicate_pad_numbers_are_jumpers no)
		(fp_line
			(start -0.7874 -0.4064)
			(end 0.7874 -0.4064)
			(stroke
				(width 0.1524)
				(type default)
			)
			(layer "F.SilkS")
		)
		(fp_line
			(start -0.7874 0.4064)
			(end -0.7874 -0.4064)
			(stroke
				(width 0.1524)
				(type default)
			)
			(layer "F.SilkS")
		)
		(fp_line
			(start 0.7874 -0.4064)
			(end 0.7874 0.4064)
			(stroke
				(width 0.1524)
				(type default)
			)
			(layer "F.SilkS")
		)
		(fp_line
			(start 0.7874 0.4064)
			(end -0.7874 0.4064)
			(stroke
				(width 0.1524)
				(type default)
			)
			(layer "F.SilkS")
		)
		(fp_line
			(start -0.67945 -0.305054)
			(end -0.12065 -0.305054)
			(stroke
				(width 0.1)
				(type default)
			)
			(layer "F.Fab")
		)
		(fp_line
			(start -0.67945 0.3048)
			(end -0.67945 -0.305054)
			(stroke
				(width 0.1)
				(type default)
			)
			(layer "F.Fab")
		)
		(fp_line
			(start -0.12065 -0.305054)
			(end -0.12065 -0.2794)
			(stroke
				(width 0.1)
				(type default)
			)
			(layer "F.Fab")
		)
		(fp_line
			(start -0.12065 -0.2794)
			(end 0.12065 -0.2794)
			(stroke
				(width 0.1)
				(type default)
			)
			(layer "F.Fab")
		)
		(fp_line
			(start -0.12065 0.2794)
			(end -0.12065 0.3048)
			(stroke
				(width 0.1)
				(type default)
			)
			(layer "F.Fab")
		)
		(fp_line
			(start -0.12065 0.3048)
			(end -0.67945 0.3048)
			(stroke
				(width 0.1)
				(type default)
			)
			(layer "F.Fab")
		)
		(fp_line
			(start 0.120396 0.2794)
			(end -0.12065 0.2794)
			(stroke
				(width 0.1)
				(type default)
			)
			(layer "F.Fab")
		)
		(fp_line
			(start 0.120396 0.3048)
			(end 0.120396 0.2794)
			(stroke
				(width 0.1)
				(type default)
			)
			(layer "F.Fab")
		)
		(fp_line
			(start 0.12065 -0.3048)
			(end 0.67945 -0.3048)
			(stroke
				(width 0.1)
				(type default)
			)
			(layer "F.Fab")
		)
		(fp_line
			(start 0.12065 -0.2794)
			(end 0.12065 -0.3048)
			(stroke
				(width 0.1)
				(type default)
			)
			(layer "F.Fab")
		)
		(fp_line
			(start 0.67945 -0.3048)
			(end 0.67945 0.3048)
			(stroke
				(width 0.1)
				(type default)
			)
			(layer "F.Fab")
		)
		(fp_line
			(start 0.67945 0.3048)
			(end 0.120396 0.3048)
			(stroke
				(width 0.1)
				(type default)
			)
			(layer "F.Fab")
		)
		(pad "1" smd circle
			(at -0.40005 0)
			(size 0 0)
			(layers "F.Cu" "F.Mask" "F.Paste")
			(net "PVNN_MAIN_CPU0_FB")
		)
		(pad "2" smd circle
			(at 0.40005 0)
			(size 0 0)
			(layers "F.Cu" "F.Mask" "F.Paste")
			(net "PVNN_MAIN_CPU0_FB_RC")
		)
	)
	(footprint ""
		(layer "F.Cu")
		(at 193.93408 -357.139748)
		(property "Reference" "R1005"
			(at 0 0 0)
			(layer "F.SilkS")
			(hide yes)
			(effects
				(font
					(size 1.27 1.27)
				)
			)
		)
		(property "Value" ""
			(at 0 0 0)
			(layer "F.Fab")
			(effects
				(font
					(size 1.27 1.27)
				)
			)
		)
		(duplicate_pad_numbers_are_jumpers no)
		(fp_line
			(start -0.7874 -0.4064)
			(end 0.7874 -0.4064)
			(stroke
				(width 0.1524)
				(type default)
			)
			(layer "F.SilkS")
		)
		(fp_line
			(start -0.7874 0.4064)
			(end -0.7874 -0.4064)
			(stroke
				(width 0.1524)
				(type default)
			)
			(layer "F.SilkS")
		)
		(fp_line
			(start 0.7874 -0.4064)
			(end 0.7874 0.4064)
			(stroke
				(width 0.1524)
				(type default)
			)
			(layer "F.SilkS")
		)
		(fp_line
			(start 0.7874 0.4064)
			(end -0.7874 0.4064)
			(stroke
				(width 0.1524)
				(type default)
			)
			(layer "F.SilkS")
		)
		(fp_line
			(start -0.67945 -0.305054)
			(end -0.12065 -0.305054)
			(stroke
				(width 0.1)
				(type default)
			)
			(layer "F.Fab")
		)
		(fp_line
			(start -0.67945 0.3048)
			(end -0.67945 -0.305054)
			(stroke
				(width 0.1)
				(type default)
			)
			(layer "F.Fab")
		)
		(fp_line
			(start -0.12065 -0.305054)
			(end -0.12065 -0.2794)
			(stroke
				(width 0.1)
				(type default)
			)
			(layer "F.Fab")
		)
		(fp_line
			(start -0.12065 -0.2794)
			(end 0.12065 -0.2794)
			(stroke
				(width 0.1)
				(type default)
			)
			(layer "F.Fab")
		)
		(fp_line
			(start -0.12065 0.2794)
			(end -0.12065 0.3048)
			(stroke
				(width 0.1)
				(type default)
			)
			(layer "F.Fab")
		)
		(fp_line
			(start -0.12065 0.3048)
			(end -0.67945 0.3048)
			(stroke
				(width 0.1)
				(type default)
			)
			(layer "F.Fab")
		)
		(fp_line
			(start 0.120396 0.2794)
			(end -0.12065 0.2794)
			(stroke
				(width 0.1)
				(type default)
			)
			(layer "F.Fab")
		)
		(fp_line
			(start 0.120396 0.3048)
			(end 0.120396 0.2794)
			(stroke
				(width 0.1)
				(type default)
			)
			(layer "F.Fab")
		)
		(fp_line
			(start 0.12065 -0.3048)
			(end 0.67945 -0.3048)
			(stroke
				(width 0.1)
				(type default)
			)
			(layer "F.Fab")
		)
		(fp_line
			(start 0.12065 -0.2794)
			(end 0.12065 -0.3048)
			(stroke
				(width 0.1)
				(type default)
			)
			(layer "F.Fab")
		)
		(fp_line
			(start 0.67945 -0.3048)
			(end 0.67945 0.3048)
			(stroke
				(width 0.1)
				(type default)
			)
			(layer "F.Fab")
		)
		(fp_line
			(start 0.67945 0.3048)
			(end 0.120396 0.3048)
			(stroke
				(width 0.1)
				(type default)
			)
			(layer "F.Fab")
		)
		(pad "1" smd circle
			(at -0.40005 0)
			(size 0 0)
			(layers "F.Cu" "F.Mask" "F.Paste")
			(net "PU_PIROM_CPU1_SM_WP")
		)
		(pad "2" smd circle
			(at 0.40005 0)
			(size 0 0)
			(layers "F.Cu" "F.Mask" "F.Paste")
			(net "GND")
		)
	)
	(footprint ""
		(layer "F.Cu")
		(at 446.73393 -181.983888)
		(property "Reference" "PC1278"
			(at 0 0 0)
			(layer "F.SilkS")
			(hide yes)
			(effects
				(font
					(size 1.27 1.27)
				)
			)
		)
		(property "Value" ""
			(at 0 0 0)
			(layer "F.Fab")
			(effects
				(font
					(size 1.27 1.27)
				)
			)
		)
		(duplicate_pad_numbers_are_jumpers no)
		(fp_line
			(start -1.524 -0.762)
			(end 1.524 -0.762)
			(stroke
				(width 0.1524)
				(type default)
			)
			(layer "F.SilkS")
		)
		(fp_line
			(start -1.524 0.762)
			(end -1.524 -0.762)
			(stroke
				(width 0.1524)
				(type default)
			)
			(layer "F.SilkS")
		)
		(fp_line
			(start 1.524 -0.762)
			(end 1.524 0.762)
			(stroke
				(width 0.1524)
				(type default)
			)
			(layer "F.SilkS")
		)
		(fp_line
			(start 1.524 0.762)
			(end -1.524 0.762)
			(stroke
				(width 0.1524)
				(type default)
			)
			(layer "F.SilkS")
		)
		(fp_line
			(start -1.1049 -0.724916)
			(end -1.1049 0.724916)
			(stroke
				(width 0.1)
				(type default)
			)
			(layer "F.Fab")
		)
		(fp_line
			(start -1.1049 0.724916)
			(end 1.1049 0.724916)
			(stroke
				(width 0.1)
				(type default)
			)
			(layer "F.Fab")
		)
		(fp_line
			(start 1.1049 -0.724916)
			(end -1.1049 -0.724916)
			(stroke
				(width 0.1)
				(type default)
			)
			(layer "F.Fab")
		)
		(fp_line
			(start 1.1049 0.724916)
			(end 1.1049 -0.724916)
			(stroke
				(width 0.1)
				(type default)
			)
			(layer "F.Fab")
		)
		(pad "1" smd rect
			(at -0.889 0 180)
			(size 1.016 1.27)
			(layers "F.Cu" "F.Mask" "F.Paste")
			(net "PVNN_MAIN_CPU0")
		)
		(pad "2" smd rect
			(at 0.889 0 180)
			(size 1.016 1.27)
			(layers "F.Cu" "F.Mask" "F.Paste")
			(net "GND")
		)
	)
	(footprint ""
		(layer "F.Cu")
		(at 28.578048 -71.88073)
		(property "Reference" "C1810"
			(at 0 0 0)
			(layer "F.SilkS")
			(hide yes)
			(effects
				(font
					(size 1.27 1.27)
				)
			)
		)
		(property "Value" ""
			(at 0 0 0)
			(layer "F.Fab")
			(effects
				(font
					(size 1.27 1.27)
				)
			)
		)
		(duplicate_pad_numbers_are_jumpers no)
		(fp_line
			(start -0.7874 -0.4064)
			(end 0.7874 -0.4064)
			(stroke
				(width 0.1524)
				(type default)
			)
			(layer "F.SilkS")
		)
		(fp_line
			(start -0.7874 0.4064)
			(end -0.7874 -0.4064)
			(stroke
				(width 0.1524)
				(type default)
			)
			(layer "F.SilkS")
		)
		(fp_line
			(start 0.7874 -0.4064)
			(end 0.7874 0.4064)
			(stroke
				(width 0.1524)
				(type default)
			)
			(layer "F.SilkS")
		)
		(fp_line
			(start 0.7874 0.4064)
			(end -0.7874 0.4064)
			(stroke
				(width 0.1524)
				(type default)
			)
			(layer "F.SilkS")
		)
		(fp_line
			(start -0.67945 -0.305054)
			(end -0.12065 -0.305054)
			(stroke
				(width 0.1)
				(type default)
			)
			(layer "F.Fab")
		)
		(fp_line
			(start -0.67945 0.3048)
			(end -0.67945 -0.305054)
			(stroke
				(width 0.1)
				(type default)
			)
			(layer "F.Fab")
		)
		(fp_line
			(start -0.12065 -0.305054)
			(end -0.12065 -0.2794)
			(stroke
				(width 0.1)
				(type default)
			)
			(layer "F.Fab")
		)
		(fp_line
			(start -0.12065 -0.2794)
			(end 0.12065 -0.2794)
			(stroke
				(width 0.1)
				(type default)
			)
			(layer "F.Fab")
		)
		(fp_line
			(start -0.12065 0.2794)
			(end -0.12065 0.3048)
			(stroke
				(width 0.1)
				(type default)
			)
			(layer "F.Fab")
		)
		(fp_line
			(start -0.12065 0.3048)
			(end -0.67945 0.3048)
			(stroke
				(width 0.1)
				(type default)
			)
			(layer "F.Fab")
		)
		(fp_line
			(start 0.120396 0.2794)
			(end -0.12065 0.2794)
			(stroke
				(width 0.1)
				(type default)
			)
			(layer "F.Fab")
		)
		(fp_line
			(start 0.120396 0.3048)
			(end 0.120396 0.2794)
			(stroke
				(width 0.1)
				(type default)
			)
			(layer "F.Fab")
		)
		(fp_line
			(start 0.12065 -0.3048)
			(end 0.67945 -0.3048)
			(stroke
				(width 0.1)
				(type default)
			)
			(layer "F.Fab")
		)
		(fp_line
			(start 0.12065 -0.2794)
			(end 0.12065 -0.3048)
			(stroke
				(width 0.1)
				(type default)
			)
			(layer "F.Fab")
		)
		(fp_line
			(start 0.67945 -0.3048)
			(end 0.67945 0.3048)
			(stroke
				(width 0.1)
				(type default)
			)
			(layer "F.Fab")
		)
		(fp_line
			(start 0.67945 0.3048)
			(end 0.120396 0.3048)
			(stroke
				(width 0.1)
				(type default)
			)
			(layer "F.Fab")
		)
		(pad "1" smd circle
			(at -0.40005 0)
			(size 0 0)
			(layers "F.Cu" "F.Mask" "F.Paste")
			(net "P3V3_AUX")
		)
		(pad "2" smd circle
			(at 0.40005 0)
			(size 0 0)
			(layers "F.Cu" "F.Mask" "F.Paste")
			(net "GND")
		)
	)
	(footprint ""
		(layer "F.Cu")
		(at 284.62732 -408.53868)
		(property "Reference" "R4893"
			(at 0 0 0)
			(layer "F.SilkS")
			(hide yes)
			(effects
				(font
					(size 1.27 1.27)
				)
			)
		)
		(property "Value" ""
			(at 0 0 0)
			(layer "F.Fab")
			(effects
				(font
					(size 1.27 1.27)
				)
			)
		)
		(duplicate_pad_numbers_are_jumpers no)
		(fp_line
			(start -0.7874 -0.4064)
			(end 0.7874 -0.4064)
			(stroke
				(width 0.1524)
				(type default)
			)
			(layer "F.SilkS")
		)
		(fp_line
			(start -0.7874 0.4064)
			(end -0.7874 -0.4064)
			(stroke
				(width 0.1524)
				(type default)
			)
			(layer "F.SilkS")
		)
		(fp_line
			(start 0.7874 -0.4064)
			(end 0.7874 0.4064)
			(stroke
				(width 0.1524)
				(type default)
			)
			(layer "F.SilkS")
		)
		(fp_line
			(start 0.7874 0.4064)
			(end -0.7874 0.4064)
			(stroke
				(width 0.1524)
				(type default)
			)
			(layer "F.SilkS")
		)
		(fp_line
			(start -0.67945 -0.305054)
			(end -0.12065 -0.305054)
			(stroke
				(width 0.1)
				(type default)
			)
			(layer "F.Fab")
		)
		(fp_line
			(start -0.67945 0.3048)
			(end -0.67945 -0.305054)
			(stroke
				(width 0.1)
				(type default)
			)
			(layer "F.Fab")
		)
		(fp_line
			(start -0.12065 -0.305054)
			(end -0.12065 -0.2794)
			(stroke
				(width 0.1)
				(type default)
			)
			(layer "F.Fab")
		)
		(fp_line
			(start -0.12065 -0.2794)
			(end 0.12065 -0.2794)
			(stroke
				(width 0.1)
				(type default)
			)
			(layer "F.Fab")
		)
		(fp_line
			(start -0.12065 0.2794)
			(end -0.12065 0.3048)
			(stroke
				(width 0.1)
				(type default)
			)
			(layer "F.Fab")
		)
		(fp_line
			(start -0.12065 0.3048)
			(end -0.67945 0.3048)
			(stroke
				(width 0.1)
				(type default)
			)
			(layer "F.Fab")
		)
		(fp_line
			(start 0.120396 0.2794)
			(end -0.12065 0.2794)
			(stroke
				(width 0.1)
				(type default)
			)
			(layer "F.Fab")
		)
		(fp_line
			(start 0.120396 0.3048)
			(end 0.120396 0.2794)
			(stroke
				(width 0.1)
				(type default)
			)
			(layer "F.Fab")
		)
		(fp_line
			(start 0.12065 -0.3048)
			(end 0.67945 -0.3048)
			(stroke
				(width 0.1)
				(type default)
			)
			(layer "F.Fab")
		)
		(fp_line
			(start 0.12065 -0.2794)
			(end 0.12065 -0.3048)
			(stroke
				(width 0.1)
				(type default)
			)
			(layer "F.Fab")
		)
		(fp_line
			(start 0.67945 -0.3048)
			(end 0.67945 0.3048)
			(stroke
				(width 0.1)
				(type default)
			)
			(layer "F.Fab")
		)
		(fp_line
			(start 0.67945 0.3048)
			(end 0.120396 0.3048)
			(stroke
				(width 0.1)
				(type default)
			)
			(layer "F.Fab")
		)
		(pad "1" smd circle
			(at -0.40005 0)
			(size 0 0)
			(layers "F.Cu" "F.Mask" "F.Paste")
			(net "P12V_HSC_TEMP_E")
		)
		(pad "2" smd circle
			(at 0.40005 0)
			(size 0 0)
			(layers "F.Cu" "F.Mask" "F.Paste")
			(net "P12V_HSC_TEMP_D-")
		)
	)
	(footprint ""
		(layer "F.Cu")
		(at 216.18575 -43.738292 180)
		(property "Reference" "U279"
			(at -0.69977 -3.434334 0)
			(unlocked yes)
			(layer "F.SilkS")
			(effects
				(font
					(size 0.7874 0.5842)
					(thickness 0.1524)
				)
				(justify left)
			)
		)
		(property "Value" ""
			(at 0 0 180)
			(layer "F.Fab")
			(effects
				(font
					(size 1.27 1.27)
				)
			)
		)
		(duplicate_pad_numbers_are_jumpers no)
		(fp_line
			(start 1.463548 1.549908)
			(end -1.463548 1.549908)
			(stroke
				(width 0.1524)
				(type default)
			)
			(layer "F.SilkS")
		)
		(fp_line
			(start 1.463548 -1.549908)
			(end 1.463548 1.549908)
			(stroke
				(width 0.1524)
				(type default)
			)
			(layer "F.SilkS")
		)
		(fp_line
			(start 0.762 -1.549908)
			(end 1.463548 -1.549908)
			(stroke
				(width 0.1524)
				(type default)
			)
			(layer "F.SilkS")
		)
		(fp_line
			(start 0 -0.762)
			(end 0.762 -1.549908)
			(stroke
				(width 0.1524)
				(type default)
			)
			(layer "F.SilkS")
		)
		(fp_line
			(start -0.787908 -1.549908)
			(end 0 -0.762)
			(stroke
				(width 0.1524)
				(type default)
			)
			(layer "F.SilkS")
		)
		(fp_line
			(start -1.463548 1.549908)
			(end -1.463548 -1.549908)
			(stroke
				(width 0.1524)
				(type default)
			)
			(layer "F.SilkS")
		)
		(fp_line
			(start -1.463548 -1.549908)
			(end -0.787908 -1.549908)
			(stroke
				(width 0.1524)
				(type default)
			)
			(layer "F.SilkS")
		)
		(fp_poly
			(pts
				(xy -2.86004 -1.050036) (xy -3.4798 -0.740156) (xy -3.4798 -1.359916)
			)
			(stroke
				(width 0)
				(type default)
			)
			(fill yes)
			(layer "F.SilkS")
		)
		(fp_line
			(start 1.549908 1.549908)
			(end -1.549908 1.549908)
			(stroke
				(width 0.1)
				(type default)
			)
			(layer "F.Fab")
		)
		(fp_line
			(start 1.549908 -1.549908)
			(end 1.549908 1.549908)
			(stroke
				(width 0.1)
				(type default)
			)
			(layer "F.Fab")
		)
		(fp_line
			(start -1.549908 1.549908)
			(end -1.549908 -1.549908)
			(stroke
				(width 0.1)
				(type default)
			)
			(layer "F.Fab")
		)
		(fp_line
			(start -1.549908 -1.549908)
			(end 1.549908 -1.549908)
			(stroke
				(width 0.1)
				(type default)
			)
			(layer "F.Fab")
		)
		(fp_poly
			(pts
				(xy -3.4798 -1.359916) (xy -2.86004 -1.050036) (xy -3.4798 -0.740156)
			)
			(stroke
				(width 0)
				(type default)
			)
			(fill yes)
			(layer "F.Fab")
		)
		(pad "1" smd rect
			(at -2.175002 -1.050036 270)
			(size 0.6096 1.1684)
			(layers "F.Cu" "F.Mask" "F.Paste")
			(net "P3V3_E1S_0")
		)
		(pad "2" smd rect
			(at -2.175002 -0.32512 270)
			(size 0.4318 1.1684)
			(layers "F.Cu" "F.Mask" "F.Paste")
			(net "SMB_E1S_3V3AUX_ISO_SCL_R")
		)
		(pad "3" smd rect
			(at -2.175002 0.32512 270)
			(size 0.4318 1.1684)
			(layers "F.Cu" "F.Mask" "F.Paste")
			(net "SMB_E1S_3V3AUX_ISO_SDA_R")
		)
		(pad "4" smd rect
			(at -2.175002 1.050036 270)
			(size 0.6096 1.1684)
			(layers "F.Cu" "F.Mask" "F.Paste")
			(net "GND")
		)
		(pad "5" smd rect
			(at 2.175002 1.050036 270)
			(size 0.6096 1.1684)
			(layers "F.Cu" "F.Mask" "F.Paste")
			(net "SMB_PCIE_E1S_ISO_EN_R")
		)
		(pad "6" smd rect
			(at 2.175002 0.32512 270)
			(size 0.4318 1.1684)
			(layers "F.Cu" "F.Mask" "F.Paste")
			(net "SMB_SENSOR_E1S_3V3AUX_SDA")
		)
		(pad "7" smd rect
			(at 2.175002 -0.32512 270)
			(size 0.4318 1.1684)
			(layers "F.Cu" "F.Mask" "F.Paste")
			(net "SMB_SENSOR_E1S_3V3AUX_SCL")
		)
		(pad "8" smd rect
			(at 2.175002 -1.050036 270)
			(size 0.6096 1.1684)
			(layers "F.Cu" "F.Mask" "F.Paste")
			(net "P3V3_AUX")
		)
	)
	(footprint ""
		(layer "F.Cu")
		(at 51.860196 -358.20223 90)
		(property "Reference" "PR1801"
			(at 0 0 90)
			(layer "F.SilkS")
			(hide yes)
			(effects
				(font
					(size 1.27 1.27)
				)
			)
		)
		(property "Value" ""
			(at 0 0 90)
			(layer "F.Fab")
			(effects
				(font
					(size 1.27 1.27)
				)
			)
		)
		(duplicate_pad_numbers_are_jumpers no)
		(fp_line
			(start 0.7874 -0.4064)
			(end 0.7874 0.4064)
			(stroke
				(width 0.1524)
				(type default)
			)
			(layer "F.SilkS")
		)
		(fp_line
			(start -0.7874 -0.4064)
			(end 0.7874 -0.4064)
			(stroke
				(width 0.1524)
				(type default)
			)
			(layer "F.SilkS")
		)
		(fp_line
			(start 0.7874 0.4064)
			(end -0.7874 0.4064)
			(stroke
				(width 0.1524)
				(type default)
			)
			(layer "F.SilkS")
		)
		(fp_line
			(start -0.7874 0.4064)
			(end -0.7874 -0.4064)
			(stroke
				(width 0.1524)
				(type default)
			)
			(layer "F.SilkS")
		)
		(fp_line
			(start -0.12065 -0.305054)
			(end -0.12065 -0.2794)
			(stroke
				(width 0.1)
				(type default)
			)
			(layer "F.Fab")
		)
		(fp_line
			(start -0.67945 -0.305054)
			(end -0.12065 -0.305054)
			(stroke
				(width 0.1)
				(type default)
			)
			(layer "F.Fab")
		)
		(fp_line
			(start 0.67945 -0.3048)
			(end 0.67945 0.3048)
			(stroke
				(width 0.1)
				(type default)
			)
			(layer "F.Fab")
		)
		(fp_line
			(start 0.12065 -0.3048)
			(end 0.67945 -0.3048)
			(stroke
				(width 0.1)
				(type default)
			)
			(layer "F.Fab")
		)
		(fp_line
			(start 0.12065 -0.2794)
			(end 0.12065 -0.3048)
			(stroke
				(width 0.1)
				(type default)
			)
			(layer "F.Fab")
		)
		(fp_line
			(start -0.12065 -0.2794)
			(end 0.12065 -0.2794)
			(stroke
				(width 0.1)
				(type default)
			)
			(layer "F.Fab")
		)
		(fp_line
			(start 0.120396 0.2794)
			(end -0.12065 0.2794)
			(stroke
				(width 0.1)
				(type default)
			)
			(layer "F.Fab")
		)
		(fp_line
			(start -0.12065 0.2794)
			(end -0.12065 0.3048)
			(stroke
				(width 0.1)
				(type default)
			)
			(layer "F.Fab")
		)
		(fp_line
			(start 0.67945 0.3048)
			(end 0.120396 0.3048)
			(stroke
				(width 0.1)
				(type default)
			)
			(layer "F.Fab")
		)
		(fp_line
			(start 0.120396 0.3048)
			(end 0.120396 0.2794)
			(stroke
				(width 0.1)
				(type default)
			)
			(layer "F.Fab")
		)
		(fp_line
			(start -0.12065 0.3048)
			(end -0.67945 0.3048)
			(stroke
				(width 0.1)
				(type default)
			)
			(layer "F.Fab")
		)
		(fp_line
			(start -0.67945 0.3048)
			(end -0.67945 -0.305054)
			(stroke
				(width 0.1)
				(type default)
			)
			(layer "F.Fab")
		)
		(pad "1" smd circle
			(at -0.40005 0 90)
			(size 0 0)
			(layers "F.Cu" "F.Mask" "F.Paste")
			(net "SW_PVCCFA_EHV_FIVRA_CPU1_BOOT2")
		)
		(pad "2" smd circle
			(at 0.40005 0 90)
			(size 0 0)
			(layers "F.Cu" "F.Mask" "F.Paste")
			(net "SW_PVCCFA_EHV_FIVRA_CPU1_BOOT2_")
		)
	)
	(footprint ""
		(layer "F.Cu")
		(at 31.856426 -77.783944 180)
		(property "Reference" "R3145"
			(at 0 0 180)
			(layer "F.SilkS")
			(hide yes)
			(effects
				(font
					(size 1.27 1.27)
				)
			)
		)
		(property "Value" ""
			(at 0 0 180)
			(layer "F.Fab")
			(effects
				(font
					(size 1.27 1.27)
				)
			)
		)
		(duplicate_pad_numbers_are_jumpers no)
		(fp_line
			(start 0.7874 0.4064)
			(end -0.7874 0.4064)
			(stroke
				(width 0.1524)
				(type default)
			)
			(layer "F.SilkS")
		)
		(fp_line
			(start 0.7874 -0.4064)
			(end 0.7874 0.4064)
			(stroke
				(width 0.1524)
				(type default)
			)
			(layer "F.SilkS")
		)
		(fp_line
			(start -0.7874 0.4064)
			(end -0.7874 -0.4064)
			(stroke
				(width 0.1524)
				(type default)
			)
			(layer "F.SilkS")
		)
		(fp_line
			(start -0.7874 -0.4064)
			(end 0.7874 -0.4064)
			(stroke
				(width 0.1524)
				(type default)
			)
			(layer "F.SilkS")
		)
		(fp_line
			(start 0.67945 0.3048)
			(end 0.120396 0.3048)
			(stroke
				(width 0.1)
				(type default)
			)
			(layer "F.Fab")
		)
		(fp_line
			(start 0.67945 -0.3048)
			(end 0.67945 0.3048)
			(stroke
				(width 0.1)
				(type default)
			)
			(layer "F.Fab")
		)
		(fp_line
			(start 0.12065 -0.2794)
			(end 0.12065 -0.3048)
			(stroke
				(width 0.1)
				(type default)
			)
			(layer "F.Fab")
		)
		(fp_line
			(start 0.12065 -0.3048)
			(end 0.67945 -0.3048)
			(stroke
				(width 0.1)
				(type default)
			)
			(layer "F.Fab")
		)
		(fp_line
			(start 0.120396 0.3048)
			(end 0.120396 0.2794)
			(stroke
				(width 0.1)
				(type default)
			)
			(layer "F.Fab")
		)
		(fp_line
			(start 0.120396 0.2794)
			(end -0.12065 0.2794)
			(stroke
				(width 0.1)
				(type default)
			)
			(layer "F.Fab")
		)
		(fp_line
			(start -0.12065 0.3048)
			(end -0.67945 0.3048)
			(stroke
				(width 0.1)
				(type default)
			)
			(layer "F.Fab")
		)
		(fp_line
			(start -0.12065 0.2794)
			(end -0.12065 0.3048)
			(stroke
				(width 0.1)
				(type default)
			)
			(layer "F.Fab")
		)
		(fp_line
			(start -0.12065 -0.2794)
			(end 0.12065 -0.2794)
			(stroke
				(width 0.1)
				(type default)
			)
			(layer "F.Fab")
		)
		(fp_line
			(start -0.12065 -0.305054)
			(end -0.12065 -0.2794)
			(stroke
				(width 0.1)
				(type default)
			)
			(layer "F.Fab")
		)
		(fp_line
			(start -0.67945 0.3048)
			(end -0.67945 -0.305054)
			(stroke
				(width 0.1)
				(type default)
			)
			(layer "F.Fab")
		)
		(fp_line
			(start -0.67945 -0.305054)
			(end -0.12065 -0.305054)
			(stroke
				(width 0.1)
				(type default)
			)
			(layer "F.Fab")
		)
		(pad "1" smd circle
			(at -0.40005 0 180)
			(size 0 0)
			(layers "F.Cu" "F.Mask" "F.Paste")
			(net "P3V3_AUX")
		)
		(pad "2" smd circle
			(at 0.40005 0 180)
			(size 0 0)
			(layers "F.Cu" "F.Mask" "F.Paste")
			(net "HP_LVC3_OCP_V3_2_ATTN_OUT_SW_N")
		)
	)
	(footprint ""
		(layer "F.Cu")
		(at 352.264726 -258.726686 90)
		(property "Reference" "C420"
			(at 0 0 90)
			(layer "F.SilkS")
			(hide yes)
			(effects
				(font
					(size 1.27 1.27)
				)
			)
		)
		(property "Value" ""
			(at 0 0 90)
			(layer "F.Fab")
			(effects
				(font
					(size 1.27 1.27)
				)
			)
		)
		(duplicate_pad_numbers_are_jumpers no)
		(fp_line
			(start 0.7874 -0.4064)
			(end 0.7874 0.4064)
			(stroke
				(width 0.1524)
				(type default)
			)
			(layer "F.SilkS")
		)
		(fp_line
			(start -0.7874 -0.4064)
			(end 0.7874 -0.4064)
			(stroke
				(width 0.1524)
				(type default)
			)
			(layer "F.SilkS")
		)
		(fp_line
			(start 0.7874 0.4064)
			(end -0.7874 0.4064)
			(stroke
				(width 0.1524)
				(type default)
			)
			(layer "F.SilkS")
		)
		(fp_line
			(start -0.7874 0.4064)
			(end -0.7874 -0.4064)
			(stroke
				(width 0.1524)
				(type default)
			)
			(layer "F.SilkS")
		)
		(fp_line
			(start -0.12065 -0.305054)
			(end -0.12065 -0.2794)
			(stroke
				(width 0.1)
				(type default)
			)
			(layer "F.Fab")
		)
		(fp_line
			(start -0.67945 -0.305054)
			(end -0.12065 -0.305054)
			(stroke
				(width 0.1)
				(type default)
			)
			(layer "F.Fab")
		)
		(fp_line
			(start 0.67945 -0.3048)
			(end 0.67945 0.3048)
			(stroke
				(width 0.1)
				(type default)
			)
			(layer "F.Fab")
		)
		(fp_line
			(start 0.12065 -0.3048)
			(end 0.67945 -0.3048)
			(stroke
				(width 0.1)
				(type default)
			)
			(layer "F.Fab")
		)
		(fp_line
			(start 0.12065 -0.2794)
			(end 0.12065 -0.3048)
			(stroke
				(width 0.1)
				(type default)
			)
			(layer "F.Fab")
		)
		(fp_line
			(start -0.12065 -0.2794)
			(end 0.12065 -0.2794)
			(stroke
				(width 0.1)
				(type default)
			)
			(layer "F.Fab")
		)
		(fp_line
			(start 0.120396 0.2794)
			(end -0.12065 0.2794)
			(stroke
				(width 0.1)
				(type default)
			)
			(layer "F.Fab")
		)
		(fp_line
			(start -0.12065 0.2794)
			(end -0.12065 0.3048)
			(stroke
				(width 0.1)
				(type default)
			)
			(layer "F.Fab")
		)
		(fp_line
			(start 0.67945 0.3048)
			(end 0.120396 0.3048)
			(stroke
				(width 0.1)
				(type default)
			)
			(layer "F.Fab")
		)
		(fp_line
			(start 0.120396 0.3048)
			(end 0.120396 0.2794)
			(stroke
				(width 0.1)
				(type default)
			)
			(layer "F.Fab")
		)
		(fp_line
			(start -0.12065 0.3048)
			(end -0.67945 0.3048)
			(stroke
				(width 0.1)
				(type default)
			)
			(layer "F.Fab")
		)
		(fp_line
			(start -0.67945 0.3048)
			(end -0.67945 -0.305054)
			(stroke
				(width 0.1)
				(type default)
			)
			(layer "F.Fab")
		)
		(pad "1" smd circle
			(at -0.40005 0 90)
			(size 0 0)
			(layers "F.Cu" "F.Mask" "F.Paste")
			(net "PVCCFA_EHV_CPU0")
		)
		(pad "2" smd circle
			(at 0.40005 0 90)
			(size 0 0)
			(layers "F.Cu" "F.Mask" "F.Paste")
			(net "GND")
		)
	)
	(footprint ""
		(layer "F.Cu")
		(at 90.037158 -408.517344 -90)
		(property "Reference" "C683"
			(at 0 0 270)
			(layer "F.SilkS")
			(hide yes)
			(effects
				(font
					(size 1.27 1.27)
				)
			)
		)
		(property "Value" ""
			(at 0 0 270)
			(layer "F.Fab")
			(effects
				(font
					(size 1.27 1.27)
				)
			)
		)
		(duplicate_pad_numbers_are_jumpers no)
		(fp_line
			(start -0.299974 0.150114)
			(end -0.299974 -0.150114)
			(stroke
				(width 0.1)
				(type default)
			)
			(layer "F.Fab")
		)
		(fp_line
			(start 0.299974 0.150114)
			(end -0.299974 0.150114)
			(stroke
				(width 0.1)
				(type default)
			)
			(layer "F.Fab")
		)
		(fp_line
			(start -0.299974 -0.150114)
			(end 0.299974 -0.150114)
			(stroke
				(width 0.1)
				(type default)
			)
			(layer "F.Fab")
		)
		(fp_line
			(start 0.299974 -0.150114)
			(end 0.299974 0.150114)
			(stroke
				(width 0.1)
				(type default)
			)
			(layer "F.Fab")
		)
		(pad "1" smd rect
			(at -0.2667 0 270)
			(size 0.3048 0.381)
			(layers "F.Cu" "F.Mask" "F.Paste")
			(net "P5E_CPU1_PE4_TX_C_DP<13>")
		)
		(pad "2" smd rect
			(at 0.2667 0 270)
			(size 0.3048 0.381)
			(layers "F.Cu" "F.Mask" "F.Paste")
			(net "P5E_CPU1_PE4_TX_DP<13>")
		)
	)
	(footprint ""
		(layer "F.Cu")
		(at 436.224172 -32.173418 90)
		(property "Reference" "R3872"
			(at 0 0 90)
			(layer "F.SilkS")
			(hide yes)
			(effects
				(font
					(size 1.27 1.27)
				)
			)
		)
		(property "Value" ""
			(at 0 0 90)
			(layer "F.Fab")
			(effects
				(font
					(size 1.27 1.27)
				)
			)
		)
		(duplicate_pad_numbers_are_jumpers no)
		(fp_line
			(start 0.7874 -0.4064)
			(end 0.7874 0.4064)
			(stroke
				(width 0.1524)
				(type default)
			)
			(layer "F.SilkS")
		)
		(fp_line
			(start -0.7874 -0.4064)
			(end 0.7874 -0.4064)
			(stroke
				(width 0.1524)
				(type default)
			)
			(layer "F.SilkS")
		)
		(fp_line
			(start 0.7874 0.4064)
			(end -0.7874 0.4064)
			(stroke
				(width 0.1524)
				(type default)
			)
			(layer "F.SilkS")
		)
		(fp_line
			(start -0.7874 0.4064)
			(end -0.7874 -0.4064)
			(stroke
				(width 0.1524)
				(type default)
			)
			(layer "F.SilkS")
		)
		(fp_line
			(start -0.12065 -0.305054)
			(end -0.12065 -0.2794)
			(stroke
				(width 0.1)
				(type default)
			)
			(layer "F.Fab")
		)
		(fp_line
			(start -0.67945 -0.305054)
			(end -0.12065 -0.305054)
			(stroke
				(width 0.1)
				(type default)
			)
			(layer "F.Fab")
		)
		(fp_line
			(start 0.67945 -0.3048)
			(end 0.67945 0.3048)
			(stroke
				(width 0.1)
				(type default)
			)
			(layer "F.Fab")
		)
		(fp_line
			(start 0.12065 -0.3048)
			(end 0.67945 -0.3048)
			(stroke
				(width 0.1)
				(type default)
			)
			(layer "F.Fab")
		)
		(fp_line
			(start 0.12065 -0.2794)
			(end 0.12065 -0.3048)
			(stroke
				(width 0.1)
				(type default)
			)
			(layer "F.Fab")
		)
		(fp_line
			(start -0.12065 -0.2794)
			(end 0.12065 -0.2794)
			(stroke
				(width 0.1)
				(type default)
			)
			(layer "F.Fab")
		)
		(fp_line
			(start 0.120396 0.2794)
			(end -0.12065 0.2794)
			(stroke
				(width 0.1)
				(type default)
			)
			(layer "F.Fab")
		)
		(fp_line
			(start -0.12065 0.2794)
			(end -0.12065 0.3048)
			(stroke
				(width 0.1)
				(type default)
			)
			(layer "F.Fab")
		)
		(fp_line
			(start 0.67945 0.3048)
			(end 0.120396 0.3048)
			(stroke
				(width 0.1)
				(type default)
			)
			(layer "F.Fab")
		)
		(fp_line
			(start 0.120396 0.3048)
			(end 0.120396 0.2794)
			(stroke
				(width 0.1)
				(type default)
			)
			(layer "F.Fab")
		)
		(fp_line
			(start -0.12065 0.3048)
			(end -0.67945 0.3048)
			(stroke
				(width 0.1)
				(type default)
			)
			(layer "F.Fab")
		)
		(fp_line
			(start -0.67945 0.3048)
			(end -0.67945 -0.305054)
			(stroke
				(width 0.1)
				(type default)
			)
			(layer "F.Fab")
		)
		(pad "1" smd circle
			(at -0.40005 0 90)
			(size 0 0)
			(layers "F.Cu" "F.Mask" "F.Paste")
			(net "P12V_OCP_IMON_1")
		)
		(pad "2" smd circle
			(at 0.40005 0 90)
			(size 0 0)
			(layers "F.Cu" "F.Mask" "F.Paste")
			(net "P12V_OCP_SFF_ISENSE_MPS_TIC")
		)
	)
	(footprint ""
		(layer "F.Cu")
		(at 105.39222 -294.01008 180)
		(property "Reference" "C255"
			(at 0 0 180)
			(layer "F.SilkS")
			(hide yes)
			(effects
				(font
					(size 1.27 1.27)
				)
			)
		)
		(property "Value" ""
			(at 0 0 180)
			(layer "F.Fab")
			(effects
				(font
					(size 1.27 1.27)
				)
			)
		)
		(duplicate_pad_numbers_are_jumpers no)
		(fp_line
			(start 1.524 0.762)
			(end -1.524 0.762)
			(stroke
				(width 0.1524)
				(type default)
			)
			(layer "F.SilkS")
		)
		(fp_line
			(start 1.524 -0.762)
			(end 1.524 0.762)
			(stroke
				(width 0.1524)
				(type default)
			)
			(layer "F.SilkS")
		)
		(fp_line
			(start -1.524 0.762)
			(end -1.524 -0.762)
			(stroke
				(width 0.1524)
				(type default)
			)
			(layer "F.SilkS")
		)
		(fp_line
			(start -1.524 -0.762)
			(end 1.524 -0.762)
			(stroke
				(width 0.1524)
				(type default)
			)
			(layer "F.SilkS")
		)
		(fp_line
			(start 1.1049 0.724916)
			(end 1.1049 -0.724916)
			(stroke
				(width 0.1)
				(type default)
			)
			(layer "F.Fab")
		)
		(fp_line
			(start 1.1049 -0.724916)
			(end -1.1049 -0.724916)
			(stroke
				(width 0.1)
				(type default)
			)
			(layer "F.Fab")
		)
		(fp_line
			(start -1.1049 0.724916)
			(end 1.1049 0.724916)
			(stroke
				(width 0.1)
				(type default)
			)
			(layer "F.Fab")
		)
		(fp_line
			(start -1.1049 -0.724916)
			(end -1.1049 0.724916)
			(stroke
				(width 0.1)
				(type default)
			)
			(layer "F.Fab")
		)
		(pad "1" smd rect
			(at -0.889 0)
			(size 1.016 1.27)
			(layers "F.Cu" "F.Mask" "F.Paste")
			(net "PVCCIN_CPU1")
		)
		(pad "2" smd rect
			(at 0.889 0)
			(size 1.016 1.27)
			(layers "F.Cu" "F.Mask" "F.Paste")
			(net "GND")
		)
	)
	(footprint ""
		(layer "F.Cu")
		(at 17.737582 -423.629836 -90)
		(property "Reference" "R3517"
			(at 0 0 270)
			(layer "F.SilkS")
			(hide yes)
			(effects
				(font
					(size 1.27 1.27)
				)
			)
		)
		(property "Value" ""
			(at 0 0 270)
			(layer "F.Fab")
			(effects
				(font
					(size 1.27 1.27)
				)
			)
		)
		(duplicate_pad_numbers_are_jumpers no)
		(fp_line
			(start -0.7874 0.4064)
			(end -0.7874 -0.4064)
			(stroke
				(width 0.1524)
				(type default)
			)
			(layer "F.SilkS")
		)
		(fp_line
			(start 0.7874 0.4064)
			(end -0.7874 0.4064)
			(stroke
				(width 0.1524)
				(type default)
			)
			(layer "F.SilkS")
		)
		(fp_line
			(start -0.7874 -0.4064)
			(end 0.7874 -0.4064)
			(stroke
				(width 0.1524)
				(type default)
			)
			(layer "F.SilkS")
		)
		(fp_line
			(start 0.7874 -0.4064)
			(end 0.7874 0.4064)
			(stroke
				(width 0.1524)
				(type default)
			)
			(layer "F.SilkS")
		)
		(fp_line
			(start -0.67945 0.3048)
			(end -0.67945 -0.305054)
			(stroke
				(width 0.1)
				(type default)
			)
			(layer "F.Fab")
		)
		(fp_line
			(start -0.12065 0.3048)
			(end -0.67945 0.3048)
			(stroke
				(width 0.1)
				(type default)
			)
			(layer "F.Fab")
		)
		(fp_line
			(start 0.120396 0.3048)
			(end 0.120396 0.2794)
			(stroke
				(width 0.1)
				(type default)
			)
			(layer "F.Fab")
		)
		(fp_line
			(start 0.67945 0.3048)
			(end 0.120396 0.3048)
			(stroke
				(width 0.1)
				(type default)
			)
			(layer "F.Fab")
		)
		(fp_line
			(start -0.12065 0.2794)
			(end -0.12065 0.3048)
			(stroke
				(width 0.1)
				(type default)
			)
			(layer "F.Fab")
		)
		(fp_line
			(start 0.120396 0.2794)
			(end -0.12065 0.2794)
			(stroke
				(width 0.1)
				(type default)
			)
			(layer "F.Fab")
		)
		(fp_line
			(start -0.12065 -0.2794)
			(end 0.12065 -0.2794)
			(stroke
				(width 0.1)
				(type default)
			)
			(layer "F.Fab")
		)
		(fp_line
			(start 0.12065 -0.2794)
			(end 0.12065 -0.3048)
			(stroke
				(width 0.1)
				(type default)
			)
			(layer "F.Fab")
		)
		(fp_line
			(start 0.12065 -0.3048)
			(end 0.67945 -0.3048)
			(stroke
				(width 0.1)
				(type default)
			)
			(layer "F.Fab")
		)
		(fp_line
			(start 0.67945 -0.3048)
			(end 0.67945 0.3048)
			(stroke
				(width 0.1)
				(type default)
			)
			(layer "F.Fab")
		)
		(fp_line
			(start -0.67945 -0.305054)
			(end -0.12065 -0.305054)
			(stroke
				(width 0.1)
				(type default)
			)
			(layer "F.Fab")
		)
		(fp_line
			(start -0.12065 -0.305054)
			(end -0.12065 -0.2794)
			(stroke
				(width 0.1)
				(type default)
			)
			(layer "F.Fab")
		)
		(pad "1" smd circle
			(at -0.40005 0 270)
			(size 0 0)
			(layers "F.Cu" "F.Mask" "F.Paste")
			(net "GPU_PEX_STRAP1")
		)
		(pad "2" smd circle
			(at 0.40005 0 270)
			(size 0 0)
			(layers "F.Cu" "F.Mask" "F.Paste")
			(net "GPU_PEX_STRAP1_R")
		)
	)
	(footprint ""
		(layer "F.Cu")
		(at 166.859204 -56.819038 90)
		(property "Reference" "C1921"
			(at 0 0 90)
			(layer "F.SilkS")
			(hide yes)
			(effects
				(font
					(size 1.27 1.27)
				)
			)
		)
		(property "Value" ""
			(at 0 0 90)
			(layer "F.Fab")
			(effects
				(font
					(size 1.27 1.27)
				)
			)
		)
		(duplicate_pad_numbers_are_jumpers no)
		(fp_line
			(start 1.2954 -0.5842)
			(end 1.2954 0.5842)
			(stroke
				(width 0.1524)
				(type default)
			)
			(layer "F.SilkS")
		)
		(fp_line
			(start 0 -0.5842)
			(end 0 0.5842)
			(stroke
				(width 0.1524)
				(type default)
			)
			(layer "F.SilkS")
		)
		(fp_line
			(start -1.2954 -0.5842)
			(end 1.2954 -0.5842)
			(stroke
				(width 0.1524)
				(type default)
			)
			(layer "F.SilkS")
		)
		(fp_line
			(start 1.2954 0.5842)
			(end -1.2954 0.5842)
			(stroke
				(width 0.1524)
				(type default)
			)
			(layer "F.SilkS")
		)
		(fp_line
			(start -1.2954 0.5842)
			(end -1.2954 -0.5842)
			(stroke
				(width 0.1524)
				(type default)
			)
			(layer "F.SilkS")
		)
		(fp_line
			(start 0.8636 -0.4572)
			(end 0.8636 -0.4064)
			(stroke
				(width 0.1)
				(type default)
			)
			(layer "F.Fab")
		)
		(fp_line
			(start -0.8636 -0.4572)
			(end 0.8636 -0.4572)
			(stroke
				(width 0.1)
				(type default)
			)
			(layer "F.Fab")
		)
		(fp_line
			(start 1.1938 -0.4064)
			(end 1.1938 0.4064)
			(stroke
				(width 0.1)
				(type default)
			)
			(layer "F.Fab")
		)
		(fp_line
			(start 0.8636 -0.4064)
			(end 1.1938 -0.4064)
			(stroke
				(width 0.1)
				(type default)
			)
			(layer "F.Fab")
		)
		(fp_line
			(start -0.8636 -0.4064)
			(end -0.8636 -0.4572)
			(stroke
				(width 0.1)
				(type default)
			)
			(layer "F.Fab")
		)
		(fp_line
			(start -1.1938 -0.4064)
			(end -0.8636 -0.4064)
			(stroke
				(width 0.1)
				(type default)
			)
			(layer "F.Fab")
		)
		(fp_line
			(start 1.1938 0.4064)
			(end 0.8636 0.4064)
			(stroke
				(width 0.1)
				(type default)
			)
			(layer "F.Fab")
		)
		(fp_line
			(start 0.8636 0.4064)
			(end 0.8636 0.4572)
			(stroke
				(width 0.1)
				(type default)
			)
			(layer "F.Fab")
		)
		(fp_line
			(start -0.8636 0.4064)
			(end -1.1938 0.4064)
			(stroke
				(width 0.1)
				(type default)
			)
			(layer "F.Fab")
		)
		(fp_line
			(start -1.1938 0.4064)
			(end -1.1938 -0.4064)
			(stroke
				(width 0.1)
				(type default)
			)
			(layer "F.Fab")
		)
		(fp_line
			(start 0.8636 0.4572)
			(end -0.8636 0.4572)
			(stroke
				(width 0.1)
				(type default)
			)
			(layer "F.Fab")
		)
		(fp_line
			(start -0.8636 0.4572)
			(end -0.8636 0.4064)
			(stroke
				(width 0.1)
				(type default)
			)
			(layer "F.Fab")
		)
		(pad "1" smd rect
			(at -0.7366 0)
			(size 0.7112 0.8128)
			(layers "F.Cu" "F.Mask" "F.Paste")
			(net "P3V3_M2_0")
		)
		(pad "2" smd rect
			(at 0.7366 0)
			(size 0.7112 0.8128)
			(layers "F.Cu" "F.Mask" "F.Paste")
			(net "GND")
		)
	)
	(footprint ""
		(layer "F.Cu")
		(at 50.317654 -145.008854)
		(property "Reference" "PC1365"
			(at 0 0 0)
			(layer "F.SilkS")
			(hide yes)
			(effects
				(font
					(size 1.27 1.27)
				)
			)
		)
		(property "Value" ""
			(at 0 0 0)
			(layer "F.Fab")
			(effects
				(font
					(size 1.27 1.27)
				)
			)
		)
		(duplicate_pad_numbers_are_jumpers no)
		(fp_line
			(start -0.7874 -0.4064)
			(end 0.7874 -0.4064)
			(stroke
				(width 0.1524)
				(type default)
			)
			(layer "F.SilkS")
		)
		(fp_line
			(start -0.7874 0.4064)
			(end -0.7874 -0.4064)
			(stroke
				(width 0.1524)
				(type default)
			)
			(layer "F.SilkS")
		)
		(fp_line
			(start 0.7874 -0.4064)
			(end 0.7874 0.4064)
			(stroke
				(width 0.1524)
				(type default)
			)
			(layer "F.SilkS")
		)
		(fp_line
			(start 0.7874 0.4064)
			(end -0.7874 0.4064)
			(stroke
				(width 0.1524)
				(type default)
			)
			(layer "F.SilkS")
		)
		(fp_line
			(start -0.67945 -0.305054)
			(end -0.12065 -0.305054)
			(stroke
				(width 0.1)
				(type default)
			)
			(layer "F.Fab")
		)
		(fp_line
			(start -0.67945 0.3048)
			(end -0.67945 -0.305054)
			(stroke
				(width 0.1)
				(type default)
			)
			(layer "F.Fab")
		)
		(fp_line
			(start -0.12065 -0.305054)
			(end -0.12065 -0.2794)
			(stroke
				(width 0.1)
				(type default)
			)
			(layer "F.Fab")
		)
		(fp_line
			(start -0.12065 -0.2794)
			(end 0.12065 -0.2794)
			(stroke
				(width 0.1)
				(type default)
			)
			(layer "F.Fab")
		)
		(fp_line
			(start -0.12065 0.2794)
			(end -0.12065 0.3048)
			(stroke
				(width 0.1)
				(type default)
			)
			(layer "F.Fab")
		)
		(fp_line
			(start -0.12065 0.3048)
			(end -0.67945 0.3048)
			(stroke
				(width 0.1)
				(type default)
			)
			(layer "F.Fab")
		)
		(fp_line
			(start 0.120396 0.2794)
			(end -0.12065 0.2794)
			(stroke
				(width 0.1)
				(type default)
			)
			(layer "F.Fab")
		)
		(fp_line
			(start 0.120396 0.3048)
			(end 0.120396 0.2794)
			(stroke
				(width 0.1)
				(type default)
			)
			(layer "F.Fab")
		)
		(fp_line
			(start 0.12065 -0.3048)
			(end 0.67945 -0.3048)
			(stroke
				(width 0.1)
				(type default)
			)
			(layer "F.Fab")
		)
		(fp_line
			(start 0.12065 -0.2794)
			(end 0.12065 -0.3048)
			(stroke
				(width 0.1)
				(type default)
			)
			(layer "F.Fab")
		)
		(fp_line
			(start 0.67945 -0.3048)
			(end 0.67945 0.3048)
			(stroke
				(width 0.1)
				(type default)
			)
			(layer "F.Fab")
		)
		(fp_line
			(start 0.67945 0.3048)
			(end 0.120396 0.3048)
			(stroke
				(width 0.1)
				(type default)
			)
			(layer "F.Fab")
		)
		(pad "1" smd circle
			(at -0.40005 0)
			(size 0 0)
			(layers "F.Cu" "F.Mask" "F.Paste")
			(net "GND")
		)
		(pad "2" smd circle
			(at 0.40005 0)
			(size 0 0)
			(layers "F.Cu" "F.Mask" "F.Paste")
			(net "PVCCINFAON_CPU1_VREF")
		)
	)
	(footprint ""
		(layer "F.Cu")
		(at 189.65037 -425.287948)
		(property "Reference" "R3923"
			(at 0 0 0)
			(layer "F.SilkS")
			(hide yes)
			(effects
				(font
					(size 1.27 1.27)
				)
			)
		)
		(property "Value" ""
			(at 0 0 0)
			(layer "F.Fab")
			(effects
				(font
					(size 1.27 1.27)
				)
			)
		)
		(duplicate_pad_numbers_are_jumpers no)
		(fp_line
			(start -0.7874 -0.4064)
			(end 0.7874 -0.4064)
			(stroke
				(width 0.1524)
				(type default)
			)
			(layer "F.SilkS")
		)
		(fp_line
			(start -0.7874 0.4064)
			(end -0.7874 -0.4064)
			(stroke
				(width 0.1524)
				(type default)
			)
			(layer "F.SilkS")
		)
		(fp_line
			(start 0.7874 -0.4064)
			(end 0.7874 0.4064)
			(stroke
				(width 0.1524)
				(type default)
			)
			(layer "F.SilkS")
		)
		(fp_line
			(start 0.7874 0.4064)
			(end -0.7874 0.4064)
			(stroke
				(width 0.1524)
				(type default)
			)
			(layer "F.SilkS")
		)
		(fp_line
			(start -0.67945 -0.305054)
			(end -0.12065 -0.305054)
			(stroke
				(width 0.1)
				(type default)
			)
			(layer "F.Fab")
		)
		(fp_line
			(start -0.67945 0.3048)
			(end -0.67945 -0.305054)
			(stroke
				(width 0.1)
				(type default)
			)
			(layer "F.Fab")
		)
		(fp_line
			(start -0.12065 -0.305054)
			(end -0.12065 -0.2794)
			(stroke
				(width 0.1)
				(type default)
			)
			(layer "F.Fab")
		)
		(fp_line
			(start -0.12065 -0.2794)
			(end 0.12065 -0.2794)
			(stroke
				(width 0.1)
				(type default)
			)
			(layer "F.Fab")
		)
		(fp_line
			(start -0.12065 0.2794)
			(end -0.12065 0.3048)
			(stroke
				(width 0.1)
				(type default)
			)
			(layer "F.Fab")
		)
		(fp_line
			(start -0.12065 0.3048)
			(end -0.67945 0.3048)
			(stroke
				(width 0.1)
				(type default)
			)
			(layer "F.Fab")
		)
		(fp_line
			(start 0.120396 0.2794)
			(end -0.12065 0.2794)
			(stroke
				(width 0.1)
				(type default)
			)
			(layer "F.Fab")
		)
		(fp_line
			(start 0.120396 0.3048)
			(end 0.120396 0.2794)
			(stroke
				(width 0.1)
				(type default)
			)
			(layer "F.Fab")
		)
		(fp_line
			(start 0.12065 -0.3048)
			(end 0.67945 -0.3048)
			(stroke
				(width 0.1)
				(type default)
			)
			(layer "F.Fab")
		)
		(fp_line
			(start 0.12065 -0.2794)
			(end 0.12065 -0.3048)
			(stroke
				(width 0.1)
				(type default)
			)
			(layer "F.Fab")
		)
		(fp_line
			(start 0.67945 -0.3048)
			(end 0.67945 0.3048)
			(stroke
				(width 0.1)
				(type default)
			)
			(layer "F.Fab")
		)
		(fp_line
			(start 0.67945 0.3048)
			(end 0.120396 0.3048)
			(stroke
				(width 0.1)
				(type default)
			)
			(layer "F.Fab")
		)
		(pad "1" smd circle
			(at -0.40005 0)
			(size 0 0)
			(layers "F.Cu" "F.Mask" "F.Paste")
			(net "P12V_PSU_FUSE")
		)
		(pad "2" smd circle
			(at 0.40005 0)
			(size 0 0)
			(layers "F.Cu" "F.Mask" "F.Paste")
			(net "PDB_PRSNT_N")
		)
	)
	(footprint ""
		(layer "F.Cu")
		(at 355.8286 -401.955 180)
		(property "Reference" "C2373"
			(at 0 0 180)
			(layer "F.SilkS")
			(hide yes)
			(effects
				(font
					(size 1.27 1.27)
				)
			)
		)
		(property "Value" ""
			(at 0 0 180)
			(layer "F.Fab")
			(effects
				(font
					(size 1.27 1.27)
				)
			)
		)
		(duplicate_pad_numbers_are_jumpers no)
		(fp_line
			(start 0.7874 0.4064)
			(end -0.7874 0.4064)
			(stroke
				(width 0.1524)
				(type default)
			)
			(layer "F.SilkS")
		)
		(fp_line
			(start 0.7874 -0.4064)
			(end 0.7874 0.4064)
			(stroke
				(width 0.1524)
				(type default)
			)
			(layer "F.SilkS")
		)
		(fp_line
			(start -0.7874 0.4064)
			(end -0.7874 -0.4064)
			(stroke
				(width 0.1524)
				(type default)
			)
			(layer "F.SilkS")
		)
		(fp_line
			(start -0.7874 -0.4064)
			(end 0.7874 -0.4064)
			(stroke
				(width 0.1524)
				(type default)
			)
			(layer "F.SilkS")
		)
		(fp_line
			(start 0.67945 0.3048)
			(end 0.120396 0.3048)
			(stroke
				(width 0.1)
				(type default)
			)
			(layer "F.Fab")
		)
		(fp_line
			(start 0.67945 -0.3048)
			(end 0.67945 0.3048)
			(stroke
				(width 0.1)
				(type default)
			)
			(layer "F.Fab")
		)
		(fp_line
			(start 0.12065 -0.2794)
			(end 0.12065 -0.3048)
			(stroke
				(width 0.1)
				(type default)
			)
			(layer "F.Fab")
		)
		(fp_line
			(start 0.12065 -0.3048)
			(end 0.67945 -0.3048)
			(stroke
				(width 0.1)
				(type default)
			)
			(layer "F.Fab")
		)
		(fp_line
			(start 0.120396 0.3048)
			(end 0.120396 0.2794)
			(stroke
				(width 0.1)
				(type default)
			)
			(layer "F.Fab")
		)
		(fp_line
			(start 0.120396 0.2794)
			(end -0.12065 0.2794)
			(stroke
				(width 0.1)
				(type default)
			)
			(layer "F.Fab")
		)
		(fp_line
			(start -0.12065 0.3048)
			(end -0.67945 0.3048)
			(stroke
				(width 0.1)
				(type default)
			)
			(layer "F.Fab")
		)
		(fp_line
			(start -0.12065 0.2794)
			(end -0.12065 0.3048)
			(stroke
				(width 0.1)
				(type default)
			)
			(layer "F.Fab")
		)
		(fp_line
			(start -0.12065 -0.2794)
			(end 0.12065 -0.2794)
			(stroke
				(width 0.1)
				(type default)
			)
			(layer "F.Fab")
		)
		(fp_line
			(start -0.12065 -0.305054)
			(end -0.12065 -0.2794)
			(stroke
				(width 0.1)
				(type default)
			)
			(layer "F.Fab")
		)
		(fp_line
			(start -0.67945 0.3048)
			(end -0.67945 -0.305054)
			(stroke
				(width 0.1)
				(type default)
			)
			(layer "F.Fab")
		)
		(fp_line
			(start -0.67945 -0.305054)
			(end -0.12065 -0.305054)
			(stroke
				(width 0.1)
				(type default)
			)
			(layer "F.Fab")
		)
		(pad "1" smd circle
			(at -0.40005 0 180)
			(size 0 0)
			(layers "F.Cu" "F.Mask" "F.Paste")
			(net "PRSNT_CABLE_SWB_B2_ISO_N")
		)
		(pad "2" smd circle
			(at 0.40005 0 180)
			(size 0 0)
			(layers "F.Cu" "F.Mask" "F.Paste")
			(net "GND")
		)
	)
	(footprint ""
		(layer "F.Cu")
		(at 19.119596 -393.215876 90)
		(property "Reference" "C1865"
			(at 0 0 90)
			(layer "F.SilkS")
			(hide yes)
			(effects
				(font
					(size 1.27 1.27)
				)
			)
		)
		(property "Value" ""
			(at 0 0 90)
			(layer "F.Fab")
			(effects
				(font
					(size 1.27 1.27)
				)
			)
		)
		(duplicate_pad_numbers_are_jumpers no)
		(fp_line
			(start 0.7874 -0.4064)
			(end 0.7874 0.4064)
			(stroke
				(width 0.1524)
				(type default)
			)
			(layer "F.SilkS")
		)
		(fp_line
			(start -0.7874 -0.4064)
			(end 0.7874 -0.4064)
			(stroke
				(width 0.1524)
				(type default)
			)
			(layer "F.SilkS")
		)
		(fp_line
			(start 0.7874 0.4064)
			(end -0.7874 0.4064)
			(stroke
				(width 0.1524)
				(type default)
			)
			(layer "F.SilkS")
		)
		(fp_line
			(start -0.7874 0.4064)
			(end -0.7874 -0.4064)
			(stroke
				(width 0.1524)
				(type default)
			)
			(layer "F.SilkS")
		)
		(fp_line
			(start -0.12065 -0.305054)
			(end -0.12065 -0.2794)
			(stroke
				(width 0.1)
				(type default)
			)
			(layer "F.Fab")
		)
		(fp_line
			(start -0.67945 -0.305054)
			(end -0.12065 -0.305054)
			(stroke
				(width 0.1)
				(type default)
			)
			(layer "F.Fab")
		)
		(fp_line
			(start 0.67945 -0.3048)
			(end 0.67945 0.3048)
			(stroke
				(width 0.1)
				(type default)
			)
			(layer "F.Fab")
		)
		(fp_line
			(start 0.12065 -0.3048)
			(end 0.67945 -0.3048)
			(stroke
				(width 0.1)
				(type default)
			)
			(layer "F.Fab")
		)
		(fp_line
			(start 0.12065 -0.2794)
			(end 0.12065 -0.3048)
			(stroke
				(width 0.1)
				(type default)
			)
			(layer "F.Fab")
		)
		(fp_line
			(start -0.12065 -0.2794)
			(end 0.12065 -0.2794)
			(stroke
				(width 0.1)
				(type default)
			)
			(layer "F.Fab")
		)
		(fp_line
			(start 0.120396 0.2794)
			(end -0.12065 0.2794)
			(stroke
				(width 0.1)
				(type default)
			)
			(layer "F.Fab")
		)
		(fp_line
			(start -0.12065 0.2794)
			(end -0.12065 0.3048)
			(stroke
				(width 0.1)
				(type default)
			)
			(layer "F.Fab")
		)
		(fp_line
			(start 0.67945 0.3048)
			(end 0.120396 0.3048)
			(stroke
				(width 0.1)
				(type default)
			)
			(layer "F.Fab")
		)
		(fp_line
			(start 0.120396 0.3048)
			(end 0.120396 0.2794)
			(stroke
				(width 0.1)
				(type default)
			)
			(layer "F.Fab")
		)
		(fp_line
			(start -0.12065 0.3048)
			(end -0.67945 0.3048)
			(stroke
				(width 0.1)
				(type default)
			)
			(layer "F.Fab")
		)
		(fp_line
			(start -0.67945 0.3048)
			(end -0.67945 -0.305054)
			(stroke
				(width 0.1)
				(type default)
			)
			(layer "F.Fab")
		)
		(pad "1" smd circle
			(at -0.40005 0 90)
			(size 0 0)
			(layers "F.Cu" "F.Mask" "F.Paste")
			(net "P3V3_AUX")
		)
		(pad "2" smd circle
			(at 0.40005 0 90)
			(size 0 0)
			(layers "F.Cu" "F.Mask" "F.Paste")
			(net "GND")
		)
	)
	(footprint ""
		(layer "F.Cu")
		(at 142.0622 -104.116378 -90)
		(property "Reference" "R4038"
			(at 0 0 270)
			(layer "F.SilkS")
			(hide yes)
			(effects
				(font
					(size 1.27 1.27)
				)
			)
		)
		(property "Value" ""
			(at 0 0 270)
			(layer "F.Fab")
			(effects
				(font
					(size 1.27 1.27)
				)
			)
		)
		(duplicate_pad_numbers_are_jumpers no)
		(fp_line
			(start -0.7874 0.4064)
			(end -0.7874 -0.4064)
			(stroke
				(width 0.1524)
				(type default)
			)
			(layer "F.SilkS")
		)
		(fp_line
			(start 0.7874 0.4064)
			(end -0.7874 0.4064)
			(stroke
				(width 0.1524)
				(type default)
			)
			(layer "F.SilkS")
		)
		(fp_line
			(start -0.7874 -0.4064)
			(end 0.7874 -0.4064)
			(stroke
				(width 0.1524)
				(type default)
			)
			(layer "F.SilkS")
		)
		(fp_line
			(start 0.7874 -0.4064)
			(end 0.7874 0.4064)
			(stroke
				(width 0.1524)
				(type default)
			)
			(layer "F.SilkS")
		)
		(fp_line
			(start -0.67945 0.3048)
			(end -0.67945 -0.305054)
			(stroke
				(width 0.1)
				(type default)
			)
			(layer "F.Fab")
		)
		(fp_line
			(start -0.12065 0.3048)
			(end -0.67945 0.3048)
			(stroke
				(width 0.1)
				(type default)
			)
			(layer "F.Fab")
		)
		(fp_line
			(start 0.120396 0.3048)
			(end 0.120396 0.2794)
			(stroke
				(width 0.1)
				(type default)
			)
			(layer "F.Fab")
		)
		(fp_line
			(start 0.67945 0.3048)
			(end 0.120396 0.3048)
			(stroke
				(width 0.1)
				(type default)
			)
			(layer "F.Fab")
		)
		(fp_line
			(start -0.12065 0.2794)
			(end -0.12065 0.3048)
			(stroke
				(width 0.1)
				(type default)
			)
			(layer "F.Fab")
		)
		(fp_line
			(start 0.120396 0.2794)
			(end -0.12065 0.2794)
			(stroke
				(width 0.1)
				(type default)
			)
			(layer "F.Fab")
		)
		(fp_line
			(start -0.12065 -0.2794)
			(end 0.12065 -0.2794)
			(stroke
				(width 0.1)
				(type default)
			)
			(layer "F.Fab")
		)
		(fp_line
			(start 0.12065 -0.2794)
			(end 0.12065 -0.3048)
			(stroke
				(width 0.1)
				(type default)
			)
			(layer "F.Fab")
		)
		(fp_line
			(start 0.12065 -0.3048)
			(end 0.67945 -0.3048)
			(stroke
				(width 0.1)
				(type default)
			)
			(layer "F.Fab")
		)
		(fp_line
			(start 0.67945 -0.3048)
			(end 0.67945 0.3048)
			(stroke
				(width 0.1)
				(type default)
			)
			(layer "F.Fab")
		)
		(fp_line
			(start -0.67945 -0.305054)
			(end -0.12065 -0.305054)
			(stroke
				(width 0.1)
				(type default)
			)
			(layer "F.Fab")
		)
		(fp_line
			(start -0.12065 -0.305054)
			(end -0.12065 -0.2794)
			(stroke
				(width 0.1)
				(type default)
			)
			(layer "F.Fab")
		)
		(pad "1" smd circle
			(at -0.40005 0 270)
			(size 0 0)
			(layers "F.Cu" "F.Mask" "F.Paste")
			(net "P3V3")
		)
		(pad "2" smd circle
			(at 0.40005 0 270)
			(size 0 0)
			(layers "F.Cu" "F.Mask" "F.Paste")
			(net "P0V62_CPU0_ERRS_U306_VREF")
		)
	)
	(footprint ""
		(layer "F.Cu")
		(at 61.26988 -16.220948 -90)
		(property "Reference" "R3171"
			(at 0 0 270)
			(layer "F.SilkS")
			(hide yes)
			(effects
				(font
					(size 1.27 1.27)
				)
			)
		)
		(property "Value" ""
			(at 0 0 270)
			(layer "F.Fab")
			(effects
				(font
					(size 1.27 1.27)
				)
			)
		)
		(duplicate_pad_numbers_are_jumpers no)
		(fp_line
			(start -0.7874 0.4064)
			(end -0.7874 -0.4064)
			(stroke
				(width 0.1524)
				(type default)
			)
			(layer "F.SilkS")
		)
		(fp_line
			(start 0.7874 0.4064)
			(end -0.7874 0.4064)
			(stroke
				(width 0.1524)
				(type default)
			)
			(layer "F.SilkS")
		)
		(fp_line
			(start -0.7874 -0.4064)
			(end 0.7874 -0.4064)
			(stroke
				(width 0.1524)
				(type default)
			)
			(layer "F.SilkS")
		)
		(fp_line
			(start 0.7874 -0.4064)
			(end 0.7874 0.4064)
			(stroke
				(width 0.1524)
				(type default)
			)
			(layer "F.SilkS")
		)
		(fp_line
			(start -0.67945 0.3048)
			(end -0.67945 -0.305054)
			(stroke
				(width 0.1)
				(type default)
			)
			(layer "F.Fab")
		)
		(fp_line
			(start -0.12065 0.3048)
			(end -0.67945 0.3048)
			(stroke
				(width 0.1)
				(type default)
			)
			(layer "F.Fab")
		)
		(fp_line
			(start 0.120396 0.3048)
			(end 0.120396 0.2794)
			(stroke
				(width 0.1)
				(type default)
			)
			(layer "F.Fab")
		)
		(fp_line
			(start 0.67945 0.3048)
			(end 0.120396 0.3048)
			(stroke
				(width 0.1)
				(type default)
			)
			(layer "F.Fab")
		)
		(fp_line
			(start -0.12065 0.2794)
			(end -0.12065 0.3048)
			(stroke
				(width 0.1)
				(type default)
			)
			(layer "F.Fab")
		)
		(fp_line
			(start 0.120396 0.2794)
			(end -0.12065 0.2794)
			(stroke
				(width 0.1)
				(type default)
			)
			(layer "F.Fab")
		)
		(fp_line
			(start -0.12065 -0.2794)
			(end 0.12065 -0.2794)
			(stroke
				(width 0.1)
				(type default)
			)
			(layer "F.Fab")
		)
		(fp_line
			(start 0.12065 -0.2794)
			(end 0.12065 -0.3048)
			(stroke
				(width 0.1)
				(type default)
			)
			(layer "F.Fab")
		)
		(fp_line
			(start 0.12065 -0.3048)
			(end 0.67945 -0.3048)
			(stroke
				(width 0.1)
				(type default)
			)
			(layer "F.Fab")
		)
		(fp_line
			(start 0.67945 -0.3048)
			(end 0.67945 0.3048)
			(stroke
				(width 0.1)
				(type default)
			)
			(layer "F.Fab")
		)
		(fp_line
			(start -0.67945 -0.305054)
			(end -0.12065 -0.305054)
			(stroke
				(width 0.1)
				(type default)
			)
			(layer "F.Fab")
		)
		(fp_line
			(start -0.12065 -0.305054)
			(end -0.12065 -0.2794)
			(stroke
				(width 0.1)
				(type default)
			)
			(layer "F.Fab")
		)
		(pad "1" smd circle
			(at -0.40005 0 270)
			(size 0 0)
			(layers "F.Cu" "F.Mask" "F.Paste")
			(net "OCP_V3_2_ISO_BIF2_EN")
		)
		(pad "2" smd circle
			(at 0.40005 0 270)
			(size 0 0)
			(layers "F.Cu" "F.Mask" "F.Paste")
			(net "OCP_V3_2_BIF2_R_N")
		)
	)
	(footprint ""
		(layer "F.Cu")
		(at 77.55001 -24.713946 -90)
		(property "Reference" "PR3830"
			(at 0 0 270)
			(layer "F.SilkS")
			(hide yes)
			(effects
				(font
					(size 1.27 1.27)
				)
			)
		)
		(property "Value" ""
			(at 0 0 270)
			(layer "F.Fab")
			(effects
				(font
					(size 1.27 1.27)
				)
			)
		)
		(duplicate_pad_numbers_are_jumpers no)
		(fp_line
			(start -0.7874 0.4064)
			(end -0.7874 -0.4064)
			(stroke
				(width 0.1524)
				(type default)
			)
			(layer "F.SilkS")
		)
		(fp_line
			(start 0.7874 0.4064)
			(end -0.7874 0.4064)
			(stroke
				(width 0.1524)
				(type default)
			)
			(layer "F.SilkS")
		)
		(fp_line
			(start -0.7874 -0.4064)
			(end 0.7874 -0.4064)
			(stroke
				(width 0.1524)
				(type default)
			)
			(layer "F.SilkS")
		)
		(fp_line
			(start 0.7874 -0.4064)
			(end 0.7874 0.4064)
			(stroke
				(width 0.1524)
				(type default)
			)
			(layer "F.SilkS")
		)
		(fp_line
			(start -0.67945 0.3048)
			(end -0.67945 -0.305054)
			(stroke
				(width 0.1)
				(type default)
			)
			(layer "F.Fab")
		)
		(fp_line
			(start -0.12065 0.3048)
			(end -0.67945 0.3048)
			(stroke
				(width 0.1)
				(type default)
			)
			(layer "F.Fab")
		)
		(fp_line
			(start 0.120396 0.3048)
			(end 0.120396 0.2794)
			(stroke
				(width 0.1)
				(type default)
			)
			(layer "F.Fab")
		)
		(fp_line
			(start 0.67945 0.3048)
			(end 0.120396 0.3048)
			(stroke
				(width 0.1)
				(type default)
			)
			(layer "F.Fab")
		)
		(fp_line
			(start -0.12065 0.2794)
			(end -0.12065 0.3048)
			(stroke
				(width 0.1)
				(type default)
			)
			(layer "F.Fab")
		)
		(fp_line
			(start 0.120396 0.2794)
			(end -0.12065 0.2794)
			(stroke
				(width 0.1)
				(type default)
			)
			(layer "F.Fab")
		)
		(fp_line
			(start -0.12065 -0.2794)
			(end 0.12065 -0.2794)
			(stroke
				(width 0.1)
				(type default)
			)
			(layer "F.Fab")
		)
		(fp_line
			(start 0.12065 -0.2794)
			(end 0.12065 -0.3048)
			(stroke
				(width 0.1)
				(type default)
			)
			(layer "F.Fab")
		)
		(fp_line
			(start 0.12065 -0.3048)
			(end 0.67945 -0.3048)
			(stroke
				(width 0.1)
				(type default)
			)
			(layer "F.Fab")
		)
		(fp_line
			(start 0.67945 -0.3048)
			(end 0.67945 0.3048)
			(stroke
				(width 0.1)
				(type default)
			)
			(layer "F.Fab")
		)
		(fp_line
			(start -0.67945 -0.305054)
			(end -0.12065 -0.305054)
			(stroke
				(width 0.1)
				(type default)
			)
			(layer "F.Fab")
		)
		(fp_line
			(start -0.12065 -0.305054)
			(end -0.12065 -0.2794)
			(stroke
				(width 0.1)
				(type default)
			)
			(layer "F.Fab")
		)
		(pad "1" smd circle
			(at -0.40005 0 270)
			(size 0 0)
			(layers "F.Cu" "F.Mask" "F.Paste")
			(net "P12V_AUX")
		)
		(pad "2" smd circle
			(at 0.40005 0 270)
			(size 0 0)
			(layers "F.Cu" "F.Mask" "F.Paste")
			(net "P12V_OCP_VCC_2")
		)
	)
	(footprint ""
		(layer "F.Cu")
		(at 260.731508 -4.696206)
		(property "Reference" "J75"
			(at -4.164838 1.013206 90)
			(unlocked yes)
			(layer "F.SilkS")
			(effects
				(font
					(size 0.7874 0.5842)
					(thickness 0.1524)
				)
				(justify left)
			)
		)
		(property "Value" ""
			(at 0 0 0)
			(layer "F.Fab")
			(effects
				(font
					(size 1.27 1.27)
				)
			)
		)
		(duplicate_pad_numbers_are_jumpers no)
		(fp_line
			(start -1.2192 -2.1082)
			(end 1.2192 -2.1082)
			(stroke
				(width 0.1524)
				(type default)
			)
			(layer "F.SilkS")
		)
		(fp_line
			(start -1.2192 2.1082)
			(end -1.2192 -2.1082)
			(stroke
				(width 0.1524)
				(type default)
			)
			(layer "F.SilkS")
		)
		(fp_line
			(start 1.2192 -2.1082)
			(end 1.2192 2.1082)
			(stroke
				(width 0.1524)
				(type default)
			)
			(layer "F.SilkS")
		)
		(fp_line
			(start 1.2192 2.1082)
			(end -1.2192 2.1082)
			(stroke
				(width 0.1524)
				(type default)
			)
			(layer "F.SilkS")
		)
		(pad "" np_thru_hole circle
			(at -2.8829 -1.27 270)
			(size 1.0414 1.0414)
			(drill 1.0414)
			(layers "*.Cu" "*.Mask")
			(clearance 0.381)
			(thermal_gap 0.381)
		)
		(pad "" np_thru_hole circle
			(at -2.8829 1.27 270)
			(size 1.0414 1.0414)
			(drill 1.0414)
			(layers "*.Cu" "*.Mask")
			(clearance 0.381)
			(thermal_gap 0.381)
		)
		(pad "" np_thru_hole circle
			(at 3.4671 -1.27 270)
			(size 1.0414 1.0414)
			(drill 1.0414)
			(layers "*.Cu" "*.Mask")
			(clearance 0.381)
			(thermal_gap 0.381)
		)
		(pad "" np_thru_hole circle
			(at 3.4671 1.27 270)
			(size 1.0414 1.0414)
			(drill 1.0414)
			(layers "*.Cu" "*.Mask")
			(clearance 0.381)
			(thermal_gap 0.381)
		)
		(pad "1" smd rect
			(at 0.8255 -0.249936 270)
			(size 0.3048 0.508)
			(layers "F.Cu" "F.Mask" "F.Paste")
			(net "DELTA_L_85_10INCH_TOP_DP")
		)
		(pad "2" smd rect
			(at 0.8255 0.249936 270)
			(size 0.3048 0.508)
			(layers "F.Cu" "F.Mask" "F.Paste")
			(net "DELTA_L_85_10INCH_TOP_DN")
		)
		(pad "3" smd circle
			(at 0 0)
			(size 0 0)
			(layers "F.Cu" "F.Mask" "F.Paste")
			(net "DELTA_L_GND_1")
		)
		(zone
			(layer "F.Cu")
			(hatch none 0.5)
			(connect_pads
				(clearance 0)
			)
			(min_thickness 0.25)
			(keepout
				(tracks not_allowed)
				(vias allowed)
				(pads allowed)
				(copperpour not_allowed)
				(footprints allowed)
			)
			(placement
				(enabled no)
				(sheetname "")
			)
			(fill
				(thermal_gap 0.5)
				(thermal_bridge_width 0.5)
				(island_removal_mode 0)
			)
			(polygon
				(pts
					(xy 261.849108 -5.244846) (xy 261.849108 -5.149342) (xy 261.252208 -5.149342) (xy 261.252208 -4.742942)
					(xy 261.849108 -4.742942) (xy 261.849108 -4.64947) (xy 261.252208 -4.64947) (xy 261.252208 -4.24307)
					(xy 261.849108 -4.24307) (xy 261.849108 -4.147566) (xy 261.150608 -4.147566) (xy 261.150608 -5.244846)
				)
			)
		)
		(zone
			(layers "F.Cu" "B.Cu" "In1.Cu" "In2.Cu" "In3.Cu" "In4.Cu" "In5.Cu" "In6.Cu"
				"In7.Cu" "In8.Cu" "In9.Cu" "In10.Cu" "In11.Cu" "In12.Cu" "In13.Cu" "In14.Cu"
				"In15.Cu" "In16.Cu"
			)
			(hatch none 0.5)
			(connect_pads
				(clearance 0)
			)
			(min_thickness 0.25)
			(keepout
				(tracks not_allowed)
				(vias allowed)
				(pads allowed)
				(copperpour not_allowed)
				(footprints allowed)
			)
			(placement
				(enabled no)
				(sheetname "")
			)
			(fill
				(thermal_gap 0.5)
				(thermal_bridge_width 0.5)
				(island_removal_mode 0)
			)
			(polygon
				(pts
					(arc
						(start 258.775708 -5.966206)
						(mid 256.921508 -5.966206)
						(end 258.775708 -5.966206)
					)
				)
			)
		)
		(zone
			(layers "F.Cu" "B.Cu" "In1.Cu" "In2.Cu" "In3.Cu" "In4.Cu" "In5.Cu" "In6.Cu"
				"In7.Cu" "In8.Cu" "In9.Cu" "In10.Cu" "In11.Cu" "In12.Cu" "In13.Cu" "In14.Cu"
				"In15.Cu" "In16.Cu"
			)
			(hatch none 0.5)
			(connect_pads
				(clearance 0)
			)
			(min_thickness 0.25)
			(keepout
				(tracks not_allowed)
				(vias allowed)
				(pads allowed)
				(copperpour not_allowed)
				(footprints allowed)
			)
			(placement
				(enabled no)
				(sheetname "")
			)
			(fill
				(thermal_gap 0.5)
				(thermal_bridge_width 0.5)
				(island_removal_mode 0)
			)
			(polygon
				(pts
					(arc
						(start 258.775708 -3.426206)
						(mid 256.921508 -3.426206)
						(end 258.775708 -3.426206)
					)
				)
			)
		)
		(zone
			(layers "F.Cu" "B.Cu" "In1.Cu" "In2.Cu" "In3.Cu" "In4.Cu" "In5.Cu" "In6.Cu"
				"In7.Cu" "In8.Cu" "In9.Cu" "In10.Cu" "In11.Cu" "In12.Cu" "In13.Cu" "In14.Cu"
				"In15.Cu" "In16.Cu"
			)
			(hatch none 0.5)
			(connect_pads
				(clearance 0)
			)
			(min_thickness 0.25)
			(keepout
				(tracks not_allowed)
				(vias allowed)
				(pads allowed)
				(copperpour not_allowed)
				(footprints allowed)
			)
			(placement
				(enabled no)
				(sheetname "")
			)
			(fill
				(thermal_gap 0.5)
				(thermal_bridge_width 0.5)
				(island_removal_mode 0)
			)
			(polygon
				(pts
					(arc
						(start 265.125708 -5.966206)
						(mid 263.271508 -5.966206)
						(end 265.125708 -5.966206)
					)
				)
			)
		)
		(zone
			(layers "F.Cu" "B.Cu" "In1.Cu" "In2.Cu" "In3.Cu" "In4.Cu" "In5.Cu" "In6.Cu"
				"In7.Cu" "In8.Cu" "In9.Cu" "In10.Cu" "In11.Cu" "In12.Cu" "In13.Cu" "In14.Cu"
				"In15.Cu" "In16.Cu"
			)
			(hatch none 0.5)
			(connect_pads
				(clearance 0)
			)
			(min_thickness 0.25)
			(keepout
				(tracks not_allowed)
				(vias allowed)
				(pads allowed)
				(copperpour not_allowed)
				(footprints allowed)
			)
			(placement
				(enabled no)
				(sheetname "")
			)
			(fill
				(thermal_gap 0.5)
				(thermal_bridge_width 0.5)
				(island_removal_mode 0)
			)
			(polygon
				(pts
					(arc
						(start 265.125708 -3.426206)
						(mid 263.271508 -3.426206)
						(end 265.125708 -3.426206)
					)
				)
			)
		)
	)
	(footprint ""
		(layer "F.Cu")
		(at 282.452826 -19.699986 180)
		(property "Reference" "R3182"
			(at 0 0 180)
			(layer "F.SilkS")
			(hide yes)
			(effects
				(font
					(size 1.27 1.27)
				)
			)
		)
		(property "Value" ""
			(at 0 0 180)
			(layer "F.Fab")
			(effects
				(font
					(size 1.27 1.27)
				)
			)
		)
		(duplicate_pad_numbers_are_jumpers no)
		(fp_line
			(start 0.7874 0.4064)
			(end -0.7874 0.4064)
			(stroke
				(width 0.1524)
				(type default)
			)
			(layer "F.SilkS")
		)
		(fp_line
			(start 0.7874 -0.4064)
			(end 0.7874 0.4064)
			(stroke
				(width 0.1524)
				(type default)
			)
			(layer "F.SilkS")
		)
		(fp_line
			(start -0.7874 0.4064)
			(end -0.7874 -0.4064)
			(stroke
				(width 0.1524)
				(type default)
			)
			(layer "F.SilkS")
		)
		(fp_line
			(start -0.7874 -0.4064)
			(end 0.7874 -0.4064)
			(stroke
				(width 0.1524)
				(type default)
			)
			(layer "F.SilkS")
		)
		(fp_line
			(start 0.67945 0.3048)
			(end 0.120396 0.3048)
			(stroke
				(width 0.1)
				(type default)
			)
			(layer "F.Fab")
		)
		(fp_line
			(start 0.67945 -0.3048)
			(end 0.67945 0.3048)
			(stroke
				(width 0.1)
				(type default)
			)
			(layer "F.Fab")
		)
		(fp_line
			(start 0.12065 -0.2794)
			(end 0.12065 -0.3048)
			(stroke
				(width 0.1)
				(type default)
			)
			(layer "F.Fab")
		)
		(fp_line
			(start 0.12065 -0.3048)
			(end 0.67945 -0.3048)
			(stroke
				(width 0.1)
				(type default)
			)
			(layer "F.Fab")
		)
		(fp_line
			(start 0.120396 0.3048)
			(end 0.120396 0.2794)
			(stroke
				(width 0.1)
				(type default)
			)
			(layer "F.Fab")
		)
		(fp_line
			(start 0.120396 0.2794)
			(end -0.12065 0.2794)
			(stroke
				(width 0.1)
				(type default)
			)
			(layer "F.Fab")
		)
		(fp_line
			(start -0.12065 0.3048)
			(end -0.67945 0.3048)
			(stroke
				(width 0.1)
				(type default)
			)
			(layer "F.Fab")
		)
		(fp_line
			(start -0.12065 0.2794)
			(end -0.12065 0.3048)
			(stroke
				(width 0.1)
				(type default)
			)
			(layer "F.Fab")
		)
		(fp_line
			(start -0.12065 -0.2794)
			(end 0.12065 -0.2794)
			(stroke
				(width 0.1)
				(type default)
			)
			(layer "F.Fab")
		)
		(fp_line
			(start -0.12065 -0.305054)
			(end -0.12065 -0.2794)
			(stroke
				(width 0.1)
				(type default)
			)
			(layer "F.Fab")
		)
		(fp_line
			(start -0.67945 0.3048)
			(end -0.67945 -0.305054)
			(stroke
				(width 0.1)
				(type default)
			)
			(layer "F.Fab")
		)
		(fp_line
			(start -0.67945 -0.305054)
			(end -0.12065 -0.305054)
			(stroke
				(width 0.1)
				(type default)
			)
			(layer "F.Fab")
		)
		(pad "1" smd circle
			(at -0.40005 0 180)
			(size 0 0)
			(layers "F.Cu" "F.Mask" "F.Paste")
			(net "P3V3_OCP_V3_2")
		)
		(pad "2" smd circle
			(at 0.40005 0 180)
			(size 0 0)
			(layers "F.Cu" "F.Mask" "F.Paste")
			(net "IRQ_LVC3_OCP_V3_2_WAKE_N")
		)
	)
	(footprint ""
		(layer "F.Cu")
		(at 193.93408 -355.996748 180)
		(property "Reference" "R1004"
			(at 0 0 180)
			(layer "F.SilkS")
			(hide yes)
			(effects
				(font
					(size 1.27 1.27)
				)
			)
		)
		(property "Value" ""
			(at 0 0 180)
			(layer "F.Fab")
			(effects
				(font
					(size 1.27 1.27)
				)
			)
		)
		(duplicate_pad_numbers_are_jumpers no)
		(fp_line
			(start 0.7874 0.4064)
			(end -0.7874 0.4064)
			(stroke
				(width 0.1524)
				(type default)
			)
			(layer "F.SilkS")
		)
		(fp_line
			(start 0.7874 -0.4064)
			(end 0.7874 0.4064)
			(stroke
				(width 0.1524)
				(type default)
			)
			(layer "F.SilkS")
		)
		(fp_line
			(start -0.7874 0.4064)
			(end -0.7874 -0.4064)
			(stroke
				(width 0.1524)
				(type default)
			)
			(layer "F.SilkS")
		)
		(fp_line
			(start -0.7874 -0.4064)
			(end 0.7874 -0.4064)
			(stroke
				(width 0.1524)
				(type default)
			)
			(layer "F.SilkS")
		)
		(fp_line
			(start 0.67945 0.3048)
			(end 0.120396 0.3048)
			(stroke
				(width 0.1)
				(type default)
			)
			(layer "F.Fab")
		)
		(fp_line
			(start 0.67945 -0.3048)
			(end 0.67945 0.3048)
			(stroke
				(width 0.1)
				(type default)
			)
			(layer "F.Fab")
		)
		(fp_line
			(start 0.12065 -0.2794)
			(end 0.12065 -0.3048)
			(stroke
				(width 0.1)
				(type default)
			)
			(layer "F.Fab")
		)
		(fp_line
			(start 0.12065 -0.3048)
			(end 0.67945 -0.3048)
			(stroke
				(width 0.1)
				(type default)
			)
			(layer "F.Fab")
		)
		(fp_line
			(start 0.120396 0.3048)
			(end 0.120396 0.2794)
			(stroke
				(width 0.1)
				(type default)
			)
			(layer "F.Fab")
		)
		(fp_line
			(start 0.120396 0.2794)
			(end -0.12065 0.2794)
			(stroke
				(width 0.1)
				(type default)
			)
			(layer "F.Fab")
		)
		(fp_line
			(start -0.12065 0.3048)
			(end -0.67945 0.3048)
			(stroke
				(width 0.1)
				(type default)
			)
			(layer "F.Fab")
		)
		(fp_line
			(start -0.12065 0.2794)
			(end -0.12065 0.3048)
			(stroke
				(width 0.1)
				(type default)
			)
			(layer "F.Fab")
		)
		(fp_line
			(start -0.12065 -0.2794)
			(end 0.12065 -0.2794)
			(stroke
				(width 0.1)
				(type default)
			)
			(layer "F.Fab")
		)
		(fp_line
			(start -0.12065 -0.305054)
			(end -0.12065 -0.2794)
			(stroke
				(width 0.1)
				(type default)
			)
			(layer "F.Fab")
		)
		(fp_line
			(start -0.67945 0.3048)
			(end -0.67945 -0.305054)
			(stroke
				(width 0.1)
				(type default)
			)
			(layer "F.Fab")
		)
		(fp_line
			(start -0.67945 -0.305054)
			(end -0.12065 -0.305054)
			(stroke
				(width 0.1)
				(type default)
			)
			(layer "F.Fab")
		)
		(pad "1" smd circle
			(at -0.40005 0 180)
			(size 0 0)
			(layers "F.Cu" "F.Mask" "F.Paste")
			(net "P3V3_AUX")
		)
		(pad "2" smd circle
			(at 0.40005 0 180)
			(size 0 0)
			(layers "F.Cu" "F.Mask" "F.Paste")
			(net "PU_PIROM_CPU1_SM_WP")
		)
	)
	(footprint ""
		(layer "F.Cu")
		(at 39.194232 -131.897374 180)
		(property "Reference" "R2354"
			(at 0 0 180)
			(layer "F.SilkS")
			(hide yes)
			(effects
				(font
					(size 1.27 1.27)
				)
			)
		)
		(property "Value" ""
			(at 0 0 180)
			(layer "F.Fab")
			(effects
				(font
					(size 1.27 1.27)
				)
			)
		)
		(duplicate_pad_numbers_are_jumpers no)
		(fp_line
			(start 0.7874 0.4064)
			(end -0.7874 0.4064)
			(stroke
				(width 0.1524)
				(type default)
			)
			(layer "F.SilkS")
		)
		(fp_line
			(start 0.7874 -0.4064)
			(end 0.7874 0.4064)
			(stroke
				(width 0.1524)
				(type default)
			)
			(layer "F.SilkS")
		)
		(fp_line
			(start -0.7874 0.4064)
			(end -0.7874 -0.4064)
			(stroke
				(width 0.1524)
				(type default)
			)
			(layer "F.SilkS")
		)
		(fp_line
			(start -0.7874 -0.4064)
			(end 0.7874 -0.4064)
			(stroke
				(width 0.1524)
				(type default)
			)
			(layer "F.SilkS")
		)
		(fp_line
			(start 0.67945 0.3048)
			(end 0.120396 0.3048)
			(stroke
				(width 0.1)
				(type default)
			)
			(layer "F.Fab")
		)
		(fp_line
			(start 0.67945 -0.3048)
			(end 0.67945 0.3048)
			(stroke
				(width 0.1)
				(type default)
			)
			(layer "F.Fab")
		)
		(fp_line
			(start 0.12065 -0.2794)
			(end 0.12065 -0.3048)
			(stroke
				(width 0.1)
				(type default)
			)
			(layer "F.Fab")
		)
		(fp_line
			(start 0.12065 -0.3048)
			(end 0.67945 -0.3048)
			(stroke
				(width 0.1)
				(type default)
			)
			(layer "F.Fab")
		)
		(fp_line
			(start 0.120396 0.3048)
			(end 0.120396 0.2794)
			(stroke
				(width 0.1)
				(type default)
			)
			(layer "F.Fab")
		)
		(fp_line
			(start 0.120396 0.2794)
			(end -0.12065 0.2794)
			(stroke
				(width 0.1)
				(type default)
			)
			(layer "F.Fab")
		)
		(fp_line
			(start -0.12065 0.3048)
			(end -0.67945 0.3048)
			(stroke
				(width 0.1)
				(type default)
			)
			(layer "F.Fab")
		)
		(fp_line
			(start -0.12065 0.2794)
			(end -0.12065 0.3048)
			(stroke
				(width 0.1)
				(type default)
			)
			(layer "F.Fab")
		)
		(fp_line
			(start -0.12065 -0.2794)
			(end 0.12065 -0.2794)
			(stroke
				(width 0.1)
				(type default)
			)
			(layer "F.Fab")
		)
		(fp_line
			(start -0.12065 -0.305054)
			(end -0.12065 -0.2794)
			(stroke
				(width 0.1)
				(type default)
			)
			(layer "F.Fab")
		)
		(fp_line
			(start -0.67945 0.3048)
			(end -0.67945 -0.305054)
			(stroke
				(width 0.1)
				(type default)
			)
			(layer "F.Fab")
		)
		(fp_line
			(start -0.67945 -0.305054)
			(end -0.12065 -0.305054)
			(stroke
				(width 0.1)
				(type default)
			)
			(layer "F.Fab")
		)
		(pad "1" smd circle
			(at -0.40005 0 180)
			(size 0 0)
			(layers "F.Cu" "F.Mask" "F.Paste")
			(net "PVNN_TERM_CPU1")
		)
		(pad "2" smd circle
			(at 0.40005 0 180)
			(size 0 0)
			(layers "F.Cu" "F.Mask" "F.Paste")
			(net "SVID_DIO0_CPU1_R")
		)
	)
	(footprint ""
		(layer "F.Cu")
		(at 49.300638 -408.517344 -90)
		(property "Reference" "C708"
			(at 0 0 270)
			(layer "F.SilkS")
			(hide yes)
			(effects
				(font
					(size 1.27 1.27)
				)
			)
		)
		(property "Value" ""
			(at 0 0 270)
			(layer "F.Fab")
			(effects
				(font
					(size 1.27 1.27)
				)
			)
		)
		(duplicate_pad_numbers_are_jumpers no)
		(fp_line
			(start -0.299974 0.150114)
			(end -0.299974 -0.150114)
			(stroke
				(width 0.1)
				(type default)
			)
			(layer "F.Fab")
		)
		(fp_line
			(start 0.299974 0.150114)
			(end -0.299974 0.150114)
			(stroke
				(width 0.1)
				(type default)
			)
			(layer "F.Fab")
		)
		(fp_line
			(start -0.299974 -0.150114)
			(end 0.299974 -0.150114)
			(stroke
				(width 0.1)
				(type default)
			)
			(layer "F.Fab")
		)
		(fp_line
			(start 0.299974 -0.150114)
			(end 0.299974 0.150114)
			(stroke
				(width 0.1)
				(type default)
			)
			(layer "F.Fab")
		)
		(pad "1" smd rect
			(at -0.2667 0 270)
			(size 0.3048 0.381)
			(layers "F.Cu" "F.Mask" "F.Paste")
			(net "P5E_CPU1_PE4_TX_C_DN<0>")
		)
		(pad "2" smd rect
			(at 0.2667 0 270)
			(size 0.3048 0.381)
			(layers "F.Cu" "F.Mask" "F.Paste")
			(net "P5E_CPU1_PE4_TX_DN<0>")
		)
	)
	(footprint ""
		(layer "F.Cu")
		(at 370.905278 -423.232326 -90)
		(property "Reference" "U270"
			(at -0.413512 -2.776982 0)
			(unlocked yes)
			(layer "F.SilkS")
			(effects
				(font
					(size 0.7874 0.5842)
					(thickness 0.1524)
				)
				(justify left)
			)
		)
		(property "Value" ""
			(at 0 0 270)
			(layer "F.Fab")
			(effects
				(font
					(size 1.27 1.27)
				)
			)
		)
		(duplicate_pad_numbers_are_jumpers no)
		(fp_line
			(start -3.447796 2.500122)
			(end 3.447796 2.500122)
			(stroke
				(width 0.1524)
				(type default)
			)
			(layer "F.SilkS")
		)
		(fp_line
			(start 3.447796 2.500122)
			(end 3.447796 -2.500122)
			(stroke
				(width 0.1524)
				(type default)
			)
			(layer "F.SilkS")
		)
		(fp_line
			(start 0 -1.016)
			(end -1.484122 -2.500122)
			(stroke
				(width 0.1524)
				(type default)
			)
			(layer "F.SilkS")
		)
		(fp_line
			(start -3.447796 -2.500122)
			(end -3.447796 2.500122)
			(stroke
				(width 0.1524)
				(type default)
			)
			(layer "F.SilkS")
		)
		(fp_line
			(start -1.484122 -2.500122)
			(end -3.447796 -2.500122)
			(stroke
				(width 0.1524)
				(type default)
			)
			(layer "F.SilkS")
		)
		(fp_line
			(start 1.484122 -2.500122)
			(end 0 -1.016)
			(stroke
				(width 0.1524)
				(type default)
			)
			(layer "F.SilkS")
		)
		(fp_line
			(start 3.447796 -2.500122)
			(end 1.484122 -2.500122)
			(stroke
				(width 0.1524)
				(type default)
			)
			(layer "F.SilkS")
		)
		(fp_poly
			(pts
				(xy -4.260342 -2.232914) (xy -3.60426 -1.905) (xy -4.260342 -1.577086)
			)
			(stroke
				(width 0)
				(type default)
			)
			(fill yes)
			(layer "F.SilkS")
		)
		(fp_line
			(start -1.999996 2.500122)
			(end 1.999996 2.500122)
			(stroke
				(width 0.1)
				(type default)
			)
			(layer "F.Fab")
		)
		(fp_line
			(start 1.999996 2.500122)
			(end 1.999996 -2.500122)
			(stroke
				(width 0.1)
				(type default)
			)
			(layer "F.Fab")
		)
		(fp_line
			(start -1.999996 -2.500122)
			(end -1.999996 2.500122)
			(stroke
				(width 0.1)
				(type default)
			)
			(layer "F.Fab")
		)
		(fp_line
			(start 1.999996 -2.500122)
			(end -1.999996 -2.500122)
			(stroke
				(width 0.1)
				(type default)
			)
			(layer "F.Fab")
		)
		(fp_poly
			(pts
				(xy -4.5974 -2.413) (xy -4.5974 -1.397) (xy -3.5814 -1.905)
			)
			(stroke
				(width 0)
				(type default)
			)
			(fill yes)
			(layer "F.Fab")
		)
		(pad "1" smd rect
			(at -2.649982 -1.905 180)
			(size 0.6096 1.3208)
			(layers "F.Cu" "F.Mask" "F.Paste")
			(net "SMB_LM75_0_3V3AUX_SDA_R1")
		)
		(pad "2" smd rect
			(at -2.649982 -0.635 180)
			(size 0.6096 1.3208)
			(layers "F.Cu" "F.Mask" "F.Paste")
			(net "SMB_LM75_0_3V3AUX_SCL_R1")
		)
		(pad "3" smd rect
			(at -2.649982 0.635 180)
			(size 0.6096 1.3208)
			(layers "F.Cu" "F.Mask" "F.Paste")
			(net "FM_G751_0_ALERT_N")
		)
		(pad "4" smd rect
			(at -2.649982 1.905 180)
			(size 0.6096 1.3208)
			(layers "F.Cu" "F.Mask" "F.Paste")
			(net "GND")
		)
		(pad "5" smd rect
			(at 2.649982 1.905 180)
			(size 0.6096 1.3208)
			(layers "F.Cu" "F.Mask" "F.Paste")
			(net "U270_0_ADD2")
		)
		(pad "6" smd rect
			(at 2.649982 0.635 180)
			(size 0.6096 1.3208)
			(layers "F.Cu" "F.Mask" "F.Paste")
			(net "U270_0_ADD1")
		)
		(pad "7" smd rect
			(at 2.649982 -0.635 180)
			(size 0.6096 1.3208)
			(layers "F.Cu" "F.Mask" "F.Paste")
			(net "U270_0_ADD0")
		)
		(pad "8" smd rect
			(at 2.649982 -1.905 180)
			(size 0.6096 1.3208)
			(layers "F.Cu" "F.Mask" "F.Paste")
			(net "P3V3_AUX")
		)
	)
	(footprint ""
		(layer "F.Cu")
		(at 445.19088 -95.872808 180)
		(property "Reference" "R3601"
			(at 0 0 180)
			(layer "F.SilkS")
			(hide yes)
			(effects
				(font
					(size 1.27 1.27)
				)
			)
		)
		(property "Value" ""
			(at 0 0 180)
			(layer "F.Fab")
			(effects
				(font
					(size 1.27 1.27)
				)
			)
		)
		(duplicate_pad_numbers_are_jumpers no)
		(fp_line
			(start 0.7874 0.4064)
			(end -0.7874 0.4064)
			(stroke
				(width 0.1524)
				(type default)
			)
			(layer "F.SilkS")
		)
		(fp_line
			(start 0.7874 -0.4064)
			(end 0.7874 0.4064)
			(stroke
				(width 0.1524)
				(type default)
			)
			(layer "F.SilkS")
		)
		(fp_line
			(start -0.7874 0.4064)
			(end -0.7874 -0.4064)
			(stroke
				(width 0.1524)
				(type default)
			)
			(layer "F.SilkS")
		)
		(fp_line
			(start -0.7874 -0.4064)
			(end 0.7874 -0.4064)
			(stroke
				(width 0.1524)
				(type default)
			)
			(layer "F.SilkS")
		)
		(fp_line
			(start 0.67945 0.3048)
			(end 0.120396 0.3048)
			(stroke
				(width 0.1)
				(type default)
			)
			(layer "F.Fab")
		)
		(fp_line
			(start 0.67945 -0.3048)
			(end 0.67945 0.3048)
			(stroke
				(width 0.1)
				(type default)
			)
			(layer "F.Fab")
		)
		(fp_line
			(start 0.12065 -0.2794)
			(end 0.12065 -0.3048)
			(stroke
				(width 0.1)
				(type default)
			)
			(layer "F.Fab")
		)
		(fp_line
			(start 0.12065 -0.3048)
			(end 0.67945 -0.3048)
			(stroke
				(width 0.1)
				(type default)
			)
			(layer "F.Fab")
		)
		(fp_line
			(start 0.120396 0.3048)
			(end 0.120396 0.2794)
			(stroke
				(width 0.1)
				(type default)
			)
			(layer "F.Fab")
		)
		(fp_line
			(start 0.120396 0.2794)
			(end -0.12065 0.2794)
			(stroke
				(width 0.1)
				(type default)
			)
			(layer "F.Fab")
		)
		(fp_line
			(start -0.12065 0.3048)
			(end -0.67945 0.3048)
			(stroke
				(width 0.1)
				(type default)
			)
			(layer "F.Fab")
		)
		(fp_line
			(start -0.12065 0.2794)
			(end -0.12065 0.3048)
			(stroke
				(width 0.1)
				(type default)
			)
			(layer "F.Fab")
		)
		(fp_line
			(start -0.12065 -0.2794)
			(end 0.12065 -0.2794)
			(stroke
				(width 0.1)
				(type default)
			)
			(layer "F.Fab")
		)
		(fp_line
			(start -0.12065 -0.305054)
			(end -0.12065 -0.2794)
			(stroke
				(width 0.1)
				(type default)
			)
			(layer "F.Fab")
		)
		(fp_line
			(start -0.67945 0.3048)
			(end -0.67945 -0.305054)
			(stroke
				(width 0.1)
				(type default)
			)
			(layer "F.Fab")
		)
		(fp_line
			(start -0.67945 -0.305054)
			(end -0.12065 -0.305054)
			(stroke
				(width 0.1)
				(type default)
			)
			(layer "F.Fab")
		)
		(pad "1" smd circle
			(at -0.40005 0 180)
			(size 0 0)
			(layers "F.Cu" "F.Mask" "F.Paste")
			(net "SMB_INA230_1_3V3AUX_SDA_R")
		)
		(pad "2" smd circle
			(at 0.40005 0 180)
			(size 0 0)
			(layers "F.Cu" "F.Mask" "F.Paste")
			(net "SMB_INA230_1_3V3AUX_SDA_R1")
		)
	)
	(footprint ""
		(layer "F.Cu")
		(at 431.828956 -105.32745 -90)
		(property "Reference" "PU202"
			(at 3.334004 -1.70815 0)
			(unlocked yes)
			(layer "F.SilkS")
			(effects
				(font
					(size 0.7874 0.5842)
					(thickness 0.1524)
				)
				(justify left)
			)
		)
		(property "Value" ""
			(at 0 0 270)
			(layer "F.Fab")
			(effects
				(font
					(size 1.27 1.27)
				)
			)
		)
		(duplicate_pad_numbers_are_jumpers no)
		(fp_line
			(start -1.774952 1.039876)
			(end 1.774952 1.039876)
			(stroke
				(width 0.1524)
				(type default)
			)
			(layer "F.SilkS")
		)
		(fp_line
			(start 1.774952 1.039876)
			(end 1.774952 -1.039876)
			(stroke
				(width 0.1524)
				(type default)
			)
			(layer "F.SilkS")
		)
		(fp_line
			(start -1.774952 -1.039876)
			(end -1.774952 1.039876)
			(stroke
				(width 0.1524)
				(type default)
			)
			(layer "F.SilkS")
		)
		(fp_line
			(start 1.774952 -1.039876)
			(end -1.774952 -1.039876)
			(stroke
				(width 0.1524)
				(type default)
			)
			(layer "F.SilkS")
		)
		(fp_poly
			(pts
				(xy -1.769872 -1.039876) (xy -1.769872 -0.249936) (xy -2.531872 -0.249936) (xy -2.531872 -1.801876)
				(xy -0.999998 -1.801876) (xy -0.999998 -1.039876)
			)
			(stroke
				(width 0)
				(type default)
			)
			(fill yes)
			(layer "F.SilkS")
		)
		(fp_line
			(start -1.769872 1.039876)
			(end 1.769872 1.039876)
			(stroke
				(width 0.1)
				(type default)
			)
			(layer "F.Fab")
		)
		(fp_line
			(start 1.769872 1.039876)
			(end 1.769872 -1.039876)
			(stroke
				(width 0.1)
				(type default)
			)
			(layer "F.Fab")
		)
		(fp_line
			(start -1.769872 -1.039876)
			(end -1.769872 1.039876)
			(stroke
				(width 0.1)
				(type default)
			)
			(layer "F.Fab")
		)
		(fp_line
			(start 1.769872 -1.039876)
			(end -1.769872 -1.039876)
			(stroke
				(width 0.1)
				(type default)
			)
			(layer "F.Fab")
		)
		(fp_poly
			(pts
				(xy -1.769872 -1.039876) (xy -0.999998 -1.039876) (xy -0.999998 -1.801876) (xy -2.531872 -1.801876)
				(xy -2.531872 -0.249936) (xy -1.769872 -0.249936)
			)
			(stroke
				(width 0)
				(type default)
			)
			(fill yes)
			(layer "F.Fab")
		)
		(pad "A1" smd circle
			(at -1.500124 -0.750062 270)
			(size 0.2286 0.2286)
			(layers "F.Cu" "F.Mask" "F.Paste")
			(net "P3V3_OCP_SENSE_1")
		)
		(pad "A2" smd circle
			(at -0.999998 -0.750062 270)
			(size 0.2286 0.2286)
			(layers "F.Cu" "F.Mask" "F.Paste")
			(net "P3V3_OCP_VCC_1")
		)
		(pad "A3" smd circle
			(at -0.499872 -0.750062 270)
			(size 0.2286 0.2286)
			(layers "F.Cu" "F.Mask" "F.Paste")
			(net "P3V3_AUX")
		)
		(pad "A4" smd circle
			(at 0 -0.750062 270)
			(size 0.2286 0.2286)
			(layers "F.Cu" "F.Mask" "F.Paste")
			(net "P3V3_OCP_SFF_R")
		)
		(pad "A5" smd circle
			(at 0.499872 -0.750062 270)
			(size 0.2286 0.2286)
			(layers "F.Cu" "F.Mask" "F.Paste")
			(net "P3V3_AUX")
		)
		(pad "A6" smd circle
			(at 0.999998 -0.750062 270)
			(size 0.2286 0.2286)
			(layers "F.Cu" "F.Mask" "F.Paste")
			(net "P3V3_OCP_GATE_PU202_1")
		)
		(pad "A7" smd circle
			(at 1.500124 -0.750062 270)
			(size 0.2286 0.2286)
			(layers "F.Cu" "F.Mask" "F.Paste")
			(net "GND")
		)
		(pad "B1" smd circle
			(at -1.500124 -0.249936 270)
			(size 0.2286 0.2286)
			(layers "F.Cu" "F.Mask" "F.Paste")
			(net "P3V3_OCP_CB_1")
		)
		(pad "B2" smd circle
			(at -0.999998 -0.249936 270)
			(size 0.2286 0.2286)
			(layers "F.Cu" "F.Mask" "F.Paste")
			(net "GND")
		)
		(pad "B3" smd circle
			(at -0.499872 -0.249936 270)
			(size 0.2286 0.2286)
			(layers "F.Cu" "F.Mask" "F.Paste")
			(net "P3V3_AUX")
		)
		(pad "B4" smd circle
			(at 0 -0.249936 270)
			(size 0.2286 0.2286)
			(layers "F.Cu" "F.Mask" "F.Paste")
			(net "P3V3_OCP_SFF_R")
		)
		(pad "B5" smd circle
			(at 0.499872 -0.249936 270)
			(size 0.2286 0.2286)
			(layers "F.Cu" "F.Mask" "F.Paste")
			(net "P3V3_AUX")
		)
		(pad "B6" smd circle
			(at 0.999998 -0.249936 270)
			(size 0.2286 0.2286)
			(layers "F.Cu" "F.Mask" "F.Paste")
			(net "P3V3_OCP_SFF_R")
		)
		(pad "B7" smd circle
			(at 1.500124 -0.249936 270)
			(size 0.2286 0.2286)
			(layers "F.Cu" "F.Mask" "F.Paste")
			(net "GND")
		)
		(pad "C1" smd circle
			(at -1.500124 0.249936 270)
			(size 0.2286 0.2286)
			(layers "F.Cu" "F.Mask" "F.Paste")
			(net "GND")
		)
		(pad "C2" smd circle
			(at -0.999998 0.249936 270)
			(size 0.2286 0.2286)
			(layers "F.Cu" "F.Mask" "F.Paste")
			(net "GND")
		)
		(pad "C3" smd circle
			(at -0.499872 0.249936 270)
			(size 0.2286 0.2286)
			(layers "F.Cu" "F.Mask" "F.Paste")
			(net "P3V3_AUX")
		)
		(pad "C4" smd circle
			(at 0 0.249936 270)
			(size 0.2286 0.2286)
			(layers "F.Cu" "F.Mask" "F.Paste")
			(net "P3V3_OCP_SFF_R")
		)
		(pad "C5" smd circle
			(at 0.499872 0.249936 270)
			(size 0.2286 0.2286)
			(layers "F.Cu" "F.Mask" "F.Paste")
			(net "P3V3_AUX")
		)
		(pad "C6" smd circle
			(at 0.999998 0.249936 270)
			(size 0.2286 0.2286)
			(layers "F.Cu" "F.Mask" "F.Paste")
			(net "P3V3_OCP_SFF_R")
		)
		(pad "C7" smd circle
			(at 1.500124 0.249936 270)
			(size 0.2286 0.2286)
			(layers "F.Cu" "F.Mask" "F.Paste")
			(net "P3V3_OCP_FAULT_1")
		)
		(pad "D1" smd circle
			(at -1.500124 0.750062 270)
			(size 0.2286 0.2286)
			(layers "F.Cu" "F.Mask" "F.Paste")
			(net "P3V3_OCP_REG_1")
		)
		(pad "D2" smd circle
			(at -0.999998 0.750062 270)
			(size 0.2286 0.2286)
			(layers "F.Cu" "F.Mask" "F.Paste")
			(net "P3V3_OCP_UV_1")
		)
		(pad "D3" smd circle
			(at -0.499872 0.750062 270)
			(size 0.2286 0.2286)
			(layers "F.Cu" "F.Mask" "F.Paste")
			(net "P3V3_OCP_OV_1")
		)
		(pad "D4" smd circle
			(at 0 0.750062 270)
			(size 0.2286 0.2286)
			(layers "F.Cu" "F.Mask" "F.Paste")
			(net "P3V3_OCP_SFF_R")
		)
		(pad "D5" smd circle
			(at 0.499872 0.750062 270)
			(size 0.2286 0.2286)
			(layers "F.Cu" "F.Mask" "F.Paste")
			(net "P3V3_AUX")
		)
		(pad "D6" smd circle
			(at 0.999998 0.750062 270)
			(size 0.2286 0.2286)
			(layers "F.Cu" "F.Mask" "F.Paste")
			(net "P3V3_OCP_SFF_R")
		)
		(pad "D7" smd circle
			(at 1.500124 0.750062 270)
			(size 0.2286 0.2286)
			(layers "F.Cu" "F.Mask" "F.Paste")
			(net "P3V3_OCP_PWRGD_1")
		)
	)
	(footprint ""
		(layer "F.Cu")
		(at 367.227358 -92.962984 -90)
		(property "Reference" "R2514"
			(at 0 0 270)
			(layer "F.SilkS")
			(hide yes)
			(effects
				(font
					(size 1.27 1.27)
				)
			)
		)
		(property "Value" ""
			(at 0 0 270)
			(layer "F.Fab")
			(effects
				(font
					(size 1.27 1.27)
				)
			)
		)
		(duplicate_pad_numbers_are_jumpers no)
		(fp_line
			(start -0.7874 0.4064)
			(end -0.7874 -0.4064)
			(stroke
				(width 0.1524)
				(type default)
			)
			(layer "F.SilkS")
		)
		(fp_line
			(start 0.7874 0.4064)
			(end -0.7874 0.4064)
			(stroke
				(width 0.1524)
				(type default)
			)
			(layer "F.SilkS")
		)
		(fp_line
			(start -0.7874 -0.4064)
			(end 0.7874 -0.4064)
			(stroke
				(width 0.1524)
				(type default)
			)
			(layer "F.SilkS")
		)
		(fp_line
			(start 0.7874 -0.4064)
			(end 0.7874 0.4064)
			(stroke
				(width 0.1524)
				(type default)
			)
			(layer "F.SilkS")
		)
		(fp_line
			(start -0.67945 0.3048)
			(end -0.67945 -0.305054)
			(stroke
				(width 0.1)
				(type default)
			)
			(layer "F.Fab")
		)
		(fp_line
			(start -0.12065 0.3048)
			(end -0.67945 0.3048)
			(stroke
				(width 0.1)
				(type default)
			)
			(layer "F.Fab")
		)
		(fp_line
			(start 0.120396 0.3048)
			(end 0.120396 0.2794)
			(stroke
				(width 0.1)
				(type default)
			)
			(layer "F.Fab")
		)
		(fp_line
			(start 0.67945 0.3048)
			(end 0.120396 0.3048)
			(stroke
				(width 0.1)
				(type default)
			)
			(layer "F.Fab")
		)
		(fp_line
			(start -0.12065 0.2794)
			(end -0.12065 0.3048)
			(stroke
				(width 0.1)
				(type default)
			)
			(layer "F.Fab")
		)
		(fp_line
			(start 0.120396 0.2794)
			(end -0.12065 0.2794)
			(stroke
				(width 0.1)
				(type default)
			)
			(layer "F.Fab")
		)
		(fp_line
			(start -0.12065 -0.2794)
			(end 0.12065 -0.2794)
			(stroke
				(width 0.1)
				(type default)
			)
			(layer "F.Fab")
		)
		(fp_line
			(start 0.12065 -0.2794)
			(end 0.12065 -0.3048)
			(stroke
				(width 0.1)
				(type default)
			)
			(layer "F.Fab")
		)
		(fp_line
			(start 0.12065 -0.3048)
			(end 0.67945 -0.3048)
			(stroke
				(width 0.1)
				(type default)
			)
			(layer "F.Fab")
		)
		(fp_line
			(start 0.67945 -0.3048)
			(end 0.67945 0.3048)
			(stroke
				(width 0.1)
				(type default)
			)
			(layer "F.Fab")
		)
		(fp_line
			(start -0.67945 -0.305054)
			(end -0.12065 -0.305054)
			(stroke
				(width 0.1)
				(type default)
			)
			(layer "F.Fab")
		)
		(fp_line
			(start -0.12065 -0.305054)
			(end -0.12065 -0.2794)
			(stroke
				(width 0.1)
				(type default)
			)
			(layer "F.Fab")
		)
		(pad "1" smd circle
			(at -0.40005 0 270)
			(size 0 0)
			(layers "F.Cu" "F.Mask" "F.Paste")
			(net "PU_GTL2014_BMC_JTAG_DIR_1")
		)
		(pad "2" smd circle
			(at 0.40005 0 270)
			(size 0 0)
			(layers "F.Cu" "F.Mask" "F.Paste")
			(net "GND")
		)
	)
	(footprint ""
		(layer "F.Cu")
		(at 53.08473 -17.623536 90)
		(property "Reference" "C833"
			(at 0 0 90)
			(layer "F.SilkS")
			(hide yes)
			(effects
				(font
					(size 1.27 1.27)
				)
			)
		)
		(property "Value" ""
			(at 0 0 90)
			(layer "F.Fab")
			(effects
				(font
					(size 1.27 1.27)
				)
			)
		)
		(duplicate_pad_numbers_are_jumpers no)
		(fp_line
			(start 0.299974 -0.150114)
			(end 0.299974 0.150114)
			(stroke
				(width 0.1)
				(type default)
			)
			(layer "F.Fab")
		)
		(fp_line
			(start -0.299974 -0.150114)
			(end 0.299974 -0.150114)
			(stroke
				(width 0.1)
				(type default)
			)
			(layer "F.Fab")
		)
		(fp_line
			(start 0.299974 0.150114)
			(end -0.299974 0.150114)
			(stroke
				(width 0.1)
				(type default)
			)
			(layer "F.Fab")
		)
		(fp_line
			(start -0.299974 0.150114)
			(end -0.299974 -0.150114)
			(stroke
				(width 0.1)
				(type default)
			)
			(layer "F.Fab")
		)
		(pad "1" smd rect
			(at -0.2667 0 90)
			(size 0.3048 0.381)
			(layers "F.Cu" "F.Mask" "F.Paste")
			(net "P5E_CPU1_PE1_TX_C_DP<2>")
		)
		(pad "2" smd rect
			(at 0.2667 0 90)
			(size 0.3048 0.381)
			(layers "F.Cu" "F.Mask" "F.Paste")
			(net "P5E_CPU1_PE1_TX_DP<2>")
		)
	)
	(footprint ""
		(layer "F.Cu")
		(at 456.520804 -76.588112 90)
		(property "Reference" "PC576"
			(at 0 0 90)
			(layer "F.SilkS")
			(hide yes)
			(effects
				(font
					(size 1.27 1.27)
				)
			)
		)
		(property "Value" ""
			(at 0 0 90)
			(layer "F.Fab")
			(effects
				(font
					(size 1.27 1.27)
				)
			)
		)
		(duplicate_pad_numbers_are_jumpers no)
		(fp_line
			(start 1.524 -0.762)
			(end 1.524 0.762)
			(stroke
				(width 0.1524)
				(type default)
			)
			(layer "F.SilkS")
		)
		(fp_line
			(start -1.524 -0.762)
			(end 1.524 -0.762)
			(stroke
				(width 0.1524)
				(type default)
			)
			(layer "F.SilkS")
		)
		(fp_line
			(start 1.524 0.762)
			(end -1.524 0.762)
			(stroke
				(width 0.1524)
				(type default)
			)
			(layer "F.SilkS")
		)
		(fp_line
			(start -1.524 0.762)
			(end -1.524 -0.762)
			(stroke
				(width 0.1524)
				(type default)
			)
			(layer "F.SilkS")
		)
		(fp_line
			(start 1.1049 -0.724916)
			(end -1.1049 -0.724916)
			(stroke
				(width 0.1)
				(type default)
			)
			(layer "F.Fab")
		)
		(fp_line
			(start -1.1049 -0.724916)
			(end -1.1049 0.724916)
			(stroke
				(width 0.1)
				(type default)
			)
			(layer "F.Fab")
		)
		(fp_line
			(start 1.1049 0.724916)
			(end 1.1049 -0.724916)
			(stroke
				(width 0.1)
				(type default)
			)
			(layer "F.Fab")
		)
		(fp_line
			(start -1.1049 0.724916)
			(end 1.1049 0.724916)
			(stroke
				(width 0.1)
				(type default)
			)
			(layer "F.Fab")
		)
		(pad "1" smd rect
			(at -0.889 0 270)
			(size 1.016 1.27)
			(layers "F.Cu" "F.Mask" "F.Paste")
			(net "SW_P3V3_AUX_FLT")
		)
		(pad "2" smd rect
			(at 0.889 0 270)
			(size 1.016 1.27)
			(layers "F.Cu" "F.Mask" "F.Paste")
			(net "GND")
		)
	)
	(footprint ""
		(layer "F.Cu")
		(at 184.290208 -407.439622 90)
		(property "Reference" "PC2189"
			(at 0 0 90)
			(layer "F.SilkS")
			(hide yes)
			(effects
				(font
					(size 1.27 1.27)
				)
			)
		)
		(property "Value" ""
			(at 0 0 90)
			(layer "F.Fab")
			(effects
				(font
					(size 1.27 1.27)
				)
			)
		)
		(duplicate_pad_numbers_are_jumpers no)
		(fp_line
			(start 0.7874 -0.4064)
			(end 0.7874 0.4064)
			(stroke
				(width 0.1524)
				(type default)
			)
			(layer "F.SilkS")
		)
		(fp_line
			(start -0.7874 -0.4064)
			(end 0.7874 -0.4064)
			(stroke
				(width 0.1524)
				(type default)
			)
			(layer "F.SilkS")
		)
		(fp_line
			(start 0.7874 0.4064)
			(end -0.7874 0.4064)
			(stroke
				(width 0.1524)
				(type default)
			)
			(layer "F.SilkS")
		)
		(fp_line
			(start -0.7874 0.4064)
			(end -0.7874 -0.4064)
			(stroke
				(width 0.1524)
				(type default)
			)
			(layer "F.SilkS")
		)
		(fp_line
			(start -0.12065 -0.305054)
			(end -0.12065 -0.2794)
			(stroke
				(width 0.1)
				(type default)
			)
			(layer "F.Fab")
		)
		(fp_line
			(start -0.67945 -0.305054)
			(end -0.12065 -0.305054)
			(stroke
				(width 0.1)
				(type default)
			)
			(layer "F.Fab")
		)
		(fp_line
			(start 0.67945 -0.3048)
			(end 0.67945 0.3048)
			(stroke
				(width 0.1)
				(type default)
			)
			(layer "F.Fab")
		)
		(fp_line
			(start 0.12065 -0.3048)
			(end 0.67945 -0.3048)
			(stroke
				(width 0.1)
				(type default)
			)
			(layer "F.Fab")
		)
		(fp_line
			(start 0.12065 -0.2794)
			(end 0.12065 -0.3048)
			(stroke
				(width 0.1)
				(type default)
			)
			(layer "F.Fab")
		)
		(fp_line
			(start -0.12065 -0.2794)
			(end 0.12065 -0.2794)
			(stroke
				(width 0.1)
				(type default)
			)
			(layer "F.Fab")
		)
		(fp_line
			(start 0.120396 0.2794)
			(end -0.12065 0.2794)
			(stroke
				(width 0.1)
				(type default)
			)
			(layer "F.Fab")
		)
		(fp_line
			(start -0.12065 0.2794)
			(end -0.12065 0.3048)
			(stroke
				(width 0.1)
				(type default)
			)
			(layer "F.Fab")
		)
		(fp_line
			(start 0.67945 0.3048)
			(end 0.120396 0.3048)
			(stroke
				(width 0.1)
				(type default)
			)
			(layer "F.Fab")
		)
		(fp_line
			(start 0.120396 0.3048)
			(end 0.120396 0.2794)
			(stroke
				(width 0.1)
				(type default)
			)
			(layer "F.Fab")
		)
		(fp_line
			(start -0.12065 0.3048)
			(end -0.67945 0.3048)
			(stroke
				(width 0.1)
				(type default)
			)
			(layer "F.Fab")
		)
		(fp_line
			(start -0.67945 0.3048)
			(end -0.67945 -0.305054)
			(stroke
				(width 0.1)
				(type default)
			)
			(layer "F.Fab")
		)
		(pad "1" smd circle
			(at -0.40005 0 90)
			(size 0 0)
			(layers "F.Cu" "F.Mask" "F.Paste")
			(net "HSC_VSENSE")
		)
		(pad "2" smd circle
			(at 0.40005 0 90)
			(size 0 0)
			(layers "F.Cu" "F.Mask" "F.Paste")
			(net "AGND_HSC")
		)
	)
	(footprint ""
		(layer "F.Cu")
		(at 305.58994 -433.0573 90)
		(property "Reference" "R4135"
			(at 0 0 90)
			(layer "F.SilkS")
			(hide yes)
			(effects
				(font
					(size 1.27 1.27)
				)
			)
		)
		(property "Value" ""
			(at 0 0 90)
			(layer "F.Fab")
			(effects
				(font
					(size 1.27 1.27)
				)
			)
		)
		(duplicate_pad_numbers_are_jumpers no)
		(fp_line
			(start 0.7874 -0.4064)
			(end 0.7874 0.4064)
			(stroke
				(width 0.1524)
				(type default)
			)
			(layer "F.SilkS")
		)
		(fp_line
			(start -0.7874 -0.4064)
			(end 0.7874 -0.4064)
			(stroke
				(width 0.1524)
				(type default)
			)
			(layer "F.SilkS")
		)
		(fp_line
			(start 0.7874 0.4064)
			(end -0.7874 0.4064)
			(stroke
				(width 0.1524)
				(type default)
			)
			(layer "F.SilkS")
		)
		(fp_line
			(start -0.7874 0.4064)
			(end -0.7874 -0.4064)
			(stroke
				(width 0.1524)
				(type default)
			)
			(layer "F.SilkS")
		)
		(fp_line
			(start -0.12065 -0.305054)
			(end -0.12065 -0.2794)
			(stroke
				(width 0.1)
				(type default)
			)
			(layer "F.Fab")
		)
		(fp_line
			(start -0.67945 -0.305054)
			(end -0.12065 -0.305054)
			(stroke
				(width 0.1)
				(type default)
			)
			(layer "F.Fab")
		)
		(fp_line
			(start 0.67945 -0.3048)
			(end 0.67945 0.3048)
			(stroke
				(width 0.1)
				(type default)
			)
			(layer "F.Fab")
		)
		(fp_line
			(start 0.12065 -0.3048)
			(end 0.67945 -0.3048)
			(stroke
				(width 0.1)
				(type default)
			)
			(layer "F.Fab")
		)
		(fp_line
			(start 0.12065 -0.2794)
			(end 0.12065 -0.3048)
			(stroke
				(width 0.1)
				(type default)
			)
			(layer "F.Fab")
		)
		(fp_line
			(start -0.12065 -0.2794)
			(end 0.12065 -0.2794)
			(stroke
				(width 0.1)
				(type default)
			)
			(layer "F.Fab")
		)
		(fp_line
			(start 0.120396 0.2794)
			(end -0.12065 0.2794)
			(stroke
				(width 0.1)
				(type default)
			)
			(layer "F.Fab")
		)
		(fp_line
			(start -0.12065 0.2794)
			(end -0.12065 0.3048)
			(stroke
				(width 0.1)
				(type default)
			)
			(layer "F.Fab")
		)
		(fp_line
			(start 0.67945 0.3048)
			(end 0.120396 0.3048)
			(stroke
				(width 0.1)
				(type default)
			)
			(layer "F.Fab")
		)
		(fp_line
			(start 0.120396 0.3048)
			(end 0.120396 0.2794)
			(stroke
				(width 0.1)
				(type default)
			)
			(layer "F.Fab")
		)
		(fp_line
			(start -0.12065 0.3048)
			(end -0.67945 0.3048)
			(stroke
				(width 0.1)
				(type default)
			)
			(layer "F.Fab")
		)
		(fp_line
			(start -0.67945 0.3048)
			(end -0.67945 -0.305054)
			(stroke
				(width 0.1)
				(type default)
			)
			(layer "F.Fab")
		)
		(pad "1" smd circle
			(at -0.40005 0 90)
			(size 0 0)
			(layers "F.Cu" "F.Mask" "F.Paste")
			(net "P3V3_AUX")
		)
		(pad "2" smd circle
			(at 0.40005 0 90)
			(size 0 0)
			(layers "F.Cu" "F.Mask" "F.Paste")
			(net "PRSNT_CABLE_GPU_A2_N")
		)
	)
	(footprint ""
		(layer "F.Cu")
		(at 126.635002 -154.195018 90)
		(property "Reference" "JP15"
			(at 9.14146 0.288798 0)
			(unlocked yes)
			(layer "F.SilkS")
			(effects
				(font
					(size 0.7874 0.5842)
					(thickness 0.1524)
				)
				(justify left)
			)
		)
		(property "Value" ""
			(at 0 0 90)
			(layer "F.Fab")
			(effects
				(font
					(size 1.27 1.27)
				)
			)
		)
		(duplicate_pad_numbers_are_jumpers no)
		(fp_line
			(start 1.249934 -1.320038)
			(end 1.249934 6.400038)
			(stroke
				(width 0.1524)
				(type default)
			)
			(layer "F.SilkS")
		)
		(fp_line
			(start -1.249934 -1.320038)
			(end 1.249934 -1.320038)
			(stroke
				(width 0.1524)
				(type default)
			)
			(layer "F.SilkS")
		)
		(fp_line
			(start 1.249934 6.400038)
			(end -1.249934 6.400038)
			(stroke
				(width 0.1524)
				(type default)
			)
			(layer "F.SilkS")
		)
		(fp_line
			(start -1.249934 6.400038)
			(end -1.249934 -1.320038)
			(stroke
				(width 0.1524)
				(type default)
			)
			(layer "F.SilkS")
		)
		(fp_poly
			(pts
				(xy -2.5654 -0.556514) (xy -1.452372 0) (xy -2.5654 0.556514)
			)
			(stroke
				(width 0)
				(type default)
			)
			(fill yes)
			(layer "F.SilkS")
		)
		(fp_line
			(start 1.249934 -1.320038)
			(end 1.249934 6.400038)
			(stroke
				(width 0.1)
				(type default)
			)
			(layer "F.Fab")
		)
		(fp_line
			(start -1.249934 -1.320038)
			(end 1.249934 -1.320038)
			(stroke
				(width 0.1)
				(type default)
			)
			(layer "F.Fab")
		)
		(fp_line
			(start 1.249934 6.400038)
			(end -1.249934 6.400038)
			(stroke
				(width 0.1)
				(type default)
			)
			(layer "F.Fab")
		)
		(fp_line
			(start -1.249934 6.400038)
			(end -1.249934 -1.320038)
			(stroke
				(width 0.1)
				(type default)
			)
			(layer "F.Fab")
		)
		(fp_poly
			(pts
				(xy -2.5654 -0.556514) (xy -1.452372 0) (xy -2.5654 0.556514)
			)
			(stroke
				(width 0)
				(type default)
			)
			(fill yes)
			(layer "F.Fab")
		)
		(fp_text user "3"
			(at -1.778 5.13207 90)
			(unlocked yes)
			(layer "F.SilkS")
			(effects
				(font
					(size 0.7874 0.5842)
					(thickness 0.1524)
				)
			)
		)
		(fp_text user "1"
			(at -1.143 0.02667 90)
			(unlocked yes)
			(layer "B.SilkS")
			(effects
				(font
					(size 0.7874 0.5842)
					(thickness 0.1524)
				)
				(justify mirror)
			)
		)
		(fp_text user "3"
			(at -1.1557 5.18287 90)
			(unlocked yes)
			(layer "B.SilkS")
			(effects
				(font
					(size 0.7874 0.5842)
					(thickness 0.1524)
				)
				(justify mirror)
			)
		)
		(fp_text user "1"
			(at -1.143 0.02667 90)
			(unlocked yes)
			(layer "B.Fab")
			(effects
				(font
					(size 0.7874 0.5842)
					(thickness 0.1524)
				)
				(justify mirror)
			)
		)
		(fp_text user "3"
			(at -1.1557 5.18287 90)
			(unlocked yes)
			(layer "B.Fab")
			(effects
				(font
					(size 0.7874 0.5842)
					(thickness 0.1524)
				)
				(justify mirror)
			)
		)
		(fp_text user "3"
			(at -1.778 5.13207 90)
			(unlocked yes)
			(layer "F.Fab")
			(effects
				(font
					(size 0.7874 0.5842)
					(thickness 0.1524)
				)
			)
		)
		(pad "1" thru_hole rect
			(at 0 0 90)
			(size 1.5494 1.5494)
			(drill 1.0414)
			(layers "*.Cu" "*.Mask")
			(remove_unused_layers no)
			(net "PU_FORCE_PWRON")
			(clearance 0)
			(padstack
				(mode front_inner_back)
				(layer "Inner"
					(shape circle)
					(size 1.5494 1.5494)
					(clearance 0)
				)
				(layer "B.Cu"
					(shape rect)
					(size 1.5494 1.5494)
					(clearance 0)
				)
			)
		)
		(pad "2" thru_hole circle
			(at 0 2.54 90)
			(size 1.5494 1.5494)
			(drill 1.0414)
			(layers "*.Cu" "*.Mask")
			(remove_unused_layers no)
			(net "FM_FORCE_PWRON_LVC3")
			(clearance 0)
		)
		(pad "3" thru_hole circle
			(at 0 5.08 90)
			(size 1.5494 1.5494)
			(drill 1.0414)
			(layers "*.Cu" "*.Mask")
			(remove_unused_layers no)
			(net "PD_FORCE_PWRON")
			(clearance 0)
		)
	)
	(footprint ""
		(layer "F.Cu")
		(at 209.149696 -67.853306)
		(property "Reference" "Q150"
			(at -1.4478 2.016252 0)
			(unlocked yes)
			(layer "F.SilkS")
			(effects
				(font
					(size 0.7874 0.5842)
					(thickness 0.1524)
				)
				(justify left)
			)
		)
		(property "Value" ""
			(at 0 0 0)
			(layer "F.Fab")
			(effects
				(font
					(size 1.27 1.27)
				)
			)
		)
		(duplicate_pad_numbers_are_jumpers no)
		(fp_line
			(start -1.332738 -1.100074)
			(end -0.4826 -1.100074)
			(stroke
				(width 0.1524)
				(type default)
			)
			(layer "F.SilkS")
		)
		(fp_line
			(start -1.332738 1.100074)
			(end -1.332738 -1.100074)
			(stroke
				(width 0.1524)
				(type default)
			)
			(layer "F.SilkS")
		)
		(fp_line
			(start -0.4826 -1.100074)
			(end 0 -0.541274)
			(stroke
				(width 0.1524)
				(type default)
			)
			(layer "F.SilkS")
		)
		(fp_line
			(start 0 -0.541274)
			(end 0.4826 -1.100074)
			(stroke
				(width 0.1524)
				(type default)
			)
			(layer "F.SilkS")
		)
		(fp_line
			(start 0.4826 -1.100074)
			(end 1.332738 -1.100074)
			(stroke
				(width 0.1524)
				(type default)
			)
			(layer "F.SilkS")
		)
		(fp_line
			(start 1.332738 -1.100074)
			(end 1.332738 1.100074)
			(stroke
				(width 0.1524)
				(type default)
			)
			(layer "F.SilkS")
		)
		(fp_line
			(start 1.332738 1.100074)
			(end -1.332738 1.100074)
			(stroke
				(width 0.1524)
				(type default)
			)
			(layer "F.SilkS")
		)
		(fp_poly
			(pts
				(xy -2.2352 -0.298958) (xy -2.2352 -1.001014) (xy -1.533144 -0.649986)
			)
			(stroke
				(width 0)
				(type default)
			)
			(fill yes)
			(layer "F.SilkS")
		)
		(fp_line
			(start -0.674878 -1.100074)
			(end 0.674878 -1.100074)
			(stroke
				(width 0.1)
				(type default)
			)
			(layer "F.Fab")
		)
		(fp_line
			(start -0.674878 1.100074)
			(end -0.674878 -1.100074)
			(stroke
				(width 0.1)
				(type default)
			)
			(layer "F.Fab")
		)
		(fp_line
			(start 0.674878 -1.100074)
			(end 0.674878 1.100074)
			(stroke
				(width 0.1)
				(type default)
			)
			(layer "F.Fab")
		)
		(fp_line
			(start 0.674878 1.100074)
			(end -0.674878 1.100074)
			(stroke
				(width 0.1)
				(type default)
			)
			(layer "F.Fab")
		)
		(fp_poly
			(pts
				(xy -2.2352 -0.298958) (xy -2.2352 -1.001014) (xy -1.533144 -0.649986)
			)
			(stroke
				(width 0)
				(type default)
			)
			(fill yes)
			(layer "F.Fab")
		)
		(pad "1" smd rect
			(at -0.94996 -0.649986 90)
			(size 0.4318 0.508)
			(layers "F.Cu" "F.Mask" "F.Paste")
			(net "GND")
		)
		(pad "2" smd rect
			(at -0.94996 0 90)
			(size 0.4318 0.508)
			(layers "F.Cu" "F.Mask" "F.Paste")
			(net "P12V_SCM_FAULT_R_N")
		)
		(pad "3" smd rect
			(at -0.94996 0.649986 90)
			(size 0.4318 0.508)
			(layers "F.Cu" "F.Mask" "F.Paste")
			(net "LED_P12V_SCM_FAULT_D2")
		)
		(pad "4" smd rect
			(at 0.94996 0.649986 90)
			(size 0.4318 0.508)
			(layers "F.Cu" "F.Mask" "F.Paste")
			(net "GND")
		)
		(pad "5" smd rect
			(at 0.94996 0 90)
			(size 0.4318 0.508)
			(layers "F.Cu" "F.Mask" "F.Paste")
			(net "LED_P12V_SCM_FAULT_D1")
		)
		(pad "6" smd rect
			(at 0.94996 -0.649986 90)
			(size 0.4318 0.508)
			(layers "F.Cu" "F.Mask" "F.Paste")
			(net "LED_P12V_SCM_FAULT_D1")
		)
	)
	(footprint ""
		(layer "F.Cu")
		(at 366.06988 -296.05478 180)
		(property "Reference" "C219"
			(at 0 0 180)
			(layer "F.SilkS")
			(hide yes)
			(effects
				(font
					(size 1.27 1.27)
				)
			)
		)
		(property "Value" ""
			(at 0 0 180)
			(layer "F.Fab")
			(effects
				(font
					(size 1.27 1.27)
				)
			)
		)
		(duplicate_pad_numbers_are_jumpers no)
		(fp_line
			(start 1.524 0.762)
			(end -1.524 0.762)
			(stroke
				(width 0.1524)
				(type default)
			)
			(layer "F.SilkS")
		)
		(fp_line
			(start 1.524 -0.762)
			(end 1.524 0.762)
			(stroke
				(width 0.1524)
				(type default)
			)
			(layer "F.SilkS")
		)
		(fp_line
			(start -1.524 0.762)
			(end -1.524 -0.762)
			(stroke
				(width 0.1524)
				(type default)
			)
			(layer "F.SilkS")
		)
		(fp_line
			(start -1.524 -0.762)
			(end 1.524 -0.762)
			(stroke
				(width 0.1524)
				(type default)
			)
			(layer "F.SilkS")
		)
		(fp_line
			(start 1.1049 0.724916)
			(end 1.1049 -0.724916)
			(stroke
				(width 0.1)
				(type default)
			)
			(layer "F.Fab")
		)
		(fp_line
			(start 1.1049 -0.724916)
			(end -1.1049 -0.724916)
			(stroke
				(width 0.1)
				(type default)
			)
			(layer "F.Fab")
		)
		(fp_line
			(start -1.1049 0.724916)
			(end 1.1049 0.724916)
			(stroke
				(width 0.1)
				(type default)
			)
			(layer "F.Fab")
		)
		(fp_line
			(start -1.1049 -0.724916)
			(end -1.1049 0.724916)
			(stroke
				(width 0.1)
				(type default)
			)
			(layer "F.Fab")
		)
		(pad "1" smd rect
			(at -0.889 0)
			(size 1.016 1.27)
			(layers "F.Cu" "F.Mask" "F.Paste")
			(net "PVCCIN_CPU0")
		)
		(pad "2" smd rect
			(at 0.889 0)
			(size 1.016 1.27)
			(layers "F.Cu" "F.Mask" "F.Paste")
			(net "GND")
		)
	)
	(footprint ""
		(layer "F.Cu")
		(at 239.152684 -57.41289 180)
		(property "Reference" "C1990"
			(at 0 0 180)
			(layer "F.SilkS")
			(hide yes)
			(effects
				(font
					(size 1.27 1.27)
				)
			)
		)
		(property "Value" ""
			(at 0 0 180)
			(layer "F.Fab")
			(effects
				(font
					(size 1.27 1.27)
				)
			)
		)
		(duplicate_pad_numbers_are_jumpers no)
		(fp_line
			(start 0.299974 0.150114)
			(end -0.299974 0.150114)
			(stroke
				(width 0.1)
				(type default)
			)
			(layer "F.Fab")
		)
		(fp_line
			(start 0.299974 -0.150114)
			(end 0.299974 0.150114)
			(stroke
				(width 0.1)
				(type default)
			)
			(layer "F.Fab")
		)
		(fp_line
			(start -0.299974 0.150114)
			(end -0.299974 -0.150114)
			(stroke
				(width 0.1)
				(type default)
			)
			(layer "F.Fab")
		)
		(fp_line
			(start -0.299974 -0.150114)
			(end 0.299974 -0.150114)
			(stroke
				(width 0.1)
				(type default)
			)
			(layer "F.Fab")
		)
		(pad "1" smd rect
			(at -0.2667 0 180)
			(size 0.3048 0.381)
			(layers "F.Cu" "F.Mask" "F.Paste")
			(net "P3E_PCH_E1S_TX_DN<3>")
		)
		(pad "2" smd rect
			(at 0.2667 0 180)
			(size 0.3048 0.381)
			(layers "F.Cu" "F.Mask" "F.Paste")
			(net "P3E_PCH_E1S_TX_C_DN<3>")
		)
		(zone
			(layer "In1.Cu")
			(hatch none 0.5)
			(connect_pads
				(clearance 0)
			)
			(min_thickness 0.25)
			(keepout
				(tracks not_allowed)
				(vias allowed)
				(pads allowed)
				(copperpour not_allowed)
				(footprints allowed)
			)
			(placement
				(enabled no)
				(sheetname "")
			)
			(fill
				(thermal_gap 0.5)
				(thermal_bridge_width 0.5)
				(island_removal_mode 0)
			)
			(polygon
				(pts
					(arc
						(start 239.012984 -57.653174)
						(mid 239.066866 -57.630856)
						(end 239.089184 -57.576974)
					)
					(arc
						(start 239.089184 -57.246774)
						(mid 239.066866 -57.192892)
						(end 239.012984 -57.170574)
					)
					(arc
						(start 238.758984 -57.170574)
						(mid 238.705102 -57.192892)
						(end 238.682784 -57.246774)
					)
					(arc
						(start 238.682784 -57.576974)
						(mid 238.705102 -57.630856)
						(end 238.758984 -57.653174)
					)
				)
			)
		)
		(zone
			(layer "In1.Cu")
			(hatch none 0.5)
			(connect_pads
				(clearance 0)
			)
			(min_thickness 0.25)
			(keepout
				(tracks not_allowed)
				(vias allowed)
				(pads allowed)
				(copperpour not_allowed)
				(footprints allowed)
			)
			(placement
				(enabled no)
				(sheetname "")
			)
			(fill
				(thermal_gap 0.5)
				(thermal_bridge_width 0.5)
				(island_removal_mode 0)
			)
			(polygon
				(pts
					(arc
						(start 239.546384 -57.653174)
						(mid 239.600266 -57.630856)
						(end 239.622584 -57.576974)
					)
					(arc
						(start 239.622584 -57.246774)
						(mid 239.600266 -57.192892)
						(end 239.546384 -57.170574)
					)
					(arc
						(start 239.292384 -57.170574)
						(mid 239.238502 -57.192892)
						(end 239.216184 -57.246774)
					)
					(arc
						(start 239.216184 -57.576974)
						(mid 239.238502 -57.630856)
						(end 239.292384 -57.653174)
					)
				)
			)
		)
	)
	(footprint ""
		(layer "F.Cu")
		(at 450.307202 -77.829918 90)
		(property "Reference" "PR833"
			(at 0 0 90)
			(layer "F.SilkS")
			(hide yes)
			(effects
				(font
					(size 1.27 1.27)
				)
			)
		)
		(property "Value" ""
			(at 0 0 90)
			(layer "F.Fab")
			(effects
				(font
					(size 1.27 1.27)
				)
			)
		)
		(duplicate_pad_numbers_are_jumpers no)
		(fp_line
			(start 0.7874 -0.4064)
			(end 0.7874 0.4064)
			(stroke
				(width 0.1524)
				(type default)
			)
			(layer "F.SilkS")
		)
		(fp_line
			(start -0.7874 -0.4064)
			(end 0.7874 -0.4064)
			(stroke
				(width 0.1524)
				(type default)
			)
			(layer "F.SilkS")
		)
		(fp_line
			(start 0.7874 0.4064)
			(end -0.7874 0.4064)
			(stroke
				(width 0.1524)
				(type default)
			)
			(layer "F.SilkS")
		)
		(fp_line
			(start -0.7874 0.4064)
			(end -0.7874 -0.4064)
			(stroke
				(width 0.1524)
				(type default)
			)
			(layer "F.SilkS")
		)
		(fp_line
			(start -0.12065 -0.305054)
			(end -0.12065 -0.2794)
			(stroke
				(width 0.1)
				(type default)
			)
			(layer "F.Fab")
		)
		(fp_line
			(start -0.67945 -0.305054)
			(end -0.12065 -0.305054)
			(stroke
				(width 0.1)
				(type default)
			)
			(layer "F.Fab")
		)
		(fp_line
			(start 0.67945 -0.3048)
			(end 0.67945 0.3048)
			(stroke
				(width 0.1)
				(type default)
			)
			(layer "F.Fab")
		)
		(fp_line
			(start 0.12065 -0.3048)
			(end 0.67945 -0.3048)
			(stroke
				(width 0.1)
				(type default)
			)
			(layer "F.Fab")
		)
		(fp_line
			(start 0.12065 -0.2794)
			(end 0.12065 -0.3048)
			(stroke
				(width 0.1)
				(type default)
			)
			(layer "F.Fab")
		)
		(fp_line
			(start -0.12065 -0.2794)
			(end 0.12065 -0.2794)
			(stroke
				(width 0.1)
				(type default)
			)
			(layer "F.Fab")
		)
		(fp_line
			(start 0.120396 0.2794)
			(end -0.12065 0.2794)
			(stroke
				(width 0.1)
				(type default)
			)
			(layer "F.Fab")
		)
		(fp_line
			(start -0.12065 0.2794)
			(end -0.12065 0.3048)
			(stroke
				(width 0.1)
				(type default)
			)
			(layer "F.Fab")
		)
		(fp_line
			(start 0.67945 0.3048)
			(end 0.120396 0.3048)
			(stroke
				(width 0.1)
				(type default)
			)
			(layer "F.Fab")
		)
		(fp_line
			(start 0.120396 0.3048)
			(end 0.120396 0.2794)
			(stroke
				(width 0.1)
				(type default)
			)
			(layer "F.Fab")
		)
		(fp_line
			(start -0.12065 0.3048)
			(end -0.67945 0.3048)
			(stroke
				(width 0.1)
				(type default)
			)
			(layer "F.Fab")
		)
		(fp_line
			(start -0.67945 0.3048)
			(end -0.67945 -0.305054)
			(stroke
				(width 0.1)
				(type default)
			)
			(layer "F.Fab")
		)
		(pad "1" smd circle
			(at -0.40005 0 90)
			(size 0 0)
			(layers "F.Cu" "F.Mask" "F.Paste")
			(net "P3V3_AUX_SS")
		)
		(pad "2" smd circle
			(at 0.40005 0 90)
			(size 0 0)
			(layers "F.Cu" "F.Mask" "F.Paste")
			(net "GND")
		)
	)
	(footprint ""
		(layer "F.Cu")
		(at 284.589728 -413.23768 -90)
		(property "Reference" "R4551"
			(at 0 0 270)
			(layer "F.SilkS")
			(hide yes)
			(effects
				(font
					(size 1.27 1.27)
				)
			)
		)
		(property "Value" ""
			(at 0 0 270)
			(layer "F.Fab")
			(effects
				(font
					(size 1.27 1.27)
				)
			)
		)
		(duplicate_pad_numbers_are_jumpers no)
		(fp_line
			(start -0.7874 0.4064)
			(end -0.7874 -0.4064)
			(stroke
				(width 0.1524)
				(type default)
			)
			(layer "F.SilkS")
		)
		(fp_line
			(start 0.7874 0.4064)
			(end -0.7874 0.4064)
			(stroke
				(width 0.1524)
				(type default)
			)
			(layer "F.SilkS")
		)
		(fp_line
			(start -0.7874 -0.4064)
			(end 0.7874 -0.4064)
			(stroke
				(width 0.1524)
				(type default)
			)
			(layer "F.SilkS")
		)
		(fp_line
			(start 0.7874 -0.4064)
			(end 0.7874 0.4064)
			(stroke
				(width 0.1524)
				(type default)
			)
			(layer "F.SilkS")
		)
		(fp_line
			(start -0.67945 0.3048)
			(end -0.67945 -0.305054)
			(stroke
				(width 0.1)
				(type default)
			)
			(layer "F.Fab")
		)
		(fp_line
			(start -0.12065 0.3048)
			(end -0.67945 0.3048)
			(stroke
				(width 0.1)
				(type default)
			)
			(layer "F.Fab")
		)
		(fp_line
			(start 0.120396 0.3048)
			(end 0.120396 0.2794)
			(stroke
				(width 0.1)
				(type default)
			)
			(layer "F.Fab")
		)
		(fp_line
			(start 0.67945 0.3048)
			(end 0.120396 0.3048)
			(stroke
				(width 0.1)
				(type default)
			)
			(layer "F.Fab")
		)
		(fp_line
			(start -0.12065 0.2794)
			(end -0.12065 0.3048)
			(stroke
				(width 0.1)
				(type default)
			)
			(layer "F.Fab")
		)
		(fp_line
			(start 0.120396 0.2794)
			(end -0.12065 0.2794)
			(stroke
				(width 0.1)
				(type default)
			)
			(layer "F.Fab")
		)
		(fp_line
			(start -0.12065 -0.2794)
			(end 0.12065 -0.2794)
			(stroke
				(width 0.1)
				(type default)
			)
			(layer "F.Fab")
		)
		(fp_line
			(start 0.12065 -0.2794)
			(end 0.12065 -0.3048)
			(stroke
				(width 0.1)
				(type default)
			)
			(layer "F.Fab")
		)
		(fp_line
			(start 0.12065 -0.3048)
			(end 0.67945 -0.3048)
			(stroke
				(width 0.1)
				(type default)
			)
			(layer "F.Fab")
		)
		(fp_line
			(start 0.67945 -0.3048)
			(end 0.67945 0.3048)
			(stroke
				(width 0.1)
				(type default)
			)
			(layer "F.Fab")
		)
		(fp_line
			(start -0.67945 -0.305054)
			(end -0.12065 -0.305054)
			(stroke
				(width 0.1)
				(type default)
			)
			(layer "F.Fab")
		)
		(fp_line
			(start -0.12065 -0.305054)
			(end -0.12065 -0.2794)
			(stroke
				(width 0.1)
				(type default)
			)
			(layer "F.Fab")
		)
		(pad "1" smd circle
			(at -0.40005 0 270)
			(size 0 0)
			(layers "F.Cu" "F.Mask" "F.Paste")
			(net "P3V3_AUX")
		)
		(pad "2" smd circle
			(at 0.40005 0 270)
			(size 0 0)
			(layers "F.Cu" "F.Mask" "F.Paste")
			(net "HPDB_HSC_PWRGD")
		)
	)
	(footprint ""
		(layer "F.Cu")
		(at 162.573462 -22.36089)
		(property "Reference" "R4151"
			(at 0 0 0)
			(layer "F.SilkS")
			(hide yes)
			(effects
				(font
					(size 1.27 1.27)
				)
			)
		)
		(property "Value" ""
			(at 0 0 0)
			(layer "F.Fab")
			(effects
				(font
					(size 1.27 1.27)
				)
			)
		)
		(duplicate_pad_numbers_are_jumpers no)
		(fp_line
			(start -0.7874 -0.4064)
			(end 0.7874 -0.4064)
			(stroke
				(width 0.1524)
				(type default)
			)
			(layer "F.SilkS")
		)
		(fp_line
			(start -0.7874 0.4064)
			(end -0.7874 -0.4064)
			(stroke
				(width 0.1524)
				(type default)
			)
			(layer "F.SilkS")
		)
		(fp_line
			(start 0.7874 -0.4064)
			(end 0.7874 0.4064)
			(stroke
				(width 0.1524)
				(type default)
			)
			(layer "F.SilkS")
		)
		(fp_line
			(start 0.7874 0.4064)
			(end -0.7874 0.4064)
			(stroke
				(width 0.1524)
				(type default)
			)
			(layer "F.SilkS")
		)
		(fp_line
			(start -0.67945 -0.305054)
			(end -0.12065 -0.305054)
			(stroke
				(width 0.1)
				(type default)
			)
			(layer "F.Fab")
		)
		(fp_line
			(start -0.67945 0.3048)
			(end -0.67945 -0.305054)
			(stroke
				(width 0.1)
				(type default)
			)
			(layer "F.Fab")
		)
		(fp_line
			(start -0.12065 -0.305054)
			(end -0.12065 -0.2794)
			(stroke
				(width 0.1)
				(type default)
			)
			(layer "F.Fab")
		)
		(fp_line
			(start -0.12065 -0.2794)
			(end 0.12065 -0.2794)
			(stroke
				(width 0.1)
				(type default)
			)
			(layer "F.Fab")
		)
		(fp_line
			(start -0.12065 0.2794)
			(end -0.12065 0.3048)
			(stroke
				(width 0.1)
				(type default)
			)
			(layer "F.Fab")
		)
		(fp_line
			(start -0.12065 0.3048)
			(end -0.67945 0.3048)
			(stroke
				(width 0.1)
				(type default)
			)
			(layer "F.Fab")
		)
		(fp_line
			(start 0.120396 0.2794)
			(end -0.12065 0.2794)
			(stroke
				(width 0.1)
				(type default)
			)
			(layer "F.Fab")
		)
		(fp_line
			(start 0.120396 0.3048)
			(end 0.120396 0.2794)
			(stroke
				(width 0.1)
				(type default)
			)
			(layer "F.Fab")
		)
		(fp_line
			(start 0.12065 -0.3048)
			(end 0.67945 -0.3048)
			(stroke
				(width 0.1)
				(type default)
			)
			(layer "F.Fab")
		)
		(fp_line
			(start 0.12065 -0.2794)
			(end 0.12065 -0.3048)
			(stroke
				(width 0.1)
				(type default)
			)
			(layer "F.Fab")
		)
		(fp_line
			(start 0.67945 -0.3048)
			(end 0.67945 0.3048)
			(stroke
				(width 0.1)
				(type default)
			)
			(layer "F.Fab")
		)
		(fp_line
			(start 0.67945 0.3048)
			(end 0.120396 0.3048)
			(stroke
				(width 0.1)
				(type default)
			)
			(layer "F.Fab")
		)
		(pad "1" smd circle
			(at -0.40005 0)
			(size 0 0)
			(layers "F.Cu" "F.Mask" "F.Paste")
			(net "SMB_1_PLD_3V3AUX_SCL")
		)
		(pad "2" smd circle
			(at 0.40005 0)
			(size 0 0)
			(layers "F.Cu" "F.Mask" "F.Paste")
			(net "SMB_2_PLD_3V3AUX_SCL_R1")
		)
	)
	(footprint ""
		(layer "F.Cu")
		(at 86.311994 -31.667958 90)
		(property "Reference" "R4602"
			(at 0 0 90)
			(layer "F.SilkS")
			(hide yes)
			(effects
				(font
					(size 1.27 1.27)
				)
			)
		)
		(property "Value" ""
			(at 0 0 90)
			(layer "F.Fab")
			(effects
				(font
					(size 1.27 1.27)
				)
			)
		)
		(duplicate_pad_numbers_are_jumpers no)
		(fp_line
			(start 0.7874 -0.4064)
			(end 0.7874 0.4064)
			(stroke
				(width 0.1524)
				(type default)
			)
			(layer "F.SilkS")
		)
		(fp_line
			(start -0.7874 -0.4064)
			(end 0.7874 -0.4064)
			(stroke
				(width 0.1524)
				(type default)
			)
			(layer "F.SilkS")
		)
		(fp_line
			(start 0.7874 0.4064)
			(end -0.7874 0.4064)
			(stroke
				(width 0.1524)
				(type default)
			)
			(layer "F.SilkS")
		)
		(fp_line
			(start -0.7874 0.4064)
			(end -0.7874 -0.4064)
			(stroke
				(width 0.1524)
				(type default)
			)
			(layer "F.SilkS")
		)
		(fp_line
			(start -0.12065 -0.305054)
			(end -0.12065 -0.2794)
			(stroke
				(width 0.1)
				(type default)
			)
			(layer "F.Fab")
		)
		(fp_line
			(start -0.67945 -0.305054)
			(end -0.12065 -0.305054)
			(stroke
				(width 0.1)
				(type default)
			)
			(layer "F.Fab")
		)
		(fp_line
			(start 0.67945 -0.3048)
			(end 0.67945 0.3048)
			(stroke
				(width 0.1)
				(type default)
			)
			(layer "F.Fab")
		)
		(fp_line
			(start 0.12065 -0.3048)
			(end 0.67945 -0.3048)
			(stroke
				(width 0.1)
				(type default)
			)
			(layer "F.Fab")
		)
		(fp_line
			(start 0.12065 -0.2794)
			(end 0.12065 -0.3048)
			(stroke
				(width 0.1)
				(type default)
			)
			(layer "F.Fab")
		)
		(fp_line
			(start -0.12065 -0.2794)
			(end 0.12065 -0.2794)
			(stroke
				(width 0.1)
				(type default)
			)
			(layer "F.Fab")
		)
		(fp_line
			(start 0.120396 0.2794)
			(end -0.12065 0.2794)
			(stroke
				(width 0.1)
				(type default)
			)
			(layer "F.Fab")
		)
		(fp_line
			(start -0.12065 0.2794)
			(end -0.12065 0.3048)
			(stroke
				(width 0.1)
				(type default)
			)
			(layer "F.Fab")
		)
		(fp_line
			(start 0.67945 0.3048)
			(end 0.120396 0.3048)
			(stroke
				(width 0.1)
				(type default)
			)
			(layer "F.Fab")
		)
		(fp_line
			(start 0.120396 0.3048)
			(end 0.120396 0.2794)
			(stroke
				(width 0.1)
				(type default)
			)
			(layer "F.Fab")
		)
		(fp_line
			(start -0.12065 0.3048)
			(end -0.67945 0.3048)
			(stroke
				(width 0.1)
				(type default)
			)
			(layer "F.Fab")
		)
		(fp_line
			(start -0.67945 0.3048)
			(end -0.67945 -0.305054)
			(stroke
				(width 0.1)
				(type default)
			)
			(layer "F.Fab")
		)
		(pad "1" smd circle
			(at -0.40005 0 90)
			(size 0 0)
			(layers "F.Cu" "F.Mask" "F.Paste")
			(net "CLK_50M_NCSI_OCP_V3_2_ISO")
		)
		(pad "2" smd circle
			(at 0.40005 0 90)
			(size 0 0)
			(layers "F.Cu" "F.Mask" "F.Paste")
			(net "CLK_50M_NCSI_OCP_V3_2_ISO_R")
		)
	)
	(footprint ""
		(layer "F.Cu")
		(at 113.28908 -397.874998 -90)
		(property "Reference" "R3514"
			(at 0 0 270)
			(layer "F.SilkS")
			(hide yes)
			(effects
				(font
					(size 1.27 1.27)
				)
			)
		)
		(property "Value" ""
			(at 0 0 270)
			(layer "F.Fab")
			(effects
				(font
					(size 1.27 1.27)
				)
			)
		)
		(duplicate_pad_numbers_are_jumpers no)
		(fp_line
			(start -0.7874 0.4064)
			(end -0.7874 -0.4064)
			(stroke
				(width 0.1524)
				(type default)
			)
			(layer "F.SilkS")
		)
		(fp_line
			(start 0.7874 0.4064)
			(end -0.7874 0.4064)
			(stroke
				(width 0.1524)
				(type default)
			)
			(layer "F.SilkS")
		)
		(fp_line
			(start -0.7874 -0.4064)
			(end 0.7874 -0.4064)
			(stroke
				(width 0.1524)
				(type default)
			)
			(layer "F.SilkS")
		)
		(fp_line
			(start 0.7874 -0.4064)
			(end 0.7874 0.4064)
			(stroke
				(width 0.1524)
				(type default)
			)
			(layer "F.SilkS")
		)
		(fp_line
			(start -0.67945 0.3048)
			(end -0.67945 -0.305054)
			(stroke
				(width 0.1)
				(type default)
			)
			(layer "F.Fab")
		)
		(fp_line
			(start -0.12065 0.3048)
			(end -0.67945 0.3048)
			(stroke
				(width 0.1)
				(type default)
			)
			(layer "F.Fab")
		)
		(fp_line
			(start 0.120396 0.3048)
			(end 0.120396 0.2794)
			(stroke
				(width 0.1)
				(type default)
			)
			(layer "F.Fab")
		)
		(fp_line
			(start 0.67945 0.3048)
			(end 0.120396 0.3048)
			(stroke
				(width 0.1)
				(type default)
			)
			(layer "F.Fab")
		)
		(fp_line
			(start -0.12065 0.2794)
			(end -0.12065 0.3048)
			(stroke
				(width 0.1)
				(type default)
			)
			(layer "F.Fab")
		)
		(fp_line
			(start 0.120396 0.2794)
			(end -0.12065 0.2794)
			(stroke
				(width 0.1)
				(type default)
			)
			(layer "F.Fab")
		)
		(fp_line
			(start -0.12065 -0.2794)
			(end 0.12065 -0.2794)
			(stroke
				(width 0.1)
				(type default)
			)
			(layer "F.Fab")
		)
		(fp_line
			(start 0.12065 -0.2794)
			(end 0.12065 -0.3048)
			(stroke
				(width 0.1)
				(type default)
			)
			(layer "F.Fab")
		)
		(fp_line
			(start 0.12065 -0.3048)
			(end 0.67945 -0.3048)
			(stroke
				(width 0.1)
				(type default)
			)
			(layer "F.Fab")
		)
		(fp_line
			(start 0.67945 -0.3048)
			(end 0.67945 0.3048)
			(stroke
				(width 0.1)
				(type default)
			)
			(layer "F.Fab")
		)
		(fp_line
			(start -0.67945 -0.305054)
			(end -0.12065 -0.305054)
			(stroke
				(width 0.1)
				(type default)
			)
			(layer "F.Fab")
		)
		(fp_line
			(start -0.12065 -0.305054)
			(end -0.12065 -0.2794)
			(stroke
				(width 0.1)
				(type default)
			)
			(layer "F.Fab")
		)
		(pad "1" smd circle
			(at -0.40005 0 270)
			(size 0 0)
			(layers "F.Cu" "F.Mask" "F.Paste")
			(net "P3V3_AUX")
		)
		(pad "2" smd circle
			(at 0.40005 0 270)
			(size 0 0)
			(layers "F.Cu" "F.Mask" "F.Paste")
			(net "FM_SMB_2_ALERT_GPU_N")
		)
	)
	(footprint ""
		(layer "F.Cu")
		(at 176.317148 -358.12476)
		(property "Reference" "PC724_P1_1"
			(at 0 0 0)
			(layer "F.SilkS")
			(hide yes)
			(effects
				(font
					(size 1.27 1.27)
				)
			)
		)
		(property "Value" ""
			(at 0 0 0)
			(layer "F.Fab")
			(effects
				(font
					(size 1.27 1.27)
				)
			)
		)
		(duplicate_pad_numbers_are_jumpers no)
		(fp_line
			(start -1.524 -0.762)
			(end 1.524 -0.762)
			(stroke
				(width 0.1524)
				(type default)
			)
			(layer "F.SilkS")
		)
		(fp_line
			(start -1.524 0.762)
			(end -1.524 -0.762)
			(stroke
				(width 0.1524)
				(type default)
			)
			(layer "F.SilkS")
		)
		(fp_line
			(start 1.524 -0.762)
			(end 1.524 0.762)
			(stroke
				(width 0.1524)
				(type default)
			)
			(layer "F.SilkS")
		)
		(fp_line
			(start 1.524 0.762)
			(end -1.524 0.762)
			(stroke
				(width 0.1524)
				(type default)
			)
			(layer "F.SilkS")
		)
		(fp_line
			(start -1.1049 -0.724916)
			(end -1.1049 0.724916)
			(stroke
				(width 0.1)
				(type default)
			)
			(layer "F.Fab")
		)
		(fp_line
			(start -1.1049 0.724916)
			(end 1.1049 0.724916)
			(stroke
				(width 0.1)
				(type default)
			)
			(layer "F.Fab")
		)
		(fp_line
			(start 1.1049 -0.724916)
			(end -1.1049 -0.724916)
			(stroke
				(width 0.1)
				(type default)
			)
			(layer "F.Fab")
		)
		(fp_line
			(start 1.1049 0.724916)
			(end 1.1049 -0.724916)
			(stroke
				(width 0.1)
				(type default)
			)
			(layer "F.Fab")
		)
		(pad "1" smd rect
			(at -0.889 0 180)
			(size 1.016 1.27)
			(layers "F.Cu" "F.Mask" "F.Paste")
			(net "SW_P12V_PVCCFA_EHV_FIVRA_CPU1_R")
		)
		(pad "2" smd rect
			(at 0.889 0 180)
			(size 1.016 1.27)
			(layers "F.Cu" "F.Mask" "F.Paste")
			(net "GND")
		)
	)
	(footprint ""
		(layer "F.Cu")
		(at 142.0622 -106.364278 90)
		(property "Reference" "R4041"
			(at 0 0 90)
			(layer "F.SilkS")
			(hide yes)
			(effects
				(font
					(size 1.27 1.27)
				)
			)
		)
		(property "Value" ""
			(at 0 0 90)
			(layer "F.Fab")
			(effects
				(font
					(size 1.27 1.27)
				)
			)
		)
		(duplicate_pad_numbers_are_jumpers no)
		(fp_line
			(start 0.7874 -0.4064)
			(end 0.7874 0.4064)
			(stroke
				(width 0.1524)
				(type default)
			)
			(layer "F.SilkS")
		)
		(fp_line
			(start -0.7874 -0.4064)
			(end 0.7874 -0.4064)
			(stroke
				(width 0.1524)
				(type default)
			)
			(layer "F.SilkS")
		)
		(fp_line
			(start 0.7874 0.4064)
			(end -0.7874 0.4064)
			(stroke
				(width 0.1524)
				(type default)
			)
			(layer "F.SilkS")
		)
		(fp_line
			(start -0.7874 0.4064)
			(end -0.7874 -0.4064)
			(stroke
				(width 0.1524)
				(type default)
			)
			(layer "F.SilkS")
		)
		(fp_line
			(start -0.12065 -0.305054)
			(end -0.12065 -0.2794)
			(stroke
				(width 0.1)
				(type default)
			)
			(layer "F.Fab")
		)
		(fp_line
			(start -0.67945 -0.305054)
			(end -0.12065 -0.305054)
			(stroke
				(width 0.1)
				(type default)
			)
			(layer "F.Fab")
		)
		(fp_line
			(start 0.67945 -0.3048)
			(end 0.67945 0.3048)
			(stroke
				(width 0.1)
				(type default)
			)
			(layer "F.Fab")
		)
		(fp_line
			(start 0.12065 -0.3048)
			(end 0.67945 -0.3048)
			(stroke
				(width 0.1)
				(type default)
			)
			(layer "F.Fab")
		)
		(fp_line
			(start 0.12065 -0.2794)
			(end 0.12065 -0.3048)
			(stroke
				(width 0.1)
				(type default)
			)
			(layer "F.Fab")
		)
		(fp_line
			(start -0.12065 -0.2794)
			(end 0.12065 -0.2794)
			(stroke
				(width 0.1)
				(type default)
			)
			(layer "F.Fab")
		)
		(fp_line
			(start 0.120396 0.2794)
			(end -0.12065 0.2794)
			(stroke
				(width 0.1)
				(type default)
			)
			(layer "F.Fab")
		)
		(fp_line
			(start -0.12065 0.2794)
			(end -0.12065 0.3048)
			(stroke
				(width 0.1)
				(type default)
			)
			(layer "F.Fab")
		)
		(fp_line
			(start 0.67945 0.3048)
			(end 0.120396 0.3048)
			(stroke
				(width 0.1)
				(type default)
			)
			(layer "F.Fab")
		)
		(fp_line
			(start 0.120396 0.3048)
			(end 0.120396 0.2794)
			(stroke
				(width 0.1)
				(type default)
			)
			(layer "F.Fab")
		)
		(fp_line
			(start -0.12065 0.3048)
			(end -0.67945 0.3048)
			(stroke
				(width 0.1)
				(type default)
			)
			(layer "F.Fab")
		)
		(fp_line
			(start -0.67945 0.3048)
			(end -0.67945 -0.305054)
			(stroke
				(width 0.1)
				(type default)
			)
			(layer "F.Fab")
		)
		(pad "1" smd circle
			(at -0.40005 0 90)
			(size 0 0)
			(layers "F.Cu" "F.Mask" "F.Paste")
			(net "P0V62_CPU0_ERRS_U306_VREF")
		)
		(pad "2" smd circle
			(at 0.40005 0 90)
			(size 0 0)
			(layers "F.Cu" "F.Mask" "F.Paste")
			(net "GND")
		)
	)
	(footprint ""
		(layer "F.Cu")
		(at 184.183782 -40.840152 180)
		(property "Reference" "R3997"
			(at 0 0 180)
			(layer "F.SilkS")
			(hide yes)
			(effects
				(font
					(size 1.27 1.27)
				)
			)
		)
		(property "Value" ""
			(at 0 0 180)
			(layer "F.Fab")
			(effects
				(font
					(size 1.27 1.27)
				)
			)
		)
		(duplicate_pad_numbers_are_jumpers no)
		(fp_line
			(start 0.7874 0.4064)
			(end -0.7874 0.4064)
			(stroke
				(width 0.1524)
				(type default)
			)
			(layer "F.SilkS")
		)
		(fp_line
			(start 0.7874 -0.4064)
			(end 0.7874 0.4064)
			(stroke
				(width 0.1524)
				(type default)
			)
			(layer "F.SilkS")
		)
		(fp_line
			(start -0.7874 0.4064)
			(end -0.7874 -0.4064)
			(stroke
				(width 0.1524)
				(type default)
			)
			(layer "F.SilkS")
		)
		(fp_line
			(start -0.7874 -0.4064)
			(end 0.7874 -0.4064)
			(stroke
				(width 0.1524)
				(type default)
			)
			(layer "F.SilkS")
		)
		(fp_line
			(start 0.67945 0.3048)
			(end 0.120396 0.3048)
			(stroke
				(width 0.1)
				(type default)
			)
			(layer "F.Fab")
		)
		(fp_line
			(start 0.67945 -0.3048)
			(end 0.67945 0.3048)
			(stroke
				(width 0.1)
				(type default)
			)
			(layer "F.Fab")
		)
		(fp_line
			(start 0.12065 -0.2794)
			(end 0.12065 -0.3048)
			(stroke
				(width 0.1)
				(type default)
			)
			(layer "F.Fab")
		)
		(fp_line
			(start 0.12065 -0.3048)
			(end 0.67945 -0.3048)
			(stroke
				(width 0.1)
				(type default)
			)
			(layer "F.Fab")
		)
		(fp_line
			(start 0.120396 0.3048)
			(end 0.120396 0.2794)
			(stroke
				(width 0.1)
				(type default)
			)
			(layer "F.Fab")
		)
		(fp_line
			(start 0.120396 0.2794)
			(end -0.12065 0.2794)
			(stroke
				(width 0.1)
				(type default)
			)
			(layer "F.Fab")
		)
		(fp_line
			(start -0.12065 0.3048)
			(end -0.67945 0.3048)
			(stroke
				(width 0.1)
				(type default)
			)
			(layer "F.Fab")
		)
		(fp_line
			(start -0.12065 0.2794)
			(end -0.12065 0.3048)
			(stroke
				(width 0.1)
				(type default)
			)
			(layer "F.Fab")
		)
		(fp_line
			(start -0.12065 -0.2794)
			(end 0.12065 -0.2794)
			(stroke
				(width 0.1)
				(type default)
			)
			(layer "F.Fab")
		)
		(fp_line
			(start -0.12065 -0.305054)
			(end -0.12065 -0.2794)
			(stroke
				(width 0.1)
				(type default)
			)
			(layer "F.Fab")
		)
		(fp_line
			(start -0.67945 0.3048)
			(end -0.67945 -0.305054)
			(stroke
				(width 0.1)
				(type default)
			)
			(layer "F.Fab")
		)
		(fp_line
			(start -0.67945 -0.305054)
			(end -0.12065 -0.305054)
			(stroke
				(width 0.1)
				(type default)
			)
			(layer "F.Fab")
		)
		(pad "1" smd circle
			(at -0.40005 0 180)
			(size 0 0)
			(layers "F.Cu" "F.Mask" "F.Paste")
			(net "P12V_SCM_UV_R")
		)
		(pad "2" smd circle
			(at 0.40005 0 180)
			(size 0 0)
			(layers "F.Cu" "F.Mask" "F.Paste")
			(net "P12V_SCM_UV")
		)
	)
	(footprint ""
		(layer "F.Cu")
		(at 196.07784 -92.832428 90)
		(property "Reference" "R4611"
			(at 0 0 90)
			(layer "F.SilkS")
			(hide yes)
			(effects
				(font
					(size 1.27 1.27)
				)
			)
		)
		(property "Value" ""
			(at 0 0 90)
			(layer "F.Fab")
			(effects
				(font
					(size 1.27 1.27)
				)
			)
		)
		(duplicate_pad_numbers_are_jumpers no)
		(fp_line
			(start 0.7874 -0.4064)
			(end 0.7874 0.4064)
			(stroke
				(width 0.1524)
				(type default)
			)
			(layer "F.SilkS")
		)
		(fp_line
			(start -0.7874 -0.4064)
			(end 0.7874 -0.4064)
			(stroke
				(width 0.1524)
				(type default)
			)
			(layer "F.SilkS")
		)
		(fp_line
			(start 0.7874 0.4064)
			(end -0.7874 0.4064)
			(stroke
				(width 0.1524)
				(type default)
			)
			(layer "F.SilkS")
		)
		(fp_line
			(start -0.7874 0.4064)
			(end -0.7874 -0.4064)
			(stroke
				(width 0.1524)
				(type default)
			)
			(layer "F.SilkS")
		)
		(fp_line
			(start -0.12065 -0.305054)
			(end -0.12065 -0.2794)
			(stroke
				(width 0.1)
				(type default)
			)
			(layer "F.Fab")
		)
		(fp_line
			(start -0.67945 -0.305054)
			(end -0.12065 -0.305054)
			(stroke
				(width 0.1)
				(type default)
			)
			(layer "F.Fab")
		)
		(fp_line
			(start 0.67945 -0.3048)
			(end 0.67945 0.3048)
			(stroke
				(width 0.1)
				(type default)
			)
			(layer "F.Fab")
		)
		(fp_line
			(start 0.12065 -0.3048)
			(end 0.67945 -0.3048)
			(stroke
				(width 0.1)
				(type default)
			)
			(layer "F.Fab")
		)
		(fp_line
			(start 0.12065 -0.2794)
			(end 0.12065 -0.3048)
			(stroke
				(width 0.1)
				(type default)
			)
			(layer "F.Fab")
		)
		(fp_line
			(start -0.12065 -0.2794)
			(end 0.12065 -0.2794)
			(stroke
				(width 0.1)
				(type default)
			)
			(layer "F.Fab")
		)
		(fp_line
			(start 0.120396 0.2794)
			(end -0.12065 0.2794)
			(stroke
				(width 0.1)
				(type default)
			)
			(layer "F.Fab")
		)
		(fp_line
			(start -0.12065 0.2794)
			(end -0.12065 0.3048)
			(stroke
				(width 0.1)
				(type default)
			)
			(layer "F.Fab")
		)
		(fp_line
			(start 0.67945 0.3048)
			(end 0.120396 0.3048)
			(stroke
				(width 0.1)
				(type default)
			)
			(layer "F.Fab")
		)
		(fp_line
			(start 0.120396 0.3048)
			(end 0.120396 0.2794)
			(stroke
				(width 0.1)
				(type default)
			)
			(layer "F.Fab")
		)
		(fp_line
			(start -0.12065 0.3048)
			(end -0.67945 0.3048)
			(stroke
				(width 0.1)
				(type default)
			)
			(layer "F.Fab")
		)
		(fp_line
			(start -0.67945 0.3048)
			(end -0.67945 -0.305054)
			(stroke
				(width 0.1)
				(type default)
			)
			(layer "F.Fab")
		)
		(pad "1" smd circle
			(at -0.40005 0 90)
			(size 0 0)
			(layers "F.Cu" "F.Mask" "F.Paste")
			(net "FM_BMC_CPU_FBRK_OUT_R_N")
		)
		(pad "2" smd circle
			(at 0.40005 0 90)
			(size 0 0)
			(layers "F.Cu" "F.Mask" "F.Paste")
			(net "FM_BMC_CPU_FBRK_OUT_N")
		)
	)
	(footprint ""
		(layer "F.Cu")
		(at 115.75288 -104.079548 90)
		(property "Reference" "C2249"
			(at 0 0 90)
			(layer "F.SilkS")
			(hide yes)
			(effects
				(font
					(size 1.27 1.27)
				)
			)
		)
		(property "Value" ""
			(at 0 0 90)
			(layer "F.Fab")
			(effects
				(font
					(size 1.27 1.27)
				)
			)
		)
		(duplicate_pad_numbers_are_jumpers no)
		(fp_line
			(start 0.7874 -0.4064)
			(end 0.7874 0.4064)
			(stroke
				(width 0.1524)
				(type default)
			)
			(layer "F.SilkS")
		)
		(fp_line
			(start -0.7874 -0.4064)
			(end 0.7874 -0.4064)
			(stroke
				(width 0.1524)
				(type default)
			)
			(layer "F.SilkS")
		)
		(fp_line
			(start 0.7874 0.4064)
			(end -0.7874 0.4064)
			(stroke
				(width 0.1524)
				(type default)
			)
			(layer "F.SilkS")
		)
		(fp_line
			(start -0.7874 0.4064)
			(end -0.7874 -0.4064)
			(stroke
				(width 0.1524)
				(type default)
			)
			(layer "F.SilkS")
		)
		(fp_line
			(start -0.12065 -0.305054)
			(end -0.12065 -0.2794)
			(stroke
				(width 0.1)
				(type default)
			)
			(layer "F.Fab")
		)
		(fp_line
			(start -0.67945 -0.305054)
			(end -0.12065 -0.305054)
			(stroke
				(width 0.1)
				(type default)
			)
			(layer "F.Fab")
		)
		(fp_line
			(start 0.67945 -0.3048)
			(end 0.67945 0.3048)
			(stroke
				(width 0.1)
				(type default)
			)
			(layer "F.Fab")
		)
		(fp_line
			(start 0.12065 -0.3048)
			(end 0.67945 -0.3048)
			(stroke
				(width 0.1)
				(type default)
			)
			(layer "F.Fab")
		)
		(fp_line
			(start 0.12065 -0.2794)
			(end 0.12065 -0.3048)
			(stroke
				(width 0.1)
				(type default)
			)
			(layer "F.Fab")
		)
		(fp_line
			(start -0.12065 -0.2794)
			(end 0.12065 -0.2794)
			(stroke
				(width 0.1)
				(type default)
			)
			(layer "F.Fab")
		)
		(fp_line
			(start 0.120396 0.2794)
			(end -0.12065 0.2794)
			(stroke
				(width 0.1)
				(type default)
			)
			(layer "F.Fab")
		)
		(fp_line
			(start -0.12065 0.2794)
			(end -0.12065 0.3048)
			(stroke
				(width 0.1)
				(type default)
			)
			(layer "F.Fab")
		)
		(fp_line
			(start 0.67945 0.3048)
			(end 0.120396 0.3048)
			(stroke
				(width 0.1)
				(type default)
			)
			(layer "F.Fab")
		)
		(fp_line
			(start 0.120396 0.3048)
			(end 0.120396 0.2794)
			(stroke
				(width 0.1)
				(type default)
			)
			(layer "F.Fab")
		)
		(fp_line
			(start -0.12065 0.3048)
			(end -0.67945 0.3048)
			(stroke
				(width 0.1)
				(type default)
			)
			(layer "F.Fab")
		)
		(fp_line
			(start -0.67945 0.3048)
			(end -0.67945 -0.305054)
			(stroke
				(width 0.1)
				(type default)
			)
			(layer "F.Fab")
		)
		(pad "1" smd circle
			(at -0.40005 0 90)
			(size 0 0)
			(layers "F.Cu" "F.Mask" "F.Paste")
			(net "P0V62_CPU0_ERRS_VREF")
		)
		(pad "2" smd circle
			(at 0.40005 0 90)
			(size 0 0)
			(layers "F.Cu" "F.Mask" "F.Paste")
			(net "GND")
		)
	)
	(footprint ""
		(layer "B.Cu")
		(at 37.599366 -192.924176 -90)
		(property "Reference" "R820"
			(at 0 0 90)
			(layer "B.SilkS")
			(hide yes)
			(effects
				(font
					(size 1.27 1.27)
				)
				(justify mirror)
			)
		)
		(property "Value" ""
			(at 0 0 90)
			(layer "B.Fab")
			(effects
				(font
					(size 1.27 1.27)
				)
				(justify mirror)
			)
		)
		(duplicate_pad_numbers_are_jumpers no)
		(fp_line
			(start -0.7874 0.4064)
			(end 0.7874 0.4064)
			(stroke
				(width 0.1524)
				(type default)
			)
			(layer "B.SilkS")
		)
		(fp_line
			(start 0.7874 0.4064)
			(end 0.7874 -0.4064)
			(stroke
				(width 0.1524)
				(type default)
			)
			(layer "B.SilkS")
		)
		(fp_line
			(start -0.7874 -0.4064)
			(end -0.7874 0.4064)
			(stroke
				(width 0.1524)
				(type default)
			)
			(layer "B.SilkS")
		)
		(fp_line
			(start 0.7874 -0.4064)
			(end -0.7874 -0.4064)
			(stroke
				(width 0.1524)
				(type default)
			)
			(layer "B.SilkS")
		)
		(fp_line
			(start -0.67945 0.3048)
			(end -0.120396 0.3048)
			(stroke
				(width 0.1)
				(type default)
			)
			(layer "B.Fab")
		)
		(fp_line
			(start -0.120396 0.3048)
			(end -0.120396 0.2794)
			(stroke
				(width 0.1)
				(type default)
			)
			(layer "B.Fab")
		)
		(fp_line
			(start 0.12065 0.3048)
			(end 0.67945 0.3048)
			(stroke
				(width 0.1)
				(type default)
			)
			(layer "B.Fab")
		)
		(fp_line
			(start 0.67945 0.3048)
			(end 0.67945 -0.305054)
			(stroke
				(width 0.1)
				(type default)
			)
			(layer "B.Fab")
		)
		(fp_line
			(start -0.120396 0.2794)
			(end 0.12065 0.2794)
			(stroke
				(width 0.1)
				(type default)
			)
			(layer "B.Fab")
		)
		(fp_line
			(start 0.12065 0.2794)
			(end 0.12065 0.3048)
			(stroke
				(width 0.1)
				(type default)
			)
			(layer "B.Fab")
		)
		(fp_line
			(start -0.12065 -0.2794)
			(end -0.12065 -0.3048)
			(stroke
				(width 0.1)
				(type default)
			)
			(layer "B.Fab")
		)
		(fp_line
			(start 0.12065 -0.2794)
			(end -0.12065 -0.2794)
			(stroke
				(width 0.1)
				(type default)
			)
			(layer "B.Fab")
		)
		(fp_line
			(start -0.67945 -0.3048)
			(end -0.67945 0.3048)
			(stroke
				(width 0.1)
				(type default)
			)
			(layer "B.Fab")
		)
		(fp_line
			(start -0.12065 -0.3048)
			(end -0.67945 -0.3048)
			(stroke
				(width 0.1)
				(type default)
			)
			(layer "B.Fab")
		)
		(fp_line
			(start 0.12065 -0.305054)
			(end 0.12065 -0.2794)
			(stroke
				(width 0.1)
				(type default)
			)
			(layer "B.Fab")
		)
		(fp_line
			(start 0.67945 -0.305054)
			(end 0.12065 -0.305054)
			(stroke
				(width 0.1)
				(type default)
			)
			(layer "B.Fab")
		)
		(pad "1" smd circle
			(at 0.40005 0 90)
			(size 0 0)
			(layers "B.Cu" "B.Mask" "B.Paste")
			(net "PVCCD_HV_CPU1")
		)
		(pad "2" smd circle
			(at -0.40005 0 90)
			(size 0 0)
			(layers "B.Cu" "B.Mask" "B.Paste")
			(net "RST_M_AB_CPU1_FPGA_N")
		)
	)
	(footprint ""
		(layer "B.Cu")
		(at 216.20988 -53.177948)
		(property "Reference" "C2067"
			(at 0 0 0)
			(layer "B.SilkS")
			(hide yes)
			(effects
				(font
					(size 1.27 1.27)
				)
				(justify mirror)
			)
		)
		(property "Value" ""
			(at 0 0 0)
			(layer "B.Fab")
			(effects
				(font
					(size 1.27 1.27)
				)
				(justify mirror)
			)
		)
		(duplicate_pad_numbers_are_jumpers no)
		(fp_line
			(start -0.7874 -0.4064)
			(end -0.7874 0.4064)
			(stroke
				(width 0.1524)
				(type default)
			)
			(layer "B.SilkS")
		)
		(fp_line
			(start -0.7874 0.4064)
			(end 0.7874 0.4064)
			(stroke
				(width 0.1524)
				(type default)
			)
			(layer "B.SilkS")
		)
		(fp_line
			(start 0.7874 -0.4064)
			(end -0.7874 -0.4064)
			(stroke
				(width 0.1524)
				(type default)
			)
			(layer "B.SilkS")
		)
		(fp_line
			(start 0.7874 0.4064)
			(end 0.7874 -0.4064)
			(stroke
				(width 0.1524)
				(type default)
			)
			(layer "B.SilkS")
		)
		(fp_line
			(start -0.67945 -0.3048)
			(end -0.67945 0.3048)
			(stroke
				(width 0.1)
				(type default)
			)
			(layer "B.Fab")
		)
		(fp_line
			(start -0.67945 0.3048)
			(end -0.120396 0.3048)
			(stroke
				(width 0.1)
				(type default)
			)
			(layer "B.Fab")
		)
		(fp_line
			(start -0.12065 -0.3048)
			(end -0.67945 -0.3048)
			(stroke
				(width 0.1)
				(type default)
			)
			(layer "B.Fab")
		)
		(fp_line
			(start -0.12065 -0.2794)
			(end -0.12065 -0.3048)
			(stroke
				(width 0.1)
				(type default)
			)
			(layer "B.Fab")
		)
		(fp_line
			(start -0.120396 0.2794)
			(end 0.12065 0.2794)
			(stroke
				(width 0.1)
				(type default)
			)
			(layer "B.Fab")
		)
		(fp_line
			(start -0.120396 0.3048)
			(end -0.120396 0.2794)
			(stroke
				(width 0.1)
				(type default)
			)
			(layer "B.Fab")
		)
		(fp_line
			(start 0.12065 -0.305054)
			(end 0.12065 -0.2794)
			(stroke
				(width 0.1)
				(type default)
			)
			(layer "B.Fab")
		)
		(fp_line
			(start 0.12065 -0.2794)
			(end -0.12065 -0.2794)
			(stroke
				(width 0.1)
				(type default)
			)
			(layer "B.Fab")
		)
		(fp_line
			(start 0.12065 0.2794)
			(end 0.12065 0.3048)
			(stroke
				(width 0.1)
				(type default)
			)
			(layer "B.Fab")
		)
		(fp_line
			(start 0.12065 0.3048)
			(end 0.67945 0.3048)
			(stroke
				(width 0.1)
				(type default)
			)
			(layer "B.Fab")
		)
		(fp_line
			(start 0.67945 -0.305054)
			(end 0.12065 -0.305054)
			(stroke
				(width 0.1)
				(type default)
			)
			(layer "B.Fab")
		)
		(fp_line
			(start 0.67945 0.3048)
			(end 0.67945 -0.305054)
			(stroke
				(width 0.1)
				(type default)
			)
			(layer "B.Fab")
		)
		(pad "1" smd circle
			(at 0.40005 0 180)
			(size 0 0)
			(layers "B.Cu" "B.Mask" "B.Paste")
			(net "P3V3_AUX")
		)
		(pad "2" smd circle
			(at -0.40005 0 180)
			(size 0 0)
			(layers "B.Cu" "B.Mask" "B.Paste")
			(net "GND")
		)
	)
	(footprint ""
		(layer "B.Cu")
		(at 338.016342 -50.678842 90)
		(property "Reference" "C1264"
			(at 0 0 90)
			(layer "B.SilkS")
			(hide yes)
			(effects
				(font
					(size 1.27 1.27)
				)
				(justify mirror)
			)
		)
		(property "Value" ""
			(at 0 0 90)
			(layer "B.Fab")
			(effects
				(font
					(size 1.27 1.27)
				)
				(justify mirror)
			)
		)
		(duplicate_pad_numbers_are_jumpers no)
		(fp_line
			(start 0.7874 -0.4064)
			(end -0.7874 -0.4064)
			(stroke
				(width 0.1524)
				(type default)
			)
			(layer "B.SilkS")
		)
		(fp_line
			(start -0.7874 -0.4064)
			(end -0.7874 0.4064)
			(stroke
				(width 0.1524)
				(type default)
			)
			(layer "B.SilkS")
		)
		(fp_line
			(start 0.7874 0.4064)
			(end 0.7874 -0.4064)
			(stroke
				(width 0.1524)
				(type default)
			)
			(layer "B.SilkS")
		)
		(fp_line
			(start -0.7874 0.4064)
			(end 0.7874 0.4064)
			(stroke
				(width 0.1524)
				(type default)
			)
			(layer "B.SilkS")
		)
		(fp_line
			(start 0.67945 -0.305054)
			(end 0.12065 -0.305054)
			(stroke
				(width 0.1)
				(type default)
			)
			(layer "B.Fab")
		)
		(fp_line
			(start 0.12065 -0.305054)
			(end 0.12065 -0.2794)
			(stroke
				(width 0.1)
				(type default)
			)
			(layer "B.Fab")
		)
		(fp_line
			(start -0.12065 -0.3048)
			(end -0.67945 -0.3048)
			(stroke
				(width 0.1)
				(type default)
			)
			(layer "B.Fab")
		)
		(fp_line
			(start -0.67945 -0.3048)
			(end -0.67945 0.3048)
			(stroke
				(width 0.1)
				(type default)
			)
			(layer "B.Fab")
		)
		(fp_line
			(start 0.12065 -0.2794)
			(end -0.12065 -0.2794)
			(stroke
				(width 0.1)
				(type default)
			)
			(layer "B.Fab")
		)
		(fp_line
			(start -0.12065 -0.2794)
			(end -0.12065 -0.3048)
			(stroke
				(width 0.1)
				(type default)
			)
			(layer "B.Fab")
		)
		(fp_line
			(start 0.12065 0.2794)
			(end 0.12065 0.3048)
			(stroke
				(width 0.1)
				(type default)
			)
			(layer "B.Fab")
		)
		(fp_line
			(start -0.120396 0.2794)
			(end 0.12065 0.2794)
			(stroke
				(width 0.1)
				(type default)
			)
			(layer "B.Fab")
		)
		(fp_line
			(start 0.67945 0.3048)
			(end 0.67945 -0.305054)
			(stroke
				(width 0.1)
				(type default)
			)
			(layer "B.Fab")
		)
		(fp_line
			(start 0.12065 0.3048)
			(end 0.67945 0.3048)
			(stroke
				(width 0.1)
				(type default)
			)
			(layer "B.Fab")
		)
		(fp_line
			(start -0.120396 0.3048)
			(end -0.120396 0.2794)
			(stroke
				(width 0.1)
				(type default)
			)
			(layer "B.Fab")
		)
		(fp_line
			(start -0.67945 0.3048)
			(end -0.120396 0.3048)
			(stroke
				(width 0.1)
				(type default)
			)
			(layer "B.Fab")
		)
		(pad "1" smd circle
			(at 0.40005 0 270)
			(size 0 0)
			(layers "B.Cu" "B.Mask" "B.Paste")
			(net "P1V05_PCH_PLL_AUX")
		)
		(pad "2" smd circle
			(at -0.40005 0 270)
			(size 0 0)
			(layers "B.Cu" "B.Mask" "B.Paste")
			(net "GND")
		)
	)
	(footprint ""
		(layer "B.Cu")
		(at 24.877522 -165.059106 180)
		(property "Reference" "PR4253"
			(at 0 0 0)
			(layer "B.SilkS")
			(hide yes)
			(effects
				(font
					(size 1.27 1.27)
				)
				(justify mirror)
			)
		)
		(property "Value" ""
			(at 0 0 0)
			(layer "B.Fab")
			(effects
				(font
					(size 1.27 1.27)
				)
				(justify mirror)
			)
		)
		(duplicate_pad_numbers_are_jumpers no)
		(fp_line
			(start 0.7874 0.4064)
			(end 0.7874 -0.4064)
			(stroke
				(width 0.1524)
				(type default)
			)
			(layer "B.SilkS")
		)
		(fp_line
			(start 0.7874 -0.4064)
			(end -0.7874 -0.4064)
			(stroke
				(width 0.1524)
				(type default)
			)
			(layer "B.SilkS")
		)
		(fp_line
			(start -0.7874 0.4064)
			(end 0.7874 0.4064)
			(stroke
				(width 0.1524)
				(type default)
			)
			(layer "B.SilkS")
		)
		(fp_line
			(start -0.7874 -0.4064)
			(end -0.7874 0.4064)
			(stroke
				(width 0.1524)
				(type default)
			)
			(layer "B.SilkS")
		)
		(fp_line
			(start 0.67945 0.3048)
			(end 0.67945 -0.305054)
			(stroke
				(width 0.1)
				(type default)
			)
			(layer "B.Fab")
		)
		(fp_line
			(start 0.67945 -0.305054)
			(end 0.12065 -0.305054)
			(stroke
				(width 0.1)
				(type default)
			)
			(layer "B.Fab")
		)
		(fp_line
			(start 0.12065 0.3048)
			(end 0.67945 0.3048)
			(stroke
				(width 0.1)
				(type default)
			)
			(layer "B.Fab")
		)
		(fp_line
			(start 0.12065 0.2794)
			(end 0.12065 0.3048)
			(stroke
				(width 0.1)
				(type default)
			)
			(layer "B.Fab")
		)
		(fp_line
			(start 0.12065 -0.2794)
			(end -0.12065 -0.2794)
			(stroke
				(width 0.1)
				(type default)
			)
			(layer "B.Fab")
		)
		(fp_line
			(start 0.12065 -0.305054)
			(end 0.12065 -0.2794)
			(stroke
				(width 0.1)
				(type default)
			)
			(layer "B.Fab")
		)
		(fp_line
			(start -0.120396 0.3048)
			(end -0.120396 0.2794)
			(stroke
				(width 0.1)
				(type default)
			)
			(layer "B.Fab")
		)
		(fp_line
			(start -0.120396 0.2794)
			(end 0.12065 0.2794)
			(stroke
				(width 0.1)
				(type default)
			)
			(layer "B.Fab")
		)
		(fp_line
			(start -0.12065 -0.2794)
			(end -0.12065 -0.3048)
			(stroke
				(width 0.1)
				(type default)
			)
			(layer "B.Fab")
		)
		(fp_line
			(start -0.12065 -0.3048)
			(end -0.67945 -0.3048)
			(stroke
				(width 0.1)
				(type default)
			)
			(layer "B.Fab")
		)
		(fp_line
			(start -0.67945 0.3048)
			(end -0.120396 0.3048)
			(stroke
				(width 0.1)
				(type default)
			)
			(layer "B.Fab")
		)
		(fp_line
			(start -0.67945 -0.3048)
			(end -0.67945 0.3048)
			(stroke
				(width 0.1)
				(type default)
			)
			(layer "B.Fab")
		)
		(pad "1" smd circle
			(at 0.40005 0)
			(size 0 0)
			(layers "B.Cu" "B.Mask" "B.Paste")
			(net "NC_PVCCD_HV_CPU1_ACSP4")
		)
		(pad "2" smd circle
			(at -0.40005 0)
			(size 0 0)
			(layers "B.Cu" "B.Mask" "B.Paste")
			(net "GND")
		)
	)
	(footprint ""
		(layer "B.Cu")
		(at 110.922054 -334.703166 -90)
		(property "Reference" "PR300"
			(at 0 0 90)
			(layer "B.SilkS")
			(hide yes)
			(effects
				(font
					(size 1.27 1.27)
				)
				(justify mirror)
			)
		)
		(property "Value" ""
			(at 0 0 90)
			(layer "B.Fab")
			(effects
				(font
					(size 1.27 1.27)
				)
				(justify mirror)
			)
		)
		(duplicate_pad_numbers_are_jumpers no)
		(fp_line
			(start -0.7874 0.4064)
			(end 0.7874 0.4064)
			(stroke
				(width 0.1524)
				(type default)
			)
			(layer "B.SilkS")
		)
		(fp_line
			(start 0.7874 0.4064)
			(end 0.7874 -0.4064)
			(stroke
				(width 0.1524)
				(type default)
			)
			(layer "B.SilkS")
		)
		(fp_line
			(start -0.7874 -0.4064)
			(end -0.7874 0.4064)
			(stroke
				(width 0.1524)
				(type default)
			)
			(layer "B.SilkS")
		)
		(fp_line
			(start 0.7874 -0.4064)
			(end -0.7874 -0.4064)
			(stroke
				(width 0.1524)
				(type default)
			)
			(layer "B.SilkS")
		)
		(fp_line
			(start -0.67945 0.3048)
			(end -0.120396 0.3048)
			(stroke
				(width 0.1)
				(type default)
			)
			(layer "B.Fab")
		)
		(fp_line
			(start -0.120396 0.3048)
			(end -0.120396 0.2794)
			(stroke
				(width 0.1)
				(type default)
			)
			(layer "B.Fab")
		)
		(fp_line
			(start 0.12065 0.3048)
			(end 0.67945 0.3048)
			(stroke
				(width 0.1)
				(type default)
			)
			(layer "B.Fab")
		)
		(fp_line
			(start 0.67945 0.3048)
			(end 0.67945 -0.305054)
			(stroke
				(width 0.1)
				(type default)
			)
			(layer "B.Fab")
		)
		(fp_line
			(start -0.120396 0.2794)
			(end 0.12065 0.2794)
			(stroke
				(width 0.1)
				(type default)
			)
			(layer "B.Fab")
		)
		(fp_line
			(start 0.12065 0.2794)
			(end 0.12065 0.3048)
			(stroke
				(width 0.1)
				(type default)
			)
			(layer "B.Fab")
		)
		(fp_line
			(start -0.12065 -0.2794)
			(end -0.12065 -0.3048)
			(stroke
				(width 0.1)
				(type default)
			)
			(layer "B.Fab")
		)
		(fp_line
			(start 0.12065 -0.2794)
			(end -0.12065 -0.2794)
			(stroke
				(width 0.1)
				(type default)
			)
			(layer "B.Fab")
		)
		(fp_line
			(start -0.67945 -0.3048)
			(end -0.67945 0.3048)
			(stroke
				(width 0.1)
				(type default)
			)
			(layer "B.Fab")
		)
		(fp_line
			(start -0.12065 -0.3048)
			(end -0.67945 -0.3048)
			(stroke
				(width 0.1)
				(type default)
			)
			(layer "B.Fab")
		)
		(fp_line
			(start 0.12065 -0.305054)
			(end 0.12065 -0.2794)
			(stroke
				(width 0.1)
				(type default)
			)
			(layer "B.Fab")
		)
		(fp_line
			(start 0.67945 -0.305054)
			(end 0.12065 -0.305054)
			(stroke
				(width 0.1)
				(type default)
			)
			(layer "B.Fab")
		)
		(pad "1" smd circle
			(at 0.40005 0 90)
			(size 0 0)
			(layers "B.Cu" "B.Mask" "B.Paste")
			(net "PVCCIN_CPU1_PVCC")
		)
		(pad "2" smd circle
			(at -0.40005 0 90)
			(size 0 0)
			(layers "B.Cu" "B.Mask" "B.Paste")
			(net "PVCCIN_CPU1_VDD3")
		)
	)
	(footprint ""
		(layer "B.Cu")
		(at 184.912 -20.284948 90)
		(property "Reference" "R4512"
			(at 0 0 90)
			(layer "B.SilkS")
			(hide yes)
			(effects
				(font
					(size 1.27 1.27)
				)
				(justify mirror)
			)
		)
		(property "Value" ""
			(at 0 0 90)
			(layer "B.Fab")
			(effects
				(font
					(size 1.27 1.27)
				)
				(justify mirror)
			)
		)
		(duplicate_pad_numbers_are_jumpers no)
		(fp_line
			(start 0.7874 -0.4064)
			(end -0.7874 -0.4064)
			(stroke
				(width 0.1524)
				(type default)
			)
			(layer "B.SilkS")
		)
		(fp_line
			(start -0.7874 -0.4064)
			(end -0.7874 0.4064)
			(stroke
				(width 0.1524)
				(type default)
			)
			(layer "B.SilkS")
		)
		(fp_line
			(start 0.7874 0.4064)
			(end 0.7874 -0.4064)
			(stroke
				(width 0.1524)
				(type default)
			)
			(layer "B.SilkS")
		)
		(fp_line
			(start -0.7874 0.4064)
			(end 0.7874 0.4064)
			(stroke
				(width 0.1524)
				(type default)
			)
			(layer "B.SilkS")
		)
		(fp_line
			(start 0.67945 -0.305054)
			(end 0.12065 -0.305054)
			(stroke
				(width 0.1)
				(type default)
			)
			(layer "B.Fab")
		)
		(fp_line
			(start 0.12065 -0.305054)
			(end 0.12065 -0.2794)
			(stroke
				(width 0.1)
				(type default)
			)
			(layer "B.Fab")
		)
		(fp_line
			(start -0.12065 -0.3048)
			(end -0.67945 -0.3048)
			(stroke
				(width 0.1)
				(type default)
			)
			(layer "B.Fab")
		)
		(fp_line
			(start -0.67945 -0.3048)
			(end -0.67945 0.3048)
			(stroke
				(width 0.1)
				(type default)
			)
			(layer "B.Fab")
		)
		(fp_line
			(start 0.12065 -0.2794)
			(end -0.12065 -0.2794)
			(stroke
				(width 0.1)
				(type default)
			)
			(layer "B.Fab")
		)
		(fp_line
			(start -0.12065 -0.2794)
			(end -0.12065 -0.3048)
			(stroke
				(width 0.1)
				(type default)
			)
			(layer "B.Fab")
		)
		(fp_line
			(start 0.12065 0.2794)
			(end 0.12065 0.3048)
			(stroke
				(width 0.1)
				(type default)
			)
			(layer "B.Fab")
		)
		(fp_line
			(start -0.120396 0.2794)
			(end 0.12065 0.2794)
			(stroke
				(width 0.1)
				(type default)
			)
			(layer "B.Fab")
		)
		(fp_line
			(start 0.67945 0.3048)
			(end 0.67945 -0.305054)
			(stroke
				(width 0.1)
				(type default)
			)
			(layer "B.Fab")
		)
		(fp_line
			(start 0.12065 0.3048)
			(end 0.67945 0.3048)
			(stroke
				(width 0.1)
				(type default)
			)
			(layer "B.Fab")
		)
		(fp_line
			(start -0.120396 0.3048)
			(end -0.120396 0.2794)
			(stroke
				(width 0.1)
				(type default)
			)
			(layer "B.Fab")
		)
		(fp_line
			(start -0.67945 0.3048)
			(end -0.120396 0.3048)
			(stroke
				(width 0.1)
				(type default)
			)
			(layer "B.Fab")
		)
		(pad "1" smd circle
			(at 0.40005 0 270)
			(size 0 0)
			(layers "B.Cu" "B.Mask" "B.Paste")
			(net "SMB_HOST_3V3AUX_SCL")
		)
		(pad "2" smd circle
			(at -0.40005 0 270)
			(size 0 0)
			(layers "B.Cu" "B.Mask" "B.Paste")
			(net "SMB_HOST_3V3AUX_SCL_R5")
		)
	)
	(footprint ""
		(layer "B.Cu")
		(at 198.47433 -70.903084)
		(property "Reference" "U223"
			(at 3.66141 -3.162554 0)
			(unlocked yes)
			(layer "B.SilkS")
			(effects
				(font
					(size 0.7874 0.5842)
					(thickness 0.1524)
				)
				(justify left mirror)
			)
		)
		(property "Value" ""
			(at 0 0 0)
			(layer "B.Fab")
			(effects
				(font
					(size 1.27 1.27)
				)
				(justify mirror)
			)
		)
		(duplicate_pad_numbers_are_jumpers no)
		(fp_line
			(start -2.0066 -2.5527)
			(end -2.0066 2.5527)
			(stroke
				(width 0.1524)
				(type default)
			)
			(layer "B.SilkS")
		)
		(fp_line
			(start -2.0066 2.5527)
			(end 2.0066 2.5527)
			(stroke
				(width 0.1524)
				(type default)
			)
			(layer "B.SilkS")
		)
		(fp_line
			(start -0.5715 -2.5527)
			(end -2.0066 -2.5527)
			(stroke
				(width 0.1524)
				(type default)
			)
			(layer "B.SilkS")
		)
		(fp_line
			(start 0 -1.9812)
			(end -0.5715 -2.5527)
			(stroke
				(width 0.1524)
				(type default)
			)
			(layer "B.SilkS")
		)
		(fp_line
			(start 0.5715 -2.5527)
			(end 0 -1.9812)
			(stroke
				(width 0.1524)
				(type default)
			)
			(layer "B.SilkS")
		)
		(fp_line
			(start 2.0066 -2.5527)
			(end 0.5715 -2.5527)
			(stroke
				(width 0.1524)
				(type default)
			)
			(layer "B.SilkS")
		)
		(fp_line
			(start 2.0066 2.5527)
			(end 2.0066 -2.5527)
			(stroke
				(width 0.1524)
				(type default)
			)
			(layer "B.SilkS")
		)
		(fp_poly
			(pts
				(xy 4.36372 -1.608328) (xy 3.81 -1.905) (xy 4.36372 -2.233168)
			)
			(stroke
				(width 0)
				(type default)
			)
			(fill yes)
			(layer "B.SilkS")
		)
		(fp_line
			(start -2.249932 -2.549906)
			(end -2.249932 2.549906)
			(stroke
				(width 0.1)
				(type default)
			)
			(layer "B.Fab")
		)
		(fp_line
			(start -2.249932 2.549906)
			(end 2.249932 2.549906)
			(stroke
				(width 0.1)
				(type default)
			)
			(layer "B.Fab")
		)
		(fp_line
			(start 2.249932 -2.549906)
			(end -2.249932 -2.549906)
			(stroke
				(width 0.1)
				(type default)
			)
			(layer "B.Fab")
		)
		(fp_line
			(start 2.249932 2.549906)
			(end 2.249932 -2.549906)
			(stroke
				(width 0.1)
				(type default)
			)
			(layer "B.Fab")
		)
		(fp_poly
			(pts
				(xy 4.36372 -1.608328) (xy 4.36372 -2.233168) (xy 3.81 -1.905)
			)
			(stroke
				(width 0)
				(type default)
			)
			(fill yes)
			(layer "B.Fab")
		)
		(pad "1" smd rect
			(at 2.921 -1.949958 270)
			(size 0.3556 1.4986)
			(layers "B.Cu" "B.Mask" "B.Paste")
			(net "FB_BMC_ISOLATE1")
		)
		(pad "2" smd rect
			(at 2.921 -1.299972 270)
			(size 0.3556 1.4986)
			(layers "B.Cu" "B.Mask" "B.Paste")
			(net "NCSI_BMC_TXD1_R1")
		)
		(pad "3" smd rect
			(at 2.921 -0.649986 270)
			(size 0.3556 1.4986)
			(layers "B.Cu" "B.Mask" "B.Paste")
			(net "NCSI_OCP_V3_2_TXD1")
		)
		(pad "4" smd rect
			(at 2.921 0 270)
			(size 0.3556 1.4986)
			(layers "B.Cu" "B.Mask" "B.Paste")
			(net "FB_BMC_ISOLATE1")
		)
		(pad "5" smd rect
			(at 2.921 0.649986 270)
			(size 0.3556 1.4986)
			(layers "B.Cu" "B.Mask" "B.Paste")
			(net "NCSI_BMC_TXD0_R1")
		)
		(pad "6" smd rect
			(at 2.921 1.299972 270)
			(size 0.3556 1.4986)
			(layers "B.Cu" "B.Mask" "B.Paste")
			(net "NCSI_OCP_V3_2_TXD0")
		)
		(pad "7" smd rect
			(at 2.921 1.949958 270)
			(size 0.3556 1.4986)
			(layers "B.Cu" "B.Mask" "B.Paste")
			(net "GND")
		)
		(pad "8" smd rect
			(at -2.921 1.949958 270)
			(size 0.3556 1.4986)
			(layers "B.Cu" "B.Mask" "B.Paste")
			(net "NCSI_OCP_V3_2_TX_EN")
		)
		(pad "9" smd rect
			(at -2.921 1.299972 270)
			(size 0.3556 1.4986)
			(layers "B.Cu" "B.Mask" "B.Paste")
			(net "NCSI_BMC_TX_EN_R1")
		)
		(pad "10" smd rect
			(at -2.921 0.649986 270)
			(size 0.3556 1.4986)
			(layers "B.Cu" "B.Mask" "B.Paste")
			(net "FB_BMC_ISOLATE1")
		)
		(pad "11" smd rect
			(at -2.921 0 270)
			(size 0.3556 1.4986)
			(layers "B.Cu" "B.Mask" "B.Paste")
			(net "OCP_V3_2_ISO2_RBT_ARB_OUT")
		)
		(pad "12" smd rect
			(at -2.921 -0.649986 270)
			(size 0.3556 1.4986)
			(layers "B.Cu" "B.Mask" "B.Paste")
			(net "OCP_V3_2_RBT_ARB_OUT")
		)
		(pad "13" smd rect
			(at -2.921 -1.299972 270)
			(size 0.3556 1.4986)
			(layers "B.Cu" "B.Mask" "B.Paste")
			(net "FB_BMC_ISOLATE1")
		)
		(pad "14" smd rect
			(at -2.921 -1.949958 270)
			(size 0.3556 1.4986)
			(layers "B.Cu" "B.Mask" "B.Paste")
			(net "P3V3_AUX")
		)
	)
	(footprint ""
		(layer "B.Cu")
		(at 451.812406 -317.15583 90)
		(property "Reference" "R3890"
			(at 0 0 90)
			(layer "B.SilkS")
			(hide yes)
			(effects
				(font
					(size 1.27 1.27)
				)
				(justify mirror)
			)
		)
		(property "Value" ""
			(at 0 0 90)
			(layer "B.Fab")
			(effects
				(font
					(size 1.27 1.27)
				)
				(justify mirror)
			)
		)
		(duplicate_pad_numbers_are_jumpers no)
		(fp_line
			(start 0.7874 -0.4064)
			(end -0.7874 -0.4064)
			(stroke
				(width 0.1524)
				(type default)
			)
			(layer "B.SilkS")
		)
		(fp_line
			(start -0.7874 -0.4064)
			(end -0.7874 0.4064)
			(stroke
				(width 0.1524)
				(type default)
			)
			(layer "B.SilkS")
		)
		(fp_line
			(start 0.7874 0.4064)
			(end 0.7874 -0.4064)
			(stroke
				(width 0.1524)
				(type default)
			)
			(layer "B.SilkS")
		)
		(fp_line
			(start -0.7874 0.4064)
			(end 0.7874 0.4064)
			(stroke
				(width 0.1524)
				(type default)
			)
			(layer "B.SilkS")
		)
		(fp_line
			(start 0.67945 -0.305054)
			(end 0.12065 -0.305054)
			(stroke
				(width 0.1)
				(type default)
			)
			(layer "B.Fab")
		)
		(fp_line
			(start 0.12065 -0.305054)
			(end 0.12065 -0.2794)
			(stroke
				(width 0.1)
				(type default)
			)
			(layer "B.Fab")
		)
		(fp_line
			(start -0.12065 -0.3048)
			(end -0.67945 -0.3048)
			(stroke
				(width 0.1)
				(type default)
			)
			(layer "B.Fab")
		)
		(fp_line
			(start -0.67945 -0.3048)
			(end -0.67945 0.3048)
			(stroke
				(width 0.1)
				(type default)
			)
			(layer "B.Fab")
		)
		(fp_line
			(start 0.12065 -0.2794)
			(end -0.12065 -0.2794)
			(stroke
				(width 0.1)
				(type default)
			)
			(layer "B.Fab")
		)
		(fp_line
			(start -0.12065 -0.2794)
			(end -0.12065 -0.3048)
			(stroke
				(width 0.1)
				(type default)
			)
			(layer "B.Fab")
		)
		(fp_line
			(start 0.12065 0.2794)
			(end 0.12065 0.3048)
			(stroke
				(width 0.1)
				(type default)
			)
			(layer "B.Fab")
		)
		(fp_line
			(start -0.120396 0.2794)
			(end 0.12065 0.2794)
			(stroke
				(width 0.1)
				(type default)
			)
			(layer "B.Fab")
		)
		(fp_line
			(start 0.67945 0.3048)
			(end 0.67945 -0.305054)
			(stroke
				(width 0.1)
				(type default)
			)
			(layer "B.Fab")
		)
		(fp_line
			(start 0.12065 0.3048)
			(end 0.67945 0.3048)
			(stroke
				(width 0.1)
				(type default)
			)
			(layer "B.Fab")
		)
		(fp_line
			(start -0.120396 0.3048)
			(end -0.120396 0.2794)
			(stroke
				(width 0.1)
				(type default)
			)
			(layer "B.Fab")
		)
		(fp_line
			(start -0.67945 0.3048)
			(end -0.120396 0.3048)
			(stroke
				(width 0.1)
				(type default)
			)
			(layer "B.Fab")
		)
		(pad "1" smd circle
			(at 0.40005 0 270)
			(size 0 0)
			(layers "B.Cu" "B.Mask" "B.Paste")
			(net "I3C_SPD_DDREFGH_CPU0_LVC1_SCL_7")
		)
		(pad "2" smd circle
			(at -0.40005 0 270)
			(size 0 0)
			(layers "B.Cu" "B.Mask" "B.Paste")
			(net "I3C_SPD_DDREFGH_CPU0_LVC1_SCL")
		)
	)
	(footprint ""
		(layer "B.Cu")
		(at 426.892212 -121.685812 180)
		(property "Reference" "PR1390"
			(at 0 0 0)
			(layer "B.SilkS")
			(hide yes)
			(effects
				(font
					(size 1.27 1.27)
				)
				(justify mirror)
			)
		)
		(property "Value" ""
			(at 0 0 0)
			(layer "B.Fab")
			(effects
				(font
					(size 1.27 1.27)
				)
				(justify mirror)
			)
		)
		(duplicate_pad_numbers_are_jumpers no)
		(fp_line
			(start 0.7874 0.4064)
			(end 0.7874 -0.4064)
			(stroke
				(width 0.1524)
				(type default)
			)
			(layer "B.SilkS")
		)
		(fp_line
			(start 0.7874 -0.4064)
			(end -0.7874 -0.4064)
			(stroke
				(width 0.1524)
				(type default)
			)
			(layer "B.SilkS")
		)
		(fp_line
			(start -0.7874 0.4064)
			(end 0.7874 0.4064)
			(stroke
				(width 0.1524)
				(type default)
			)
			(layer "B.SilkS")
		)
		(fp_line
			(start -0.7874 -0.4064)
			(end -0.7874 0.4064)
			(stroke
				(width 0.1524)
				(type default)
			)
			(layer "B.SilkS")
		)
		(fp_line
			(start 0.67945 0.3048)
			(end 0.67945 -0.305054)
			(stroke
				(width 0.1)
				(type default)
			)
			(layer "B.Fab")
		)
		(fp_line
			(start 0.67945 -0.305054)
			(end 0.12065 -0.305054)
			(stroke
				(width 0.1)
				(type default)
			)
			(layer "B.Fab")
		)
		(fp_line
			(start 0.12065 0.3048)
			(end 0.67945 0.3048)
			(stroke
				(width 0.1)
				(type default)
			)
			(layer "B.Fab")
		)
		(fp_line
			(start 0.12065 0.2794)
			(end 0.12065 0.3048)
			(stroke
				(width 0.1)
				(type default)
			)
			(layer "B.Fab")
		)
		(fp_line
			(start 0.12065 -0.2794)
			(end -0.12065 -0.2794)
			(stroke
				(width 0.1)
				(type default)
			)
			(layer "B.Fab")
		)
		(fp_line
			(start 0.12065 -0.305054)
			(end 0.12065 -0.2794)
			(stroke
				(width 0.1)
				(type default)
			)
			(layer "B.Fab")
		)
		(fp_line
			(start -0.120396 0.3048)
			(end -0.120396 0.2794)
			(stroke
				(width 0.1)
				(type default)
			)
			(layer "B.Fab")
		)
		(fp_line
			(start -0.120396 0.2794)
			(end 0.12065 0.2794)
			(stroke
				(width 0.1)
				(type default)
			)
			(layer "B.Fab")
		)
		(fp_line
			(start -0.12065 -0.2794)
			(end -0.12065 -0.3048)
			(stroke
				(width 0.1)
				(type default)
			)
			(layer "B.Fab")
		)
		(fp_line
			(start -0.12065 -0.3048)
			(end -0.67945 -0.3048)
			(stroke
				(width 0.1)
				(type default)
			)
			(layer "B.Fab")
		)
		(fp_line
			(start -0.67945 0.3048)
			(end -0.120396 0.3048)
			(stroke
				(width 0.1)
				(type default)
			)
			(layer "B.Fab")
		)
		(fp_line
			(start -0.67945 -0.3048)
			(end -0.67945 0.3048)
			(stroke
				(width 0.1)
				(type default)
			)
			(layer "B.Fab")
		)
		(pad "1" smd circle
			(at 0.40005 0)
			(size 0 0)
			(layers "B.Cu" "B.Mask" "B.Paste")
			(net "P12V_AUX_CPU0_DIMM_ISEN_N")
		)
		(pad "2" smd circle
			(at -0.40005 0)
			(size 0 0)
			(layers "B.Cu" "B.Mask" "B.Paste")
			(net "PVCCD_HV_CPU0_ISENSE_N")
		)
	)
	(footprint ""
		(layer "B.Cu")
		(at 70.012306 -219.823538 90)
		(property "Reference" "R1243"
			(at 0 0 90)
			(layer "B.SilkS")
			(hide yes)
			(effects
				(font
					(size 1.27 1.27)
				)
				(justify mirror)
			)
		)
		(property "Value" ""
			(at 0 0 90)
			(layer "B.Fab")
			(effects
				(font
					(size 1.27 1.27)
				)
				(justify mirror)
			)
		)
		(duplicate_pad_numbers_are_jumpers no)
		(fp_line
			(start 0.7874 -0.4064)
			(end -0.7874 -0.4064)
			(stroke
				(width 0.1524)
				(type default)
			)
			(layer "B.SilkS")
		)
		(fp_line
			(start -0.7874 -0.4064)
			(end -0.7874 0.4064)
			(stroke
				(width 0.1524)
				(type default)
			)
			(layer "B.SilkS")
		)
		(fp_line
			(start 0.7874 0.4064)
			(end 0.7874 -0.4064)
			(stroke
				(width 0.1524)
				(type default)
			)
			(layer "B.SilkS")
		)
		(fp_line
			(start -0.7874 0.4064)
			(end 0.7874 0.4064)
			(stroke
				(width 0.1524)
				(type default)
			)
			(layer "B.SilkS")
		)
		(fp_line
			(start 0.67945 -0.305054)
			(end 0.12065 -0.305054)
			(stroke
				(width 0.1)
				(type default)
			)
			(layer "B.Fab")
		)
		(fp_line
			(start 0.12065 -0.305054)
			(end 0.12065 -0.2794)
			(stroke
				(width 0.1)
				(type default)
			)
			(layer "B.Fab")
		)
		(fp_line
			(start -0.12065 -0.3048)
			(end -0.67945 -0.3048)
			(stroke
				(width 0.1)
				(type default)
			)
			(layer "B.Fab")
		)
		(fp_line
			(start -0.67945 -0.3048)
			(end -0.67945 0.3048)
			(stroke
				(width 0.1)
				(type default)
			)
			(layer "B.Fab")
		)
		(fp_line
			(start 0.12065 -0.2794)
			(end -0.12065 -0.2794)
			(stroke
				(width 0.1)
				(type default)
			)
			(layer "B.Fab")
		)
		(fp_line
			(start -0.12065 -0.2794)
			(end -0.12065 -0.3048)
			(stroke
				(width 0.1)
				(type default)
			)
			(layer "B.Fab")
		)
		(fp_line
			(start 0.12065 0.2794)
			(end 0.12065 0.3048)
			(stroke
				(width 0.1)
				(type default)
			)
			(layer "B.Fab")
		)
		(fp_line
			(start -0.120396 0.2794)
			(end 0.12065 0.2794)
			(stroke
				(width 0.1)
				(type default)
			)
			(layer "B.Fab")
		)
		(fp_line
			(start 0.67945 0.3048)
			(end 0.67945 -0.305054)
			(stroke
				(width 0.1)
				(type default)
			)
			(layer "B.Fab")
		)
		(fp_line
			(start 0.12065 0.3048)
			(end 0.67945 0.3048)
			(stroke
				(width 0.1)
				(type default)
			)
			(layer "B.Fab")
		)
		(fp_line
			(start -0.120396 0.3048)
			(end -0.120396 0.2794)
			(stroke
				(width 0.1)
				(type default)
			)
			(layer "B.Fab")
		)
		(fp_line
			(start -0.67945 0.3048)
			(end -0.120396 0.3048)
			(stroke
				(width 0.1)
				(type default)
			)
			(layer "B.Fab")
		)
		(pad "1" smd circle
			(at 0.40005 0 270)
			(size 0 0)
			(layers "B.Cu" "B.Mask" "B.Paste")
			(net "H_PMAX_TRIGGER_IO_CPU1")
		)
		(pad "2" smd circle
			(at -0.40005 0 270)
			(size 0 0)
			(layers "B.Cu" "B.Mask" "B.Paste")
			(net "GND")
		)
	)
	(footprint ""
		(layer "B.Cu")
		(at 81.422494 -45.785786 -90)
		(property "Reference" "R3633"
			(at 0 0 90)
			(layer "B.SilkS")
			(hide yes)
			(effects
				(font
					(size 1.27 1.27)
				)
				(justify mirror)
			)
		)
		(property "Value" ""
			(at 0 0 90)
			(layer "B.Fab")
			(effects
				(font
					(size 1.27 1.27)
				)
				(justify mirror)
			)
		)
		(duplicate_pad_numbers_are_jumpers no)
		(fp_line
			(start -4.0386 1.7526)
			(end 4.0386 1.7526)
			(stroke
				(width 0.1524)
				(type default)
			)
			(layer "B.SilkS")
		)
		(fp_line
			(start 4.0386 1.7526)
			(end 4.0386 -1.7526)
			(stroke
				(width 0.1524)
				(type default)
			)
			(layer "B.SilkS")
		)
		(fp_line
			(start -4.0386 -1.7526)
			(end -4.0386 1.7526)
			(stroke
				(width 0.1524)
				(type default)
			)
			(layer "B.SilkS")
		)
		(fp_line
			(start 4.0386 -1.7526)
			(end -4.0386 -1.7526)
			(stroke
				(width 0.1524)
				(type default)
			)
			(layer "B.SilkS")
		)
		(fp_line
			(start -4.0386 1.7526)
			(end 4.0386 1.7526)
			(stroke
				(width 0.1)
				(type default)
			)
			(layer "B.Fab")
		)
		(fp_line
			(start 4.0386 1.7526)
			(end 4.0386 -1.7526)
			(stroke
				(width 0.1)
				(type default)
			)
			(layer "B.Fab")
		)
		(fp_line
			(start -4.0386 -1.7526)
			(end -4.0386 1.7526)
			(stroke
				(width 0.1)
				(type default)
			)
			(layer "B.Fab")
		)
		(fp_line
			(start 4.0386 -1.7526)
			(end -4.0386 -1.7526)
			(stroke
				(width 0.1)
				(type default)
			)
			(layer "B.Fab")
		)
		(pad "1" smd rect
			(at 3.1115 0 90)
			(size 1.524 3.2004)
			(layers "B.Cu" "B.Mask" "B.Paste")
			(net "P3V3_OCP_V3_2")
		)
		(pad "2" smd rect
			(at -3.1115 0 90)
			(size 1.524 3.2004)
			(layers "B.Cu" "B.Mask" "B.Paste")
			(net "P3V3_OCP_V3_2_R")
		)
	)
	(footprint ""
		(layer "B.Cu")
		(at 51.95316 -143.759428)
		(property "Reference" "PR1797"
			(at 0 0 0)
			(layer "B.SilkS")
			(hide yes)
			(effects
				(font
					(size 1.27 1.27)
				)
				(justify mirror)
			)
		)
		(property "Value" ""
			(at 0 0 0)
			(layer "B.Fab")
			(effects
				(font
					(size 1.27 1.27)
				)
				(justify mirror)
			)
		)
		(duplicate_pad_numbers_are_jumpers no)
		(fp_line
			(start -0.7874 -0.4064)
			(end -0.7874 0.4064)
			(stroke
				(width 0.1524)
				(type default)
			)
			(layer "B.SilkS")
		)
		(fp_line
			(start -0.7874 0.4064)
			(end 0.7874 0.4064)
			(stroke
				(width 0.1524)
				(type default)
			)
			(layer "B.SilkS")
		)
		(fp_line
			(start 0.7874 -0.4064)
			(end -0.7874 -0.4064)
			(stroke
				(width 0.1524)
				(type default)
			)
			(layer "B.SilkS")
		)
		(fp_line
			(start 0.7874 0.4064)
			(end 0.7874 -0.4064)
			(stroke
				(width 0.1524)
				(type default)
			)
			(layer "B.SilkS")
		)
		(fp_line
			(start -0.67945 -0.3048)
			(end -0.67945 0.3048)
			(stroke
				(width 0.1)
				(type default)
			)
			(layer "B.Fab")
		)
		(fp_line
			(start -0.67945 0.3048)
			(end -0.120396 0.3048)
			(stroke
				(width 0.1)
				(type default)
			)
			(layer "B.Fab")
		)
		(fp_line
			(start -0.12065 -0.3048)
			(end -0.67945 -0.3048)
			(stroke
				(width 0.1)
				(type default)
			)
			(layer "B.Fab")
		)
		(fp_line
			(start -0.12065 -0.2794)
			(end -0.12065 -0.3048)
			(stroke
				(width 0.1)
				(type default)
			)
			(layer "B.Fab")
		)
		(fp_line
			(start -0.120396 0.2794)
			(end 0.12065 0.2794)
			(stroke
				(width 0.1)
				(type default)
			)
			(layer "B.Fab")
		)
		(fp_line
			(start -0.120396 0.3048)
			(end -0.120396 0.2794)
			(stroke
				(width 0.1)
				(type default)
			)
			(layer "B.Fab")
		)
		(fp_line
			(start 0.12065 -0.305054)
			(end 0.12065 -0.2794)
			(stroke
				(width 0.1)
				(type default)
			)
			(layer "B.Fab")
		)
		(fp_line
			(start 0.12065 -0.2794)
			(end -0.12065 -0.2794)
			(stroke
				(width 0.1)
				(type default)
			)
			(layer "B.Fab")
		)
		(fp_line
			(start 0.12065 0.2794)
			(end 0.12065 0.3048)
			(stroke
				(width 0.1)
				(type default)
			)
			(layer "B.Fab")
		)
		(fp_line
			(start 0.12065 0.3048)
			(end 0.67945 0.3048)
			(stroke
				(width 0.1)
				(type default)
			)
			(layer "B.Fab")
		)
		(fp_line
			(start 0.67945 -0.305054)
			(end 0.12065 -0.305054)
			(stroke
				(width 0.1)
				(type default)
			)
			(layer "B.Fab")
		)
		(fp_line
			(start 0.67945 0.3048)
			(end 0.67945 -0.305054)
			(stroke
				(width 0.1)
				(type default)
			)
			(layer "B.Fab")
		)
		(pad "1" smd circle
			(at 0.40005 0 180)
			(size 0 0)
			(layers "B.Cu" "B.Mask" "B.Paste")
			(net "PVCCINFAON_CPU1_VOS2")
		)
		(pad "2" smd circle
			(at -0.40005 0 180)
			(size 0 0)
			(layers "B.Cu" "B.Mask" "B.Paste")
			(net "PVCCINFAON_CPU1")
		)
	)
	(footprint ""
		(layer "B.Cu")
		(at 348.929706 -324.873366 -90)
		(property "Reference" "PC311_P0_2"
			(at 0 0 90)
			(layer "B.SilkS")
			(hide yes)
			(effects
				(font
					(size 1.27 1.27)
				)
				(justify mirror)
			)
		)
		(property "Value" ""
			(at 0 0 90)
			(layer "B.Fab")
			(effects
				(font
					(size 1.27 1.27)
				)
				(justify mirror)
			)
		)
		(duplicate_pad_numbers_are_jumpers no)
		(fp_line
			(start -1.524 0.762)
			(end 1.524 0.762)
			(stroke
				(width 0.1524)
				(type default)
			)
			(layer "B.SilkS")
		)
		(fp_line
			(start 1.524 0.762)
			(end 1.524 -0.762)
			(stroke
				(width 0.1524)
				(type default)
			)
			(layer "B.SilkS")
		)
		(fp_line
			(start -1.524 -0.762)
			(end -1.524 0.762)
			(stroke
				(width 0.1524)
				(type default)
			)
			(layer "B.SilkS")
		)
		(fp_line
			(start 1.524 -0.762)
			(end -1.524 -0.762)
			(stroke
				(width 0.1524)
				(type default)
			)
			(layer "B.SilkS")
		)
		(fp_line
			(start -1.1049 0.724916)
			(end -1.1049 -0.724916)
			(stroke
				(width 0.1)
				(type default)
			)
			(layer "B.Fab")
		)
		(fp_line
			(start 1.1049 0.724916)
			(end -1.1049 0.724916)
			(stroke
				(width 0.1)
				(type default)
			)
			(layer "B.Fab")
		)
		(fp_line
			(start -1.1049 -0.724916)
			(end 1.1049 -0.724916)
			(stroke
				(width 0.1)
				(type default)
			)
			(layer "B.Fab")
		)
		(fp_line
			(start 1.1049 -0.724916)
			(end 1.1049 0.724916)
			(stroke
				(width 0.1)
				(type default)
			)
			(layer "B.Fab")
		)
		(pad "1" smd rect
			(at 0.889 0 270)
			(size 1.016 1.27)
			(layers "B.Cu" "B.Mask" "B.Paste")
			(net "PVCCIN_CPU0")
		)
		(pad "2" smd rect
			(at -0.889 0 270)
			(size 1.016 1.27)
			(layers "B.Cu" "B.Mask" "B.Paste")
			(net "GND")
		)
	)
	(footprint ""
		(layer "B.Cu")
		(at 181.755542 -115.375436)
		(property "Reference" "C1133"
			(at 0 0 0)
			(layer "B.SilkS")
			(hide yes)
			(effects
				(font
					(size 1.27 1.27)
				)
				(justify mirror)
			)
		)
		(property "Value" ""
			(at 0 0 0)
			(layer "B.Fab")
			(effects
				(font
					(size 1.27 1.27)
				)
				(justify mirror)
			)
		)
		(duplicate_pad_numbers_are_jumpers no)
		(fp_line
			(start -0.69215 -0.2921)
			(end -0.69215 0.2921)
			(stroke
				(width 0.1524)
				(type default)
			)
			(layer "B.SilkS")
		)
		(fp_line
			(start -0.69215 0.2921)
			(end 0.69215 0.2921)
			(stroke
				(width 0.1524)
				(type default)
			)
			(layer "B.SilkS")
		)
		(fp_line
			(start 0.69215 -0.2921)
			(end -0.69215 -0.2921)
			(stroke
				(width 0.1524)
				(type default)
			)
			(layer "B.SilkS")
		)
		(fp_line
			(start 0.69215 0.2921)
			(end 0.69215 -0.2921)
			(stroke
				(width 0.1524)
				(type default)
			)
			(layer "B.SilkS")
		)
		(fp_line
			(start -0.51435 -0.2794)
			(end -0.51435 0.2794)
			(stroke
				(width 0.1)
				(type default)
			)
			(layer "B.Fab")
		)
		(fp_line
			(start -0.51435 0.2794)
			(end 0.51435 0.2794)
			(stroke
				(width 0.1)
				(type default)
			)
			(layer "B.Fab")
		)
		(fp_line
			(start 0.51435 -0.2794)
			(end -0.51435 -0.2794)
			(stroke
				(width 0.1)
				(type default)
			)
			(layer "B.Fab")
		)
		(fp_line
			(start 0.51435 0.2794)
			(end 0.51435 -0.2794)
			(stroke
				(width 0.1)
				(type default)
			)
			(layer "B.Fab")
		)
		(pad "1" smd circle
			(at 0.40005 0 180)
			(size 0 0)
			(layers "B.Cu" "B.Mask" "B.Paste")
			(net "P3V3_AUX_FPGA_VCCIO2")
		)
		(pad "2" smd circle
			(at -0.40005 0 180)
			(size 0 0)
			(layers "B.Cu" "B.Mask" "B.Paste")
			(net "GND")
		)
		(zone
			(layer "B.Cu")
			(hatch none 0.5)
			(connect_pads
				(clearance 0)
			)
			(min_thickness 0.25)
			(keepout
				(tracks not_allowed)
				(vias allowed)
				(pads allowed)
				(copperpour not_allowed)
				(footprints allowed)
			)
			(placement
				(enabled no)
				(sheetname "")
			)
			(fill
				(thermal_gap 0.5)
				(thermal_bridge_width 0.5)
				(island_removal_mode 0)
			)
			(polygon
				(pts
					(xy 181.946042 -115.287806) (xy 181.854602 -115.22964) (xy 181.655212 -115.22964) (xy 181.565042 -115.287806)
					(xy 181.565042 -115.463066) (xy 181.655212 -115.521486) (xy 181.854602 -115.521486) (xy 181.946042 -115.46332)
				)
			)
		)
	)
	(footprint ""
		(layer "B.Cu")
		(at 310.843422 -316.328044 90)
		(property "Reference" "R940"
			(at 0 0 90)
			(layer "B.SilkS")
			(hide yes)
			(effects
				(font
					(size 1.27 1.27)
				)
				(justify mirror)
			)
		)
		(property "Value" ""
			(at 0 0 90)
			(layer "B.Fab")
			(effects
				(font
					(size 1.27 1.27)
				)
				(justify mirror)
			)
		)
		(duplicate_pad_numbers_are_jumpers no)
		(fp_line
			(start 0.7874 -0.4064)
			(end -0.7874 -0.4064)
			(stroke
				(width 0.1524)
				(type default)
			)
			(layer "B.SilkS")
		)
		(fp_line
			(start -0.7874 -0.4064)
			(end -0.7874 0.4064)
			(stroke
				(width 0.1524)
				(type default)
			)
			(layer "B.SilkS")
		)
		(fp_line
			(start 0.7874 0.4064)
			(end 0.7874 -0.4064)
			(stroke
				(width 0.1524)
				(type default)
			)
			(layer "B.SilkS")
		)
		(fp_line
			(start -0.7874 0.4064)
			(end 0.7874 0.4064)
			(stroke
				(width 0.1524)
				(type default)
			)
			(layer "B.SilkS")
		)
		(fp_line
			(start 0.67945 -0.305054)
			(end 0.12065 -0.305054)
			(stroke
				(width 0.1)
				(type default)
			)
			(layer "B.Fab")
		)
		(fp_line
			(start 0.12065 -0.305054)
			(end 0.12065 -0.2794)
			(stroke
				(width 0.1)
				(type default)
			)
			(layer "B.Fab")
		)
		(fp_line
			(start -0.12065 -0.3048)
			(end -0.67945 -0.3048)
			(stroke
				(width 0.1)
				(type default)
			)
			(layer "B.Fab")
		)
		(fp_line
			(start -0.67945 -0.3048)
			(end -0.67945 0.3048)
			(stroke
				(width 0.1)
				(type default)
			)
			(layer "B.Fab")
		)
		(fp_line
			(start 0.12065 -0.2794)
			(end -0.12065 -0.2794)
			(stroke
				(width 0.1)
				(type default)
			)
			(layer "B.Fab")
		)
		(fp_line
			(start -0.12065 -0.2794)
			(end -0.12065 -0.3048)
			(stroke
				(width 0.1)
				(type default)
			)
			(layer "B.Fab")
		)
		(fp_line
			(start 0.12065 0.2794)
			(end 0.12065 0.3048)
			(stroke
				(width 0.1)
				(type default)
			)
			(layer "B.Fab")
		)
		(fp_line
			(start -0.120396 0.2794)
			(end 0.12065 0.2794)
			(stroke
				(width 0.1)
				(type default)
			)
			(layer "B.Fab")
		)
		(fp_line
			(start 0.67945 0.3048)
			(end 0.67945 -0.305054)
			(stroke
				(width 0.1)
				(type default)
			)
			(layer "B.Fab")
		)
		(fp_line
			(start 0.12065 0.3048)
			(end 0.67945 0.3048)
			(stroke
				(width 0.1)
				(type default)
			)
			(layer "B.Fab")
		)
		(fp_line
			(start -0.120396 0.3048)
			(end -0.120396 0.2794)
			(stroke
				(width 0.1)
				(type default)
			)
			(layer "B.Fab")
		)
		(fp_line
			(start -0.67945 0.3048)
			(end -0.120396 0.3048)
			(stroke
				(width 0.1)
				(type default)
			)
			(layer "B.Fab")
		)
		(pad "1" smd circle
			(at 0.40005 0 270)
			(size 0 0)
			(layers "B.Cu" "B.Mask" "B.Paste")
			(net "P3V3_AUX")
		)
		(pad "2" smd circle
			(at -0.40005 0 270)
			(size 0 0)
			(layers "B.Cu" "B.Mask" "B.Paste")
			(net "PWRGD_FAIL_CPU0_AB_R1")
		)
	)
	(footprint ""
		(layer "B.Cu")
		(at 192.052448 -400.609562 180)
		(property "Reference" "R3936"
			(at 0 0 0)
			(layer "B.SilkS")
			(hide yes)
			(effects
				(font
					(size 1.27 1.27)
				)
				(justify mirror)
			)
		)
		(property "Value" ""
			(at 0 0 0)
			(layer "B.Fab")
			(effects
				(font
					(size 1.27 1.27)
				)
				(justify mirror)
			)
		)
		(duplicate_pad_numbers_are_jumpers no)
		(fp_line
			(start 0.7874 0.4064)
			(end 0.7874 -0.4064)
			(stroke
				(width 0.1524)
				(type default)
			)
			(layer "B.SilkS")
		)
		(fp_line
			(start 0.7874 -0.4064)
			(end -0.7874 -0.4064)
			(stroke
				(width 0.1524)
				(type default)
			)
			(layer "B.SilkS")
		)
		(fp_line
			(start -0.7874 0.4064)
			(end 0.7874 0.4064)
			(stroke
				(width 0.1524)
				(type default)
			)
			(layer "B.SilkS")
		)
		(fp_line
			(start -0.7874 -0.4064)
			(end -0.7874 0.4064)
			(stroke
				(width 0.1524)
				(type default)
			)
			(layer "B.SilkS")
		)
		(fp_line
			(start 0.67945 0.3048)
			(end 0.67945 -0.305054)
			(stroke
				(width 0.1)
				(type default)
			)
			(layer "B.Fab")
		)
		(fp_line
			(start 0.67945 -0.305054)
			(end 0.12065 -0.305054)
			(stroke
				(width 0.1)
				(type default)
			)
			(layer "B.Fab")
		)
		(fp_line
			(start 0.12065 0.3048)
			(end 0.67945 0.3048)
			(stroke
				(width 0.1)
				(type default)
			)
			(layer "B.Fab")
		)
		(fp_line
			(start 0.12065 0.2794)
			(end 0.12065 0.3048)
			(stroke
				(width 0.1)
				(type default)
			)
			(layer "B.Fab")
		)
		(fp_line
			(start 0.12065 -0.2794)
			(end -0.12065 -0.2794)
			(stroke
				(width 0.1)
				(type default)
			)
			(layer "B.Fab")
		)
		(fp_line
			(start 0.12065 -0.305054)
			(end 0.12065 -0.2794)
			(stroke
				(width 0.1)
				(type default)
			)
			(layer "B.Fab")
		)
		(fp_line
			(start -0.120396 0.3048)
			(end -0.120396 0.2794)
			(stroke
				(width 0.1)
				(type default)
			)
			(layer "B.Fab")
		)
		(fp_line
			(start -0.120396 0.2794)
			(end 0.12065 0.2794)
			(stroke
				(width 0.1)
				(type default)
			)
			(layer "B.Fab")
		)
		(fp_line
			(start -0.12065 -0.2794)
			(end -0.12065 -0.3048)
			(stroke
				(width 0.1)
				(type default)
			)
			(layer "B.Fab")
		)
		(fp_line
			(start -0.12065 -0.3048)
			(end -0.67945 -0.3048)
			(stroke
				(width 0.1)
				(type default)
			)
			(layer "B.Fab")
		)
		(fp_line
			(start -0.67945 0.3048)
			(end -0.120396 0.3048)
			(stroke
				(width 0.1)
				(type default)
			)
			(layer "B.Fab")
		)
		(fp_line
			(start -0.67945 -0.3048)
			(end -0.67945 0.3048)
			(stroke
				(width 0.1)
				(type default)
			)
			(layer "B.Fab")
		)
		(pad "1" smd circle
			(at 0.40005 0)
			(size 0 0)
			(layers "B.Cu" "B.Mask" "B.Paste")
			(net "HSC_VDD")
		)
		(pad "2" smd circle
			(at -0.40005 0)
			(size 0 0)
			(layers "B.Cu" "B.Mask" "B.Paste")
			(net "HSC_D_OC")
		)
	)
	(footprint ""
		(layer "B.Cu")
		(at 404.002748 -59.939428 180)
		(property "Reference" "R773"
			(at 0 0 0)
			(layer "B.SilkS")
			(hide yes)
			(effects
				(font
					(size 1.27 1.27)
				)
				(justify mirror)
			)
		)
		(property "Value" ""
			(at 0 0 0)
			(layer "B.Fab")
			(effects
				(font
					(size 1.27 1.27)
				)
				(justify mirror)
			)
		)
		(duplicate_pad_numbers_are_jumpers no)
		(fp_line
			(start 0.7874 0.4064)
			(end 0.7874 -0.4064)
			(stroke
				(width 0.1524)
				(type default)
			)
			(layer "B.SilkS")
		)
		(fp_line
			(start 0.7874 -0.4064)
			(end -0.7874 -0.4064)
			(stroke
				(width 0.1524)
				(type default)
			)
			(layer "B.SilkS")
		)
		(fp_line
			(start -0.7874 0.4064)
			(end 0.7874 0.4064)
			(stroke
				(width 0.1524)
				(type default)
			)
			(layer "B.SilkS")
		)
		(fp_line
			(start -0.7874 -0.4064)
			(end -0.7874 0.4064)
			(stroke
				(width 0.1524)
				(type default)
			)
			(layer "B.SilkS")
		)
		(fp_line
			(start 0.67945 0.3048)
			(end 0.67945 -0.305054)
			(stroke
				(width 0.1)
				(type default)
			)
			(layer "B.Fab")
		)
		(fp_line
			(start 0.67945 -0.305054)
			(end 0.12065 -0.305054)
			(stroke
				(width 0.1)
				(type default)
			)
			(layer "B.Fab")
		)
		(fp_line
			(start 0.12065 0.3048)
			(end 0.67945 0.3048)
			(stroke
				(width 0.1)
				(type default)
			)
			(layer "B.Fab")
		)
		(fp_line
			(start 0.12065 0.2794)
			(end 0.12065 0.3048)
			(stroke
				(width 0.1)
				(type default)
			)
			(layer "B.Fab")
		)
		(fp_line
			(start 0.12065 -0.2794)
			(end -0.12065 -0.2794)
			(stroke
				(width 0.1)
				(type default)
			)
			(layer "B.Fab")
		)
		(fp_line
			(start 0.12065 -0.305054)
			(end 0.12065 -0.2794)
			(stroke
				(width 0.1)
				(type default)
			)
			(layer "B.Fab")
		)
		(fp_line
			(start -0.120396 0.3048)
			(end -0.120396 0.2794)
			(stroke
				(width 0.1)
				(type default)
			)
			(layer "B.Fab")
		)
		(fp_line
			(start -0.120396 0.2794)
			(end 0.12065 0.2794)
			(stroke
				(width 0.1)
				(type default)
			)
			(layer "B.Fab")
		)
		(fp_line
			(start -0.12065 -0.2794)
			(end -0.12065 -0.3048)
			(stroke
				(width 0.1)
				(type default)
			)
			(layer "B.Fab")
		)
		(fp_line
			(start -0.12065 -0.3048)
			(end -0.67945 -0.3048)
			(stroke
				(width 0.1)
				(type default)
			)
			(layer "B.Fab")
		)
		(fp_line
			(start -0.67945 0.3048)
			(end -0.120396 0.3048)
			(stroke
				(width 0.1)
				(type default)
			)
			(layer "B.Fab")
		)
		(fp_line
			(start -0.67945 -0.3048)
			(end -0.67945 0.3048)
			(stroke
				(width 0.1)
				(type default)
			)
			(layer "B.Fab")
		)
		(pad "1" smd circle
			(at 0.40005 0)
			(size 0 0)
			(layers "B.Cu" "B.Mask" "B.Paste")
			(net "JTAG_DBP_BOOT_HALT_N")
		)
		(pad "2" smd circle
			(at -0.40005 0)
			(size 0 0)
			(layers "B.Cu" "B.Mask" "B.Paste")
			(net "FM_ADR_MODE0")
		)
	)
	(footprint ""
		(layer "B.Cu")
		(at 391.416032 -340.08568)
		(property "Reference" "C1398"
			(at 0 0 0)
			(layer "B.SilkS")
			(hide yes)
			(effects
				(font
					(size 1.27 1.27)
				)
				(justify mirror)
			)
		)
		(property "Value" ""
			(at 0 0 0)
			(layer "B.Fab")
			(effects
				(font
					(size 1.27 1.27)
				)
				(justify mirror)
			)
		)
		(duplicate_pad_numbers_are_jumpers no)
		(fp_line
			(start -1.524 -0.762)
			(end -1.524 0.762)
			(stroke
				(width 0.1524)
				(type default)
			)
			(layer "B.SilkS")
		)
		(fp_line
			(start -1.524 0.762)
			(end 1.524 0.762)
			(stroke
				(width 0.1524)
				(type default)
			)
			(layer "B.SilkS")
		)
		(fp_line
			(start 1.524 -0.762)
			(end -1.524 -0.762)
			(stroke
				(width 0.1524)
				(type default)
			)
			(layer "B.SilkS")
		)
		(fp_line
			(start 1.524 0.762)
			(end 1.524 -0.762)
			(stroke
				(width 0.1524)
				(type default)
			)
			(layer "B.SilkS")
		)
		(fp_line
			(start -1.1049 -0.724916)
			(end 1.1049 -0.724916)
			(stroke
				(width 0.1)
				(type default)
			)
			(layer "B.Fab")
		)
		(fp_line
			(start -1.1049 0.724916)
			(end -1.1049 -0.724916)
			(stroke
				(width 0.1)
				(type default)
			)
			(layer "B.Fab")
		)
		(fp_line
			(start 1.1049 -0.724916)
			(end 1.1049 0.724916)
			(stroke
				(width 0.1)
				(type default)
			)
			(layer "B.Fab")
		)
		(fp_line
			(start 1.1049 0.724916)
			(end -1.1049 0.724916)
			(stroke
				(width 0.1)
				(type default)
			)
			(layer "B.Fab")
		)
		(pad "1" smd rect
			(at 0.889 0)
			(size 1.016 1.27)
			(layers "B.Cu" "B.Mask" "B.Paste")
			(net "PVPP_HBM_CPU0")
		)
		(pad "2" smd rect
			(at -0.889 0)
			(size 1.016 1.27)
			(layers "B.Cu" "B.Mask" "B.Paste")
			(net "GND")
		)
	)
	(footprint ""
		(layer "B.Cu")
		(at 449.723764 -76.697586 90)
		(property "Reference" "C2541"
			(at 0 0 90)
			(layer "B.SilkS")
			(hide yes)
			(effects
				(font
					(size 1.27 1.27)
				)
				(justify mirror)
			)
		)
		(property "Value" ""
			(at 0 0 90)
			(layer "B.Fab")
			(effects
				(font
					(size 1.27 1.27)
				)
				(justify mirror)
			)
		)
		(duplicate_pad_numbers_are_jumpers no)
		(fp_line
			(start 0.7874 -0.4064)
			(end -0.7874 -0.4064)
			(stroke
				(width 0.1524)
				(type default)
			)
			(layer "B.SilkS")
		)
		(fp_line
			(start -0.7874 -0.4064)
			(end -0.7874 0.4064)
			(stroke
				(width 0.1524)
				(type default)
			)
			(layer "B.SilkS")
		)
		(fp_line
			(start 0.7874 0.4064)
			(end 0.7874 -0.4064)
			(stroke
				(width 0.1524)
				(type default)
			)
			(layer "B.SilkS")
		)
		(fp_line
			(start -0.7874 0.4064)
			(end 0.7874 0.4064)
			(stroke
				(width 0.1524)
				(type default)
			)
			(layer "B.SilkS")
		)
		(fp_line
			(start 0.67945 -0.305054)
			(end 0.12065 -0.305054)
			(stroke
				(width 0.1)
				(type default)
			)
			(layer "B.Fab")
		)
		(fp_line
			(start 0.12065 -0.305054)
			(end 0.12065 -0.2794)
			(stroke
				(width 0.1)
				(type default)
			)
			(layer "B.Fab")
		)
		(fp_line
			(start -0.12065 -0.3048)
			(end -0.67945 -0.3048)
			(stroke
				(width 0.1)
				(type default)
			)
			(layer "B.Fab")
		)
		(fp_line
			(start -0.67945 -0.3048)
			(end -0.67945 0.3048)
			(stroke
				(width 0.1)
				(type default)
			)
			(layer "B.Fab")
		)
		(fp_line
			(start 0.12065 -0.2794)
			(end -0.12065 -0.2794)
			(stroke
				(width 0.1)
				(type default)
			)
			(layer "B.Fab")
		)
		(fp_line
			(start -0.12065 -0.2794)
			(end -0.12065 -0.3048)
			(stroke
				(width 0.1)
				(type default)
			)
			(layer "B.Fab")
		)
		(fp_line
			(start 0.12065 0.2794)
			(end 0.12065 0.3048)
			(stroke
				(width 0.1)
				(type default)
			)
			(layer "B.Fab")
		)
		(fp_line
			(start -0.120396 0.2794)
			(end 0.12065 0.2794)
			(stroke
				(width 0.1)
				(type default)
			)
			(layer "B.Fab")
		)
		(fp_line
			(start 0.67945 0.3048)
			(end 0.67945 -0.305054)
			(stroke
				(width 0.1)
				(type default)
			)
			(layer "B.Fab")
		)
		(fp_line
			(start 0.12065 0.3048)
			(end 0.67945 0.3048)
			(stroke
				(width 0.1)
				(type default)
			)
			(layer "B.Fab")
		)
		(fp_line
			(start -0.120396 0.3048)
			(end -0.120396 0.2794)
			(stroke
				(width 0.1)
				(type default)
			)
			(layer "B.Fab")
		)
		(fp_line
			(start -0.67945 0.3048)
			(end -0.120396 0.3048)
			(stroke
				(width 0.1)
				(type default)
			)
			(layer "B.Fab")
		)
		(pad "1" smd circle
			(at 0.40005 0 270)
			(size 0 0)
			(layers "B.Cu" "B.Mask" "B.Paste")
			(net "P3V3_AUX_EN")
		)
		(pad "2" smd circle
			(at -0.40005 0 270)
			(size 0 0)
			(layers "B.Cu" "B.Mask" "B.Paste")
			(net "GND")
		)
	)
	(footprint ""
		(layer "B.Cu")
		(at 423.650156 -318.781176)
		(property "Reference" "R37"
			(at 0 0 0)
			(layer "B.SilkS")
			(hide yes)
			(effects
				(font
					(size 1.27 1.27)
				)
				(justify mirror)
			)
		)
		(property "Value" ""
			(at 0 0 0)
			(layer "B.Fab")
			(effects
				(font
					(size 1.27 1.27)
				)
				(justify mirror)
			)
		)
		(duplicate_pad_numbers_are_jumpers no)
		(fp_line
			(start -0.7874 -0.4064)
			(end -0.7874 0.4064)
			(stroke
				(width 0.1524)
				(type default)
			)
			(layer "B.SilkS")
		)
		(fp_line
			(start -0.7874 0.4064)
			(end 0.7874 0.4064)
			(stroke
				(width 0.1524)
				(type default)
			)
			(layer "B.SilkS")
		)
		(fp_line
			(start 0.7874 -0.4064)
			(end -0.7874 -0.4064)
			(stroke
				(width 0.1524)
				(type default)
			)
			(layer "B.SilkS")
		)
		(fp_line
			(start 0.7874 0.4064)
			(end 0.7874 -0.4064)
			(stroke
				(width 0.1524)
				(type default)
			)
			(layer "B.SilkS")
		)
		(fp_line
			(start -0.67945 -0.3048)
			(end -0.67945 0.3048)
			(stroke
				(width 0.1)
				(type default)
			)
			(layer "B.Fab")
		)
		(fp_line
			(start -0.67945 0.3048)
			(end -0.120396 0.3048)
			(stroke
				(width 0.1)
				(type default)
			)
			(layer "B.Fab")
		)
		(fp_line
			(start -0.12065 -0.3048)
			(end -0.67945 -0.3048)
			(stroke
				(width 0.1)
				(type default)
			)
			(layer "B.Fab")
		)
		(fp_line
			(start -0.12065 -0.2794)
			(end -0.12065 -0.3048)
			(stroke
				(width 0.1)
				(type default)
			)
			(layer "B.Fab")
		)
		(fp_line
			(start -0.120396 0.2794)
			(end 0.12065 0.2794)
			(stroke
				(width 0.1)
				(type default)
			)
			(layer "B.Fab")
		)
		(fp_line
			(start -0.120396 0.3048)
			(end -0.120396 0.2794)
			(stroke
				(width 0.1)
				(type default)
			)
			(layer "B.Fab")
		)
		(fp_line
			(start 0.12065 -0.305054)
			(end 0.12065 -0.2794)
			(stroke
				(width 0.1)
				(type default)
			)
			(layer "B.Fab")
		)
		(fp_line
			(start 0.12065 -0.2794)
			(end -0.12065 -0.2794)
			(stroke
				(width 0.1)
				(type default)
			)
			(layer "B.Fab")
		)
		(fp_line
			(start 0.12065 0.2794)
			(end 0.12065 0.3048)
			(stroke
				(width 0.1)
				(type default)
			)
			(layer "B.Fab")
		)
		(fp_line
			(start 0.12065 0.3048)
			(end 0.67945 0.3048)
			(stroke
				(width 0.1)
				(type default)
			)
			(layer "B.Fab")
		)
		(fp_line
			(start 0.67945 -0.305054)
			(end 0.12065 -0.305054)
			(stroke
				(width 0.1)
				(type default)
			)
			(layer "B.Fab")
		)
		(fp_line
			(start 0.67945 0.3048)
			(end 0.67945 -0.305054)
			(stroke
				(width 0.1)
				(type default)
			)
			(layer "B.Fab")
		)
		(pad "1" smd circle
			(at 0.40005 0 180)
			(size 0 0)
			(layers "B.Cu" "B.Mask" "B.Paste")
			(net "PD_CHF_CPU0_DIMM2_SAA")
		)
		(pad "2" smd circle
			(at -0.40005 0 180)
			(size 0 0)
			(layers "B.Cu" "B.Mask" "B.Paste")
			(net "GND")
		)
	)
	(footprint ""
		(layer "B.Cu")
		(at 110.864396 -357.578406)
		(property "Reference" "PR318"
			(at 0 0 0)
			(layer "B.SilkS")
			(hide yes)
			(effects
				(font
					(size 1.27 1.27)
				)
				(justify mirror)
			)
		)
		(property "Value" ""
			(at 0 0 0)
			(layer "B.Fab")
			(effects
				(font
					(size 1.27 1.27)
				)
				(justify mirror)
			)
		)
		(duplicate_pad_numbers_are_jumpers no)
		(fp_line
			(start -0.7874 -0.4064)
			(end -0.7874 0.4064)
			(stroke
				(width 0.1524)
				(type default)
			)
			(layer "B.SilkS")
		)
		(fp_line
			(start -0.7874 0.4064)
			(end 0.7874 0.4064)
			(stroke
				(width 0.1524)
				(type default)
			)
			(layer "B.SilkS")
		)
		(fp_line
			(start 0.7874 -0.4064)
			(end -0.7874 -0.4064)
			(stroke
				(width 0.1524)
				(type default)
			)
			(layer "B.SilkS")
		)
		(fp_line
			(start 0.7874 0.4064)
			(end 0.7874 -0.4064)
			(stroke
				(width 0.1524)
				(type default)
			)
			(layer "B.SilkS")
		)
		(fp_line
			(start -0.67945 -0.3048)
			(end -0.67945 0.3048)
			(stroke
				(width 0.1)
				(type default)
			)
			(layer "B.Fab")
		)
		(fp_line
			(start -0.67945 0.3048)
			(end -0.120396 0.3048)
			(stroke
				(width 0.1)
				(type default)
			)
			(layer "B.Fab")
		)
		(fp_line
			(start -0.12065 -0.3048)
			(end -0.67945 -0.3048)
			(stroke
				(width 0.1)
				(type default)
			)
			(layer "B.Fab")
		)
		(fp_line
			(start -0.12065 -0.2794)
			(end -0.12065 -0.3048)
			(stroke
				(width 0.1)
				(type default)
			)
			(layer "B.Fab")
		)
		(fp_line
			(start -0.120396 0.2794)
			(end 0.12065 0.2794)
			(stroke
				(width 0.1)
				(type default)
			)
			(layer "B.Fab")
		)
		(fp_line
			(start -0.120396 0.3048)
			(end -0.120396 0.2794)
			(stroke
				(width 0.1)
				(type default)
			)
			(layer "B.Fab")
		)
		(fp_line
			(start 0.12065 -0.305054)
			(end 0.12065 -0.2794)
			(stroke
				(width 0.1)
				(type default)
			)
			(layer "B.Fab")
		)
		(fp_line
			(start 0.12065 -0.2794)
			(end -0.12065 -0.2794)
			(stroke
				(width 0.1)
				(type default)
			)
			(layer "B.Fab")
		)
		(fp_line
			(start 0.12065 0.2794)
			(end 0.12065 0.3048)
			(stroke
				(width 0.1)
				(type default)
			)
			(layer "B.Fab")
		)
		(fp_line
			(start 0.12065 0.3048)
			(end 0.67945 0.3048)
			(stroke
				(width 0.1)
				(type default)
			)
			(layer "B.Fab")
		)
		(fp_line
			(start 0.67945 -0.305054)
			(end 0.12065 -0.305054)
			(stroke
				(width 0.1)
				(type default)
			)
			(layer "B.Fab")
		)
		(fp_line
			(start 0.67945 0.3048)
			(end 0.67945 -0.305054)
			(stroke
				(width 0.1)
				(type default)
			)
			(layer "B.Fab")
		)
		(pad "1" smd circle
			(at 0.40005 0 180)
			(size 0 0)
			(layers "B.Cu" "B.Mask" "B.Paste")
			(net "PVCCIN_CPU1_ADDR")
		)
		(pad "2" smd circle
			(at -0.40005 0 180)
			(size 0 0)
			(layers "B.Cu" "B.Mask" "B.Paste")
			(net "GND")
		)
	)
	(footprint ""
		(layer "B.Cu")
		(at 234.26928 -423.001948 90)
		(property "Reference" "C2294"
			(at 0 0 90)
			(layer "B.SilkS")
			(hide yes)
			(effects
				(font
					(size 1.27 1.27)
				)
				(justify mirror)
			)
		)
		(property "Value" ""
			(at 0 0 90)
			(layer "B.Fab")
			(effects
				(font
					(size 1.27 1.27)
				)
				(justify mirror)
			)
		)
		(duplicate_pad_numbers_are_jumpers no)
		(fp_line
			(start 0.7874 -0.4064)
			(end -0.7874 -0.4064)
			(stroke
				(width 0.1524)
				(type default)
			)
			(layer "B.SilkS")
		)
		(fp_line
			(start -0.7874 -0.4064)
			(end -0.7874 0.4064)
			(stroke
				(width 0.1524)
				(type default)
			)
			(layer "B.SilkS")
		)
		(fp_line
			(start 0.7874 0.4064)
			(end 0.7874 -0.4064)
			(stroke
				(width 0.1524)
				(type default)
			)
			(layer "B.SilkS")
		)
		(fp_line
			(start -0.7874 0.4064)
			(end 0.7874 0.4064)
			(stroke
				(width 0.1524)
				(type default)
			)
			(layer "B.SilkS")
		)
		(fp_line
			(start 0.67945 -0.305054)
			(end 0.12065 -0.305054)
			(stroke
				(width 0.1)
				(type default)
			)
			(layer "B.Fab")
		)
		(fp_line
			(start 0.12065 -0.305054)
			(end 0.12065 -0.2794)
			(stroke
				(width 0.1)
				(type default)
			)
			(layer "B.Fab")
		)
		(fp_line
			(start -0.12065 -0.3048)
			(end -0.67945 -0.3048)
			(stroke
				(width 0.1)
				(type default)
			)
			(layer "B.Fab")
		)
		(fp_line
			(start -0.67945 -0.3048)
			(end -0.67945 0.3048)
			(stroke
				(width 0.1)
				(type default)
			)
			(layer "B.Fab")
		)
		(fp_line
			(start 0.12065 -0.2794)
			(end -0.12065 -0.2794)
			(stroke
				(width 0.1)
				(type default)
			)
			(layer "B.Fab")
		)
		(fp_line
			(start -0.12065 -0.2794)
			(end -0.12065 -0.3048)
			(stroke
				(width 0.1)
				(type default)
			)
			(layer "B.Fab")
		)
		(fp_line
			(start 0.12065 0.2794)
			(end 0.12065 0.3048)
			(stroke
				(width 0.1)
				(type default)
			)
			(layer "B.Fab")
		)
		(fp_line
			(start -0.120396 0.2794)
			(end 0.12065 0.2794)
			(stroke
				(width 0.1)
				(type default)
			)
			(layer "B.Fab")
		)
		(fp_line
			(start 0.67945 0.3048)
			(end 0.67945 -0.305054)
			(stroke
				(width 0.1)
				(type default)
			)
			(layer "B.Fab")
		)
		(fp_line
			(start 0.12065 0.3048)
			(end 0.67945 0.3048)
			(stroke
				(width 0.1)
				(type default)
			)
			(layer "B.Fab")
		)
		(fp_line
			(start -0.120396 0.3048)
			(end -0.120396 0.2794)
			(stroke
				(width 0.1)
				(type default)
			)
			(layer "B.Fab")
		)
		(fp_line
			(start -0.67945 0.3048)
			(end -0.120396 0.3048)
			(stroke
				(width 0.1)
				(type default)
			)
			(layer "B.Fab")
		)
		(pad "1" smd circle
			(at 0.40005 0 270)
			(size 0 0)
			(layers "B.Cu" "B.Mask" "B.Paste")
			(net "PDB_PRSNT_N")
		)
		(pad "2" smd circle
			(at -0.40005 0 270)
			(size 0 0)
			(layers "B.Cu" "B.Mask" "B.Paste")
			(net "GND")
		)
	)
	(footprint ""
		(layer "B.Cu")
		(at 455.093324 -13.09116 90)
		(property "Reference" "R1930"
			(at 0 0 90)
			(layer "B.SilkS")
			(hide yes)
			(effects
				(font
					(size 1.27 1.27)
				)
				(justify mirror)
			)
		)
		(property "Value" ""
			(at 0 0 90)
			(layer "B.Fab")
			(effects
				(font
					(size 1.27 1.27)
				)
				(justify mirror)
			)
		)
		(duplicate_pad_numbers_are_jumpers no)
		(fp_line
			(start 0.7874 -0.4064)
			(end -0.7874 -0.4064)
			(stroke
				(width 0.1524)
				(type default)
			)
			(layer "B.SilkS")
		)
		(fp_line
			(start -0.7874 -0.4064)
			(end -0.7874 0.4064)
			(stroke
				(width 0.1524)
				(type default)
			)
			(layer "B.SilkS")
		)
		(fp_line
			(start 0.7874 0.4064)
			(end 0.7874 -0.4064)
			(stroke
				(width 0.1524)
				(type default)
			)
			(layer "B.SilkS")
		)
		(fp_line
			(start -0.7874 0.4064)
			(end 0.7874 0.4064)
			(stroke
				(width 0.1524)
				(type default)
			)
			(layer "B.SilkS")
		)
		(fp_line
			(start 0.67945 -0.305054)
			(end 0.12065 -0.305054)
			(stroke
				(width 0.1)
				(type default)
			)
			(layer "B.Fab")
		)
		(fp_line
			(start 0.12065 -0.305054)
			(end 0.12065 -0.2794)
			(stroke
				(width 0.1)
				(type default)
			)
			(layer "B.Fab")
		)
		(fp_line
			(start -0.12065 -0.3048)
			(end -0.67945 -0.3048)
			(stroke
				(width 0.1)
				(type default)
			)
			(layer "B.Fab")
		)
		(fp_line
			(start -0.67945 -0.3048)
			(end -0.67945 0.3048)
			(stroke
				(width 0.1)
				(type default)
			)
			(layer "B.Fab")
		)
		(fp_line
			(start 0.12065 -0.2794)
			(end -0.12065 -0.2794)
			(stroke
				(width 0.1)
				(type default)
			)
			(layer "B.Fab")
		)
		(fp_line
			(start -0.12065 -0.2794)
			(end -0.12065 -0.3048)
			(stroke
				(width 0.1)
				(type default)
			)
			(layer "B.Fab")
		)
		(fp_line
			(start 0.12065 0.2794)
			(end 0.12065 0.3048)
			(stroke
				(width 0.1)
				(type default)
			)
			(layer "B.Fab")
		)
		(fp_line
			(start -0.120396 0.2794)
			(end 0.12065 0.2794)
			(stroke
				(width 0.1)
				(type default)
			)
			(layer "B.Fab")
		)
		(fp_line
			(start 0.67945 0.3048)
			(end 0.67945 -0.305054)
			(stroke
				(width 0.1)
				(type default)
			)
			(layer "B.Fab")
		)
		(fp_line
			(start 0.12065 0.3048)
			(end 0.67945 0.3048)
			(stroke
				(width 0.1)
				(type default)
			)
			(layer "B.Fab")
		)
		(fp_line
			(start -0.120396 0.3048)
			(end -0.120396 0.2794)
			(stroke
				(width 0.1)
				(type default)
			)
			(layer "B.Fab")
		)
		(fp_line
			(start -0.67945 0.3048)
			(end -0.120396 0.3048)
			(stroke
				(width 0.1)
				(type default)
			)
			(layer "B.Fab")
		)
		(pad "1" smd circle
			(at 0.40005 0 270)
			(size 0 0)
			(layers "B.Cu" "B.Mask" "B.Paste")
			(net "GND")
		)
		(pad "2" smd circle
			(at -0.40005 0 270)
			(size 0 0)
			(layers "B.Cu" "B.Mask" "B.Paste")
			(net "OCP_SFF_MAIN_PWR_EN")
		)
	)
	(footprint ""
		(layer "B.Cu")
		(at 173.33976 -29.81198 90)
		(property "Reference" "R4770"
			(at 0 0 90)
			(layer "B.SilkS")
			(hide yes)
			(effects
				(font
					(size 1.27 1.27)
				)
				(justify mirror)
			)
		)
		(property "Value" ""
			(at 0 0 90)
			(layer "B.Fab")
			(effects
				(font
					(size 1.27 1.27)
				)
				(justify mirror)
			)
		)
		(duplicate_pad_numbers_are_jumpers no)
		(fp_line
			(start 0.7874 -0.4064)
			(end -0.7874 -0.4064)
			(stroke
				(width 0.1524)
				(type default)
			)
			(layer "B.SilkS")
		)
		(fp_line
			(start -0.7874 -0.4064)
			(end -0.7874 0.4064)
			(stroke
				(width 0.1524)
				(type default)
			)
			(layer "B.SilkS")
		)
		(fp_line
			(start 0.7874 0.4064)
			(end 0.7874 -0.4064)
			(stroke
				(width 0.1524)
				(type default)
			)
			(layer "B.SilkS")
		)
		(fp_line
			(start -0.7874 0.4064)
			(end 0.7874 0.4064)
			(stroke
				(width 0.1524)
				(type default)
			)
			(layer "B.SilkS")
		)
		(fp_line
			(start 0.67945 -0.305054)
			(end 0.12065 -0.305054)
			(stroke
				(width 0.1)
				(type default)
			)
			(layer "B.Fab")
		)
		(fp_line
			(start 0.12065 -0.305054)
			(end 0.12065 -0.2794)
			(stroke
				(width 0.1)
				(type default)
			)
			(layer "B.Fab")
		)
		(fp_line
			(start -0.12065 -0.3048)
			(end -0.67945 -0.3048)
			(stroke
				(width 0.1)
				(type default)
			)
			(layer "B.Fab")
		)
		(fp_line
			(start -0.67945 -0.3048)
			(end -0.67945 0.3048)
			(stroke
				(width 0.1)
				(type default)
			)
			(layer "B.Fab")
		)
		(fp_line
			(start 0.12065 -0.2794)
			(end -0.12065 -0.2794)
			(stroke
				(width 0.1)
				(type default)
			)
			(layer "B.Fab")
		)
		(fp_line
			(start -0.12065 -0.2794)
			(end -0.12065 -0.3048)
			(stroke
				(width 0.1)
				(type default)
			)
			(layer "B.Fab")
		)
		(fp_line
			(start 0.12065 0.2794)
			(end 0.12065 0.3048)
			(stroke
				(width 0.1)
				(type default)
			)
			(layer "B.Fab")
		)
		(fp_line
			(start -0.120396 0.2794)
			(end 0.12065 0.2794)
			(stroke
				(width 0.1)
				(type default)
			)
			(layer "B.Fab")
		)
		(fp_line
			(start 0.67945 0.3048)
			(end 0.67945 -0.305054)
			(stroke
				(width 0.1)
				(type default)
			)
			(layer "B.Fab")
		)
		(fp_line
			(start 0.12065 0.3048)
			(end 0.67945 0.3048)
			(stroke
				(width 0.1)
				(type default)
			)
			(layer "B.Fab")
		)
		(fp_line
			(start -0.120396 0.3048)
			(end -0.120396 0.2794)
			(stroke
				(width 0.1)
				(type default)
			)
			(layer "B.Fab")
		)
		(fp_line
			(start -0.67945 0.3048)
			(end -0.120396 0.3048)
			(stroke
				(width 0.1)
				(type default)
			)
			(layer "B.Fab")
		)
		(pad "1" smd circle
			(at 0.40005 0 270)
			(size 0 0)
			(layers "B.Cu" "B.Mask" "B.Paste")
			(net "HP_LVC3_SCM_HSC_PWRGD_R")
		)
		(pad "2" smd circle
			(at -0.40005 0 270)
			(size 0 0)
			(layers "B.Cu" "B.Mask" "B.Paste")
			(net "HP_LVC3_SCM_HSC_PWRGD")
		)
	)
	(footprint ""
		(layer "B.Cu")
		(at 178.368706 -344.941906 -90)
		(property "Reference" "PC1208_P1_3"
			(at 0 0 90)
			(layer "B.SilkS")
			(hide yes)
			(effects
				(font
					(size 1.27 1.27)
				)
				(justify mirror)
			)
		)
		(property "Value" ""
			(at 0 0 90)
			(layer "B.Fab")
			(effects
				(font
					(size 1.27 1.27)
				)
				(justify mirror)
			)
		)
		(duplicate_pad_numbers_are_jumpers no)
		(fp_line
			(start -1.524 0.762)
			(end 1.524 0.762)
			(stroke
				(width 0.1524)
				(type default)
			)
			(layer "B.SilkS")
		)
		(fp_line
			(start 1.524 0.762)
			(end 1.524 -0.762)
			(stroke
				(width 0.1524)
				(type default)
			)
			(layer "B.SilkS")
		)
		(fp_line
			(start -1.524 -0.762)
			(end -1.524 0.762)
			(stroke
				(width 0.1524)
				(type default)
			)
			(layer "B.SilkS")
		)
		(fp_line
			(start 1.524 -0.762)
			(end -1.524 -0.762)
			(stroke
				(width 0.1524)
				(type default)
			)
			(layer "B.SilkS")
		)
		(fp_line
			(start -1.1049 0.724916)
			(end -1.1049 -0.724916)
			(stroke
				(width 0.1)
				(type default)
			)
			(layer "B.Fab")
		)
		(fp_line
			(start 1.1049 0.724916)
			(end -1.1049 0.724916)
			(stroke
				(width 0.1)
				(type default)
			)
			(layer "B.Fab")
		)
		(fp_line
			(start -1.1049 -0.724916)
			(end 1.1049 -0.724916)
			(stroke
				(width 0.1)
				(type default)
			)
			(layer "B.Fab")
		)
		(fp_line
			(start 1.1049 -0.724916)
			(end 1.1049 0.724916)
			(stroke
				(width 0.1)
				(type default)
			)
			(layer "B.Fab")
		)
		(pad "1" smd rect
			(at 0.889 0 270)
			(size 1.016 1.27)
			(layers "B.Cu" "B.Mask" "B.Paste")
			(net "PVCCFA_EHV_FIVRA_CPU1")
		)
		(pad "2" smd rect
			(at -0.889 0 270)
			(size 1.016 1.27)
			(layers "B.Cu" "B.Mask" "B.Paste")
			(net "GND")
		)
	)
	(footprint ""
		(layer "B.Cu")
		(at 29.577538 -165.540436)
		(property "Reference" "PR214"
			(at 0 0 0)
			(layer "B.SilkS")
			(hide yes)
			(effects
				(font
					(size 1.27 1.27)
				)
				(justify mirror)
			)
		)
		(property "Value" ""
			(at 0 0 0)
			(layer "B.Fab")
			(effects
				(font
					(size 1.27 1.27)
				)
				(justify mirror)
			)
		)
		(duplicate_pad_numbers_are_jumpers no)
		(fp_line
			(start -0.7874 -0.4064)
			(end -0.7874 0.4064)
			(stroke
				(width 0.1524)
				(type default)
			)
			(layer "B.SilkS")
		)
		(fp_line
			(start -0.7874 0.4064)
			(end 0.7874 0.4064)
			(stroke
				(width 0.1524)
				(type default)
			)
			(layer "B.SilkS")
		)
		(fp_line
			(start 0.7874 -0.4064)
			(end -0.7874 -0.4064)
			(stroke
				(width 0.1524)
				(type default)
			)
			(layer "B.SilkS")
		)
		(fp_line
			(start 0.7874 0.4064)
			(end 0.7874 -0.4064)
			(stroke
				(width 0.1524)
				(type default)
			)
			(layer "B.SilkS")
		)
		(fp_line
			(start -0.67945 -0.3048)
			(end -0.67945 0.3048)
			(stroke
				(width 0.1)
				(type default)
			)
			(layer "B.Fab")
		)
		(fp_line
			(start -0.67945 0.3048)
			(end -0.120396 0.3048)
			(stroke
				(width 0.1)
				(type default)
			)
			(layer "B.Fab")
		)
		(fp_line
			(start -0.12065 -0.3048)
			(end -0.67945 -0.3048)
			(stroke
				(width 0.1)
				(type default)
			)
			(layer "B.Fab")
		)
		(fp_line
			(start -0.12065 -0.2794)
			(end -0.12065 -0.3048)
			(stroke
				(width 0.1)
				(type default)
			)
			(layer "B.Fab")
		)
		(fp_line
			(start -0.120396 0.2794)
			(end 0.12065 0.2794)
			(stroke
				(width 0.1)
				(type default)
			)
			(layer "B.Fab")
		)
		(fp_line
			(start -0.120396 0.3048)
			(end -0.120396 0.2794)
			(stroke
				(width 0.1)
				(type default)
			)
			(layer "B.Fab")
		)
		(fp_line
			(start 0.12065 -0.305054)
			(end 0.12065 -0.2794)
			(stroke
				(width 0.1)
				(type default)
			)
			(layer "B.Fab")
		)
		(fp_line
			(start 0.12065 -0.2794)
			(end -0.12065 -0.2794)
			(stroke
				(width 0.1)
				(type default)
			)
			(layer "B.Fab")
		)
		(fp_line
			(start 0.12065 0.2794)
			(end 0.12065 0.3048)
			(stroke
				(width 0.1)
				(type default)
			)
			(layer "B.Fab")
		)
		(fp_line
			(start 0.12065 0.3048)
			(end 0.67945 0.3048)
			(stroke
				(width 0.1)
				(type default)
			)
			(layer "B.Fab")
		)
		(fp_line
			(start 0.67945 -0.305054)
			(end 0.12065 -0.305054)
			(stroke
				(width 0.1)
				(type default)
			)
			(layer "B.Fab")
		)
		(fp_line
			(start 0.67945 0.3048)
			(end 0.67945 -0.305054)
			(stroke
				(width 0.1)
				(type default)
			)
			(layer "B.Fab")
		)
		(pad "1" smd circle
			(at 0.40005 0 180)
			(size 0 0)
			(layers "B.Cu" "B.Mask" "B.Paste")
			(net "PVCCD_HV_CPU1_ISENSE_P")
		)
		(pad "2" smd circle
			(at -0.40005 0 180)
			(size 0 0)
			(layers "B.Cu" "B.Mask" "B.Paste")
			(net "GND")
		)
	)
	(footprint ""
		(layer "B.Cu")
		(at 174.235872 -13.762228 -90)
		(property "Reference" "R1460"
			(at 0 0 90)
			(layer "B.SilkS")
			(hide yes)
			(effects
				(font
					(size 1.27 1.27)
				)
				(justify mirror)
			)
		)
		(property "Value" ""
			(at 0 0 90)
			(layer "B.Fab")
			(effects
				(font
					(size 1.27 1.27)
				)
				(justify mirror)
			)
		)
		(duplicate_pad_numbers_are_jumpers no)
		(fp_line
			(start -0.7874 0.4064)
			(end 0.7874 0.4064)
			(stroke
				(width 0.1524)
				(type default)
			)
			(layer "B.SilkS")
		)
		(fp_line
			(start 0.7874 0.4064)
			(end 0.7874 -0.4064)
			(stroke
				(width 0.1524)
				(type default)
			)
			(layer "B.SilkS")
		)
		(fp_line
			(start -0.7874 -0.4064)
			(end -0.7874 0.4064)
			(stroke
				(width 0.1524)
				(type default)
			)
			(layer "B.SilkS")
		)
		(fp_line
			(start 0.7874 -0.4064)
			(end -0.7874 -0.4064)
			(stroke
				(width 0.1524)
				(type default)
			)
			(layer "B.SilkS")
		)
		(fp_line
			(start -0.67945 0.3048)
			(end -0.120396 0.3048)
			(stroke
				(width 0.1)
				(type default)
			)
			(layer "B.Fab")
		)
		(fp_line
			(start -0.120396 0.3048)
			(end -0.120396 0.2794)
			(stroke
				(width 0.1)
				(type default)
			)
			(layer "B.Fab")
		)
		(fp_line
			(start 0.12065 0.3048)
			(end 0.67945 0.3048)
			(stroke
				(width 0.1)
				(type default)
			)
			(layer "B.Fab")
		)
		(fp_line
			(start 0.67945 0.3048)
			(end 0.67945 -0.305054)
			(stroke
				(width 0.1)
				(type default)
			)
			(layer "B.Fab")
		)
		(fp_line
			(start -0.120396 0.2794)
			(end 0.12065 0.2794)
			(stroke
				(width 0.1)
				(type default)
			)
			(layer "B.Fab")
		)
		(fp_line
			(start 0.12065 0.2794)
			(end 0.12065 0.3048)
			(stroke
				(width 0.1)
				(type default)
			)
			(layer "B.Fab")
		)
		(fp_line
			(start -0.12065 -0.2794)
			(end -0.12065 -0.3048)
			(stroke
				(width 0.1)
				(type default)
			)
			(layer "B.Fab")
		)
		(fp_line
			(start 0.12065 -0.2794)
			(end -0.12065 -0.2794)
			(stroke
				(width 0.1)
				(type default)
			)
			(layer "B.Fab")
		)
		(fp_line
			(start -0.67945 -0.3048)
			(end -0.67945 0.3048)
			(stroke
				(width 0.1)
				(type default)
			)
			(layer "B.Fab")
		)
		(fp_line
			(start -0.12065 -0.3048)
			(end -0.67945 -0.3048)
			(stroke
				(width 0.1)
				(type default)
			)
			(layer "B.Fab")
		)
		(fp_line
			(start 0.12065 -0.305054)
			(end 0.12065 -0.2794)
			(stroke
				(width 0.1)
				(type default)
			)
			(layer "B.Fab")
		)
		(fp_line
			(start 0.67945 -0.305054)
			(end 0.12065 -0.305054)
			(stroke
				(width 0.1)
				(type default)
			)
			(layer "B.Fab")
		)
		(pad "1" smd circle
			(at 0.40005 0 90)
			(size 0 0)
			(layers "B.Cu" "B.Mask" "B.Paste")
			(net "I3C_BMC_SWB_SDA")
		)
		(pad "2" smd circle
			(at -0.40005 0 90)
			(size 0 0)
			(layers "B.Cu" "B.Mask" "B.Paste")
			(net "P3V3_AUX")
		)
	)
	(footprint ""
		(layer "B.Cu")
		(at 412.007558 -365.383064 -90)
		(property "Reference" "PR1322"
			(at 0 0 90)
			(layer "B.SilkS")
			(hide yes)
			(effects
				(font
					(size 1.27 1.27)
				)
				(justify mirror)
			)
		)
		(property "Value" ""
			(at 0 0 90)
			(layer "B.Fab")
			(effects
				(font
					(size 1.27 1.27)
				)
				(justify mirror)
			)
		)
		(duplicate_pad_numbers_are_jumpers no)
		(fp_line
			(start -0.7874 0.4064)
			(end 0.7874 0.4064)
			(stroke
				(width 0.1524)
				(type default)
			)
			(layer "B.SilkS")
		)
		(fp_line
			(start 0.7874 0.4064)
			(end 0.7874 -0.4064)
			(stroke
				(width 0.1524)
				(type default)
			)
			(layer "B.SilkS")
		)
		(fp_line
			(start -0.7874 -0.4064)
			(end -0.7874 0.4064)
			(stroke
				(width 0.1524)
				(type default)
			)
			(layer "B.SilkS")
		)
		(fp_line
			(start 0.7874 -0.4064)
			(end -0.7874 -0.4064)
			(stroke
				(width 0.1524)
				(type default)
			)
			(layer "B.SilkS")
		)
		(fp_line
			(start -0.67945 0.3048)
			(end -0.120396 0.3048)
			(stroke
				(width 0.1)
				(type default)
			)
			(layer "B.Fab")
		)
		(fp_line
			(start -0.120396 0.3048)
			(end -0.120396 0.2794)
			(stroke
				(width 0.1)
				(type default)
			)
			(layer "B.Fab")
		)
		(fp_line
			(start 0.12065 0.3048)
			(end 0.67945 0.3048)
			(stroke
				(width 0.1)
				(type default)
			)
			(layer "B.Fab")
		)
		(fp_line
			(start 0.67945 0.3048)
			(end 0.67945 -0.305054)
			(stroke
				(width 0.1)
				(type default)
			)
			(layer "B.Fab")
		)
		(fp_line
			(start -0.120396 0.2794)
			(end 0.12065 0.2794)
			(stroke
				(width 0.1)
				(type default)
			)
			(layer "B.Fab")
		)
		(fp_line
			(start 0.12065 0.2794)
			(end 0.12065 0.3048)
			(stroke
				(width 0.1)
				(type default)
			)
			(layer "B.Fab")
		)
		(fp_line
			(start -0.12065 -0.2794)
			(end -0.12065 -0.3048)
			(stroke
				(width 0.1)
				(type default)
			)
			(layer "B.Fab")
		)
		(fp_line
			(start 0.12065 -0.2794)
			(end -0.12065 -0.2794)
			(stroke
				(width 0.1)
				(type default)
			)
			(layer "B.Fab")
		)
		(fp_line
			(start -0.67945 -0.3048)
			(end -0.67945 0.3048)
			(stroke
				(width 0.1)
				(type default)
			)
			(layer "B.Fab")
		)
		(fp_line
			(start -0.12065 -0.3048)
			(end -0.67945 -0.3048)
			(stroke
				(width 0.1)
				(type default)
			)
			(layer "B.Fab")
		)
		(fp_line
			(start 0.12065 -0.305054)
			(end 0.12065 -0.2794)
			(stroke
				(width 0.1)
				(type default)
			)
			(layer "B.Fab")
		)
		(fp_line
			(start 0.67945 -0.305054)
			(end 0.12065 -0.305054)
			(stroke
				(width 0.1)
				(type default)
			)
			(layer "B.Fab")
		)
		(pad "1" smd circle
			(at 0.40005 0 90)
			(size 0 0)
			(layers "B.Cu" "B.Mask" "B.Paste")
			(net "PVCCFA_EHV_FIVRA_CPU0_VOS1")
		)
		(pad "2" smd circle
			(at -0.40005 0 90)
			(size 0 0)
			(layers "B.Cu" "B.Mask" "B.Paste")
			(net "PVCCFA_EHV_FIVRA_CPU0")
		)
	)
	(footprint ""
		(layer "B.Cu")
		(at 21.914612 -167.548814 180)
		(property "Reference" "R2577"
			(at 0 0 0)
			(layer "B.SilkS")
			(hide yes)
			(effects
				(font
					(size 1.27 1.27)
				)
				(justify mirror)
			)
		)
		(property "Value" ""
			(at 0 0 0)
			(layer "B.Fab")
			(effects
				(font
					(size 1.27 1.27)
				)
				(justify mirror)
			)
		)
		(duplicate_pad_numbers_are_jumpers no)
		(fp_line
			(start 0.7874 0.4064)
			(end 0.7874 -0.4064)
			(stroke
				(width 0.1524)
				(type default)
			)
			(layer "B.SilkS")
		)
		(fp_line
			(start 0.7874 -0.4064)
			(end -0.7874 -0.4064)
			(stroke
				(width 0.1524)
				(type default)
			)
			(layer "B.SilkS")
		)
		(fp_line
			(start -0.7874 0.4064)
			(end 0.7874 0.4064)
			(stroke
				(width 0.1524)
				(type default)
			)
			(layer "B.SilkS")
		)
		(fp_line
			(start -0.7874 -0.4064)
			(end -0.7874 0.4064)
			(stroke
				(width 0.1524)
				(type default)
			)
			(layer "B.SilkS")
		)
		(fp_line
			(start 0.67945 0.3048)
			(end 0.67945 -0.305054)
			(stroke
				(width 0.1)
				(type default)
			)
			(layer "B.Fab")
		)
		(fp_line
			(start 0.67945 -0.305054)
			(end 0.12065 -0.305054)
			(stroke
				(width 0.1)
				(type default)
			)
			(layer "B.Fab")
		)
		(fp_line
			(start 0.12065 0.3048)
			(end 0.67945 0.3048)
			(stroke
				(width 0.1)
				(type default)
			)
			(layer "B.Fab")
		)
		(fp_line
			(start 0.12065 0.2794)
			(end 0.12065 0.3048)
			(stroke
				(width 0.1)
				(type default)
			)
			(layer "B.Fab")
		)
		(fp_line
			(start 0.12065 -0.2794)
			(end -0.12065 -0.2794)
			(stroke
				(width 0.1)
				(type default)
			)
			(layer "B.Fab")
		)
		(fp_line
			(start 0.12065 -0.305054)
			(end 0.12065 -0.2794)
			(stroke
				(width 0.1)
				(type default)
			)
			(layer "B.Fab")
		)
		(fp_line
			(start -0.120396 0.3048)
			(end -0.120396 0.2794)
			(stroke
				(width 0.1)
				(type default)
			)
			(layer "B.Fab")
		)
		(fp_line
			(start -0.120396 0.2794)
			(end 0.12065 0.2794)
			(stroke
				(width 0.1)
				(type default)
			)
			(layer "B.Fab")
		)
		(fp_line
			(start -0.12065 -0.2794)
			(end -0.12065 -0.3048)
			(stroke
				(width 0.1)
				(type default)
			)
			(layer "B.Fab")
		)
		(fp_line
			(start -0.12065 -0.3048)
			(end -0.67945 -0.3048)
			(stroke
				(width 0.1)
				(type default)
			)
			(layer "B.Fab")
		)
		(fp_line
			(start -0.67945 0.3048)
			(end -0.120396 0.3048)
			(stroke
				(width 0.1)
				(type default)
			)
			(layer "B.Fab")
		)
		(fp_line
			(start -0.67945 -0.3048)
			(end -0.67945 0.3048)
			(stroke
				(width 0.1)
				(type default)
			)
			(layer "B.Fab")
		)
		(pad "1" smd circle
			(at 0.40005 0)
			(size 0 0)
			(layers "B.Cu" "B.Mask" "B.Paste")
			(net "FM_PVCCD_HV_CPU1_EN")
		)
		(pad "2" smd circle
			(at -0.40005 0)
			(size 0 0)
			(layers "B.Cu" "B.Mask" "B.Paste")
			(net "PVCCD_HV_CPU1_EN_R")
		)
	)
	(footprint ""
		(layer "B.Cu")
		(at 251.007626 -105.256584 90)
		(property "Reference" "R1680"
			(at 0 0 90)
			(layer "B.SilkS")
			(hide yes)
			(effects
				(font
					(size 1.27 1.27)
				)
				(justify mirror)
			)
		)
		(property "Value" ""
			(at 0 0 90)
			(layer "B.Fab")
			(effects
				(font
					(size 1.27 1.27)
				)
				(justify mirror)
			)
		)
		(duplicate_pad_numbers_are_jumpers no)
		(fp_line
			(start 0.7874 -0.4064)
			(end -0.7874 -0.4064)
			(stroke
				(width 0.1524)
				(type default)
			)
			(layer "B.SilkS")
		)
		(fp_line
			(start -0.7874 -0.4064)
			(end -0.7874 0.4064)
			(stroke
				(width 0.1524)
				(type default)
			)
			(layer "B.SilkS")
		)
		(fp_line
			(start 0.7874 0.4064)
			(end 0.7874 -0.4064)
			(stroke
				(width 0.1524)
				(type default)
			)
			(layer "B.SilkS")
		)
		(fp_line
			(start -0.7874 0.4064)
			(end 0.7874 0.4064)
			(stroke
				(width 0.1524)
				(type default)
			)
			(layer "B.SilkS")
		)
		(fp_line
			(start 0.67945 -0.305054)
			(end 0.12065 -0.305054)
			(stroke
				(width 0.1)
				(type default)
			)
			(layer "B.Fab")
		)
		(fp_line
			(start 0.12065 -0.305054)
			(end 0.12065 -0.2794)
			(stroke
				(width 0.1)
				(type default)
			)
			(layer "B.Fab")
		)
		(fp_line
			(start -0.12065 -0.3048)
			(end -0.67945 -0.3048)
			(stroke
				(width 0.1)
				(type default)
			)
			(layer "B.Fab")
		)
		(fp_line
			(start -0.67945 -0.3048)
			(end -0.67945 0.3048)
			(stroke
				(width 0.1)
				(type default)
			)
			(layer "B.Fab")
		)
		(fp_line
			(start 0.12065 -0.2794)
			(end -0.12065 -0.2794)
			(stroke
				(width 0.1)
				(type default)
			)
			(layer "B.Fab")
		)
		(fp_line
			(start -0.12065 -0.2794)
			(end -0.12065 -0.3048)
			(stroke
				(width 0.1)
				(type default)
			)
			(layer "B.Fab")
		)
		(fp_line
			(start 0.12065 0.2794)
			(end 0.12065 0.3048)
			(stroke
				(width 0.1)
				(type default)
			)
			(layer "B.Fab")
		)
		(fp_line
			(start -0.120396 0.2794)
			(end 0.12065 0.2794)
			(stroke
				(width 0.1)
				(type default)
			)
			(layer "B.Fab")
		)
		(fp_line
			(start 0.67945 0.3048)
			(end 0.67945 -0.305054)
			(stroke
				(width 0.1)
				(type default)
			)
			(layer "B.Fab")
		)
		(fp_line
			(start 0.12065 0.3048)
			(end 0.67945 0.3048)
			(stroke
				(width 0.1)
				(type default)
			)
			(layer "B.Fab")
		)
		(fp_line
			(start -0.120396 0.3048)
			(end -0.120396 0.2794)
			(stroke
				(width 0.1)
				(type default)
			)
			(layer "B.Fab")
		)
		(fp_line
			(start -0.67945 0.3048)
			(end -0.120396 0.3048)
			(stroke
				(width 0.1)
				(type default)
			)
			(layer "B.Fab")
		)
		(pad "1" smd circle
			(at 0.40005 0 270)
			(size 0 0)
			(layers "B.Cu" "B.Mask" "B.Paste")
			(net "FM_PLD_CLK_25M_EN")
		)
		(pad "2" smd circle
			(at -0.40005 0 270)
			(size 0 0)
			(layers "B.Cu" "B.Mask" "B.Paste")
			(net "FM_CK440Q_DEV_25M_EN")
		)
	)
	(footprint ""
		(layer "B.Cu")
		(at 189.039754 -319.450974 180)
		(property "Reference" "C78"
			(at 0 0 0)
			(layer "B.SilkS")
			(hide yes)
			(effects
				(font
					(size 1.27 1.27)
				)
				(justify mirror)
			)
		)
		(property "Value" ""
			(at 0 0 0)
			(layer "B.Fab")
			(effects
				(font
					(size 1.27 1.27)
				)
				(justify mirror)
			)
		)
		(duplicate_pad_numbers_are_jumpers no)
		(fp_line
			(start 0.7874 0.4064)
			(end 0.7874 -0.4064)
			(stroke
				(width 0.1524)
				(type default)
			)
			(layer "B.SilkS")
		)
		(fp_line
			(start 0.7874 -0.4064)
			(end -0.7874 -0.4064)
			(stroke
				(width 0.1524)
				(type default)
			)
			(layer "B.SilkS")
		)
		(fp_line
			(start -0.7874 0.4064)
			(end 0.7874 0.4064)
			(stroke
				(width 0.1524)
				(type default)
			)
			(layer "B.SilkS")
		)
		(fp_line
			(start -0.7874 -0.4064)
			(end -0.7874 0.4064)
			(stroke
				(width 0.1524)
				(type default)
			)
			(layer "B.SilkS")
		)
		(fp_line
			(start 0.67945 0.3048)
			(end 0.67945 -0.305054)
			(stroke
				(width 0.1)
				(type default)
			)
			(layer "B.Fab")
		)
		(fp_line
			(start 0.67945 -0.305054)
			(end 0.12065 -0.305054)
			(stroke
				(width 0.1)
				(type default)
			)
			(layer "B.Fab")
		)
		(fp_line
			(start 0.12065 0.3048)
			(end 0.67945 0.3048)
			(stroke
				(width 0.1)
				(type default)
			)
			(layer "B.Fab")
		)
		(fp_line
			(start 0.12065 0.2794)
			(end 0.12065 0.3048)
			(stroke
				(width 0.1)
				(type default)
			)
			(layer "B.Fab")
		)
		(fp_line
			(start 0.12065 -0.2794)
			(end -0.12065 -0.2794)
			(stroke
				(width 0.1)
				(type default)
			)
			(layer "B.Fab")
		)
		(fp_line
			(start 0.12065 -0.305054)
			(end 0.12065 -0.2794)
			(stroke
				(width 0.1)
				(type default)
			)
			(layer "B.Fab")
		)
		(fp_line
			(start -0.120396 0.3048)
			(end -0.120396 0.2794)
			(stroke
				(width 0.1)
				(type default)
			)
			(layer "B.Fab")
		)
		(fp_line
			(start -0.120396 0.2794)
			(end 0.12065 0.2794)
			(stroke
				(width 0.1)
				(type default)
			)
			(layer "B.Fab")
		)
		(fp_line
			(start -0.12065 -0.2794)
			(end -0.12065 -0.3048)
			(stroke
				(width 0.1)
				(type default)
			)
			(layer "B.Fab")
		)
		(fp_line
			(start -0.12065 -0.3048)
			(end -0.67945 -0.3048)
			(stroke
				(width 0.1)
				(type default)
			)
			(layer "B.Fab")
		)
		(fp_line
			(start -0.67945 0.3048)
			(end -0.120396 0.3048)
			(stroke
				(width 0.1)
				(type default)
			)
			(layer "B.Fab")
		)
		(fp_line
			(start -0.67945 -0.3048)
			(end -0.67945 0.3048)
			(stroke
				(width 0.1)
				(type default)
			)
			(layer "B.Fab")
		)
		(pad "1" smd circle
			(at 0.40005 0)
			(size 0 0)
			(layers "B.Cu" "B.Mask" "B.Paste")
			(net "P3V3_AUX")
		)
		(pad "2" smd circle
			(at -0.40005 0)
			(size 0 0)
			(layers "B.Cu" "B.Mask" "B.Paste")
			(net "GND")
		)
	)
	(footprint ""
		(layer "B.Cu")
		(at 233.55681 -123.015248 -90)
		(property "Reference" "R572"
			(at 0 0 90)
			(layer "B.SilkS")
			(hide yes)
			(effects
				(font
					(size 1.27 1.27)
				)
				(justify mirror)
			)
		)
		(property "Value" ""
			(at 0 0 90)
			(layer "B.Fab")
			(effects
				(font
					(size 1.27 1.27)
				)
				(justify mirror)
			)
		)
		(duplicate_pad_numbers_are_jumpers no)
		(fp_line
			(start -1.2954 0.5842)
			(end 1.2954 0.5842)
			(stroke
				(width 0.1524)
				(type default)
			)
			(layer "B.SilkS")
		)
		(fp_line
			(start 1.2954 0.5842)
			(end 1.2954 -0.5842)
			(stroke
				(width 0.1524)
				(type default)
			)
			(layer "B.SilkS")
		)
		(fp_line
			(start -1.2954 -0.5842)
			(end -1.2954 0.5842)
			(stroke
				(width 0.1524)
				(type default)
			)
			(layer "B.SilkS")
		)
		(fp_line
			(start 1.2954 -0.5842)
			(end -1.2954 -0.5842)
			(stroke
				(width 0.1524)
				(type default)
			)
			(layer "B.SilkS")
		)
		(fp_line
			(start -0.8636 0.4572)
			(end 0.8636 0.4572)
			(stroke
				(width 0.1)
				(type default)
			)
			(layer "B.Fab")
		)
		(fp_line
			(start 0.8636 0.4572)
			(end 0.8636 0.4318)
			(stroke
				(width 0.1)
				(type default)
			)
			(layer "B.Fab")
		)
		(fp_line
			(start 0.8636 0.4318)
			(end 0.8636 0.4064)
			(stroke
				(width 0.1)
				(type default)
			)
			(layer "B.Fab")
		)
		(fp_line
			(start -1.1938 0.4064)
			(end -0.8636 0.4064)
			(stroke
				(width 0.1)
				(type default)
			)
			(layer "B.Fab")
		)
		(fp_line
			(start -0.8636 0.4064)
			(end -0.8636 0.4572)
			(stroke
				(width 0.1)
				(type default)
			)
			(layer "B.Fab")
		)
		(fp_line
			(start 0.8636 0.4064)
			(end 1.1938 0.4064)
			(stroke
				(width 0.1)
				(type default)
			)
			(layer "B.Fab")
		)
		(fp_line
			(start 1.1938 0.4064)
			(end 1.1938 -0.406654)
			(stroke
				(width 0.1)
				(type default)
			)
			(layer "B.Fab")
		)
		(fp_line
			(start -1.1938 -0.406654)
			(end -1.1938 0.4064)
			(stroke
				(width 0.1)
				(type default)
			)
			(layer "B.Fab")
		)
		(fp_line
			(start -0.8636 -0.406654)
			(end -1.1938 -0.406654)
			(stroke
				(width 0.1)
				(type default)
			)
			(layer "B.Fab")
		)
		(fp_line
			(start 0.8636 -0.406654)
			(end 0.8636 -0.4572)
			(stroke
				(width 0.1)
				(type default)
			)
			(layer "B.Fab")
		)
		(fp_line
			(start 1.1938 -0.406654)
			(end 0.8636 -0.406654)
			(stroke
				(width 0.1)
				(type default)
			)
			(layer "B.Fab")
		)
		(fp_line
			(start -0.8636 -0.4572)
			(end -0.8636 -0.406654)
			(stroke
				(width 0.1)
				(type default)
			)
			(layer "B.Fab")
		)
		(fp_line
			(start 0.8636 -0.4572)
			(end -0.8636 -0.4572)
			(stroke
				(width 0.1)
				(type default)
			)
			(layer "B.Fab")
		)
		(pad "1" smd rect
			(at 0.7366 0 180)
			(size 0.7112 0.8128)
			(layers "B.Cu" "B.Mask" "B.Paste")
			(net "P3V3_DB2000_FB_VDD")
		)
		(pad "2" smd rect
			(at -0.7366 0 180)
			(size 0.7112 0.8128)
			(layers "B.Cu" "B.Mask" "B.Paste")
			(net "P3V3_DB2000_VDDA")
		)
	)
	(footprint ""
		(layer "B.Cu")
		(at 180.155596 -112.175544 180)
		(property "Reference" "C1152"
			(at 0 0 0)
			(layer "B.SilkS")
			(hide yes)
			(effects
				(font
					(size 1.27 1.27)
				)
				(justify mirror)
			)
		)
		(property "Value" ""
			(at 0 0 0)
			(layer "B.Fab")
			(effects
				(font
					(size 1.27 1.27)
				)
				(justify mirror)
			)
		)
		(duplicate_pad_numbers_are_jumpers no)
		(fp_line
			(start 0.69215 0.2921)
			(end 0.69215 -0.2921)
			(stroke
				(width 0.1524)
				(type default)
			)
			(layer "B.SilkS")
		)
		(fp_line
			(start 0.69215 -0.2921)
			(end -0.69215 -0.2921)
			(stroke
				(width 0.1524)
				(type default)
			)
			(layer "B.SilkS")
		)
		(fp_line
			(start -0.69215 0.2921)
			(end 0.69215 0.2921)
			(stroke
				(width 0.1524)
				(type default)
			)
			(layer "B.SilkS")
		)
		(fp_line
			(start -0.69215 -0.2921)
			(end -0.69215 0.2921)
			(stroke
				(width 0.1524)
				(type default)
			)
			(layer "B.SilkS")
		)
		(fp_line
			(start 0.51435 0.2794)
			(end 0.51435 -0.2794)
			(stroke
				(width 0.1)
				(type default)
			)
			(layer "B.Fab")
		)
		(fp_line
			(start 0.51435 -0.2794)
			(end -0.51435 -0.2794)
			(stroke
				(width 0.1)
				(type default)
			)
			(layer "B.Fab")
		)
		(fp_line
			(start -0.51435 0.2794)
			(end 0.51435 0.2794)
			(stroke
				(width 0.1)
				(type default)
			)
			(layer "B.Fab")
		)
		(fp_line
			(start -0.51435 -0.2794)
			(end -0.51435 0.2794)
			(stroke
				(width 0.1)
				(type default)
			)
			(layer "B.Fab")
		)
		(pad "1" smd circle
			(at 0.40005 0)
			(size 0 0)
			(layers "B.Cu" "B.Mask" "B.Paste")
			(net "VCC_PLD_CORE")
		)
		(pad "2" smd circle
			(at -0.40005 0)
			(size 0 0)
			(layers "B.Cu" "B.Mask" "B.Paste")
			(net "GND")
		)
		(zone
			(layer "B.Cu")
			(hatch none 0.5)
			(connect_pads
				(clearance 0)
			)
			(min_thickness 0.25)
			(keepout
				(tracks not_allowed)
				(vias allowed)
				(pads allowed)
				(copperpour not_allowed)
				(footprints allowed)
			)
			(placement
				(enabled no)
				(sheetname "")
			)
			(fill
				(thermal_gap 0.5)
				(thermal_bridge_width 0.5)
				(island_removal_mode 0)
			)
			(polygon
				(pts
					(xy 179.965096 -112.263174) (xy 180.056536 -112.32134) (xy 180.255926 -112.32134) (xy 180.346096 -112.263174)
					(xy 180.346096 -112.087914) (xy 180.255926 -112.029494) (xy 180.056536 -112.029494) (xy 179.965096 -112.08766)
				)
			)
		)
	)
	(footprint ""
		(layer "B.Cu")
		(at 251.144786 -86.816946)
		(property "Reference" "R1502"
			(at 0 0 0)
			(layer "B.SilkS")
			(hide yes)
			(effects
				(font
					(size 1.27 1.27)
				)
				(justify mirror)
			)
		)
		(property "Value" ""
			(at 0 0 0)
			(layer "B.Fab")
			(effects
				(font
					(size 1.27 1.27)
				)
				(justify mirror)
			)
		)
		(duplicate_pad_numbers_are_jumpers no)
		(fp_line
			(start -0.7874 -0.4064)
			(end -0.7874 0.4064)
			(stroke
				(width 0.1524)
				(type default)
			)
			(layer "B.SilkS")
		)
		(fp_line
			(start -0.7874 0.4064)
			(end 0.7874 0.4064)
			(stroke
				(width 0.1524)
				(type default)
			)
			(layer "B.SilkS")
		)
		(fp_line
			(start 0.7874 -0.4064)
			(end -0.7874 -0.4064)
			(stroke
				(width 0.1524)
				(type default)
			)
			(layer "B.SilkS")
		)
		(fp_line
			(start 0.7874 0.4064)
			(end 0.7874 -0.4064)
			(stroke
				(width 0.1524)
				(type default)
			)
			(layer "B.SilkS")
		)
		(fp_line
			(start -0.67945 -0.3048)
			(end -0.67945 0.3048)
			(stroke
				(width 0.1)
				(type default)
			)
			(layer "B.Fab")
		)
		(fp_line
			(start -0.67945 0.3048)
			(end -0.120396 0.3048)
			(stroke
				(width 0.1)
				(type default)
			)
			(layer "B.Fab")
		)
		(fp_line
			(start -0.12065 -0.3048)
			(end -0.67945 -0.3048)
			(stroke
				(width 0.1)
				(type default)
			)
			(layer "B.Fab")
		)
		(fp_line
			(start -0.12065 -0.2794)
			(end -0.12065 -0.3048)
			(stroke
				(width 0.1)
				(type default)
			)
			(layer "B.Fab")
		)
		(fp_line
			(start -0.120396 0.2794)
			(end 0.12065 0.2794)
			(stroke
				(width 0.1)
				(type default)
			)
			(layer "B.Fab")
		)
		(fp_line
			(start -0.120396 0.3048)
			(end -0.120396 0.2794)
			(stroke
				(width 0.1)
				(type default)
			)
			(layer "B.Fab")
		)
		(fp_line
			(start 0.12065 -0.305054)
			(end 0.12065 -0.2794)
			(stroke
				(width 0.1)
				(type default)
			)
			(layer "B.Fab")
		)
		(fp_line
			(start 0.12065 -0.2794)
			(end -0.12065 -0.2794)
			(stroke
				(width 0.1)
				(type default)
			)
			(layer "B.Fab")
		)
		(fp_line
			(start 0.12065 0.2794)
			(end 0.12065 0.3048)
			(stroke
				(width 0.1)
				(type default)
			)
			(layer "B.Fab")
		)
		(fp_line
			(start 0.12065 0.3048)
			(end 0.67945 0.3048)
			(stroke
				(width 0.1)
				(type default)
			)
			(layer "B.Fab")
		)
		(fp_line
			(start 0.67945 -0.305054)
			(end 0.12065 -0.305054)
			(stroke
				(width 0.1)
				(type default)
			)
			(layer "B.Fab")
		)
		(fp_line
			(start 0.67945 0.3048)
			(end 0.67945 -0.305054)
			(stroke
				(width 0.1)
				(type default)
			)
			(layer "B.Fab")
		)
		(pad "1" smd circle
			(at 0.40005 0 180)
			(size 0 0)
			(layers "B.Cu" "B.Mask" "B.Paste")
			(net "FM_CLK_CK440_SS_EN")
		)
		(pad "2" smd circle
			(at -0.40005 0 180)
			(size 0 0)
			(layers "B.Cu" "B.Mask" "B.Paste")
			(net "GND")
		)
	)
	(footprint ""
		(layer "B.Cu")
		(at 450.732398 -76.719176 90)
		(property "Reference" "R3118"
			(at 0 0 90)
			(layer "B.SilkS")
			(hide yes)
			(effects
				(font
					(size 1.27 1.27)
				)
				(justify mirror)
			)
		)
		(property "Value" ""
			(at 0 0 90)
			(layer "B.Fab")
			(effects
				(font
					(size 1.27 1.27)
				)
				(justify mirror)
			)
		)
		(duplicate_pad_numbers_are_jumpers no)
		(fp_line
			(start 0.7874 -0.4064)
			(end -0.7874 -0.4064)
			(stroke
				(width 0.1524)
				(type default)
			)
			(layer "B.SilkS")
		)
		(fp_line
			(start -0.7874 -0.4064)
			(end -0.7874 0.4064)
			(stroke
				(width 0.1524)
				(type default)
			)
			(layer "B.SilkS")
		)
		(fp_line
			(start 0.7874 0.4064)
			(end 0.7874 -0.4064)
			(stroke
				(width 0.1524)
				(type default)
			)
			(layer "B.SilkS")
		)
		(fp_line
			(start -0.7874 0.4064)
			(end 0.7874 0.4064)
			(stroke
				(width 0.1524)
				(type default)
			)
			(layer "B.SilkS")
		)
		(fp_line
			(start 0.67945 -0.305054)
			(end 0.12065 -0.305054)
			(stroke
				(width 0.1)
				(type default)
			)
			(layer "B.Fab")
		)
		(fp_line
			(start 0.12065 -0.305054)
			(end 0.12065 -0.2794)
			(stroke
				(width 0.1)
				(type default)
			)
			(layer "B.Fab")
		)
		(fp_line
			(start -0.12065 -0.3048)
			(end -0.67945 -0.3048)
			(stroke
				(width 0.1)
				(type default)
			)
			(layer "B.Fab")
		)
		(fp_line
			(start -0.67945 -0.3048)
			(end -0.67945 0.3048)
			(stroke
				(width 0.1)
				(type default)
			)
			(layer "B.Fab")
		)
		(fp_line
			(start 0.12065 -0.2794)
			(end -0.12065 -0.2794)
			(stroke
				(width 0.1)
				(type default)
			)
			(layer "B.Fab")
		)
		(fp_line
			(start -0.12065 -0.2794)
			(end -0.12065 -0.3048)
			(stroke
				(width 0.1)
				(type default)
			)
			(layer "B.Fab")
		)
		(fp_line
			(start 0.12065 0.2794)
			(end 0.12065 0.3048)
			(stroke
				(width 0.1)
				(type default)
			)
			(layer "B.Fab")
		)
		(fp_line
			(start -0.120396 0.2794)
			(end 0.12065 0.2794)
			(stroke
				(width 0.1)
				(type default)
			)
			(layer "B.Fab")
		)
		(fp_line
			(start 0.67945 0.3048)
			(end 0.67945 -0.305054)
			(stroke
				(width 0.1)
				(type default)
			)
			(layer "B.Fab")
		)
		(fp_line
			(start 0.12065 0.3048)
			(end 0.67945 0.3048)
			(stroke
				(width 0.1)
				(type default)
			)
			(layer "B.Fab")
		)
		(fp_line
			(start -0.120396 0.3048)
			(end -0.120396 0.2794)
			(stroke
				(width 0.1)
				(type default)
			)
			(layer "B.Fab")
		)
		(fp_line
			(start -0.67945 0.3048)
			(end -0.120396 0.3048)
			(stroke
				(width 0.1)
				(type default)
			)
			(layer "B.Fab")
		)
		(pad "1" smd circle
			(at 0.40005 0 270)
			(size 0 0)
			(layers "B.Cu" "B.Mask" "B.Paste")
			(net "P3V3_AUX_EN")
		)
		(pad "2" smd circle
			(at -0.40005 0 270)
			(size 0 0)
			(layers "B.Cu" "B.Mask" "B.Paste")
			(net "GND")
		)
	)
	(footprint ""
		(layer "B.Cu")
		(at 354.219764 -333.639922 90)
		(property "Reference" "PC306_P0_2"
			(at 0 0 90)
			(layer "B.SilkS")
			(hide yes)
			(effects
				(font
					(size 1.27 1.27)
				)
				(justify mirror)
			)
		)
		(property "Value" ""
			(at 0 0 90)
			(layer "B.Fab")
			(effects
				(font
					(size 1.27 1.27)
				)
				(justify mirror)
			)
		)
		(duplicate_pad_numbers_are_jumpers no)
		(fp_line
			(start 1.524 -0.762)
			(end -1.524 -0.762)
			(stroke
				(width 0.1524)
				(type default)
			)
			(layer "B.SilkS")
		)
		(fp_line
			(start -1.524 -0.762)
			(end -1.524 0.762)
			(stroke
				(width 0.1524)
				(type default)
			)
			(layer "B.SilkS")
		)
		(fp_line
			(start 1.524 0.762)
			(end 1.524 -0.762)
			(stroke
				(width 0.1524)
				(type default)
			)
			(layer "B.SilkS")
		)
		(fp_line
			(start -1.524 0.762)
			(end 1.524 0.762)
			(stroke
				(width 0.1524)
				(type default)
			)
			(layer "B.SilkS")
		)
		(fp_line
			(start 1.1049 -0.724916)
			(end 1.1049 0.724916)
			(stroke
				(width 0.1)
				(type default)
			)
			(layer "B.Fab")
		)
		(fp_line
			(start -1.1049 -0.724916)
			(end 1.1049 -0.724916)
			(stroke
				(width 0.1)
				(type default)
			)
			(layer "B.Fab")
		)
		(fp_line
			(start 1.1049 0.724916)
			(end -1.1049 0.724916)
			(stroke
				(width 0.1)
				(type default)
			)
			(layer "B.Fab")
		)
		(fp_line
			(start -1.1049 0.724916)
			(end -1.1049 -0.724916)
			(stroke
				(width 0.1)
				(type default)
			)
			(layer "B.Fab")
		)
		(pad "1" smd rect
			(at 0.889 0 90)
			(size 1.016 1.27)
			(layers "B.Cu" "B.Mask" "B.Paste")
			(net "SW_P12V_PVCCIN_CPU0_FLT")
		)
		(pad "2" smd rect
			(at -0.889 0 90)
			(size 1.016 1.27)
			(layers "B.Cu" "B.Mask" "B.Paste")
			(net "GND")
		)
	)
	(footprint ""
		(layer "B.Cu")
		(at 131.93522 -24.100028 180)
		(property "Reference" "C2289"
			(at 0 0 0)
			(layer "B.SilkS")
			(hide yes)
			(effects
				(font
					(size 1.27 1.27)
				)
				(justify mirror)
			)
		)
		(property "Value" ""
			(at 0 0 0)
			(layer "B.Fab")
			(effects
				(font
					(size 1.27 1.27)
				)
				(justify mirror)
			)
		)
		(duplicate_pad_numbers_are_jumpers no)
		(fp_line
			(start 0.299974 0.150114)
			(end 0.299974 -0.150114)
			(stroke
				(width 0.1)
				(type default)
			)
			(layer "B.Fab")
		)
		(fp_line
			(start 0.299974 -0.150114)
			(end -0.299974 -0.150114)
			(stroke
				(width 0.1)
				(type default)
			)
			(layer "B.Fab")
		)
		(fp_line
			(start -0.299974 0.150114)
			(end 0.299974 0.150114)
			(stroke
				(width 0.1)
				(type default)
			)
			(layer "B.Fab")
		)
		(fp_line
			(start -0.299974 -0.150114)
			(end -0.299974 0.150114)
			(stroke
				(width 0.1)
				(type default)
			)
			(layer "B.Fab")
		)
		(pad "1" smd rect
			(at 0.2667 0)
			(size 0.3048 0.381)
			(layers "B.Cu" "B.Mask" "B.Paste")
			(net "USB3_PCH_TX_BUF_DP<4>")
		)
		(pad "2" smd rect
			(at -0.2667 0)
			(size 0.3048 0.381)
			(layers "B.Cu" "B.Mask" "B.Paste")
			(net "USB3_PCH_TX_BUF_C_DP<4>")
		)
	)
	(footprint ""
		(layer "B.Cu")
		(at 320.178176 -58.298588 -90)
		(property "Reference" "R3042"
			(at 0 0 90)
			(layer "B.SilkS")
			(hide yes)
			(effects
				(font
					(size 1.27 1.27)
				)
				(justify mirror)
			)
		)
		(property "Value" ""
			(at 0 0 90)
			(layer "B.Fab")
			(effects
				(font
					(size 1.27 1.27)
				)
				(justify mirror)
			)
		)
		(duplicate_pad_numbers_are_jumpers no)
		(fp_line
			(start -0.7874 0.4064)
			(end 0.7874 0.4064)
			(stroke
				(width 0.1524)
				(type default)
			)
			(layer "B.SilkS")
		)
		(fp_line
			(start 0.7874 0.4064)
			(end 0.7874 -0.4064)
			(stroke
				(width 0.1524)
				(type default)
			)
			(layer "B.SilkS")
		)
		(fp_line
			(start -0.7874 -0.4064)
			(end -0.7874 0.4064)
			(stroke
				(width 0.1524)
				(type default)
			)
			(layer "B.SilkS")
		)
		(fp_line
			(start 0.7874 -0.4064)
			(end -0.7874 -0.4064)
			(stroke
				(width 0.1524)
				(type default)
			)
			(layer "B.SilkS")
		)
		(fp_line
			(start -0.67945 0.3048)
			(end -0.120396 0.3048)
			(stroke
				(width 0.1)
				(type default)
			)
			(layer "B.Fab")
		)
		(fp_line
			(start -0.120396 0.3048)
			(end -0.120396 0.2794)
			(stroke
				(width 0.1)
				(type default)
			)
			(layer "B.Fab")
		)
		(fp_line
			(start 0.12065 0.3048)
			(end 0.67945 0.3048)
			(stroke
				(width 0.1)
				(type default)
			)
			(layer "B.Fab")
		)
		(fp_line
			(start 0.67945 0.3048)
			(end 0.67945 -0.305054)
			(stroke
				(width 0.1)
				(type default)
			)
			(layer "B.Fab")
		)
		(fp_line
			(start -0.120396 0.2794)
			(end 0.12065 0.2794)
			(stroke
				(width 0.1)
				(type default)
			)
			(layer "B.Fab")
		)
		(fp_line
			(start 0.12065 0.2794)
			(end 0.12065 0.3048)
			(stroke
				(width 0.1)
				(type default)
			)
			(layer "B.Fab")
		)
		(fp_line
			(start -0.12065 -0.2794)
			(end -0.12065 -0.3048)
			(stroke
				(width 0.1)
				(type default)
			)
			(layer "B.Fab")
		)
		(fp_line
			(start 0.12065 -0.2794)
			(end -0.12065 -0.2794)
			(stroke
				(width 0.1)
				(type default)
			)
			(layer "B.Fab")
		)
		(fp_line
			(start -0.67945 -0.3048)
			(end -0.67945 0.3048)
			(stroke
				(width 0.1)
				(type default)
			)
			(layer "B.Fab")
		)
		(fp_line
			(start -0.12065 -0.3048)
			(end -0.67945 -0.3048)
			(stroke
				(width 0.1)
				(type default)
			)
			(layer "B.Fab")
		)
		(fp_line
			(start 0.12065 -0.305054)
			(end 0.12065 -0.2794)
			(stroke
				(width 0.1)
				(type default)
			)
			(layer "B.Fab")
		)
		(fp_line
			(start 0.67945 -0.305054)
			(end 0.12065 -0.305054)
			(stroke
				(width 0.1)
				(type default)
			)
			(layer "B.Fab")
		)
		(pad "1" smd circle
			(at 0.40005 0 90)
			(size 0 0)
			(layers "B.Cu" "B.Mask" "B.Paste")
			(net "P1V05_PCH_AUX")
		)
		(pad "2" smd circle
			(at -0.40005 0 90)
			(size 0 0)
			(layers "B.Cu" "B.Mask" "B.Paste")
			(net "H_CPU_ERR1_PCH_R_N")
		)
	)
	(footprint ""
		(layer "B.Cu")
		(at 336.17408 -43.504358)
		(property "Reference" "C1203"
			(at 0 0 0)
			(layer "B.SilkS")
			(hide yes)
			(effects
				(font
					(size 1.27 1.27)
				)
				(justify mirror)
			)
		)
		(property "Value" ""
			(at 0 0 0)
			(layer "B.Fab")
			(effects
				(font
					(size 1.27 1.27)
				)
				(justify mirror)
			)
		)
		(duplicate_pad_numbers_are_jumpers no)
		(fp_line
			(start -0.7874 -0.4064)
			(end -0.7874 0.4064)
			(stroke
				(width 0.1524)
				(type default)
			)
			(layer "B.SilkS")
		)
		(fp_line
			(start -0.7874 0.4064)
			(end 0.7874 0.4064)
			(stroke
				(width 0.1524)
				(type default)
			)
			(layer "B.SilkS")
		)
		(fp_line
			(start 0.7874 -0.4064)
			(end -0.7874 -0.4064)
			(stroke
				(width 0.1524)
				(type default)
			)
			(layer "B.SilkS")
		)
		(fp_line
			(start 0.7874 0.4064)
			(end 0.7874 -0.4064)
			(stroke
				(width 0.1524)
				(type default)
			)
			(layer "B.SilkS")
		)
		(fp_line
			(start -0.67945 -0.3048)
			(end -0.67945 0.3048)
			(stroke
				(width 0.1)
				(type default)
			)
			(layer "B.Fab")
		)
		(fp_line
			(start -0.67945 0.3048)
			(end -0.120396 0.3048)
			(stroke
				(width 0.1)
				(type default)
			)
			(layer "B.Fab")
		)
		(fp_line
			(start -0.12065 -0.3048)
			(end -0.67945 -0.3048)
			(stroke
				(width 0.1)
				(type default)
			)
			(layer "B.Fab")
		)
		(fp_line
			(start -0.12065 -0.2794)
			(end -0.12065 -0.3048)
			(stroke
				(width 0.1)
				(type default)
			)
			(layer "B.Fab")
		)
		(fp_line
			(start -0.120396 0.2794)
			(end 0.12065 0.2794)
			(stroke
				(width 0.1)
				(type default)
			)
			(layer "B.Fab")
		)
		(fp_line
			(start -0.120396 0.3048)
			(end -0.120396 0.2794)
			(stroke
				(width 0.1)
				(type default)
			)
			(layer "B.Fab")
		)
		(fp_line
			(start 0.12065 -0.305054)
			(end 0.12065 -0.2794)
			(stroke
				(width 0.1)
				(type default)
			)
			(layer "B.Fab")
		)
		(fp_line
			(start 0.12065 -0.2794)
			(end -0.12065 -0.2794)
			(stroke
				(width 0.1)
				(type default)
			)
			(layer "B.Fab")
		)
		(fp_line
			(start 0.12065 0.2794)
			(end 0.12065 0.3048)
			(stroke
				(width 0.1)
				(type default)
			)
			(layer "B.Fab")
		)
		(fp_line
			(start 0.12065 0.3048)
			(end 0.67945 0.3048)
			(stroke
				(width 0.1)
				(type default)
			)
			(layer "B.Fab")
		)
		(fp_line
			(start 0.67945 -0.305054)
			(end 0.12065 -0.305054)
			(stroke
				(width 0.1)
				(type default)
			)
			(layer "B.Fab")
		)
		(fp_line
			(start 0.67945 0.3048)
			(end 0.67945 -0.305054)
			(stroke
				(width 0.1)
				(type default)
			)
			(layer "B.Fab")
		)
		(pad "1" smd circle
			(at 0.40005 0 180)
			(size 0 0)
			(layers "B.Cu" "B.Mask" "B.Paste")
			(net "P1V05_PCH_AUX")
		)
		(pad "2" smd circle
			(at -0.40005 0 180)
			(size 0 0)
			(layers "B.Cu" "B.Mask" "B.Paste")
			(net "GND")
		)
	)
	(footprint ""
		(layer "B.Cu")
		(at 80.763618 -188.552836 -90)
		(property "Reference" "R49"
			(at 0 0 90)
			(layer "B.SilkS")
			(hide yes)
			(effects
				(font
					(size 1.27 1.27)
				)
				(justify mirror)
			)
		)
		(property "Value" ""
			(at 0 0 90)
			(layer "B.Fab")
			(effects
				(font
					(size 1.27 1.27)
				)
				(justify mirror)
			)
		)
		(duplicate_pad_numbers_are_jumpers no)
		(fp_line
			(start -0.7874 0.4064)
			(end 0.7874 0.4064)
			(stroke
				(width 0.1524)
				(type default)
			)
			(layer "B.SilkS")
		)
		(fp_line
			(start 0.7874 0.4064)
			(end 0.7874 -0.4064)
			(stroke
				(width 0.1524)
				(type default)
			)
			(layer "B.SilkS")
		)
		(fp_line
			(start -0.7874 -0.4064)
			(end -0.7874 0.4064)
			(stroke
				(width 0.1524)
				(type default)
			)
			(layer "B.SilkS")
		)
		(fp_line
			(start 0.7874 -0.4064)
			(end -0.7874 -0.4064)
			(stroke
				(width 0.1524)
				(type default)
			)
			(layer "B.SilkS")
		)
		(fp_line
			(start -0.67945 0.3048)
			(end -0.120396 0.3048)
			(stroke
				(width 0.1)
				(type default)
			)
			(layer "B.Fab")
		)
		(fp_line
			(start -0.120396 0.3048)
			(end -0.120396 0.2794)
			(stroke
				(width 0.1)
				(type default)
			)
			(layer "B.Fab")
		)
		(fp_line
			(start 0.12065 0.3048)
			(end 0.67945 0.3048)
			(stroke
				(width 0.1)
				(type default)
			)
			(layer "B.Fab")
		)
		(fp_line
			(start 0.67945 0.3048)
			(end 0.67945 -0.305054)
			(stroke
				(width 0.1)
				(type default)
			)
			(layer "B.Fab")
		)
		(fp_line
			(start -0.120396 0.2794)
			(end 0.12065 0.2794)
			(stroke
				(width 0.1)
				(type default)
			)
			(layer "B.Fab")
		)
		(fp_line
			(start 0.12065 0.2794)
			(end 0.12065 0.3048)
			(stroke
				(width 0.1)
				(type default)
			)
			(layer "B.Fab")
		)
		(fp_line
			(start -0.12065 -0.2794)
			(end -0.12065 -0.3048)
			(stroke
				(width 0.1)
				(type default)
			)
			(layer "B.Fab")
		)
		(fp_line
			(start 0.12065 -0.2794)
			(end -0.12065 -0.2794)
			(stroke
				(width 0.1)
				(type default)
			)
			(layer "B.Fab")
		)
		(fp_line
			(start -0.67945 -0.3048)
			(end -0.67945 0.3048)
			(stroke
				(width 0.1)
				(type default)
			)
			(layer "B.Fab")
		)
		(fp_line
			(start -0.12065 -0.3048)
			(end -0.67945 -0.3048)
			(stroke
				(width 0.1)
				(type default)
			)
			(layer "B.Fab")
		)
		(fp_line
			(start 0.12065 -0.305054)
			(end 0.12065 -0.2794)
			(stroke
				(width 0.1)
				(type default)
			)
			(layer "B.Fab")
		)
		(fp_line
			(start 0.67945 -0.305054)
			(end 0.12065 -0.305054)
			(stroke
				(width 0.1)
				(type default)
			)
			(layer "B.Fab")
		)
		(pad "1" smd circle
			(at 0.40005 0 90)
			(size 0 0)
			(layers "B.Cu" "B.Mask" "B.Paste")
			(net "PVNN_TERM_CPU1")
		)
		(pad "2" smd circle
			(at -0.40005 0 90)
			(size 0 0)
			(layers "B.Cu" "B.Mask" "B.Paste")
			(net "DBP_CPU_MBP0_GTL_N")
		)
	)
	(footprint ""
		(layer "B.Cu")
		(at 436.941214 -319.263776 180)
		(property "Reference" "C41"
			(at 0 0 0)
			(layer "B.SilkS")
			(hide yes)
			(effects
				(font
					(size 1.27 1.27)
				)
				(justify mirror)
			)
		)
		(property "Value" ""
			(at 0 0 0)
			(layer "B.Fab")
			(effects
				(font
					(size 1.27 1.27)
				)
				(justify mirror)
			)
		)
		(duplicate_pad_numbers_are_jumpers no)
		(fp_line
			(start 0.7874 0.4064)
			(end 0.7874 -0.4064)
			(stroke
				(width 0.1524)
				(type default)
			)
			(layer "B.SilkS")
		)
		(fp_line
			(start 0.7874 -0.4064)
			(end -0.7874 -0.4064)
			(stroke
				(width 0.1524)
				(type default)
			)
			(layer "B.SilkS")
		)
		(fp_line
			(start -0.7874 0.4064)
			(end 0.7874 0.4064)
			(stroke
				(width 0.1524)
				(type default)
			)
			(layer "B.SilkS")
		)
		(fp_line
			(start -0.7874 -0.4064)
			(end -0.7874 0.4064)
			(stroke
				(width 0.1524)
				(type default)
			)
			(layer "B.SilkS")
		)
		(fp_line
			(start 0.67945 0.3048)
			(end 0.67945 -0.305054)
			(stroke
				(width 0.1)
				(type default)
			)
			(layer "B.Fab")
		)
		(fp_line
			(start 0.67945 -0.305054)
			(end 0.12065 -0.305054)
			(stroke
				(width 0.1)
				(type default)
			)
			(layer "B.Fab")
		)
		(fp_line
			(start 0.12065 0.3048)
			(end 0.67945 0.3048)
			(stroke
				(width 0.1)
				(type default)
			)
			(layer "B.Fab")
		)
		(fp_line
			(start 0.12065 0.2794)
			(end 0.12065 0.3048)
			(stroke
				(width 0.1)
				(type default)
			)
			(layer "B.Fab")
		)
		(fp_line
			(start 0.12065 -0.2794)
			(end -0.12065 -0.2794)
			(stroke
				(width 0.1)
				(type default)
			)
			(layer "B.Fab")
		)
		(fp_line
			(start 0.12065 -0.305054)
			(end 0.12065 -0.2794)
			(stroke
				(width 0.1)
				(type default)
			)
			(layer "B.Fab")
		)
		(fp_line
			(start -0.120396 0.3048)
			(end -0.120396 0.2794)
			(stroke
				(width 0.1)
				(type default)
			)
			(layer "B.Fab")
		)
		(fp_line
			(start -0.120396 0.2794)
			(end 0.12065 0.2794)
			(stroke
				(width 0.1)
				(type default)
			)
			(layer "B.Fab")
		)
		(fp_line
			(start -0.12065 -0.2794)
			(end -0.12065 -0.3048)
			(stroke
				(width 0.1)
				(type default)
			)
			(layer "B.Fab")
		)
		(fp_line
			(start -0.12065 -0.3048)
			(end -0.67945 -0.3048)
			(stroke
				(width 0.1)
				(type default)
			)
			(layer "B.Fab")
		)
		(fp_line
			(start -0.67945 0.3048)
			(end -0.120396 0.3048)
			(stroke
				(width 0.1)
				(type default)
			)
			(layer "B.Fab")
		)
		(fp_line
			(start -0.67945 -0.3048)
			(end -0.67945 0.3048)
			(stroke
				(width 0.1)
				(type default)
			)
			(layer "B.Fab")
		)
		(pad "1" smd circle
			(at 0.40005 0)
			(size 0 0)
			(layers "B.Cu" "B.Mask" "B.Paste")
			(net "P3V3_AUX")
		)
		(pad "2" smd circle
			(at -0.40005 0)
			(size 0 0)
			(layers "B.Cu" "B.Mask" "B.Paste")
			(net "GND")
		)
	)
	(footprint ""
		(layer "B.Cu")
		(at 407.91892 -35.187128)
		(property "Reference" "ME4"
			(at 9.652 -9.540748 0)
			(unlocked yes)
			(layer "B.SilkS")
			(effects
				(font
					(size 0.7874 0.5842)
					(thickness 0.1524)
				)
				(justify left mirror)
			)
		)
		(property "Value" ""
			(at 0 0 0)
			(layer "B.Fab")
			(effects
				(font
					(size 1.27 1.27)
				)
				(justify mirror)
			)
		)
		(duplicate_pad_numbers_are_jumpers no)
	)
	(footprint ""
		(layer "B.Cu")
		(at 228.71684 -125.202188 -90)
		(property "Reference" "C1409"
			(at 0 0 90)
			(layer "B.SilkS")
			(hide yes)
			(effects
				(font
					(size 1.27 1.27)
				)
				(justify mirror)
			)
		)
		(property "Value" ""
			(at 0 0 90)
			(layer "B.Fab")
			(effects
				(font
					(size 1.27 1.27)
				)
				(justify mirror)
			)
		)
		(duplicate_pad_numbers_are_jumpers no)
		(fp_line
			(start -1.2954 0.5842)
			(end 1.2954 0.5842)
			(stroke
				(width 0.1524)
				(type default)
			)
			(layer "B.SilkS")
		)
		(fp_line
			(start 1.2954 0.5842)
			(end 1.2954 -0.5842)
			(stroke
				(width 0.1524)
				(type default)
			)
			(layer "B.SilkS")
		)
		(fp_line
			(start -1.2954 -0.5842)
			(end -1.2954 0.5842)
			(stroke
				(width 0.1524)
				(type default)
			)
			(layer "B.SilkS")
		)
		(fp_line
			(start 0 -0.5842)
			(end 0 0.5842)
			(stroke
				(width 0.1524)
				(type default)
			)
			(layer "B.SilkS")
		)
		(fp_line
			(start 1.2954 -0.5842)
			(end -1.2954 -0.5842)
			(stroke
				(width 0.1524)
				(type default)
			)
			(layer "B.SilkS")
		)
		(fp_line
			(start -0.8636 0.4572)
			(end 0.8636 0.4572)
			(stroke
				(width 0.1)
				(type default)
			)
			(layer "B.Fab")
		)
		(fp_line
			(start 0.8636 0.4572)
			(end 0.8636 0.4064)
			(stroke
				(width 0.1)
				(type default)
			)
			(layer "B.Fab")
		)
		(fp_line
			(start -1.1938 0.4064)
			(end -0.8636 0.4064)
			(stroke
				(width 0.1)
				(type default)
			)
			(layer "B.Fab")
		)
		(fp_line
			(start -0.8636 0.4064)
			(end -0.8636 0.4572)
			(stroke
				(width 0.1)
				(type default)
			)
			(layer "B.Fab")
		)
		(fp_line
			(start 0.8636 0.4064)
			(end 1.1938 0.4064)
			(stroke
				(width 0.1)
				(type default)
			)
			(layer "B.Fab")
		)
		(fp_line
			(start 1.1938 0.4064)
			(end 1.1938 -0.4064)
			(stroke
				(width 0.1)
				(type default)
			)
			(layer "B.Fab")
		)
		(fp_line
			(start -1.1938 -0.4064)
			(end -1.1938 0.4064)
			(stroke
				(width 0.1)
				(type default)
			)
			(layer "B.Fab")
		)
		(fp_line
			(start -0.8636 -0.4064)
			(end -1.1938 -0.4064)
			(stroke
				(width 0.1)
				(type default)
			)
			(layer "B.Fab")
		)
		(fp_line
			(start 0.8636 -0.4064)
			(end 0.8636 -0.4572)
			(stroke
				(width 0.1)
				(type default)
			)
			(layer "B.Fab")
		)
		(fp_line
			(start 1.1938 -0.4064)
			(end 0.8636 -0.4064)
			(stroke
				(width 0.1)
				(type default)
			)
			(layer "B.Fab")
		)
		(fp_line
			(start -0.8636 -0.4572)
			(end -0.8636 -0.4064)
			(stroke
				(width 0.1)
				(type default)
			)
			(layer "B.Fab")
		)
		(fp_line
			(start 0.8636 -0.4572)
			(end -0.8636 -0.4572)
			(stroke
				(width 0.1)
				(type default)
			)
			(layer "B.Fab")
		)
		(pad "1" smd rect
			(at 0.7366 0 180)
			(size 0.7112 0.8128)
			(layers "B.Cu" "B.Mask" "B.Paste")
			(net "P3V3_DB2000_VDD")
		)
		(pad "2" smd rect
			(at -0.7366 0 180)
			(size 0.7112 0.8128)
			(layers "B.Cu" "B.Mask" "B.Paste")
			(net "GND")
		)
	)
	(footprint ""
		(layer "B.Cu")
		(at 373.112538 -187.99429 90)
		(property "Reference" "R910"
			(at 0 0 90)
			(layer "B.SilkS")
			(hide yes)
			(effects
				(font
					(size 1.27 1.27)
				)
				(justify mirror)
			)
		)
		(property "Value" ""
			(at 0 0 90)
			(layer "B.Fab")
			(effects
				(font
					(size 1.27 1.27)
				)
				(justify mirror)
			)
		)
		(duplicate_pad_numbers_are_jumpers no)
		(fp_line
			(start 0.7874 -0.4064)
			(end -0.7874 -0.4064)
			(stroke
				(width 0.1524)
				(type default)
			)
			(layer "B.SilkS")
		)
		(fp_line
			(start -0.7874 -0.4064)
			(end -0.7874 0.4064)
			(stroke
				(width 0.1524)
				(type default)
			)
			(layer "B.SilkS")
		)
		(fp_line
			(start 0.7874 0.4064)
			(end 0.7874 -0.4064)
			(stroke
				(width 0.1524)
				(type default)
			)
			(layer "B.SilkS")
		)
		(fp_line
			(start -0.7874 0.4064)
			(end 0.7874 0.4064)
			(stroke
				(width 0.1524)
				(type default)
			)
			(layer "B.SilkS")
		)
		(fp_line
			(start 0.67945 -0.305054)
			(end 0.12065 -0.305054)
			(stroke
				(width 0.1)
				(type default)
			)
			(layer "B.Fab")
		)
		(fp_line
			(start 0.12065 -0.305054)
			(end 0.12065 -0.2794)
			(stroke
				(width 0.1)
				(type default)
			)
			(layer "B.Fab")
		)
		(fp_line
			(start -0.12065 -0.3048)
			(end -0.67945 -0.3048)
			(stroke
				(width 0.1)
				(type default)
			)
			(layer "B.Fab")
		)
		(fp_line
			(start -0.67945 -0.3048)
			(end -0.67945 0.3048)
			(stroke
				(width 0.1)
				(type default)
			)
			(layer "B.Fab")
		)
		(fp_line
			(start 0.12065 -0.2794)
			(end -0.12065 -0.2794)
			(stroke
				(width 0.1)
				(type default)
			)
			(layer "B.Fab")
		)
		(fp_line
			(start -0.12065 -0.2794)
			(end -0.12065 -0.3048)
			(stroke
				(width 0.1)
				(type default)
			)
			(layer "B.Fab")
		)
		(fp_line
			(start 0.12065 0.2794)
			(end 0.12065 0.3048)
			(stroke
				(width 0.1)
				(type default)
			)
			(layer "B.Fab")
		)
		(fp_line
			(start -0.120396 0.2794)
			(end 0.12065 0.2794)
			(stroke
				(width 0.1)
				(type default)
			)
			(layer "B.Fab")
		)
		(fp_line
			(start 0.67945 0.3048)
			(end 0.67945 -0.305054)
			(stroke
				(width 0.1)
				(type default)
			)
			(layer "B.Fab")
		)
		(fp_line
			(start 0.12065 0.3048)
			(end 0.67945 0.3048)
			(stroke
				(width 0.1)
				(type default)
			)
			(layer "B.Fab")
		)
		(fp_line
			(start -0.120396 0.3048)
			(end -0.120396 0.2794)
			(stroke
				(width 0.1)
				(type default)
			)
			(layer "B.Fab")
		)
		(fp_line
			(start -0.67945 0.3048)
			(end -0.120396 0.3048)
			(stroke
				(width 0.1)
				(type default)
			)
			(layer "B.Fab")
		)
		(pad "1" smd circle
			(at 0.40005 0 270)
			(size 0 0)
			(layers "B.Cu" "B.Mask" "B.Paste")
			(net "PVNN_TERM_CPU0")
		)
		(pad "2" smd circle
			(at -0.40005 0 270)
			(size 0 0)
			(layers "B.Cu" "B.Mask" "B.Paste")
			(net "SMB_PEHPCPU0_GTL_R_SCL")
		)
	)
	(footprint ""
		(layer "B.Cu")
		(at 324.423278 -186.68619 -90)
		(property "Reference" "R275"
			(at 0 0 90)
			(layer "B.SilkS")
			(hide yes)
			(effects
				(font
					(size 1.27 1.27)
				)
				(justify mirror)
			)
		)
		(property "Value" ""
			(at 0 0 90)
			(layer "B.Fab")
			(effects
				(font
					(size 1.27 1.27)
				)
				(justify mirror)
			)
		)
		(duplicate_pad_numbers_are_jumpers no)
		(fp_line
			(start -0.7874 0.4064)
			(end 0.7874 0.4064)
			(stroke
				(width 0.1524)
				(type default)
			)
			(layer "B.SilkS")
		)
		(fp_line
			(start 0.7874 0.4064)
			(end 0.7874 -0.4064)
			(stroke
				(width 0.1524)
				(type default)
			)
			(layer "B.SilkS")
		)
		(fp_line
			(start -0.7874 -0.4064)
			(end -0.7874 0.4064)
			(stroke
				(width 0.1524)
				(type default)
			)
			(layer "B.SilkS")
		)
		(fp_line
			(start 0.7874 -0.4064)
			(end -0.7874 -0.4064)
			(stroke
				(width 0.1524)
				(type default)
			)
			(layer "B.SilkS")
		)
		(fp_line
			(start -0.67945 0.3048)
			(end -0.120396 0.3048)
			(stroke
				(width 0.1)
				(type default)
			)
			(layer "B.Fab")
		)
		(fp_line
			(start -0.120396 0.3048)
			(end -0.120396 0.2794)
			(stroke
				(width 0.1)
				(type default)
			)
			(layer "B.Fab")
		)
		(fp_line
			(start 0.12065 0.3048)
			(end 0.67945 0.3048)
			(stroke
				(width 0.1)
				(type default)
			)
			(layer "B.Fab")
		)
		(fp_line
			(start 0.67945 0.3048)
			(end 0.67945 -0.305054)
			(stroke
				(width 0.1)
				(type default)
			)
			(layer "B.Fab")
		)
		(fp_line
			(start -0.120396 0.2794)
			(end 0.12065 0.2794)
			(stroke
				(width 0.1)
				(type default)
			)
			(layer "B.Fab")
		)
		(fp_line
			(start 0.12065 0.2794)
			(end 0.12065 0.3048)
			(stroke
				(width 0.1)
				(type default)
			)
			(layer "B.Fab")
		)
		(fp_line
			(start -0.12065 -0.2794)
			(end -0.12065 -0.3048)
			(stroke
				(width 0.1)
				(type default)
			)
			(layer "B.Fab")
		)
		(fp_line
			(start 0.12065 -0.2794)
			(end -0.12065 -0.2794)
			(stroke
				(width 0.1)
				(type default)
			)
			(layer "B.Fab")
		)
		(fp_line
			(start -0.67945 -0.3048)
			(end -0.67945 0.3048)
			(stroke
				(width 0.1)
				(type default)
			)
			(layer "B.Fab")
		)
		(fp_line
			(start -0.12065 -0.3048)
			(end -0.67945 -0.3048)
			(stroke
				(width 0.1)
				(type default)
			)
			(layer "B.Fab")
		)
		(fp_line
			(start 0.12065 -0.305054)
			(end 0.12065 -0.2794)
			(stroke
				(width 0.1)
				(type default)
			)
			(layer "B.Fab")
		)
		(fp_line
			(start 0.67945 -0.305054)
			(end 0.12065 -0.305054)
			(stroke
				(width 0.1)
				(type default)
			)
			(layer "B.Fab")
		)
		(pad "1" smd circle
			(at 0.40005 0 90)
			(size 0 0)
			(layers "B.Cu" "B.Mask" "B.Paste")
			(net "PVNN_TERM_CPU0")
		)
		(pad "2" smd circle
			(at -0.40005 0 90)
			(size 0 0)
			(layers "B.Cu" "B.Mask" "B.Paste")
			(net "PU_CPU0_TXT_AGENT")
		)
	)
	(footprint ""
		(layer "B.Cu")
		(at 351.841308 -244.820186 -90)
		(property "Reference" "C397"
			(at 0 0 90)
			(layer "B.SilkS")
			(hide yes)
			(effects
				(font
					(size 1.27 1.27)
				)
				(justify mirror)
			)
		)
		(property "Value" ""
			(at 0 0 90)
			(layer "B.Fab")
			(effects
				(font
					(size 1.27 1.27)
				)
				(justify mirror)
			)
		)
		(duplicate_pad_numbers_are_jumpers no)
		(fp_line
			(start -1.524 0.762)
			(end 1.524 0.762)
			(stroke
				(width 0.1524)
				(type default)
			)
			(layer "B.SilkS")
		)
		(fp_line
			(start 1.524 0.762)
			(end 1.524 -0.762)
			(stroke
				(width 0.1524)
				(type default)
			)
			(layer "B.SilkS")
		)
		(fp_line
			(start -1.524 -0.762)
			(end -1.524 0.762)
			(stroke
				(width 0.1524)
				(type default)
			)
			(layer "B.SilkS")
		)
		(fp_line
			(start 1.524 -0.762)
			(end -1.524 -0.762)
			(stroke
				(width 0.1524)
				(type default)
			)
			(layer "B.SilkS")
		)
		(fp_line
			(start -1.1049 0.724916)
			(end -1.1049 -0.724916)
			(stroke
				(width 0.1)
				(type default)
			)
			(layer "B.Fab")
		)
		(fp_line
			(start 1.1049 0.724916)
			(end -1.1049 0.724916)
			(stroke
				(width 0.1)
				(type default)
			)
			(layer "B.Fab")
		)
		(fp_line
			(start -1.1049 -0.724916)
			(end 1.1049 -0.724916)
			(stroke
				(width 0.1)
				(type default)
			)
			(layer "B.Fab")
		)
		(fp_line
			(start 1.1049 -0.724916)
			(end 1.1049 0.724916)
			(stroke
				(width 0.1)
				(type default)
			)
			(layer "B.Fab")
		)
		(pad "1" smd rect
			(at 0.889 0 270)
			(size 1.016 1.27)
			(layers "B.Cu" "B.Mask" "B.Paste")
			(net "PVCCIN_CPU0")
		)
		(pad "2" smd rect
			(at -0.889 0 270)
			(size 1.016 1.27)
			(layers "B.Cu" "B.Mask" "B.Paste")
			(net "GND")
		)
	)
	(footprint ""
		(layer "B.Cu")
		(at 36.12896 -319.519808 180)
		(property "Reference" "R2495"
			(at 0 0 0)
			(layer "B.SilkS")
			(hide yes)
			(effects
				(font
					(size 1.27 1.27)
				)
				(justify mirror)
			)
		)
		(property "Value" ""
			(at 0 0 0)
			(layer "B.Fab")
			(effects
				(font
					(size 1.27 1.27)
				)
				(justify mirror)
			)
		)
		(duplicate_pad_numbers_are_jumpers no)
		(fp_line
			(start 0.7874 0.4064)
			(end 0.7874 -0.4064)
			(stroke
				(width 0.1524)
				(type default)
			)
			(layer "B.SilkS")
		)
		(fp_line
			(start 0.7874 -0.4064)
			(end -0.7874 -0.4064)
			(stroke
				(width 0.1524)
				(type default)
			)
			(layer "B.SilkS")
		)
		(fp_line
			(start -0.7874 0.4064)
			(end 0.7874 0.4064)
			(stroke
				(width 0.1524)
				(type default)
			)
			(layer "B.SilkS")
		)
		(fp_line
			(start -0.7874 -0.4064)
			(end -0.7874 0.4064)
			(stroke
				(width 0.1524)
				(type default)
			)
			(layer "B.SilkS")
		)
		(fp_line
			(start 0.67945 0.3048)
			(end 0.67945 -0.305054)
			(stroke
				(width 0.1)
				(type default)
			)
			(layer "B.Fab")
		)
		(fp_line
			(start 0.67945 -0.305054)
			(end 0.12065 -0.305054)
			(stroke
				(width 0.1)
				(type default)
			)
			(layer "B.Fab")
		)
		(fp_line
			(start 0.12065 0.3048)
			(end 0.67945 0.3048)
			(stroke
				(width 0.1)
				(type default)
			)
			(layer "B.Fab")
		)
		(fp_line
			(start 0.12065 0.2794)
			(end 0.12065 0.3048)
			(stroke
				(width 0.1)
				(type default)
			)
			(layer "B.Fab")
		)
		(fp_line
			(start 0.12065 -0.2794)
			(end -0.12065 -0.2794)
			(stroke
				(width 0.1)
				(type default)
			)
			(layer "B.Fab")
		)
		(fp_line
			(start 0.12065 -0.305054)
			(end 0.12065 -0.2794)
			(stroke
				(width 0.1)
				(type default)
			)
			(layer "B.Fab")
		)
		(fp_line
			(start -0.120396 0.3048)
			(end -0.120396 0.2794)
			(stroke
				(width 0.1)
				(type default)
			)
			(layer "B.Fab")
		)
		(fp_line
			(start -0.120396 0.2794)
			(end 0.12065 0.2794)
			(stroke
				(width 0.1)
				(type default)
			)
			(layer "B.Fab")
		)
		(fp_line
			(start -0.12065 -0.2794)
			(end -0.12065 -0.3048)
			(stroke
				(width 0.1)
				(type default)
			)
			(layer "B.Fab")
		)
		(fp_line
			(start -0.12065 -0.3048)
			(end -0.67945 -0.3048)
			(stroke
				(width 0.1)
				(type default)
			)
			(layer "B.Fab")
		)
		(fp_line
			(start -0.67945 0.3048)
			(end -0.120396 0.3048)
			(stroke
				(width 0.1)
				(type default)
			)
			(layer "B.Fab")
		)
		(fp_line
			(start -0.67945 -0.3048)
			(end -0.67945 0.3048)
			(stroke
				(width 0.1)
				(type default)
			)
			(layer "B.Fab")
		)
		(pad "1" smd circle
			(at 0.40005 0)
			(size 0 0)
			(layers "B.Cu" "B.Mask" "B.Paste")
			(net "PWRGD_FAIL_CPU1_CD")
		)
		(pad "2" smd circle
			(at -0.40005 0)
			(size 0 0)
			(layers "B.Cu" "B.Mask" "B.Paste")
			(net "PWRGD_FAIL_CPU1_CD_R1")
		)
	)
	(footprint ""
		(layer "B.Cu")
		(at 30.784546 -319.268856 180)
		(property "Reference" "C65"
			(at 0 0 0)
			(layer "B.SilkS")
			(hide yes)
			(effects
				(font
					(size 1.27 1.27)
				)
				(justify mirror)
			)
		)
		(property "Value" ""
			(at 0 0 0)
			(layer "B.Fab")
			(effects
				(font
					(size 1.27 1.27)
				)
				(justify mirror)
			)
		)
		(duplicate_pad_numbers_are_jumpers no)
		(fp_line
			(start 0.7874 0.4064)
			(end 0.7874 -0.4064)
			(stroke
				(width 0.1524)
				(type default)
			)
			(layer "B.SilkS")
		)
		(fp_line
			(start 0.7874 -0.4064)
			(end -0.7874 -0.4064)
			(stroke
				(width 0.1524)
				(type default)
			)
			(layer "B.SilkS")
		)
		(fp_line
			(start -0.7874 0.4064)
			(end 0.7874 0.4064)
			(stroke
				(width 0.1524)
				(type default)
			)
			(layer "B.SilkS")
		)
		(fp_line
			(start -0.7874 -0.4064)
			(end -0.7874 0.4064)
			(stroke
				(width 0.1524)
				(type default)
			)
			(layer "B.SilkS")
		)
		(fp_line
			(start 0.67945 0.3048)
			(end 0.67945 -0.305054)
			(stroke
				(width 0.1)
				(type default)
			)
			(layer "B.Fab")
		)
		(fp_line
			(start 0.67945 -0.305054)
			(end 0.12065 -0.305054)
			(stroke
				(width 0.1)
				(type default)
			)
			(layer "B.Fab")
		)
		(fp_line
			(start 0.12065 0.3048)
			(end 0.67945 0.3048)
			(stroke
				(width 0.1)
				(type default)
			)
			(layer "B.Fab")
		)
		(fp_line
			(start 0.12065 0.2794)
			(end 0.12065 0.3048)
			(stroke
				(width 0.1)
				(type default)
			)
			(layer "B.Fab")
		)
		(fp_line
			(start 0.12065 -0.2794)
			(end -0.12065 -0.2794)
			(stroke
				(width 0.1)
				(type default)
			)
			(layer "B.Fab")
		)
		(fp_line
			(start 0.12065 -0.305054)
			(end 0.12065 -0.2794)
			(stroke
				(width 0.1)
				(type default)
			)
			(layer "B.Fab")
		)
		(fp_line
			(start -0.120396 0.3048)
			(end -0.120396 0.2794)
			(stroke
				(width 0.1)
				(type default)
			)
			(layer "B.Fab")
		)
		(fp_line
			(start -0.120396 0.2794)
			(end 0.12065 0.2794)
			(stroke
				(width 0.1)
				(type default)
			)
			(layer "B.Fab")
		)
		(fp_line
			(start -0.12065 -0.2794)
			(end -0.12065 -0.3048)
			(stroke
				(width 0.1)
				(type default)
			)
			(layer "B.Fab")
		)
		(fp_line
			(start -0.12065 -0.3048)
			(end -0.67945 -0.3048)
			(stroke
				(width 0.1)
				(type default)
			)
			(layer "B.Fab")
		)
		(fp_line
			(start -0.67945 0.3048)
			(end -0.120396 0.3048)
			(stroke
				(width 0.1)
				(type default)
			)
			(layer "B.Fab")
		)
		(fp_line
			(start -0.67945 -0.3048)
			(end -0.67945 0.3048)
			(stroke
				(width 0.1)
				(type default)
			)
			(layer "B.Fab")
		)
		(pad "1" smd circle
			(at 0.40005 0)
			(size 0 0)
			(layers "B.Cu" "B.Mask" "B.Paste")
			(net "P3V3_AUX")
		)
		(pad "2" smd circle
			(at -0.40005 0)
			(size 0 0)
			(layers "B.Cu" "B.Mask" "B.Paste")
			(net "GND")
		)
	)
	(footprint ""
		(layer "B.Cu")
		(at 407.91257 -174.140368 180)
		(property "Reference" "PC202_P0_1"
			(at 0 0 0)
			(layer "B.SilkS")
			(hide yes)
			(effects
				(font
					(size 1.27 1.27)
				)
				(justify mirror)
			)
		)
		(property "Value" ""
			(at 0 0 0)
			(layer "B.Fab")
			(effects
				(font
					(size 1.27 1.27)
				)
				(justify mirror)
			)
		)
		(duplicate_pad_numbers_are_jumpers no)
		(fp_line
			(start 1.524 0.762)
			(end 1.524 -0.762)
			(stroke
				(width 0.1524)
				(type default)
			)
			(layer "B.SilkS")
		)
		(fp_line
			(start 1.524 -0.762)
			(end -1.524 -0.762)
			(stroke
				(width 0.1524)
				(type default)
			)
			(layer "B.SilkS")
		)
		(fp_line
			(start -1.524 0.762)
			(end 1.524 0.762)
			(stroke
				(width 0.1524)
				(type default)
			)
			(layer "B.SilkS")
		)
		(fp_line
			(start -1.524 -0.762)
			(end -1.524 0.762)
			(stroke
				(width 0.1524)
				(type default)
			)
			(layer "B.SilkS")
		)
		(fp_line
			(start 1.1049 0.724916)
			(end -1.1049 0.724916)
			(stroke
				(width 0.1)
				(type default)
			)
			(layer "B.Fab")
		)
		(fp_line
			(start 1.1049 -0.724916)
			(end 1.1049 0.724916)
			(stroke
				(width 0.1)
				(type default)
			)
			(layer "B.Fab")
		)
		(fp_line
			(start -1.1049 0.724916)
			(end -1.1049 -0.724916)
			(stroke
				(width 0.1)
				(type default)
			)
			(layer "B.Fab")
		)
		(fp_line
			(start -1.1049 -0.724916)
			(end 1.1049 -0.724916)
			(stroke
				(width 0.1)
				(type default)
			)
			(layer "B.Fab")
		)
		(pad "1" smd rect
			(at 0.889 0 180)
			(size 1.016 1.27)
			(layers "B.Cu" "B.Mask" "B.Paste")
			(net "PVCCINFAON_CPU0")
		)
		(pad "2" smd rect
			(at -0.889 0 180)
			(size 1.016 1.27)
			(layers "B.Cu" "B.Mask" "B.Paste")
			(net "GND")
		)
	)
	(footprint ""
		(layer "B.Cu")
		(at 324.35292 -333.566008 -90)
		(property "Reference" "PR527"
			(at 0 0 90)
			(layer "B.SilkS")
			(hide yes)
			(effects
				(font
					(size 1.27 1.27)
				)
				(justify mirror)
			)
		)
		(property "Value" ""
			(at 0 0 90)
			(layer "B.Fab")
			(effects
				(font
					(size 1.27 1.27)
				)
				(justify mirror)
			)
		)
		(duplicate_pad_numbers_are_jumpers no)
		(fp_line
			(start -0.7874 0.4064)
			(end 0.7874 0.4064)
			(stroke
				(width 0.1524)
				(type default)
			)
			(layer "B.SilkS")
		)
		(fp_line
			(start 0.7874 0.4064)
			(end 0.7874 -0.4064)
			(stroke
				(width 0.1524)
				(type default)
			)
			(layer "B.SilkS")
		)
		(fp_line
			(start -0.7874 -0.4064)
			(end -0.7874 0.4064)
			(stroke
				(width 0.1524)
				(type default)
			)
			(layer "B.SilkS")
		)
		(fp_line
			(start 0.7874 -0.4064)
			(end -0.7874 -0.4064)
			(stroke
				(width 0.1524)
				(type default)
			)
			(layer "B.SilkS")
		)
		(fp_line
			(start -0.67945 0.3048)
			(end -0.120396 0.3048)
			(stroke
				(width 0.1)
				(type default)
			)
			(layer "B.Fab")
		)
		(fp_line
			(start -0.120396 0.3048)
			(end -0.120396 0.2794)
			(stroke
				(width 0.1)
				(type default)
			)
			(layer "B.Fab")
		)
		(fp_line
			(start 0.12065 0.3048)
			(end 0.67945 0.3048)
			(stroke
				(width 0.1)
				(type default)
			)
			(layer "B.Fab")
		)
		(fp_line
			(start 0.67945 0.3048)
			(end 0.67945 -0.305054)
			(stroke
				(width 0.1)
				(type default)
			)
			(layer "B.Fab")
		)
		(fp_line
			(start -0.120396 0.2794)
			(end 0.12065 0.2794)
			(stroke
				(width 0.1)
				(type default)
			)
			(layer "B.Fab")
		)
		(fp_line
			(start 0.12065 0.2794)
			(end 0.12065 0.3048)
			(stroke
				(width 0.1)
				(type default)
			)
			(layer "B.Fab")
		)
		(fp_line
			(start -0.12065 -0.2794)
			(end -0.12065 -0.3048)
			(stroke
				(width 0.1)
				(type default)
			)
			(layer "B.Fab")
		)
		(fp_line
			(start 0.12065 -0.2794)
			(end -0.12065 -0.2794)
			(stroke
				(width 0.1)
				(type default)
			)
			(layer "B.Fab")
		)
		(fp_line
			(start -0.67945 -0.3048)
			(end -0.67945 0.3048)
			(stroke
				(width 0.1)
				(type default)
			)
			(layer "B.Fab")
		)
		(fp_line
			(start -0.12065 -0.3048)
			(end -0.67945 -0.3048)
			(stroke
				(width 0.1)
				(type default)
			)
			(layer "B.Fab")
		)
		(fp_line
			(start 0.12065 -0.305054)
			(end 0.12065 -0.2794)
			(stroke
				(width 0.1)
				(type default)
			)
			(layer "B.Fab")
		)
		(fp_line
			(start 0.67945 -0.305054)
			(end 0.12065 -0.305054)
			(stroke
				(width 0.1)
				(type default)
			)
			(layer "B.Fab")
		)
		(pad "1" smd circle
			(at 0.40005 0 90)
			(size 0 0)
			(layers "B.Cu" "B.Mask" "B.Paste")
			(net "VSENSE_PVCCIN_CPU0_DN")
		)
		(pad "2" smd circle
			(at -0.40005 0 90)
			(size 0 0)
			(layers "B.Cu" "B.Mask" "B.Paste")
			(net "GND")
		)
	)
	(footprint ""
		(layer "B.Cu")
		(at 351.841308 -255.853946 90)
		(property "Reference" "C492"
			(at 0 0 90)
			(layer "B.SilkS")
			(hide yes)
			(effects
				(font
					(size 1.27 1.27)
				)
				(justify mirror)
			)
		)
		(property "Value" ""
			(at 0 0 90)
			(layer "B.Fab")
			(effects
				(font
					(size 1.27 1.27)
				)
				(justify mirror)
			)
		)
		(duplicate_pad_numbers_are_jumpers no)
		(fp_line
			(start 1.524 -0.762)
			(end -1.524 -0.762)
			(stroke
				(width 0.1524)
				(type default)
			)
			(layer "B.SilkS")
		)
		(fp_line
			(start -1.524 -0.762)
			(end -1.524 0.762)
			(stroke
				(width 0.1524)
				(type default)
			)
			(layer "B.SilkS")
		)
		(fp_line
			(start 1.524 0.762)
			(end 1.524 -0.762)
			(stroke
				(width 0.1524)
				(type default)
			)
			(layer "B.SilkS")
		)
		(fp_line
			(start -1.524 0.762)
			(end 1.524 0.762)
			(stroke
				(width 0.1524)
				(type default)
			)
			(layer "B.SilkS")
		)
		(fp_line
			(start 1.1049 -0.724916)
			(end 1.1049 0.724916)
			(stroke
				(width 0.1)
				(type default)
			)
			(layer "B.Fab")
		)
		(fp_line
			(start -1.1049 -0.724916)
			(end 1.1049 -0.724916)
			(stroke
				(width 0.1)
				(type default)
			)
			(layer "B.Fab")
		)
		(fp_line
			(start 1.1049 0.724916)
			(end -1.1049 0.724916)
			(stroke
				(width 0.1)
				(type default)
			)
			(layer "B.Fab")
		)
		(fp_line
			(start -1.1049 0.724916)
			(end -1.1049 -0.724916)
			(stroke
				(width 0.1)
				(type default)
			)
			(layer "B.Fab")
		)
		(pad "1" smd rect
			(at 0.889 0 90)
			(size 1.016 1.27)
			(layers "B.Cu" "B.Mask" "B.Paste")
			(net "PVCCFA_EHV_CPU0")
		)
		(pad "2" smd rect
			(at -0.889 0 90)
			(size 1.016 1.27)
			(layers "B.Cu" "B.Mask" "B.Paste")
			(net "GND")
		)
	)
	(footprint ""
		(layer "B.Cu")
		(at 53.415946 -319.268856 180)
		(property "Reference" "C50"
			(at 0 0 0)
			(layer "B.SilkS")
			(hide yes)
			(effects
				(font
					(size 1.27 1.27)
				)
				(justify mirror)
			)
		)
		(property "Value" ""
			(at 0 0 0)
			(layer "B.Fab")
			(effects
				(font
					(size 1.27 1.27)
				)
				(justify mirror)
			)
		)
		(duplicate_pad_numbers_are_jumpers no)
		(fp_line
			(start 0.7874 0.4064)
			(end 0.7874 -0.4064)
			(stroke
				(width 0.1524)
				(type default)
			)
			(layer "B.SilkS")
		)
		(fp_line
			(start 0.7874 -0.4064)
			(end -0.7874 -0.4064)
			(stroke
				(width 0.1524)
				(type default)
			)
			(layer "B.SilkS")
		)
		(fp_line
			(start -0.7874 0.4064)
			(end 0.7874 0.4064)
			(stroke
				(width 0.1524)
				(type default)
			)
			(layer "B.SilkS")
		)
		(fp_line
			(start -0.7874 -0.4064)
			(end -0.7874 0.4064)
			(stroke
				(width 0.1524)
				(type default)
			)
			(layer "B.SilkS")
		)
		(fp_line
			(start 0.67945 0.3048)
			(end 0.67945 -0.305054)
			(stroke
				(width 0.1)
				(type default)
			)
			(layer "B.Fab")
		)
		(fp_line
			(start 0.67945 -0.305054)
			(end 0.12065 -0.305054)
			(stroke
				(width 0.1)
				(type default)
			)
			(layer "B.Fab")
		)
		(fp_line
			(start 0.12065 0.3048)
			(end 0.67945 0.3048)
			(stroke
				(width 0.1)
				(type default)
			)
			(layer "B.Fab")
		)
		(fp_line
			(start 0.12065 0.2794)
			(end 0.12065 0.3048)
			(stroke
				(width 0.1)
				(type default)
			)
			(layer "B.Fab")
		)
		(fp_line
			(start 0.12065 -0.2794)
			(end -0.12065 -0.2794)
			(stroke
				(width 0.1)
				(type default)
			)
			(layer "B.Fab")
		)
		(fp_line
			(start 0.12065 -0.305054)
			(end 0.12065 -0.2794)
			(stroke
				(width 0.1)
				(type default)
			)
			(layer "B.Fab")
		)
		(fp_line
			(start -0.120396 0.3048)
			(end -0.120396 0.2794)
			(stroke
				(width 0.1)
				(type default)
			)
			(layer "B.Fab")
		)
		(fp_line
			(start -0.120396 0.2794)
			(end 0.12065 0.2794)
			(stroke
				(width 0.1)
				(type default)
			)
			(layer "B.Fab")
		)
		(fp_line
			(start -0.12065 -0.2794)
			(end -0.12065 -0.3048)
			(stroke
				(width 0.1)
				(type default)
			)
			(layer "B.Fab")
		)
		(fp_line
			(start -0.12065 -0.3048)
			(end -0.67945 -0.3048)
			(stroke
				(width 0.1)
				(type default)
			)
			(layer "B.Fab")
		)
		(fp_line
			(start -0.67945 0.3048)
			(end -0.120396 0.3048)
			(stroke
				(width 0.1)
				(type default)
			)
			(layer "B.Fab")
		)
		(fp_line
			(start -0.67945 -0.3048)
			(end -0.67945 0.3048)
			(stroke
				(width 0.1)
				(type default)
			)
			(layer "B.Fab")
		)
		(pad "1" smd circle
			(at 0.40005 0)
			(size 0 0)
			(layers "B.Cu" "B.Mask" "B.Paste")
			(net "P3V3_AUX")
		)
		(pad "2" smd circle
			(at -0.40005 0)
			(size 0 0)
			(layers "B.Cu" "B.Mask" "B.Paste")
			(net "GND")
		)
	)
	(footprint ""
		(layer "B.Cu")
		(at 61.980572 -170.657774)
		(property "Reference" "PC437"
			(at 0 0 0)
			(layer "B.SilkS")
			(hide yes)
			(effects
				(font
					(size 1.27 1.27)
				)
				(justify mirror)
			)
		)
		(property "Value" ""
			(at 0 0 0)
			(layer "B.Fab")
			(effects
				(font
					(size 1.27 1.27)
				)
				(justify mirror)
			)
		)
		(duplicate_pad_numbers_are_jumpers no)
		(fp_line
			(start -1.524 -0.762)
			(end -1.524 0.762)
			(stroke
				(width 0.1524)
				(type default)
			)
			(layer "B.SilkS")
		)
		(fp_line
			(start -1.524 0.762)
			(end 1.524 0.762)
			(stroke
				(width 0.1524)
				(type default)
			)
			(layer "B.SilkS")
		)
		(fp_line
			(start 1.524 -0.762)
			(end -1.524 -0.762)
			(stroke
				(width 0.1524)
				(type default)
			)
			(layer "B.SilkS")
		)
		(fp_line
			(start 1.524 0.762)
			(end 1.524 -0.762)
			(stroke
				(width 0.1524)
				(type default)
			)
			(layer "B.SilkS")
		)
		(fp_line
			(start -1.1049 -0.724916)
			(end 1.1049 -0.724916)
			(stroke
				(width 0.1)
				(type default)
			)
			(layer "B.Fab")
		)
		(fp_line
			(start -1.1049 0.724916)
			(end -1.1049 -0.724916)
			(stroke
				(width 0.1)
				(type default)
			)
			(layer "B.Fab")
		)
		(fp_line
			(start 1.1049 -0.724916)
			(end 1.1049 0.724916)
			(stroke
				(width 0.1)
				(type default)
			)
			(layer "B.Fab")
		)
		(fp_line
			(start 1.1049 0.724916)
			(end -1.1049 0.724916)
			(stroke
				(width 0.1)
				(type default)
			)
			(layer "B.Fab")
		)
		(pad "1" smd rect
			(at 0.889 0)
			(size 1.016 1.27)
			(layers "B.Cu" "B.Mask" "B.Paste")
			(net "PVCCFA_EHV_CPU1")
		)
		(pad "2" smd rect
			(at -0.889 0)
			(size 1.016 1.27)
			(layers "B.Cu" "B.Mask" "B.Paste")
			(net "GND")
		)
	)
	(footprint ""
		(layer "B.Cu")
		(at 274.83562 -318.986408 90)
		(property "Reference" "R2729"
			(at 0 0 90)
			(layer "B.SilkS")
			(hide yes)
			(effects
				(font
					(size 1.27 1.27)
				)
				(justify mirror)
			)
		)
		(property "Value" ""
			(at 0 0 90)
			(layer "B.Fab")
			(effects
				(font
					(size 1.27 1.27)
				)
				(justify mirror)
			)
		)
		(duplicate_pad_numbers_are_jumpers no)
		(fp_line
			(start 0.7874 -0.4064)
			(end -0.7874 -0.4064)
			(stroke
				(width 0.1524)
				(type default)
			)
			(layer "B.SilkS")
		)
		(fp_line
			(start -0.7874 -0.4064)
			(end -0.7874 0.4064)
			(stroke
				(width 0.1524)
				(type default)
			)
			(layer "B.SilkS")
		)
		(fp_line
			(start 0.7874 0.4064)
			(end 0.7874 -0.4064)
			(stroke
				(width 0.1524)
				(type default)
			)
			(layer "B.SilkS")
		)
		(fp_line
			(start -0.7874 0.4064)
			(end 0.7874 0.4064)
			(stroke
				(width 0.1524)
				(type default)
			)
			(layer "B.SilkS")
		)
		(fp_line
			(start 0.67945 -0.305054)
			(end 0.12065 -0.305054)
			(stroke
				(width 0.1)
				(type default)
			)
			(layer "B.Fab")
		)
		(fp_line
			(start 0.12065 -0.305054)
			(end 0.12065 -0.2794)
			(stroke
				(width 0.1)
				(type default)
			)
			(layer "B.Fab")
		)
		(fp_line
			(start -0.12065 -0.3048)
			(end -0.67945 -0.3048)
			(stroke
				(width 0.1)
				(type default)
			)
			(layer "B.Fab")
		)
		(fp_line
			(start -0.67945 -0.3048)
			(end -0.67945 0.3048)
			(stroke
				(width 0.1)
				(type default)
			)
			(layer "B.Fab")
		)
		(fp_line
			(start 0.12065 -0.2794)
			(end -0.12065 -0.2794)
			(stroke
				(width 0.1)
				(type default)
			)
			(layer "B.Fab")
		)
		(fp_line
			(start -0.12065 -0.2794)
			(end -0.12065 -0.3048)
			(stroke
				(width 0.1)
				(type default)
			)
			(layer "B.Fab")
		)
		(fp_line
			(start 0.12065 0.2794)
			(end 0.12065 0.3048)
			(stroke
				(width 0.1)
				(type default)
			)
			(layer "B.Fab")
		)
		(fp_line
			(start -0.120396 0.2794)
			(end 0.12065 0.2794)
			(stroke
				(width 0.1)
				(type default)
			)
			(layer "B.Fab")
		)
		(fp_line
			(start 0.67945 0.3048)
			(end 0.67945 -0.305054)
			(stroke
				(width 0.1)
				(type default)
			)
			(layer "B.Fab")
		)
		(fp_line
			(start 0.12065 0.3048)
			(end 0.67945 0.3048)
			(stroke
				(width 0.1)
				(type default)
			)
			(layer "B.Fab")
		)
		(fp_line
			(start -0.120396 0.3048)
			(end -0.120396 0.2794)
			(stroke
				(width 0.1)
				(type default)
			)
			(layer "B.Fab")
		)
		(fp_line
			(start -0.67945 0.3048)
			(end -0.120396 0.3048)
			(stroke
				(width 0.1)
				(type default)
			)
			(layer "B.Fab")
		)
		(pad "1" smd circle
			(at 0.40005 0 270)
			(size 0 0)
			(layers "B.Cu" "B.Mask" "B.Paste")
			(net "PWRGD_CHC_CPU0_DIMM1")
		)
		(pad "2" smd circle
			(at -0.40005 0 270)
			(size 0 0)
			(layers "B.Cu" "B.Mask" "B.Paste")
			(net "PWRGD_FAIL_CPU0_CD")
		)
	)
	(footprint ""
		(layer "B.Cu")
		(at 260.121146 -76.558902 -90)
		(property "Reference" "PC2286"
			(at 0 0 90)
			(layer "B.SilkS")
			(hide yes)
			(effects
				(font
					(size 1.27 1.27)
				)
				(justify mirror)
			)
		)
		(property "Value" ""
			(at 0 0 90)
			(layer "B.Fab")
			(effects
				(font
					(size 1.27 1.27)
				)
				(justify mirror)
			)
		)
		(duplicate_pad_numbers_are_jumpers no)
		(fp_line
			(start -0.7874 0.4064)
			(end 0.7874 0.4064)
			(stroke
				(width 0.1524)
				(type default)
			)
			(layer "B.SilkS")
		)
		(fp_line
			(start 0.7874 0.4064)
			(end 0.7874 -0.4064)
			(stroke
				(width 0.1524)
				(type default)
			)
			(layer "B.SilkS")
		)
		(fp_line
			(start -0.7874 -0.4064)
			(end -0.7874 0.4064)
			(stroke
				(width 0.1524)
				(type default)
			)
			(layer "B.SilkS")
		)
		(fp_line
			(start 0.7874 -0.4064)
			(end -0.7874 -0.4064)
			(stroke
				(width 0.1524)
				(type default)
			)
			(layer "B.SilkS")
		)
		(fp_line
			(start -0.67945 0.3048)
			(end -0.120396 0.3048)
			(stroke
				(width 0.1)
				(type default)
			)
			(layer "B.Fab")
		)
		(fp_line
			(start -0.120396 0.3048)
			(end -0.120396 0.2794)
			(stroke
				(width 0.1)
				(type default)
			)
			(layer "B.Fab")
		)
		(fp_line
			(start 0.12065 0.3048)
			(end 0.67945 0.3048)
			(stroke
				(width 0.1)
				(type default)
			)
			(layer "B.Fab")
		)
		(fp_line
			(start 0.67945 0.3048)
			(end 0.67945 -0.305054)
			(stroke
				(width 0.1)
				(type default)
			)
			(layer "B.Fab")
		)
		(fp_line
			(start -0.120396 0.2794)
			(end 0.12065 0.2794)
			(stroke
				(width 0.1)
				(type default)
			)
			(layer "B.Fab")
		)
		(fp_line
			(start 0.12065 0.2794)
			(end 0.12065 0.3048)
			(stroke
				(width 0.1)
				(type default)
			)
			(layer "B.Fab")
		)
		(fp_line
			(start -0.12065 -0.2794)
			(end -0.12065 -0.3048)
			(stroke
				(width 0.1)
				(type default)
			)
			(layer "B.Fab")
		)
		(fp_line
			(start 0.12065 -0.2794)
			(end -0.12065 -0.2794)
			(stroke
				(width 0.1)
				(type default)
			)
			(layer "B.Fab")
		)
		(fp_line
			(start -0.67945 -0.3048)
			(end -0.67945 0.3048)
			(stroke
				(width 0.1)
				(type default)
			)
			(layer "B.Fab")
		)
		(fp_line
			(start -0.12065 -0.3048)
			(end -0.67945 -0.3048)
			(stroke
				(width 0.1)
				(type default)
			)
			(layer "B.Fab")
		)
		(fp_line
			(start 0.12065 -0.305054)
			(end 0.12065 -0.2794)
			(stroke
				(width 0.1)
				(type default)
			)
			(layer "B.Fab")
		)
		(fp_line
			(start 0.67945 -0.305054)
			(end 0.12065 -0.305054)
			(stroke
				(width 0.1)
				(type default)
			)
			(layer "B.Fab")
		)
		(pad "1" smd circle
			(at 0.40005 0 90)
			(size 0 0)
			(layers "B.Cu" "B.Mask" "B.Paste")
			(net "FM_P1V05_PCH_AUX_R_EN")
		)
		(pad "2" smd circle
			(at -0.40005 0 90)
			(size 0 0)
			(layers "B.Cu" "B.Mask" "B.Paste")
			(net "GND")
		)
	)
	(footprint ""
		(layer "B.Cu")
		(at 26.359866 -193.152776 -90)
		(property "Reference" "R817"
			(at 0 0 90)
			(layer "B.SilkS")
			(hide yes)
			(effects
				(font
					(size 1.27 1.27)
				)
				(justify mirror)
			)
		)
		(property "Value" ""
			(at 0 0 90)
			(layer "B.Fab")
			(effects
				(font
					(size 1.27 1.27)
				)
				(justify mirror)
			)
		)
		(duplicate_pad_numbers_are_jumpers no)
		(fp_line
			(start -0.7874 0.4064)
			(end 0.7874 0.4064)
			(stroke
				(width 0.1524)
				(type default)
			)
			(layer "B.SilkS")
		)
		(fp_line
			(start 0.7874 0.4064)
			(end 0.7874 -0.4064)
			(stroke
				(width 0.1524)
				(type default)
			)
			(layer "B.SilkS")
		)
		(fp_line
			(start -0.7874 -0.4064)
			(end -0.7874 0.4064)
			(stroke
				(width 0.1524)
				(type default)
			)
			(layer "B.SilkS")
		)
		(fp_line
			(start 0.7874 -0.4064)
			(end -0.7874 -0.4064)
			(stroke
				(width 0.1524)
				(type default)
			)
			(layer "B.SilkS")
		)
		(fp_line
			(start -0.67945 0.3048)
			(end -0.120396 0.3048)
			(stroke
				(width 0.1)
				(type default)
			)
			(layer "B.Fab")
		)
		(fp_line
			(start -0.120396 0.3048)
			(end -0.120396 0.2794)
			(stroke
				(width 0.1)
				(type default)
			)
			(layer "B.Fab")
		)
		(fp_line
			(start 0.12065 0.3048)
			(end 0.67945 0.3048)
			(stroke
				(width 0.1)
				(type default)
			)
			(layer "B.Fab")
		)
		(fp_line
			(start 0.67945 0.3048)
			(end 0.67945 -0.305054)
			(stroke
				(width 0.1)
				(type default)
			)
			(layer "B.Fab")
		)
		(fp_line
			(start -0.120396 0.2794)
			(end 0.12065 0.2794)
			(stroke
				(width 0.1)
				(type default)
			)
			(layer "B.Fab")
		)
		(fp_line
			(start 0.12065 0.2794)
			(end 0.12065 0.3048)
			(stroke
				(width 0.1)
				(type default)
			)
			(layer "B.Fab")
		)
		(fp_line
			(start -0.12065 -0.2794)
			(end -0.12065 -0.3048)
			(stroke
				(width 0.1)
				(type default)
			)
			(layer "B.Fab")
		)
		(fp_line
			(start 0.12065 -0.2794)
			(end -0.12065 -0.2794)
			(stroke
				(width 0.1)
				(type default)
			)
			(layer "B.Fab")
		)
		(fp_line
			(start -0.67945 -0.3048)
			(end -0.67945 0.3048)
			(stroke
				(width 0.1)
				(type default)
			)
			(layer "B.Fab")
		)
		(fp_line
			(start -0.12065 -0.3048)
			(end -0.67945 -0.3048)
			(stroke
				(width 0.1)
				(type default)
			)
			(layer "B.Fab")
		)
		(fp_line
			(start 0.12065 -0.305054)
			(end 0.12065 -0.2794)
			(stroke
				(width 0.1)
				(type default)
			)
			(layer "B.Fab")
		)
		(fp_line
			(start 0.67945 -0.305054)
			(end 0.12065 -0.305054)
			(stroke
				(width 0.1)
				(type default)
			)
			(layer "B.Fab")
		)
		(pad "1" smd circle
			(at 0.40005 0 90)
			(size 0 0)
			(layers "B.Cu" "B.Mask" "B.Paste")
			(net "RST_PLD_CPU1_DRAM_CD_N")
		)
		(pad "2" smd circle
			(at -0.40005 0 90)
			(size 0 0)
			(layers "B.Cu" "B.Mask" "B.Paste")
			(net "RST_M_CD_CPU1_FPGA_N")
		)
	)
	(footprint ""
		(layer "B.Cu")
		(at 355.397308 -248.498106 -90)
		(property "Reference" "C389"
			(at 0 0 90)
			(layer "B.SilkS")
			(hide yes)
			(effects
				(font
					(size 1.27 1.27)
				)
				(justify mirror)
			)
		)
		(property "Value" ""
			(at 0 0 90)
			(layer "B.Fab")
			(effects
				(font
					(size 1.27 1.27)
				)
				(justify mirror)
			)
		)
		(duplicate_pad_numbers_are_jumpers no)
		(fp_line
			(start -1.524 0.762)
			(end 1.524 0.762)
			(stroke
				(width 0.1524)
				(type default)
			)
			(layer "B.SilkS")
		)
		(fp_line
			(start 1.524 0.762)
			(end 1.524 -0.762)
			(stroke
				(width 0.1524)
				(type default)
			)
			(layer "B.SilkS")
		)
		(fp_line
			(start -1.524 -0.762)
			(end -1.524 0.762)
			(stroke
				(width 0.1524)
				(type default)
			)
			(layer "B.SilkS")
		)
		(fp_line
			(start 1.524 -0.762)
			(end -1.524 -0.762)
			(stroke
				(width 0.1524)
				(type default)
			)
			(layer "B.SilkS")
		)
		(fp_line
			(start -1.1049 0.724916)
			(end -1.1049 -0.724916)
			(stroke
				(width 0.1)
				(type default)
			)
			(layer "B.Fab")
		)
		(fp_line
			(start 1.1049 0.724916)
			(end -1.1049 0.724916)
			(stroke
				(width 0.1)
				(type default)
			)
			(layer "B.Fab")
		)
		(fp_line
			(start -1.1049 -0.724916)
			(end 1.1049 -0.724916)
			(stroke
				(width 0.1)
				(type default)
			)
			(layer "B.Fab")
		)
		(fp_line
			(start 1.1049 -0.724916)
			(end 1.1049 0.724916)
			(stroke
				(width 0.1)
				(type default)
			)
			(layer "B.Fab")
		)
		(pad "1" smd rect
			(at 0.889 0 270)
			(size 1.016 1.27)
			(layers "B.Cu" "B.Mask" "B.Paste")
			(net "PVCCIN_CPU0")
		)
		(pad "2" smd rect
			(at -0.889 0 270)
			(size 1.016 1.27)
			(layers "B.Cu" "B.Mask" "B.Paste")
			(net "GND")
		)
	)
	(footprint ""
		(layer "B.Cu")
		(at 433.297584 -179.818538 90)
		(property "Reference" "C1296"
			(at 0 0 90)
			(layer "B.SilkS")
			(hide yes)
			(effects
				(font
					(size 1.27 1.27)
				)
				(justify mirror)
			)
		)
		(property "Value" ""
			(at 0 0 90)
			(layer "B.Fab")
			(effects
				(font
					(size 1.27 1.27)
				)
				(justify mirror)
			)
		)
		(duplicate_pad_numbers_are_jumpers no)
		(fp_line
			(start 0.7874 -0.4064)
			(end -0.7874 -0.4064)
			(stroke
				(width 0.1524)
				(type default)
			)
			(layer "B.SilkS")
		)
		(fp_line
			(start -0.7874 -0.4064)
			(end -0.7874 0.4064)
			(stroke
				(width 0.1524)
				(type default)
			)
			(layer "B.SilkS")
		)
		(fp_line
			(start 0.7874 0.4064)
			(end 0.7874 -0.4064)
			(stroke
				(width 0.1524)
				(type default)
			)
			(layer "B.SilkS")
		)
		(fp_line
			(start -0.7874 0.4064)
			(end 0.7874 0.4064)
			(stroke
				(width 0.1524)
				(type default)
			)
			(layer "B.SilkS")
		)
		(fp_line
			(start 0.67945 -0.305054)
			(end 0.12065 -0.305054)
			(stroke
				(width 0.1)
				(type default)
			)
			(layer "B.Fab")
		)
		(fp_line
			(start 0.12065 -0.305054)
			(end 0.12065 -0.2794)
			(stroke
				(width 0.1)
				(type default)
			)
			(layer "B.Fab")
		)
		(fp_line
			(start -0.12065 -0.3048)
			(end -0.67945 -0.3048)
			(stroke
				(width 0.1)
				(type default)
			)
			(layer "B.Fab")
		)
		(fp_line
			(start -0.67945 -0.3048)
			(end -0.67945 0.3048)
			(stroke
				(width 0.1)
				(type default)
			)
			(layer "B.Fab")
		)
		(fp_line
			(start 0.12065 -0.2794)
			(end -0.12065 -0.2794)
			(stroke
				(width 0.1)
				(type default)
			)
			(layer "B.Fab")
		)
		(fp_line
			(start -0.12065 -0.2794)
			(end -0.12065 -0.3048)
			(stroke
				(width 0.1)
				(type default)
			)
			(layer "B.Fab")
		)
		(fp_line
			(start 0.12065 0.2794)
			(end 0.12065 0.3048)
			(stroke
				(width 0.1)
				(type default)
			)
			(layer "B.Fab")
		)
		(fp_line
			(start -0.120396 0.2794)
			(end 0.12065 0.2794)
			(stroke
				(width 0.1)
				(type default)
			)
			(layer "B.Fab")
		)
		(fp_line
			(start 0.67945 0.3048)
			(end 0.67945 -0.305054)
			(stroke
				(width 0.1)
				(type default)
			)
			(layer "B.Fab")
		)
		(fp_line
			(start 0.12065 0.3048)
			(end 0.67945 0.3048)
			(stroke
				(width 0.1)
				(type default)
			)
			(layer "B.Fab")
		)
		(fp_line
			(start -0.120396 0.3048)
			(end -0.120396 0.2794)
			(stroke
				(width 0.1)
				(type default)
			)
			(layer "B.Fab")
		)
		(fp_line
			(start -0.67945 0.3048)
			(end -0.120396 0.3048)
			(stroke
				(width 0.1)
				(type default)
			)
			(layer "B.Fab")
		)
		(pad "1" smd circle
			(at 0.40005 0 270)
			(size 0 0)
			(layers "B.Cu" "B.Mask" "B.Paste")
			(net "PWRGD_PVNN_MAIN_CPU0")
		)
		(pad "2" smd circle
			(at -0.40005 0 270)
			(size 0 0)
			(layers "B.Cu" "B.Mask" "B.Paste")
			(net "GND")
		)
	)
	(footprint ""
		(layer "B.Cu")
		(at 477.95688 -251.022866)
		(property "Reference" "DB12"
			(at 2.467356 -5.911342 270)
			(unlocked yes)
			(layer "B.SilkS")
			(effects
				(font
					(size 0.7874 0.5842)
					(thickness 0.1524)
				)
				(justify left mirror)
			)
		)
		(property "Value" ""
			(at 0 0 0)
			(layer "B.Fab")
			(effects
				(font
					(size 1.27 1.27)
				)
				(justify mirror)
			)
		)
		(duplicate_pad_numbers_are_jumpers no)
		(fp_line
			(start -3.330702 -4.771136)
			(end 0 4.011168)
			(stroke
				(width 0.1524)
				(type default)
			)
			(layer "B.SilkS")
		)
		(fp_line
			(start 0 4.011168)
			(end 3.330702 -4.771136)
			(stroke
				(width 0.1524)
				(type default)
			)
			(layer "B.SilkS")
		)
		(fp_line
			(start 3.330702 -4.771136)
			(end -3.330702 -4.771136)
			(stroke
				(width 0.1524)
				(type default)
			)
			(layer "B.SilkS")
		)
		(fp_line
			(start -3.330702 -4.771136)
			(end 0 4.011168)
			(stroke
				(width 0.1)
				(type default)
			)
			(layer "B.Fab")
		)
		(fp_line
			(start 0 4.011168)
			(end 3.330702 -4.771136)
			(stroke
				(width 0.1)
				(type default)
			)
			(layer "B.Fab")
		)
		(fp_line
			(start 3.330702 -4.771136)
			(end -3.330702 -4.771136)
			(stroke
				(width 0.1)
				(type default)
			)
			(layer "B.Fab")
		)
		(pad "1" thru_hole circle
			(at 0 0 180)
			(size 2.159 2.159)
			(drill 1.7018)
			(layers "*.Cu" "*.Mask")
			(remove_unused_layers no)
			(net "T1_GND")
			(clearance 0.0254)
			(thermal_gap 0.0254)
		)
		(pad "2" thru_hole circle
			(at 1.27 -3.348736 180)
			(size 2.159 2.159)
			(drill 1.7018)
			(layers "*.Cu" "*.Mask")
			(remove_unused_layers no)
			(net "TDR_SE_50_OHM_BOT")
			(clearance 0.0254)
			(thermal_gap 0.0254)
		)
		(pad "3" thru_hole circle
			(at -1.27 -3.348736 180)
			(size 2.159 2.159)
			(drill 1.7018)
			(layers "*.Cu" "*.Mask")
			(remove_unused_layers no)
			(net "TDR_SE_50_OHM_BOT")
			(clearance 0.0254)
			(thermal_gap 0.0254)
		)
	)
	(footprint ""
		(layer "B.Cu")
		(at 260.731508 -2.156206 180)
		(property "Reference" "J76"
			(at 4.218178 -1.140206 270)
			(unlocked yes)
			(layer "B.SilkS")
			(effects
				(font
					(size 0.7874 0.5842)
					(thickness 0.1524)
				)
				(justify left mirror)
			)
		)
		(property "Value" ""
			(at 0 0 0)
			(layer "B.Fab")
			(effects
				(font
					(size 1.27 1.27)
				)
				(justify mirror)
			)
		)
		(duplicate_pad_numbers_are_jumpers no)
		(fp_line
			(start 1.2192 2.1082)
			(end 1.2192 -2.1082)
			(stroke
				(width 0.1524)
				(type default)
			)
			(layer "B.SilkS")
		)
		(fp_line
			(start 1.2192 -2.1082)
			(end -1.2192 -2.1082)
			(stroke
				(width 0.1524)
				(type default)
			)
			(layer "B.SilkS")
		)
		(fp_line
			(start -1.2192 2.1082)
			(end 1.2192 2.1082)
			(stroke
				(width 0.1524)
				(type default)
			)
			(layer "B.SilkS")
		)
		(fp_line
			(start -1.2192 -2.1082)
			(end -1.2192 2.1082)
			(stroke
				(width 0.1524)
				(type default)
			)
			(layer "B.SilkS")
		)
		(pad "" np_thru_hole circle
			(at -3.4671 -1.27 90)
			(size 1.0414 1.0414)
			(drill 1.0414)
			(layers "*.Cu" "*.Mask")
			(clearance 0.381)
			(thermal_gap 0.381)
		)
		(pad "" np_thru_hole circle
			(at -3.4671 1.27 90)
			(size 1.0414 1.0414)
			(drill 1.0414)
			(layers "*.Cu" "*.Mask")
			(clearance 0.381)
			(thermal_gap 0.381)
		)
		(pad "" np_thru_hole circle
			(at 2.8829 -1.27 90)
			(size 1.0414 1.0414)
			(drill 1.0414)
			(layers "*.Cu" "*.Mask")
			(clearance 0.381)
			(thermal_gap 0.381)
		)
		(pad "" np_thru_hole circle
			(at 2.8829 1.27 90)
			(size 1.0414 1.0414)
			(drill 1.0414)
			(layers "*.Cu" "*.Mask")
			(clearance 0.381)
			(thermal_gap 0.381)
		)
		(pad "1" smd rect
			(at -0.8255 -0.249936 90)
			(size 0.3048 0.508)
			(layers "B.Cu" "B.Mask" "B.Paste")
			(net "DELTA_L_85_10INCH_BOT_DP")
		)
		(pad "2" smd rect
			(at -0.8255 0.249936 90)
			(size 0.3048 0.508)
			(layers "B.Cu" "B.Mask" "B.Paste")
			(net "DELTA_L_85_10INCH_BOT_DN")
		)
		(pad "3" smd circle
			(at 0 0)
			(size 0 0)
			(layers "B.Cu" "B.Mask" "B.Paste")
			(net "DELTA_L_GND_1")
		)
		(zone
			(layers "F.Cu" "B.Cu" "In1.Cu" "In2.Cu" "In3.Cu" "In4.Cu" "In5.Cu" "In6.Cu"
				"In7.Cu" "In8.Cu" "In9.Cu" "In10.Cu" "In11.Cu" "In12.Cu" "In13.Cu" "In14.Cu"
				"In15.Cu" "In16.Cu"
			)
			(hatch none 0.5)
			(connect_pads
				(clearance 0)
			)
			(min_thickness 0.25)
			(keepout
				(tracks not_allowed)
				(vias allowed)
				(pads allowed)
				(copperpour not_allowed)
				(footprints allowed)
			)
			(placement
				(enabled no)
				(sheetname "")
			)
			(fill
				(thermal_gap 0.5)
				(thermal_bridge_width 0.5)
				(island_removal_mode 0)
			)
			(polygon
				(pts
					(arc
						(start 258.775708 -3.426206)
						(mid 256.921508 -3.426206)
						(end 258.775708 -3.426206)
					)
				)
			)
		)
		(zone
			(layers "F.Cu" "B.Cu" "In1.Cu" "In2.Cu" "In3.Cu" "In4.Cu" "In5.Cu" "In6.Cu"
				"In7.Cu" "In8.Cu" "In9.Cu" "In10.Cu" "In11.Cu" "In12.Cu" "In13.Cu" "In14.Cu"
				"In15.Cu" "In16.Cu"
			)
			(hatch none 0.5)
			(connect_pads
				(clearance 0)
			)
			(min_thickness 0.25)
			(keepout
				(tracks not_allowed)
				(vias allowed)
				(pads allowed)
				(copperpour not_allowed)
				(footprints allowed)
			)
			(placement
				(enabled no)
				(sheetname "")
			)
			(fill
				(thermal_gap 0.5)
				(thermal_bridge_width 0.5)
				(island_removal_mode 0)
			)
			(polygon
				(pts
					(arc
						(start 258.775708 -0.886206)
						(mid 256.921508 -0.886206)
						(end 258.775708 -0.886206)
					)
				)
			)
		)
		(zone
			(layers "F.Cu" "B.Cu" "In1.Cu" "In2.Cu" "In3.Cu" "In4.Cu" "In5.Cu" "In6.Cu"
				"In7.Cu" "In8.Cu" "In9.Cu" "In10.Cu" "In11.Cu" "In12.Cu" "In13.Cu" "In14.Cu"
				"In15.Cu" "In16.Cu"
			)
			(hatch none 0.5)
			(connect_pads
				(clearance 0)
			)
			(min_thickness 0.25)
			(keepout
				(tracks not_allowed)
				(vias allowed)
				(pads allowed)
				(copperpour not_allowed)
				(footprints allowed)
			)
			(placement
				(enabled no)
				(sheetname "")
			)
			(fill
				(thermal_gap 0.5)
				(thermal_bridge_width 0.5)
				(island_removal_mode 0)
			)
			(polygon
				(pts
					(arc
						(start 265.125708 -3.426206)
						(mid 263.271508 -3.426206)
						(end 265.125708 -3.426206)
					)
				)
			)
		)
		(zone
			(layers "F.Cu" "B.Cu" "In1.Cu" "In2.Cu" "In3.Cu" "In4.Cu" "In5.Cu" "In6.Cu"
				"In7.Cu" "In8.Cu" "In9.Cu" "In10.Cu" "In11.Cu" "In12.Cu" "In13.Cu" "In14.Cu"
				"In15.Cu" "In16.Cu"
			)
			(hatch none 0.5)
			(connect_pads
				(clearance 0)
			)
			(min_thickness 0.25)
			(keepout
				(tracks not_allowed)
				(vias allowed)
				(pads allowed)
				(copperpour not_allowed)
				(footprints allowed)
			)
			(placement
				(enabled no)
				(sheetname "")
			)
			(fill
				(thermal_gap 0.5)
				(thermal_bridge_width 0.5)
				(island_removal_mode 0)
			)
			(polygon
				(pts
					(arc
						(start 265.125708 -0.886206)
						(mid 263.271508 -0.886206)
						(end 265.125708 -0.886206)
					)
				)
			)
		)
		(zone
			(layer "B.Cu")
			(hatch none 0.5)
			(connect_pads
				(clearance 0)
			)
			(min_thickness 0.25)
			(keepout
				(tracks not_allowed)
				(vias allowed)
				(pads allowed)
				(copperpour not_allowed)
				(footprints allowed)
			)
			(placement
				(enabled no)
				(sheetname "")
			)
			(fill
				(thermal_gap 0.5)
				(thermal_bridge_width 0.5)
				(island_removal_mode 0)
			)
			(polygon
				(pts
					(xy 261.849108 -1.607566) (xy 261.849108 -1.70307) (xy 261.252208 -1.70307) (xy 261.252208 -2.10947)
					(xy 261.849108 -2.10947) (xy 261.849108 -2.202942) (xy 261.252208 -2.202942) (xy 261.252208 -2.609342)
					(xy 261.849108 -2.609342) (xy 261.849108 -2.704846) (xy 261.150608 -2.704846) (xy 261.150608 -1.607566)
				)
			)
		)
	)
	(footprint ""
		(layer "B.Cu")
		(at 194.357752 -403.022054 -90)
		(property "Reference" "PR3910"
			(at 0 0 90)
			(layer "B.SilkS")
			(hide yes)
			(effects
				(font
					(size 1.27 1.27)
				)
				(justify mirror)
			)
		)
		(property "Value" ""
			(at 0 0 90)
			(layer "B.Fab")
			(effects
				(font
					(size 1.27 1.27)
				)
				(justify mirror)
			)
		)
		(duplicate_pad_numbers_are_jumpers no)
		(fp_line
			(start -0.7874 0.4064)
			(end 0.7874 0.4064)
			(stroke
				(width 0.1524)
				(type default)
			)
			(layer "B.SilkS")
		)
		(fp_line
			(start 0.7874 0.4064)
			(end 0.7874 -0.4064)
			(stroke
				(width 0.1524)
				(type default)
			)
			(layer "B.SilkS")
		)
		(fp_line
			(start -0.7874 -0.4064)
			(end -0.7874 0.4064)
			(stroke
				(width 0.1524)
				(type default)
			)
			(layer "B.SilkS")
		)
		(fp_line
			(start 0.7874 -0.4064)
			(end -0.7874 -0.4064)
			(stroke
				(width 0.1524)
				(type default)
			)
			(layer "B.SilkS")
		)
		(fp_line
			(start -0.67945 0.3048)
			(end -0.120396 0.3048)
			(stroke
				(width 0.1)
				(type default)
			)
			(layer "B.Fab")
		)
		(fp_line
			(start -0.120396 0.3048)
			(end -0.120396 0.2794)
			(stroke
				(width 0.1)
				(type default)
			)
			(layer "B.Fab")
		)
		(fp_line
			(start 0.12065 0.3048)
			(end 0.67945 0.3048)
			(stroke
				(width 0.1)
				(type default)
			)
			(layer "B.Fab")
		)
		(fp_line
			(start 0.67945 0.3048)
			(end 0.67945 -0.305054)
			(stroke
				(width 0.1)
				(type default)
			)
			(layer "B.Fab")
		)
		(fp_line
			(start -0.120396 0.2794)
			(end 0.12065 0.2794)
			(stroke
				(width 0.1)
				(type default)
			)
			(layer "B.Fab")
		)
		(fp_line
			(start 0.12065 0.2794)
			(end 0.12065 0.3048)
			(stroke
				(width 0.1)
				(type default)
			)
			(layer "B.Fab")
		)
		(fp_line
			(start -0.12065 -0.2794)
			(end -0.12065 -0.3048)
			(stroke
				(width 0.1)
				(type default)
			)
			(layer "B.Fab")
		)
		(fp_line
			(start 0.12065 -0.2794)
			(end -0.12065 -0.2794)
			(stroke
				(width 0.1)
				(type default)
			)
			(layer "B.Fab")
		)
		(fp_line
			(start -0.67945 -0.3048)
			(end -0.67945 0.3048)
			(stroke
				(width 0.1)
				(type default)
			)
			(layer "B.Fab")
		)
		(fp_line
			(start -0.12065 -0.3048)
			(end -0.67945 -0.3048)
			(stroke
				(width 0.1)
				(type default)
			)
			(layer "B.Fab")
		)
		(fp_line
			(start 0.12065 -0.305054)
			(end 0.12065 -0.2794)
			(stroke
				(width 0.1)
				(type default)
			)
			(layer "B.Fab")
		)
		(fp_line
			(start 0.67945 -0.305054)
			(end 0.12065 -0.305054)
			(stroke
				(width 0.1)
				(type default)
			)
			(layer "B.Fab")
		)
		(pad "1" smd circle
			(at 0.40005 0 90)
			(size 0 0)
			(layers "B.Cu" "B.Mask" "B.Paste")
			(net "HSC_VDD_R_1")
		)
		(pad "2" smd circle
			(at -0.40005 0 90)
			(size 0 0)
			(layers "B.Cu" "B.Mask" "B.Paste")
			(net "HSC_VDD")
		)
	)
	(footprint ""
		(layer "B.Cu")
		(at 290.948618 -149.992588 -90)
		(property "Reference" "R1821"
			(at 0 0 90)
			(layer "B.SilkS")
			(hide yes)
			(effects
				(font
					(size 1.27 1.27)
				)
				(justify mirror)
			)
		)
		(property "Value" ""
			(at 0 0 90)
			(layer "B.Fab")
			(effects
				(font
					(size 1.27 1.27)
				)
				(justify mirror)
			)
		)
		(duplicate_pad_numbers_are_jumpers no)
		(fp_line
			(start -0.7874 0.4064)
			(end 0.7874 0.4064)
			(stroke
				(width 0.1524)
				(type default)
			)
			(layer "B.SilkS")
		)
		(fp_line
			(start 0.7874 0.4064)
			(end 0.7874 -0.4064)
			(stroke
				(width 0.1524)
				(type default)
			)
			(layer "B.SilkS")
		)
		(fp_line
			(start -0.7874 -0.4064)
			(end -0.7874 0.4064)
			(stroke
				(width 0.1524)
				(type default)
			)
			(layer "B.SilkS")
		)
		(fp_line
			(start 0.7874 -0.4064)
			(end -0.7874 -0.4064)
			(stroke
				(width 0.1524)
				(type default)
			)
			(layer "B.SilkS")
		)
		(fp_line
			(start -0.67945 0.3048)
			(end -0.120396 0.3048)
			(stroke
				(width 0.1)
				(type default)
			)
			(layer "B.Fab")
		)
		(fp_line
			(start -0.120396 0.3048)
			(end -0.120396 0.2794)
			(stroke
				(width 0.1)
				(type default)
			)
			(layer "B.Fab")
		)
		(fp_line
			(start 0.12065 0.3048)
			(end 0.67945 0.3048)
			(stroke
				(width 0.1)
				(type default)
			)
			(layer "B.Fab")
		)
		(fp_line
			(start 0.67945 0.3048)
			(end 0.67945 -0.305054)
			(stroke
				(width 0.1)
				(type default)
			)
			(layer "B.Fab")
		)
		(fp_line
			(start -0.120396 0.2794)
			(end 0.12065 0.2794)
			(stroke
				(width 0.1)
				(type default)
			)
			(layer "B.Fab")
		)
		(fp_line
			(start 0.12065 0.2794)
			(end 0.12065 0.3048)
			(stroke
				(width 0.1)
				(type default)
			)
			(layer "B.Fab")
		)
		(fp_line
			(start -0.12065 -0.2794)
			(end -0.12065 -0.3048)
			(stroke
				(width 0.1)
				(type default)
			)
			(layer "B.Fab")
		)
		(fp_line
			(start 0.12065 -0.2794)
			(end -0.12065 -0.2794)
			(stroke
				(width 0.1)
				(type default)
			)
			(layer "B.Fab")
		)
		(fp_line
			(start -0.67945 -0.3048)
			(end -0.67945 0.3048)
			(stroke
				(width 0.1)
				(type default)
			)
			(layer "B.Fab")
		)
		(fp_line
			(start -0.12065 -0.3048)
			(end -0.67945 -0.3048)
			(stroke
				(width 0.1)
				(type default)
			)
			(layer "B.Fab")
		)
		(fp_line
			(start 0.12065 -0.305054)
			(end 0.12065 -0.2794)
			(stroke
				(width 0.1)
				(type default)
			)
			(layer "B.Fab")
		)
		(fp_line
			(start 0.67945 -0.305054)
			(end 0.12065 -0.305054)
			(stroke
				(width 0.1)
				(type default)
			)
			(layer "B.Fab")
		)
		(pad "1" smd circle
			(at 0.40005 0 90)
			(size 0 0)
			(layers "B.Cu" "B.Mask" "B.Paste")
			(net "FM_SPD_REMOTE_EN_R")
		)
		(pad "2" smd circle
			(at -0.40005 0 90)
			(size 0 0)
			(layers "B.Cu" "B.Mask" "B.Paste")
			(net "FM_SPD_REMOTE_EN")
		)
	)
	(footprint ""
		(layer "B.Cu")
		(at 308.902608 -250.785376 90)
		(property "Reference" "C520"
			(at 0 0 90)
			(layer "B.SilkS")
			(hide yes)
			(effects
				(font
					(size 1.27 1.27)
				)
				(justify mirror)
			)
		)
		(property "Value" ""
			(at 0 0 90)
			(layer "B.Fab")
			(effects
				(font
					(size 1.27 1.27)
				)
				(justify mirror)
			)
		)
		(duplicate_pad_numbers_are_jumpers no)
		(fp_line
			(start 1.524 -0.762)
			(end -1.524 -0.762)
			(stroke
				(width 0.1524)
				(type default)
			)
			(layer "B.SilkS")
		)
		(fp_line
			(start -1.524 -0.762)
			(end -1.524 0.762)
			(stroke
				(width 0.1524)
				(type default)
			)
			(layer "B.SilkS")
		)
		(fp_line
			(start 1.524 0.762)
			(end 1.524 -0.762)
			(stroke
				(width 0.1524)
				(type default)
			)
			(layer "B.SilkS")
		)
		(fp_line
			(start -1.524 0.762)
			(end 1.524 0.762)
			(stroke
				(width 0.1524)
				(type default)
			)
			(layer "B.SilkS")
		)
		(fp_line
			(start 1.1049 -0.724916)
			(end 1.1049 0.724916)
			(stroke
				(width 0.1)
				(type default)
			)
			(layer "B.Fab")
		)
		(fp_line
			(start -1.1049 -0.724916)
			(end 1.1049 -0.724916)
			(stroke
				(width 0.1)
				(type default)
			)
			(layer "B.Fab")
		)
		(fp_line
			(start 1.1049 0.724916)
			(end -1.1049 0.724916)
			(stroke
				(width 0.1)
				(type default)
			)
			(layer "B.Fab")
		)
		(fp_line
			(start -1.1049 0.724916)
			(end -1.1049 -0.724916)
			(stroke
				(width 0.1)
				(type default)
			)
			(layer "B.Fab")
		)
		(pad "1" smd rect
			(at 0.889 0 90)
			(size 1.016 1.27)
			(layers "B.Cu" "B.Mask" "B.Paste")
			(net "PVCCFA_EHV_FIVRA_CPU0")
		)
		(pad "2" smd rect
			(at -0.889 0 90)
			(size 1.016 1.27)
			(layers "B.Cu" "B.Mask" "B.Paste")
			(net "GND")
		)
	)
	(footprint ""
		(layer "B.Cu")
		(at 15.433294 -110.987586 90)
		(property "Reference" "C5234"
			(at 0 0 90)
			(layer "B.SilkS")
			(hide yes)
			(effects
				(font
					(size 1.27 1.27)
				)
				(justify mirror)
			)
		)
		(property "Value" ""
			(at 0 0 90)
			(layer "B.Fab")
			(effects
				(font
					(size 1.27 1.27)
				)
				(justify mirror)
			)
		)
		(duplicate_pad_numbers_are_jumpers no)
		(fp_line
			(start 0.7874 -0.4064)
			(end -0.7874 -0.4064)
			(stroke
				(width 0.1524)
				(type default)
			)
			(layer "B.SilkS")
		)
		(fp_line
			(start -0.7874 -0.4064)
			(end -0.7874 0.4064)
			(stroke
				(width 0.1524)
				(type default)
			)
			(layer "B.SilkS")
		)
		(fp_line
			(start 0.7874 0.4064)
			(end 0.7874 -0.4064)
			(stroke
				(width 0.1524)
				(type default)
			)
			(layer "B.SilkS")
		)
		(fp_line
			(start -0.7874 0.4064)
			(end 0.7874 0.4064)
			(stroke
				(width 0.1524)
				(type default)
			)
			(layer "B.SilkS")
		)
		(fp_line
			(start 0.67945 -0.305054)
			(end 0.12065 -0.305054)
			(stroke
				(width 0.1)
				(type default)
			)
			(layer "B.Fab")
		)
		(fp_line
			(start 0.12065 -0.305054)
			(end 0.12065 -0.2794)
			(stroke
				(width 0.1)
				(type default)
			)
			(layer "B.Fab")
		)
		(fp_line
			(start -0.12065 -0.3048)
			(end -0.67945 -0.3048)
			(stroke
				(width 0.1)
				(type default)
			)
			(layer "B.Fab")
		)
		(fp_line
			(start -0.67945 -0.3048)
			(end -0.67945 0.3048)
			(stroke
				(width 0.1)
				(type default)
			)
			(layer "B.Fab")
		)
		(fp_line
			(start 0.12065 -0.2794)
			(end -0.12065 -0.2794)
			(stroke
				(width 0.1)
				(type default)
			)
			(layer "B.Fab")
		)
		(fp_line
			(start -0.12065 -0.2794)
			(end -0.12065 -0.3048)
			(stroke
				(width 0.1)
				(type default)
			)
			(layer "B.Fab")
		)
		(fp_line
			(start 0.12065 0.2794)
			(end 0.12065 0.3048)
			(stroke
				(width 0.1)
				(type default)
			)
			(layer "B.Fab")
		)
		(fp_line
			(start -0.120396 0.2794)
			(end 0.12065 0.2794)
			(stroke
				(width 0.1)
				(type default)
			)
			(layer "B.Fab")
		)
		(fp_line
			(start 0.67945 0.3048)
			(end 0.67945 -0.305054)
			(stroke
				(width 0.1)
				(type default)
			)
			(layer "B.Fab")
		)
		(fp_line
			(start 0.12065 0.3048)
			(end 0.67945 0.3048)
			(stroke
				(width 0.1)
				(type default)
			)
			(layer "B.Fab")
		)
		(fp_line
			(start -0.120396 0.3048)
			(end -0.120396 0.2794)
			(stroke
				(width 0.1)
				(type default)
			)
			(layer "B.Fab")
		)
		(fp_line
			(start -0.67945 0.3048)
			(end -0.120396 0.3048)
			(stroke
				(width 0.1)
				(type default)
			)
			(layer "B.Fab")
		)
		(pad "1" smd circle
			(at 0.40005 0 270)
			(size 0 0)
			(layers "B.Cu" "B.Mask" "B.Paste")
			(net "P3V3_AUX")
		)
		(pad "2" smd circle
			(at -0.40005 0 270)
			(size 0 0)
			(layers "B.Cu" "B.Mask" "B.Paste")
			(net "GND")
		)
	)
	(footprint ""
		(layer "B.Cu")
		(at 329.119992 -65.24752 45)
		(property "Reference" "C1251"
			(at 0 0 45)
			(layer "B.SilkS")
			(hide yes)
			(effects
				(font
					(size 1.27 1.27)
				)
				(justify mirror)
			)
		)
		(property "Value" ""
			(at 0 0 45)
			(layer "B.Fab")
			(effects
				(font
					(size 1.27 1.27)
				)
				(justify mirror)
			)
		)
		(duplicate_pad_numbers_are_jumpers no)
		(fp_line
			(start -1.295492 -0.584255)
			(end -1.295492 0.584255)
			(stroke
				(width 0.1524)
				(type default)
			)
			(layer "B.SilkS")
		)
		(fp_line
			(start -1.295492 0.584255)
			(end 1.295492 0.584255)
			(stroke
				(width 0.1524)
				(type default)
			)
			(layer "B.SilkS")
		)
		(fp_line
			(start 0 -0.584076)
			(end 0 0.584076)
			(stroke
				(width 0.1524)
				(type default)
			)
			(layer "B.SilkS")
		)
		(fp_line
			(start 1.295492 -0.584255)
			(end -1.295492 -0.584255)
			(stroke
				(width 0.1524)
				(type default)
			)
			(layer "B.SilkS")
		)
		(fp_line
			(start 1.295492 0.584255)
			(end 1.295492 -0.584255)
			(stroke
				(width 0.1524)
				(type default)
			)
			(layer "B.SilkS")
		)
		(fp_line
			(start -1.193835 -0.406446)
			(end -1.193835 0.406446)
			(stroke
				(width 0.1)
				(type default)
			)
			(layer "B.Fab")
		)
		(fp_line
			(start -0.863541 -0.457275)
			(end -0.863721 -0.406446)
			(stroke
				(width 0.1)
				(type default)
			)
			(layer "B.Fab")
		)
		(fp_line
			(start -0.863721 -0.406446)
			(end -1.193835 -0.406446)
			(stroke
				(width 0.1)
				(type default)
			)
			(layer "B.Fab")
		)
		(fp_line
			(start -1.193835 0.406446)
			(end -0.863721 0.406446)
			(stroke
				(width 0.1)
				(type default)
			)
			(layer "B.Fab")
		)
		(fp_line
			(start -0.863721 0.406446)
			(end -0.863541 0.457275)
			(stroke
				(width 0.1)
				(type default)
			)
			(layer "B.Fab")
		)
		(fp_line
			(start -0.863541 0.457275)
			(end 0.863541 0.457275)
			(stroke
				(width 0.1)
				(type default)
			)
			(layer "B.Fab")
		)
		(fp_line
			(start 0.863541 -0.457275)
			(end -0.863541 -0.457275)
			(stroke
				(width 0.1)
				(type default)
			)
			(layer "B.Fab")
		)
		(fp_line
			(start 0.863721 -0.406446)
			(end 0.863541 -0.457275)
			(stroke
				(width 0.1)
				(type default)
			)
			(layer "B.Fab")
		)
		(fp_line
			(start 1.193835 -0.406446)
			(end 0.863721 -0.406446)
			(stroke
				(width 0.1)
				(type default)
			)
			(layer "B.Fab")
		)
		(fp_line
			(start 0.863721 0.406446)
			(end 1.193835 0.406446)
			(stroke
				(width 0.1)
				(type default)
			)
			(layer "B.Fab")
		)
		(fp_line
			(start 0.863541 0.457275)
			(end 0.863721 0.406446)
			(stroke
				(width 0.1)
				(type default)
			)
			(layer "B.Fab")
		)
		(fp_line
			(start 1.193835 0.406446)
			(end 1.193835 -0.406446)
			(stroke
				(width 0.1)
				(type default)
			)
			(layer "B.Fab")
		)
		(pad "1" smd rect
			(at 0.7366 0 315)
			(size 0.7112 0.8128)
			(layers "B.Cu" "B.Mask" "B.Paste")
			(net "P1V05_PCH_PLL_AUX")
		)
		(pad "2" smd rect
			(at -0.7366 0 315)
			(size 0.7112 0.8128)
			(layers "B.Cu" "B.Mask" "B.Paste")
			(net "GND")
		)
	)
	(footprint ""
		(layer "B.Cu")
		(at 175.830738 -97.32137 -90)
		(property "Reference" "R162"
			(at 0 0 90)
			(layer "B.SilkS")
			(hide yes)
			(effects
				(font
					(size 1.27 1.27)
				)
				(justify mirror)
			)
		)
		(property "Value" ""
			(at 0 0 90)
			(layer "B.Fab")
			(effects
				(font
					(size 1.27 1.27)
				)
				(justify mirror)
			)
		)
		(duplicate_pad_numbers_are_jumpers no)
		(fp_line
			(start -0.7874 0.4064)
			(end 0.7874 0.4064)
			(stroke
				(width 0.1524)
				(type default)
			)
			(layer "B.SilkS")
		)
		(fp_line
			(start 0.7874 0.4064)
			(end 0.7874 -0.4064)
			(stroke
				(width 0.1524)
				(type default)
			)
			(layer "B.SilkS")
		)
		(fp_line
			(start -0.7874 -0.4064)
			(end -0.7874 0.4064)
			(stroke
				(width 0.1524)
				(type default)
			)
			(layer "B.SilkS")
		)
		(fp_line
			(start 0.7874 -0.4064)
			(end -0.7874 -0.4064)
			(stroke
				(width 0.1524)
				(type default)
			)
			(layer "B.SilkS")
		)
		(fp_line
			(start -0.67945 0.3048)
			(end -0.120396 0.3048)
			(stroke
				(width 0.1)
				(type default)
			)
			(layer "B.Fab")
		)
		(fp_line
			(start -0.120396 0.3048)
			(end -0.120396 0.2794)
			(stroke
				(width 0.1)
				(type default)
			)
			(layer "B.Fab")
		)
		(fp_line
			(start 0.12065 0.3048)
			(end 0.67945 0.3048)
			(stroke
				(width 0.1)
				(type default)
			)
			(layer "B.Fab")
		)
		(fp_line
			(start 0.67945 0.3048)
			(end 0.67945 -0.305054)
			(stroke
				(width 0.1)
				(type default)
			)
			(layer "B.Fab")
		)
		(fp_line
			(start -0.120396 0.2794)
			(end 0.12065 0.2794)
			(stroke
				(width 0.1)
				(type default)
			)
			(layer "B.Fab")
		)
		(fp_line
			(start 0.12065 0.2794)
			(end 0.12065 0.3048)
			(stroke
				(width 0.1)
				(type default)
			)
			(layer "B.Fab")
		)
		(fp_line
			(start -0.12065 -0.2794)
			(end -0.12065 -0.3048)
			(stroke
				(width 0.1)
				(type default)
			)
			(layer "B.Fab")
		)
		(fp_line
			(start 0.12065 -0.2794)
			(end -0.12065 -0.2794)
			(stroke
				(width 0.1)
				(type default)
			)
			(layer "B.Fab")
		)
		(fp_line
			(start -0.67945 -0.3048)
			(end -0.67945 0.3048)
			(stroke
				(width 0.1)
				(type default)
			)
			(layer "B.Fab")
		)
		(fp_line
			(start -0.12065 -0.3048)
			(end -0.67945 -0.3048)
			(stroke
				(width 0.1)
				(type default)
			)
			(layer "B.Fab")
		)
		(fp_line
			(start 0.12065 -0.305054)
			(end 0.12065 -0.2794)
			(stroke
				(width 0.1)
				(type default)
			)
			(layer "B.Fab")
		)
		(fp_line
			(start 0.67945 -0.305054)
			(end 0.12065 -0.305054)
			(stroke
				(width 0.1)
				(type default)
			)
			(layer "B.Fab")
		)
		(pad "1" smd circle
			(at 0.40005 0 90)
			(size 0 0)
			(layers "B.Cu" "B.Mask" "B.Paste")
			(net "PWRGD_DRAMPWRGD_CPU0_CD_R_LVC1")
		)
		(pad "2" smd circle
			(at -0.40005 0 90)
			(size 0 0)
			(layers "B.Cu" "B.Mask" "B.Paste")
			(net "PWRGD_DRAMPWRGD_CPU0_CD_LVC1_R2")
		)
	)
	(footprint ""
		(layer "B.Cu")
		(at 382.782064 -186.935364 90)
		(property "Reference" "R292"
			(at 0 0 90)
			(layer "B.SilkS")
			(hide yes)
			(effects
				(font
					(size 1.27 1.27)
				)
				(justify mirror)
			)
		)
		(property "Value" ""
			(at 0 0 90)
			(layer "B.Fab")
			(effects
				(font
					(size 1.27 1.27)
				)
				(justify mirror)
			)
		)
		(duplicate_pad_numbers_are_jumpers no)
		(fp_line
			(start 0.7874 -0.4064)
			(end -0.7874 -0.4064)
			(stroke
				(width 0.1524)
				(type default)
			)
			(layer "B.SilkS")
		)
		(fp_line
			(start -0.7874 -0.4064)
			(end -0.7874 0.4064)
			(stroke
				(width 0.1524)
				(type default)
			)
			(layer "B.SilkS")
		)
		(fp_line
			(start 0.7874 0.4064)
			(end 0.7874 -0.4064)
			(stroke
				(width 0.1524)
				(type default)
			)
			(layer "B.SilkS")
		)
		(fp_line
			(start -0.7874 0.4064)
			(end 0.7874 0.4064)
			(stroke
				(width 0.1524)
				(type default)
			)
			(layer "B.SilkS")
		)
		(fp_line
			(start 0.67945 -0.305054)
			(end 0.12065 -0.305054)
			(stroke
				(width 0.1)
				(type default)
			)
			(layer "B.Fab")
		)
		(fp_line
			(start 0.12065 -0.305054)
			(end 0.12065 -0.2794)
			(stroke
				(width 0.1)
				(type default)
			)
			(layer "B.Fab")
		)
		(fp_line
			(start -0.12065 -0.3048)
			(end -0.67945 -0.3048)
			(stroke
				(width 0.1)
				(type default)
			)
			(layer "B.Fab")
		)
		(fp_line
			(start -0.67945 -0.3048)
			(end -0.67945 0.3048)
			(stroke
				(width 0.1)
				(type default)
			)
			(layer "B.Fab")
		)
		(fp_line
			(start 0.12065 -0.2794)
			(end -0.12065 -0.2794)
			(stroke
				(width 0.1)
				(type default)
			)
			(layer "B.Fab")
		)
		(fp_line
			(start -0.12065 -0.2794)
			(end -0.12065 -0.3048)
			(stroke
				(width 0.1)
				(type default)
			)
			(layer "B.Fab")
		)
		(fp_line
			(start 0.12065 0.2794)
			(end 0.12065 0.3048)
			(stroke
				(width 0.1)
				(type default)
			)
			(layer "B.Fab")
		)
		(fp_line
			(start -0.120396 0.2794)
			(end 0.12065 0.2794)
			(stroke
				(width 0.1)
				(type default)
			)
			(layer "B.Fab")
		)
		(fp_line
			(start 0.67945 0.3048)
			(end 0.67945 -0.305054)
			(stroke
				(width 0.1)
				(type default)
			)
			(layer "B.Fab")
		)
		(fp_line
			(start 0.12065 0.3048)
			(end 0.67945 0.3048)
			(stroke
				(width 0.1)
				(type default)
			)
			(layer "B.Fab")
		)
		(fp_line
			(start -0.120396 0.3048)
			(end -0.120396 0.2794)
			(stroke
				(width 0.1)
				(type default)
			)
			(layer "B.Fab")
		)
		(fp_line
			(start -0.67945 0.3048)
			(end -0.120396 0.3048)
			(stroke
				(width 0.1)
				(type default)
			)
			(layer "B.Fab")
		)
		(pad "1" smd circle
			(at 0.40005 0 270)
			(size 0 0)
			(layers "B.Cu" "B.Mask" "B.Paste")
			(net "PVNN_TERM_CPU0")
		)
		(pad "2" smd circle
			(at -0.40005 0 270)
			(size 0 0)
			(layers "B.Cu" "B.Mask" "B.Paste")
			(net "PD_CPU0_TXT_PLTEN")
		)
	)
	(footprint ""
		(layer "B.Cu")
		(at 185.53684 -104.491028 180)
		(property "Reference" "R171"
			(at 0 0 0)
			(layer "B.SilkS")
			(hide yes)
			(effects
				(font
					(size 1.27 1.27)
				)
				(justify mirror)
			)
		)
		(property "Value" ""
			(at 0 0 0)
			(layer "B.Fab")
			(effects
				(font
					(size 1.27 1.27)
				)
				(justify mirror)
			)
		)
		(duplicate_pad_numbers_are_jumpers no)
		(fp_line
			(start 0.7874 0.4064)
			(end 0.7874 -0.4064)
			(stroke
				(width 0.1524)
				(type default)
			)
			(layer "B.SilkS")
		)
		(fp_line
			(start 0.7874 -0.4064)
			(end -0.7874 -0.4064)
			(stroke
				(width 0.1524)
				(type default)
			)
			(layer "B.SilkS")
		)
		(fp_line
			(start -0.7874 0.4064)
			(end 0.7874 0.4064)
			(stroke
				(width 0.1524)
				(type default)
			)
			(layer "B.SilkS")
		)
		(fp_line
			(start -0.7874 -0.4064)
			(end -0.7874 0.4064)
			(stroke
				(width 0.1524)
				(type default)
			)
			(layer "B.SilkS")
		)
		(fp_line
			(start 0.67945 0.3048)
			(end 0.67945 -0.305054)
			(stroke
				(width 0.1)
				(type default)
			)
			(layer "B.Fab")
		)
		(fp_line
			(start 0.67945 -0.305054)
			(end 0.12065 -0.305054)
			(stroke
				(width 0.1)
				(type default)
			)
			(layer "B.Fab")
		)
		(fp_line
			(start 0.12065 0.3048)
			(end 0.67945 0.3048)
			(stroke
				(width 0.1)
				(type default)
			)
			(layer "B.Fab")
		)
		(fp_line
			(start 0.12065 0.2794)
			(end 0.12065 0.3048)
			(stroke
				(width 0.1)
				(type default)
			)
			(layer "B.Fab")
		)
		(fp_line
			(start 0.12065 -0.2794)
			(end -0.12065 -0.2794)
			(stroke
				(width 0.1)
				(type default)
			)
			(layer "B.Fab")
		)
		(fp_line
			(start 0.12065 -0.305054)
			(end 0.12065 -0.2794)
			(stroke
				(width 0.1)
				(type default)
			)
			(layer "B.Fab")
		)
		(fp_line
			(start -0.120396 0.3048)
			(end -0.120396 0.2794)
			(stroke
				(width 0.1)
				(type default)
			)
			(layer "B.Fab")
		)
		(fp_line
			(start -0.120396 0.2794)
			(end 0.12065 0.2794)
			(stroke
				(width 0.1)
				(type default)
			)
			(layer "B.Fab")
		)
		(fp_line
			(start -0.12065 -0.2794)
			(end -0.12065 -0.3048)
			(stroke
				(width 0.1)
				(type default)
			)
			(layer "B.Fab")
		)
		(fp_line
			(start -0.12065 -0.3048)
			(end -0.67945 -0.3048)
			(stroke
				(width 0.1)
				(type default)
			)
			(layer "B.Fab")
		)
		(fp_line
			(start -0.67945 0.3048)
			(end -0.120396 0.3048)
			(stroke
				(width 0.1)
				(type default)
			)
			(layer "B.Fab")
		)
		(fp_line
			(start -0.67945 -0.3048)
			(end -0.67945 0.3048)
			(stroke
				(width 0.1)
				(type default)
			)
			(layer "B.Fab")
		)
		(pad "1" smd circle
			(at 0.40005 0)
			(size 0 0)
			(layers "B.Cu" "B.Mask" "B.Paste")
			(net "RST_CPU0_LVC1_R_N")
		)
		(pad "2" smd circle
			(at -0.40005 0)
			(size 0 0)
			(layers "B.Cu" "B.Mask" "B.Paste")
			(net "RST_CPU0_BUF_R_N")
		)
	)
	(footprint ""
		(layer "B.Cu")
		(at 166.369746 -319.268856 180)
		(property "Reference" "C93"
			(at 0 0 0)
			(layer "B.SilkS")
			(hide yes)
			(effects
				(font
					(size 1.27 1.27)
				)
				(justify mirror)
			)
		)
		(property "Value" ""
			(at 0 0 0)
			(layer "B.Fab")
			(effects
				(font
					(size 1.27 1.27)
				)
				(justify mirror)
			)
		)
		(duplicate_pad_numbers_are_jumpers no)
		(fp_line
			(start 0.7874 0.4064)
			(end 0.7874 -0.4064)
			(stroke
				(width 0.1524)
				(type default)
			)
			(layer "B.SilkS")
		)
		(fp_line
			(start 0.7874 -0.4064)
			(end -0.7874 -0.4064)
			(stroke
				(width 0.1524)
				(type default)
			)
			(layer "B.SilkS")
		)
		(fp_line
			(start -0.7874 0.4064)
			(end 0.7874 0.4064)
			(stroke
				(width 0.1524)
				(type default)
			)
			(layer "B.SilkS")
		)
		(fp_line
			(start -0.7874 -0.4064)
			(end -0.7874 0.4064)
			(stroke
				(width 0.1524)
				(type default)
			)
			(layer "B.SilkS")
		)
		(fp_line
			(start 0.67945 0.3048)
			(end 0.67945 -0.305054)
			(stroke
				(width 0.1)
				(type default)
			)
			(layer "B.Fab")
		)
		(fp_line
			(start 0.67945 -0.305054)
			(end 0.12065 -0.305054)
			(stroke
				(width 0.1)
				(type default)
			)
			(layer "B.Fab")
		)
		(fp_line
			(start 0.12065 0.3048)
			(end 0.67945 0.3048)
			(stroke
				(width 0.1)
				(type default)
			)
			(layer "B.Fab")
		)
		(fp_line
			(start 0.12065 0.2794)
			(end 0.12065 0.3048)
			(stroke
				(width 0.1)
				(type default)
			)
			(layer "B.Fab")
		)
		(fp_line
			(start 0.12065 -0.2794)
			(end -0.12065 -0.2794)
			(stroke
				(width 0.1)
				(type default)
			)
			(layer "B.Fab")
		)
		(fp_line
			(start 0.12065 -0.305054)
			(end 0.12065 -0.2794)
			(stroke
				(width 0.1)
				(type default)
			)
			(layer "B.Fab")
		)
		(fp_line
			(start -0.120396 0.3048)
			(end -0.120396 0.2794)
			(stroke
				(width 0.1)
				(type default)
			)
			(layer "B.Fab")
		)
		(fp_line
			(start -0.120396 0.2794)
			(end 0.12065 0.2794)
			(stroke
				(width 0.1)
				(type default)
			)
			(layer "B.Fab")
		)
		(fp_line
			(start -0.12065 -0.2794)
			(end -0.12065 -0.3048)
			(stroke
				(width 0.1)
				(type default)
			)
			(layer "B.Fab")
		)
		(fp_line
			(start -0.12065 -0.3048)
			(end -0.67945 -0.3048)
			(stroke
				(width 0.1)
				(type default)
			)
			(layer "B.Fab")
		)
		(fp_line
			(start -0.67945 0.3048)
			(end -0.120396 0.3048)
			(stroke
				(width 0.1)
				(type default)
			)
			(layer "B.Fab")
		)
		(fp_line
			(start -0.67945 -0.3048)
			(end -0.67945 0.3048)
			(stroke
				(width 0.1)
				(type default)
			)
			(layer "B.Fab")
		)
		(pad "1" smd circle
			(at 0.40005 0)
			(size 0 0)
			(layers "B.Cu" "B.Mask" "B.Paste")
			(net "P3V3_AUX")
		)
		(pad "2" smd circle
			(at -0.40005 0)
			(size 0 0)
			(layers "B.Cu" "B.Mask" "B.Paste")
			(net "GND")
		)
	)
	(footprint ""
		(layer "B.Cu")
		(at 333.824326 -31.397702 90)
		(property "Reference" "R915"
			(at 0 0 90)
			(layer "B.SilkS")
			(hide yes)
			(effects
				(font
					(size 1.27 1.27)
				)
				(justify mirror)
			)
		)
		(property "Value" ""
			(at 0 0 90)
			(layer "B.Fab")
			(effects
				(font
					(size 1.27 1.27)
				)
				(justify mirror)
			)
		)
		(duplicate_pad_numbers_are_jumpers no)
		(fp_line
			(start 0.7874 -0.4064)
			(end -0.7874 -0.4064)
			(stroke
				(width 0.1524)
				(type default)
			)
			(layer "B.SilkS")
		)
		(fp_line
			(start -0.7874 -0.4064)
			(end -0.7874 0.4064)
			(stroke
				(width 0.1524)
				(type default)
			)
			(layer "B.SilkS")
		)
		(fp_line
			(start 0.7874 0.4064)
			(end 0.7874 -0.4064)
			(stroke
				(width 0.1524)
				(type default)
			)
			(layer "B.SilkS")
		)
		(fp_line
			(start -0.7874 0.4064)
			(end 0.7874 0.4064)
			(stroke
				(width 0.1524)
				(type default)
			)
			(layer "B.SilkS")
		)
		(fp_line
			(start 0.67945 -0.305054)
			(end 0.12065 -0.305054)
			(stroke
				(width 0.1)
				(type default)
			)
			(layer "B.Fab")
		)
		(fp_line
			(start 0.12065 -0.305054)
			(end 0.12065 -0.2794)
			(stroke
				(width 0.1)
				(type default)
			)
			(layer "B.Fab")
		)
		(fp_line
			(start -0.12065 -0.3048)
			(end -0.67945 -0.3048)
			(stroke
				(width 0.1)
				(type default)
			)
			(layer "B.Fab")
		)
		(fp_line
			(start -0.67945 -0.3048)
			(end -0.67945 0.3048)
			(stroke
				(width 0.1)
				(type default)
			)
			(layer "B.Fab")
		)
		(fp_line
			(start 0.12065 -0.2794)
			(end -0.12065 -0.2794)
			(stroke
				(width 0.1)
				(type default)
			)
			(layer "B.Fab")
		)
		(fp_line
			(start -0.12065 -0.2794)
			(end -0.12065 -0.3048)
			(stroke
				(width 0.1)
				(type default)
			)
			(layer "B.Fab")
		)
		(fp_line
			(start 0.12065 0.2794)
			(end 0.12065 0.3048)
			(stroke
				(width 0.1)
				(type default)
			)
			(layer "B.Fab")
		)
		(fp_line
			(start -0.120396 0.2794)
			(end 0.12065 0.2794)
			(stroke
				(width 0.1)
				(type default)
			)
			(layer "B.Fab")
		)
		(fp_line
			(start 0.67945 0.3048)
			(end 0.67945 -0.305054)
			(stroke
				(width 0.1)
				(type default)
			)
			(layer "B.Fab")
		)
		(fp_line
			(start 0.12065 0.3048)
			(end 0.67945 0.3048)
			(stroke
				(width 0.1)
				(type default)
			)
			(layer "B.Fab")
		)
		(fp_line
			(start -0.120396 0.3048)
			(end -0.120396 0.2794)
			(stroke
				(width 0.1)
				(type default)
			)
			(layer "B.Fab")
		)
		(fp_line
			(start -0.67945 0.3048)
			(end -0.120396 0.3048)
			(stroke
				(width 0.1)
				(type default)
			)
			(layer "B.Fab")
		)
		(pad "1" smd circle
			(at 0.40005 0 270)
			(size 0 0)
			(layers "B.Cu" "B.Mask" "B.Paste")
			(net "SPI_PCH_IO0")
		)
		(pad "2" smd circle
			(at -0.40005 0 270)
			(size 0 0)
			(layers "B.Cu" "B.Mask" "B.Paste")
			(net "SPI_SYS_MOSI")
		)
	)
	(footprint ""
		(layer "B.Cu")
		(at 175.9712 -319.293748)
		(property "Reference" "R76"
			(at 0 0 0)
			(layer "B.SilkS")
			(hide yes)
			(effects
				(font
					(size 1.27 1.27)
				)
				(justify mirror)
			)
		)
		(property "Value" ""
			(at 0 0 0)
			(layer "B.Fab")
			(effects
				(font
					(size 1.27 1.27)
				)
				(justify mirror)
			)
		)
		(duplicate_pad_numbers_are_jumpers no)
		(fp_line
			(start -0.7874 -0.4064)
			(end -0.7874 0.4064)
			(stroke
				(width 0.1524)
				(type default)
			)
			(layer "B.SilkS")
		)
		(fp_line
			(start -0.7874 0.4064)
			(end 0.7874 0.4064)
			(stroke
				(width 0.1524)
				(type default)
			)
			(layer "B.SilkS")
		)
		(fp_line
			(start 0.7874 -0.4064)
			(end -0.7874 -0.4064)
			(stroke
				(width 0.1524)
				(type default)
			)
			(layer "B.SilkS")
		)
		(fp_line
			(start 0.7874 0.4064)
			(end 0.7874 -0.4064)
			(stroke
				(width 0.1524)
				(type default)
			)
			(layer "B.SilkS")
		)
		(fp_line
			(start -0.67945 -0.3048)
			(end -0.67945 0.3048)
			(stroke
				(width 0.1)
				(type default)
			)
			(layer "B.Fab")
		)
		(fp_line
			(start -0.67945 0.3048)
			(end -0.120396 0.3048)
			(stroke
				(width 0.1)
				(type default)
			)
			(layer "B.Fab")
		)
		(fp_line
			(start -0.12065 -0.3048)
			(end -0.67945 -0.3048)
			(stroke
				(width 0.1)
				(type default)
			)
			(layer "B.Fab")
		)
		(fp_line
			(start -0.12065 -0.2794)
			(end -0.12065 -0.3048)
			(stroke
				(width 0.1)
				(type default)
			)
			(layer "B.Fab")
		)
		(fp_line
			(start -0.120396 0.2794)
			(end 0.12065 0.2794)
			(stroke
				(width 0.1)
				(type default)
			)
			(layer "B.Fab")
		)
		(fp_line
			(start -0.120396 0.3048)
			(end -0.120396 0.2794)
			(stroke
				(width 0.1)
				(type default)
			)
			(layer "B.Fab")
		)
		(fp_line
			(start 0.12065 -0.305054)
			(end 0.12065 -0.2794)
			(stroke
				(width 0.1)
				(type default)
			)
			(layer "B.Fab")
		)
		(fp_line
			(start 0.12065 -0.2794)
			(end -0.12065 -0.2794)
			(stroke
				(width 0.1)
				(type default)
			)
			(layer "B.Fab")
		)
		(fp_line
			(start 0.12065 0.2794)
			(end 0.12065 0.3048)
			(stroke
				(width 0.1)
				(type default)
			)
			(layer "B.Fab")
		)
		(fp_line
			(start 0.12065 0.3048)
			(end 0.67945 0.3048)
			(stroke
				(width 0.1)
				(type default)
			)
			(layer "B.Fab")
		)
		(fp_line
			(start 0.67945 -0.305054)
			(end 0.12065 -0.305054)
			(stroke
				(width 0.1)
				(type default)
			)
			(layer "B.Fab")
		)
		(fp_line
			(start 0.67945 0.3048)
			(end 0.67945 -0.305054)
			(stroke
				(width 0.1)
				(type default)
			)
			(layer "B.Fab")
		)
		(pad "1" smd circle
			(at 0.40005 0 180)
			(size 0 0)
			(layers "B.Cu" "B.Mask" "B.Paste")
			(net "PD_CHF_CPU1_DIMM2_SAA")
		)
		(pad "2" smd circle
			(at -0.40005 0 180)
			(size 0 0)
			(layers "B.Cu" "B.Mask" "B.Paste")
			(net "GND")
		)
	)
	(footprint ""
		(layer "B.Cu")
		(at 311.84088 -52.288948)
		(property "Reference" "R4103"
			(at 0 0 0)
			(layer "B.SilkS")
			(hide yes)
			(effects
				(font
					(size 1.27 1.27)
				)
				(justify mirror)
			)
		)
		(property "Value" ""
			(at 0 0 0)
			(layer "B.Fab")
			(effects
				(font
					(size 1.27 1.27)
				)
				(justify mirror)
			)
		)
		(duplicate_pad_numbers_are_jumpers no)
		(fp_line
			(start -0.7874 -0.4064)
			(end -0.7874 0.4064)
			(stroke
				(width 0.1524)
				(type default)
			)
			(layer "B.SilkS")
		)
		(fp_line
			(start -0.7874 0.4064)
			(end 0.7874 0.4064)
			(stroke
				(width 0.1524)
				(type default)
			)
			(layer "B.SilkS")
		)
		(fp_line
			(start 0.7874 -0.4064)
			(end -0.7874 -0.4064)
			(stroke
				(width 0.1524)
				(type default)
			)
			(layer "B.SilkS")
		)
		(fp_line
			(start 0.7874 0.4064)
			(end 0.7874 -0.4064)
			(stroke
				(width 0.1524)
				(type default)
			)
			(layer "B.SilkS")
		)
		(fp_line
			(start -0.67945 -0.3048)
			(end -0.67945 0.3048)
			(stroke
				(width 0.1)
				(type default)
			)
			(layer "B.Fab")
		)
		(fp_line
			(start -0.67945 0.3048)
			(end -0.120396 0.3048)
			(stroke
				(width 0.1)
				(type default)
			)
			(layer "B.Fab")
		)
		(fp_line
			(start -0.12065 -0.3048)
			(end -0.67945 -0.3048)
			(stroke
				(width 0.1)
				(type default)
			)
			(layer "B.Fab")
		)
		(fp_line
			(start -0.12065 -0.2794)
			(end -0.12065 -0.3048)
			(stroke
				(width 0.1)
				(type default)
			)
			(layer "B.Fab")
		)
		(fp_line
			(start -0.120396 0.2794)
			(end 0.12065 0.2794)
			(stroke
				(width 0.1)
				(type default)
			)
			(layer "B.Fab")
		)
		(fp_line
			(start -0.120396 0.3048)
			(end -0.120396 0.2794)
			(stroke
				(width 0.1)
				(type default)
			)
			(layer "B.Fab")
		)
		(fp_line
			(start 0.12065 -0.305054)
			(end 0.12065 -0.2794)
			(stroke
				(width 0.1)
				(type default)
			)
			(layer "B.Fab")
		)
		(fp_line
			(start 0.12065 -0.2794)
			(end -0.12065 -0.2794)
			(stroke
				(width 0.1)
				(type default)
			)
			(layer "B.Fab")
		)
		(fp_line
			(start 0.12065 0.2794)
			(end 0.12065 0.3048)
			(stroke
				(width 0.1)
				(type default)
			)
			(layer "B.Fab")
		)
		(fp_line
			(start 0.12065 0.3048)
			(end 0.67945 0.3048)
			(stroke
				(width 0.1)
				(type default)
			)
			(layer "B.Fab")
		)
		(fp_line
			(start 0.67945 -0.305054)
			(end 0.12065 -0.305054)
			(stroke
				(width 0.1)
				(type default)
			)
			(layer "B.Fab")
		)
		(fp_line
			(start 0.67945 0.3048)
			(end 0.67945 -0.305054)
			(stroke
				(width 0.1)
				(type default)
			)
			(layer "B.Fab")
		)
		(pad "1" smd circle
			(at 0.40005 0 180)
			(size 0 0)
			(layers "B.Cu" "B.Mask" "B.Paste")
			(net "PD_GPP_M_17")
		)
		(pad "2" smd circle
			(at -0.40005 0 180)
			(size 0 0)
			(layers "B.Cu" "B.Mask" "B.Paste")
			(net "GND")
		)
	)
	(footprint ""
		(layer "B.Cu")
		(at 357.96093 -324.911466 -90)
		(property "Reference" "PC289_P0_3"
			(at 0 0 90)
			(layer "B.SilkS")
			(hide yes)
			(effects
				(font
					(size 1.27 1.27)
				)
				(justify mirror)
			)
		)
		(property "Value" ""
			(at 0 0 90)
			(layer "B.Fab")
			(effects
				(font
					(size 1.27 1.27)
				)
				(justify mirror)
			)
		)
		(duplicate_pad_numbers_are_jumpers no)
		(fp_line
			(start -1.524 0.762)
			(end 1.524 0.762)
			(stroke
				(width 0.1524)
				(type default)
			)
			(layer "B.SilkS")
		)
		(fp_line
			(start 1.524 0.762)
			(end 1.524 -0.762)
			(stroke
				(width 0.1524)
				(type default)
			)
			(layer "B.SilkS")
		)
		(fp_line
			(start -1.524 -0.762)
			(end -1.524 0.762)
			(stroke
				(width 0.1524)
				(type default)
			)
			(layer "B.SilkS")
		)
		(fp_line
			(start 1.524 -0.762)
			(end -1.524 -0.762)
			(stroke
				(width 0.1524)
				(type default)
			)
			(layer "B.SilkS")
		)
		(fp_line
			(start -1.1049 0.724916)
			(end -1.1049 -0.724916)
			(stroke
				(width 0.1)
				(type default)
			)
			(layer "B.Fab")
		)
		(fp_line
			(start 1.1049 0.724916)
			(end -1.1049 0.724916)
			(stroke
				(width 0.1)
				(type default)
			)
			(layer "B.Fab")
		)
		(fp_line
			(start -1.1049 -0.724916)
			(end 1.1049 -0.724916)
			(stroke
				(width 0.1)
				(type default)
			)
			(layer "B.Fab")
		)
		(fp_line
			(start 1.1049 -0.724916)
			(end 1.1049 0.724916)
			(stroke
				(width 0.1)
				(type default)
			)
			(layer "B.Fab")
		)
		(pad "1" smd rect
			(at 0.889 0 270)
			(size 1.016 1.27)
			(layers "B.Cu" "B.Mask" "B.Paste")
			(net "PVCCIN_CPU0")
		)
		(pad "2" smd rect
			(at -0.889 0 270)
			(size 1.016 1.27)
			(layers "B.Cu" "B.Mask" "B.Paste")
			(net "GND")
		)
	)
	(footprint ""
		(layer "B.Cu")
		(at 452.247 -81.031842 -90)
		(property "Reference" "D145"
			(at 1.205484 -1.580642 270)
			(unlocked yes)
			(layer "B.SilkS")
			(effects
				(font
					(size 0.7874 0.5842)
					(thickness 0.1524)
				)
				(justify left mirror)
			)
		)
		(property "Value" ""
			(at 0 0 90)
			(layer "B.Fab")
			(effects
				(font
					(size 1.27 1.27)
				)
				(justify mirror)
			)
		)
		(duplicate_pad_numbers_are_jumpers no)
		(fp_line
			(start -2.050796 0.700024)
			(end 2.050796 0.700024)
			(stroke
				(width 0.1524)
				(type default)
			)
			(layer "B.SilkS")
		)
		(fp_line
			(start 2.050796 0.700024)
			(end 2.050796 -0.700024)
			(stroke
				(width 0.1524)
				(type default)
			)
			(layer "B.SilkS")
		)
		(fp_line
			(start -2.343404 0.6985)
			(end -2.216404 0.6985)
			(stroke
				(width 0.1524)
				(type default)
			)
			(layer "B.SilkS")
		)
		(fp_line
			(start -2.229104 0.6985)
			(end -2.051304 0.6985)
			(stroke
				(width 0.1524)
				(type default)
			)
			(layer "B.SilkS")
		)
		(fp_line
			(start -2.051304 0.6985)
			(end -2.051304 0.635)
			(stroke
				(width 0.1524)
				(type default)
			)
			(layer "B.SilkS")
		)
		(fp_line
			(start -2.152904 0.635)
			(end -2.152904 -0.6985)
			(stroke
				(width 0.1524)
				(type default)
			)
			(layer "B.SilkS")
		)
		(fp_line
			(start -2.051304 0.635)
			(end -2.152904 0.635)
			(stroke
				(width 0.1524)
				(type default)
			)
			(layer "B.SilkS")
		)
		(fp_line
			(start 0.30607 0.500126)
			(end -0.193802 0)
			(stroke
				(width 0.1524)
				(type default)
			)
			(layer "B.SilkS")
		)
		(fp_line
			(start -0.193802 0)
			(end 0.30607 -0.500126)
			(stroke
				(width 0.1524)
				(type default)
			)
			(layer "B.SilkS")
		)
		(fp_line
			(start -0.293878 -0.500126)
			(end -0.293878 0.500126)
			(stroke
				(width 0.1524)
				(type default)
			)
			(layer "B.SilkS")
		)
		(fp_line
			(start 0.30607 -0.500126)
			(end 0.30607 0.500126)
			(stroke
				(width 0.1524)
				(type default)
			)
			(layer "B.SilkS")
		)
		(fp_line
			(start -2.064004 -0.6731)
			(end -2.064004 -0.6985)
			(stroke
				(width 0.1524)
				(type default)
			)
			(layer "B.SilkS")
		)
		(fp_line
			(start -2.343404 -0.6985)
			(end -2.343404 0.6985)
			(stroke
				(width 0.1524)
				(type default)
			)
			(layer "B.SilkS")
		)
		(fp_line
			(start -2.229104 -0.6985)
			(end -2.229104 0.6985)
			(stroke
				(width 0.1524)
				(type default)
			)
			(layer "B.SilkS")
		)
		(fp_line
			(start -2.152904 -0.6985)
			(end -2.343404 -0.6985)
			(stroke
				(width 0.1524)
				(type default)
			)
			(layer "B.SilkS")
		)
		(fp_line
			(start -2.064004 -0.6985)
			(end -2.229104 -0.6985)
			(stroke
				(width 0.1524)
				(type default)
			)
			(layer "B.SilkS")
		)
		(fp_line
			(start -2.050796 -0.700024)
			(end -2.050796 0.700024)
			(stroke
				(width 0.1524)
				(type default)
			)
			(layer "B.SilkS")
		)
		(fp_line
			(start 2.050796 -0.700024)
			(end -2.050796 -0.700024)
			(stroke
				(width 0.1524)
				(type default)
			)
			(layer "B.SilkS")
		)
		(fp_line
			(start -0.899922 0.700024)
			(end 0.899922 0.700024)
			(stroke
				(width 0.1)
				(type default)
			)
			(layer "B.Fab")
		)
		(fp_line
			(start 0.899922 0.700024)
			(end 0.899922 -0.700024)
			(stroke
				(width 0.1)
				(type default)
			)
			(layer "B.Fab")
		)
		(fp_line
			(start -0.899922 -0.700024)
			(end -0.899922 0.700024)
			(stroke
				(width 0.1)
				(type default)
			)
			(layer "B.Fab")
		)
		(fp_line
			(start 0.899922 -0.700024)
			(end -0.899922 -0.700024)
			(stroke
				(width 0.1)
				(type default)
			)
			(layer "B.Fab")
		)
		(fp_text user "+"
			(at 3.220466 -0.241046 180)
			(unlocked yes)
			(layer "B.SilkS")
			(effects
				(font
					(size 1.905 1.4224)
					(thickness 0.1524)
				)
				(justify left mirror)
			)
		)
		(fp_text user "-"
			(at -3.95732 -0.652526 90)
			(unlocked yes)
			(layer "B.SilkS")
			(effects
				(font
					(size 1.905 1.4224)
					(thickness 0.1524)
				)
				(justify left mirror)
			)
		)
		(fp_text user "+"
			(at 3.123946 0.762 180)
			(unlocked yes)
			(layer "B.Fab")
			(effects
				(font
					(size 1.905 1.4224)
					(thickness 0.1524)
				)
				(justify left mirror)
			)
		)
		(fp_text user "-"
			(at -3.880104 0.23495 90)
			(unlocked yes)
			(layer "B.Fab")
			(effects
				(font
					(size 1.905 1.4224)
					(thickness 0.1524)
				)
				(justify left mirror)
			)
		)
		(pad "1" smd rect
			(at 1.199896 0 180)
			(size 0.6604 1.3716)
			(layers "B.Cu" "B.Mask" "B.Paste")
			(net "MB0_P12V_STBY_PWRGD")
		)
		(pad "2" smd rect
			(at -1.199896 0)
			(size 0.6604 1.3716)
			(layers "B.Cu" "B.Mask" "B.Paste")
			(net "P3V3_AUX_EN")
		)
	)
	(footprint ""
		(layer "B.Cu")
		(at 184.976008 -398.651222)
		(property "Reference" "PR3931"
			(at 0 0 0)
			(layer "B.SilkS")
			(hide yes)
			(effects
				(font
					(size 1.27 1.27)
				)
				(justify mirror)
			)
		)
		(property "Value" ""
			(at 0 0 0)
			(layer "B.Fab")
			(effects
				(font
					(size 1.27 1.27)
				)
				(justify mirror)
			)
		)
		(duplicate_pad_numbers_are_jumpers no)
		(fp_line
			(start -0.7874 -0.4064)
			(end -0.7874 0.4064)
			(stroke
				(width 0.1524)
				(type default)
			)
			(layer "B.SilkS")
		)
		(fp_line
			(start -0.7874 0.4064)
			(end 0.7874 0.4064)
			(stroke
				(width 0.1524)
				(type default)
			)
			(layer "B.SilkS")
		)
		(fp_line
			(start 0.7874 -0.4064)
			(end -0.7874 -0.4064)
			(stroke
				(width 0.1524)
				(type default)
			)
			(layer "B.SilkS")
		)
		(fp_line
			(start 0.7874 0.4064)
			(end 0.7874 -0.4064)
			(stroke
				(width 0.1524)
				(type default)
			)
			(layer "B.SilkS")
		)
		(fp_line
			(start -0.67945 -0.3048)
			(end -0.67945 0.3048)
			(stroke
				(width 0.1)
				(type default)
			)
			(layer "B.Fab")
		)
		(fp_line
			(start -0.67945 0.3048)
			(end -0.120396 0.3048)
			(stroke
				(width 0.1)
				(type default)
			)
			(layer "B.Fab")
		)
		(fp_line
			(start -0.12065 -0.3048)
			(end -0.67945 -0.3048)
			(stroke
				(width 0.1)
				(type default)
			)
			(layer "B.Fab")
		)
		(fp_line
			(start -0.12065 -0.2794)
			(end -0.12065 -0.3048)
			(stroke
				(width 0.1)
				(type default)
			)
			(layer "B.Fab")
		)
		(fp_line
			(start -0.120396 0.2794)
			(end 0.12065 0.2794)
			(stroke
				(width 0.1)
				(type default)
			)
			(layer "B.Fab")
		)
		(fp_line
			(start -0.120396 0.3048)
			(end -0.120396 0.2794)
			(stroke
				(width 0.1)
				(type default)
			)
			(layer "B.Fab")
		)
		(fp_line
			(start 0.12065 -0.305054)
			(end 0.12065 -0.2794)
			(stroke
				(width 0.1)
				(type default)
			)
			(layer "B.Fab")
		)
		(fp_line
			(start 0.12065 -0.2794)
			(end -0.12065 -0.2794)
			(stroke
				(width 0.1)
				(type default)
			)
			(layer "B.Fab")
		)
		(fp_line
			(start 0.12065 0.2794)
			(end 0.12065 0.3048)
			(stroke
				(width 0.1)
				(type default)
			)
			(layer "B.Fab")
		)
		(fp_line
			(start 0.12065 0.3048)
			(end 0.67945 0.3048)
			(stroke
				(width 0.1)
				(type default)
			)
			(layer "B.Fab")
		)
		(fp_line
			(start 0.67945 -0.305054)
			(end 0.12065 -0.305054)
			(stroke
				(width 0.1)
				(type default)
			)
			(layer "B.Fab")
		)
		(fp_line
			(start 0.67945 0.3048)
			(end 0.67945 -0.305054)
			(stroke
				(width 0.1)
				(type default)
			)
			(layer "B.Fab")
		)
		(pad "1" smd circle
			(at 0.40005 0 180)
			(size 0 0)
			(layers "B.Cu" "B.Mask" "B.Paste")
			(net "P12V_AUX")
		)
		(pad "2" smd circle
			(at -0.40005 0 180)
			(size 0 0)
			(layers "B.Cu" "B.Mask" "B.Paste")
			(net "HSC_VOSEN")
		)
	)
	(footprint ""
		(layer "B.Cu")
		(at 155.792932 -238.728758)
		(property "Reference" "R4089"
			(at 0 0 0)
			(layer "B.SilkS")
			(hide yes)
			(effects
				(font
					(size 1.27 1.27)
				)
				(justify mirror)
			)
		)
		(property "Value" ""
			(at 0 0 0)
			(layer "B.Fab")
			(effects
				(font
					(size 1.27 1.27)
				)
				(justify mirror)
			)
		)
		(duplicate_pad_numbers_are_jumpers no)
		(fp_line
			(start -0.7874 -0.406146)
			(end -0.7874 0.406146)
			(stroke
				(width 0.1524)
				(type default)
			)
			(layer "B.SilkS")
		)
		(fp_line
			(start -0.7874 0.406146)
			(end 0.7874 0.406146)
			(stroke
				(width 0.1524)
				(type default)
			)
			(layer "B.SilkS")
		)
		(fp_line
			(start 0.7874 -0.406146)
			(end -0.7874 -0.406146)
			(stroke
				(width 0.1524)
				(type default)
			)
			(layer "B.SilkS")
		)
		(fp_line
			(start 0.7874 0.406146)
			(end 0.7874 -0.406146)
			(stroke
				(width 0.1524)
				(type default)
			)
			(layer "B.SilkS")
		)
		(fp_line
			(start -0.67945 -0.3048)
			(end -0.67945 0.3048)
			(stroke
				(width 0.1)
				(type default)
			)
			(layer "B.Fab")
		)
		(fp_line
			(start -0.67945 0.3048)
			(end -0.120396 0.3048)
			(stroke
				(width 0.1)
				(type default)
			)
			(layer "B.Fab")
		)
		(fp_line
			(start -0.12065 -0.2794)
			(end -0.120396 -0.3048)
			(stroke
				(width 0.1)
				(type default)
			)
			(layer "B.Fab")
		)
		(fp_line
			(start -0.120396 -0.3048)
			(end -0.67945 -0.3048)
			(stroke
				(width 0.1)
				(type default)
			)
			(layer "B.Fab")
		)
		(fp_line
			(start -0.120396 0.2794)
			(end 0.12065 0.2794)
			(stroke
				(width 0.1)
				(type default)
			)
			(layer "B.Fab")
		)
		(fp_line
			(start -0.120396 0.3048)
			(end -0.120396 0.2794)
			(stroke
				(width 0.1)
				(type default)
			)
			(layer "B.Fab")
		)
		(fp_line
			(start 0.120396 0.3048)
			(end 0.67945 0.3048)
			(stroke
				(width 0.1)
				(type default)
			)
			(layer "B.Fab")
		)
		(fp_line
			(start 0.12065 -0.305054)
			(end 0.12065 -0.2794)
			(stroke
				(width 0.1)
				(type default)
			)
			(layer "B.Fab")
		)
		(fp_line
			(start 0.12065 -0.2794)
			(end -0.12065 -0.2794)
			(stroke
				(width 0.1)
				(type default)
			)
			(layer "B.Fab")
		)
		(fp_line
			(start 0.12065 0.2794)
			(end 0.120396 0.3048)
			(stroke
				(width 0.1)
				(type default)
			)
			(layer "B.Fab")
		)
		(fp_line
			(start 0.67945 -0.305054)
			(end 0.12065 -0.305054)
			(stroke
				(width 0.1)
				(type default)
			)
			(layer "B.Fab")
		)
		(fp_line
			(start 0.67945 0.3048)
			(end 0.67945 -0.305054)
			(stroke
				(width 0.1)
				(type default)
			)
			(layer "B.Fab")
		)
		(pad "1" smd circle
			(at 0.40005 0 180)
			(size 0 0)
			(layers "B.Cu" "B.Mask" "B.Paste")
			(net "H_CPU0_PMSYNC_CPU1_R1")
		)
		(pad "2" smd circle
			(at -0.40005 0 180)
			(size 0 0)
			(layers "B.Cu" "B.Mask" "B.Paste")
			(net "H_CPU0_PMSYNC_CPU1")
		)
	)
	(footprint ""
		(layer "B.Cu")
		(at 60.959746 -321.554856 -90)
		(property "Reference" "C55"
			(at 0 0 90)
			(layer "B.SilkS")
			(hide yes)
			(effects
				(font
					(size 1.27 1.27)
				)
				(justify mirror)
			)
		)
		(property "Value" ""
			(at 0 0 90)
			(layer "B.Fab")
			(effects
				(font
					(size 1.27 1.27)
				)
				(justify mirror)
			)
		)
		(duplicate_pad_numbers_are_jumpers no)
		(fp_line
			(start -1.524 0.762)
			(end 1.524 0.762)
			(stroke
				(width 0.1524)
				(type default)
			)
			(layer "B.SilkS")
		)
		(fp_line
			(start 1.524 0.762)
			(end 1.524 -0.762)
			(stroke
				(width 0.1524)
				(type default)
			)
			(layer "B.SilkS")
		)
		(fp_line
			(start -1.524 -0.762)
			(end -1.524 0.762)
			(stroke
				(width 0.1524)
				(type default)
			)
			(layer "B.SilkS")
		)
		(fp_line
			(start 1.524 -0.762)
			(end -1.524 -0.762)
			(stroke
				(width 0.1524)
				(type default)
			)
			(layer "B.SilkS")
		)
		(fp_line
			(start -1.1049 0.724916)
			(end -1.1049 -0.724916)
			(stroke
				(width 0.1)
				(type default)
			)
			(layer "B.Fab")
		)
		(fp_line
			(start 1.1049 0.724916)
			(end -1.1049 0.724916)
			(stroke
				(width 0.1)
				(type default)
			)
			(layer "B.Fab")
		)
		(fp_line
			(start -1.1049 -0.724916)
			(end 1.1049 -0.724916)
			(stroke
				(width 0.1)
				(type default)
			)
			(layer "B.Fab")
		)
		(fp_line
			(start 1.1049 -0.724916)
			(end 1.1049 0.724916)
			(stroke
				(width 0.1)
				(type default)
			)
			(layer "B.Fab")
		)
		(pad "1" smd rect
			(at 0.889 0 270)
			(size 1.016 1.27)
			(layers "B.Cu" "B.Mask" "B.Paste")
			(net "P12V_S3_AUX_CPU1_NVDIMM")
		)
		(pad "2" smd rect
			(at -0.889 0 270)
			(size 1.016 1.27)
			(layers "B.Cu" "B.Mask" "B.Paste")
			(net "GND")
		)
	)
	(footprint ""
		(layer "B.Cu")
		(at 205.307438 -403.804882 -90)
		(property "Reference" "PR3911"
			(at 0 0 90)
			(layer "B.SilkS")
			(hide yes)
			(effects
				(font
					(size 1.27 1.27)
				)
				(justify mirror)
			)
		)
		(property "Value" ""
			(at 0 0 90)
			(layer "B.Fab")
			(effects
				(font
					(size 1.27 1.27)
				)
				(justify mirror)
			)
		)
		(duplicate_pad_numbers_are_jumpers no)
		(fp_line
			(start -0.7874 0.4064)
			(end 0.7874 0.4064)
			(stroke
				(width 0.1524)
				(type default)
			)
			(layer "B.SilkS")
		)
		(fp_line
			(start 0.7874 0.4064)
			(end 0.7874 -0.4064)
			(stroke
				(width 0.1524)
				(type default)
			)
			(layer "B.SilkS")
		)
		(fp_line
			(start -0.7874 -0.4064)
			(end -0.7874 0.4064)
			(stroke
				(width 0.1524)
				(type default)
			)
			(layer "B.SilkS")
		)
		(fp_line
			(start 0.7874 -0.4064)
			(end -0.7874 -0.4064)
			(stroke
				(width 0.1524)
				(type default)
			)
			(layer "B.SilkS")
		)
		(fp_line
			(start -0.67945 0.3048)
			(end -0.120396 0.3048)
			(stroke
				(width 0.1)
				(type default)
			)
			(layer "B.Fab")
		)
		(fp_line
			(start -0.120396 0.3048)
			(end -0.120396 0.2794)
			(stroke
				(width 0.1)
				(type default)
			)
			(layer "B.Fab")
		)
		(fp_line
			(start 0.12065 0.3048)
			(end 0.67945 0.3048)
			(stroke
				(width 0.1)
				(type default)
			)
			(layer "B.Fab")
		)
		(fp_line
			(start 0.67945 0.3048)
			(end 0.67945 -0.305054)
			(stroke
				(width 0.1)
				(type default)
			)
			(layer "B.Fab")
		)
		(fp_line
			(start -0.120396 0.2794)
			(end 0.12065 0.2794)
			(stroke
				(width 0.1)
				(type default)
			)
			(layer "B.Fab")
		)
		(fp_line
			(start 0.12065 0.2794)
			(end 0.12065 0.3048)
			(stroke
				(width 0.1)
				(type default)
			)
			(layer "B.Fab")
		)
		(fp_line
			(start -0.12065 -0.2794)
			(end -0.12065 -0.3048)
			(stroke
				(width 0.1)
				(type default)
			)
			(layer "B.Fab")
		)
		(fp_line
			(start 0.12065 -0.2794)
			(end -0.12065 -0.2794)
			(stroke
				(width 0.1)
				(type default)
			)
			(layer "B.Fab")
		)
		(fp_line
			(start -0.67945 -0.3048)
			(end -0.67945 0.3048)
			(stroke
				(width 0.1)
				(type default)
			)
			(layer "B.Fab")
		)
		(fp_line
			(start -0.12065 -0.3048)
			(end -0.67945 -0.3048)
			(stroke
				(width 0.1)
				(type default)
			)
			(layer "B.Fab")
		)
		(fp_line
			(start 0.12065 -0.305054)
			(end 0.12065 -0.2794)
			(stroke
				(width 0.1)
				(type default)
			)
			(layer "B.Fab")
		)
		(fp_line
			(start 0.67945 -0.305054)
			(end 0.12065 -0.305054)
			(stroke
				(width 0.1)
				(type default)
			)
			(layer "B.Fab")
		)
		(pad "1" smd circle
			(at 0.40005 0 90)
			(size 0 0)
			(layers "B.Cu" "B.Mask" "B.Paste")
			(net "HSC_VDD_R_2")
		)
		(pad "2" smd circle
			(at -0.40005 0 90)
			(size 0 0)
			(layers "B.Cu" "B.Mask" "B.Paste")
			(net "HSC_VDD")
		)
	)
	(footprint ""
		(layer "B.Cu")
		(at 178.50866 -13.759688 90)
		(property "Reference" "R1386"
			(at 0 0 90)
			(layer "B.SilkS")
			(hide yes)
			(effects
				(font
					(size 1.27 1.27)
				)
				(justify mirror)
			)
		)
		(property "Value" ""
			(at 0 0 90)
			(layer "B.Fab")
			(effects
				(font
					(size 1.27 1.27)
				)
				(justify mirror)
			)
		)
		(duplicate_pad_numbers_are_jumpers no)
		(fp_line
			(start 0.7874 -0.4064)
			(end -0.7874 -0.4064)
			(stroke
				(width 0.1524)
				(type default)
			)
			(layer "B.SilkS")
		)
		(fp_line
			(start -0.7874 -0.4064)
			(end -0.7874 0.4064)
			(stroke
				(width 0.1524)
				(type default)
			)
			(layer "B.SilkS")
		)
		(fp_line
			(start 0.7874 0.4064)
			(end 0.7874 -0.4064)
			(stroke
				(width 0.1524)
				(type default)
			)
			(layer "B.SilkS")
		)
		(fp_line
			(start -0.7874 0.4064)
			(end 0.7874 0.4064)
			(stroke
				(width 0.1524)
				(type default)
			)
			(layer "B.SilkS")
		)
		(fp_line
			(start 0.67945 -0.305054)
			(end 0.12065 -0.305054)
			(stroke
				(width 0.1)
				(type default)
			)
			(layer "B.Fab")
		)
		(fp_line
			(start 0.12065 -0.305054)
			(end 0.12065 -0.2794)
			(stroke
				(width 0.1)
				(type default)
			)
			(layer "B.Fab")
		)
		(fp_line
			(start -0.12065 -0.3048)
			(end -0.67945 -0.3048)
			(stroke
				(width 0.1)
				(type default)
			)
			(layer "B.Fab")
		)
		(fp_line
			(start -0.67945 -0.3048)
			(end -0.67945 0.3048)
			(stroke
				(width 0.1)
				(type default)
			)
			(layer "B.Fab")
		)
		(fp_line
			(start 0.12065 -0.2794)
			(end -0.12065 -0.2794)
			(stroke
				(width 0.1)
				(type default)
			)
			(layer "B.Fab")
		)
		(fp_line
			(start -0.12065 -0.2794)
			(end -0.12065 -0.3048)
			(stroke
				(width 0.1)
				(type default)
			)
			(layer "B.Fab")
		)
		(fp_line
			(start 0.12065 0.2794)
			(end 0.12065 0.3048)
			(stroke
				(width 0.1)
				(type default)
			)
			(layer "B.Fab")
		)
		(fp_line
			(start -0.120396 0.2794)
			(end 0.12065 0.2794)
			(stroke
				(width 0.1)
				(type default)
			)
			(layer "B.Fab")
		)
		(fp_line
			(start 0.67945 0.3048)
			(end 0.67945 -0.305054)
			(stroke
				(width 0.1)
				(type default)
			)
			(layer "B.Fab")
		)
		(fp_line
			(start 0.12065 0.3048)
			(end 0.67945 0.3048)
			(stroke
				(width 0.1)
				(type default)
			)
			(layer "B.Fab")
		)
		(fp_line
			(start -0.120396 0.3048)
			(end -0.120396 0.2794)
			(stroke
				(width 0.1)
				(type default)
			)
			(layer "B.Fab")
		)
		(fp_line
			(start -0.67945 0.3048)
			(end -0.120396 0.3048)
			(stroke
				(width 0.1)
				(type default)
			)
			(layer "B.Fab")
		)
		(pad "1" smd circle
			(at 0.40005 0 270)
			(size 0 0)
			(layers "B.Cu" "B.Mask" "B.Paste")
			(net "SMB_SML1_PMBUS_3V3AUX_PCH_SCL")
		)
		(pad "2" smd circle
			(at -0.40005 0 270)
			(size 0 0)
			(layers "B.Cu" "B.Mask" "B.Paste")
			(net "P3V3_AUX")
		)
	)
	(footprint ""
		(layer "B.Cu")
		(at 312.443622 -35.804348)
		(property "Reference" "R1657"
			(at 0 0 0)
			(layer "B.SilkS")
			(hide yes)
			(effects
				(font
					(size 1.27 1.27)
				)
				(justify mirror)
			)
		)
		(property "Value" ""
			(at 0 0 0)
			(layer "B.Fab")
			(effects
				(font
					(size 1.27 1.27)
				)
				(justify mirror)
			)
		)
		(duplicate_pad_numbers_are_jumpers no)
		(fp_line
			(start -0.7874 -0.4064)
			(end -0.7874 0.4064)
			(stroke
				(width 0.1524)
				(type default)
			)
			(layer "B.SilkS")
		)
		(fp_line
			(start -0.7874 0.4064)
			(end 0.7874 0.4064)
			(stroke
				(width 0.1524)
				(type default)
			)
			(layer "B.SilkS")
		)
		(fp_line
			(start 0.7874 -0.4064)
			(end -0.7874 -0.4064)
			(stroke
				(width 0.1524)
				(type default)
			)
			(layer "B.SilkS")
		)
		(fp_line
			(start 0.7874 0.4064)
			(end 0.7874 -0.4064)
			(stroke
				(width 0.1524)
				(type default)
			)
			(layer "B.SilkS")
		)
		(fp_line
			(start -0.67945 -0.3048)
			(end -0.67945 0.3048)
			(stroke
				(width 0.1)
				(type default)
			)
			(layer "B.Fab")
		)
		(fp_line
			(start -0.67945 0.3048)
			(end -0.120396 0.3048)
			(stroke
				(width 0.1)
				(type default)
			)
			(layer "B.Fab")
		)
		(fp_line
			(start -0.12065 -0.3048)
			(end -0.67945 -0.3048)
			(stroke
				(width 0.1)
				(type default)
			)
			(layer "B.Fab")
		)
		(fp_line
			(start -0.12065 -0.2794)
			(end -0.12065 -0.3048)
			(stroke
				(width 0.1)
				(type default)
			)
			(layer "B.Fab")
		)
		(fp_line
			(start -0.120396 0.2794)
			(end 0.12065 0.2794)
			(stroke
				(width 0.1)
				(type default)
			)
			(layer "B.Fab")
		)
		(fp_line
			(start -0.120396 0.3048)
			(end -0.120396 0.2794)
			(stroke
				(width 0.1)
				(type default)
			)
			(layer "B.Fab")
		)
		(fp_line
			(start 0.12065 -0.305054)
			(end 0.12065 -0.2794)
			(stroke
				(width 0.1)
				(type default)
			)
			(layer "B.Fab")
		)
		(fp_line
			(start 0.12065 -0.2794)
			(end -0.12065 -0.2794)
			(stroke
				(width 0.1)
				(type default)
			)
			(layer "B.Fab")
		)
		(fp_line
			(start 0.12065 0.2794)
			(end 0.12065 0.3048)
			(stroke
				(width 0.1)
				(type default)
			)
			(layer "B.Fab")
		)
		(fp_line
			(start 0.12065 0.3048)
			(end 0.67945 0.3048)
			(stroke
				(width 0.1)
				(type default)
			)
			(layer "B.Fab")
		)
		(fp_line
			(start 0.67945 -0.305054)
			(end 0.12065 -0.305054)
			(stroke
				(width 0.1)
				(type default)
			)
			(layer "B.Fab")
		)
		(fp_line
			(start 0.67945 0.3048)
			(end 0.67945 -0.305054)
			(stroke
				(width 0.1)
				(type default)
			)
			(layer "B.Fab")
		)
		(pad "1" smd circle
			(at 0.40005 0 180)
			(size 0 0)
			(layers "B.Cu" "B.Mask" "B.Paste")
			(net "IRQ_SML1_PMBUS_ALERT_N")
		)
		(pad "2" smd circle
			(at -0.40005 0 180)
			(size 0 0)
			(layers "B.Cu" "B.Mask" "B.Paste")
			(net "IRQ_SML1_PMBUS_BMC_ALERT_N")
		)
	)
	(footprint ""
		(layer "B.Cu")
		(at 26.7716 -162.829748 -90)
		(property "Reference" "PR4254"
			(at 0 0 90)
			(layer "B.SilkS")
			(hide yes)
			(effects
				(font
					(size 1.27 1.27)
				)
				(justify mirror)
			)
		)
		(property "Value" ""
			(at 0 0 90)
			(layer "B.Fab")
			(effects
				(font
					(size 1.27 1.27)
				)
				(justify mirror)
			)
		)
		(duplicate_pad_numbers_are_jumpers no)
		(fp_line
			(start -0.7874 0.4064)
			(end 0.7874 0.4064)
			(stroke
				(width 0.1524)
				(type default)
			)
			(layer "B.SilkS")
		)
		(fp_line
			(start 0.7874 0.4064)
			(end 0.7874 -0.4064)
			(stroke
				(width 0.1524)
				(type default)
			)
			(layer "B.SilkS")
		)
		(fp_line
			(start -0.7874 -0.4064)
			(end -0.7874 0.4064)
			(stroke
				(width 0.1524)
				(type default)
			)
			(layer "B.SilkS")
		)
		(fp_line
			(start 0.7874 -0.4064)
			(end -0.7874 -0.4064)
			(stroke
				(width 0.1524)
				(type default)
			)
			(layer "B.SilkS")
		)
		(fp_line
			(start -0.67945 0.3048)
			(end -0.120396 0.3048)
			(stroke
				(width 0.1)
				(type default)
			)
			(layer "B.Fab")
		)
		(fp_line
			(start -0.120396 0.3048)
			(end -0.120396 0.2794)
			(stroke
				(width 0.1)
				(type default)
			)
			(layer "B.Fab")
		)
		(fp_line
			(start 0.12065 0.3048)
			(end 0.67945 0.3048)
			(stroke
				(width 0.1)
				(type default)
			)
			(layer "B.Fab")
		)
		(fp_line
			(start 0.67945 0.3048)
			(end 0.67945 -0.305054)
			(stroke
				(width 0.1)
				(type default)
			)
			(layer "B.Fab")
		)
		(fp_line
			(start -0.120396 0.2794)
			(end 0.12065 0.2794)
			(stroke
				(width 0.1)
				(type default)
			)
			(layer "B.Fab")
		)
		(fp_line
			(start 0.12065 0.2794)
			(end 0.12065 0.3048)
			(stroke
				(width 0.1)
				(type default)
			)
			(layer "B.Fab")
		)
		(fp_line
			(start -0.12065 -0.2794)
			(end -0.12065 -0.3048)
			(stroke
				(width 0.1)
				(type default)
			)
			(layer "B.Fab")
		)
		(fp_line
			(start 0.12065 -0.2794)
			(end -0.12065 -0.2794)
			(stroke
				(width 0.1)
				(type default)
			)
			(layer "B.Fab")
		)
		(fp_line
			(start -0.67945 -0.3048)
			(end -0.67945 0.3048)
			(stroke
				(width 0.1)
				(type default)
			)
			(layer "B.Fab")
		)
		(fp_line
			(start -0.12065 -0.3048)
			(end -0.67945 -0.3048)
			(stroke
				(width 0.1)
				(type default)
			)
			(layer "B.Fab")
		)
		(fp_line
			(start 0.12065 -0.305054)
			(end 0.12065 -0.2794)
			(stroke
				(width 0.1)
				(type default)
			)
			(layer "B.Fab")
		)
		(fp_line
			(start 0.67945 -0.305054)
			(end 0.12065 -0.305054)
			(stroke
				(width 0.1)
				(type default)
			)
			(layer "B.Fab")
		)
		(pad "1" smd circle
			(at 0.40005 0 90)
			(size 0 0)
			(layers "B.Cu" "B.Mask" "B.Paste")
			(net "NC_PVCCD_HV_CPU1_ACSP5")
		)
		(pad "2" smd circle
			(at -0.40005 0 90)
			(size 0 0)
			(layers "B.Cu" "B.Mask" "B.Paste")
			(net "GND")
		)
	)
	(footprint ""
		(layer "B.Cu")
		(at 77.142594 -46.044866)
		(property "Reference" "R3570"
			(at 0 0 0)
			(layer "B.SilkS")
			(hide yes)
			(effects
				(font
					(size 1.27 1.27)
				)
				(justify mirror)
			)
		)
		(property "Value" ""
			(at 0 0 0)
			(layer "B.Fab")
			(effects
				(font
					(size 1.27 1.27)
				)
				(justify mirror)
			)
		)
		(duplicate_pad_numbers_are_jumpers no)
		(fp_line
			(start -0.7874 -0.4064)
			(end -0.7874 0.4064)
			(stroke
				(width 0.1524)
				(type default)
			)
			(layer "B.SilkS")
		)
		(fp_line
			(start -0.7874 0.4064)
			(end 0.7874 0.4064)
			(stroke
				(width 0.1524)
				(type default)
			)
			(layer "B.SilkS")
		)
		(fp_line
			(start 0.7874 -0.4064)
			(end -0.7874 -0.4064)
			(stroke
				(width 0.1524)
				(type default)
			)
			(layer "B.SilkS")
		)
		(fp_line
			(start 0.7874 0.4064)
			(end 0.7874 -0.4064)
			(stroke
				(width 0.1524)
				(type default)
			)
			(layer "B.SilkS")
		)
		(fp_line
			(start -0.67945 -0.3048)
			(end -0.67945 0.3048)
			(stroke
				(width 0.1)
				(type default)
			)
			(layer "B.Fab")
		)
		(fp_line
			(start -0.67945 0.3048)
			(end -0.120396 0.3048)
			(stroke
				(width 0.1)
				(type default)
			)
			(layer "B.Fab")
		)
		(fp_line
			(start -0.12065 -0.3048)
			(end -0.67945 -0.3048)
			(stroke
				(width 0.1)
				(type default)
			)
			(layer "B.Fab")
		)
		(fp_line
			(start -0.12065 -0.2794)
			(end -0.12065 -0.3048)
			(stroke
				(width 0.1)
				(type default)
			)
			(layer "B.Fab")
		)
		(fp_line
			(start -0.120396 0.2794)
			(end 0.12065 0.2794)
			(stroke
				(width 0.1)
				(type default)
			)
			(layer "B.Fab")
		)
		(fp_line
			(start -0.120396 0.3048)
			(end -0.120396 0.2794)
			(stroke
				(width 0.1)
				(type default)
			)
			(layer "B.Fab")
		)
		(fp_line
			(start 0.12065 -0.305054)
			(end 0.12065 -0.2794)
			(stroke
				(width 0.1)
				(type default)
			)
			(layer "B.Fab")
		)
		(fp_line
			(start 0.12065 -0.2794)
			(end -0.12065 -0.2794)
			(stroke
				(width 0.1)
				(type default)
			)
			(layer "B.Fab")
		)
		(fp_line
			(start 0.12065 0.2794)
			(end 0.12065 0.3048)
			(stroke
				(width 0.1)
				(type default)
			)
			(layer "B.Fab")
		)
		(fp_line
			(start 0.12065 0.3048)
			(end 0.67945 0.3048)
			(stroke
				(width 0.1)
				(type default)
			)
			(layer "B.Fab")
		)
		(fp_line
			(start 0.67945 -0.305054)
			(end 0.12065 -0.305054)
			(stroke
				(width 0.1)
				(type default)
			)
			(layer "B.Fab")
		)
		(fp_line
			(start 0.67945 0.3048)
			(end 0.67945 -0.305054)
			(stroke
				(width 0.1)
				(type default)
			)
			(layer "B.Fab")
		)
		(pad "1" smd circle
			(at 0.40005 0 180)
			(size 0 0)
			(layers "B.Cu" "B.Mask" "B.Paste")
			(net "P3V3_OCP_V3_2_R")
		)
		(pad "2" smd circle
			(at -0.40005 0 180)
			(size 0 0)
			(layers "B.Cu" "B.Mask" "B.Paste")
			(net "VSENSE_P12V_INA230_3_INP")
		)
	)
	(footprint ""
		(layer "B.Cu")
		(at 359.56113 -360.847386)
		(property "Reference" "PR166"
			(at 0 0 0)
			(layer "B.SilkS")
			(hide yes)
			(effects
				(font
					(size 1.27 1.27)
				)
				(justify mirror)
			)
		)
		(property "Value" ""
			(at 0 0 0)
			(layer "B.Fab")
			(effects
				(font
					(size 1.27 1.27)
				)
				(justify mirror)
			)
		)
		(duplicate_pad_numbers_are_jumpers no)
		(fp_line
			(start -0.7874 -0.4064)
			(end -0.7874 0.4064)
			(stroke
				(width 0.1524)
				(type default)
			)
			(layer "B.SilkS")
		)
		(fp_line
			(start -0.7874 0.4064)
			(end 0.7874 0.4064)
			(stroke
				(width 0.1524)
				(type default)
			)
			(layer "B.SilkS")
		)
		(fp_line
			(start 0.7874 -0.4064)
			(end -0.7874 -0.4064)
			(stroke
				(width 0.1524)
				(type default)
			)
			(layer "B.SilkS")
		)
		(fp_line
			(start 0.7874 0.4064)
			(end 0.7874 -0.4064)
			(stroke
				(width 0.1524)
				(type default)
			)
			(layer "B.SilkS")
		)
		(fp_line
			(start -0.67945 -0.3048)
			(end -0.67945 0.3048)
			(stroke
				(width 0.1)
				(type default)
			)
			(layer "B.Fab")
		)
		(fp_line
			(start -0.67945 0.3048)
			(end -0.120396 0.3048)
			(stroke
				(width 0.1)
				(type default)
			)
			(layer "B.Fab")
		)
		(fp_line
			(start -0.12065 -0.3048)
			(end -0.67945 -0.3048)
			(stroke
				(width 0.1)
				(type default)
			)
			(layer "B.Fab")
		)
		(fp_line
			(start -0.12065 -0.2794)
			(end -0.12065 -0.3048)
			(stroke
				(width 0.1)
				(type default)
			)
			(layer "B.Fab")
		)
		(fp_line
			(start -0.120396 0.2794)
			(end 0.12065 0.2794)
			(stroke
				(width 0.1)
				(type default)
			)
			(layer "B.Fab")
		)
		(fp_line
			(start -0.120396 0.3048)
			(end -0.120396 0.2794)
			(stroke
				(width 0.1)
				(type default)
			)
			(layer "B.Fab")
		)
		(fp_line
			(start 0.12065 -0.305054)
			(end 0.12065 -0.2794)
			(stroke
				(width 0.1)
				(type default)
			)
			(layer "B.Fab")
		)
		(fp_line
			(start 0.12065 -0.2794)
			(end -0.12065 -0.2794)
			(stroke
				(width 0.1)
				(type default)
			)
			(layer "B.Fab")
		)
		(fp_line
			(start 0.12065 0.2794)
			(end 0.12065 0.3048)
			(stroke
				(width 0.1)
				(type default)
			)
			(layer "B.Fab")
		)
		(fp_line
			(start 0.12065 0.3048)
			(end 0.67945 0.3048)
			(stroke
				(width 0.1)
				(type default)
			)
			(layer "B.Fab")
		)
		(fp_line
			(start 0.67945 -0.305054)
			(end 0.12065 -0.305054)
			(stroke
				(width 0.1)
				(type default)
			)
			(layer "B.Fab")
		)
		(fp_line
			(start 0.67945 0.3048)
			(end 0.67945 -0.305054)
			(stroke
				(width 0.1)
				(type default)
			)
			(layer "B.Fab")
		)
		(pad "1" smd circle
			(at 0.40005 0 180)
			(size 0 0)
			(layers "B.Cu" "B.Mask" "B.Paste")
			(net "PVCCIN_CPU0_VIN_CSNIN")
		)
		(pad "2" smd circle
			(at -0.40005 0 180)
			(size 0 0)
			(layers "B.Cu" "B.Mask" "B.Paste")
			(net "GND")
		)
	)
	(footprint ""
		(layer "B.Cu")
		(at 416.02914 -167.56507)
		(property "Reference" "PC195_P0_1"
			(at 0 0 0)
			(layer "B.SilkS")
			(hide yes)
			(effects
				(font
					(size 1.27 1.27)
				)
				(justify mirror)
			)
		)
		(property "Value" ""
			(at 0 0 0)
			(layer "B.Fab")
			(effects
				(font
					(size 1.27 1.27)
				)
				(justify mirror)
			)
		)
		(duplicate_pad_numbers_are_jumpers no)
		(fp_line
			(start -1.524 -0.762)
			(end -1.524 0.762)
			(stroke
				(width 0.1524)
				(type default)
			)
			(layer "B.SilkS")
		)
		(fp_line
			(start -1.524 0.762)
			(end 1.524 0.762)
			(stroke
				(width 0.1524)
				(type default)
			)
			(layer "B.SilkS")
		)
		(fp_line
			(start 1.524 -0.762)
			(end -1.524 -0.762)
			(stroke
				(width 0.1524)
				(type default)
			)
			(layer "B.SilkS")
		)
		(fp_line
			(start 1.524 0.762)
			(end 1.524 -0.762)
			(stroke
				(width 0.1524)
				(type default)
			)
			(layer "B.SilkS")
		)
		(fp_line
			(start -1.1049 -0.724916)
			(end 1.1049 -0.724916)
			(stroke
				(width 0.1)
				(type default)
			)
			(layer "B.Fab")
		)
		(fp_line
			(start -1.1049 0.724916)
			(end -1.1049 -0.724916)
			(stroke
				(width 0.1)
				(type default)
			)
			(layer "B.Fab")
		)
		(fp_line
			(start 1.1049 -0.724916)
			(end 1.1049 0.724916)
			(stroke
				(width 0.1)
				(type default)
			)
			(layer "B.Fab")
		)
		(fp_line
			(start 1.1049 0.724916)
			(end -1.1049 0.724916)
			(stroke
				(width 0.1)
				(type default)
			)
			(layer "B.Fab")
		)
		(pad "1" smd rect
			(at 0.889 0)
			(size 1.016 1.27)
			(layers "B.Cu" "B.Mask" "B.Paste")
			(net "SW_P12V_PVCCINFAON_CPU0_FLT")
		)
		(pad "2" smd rect
			(at -0.889 0)
			(size 1.016 1.27)
			(layers "B.Cu" "B.Mask" "B.Paste")
			(net "GND")
		)
	)
	(footprint ""
		(layer "B.Cu")
		(at 127.257302 -338.098892 -90)
		(property "Reference" "PR294"
			(at 0 0 90)
			(layer "B.SilkS")
			(hide yes)
			(effects
				(font
					(size 1.27 1.27)
				)
				(justify mirror)
			)
		)
		(property "Value" ""
			(at 0 0 90)
			(layer "B.Fab")
			(effects
				(font
					(size 1.27 1.27)
				)
				(justify mirror)
			)
		)
		(duplicate_pad_numbers_are_jumpers no)
		(fp_line
			(start -0.7874 0.4064)
			(end 0.7874 0.4064)
			(stroke
				(width 0.1524)
				(type default)
			)
			(layer "B.SilkS")
		)
		(fp_line
			(start 0.7874 0.4064)
			(end 0.7874 -0.4064)
			(stroke
				(width 0.1524)
				(type default)
			)
			(layer "B.SilkS")
		)
		(fp_line
			(start -0.7874 -0.4064)
			(end -0.7874 0.4064)
			(stroke
				(width 0.1524)
				(type default)
			)
			(layer "B.SilkS")
		)
		(fp_line
			(start 0.7874 -0.4064)
			(end -0.7874 -0.4064)
			(stroke
				(width 0.1524)
				(type default)
			)
			(layer "B.SilkS")
		)
		(fp_line
			(start -0.67945 0.3048)
			(end -0.120396 0.3048)
			(stroke
				(width 0.1)
				(type default)
			)
			(layer "B.Fab")
		)
		(fp_line
			(start -0.120396 0.3048)
			(end -0.120396 0.2794)
			(stroke
				(width 0.1)
				(type default)
			)
			(layer "B.Fab")
		)
		(fp_line
			(start 0.12065 0.3048)
			(end 0.67945 0.3048)
			(stroke
				(width 0.1)
				(type default)
			)
			(layer "B.Fab")
		)
		(fp_line
			(start 0.67945 0.3048)
			(end 0.67945 -0.305054)
			(stroke
				(width 0.1)
				(type default)
			)
			(layer "B.Fab")
		)
		(fp_line
			(start -0.120396 0.2794)
			(end 0.12065 0.2794)
			(stroke
				(width 0.1)
				(type default)
			)
			(layer "B.Fab")
		)
		(fp_line
			(start 0.12065 0.2794)
			(end 0.12065 0.3048)
			(stroke
				(width 0.1)
				(type default)
			)
			(layer "B.Fab")
		)
		(fp_line
			(start -0.12065 -0.2794)
			(end -0.12065 -0.3048)
			(stroke
				(width 0.1)
				(type default)
			)
			(layer "B.Fab")
		)
		(fp_line
			(start 0.12065 -0.2794)
			(end -0.12065 -0.2794)
			(stroke
				(width 0.1)
				(type default)
			)
			(layer "B.Fab")
		)
		(fp_line
			(start -0.67945 -0.3048)
			(end -0.67945 0.3048)
			(stroke
				(width 0.1)
				(type default)
			)
			(layer "B.Fab")
		)
		(fp_line
			(start -0.12065 -0.3048)
			(end -0.67945 -0.3048)
			(stroke
				(width 0.1)
				(type default)
			)
			(layer "B.Fab")
		)
		(fp_line
			(start 0.12065 -0.305054)
			(end 0.12065 -0.2794)
			(stroke
				(width 0.1)
				(type default)
			)
			(layer "B.Fab")
		)
		(fp_line
			(start 0.67945 -0.305054)
			(end 0.12065 -0.305054)
			(stroke
				(width 0.1)
				(type default)
			)
			(layer "B.Fab")
		)
		(pad "1" smd circle
			(at 0.40005 0 90)
			(size 0 0)
			(layers "B.Cu" "B.Mask" "B.Paste")
			(net "PVCCIN_CPU1_PVCC")
		)
		(pad "2" smd circle
			(at -0.40005 0 90)
			(size 0 0)
			(layers "B.Cu" "B.Mask" "B.Paste")
			(net "PVCCIN_CPU1_VDD5")
		)
	)
	(footprint ""
		(layer "B.Cu")
		(at 104.49052 -326.994012 -90)
		(property "Reference" "PC590"
			(at 0 0 90)
			(layer "B.SilkS")
			(hide yes)
			(effects
				(font
					(size 1.27 1.27)
				)
				(justify mirror)
			)
		)
		(property "Value" ""
			(at 0 0 90)
			(layer "B.Fab")
			(effects
				(font
					(size 1.27 1.27)
				)
				(justify mirror)
			)
		)
		(duplicate_pad_numbers_are_jumpers no)
		(fp_line
			(start -4.533392 2.249932)
			(end 4.533392 2.249932)
			(stroke
				(width 0.1524)
				(type default)
			)
			(layer "B.SilkS")
		)
		(fp_line
			(start 4.533392 2.249932)
			(end 4.533392 -2.249932)
			(stroke
				(width 0.1524)
				(type default)
			)
			(layer "B.SilkS")
		)
		(fp_line
			(start -4.533392 -2.249932)
			(end -4.533392 2.249932)
			(stroke
				(width 0.1524)
				(type default)
			)
			(layer "B.SilkS")
		)
		(fp_line
			(start 4.533392 -2.249932)
			(end -4.533392 -2.249932)
			(stroke
				(width 0.1524)
				(type default)
			)
			(layer "B.SilkS")
		)
		(fp_rect
			(start 5.39242 2.326132)
			(end 4.533392 -2.326132)
			(stroke
				(width 0)
				(type default)
			)
			(fill yes)
			(layer "B.SilkS")
		)
		(fp_line
			(start -3.750056 2.249932)
			(end 3.750056 2.249932)
			(stroke
				(width 0.1)
				(type default)
			)
			(layer "B.Fab")
		)
		(fp_line
			(start 3.750056 2.249932)
			(end 3.750056 -2.249932)
			(stroke
				(width 0.1)
				(type default)
			)
			(layer "B.Fab")
		)
		(fp_line
			(start -3.750056 -2.249932)
			(end -3.750056 2.249932)
			(stroke
				(width 0.1)
				(type default)
			)
			(layer "B.Fab")
		)
		(fp_line
			(start 3.750056 -2.249932)
			(end -3.750056 -2.249932)
			(stroke
				(width 0.1)
				(type default)
			)
			(layer "B.Fab")
		)
		(fp_text user "+"
			(at 6.322314 0.786384 180)
			(unlocked yes)
			(layer "B.SilkS")
			(effects
				(font
					(size 1.905 1.4224)
					(thickness 0.1524)
				)
				(justify left mirror)
			)
		)
		(fp_text user "-"
			(at -4.575556 0.51435 270)
			(unlocked yes)
			(layer "B.SilkS")
			(effects
				(font
					(size 1.905 1.4224)
					(thickness 0.1524)
				)
				(justify left mirror)
			)
		)
		(fp_text user "+"
			(at 6.322314 0.786384 180)
			(unlocked yes)
			(layer "B.Fab")
			(effects
				(font
					(size 1.905 1.4224)
					(thickness 0.1524)
				)
				(justify left mirror)
			)
		)
		(fp_text user "-"
			(at -4.8514 -0.14605 270)
			(unlocked yes)
			(layer "B.Fab")
			(effects
				(font
					(size 1.905 1.4224)
					(thickness 0.1524)
				)
				(justify left mirror)
			)
		)
		(pad "1" smd rect
			(at 3.199892 0 90)
			(size 2.413 2.8194)
			(layers "B.Cu" "B.Mask" "B.Paste")
			(net "PVCCIN_CPU1")
		)
		(pad "2" smd rect
			(at -3.199892 0 90)
			(size 2.413 2.8194)
			(layers "B.Cu" "B.Mask" "B.Paste")
			(net "GND")
		)
	)
	(footprint ""
		(layer "B.Cu")
		(at 30.784546 -321.554856 -90)
		(property "Reference" "C67"
			(at 0 0 90)
			(layer "B.SilkS")
			(hide yes)
			(effects
				(font
					(size 1.27 1.27)
				)
				(justify mirror)
			)
		)
		(property "Value" ""
			(at 0 0 90)
			(layer "B.Fab")
			(effects
				(font
					(size 1.27 1.27)
				)
				(justify mirror)
			)
		)
		(duplicate_pad_numbers_are_jumpers no)
		(fp_line
			(start -1.524 0.762)
			(end 1.524 0.762)
			(stroke
				(width 0.1524)
				(type default)
			)
			(layer "B.SilkS")
		)
		(fp_line
			(start 1.524 0.762)
			(end 1.524 -0.762)
			(stroke
				(width 0.1524)
				(type default)
			)
			(layer "B.SilkS")
		)
		(fp_line
			(start -1.524 -0.762)
			(end -1.524 0.762)
			(stroke
				(width 0.1524)
				(type default)
			)
			(layer "B.SilkS")
		)
		(fp_line
			(start 1.524 -0.762)
			(end -1.524 -0.762)
			(stroke
				(width 0.1524)
				(type default)
			)
			(layer "B.SilkS")
		)
		(fp_line
			(start -1.1049 0.724916)
			(end -1.1049 -0.724916)
			(stroke
				(width 0.1)
				(type default)
			)
			(layer "B.Fab")
		)
		(fp_line
			(start 1.1049 0.724916)
			(end -1.1049 0.724916)
			(stroke
				(width 0.1)
				(type default)
			)
			(layer "B.Fab")
		)
		(fp_line
			(start -1.1049 -0.724916)
			(end 1.1049 -0.724916)
			(stroke
				(width 0.1)
				(type default)
			)
			(layer "B.Fab")
		)
		(fp_line
			(start 1.1049 -0.724916)
			(end 1.1049 0.724916)
			(stroke
				(width 0.1)
				(type default)
			)
			(layer "B.Fab")
		)
		(pad "1" smd rect
			(at 0.889 0 270)
			(size 1.016 1.27)
			(layers "B.Cu" "B.Mask" "B.Paste")
			(net "P12V_S3_AUX_CPU1_NVDIMM")
		)
		(pad "2" smd rect
			(at -0.889 0 270)
			(size 1.016 1.27)
			(layers "B.Cu" "B.Mask" "B.Paste")
			(net "GND")
		)
	)
	(footprint ""
		(layer "B.Cu")
		(at 114.427 -86.705948 180)
		(property "Reference" "R4022"
			(at 0 0 0)
			(layer "B.SilkS")
			(hide yes)
			(effects
				(font
					(size 1.27 1.27)
				)
				(justify mirror)
			)
		)
		(property "Value" ""
			(at 0 0 0)
			(layer "B.Fab")
			(effects
				(font
					(size 1.27 1.27)
				)
				(justify mirror)
			)
		)
		(duplicate_pad_numbers_are_jumpers no)
		(fp_line
			(start 0.7874 0.4064)
			(end 0.7874 -0.4064)
			(stroke
				(width 0.1524)
				(type default)
			)
			(layer "B.SilkS")
		)
		(fp_line
			(start 0.7874 -0.4064)
			(end -0.7874 -0.4064)
			(stroke
				(width 0.1524)
				(type default)
			)
			(layer "B.SilkS")
		)
		(fp_line
			(start -0.7874 0.4064)
			(end 0.7874 0.4064)
			(stroke
				(width 0.1524)
				(type default)
			)
			(layer "B.SilkS")
		)
		(fp_line
			(start -0.7874 -0.4064)
			(end -0.7874 0.4064)
			(stroke
				(width 0.1524)
				(type default)
			)
			(layer "B.SilkS")
		)
		(fp_line
			(start 0.67945 0.3048)
			(end 0.67945 -0.305054)
			(stroke
				(width 0.1)
				(type default)
			)
			(layer "B.Fab")
		)
		(fp_line
			(start 0.67945 -0.305054)
			(end 0.12065 -0.305054)
			(stroke
				(width 0.1)
				(type default)
			)
			(layer "B.Fab")
		)
		(fp_line
			(start 0.12065 0.3048)
			(end 0.67945 0.3048)
			(stroke
				(width 0.1)
				(type default)
			)
			(layer "B.Fab")
		)
		(fp_line
			(start 0.12065 0.2794)
			(end 0.12065 0.3048)
			(stroke
				(width 0.1)
				(type default)
			)
			(layer "B.Fab")
		)
		(fp_line
			(start 0.12065 -0.2794)
			(end -0.12065 -0.2794)
			(stroke
				(width 0.1)
				(type default)
			)
			(layer "B.Fab")
		)
		(fp_line
			(start 0.12065 -0.305054)
			(end 0.12065 -0.2794)
			(stroke
				(width 0.1)
				(type default)
			)
			(layer "B.Fab")
		)
		(fp_line
			(start -0.120396 0.3048)
			(end -0.120396 0.2794)
			(stroke
				(width 0.1)
				(type default)
			)
			(layer "B.Fab")
		)
		(fp_line
			(start -0.120396 0.2794)
			(end 0.12065 0.2794)
			(stroke
				(width 0.1)
				(type default)
			)
			(layer "B.Fab")
		)
		(fp_line
			(start -0.12065 -0.2794)
			(end -0.12065 -0.3048)
			(stroke
				(width 0.1)
				(type default)
			)
			(layer "B.Fab")
		)
		(fp_line
			(start -0.12065 -0.3048)
			(end -0.67945 -0.3048)
			(stroke
				(width 0.1)
				(type default)
			)
			(layer "B.Fab")
		)
		(fp_line
			(start -0.67945 0.3048)
			(end -0.120396 0.3048)
			(stroke
				(width 0.1)
				(type default)
			)
			(layer "B.Fab")
		)
		(fp_line
			(start -0.67945 -0.3048)
			(end -0.67945 0.3048)
			(stroke
				(width 0.1)
				(type default)
			)
			(layer "B.Fab")
		)
		(pad "1" smd circle
			(at 0.40005 0)
			(size 0 0)
			(layers "B.Cu" "B.Mask" "B.Paste")
			(net "H_CPU_RMCA_LVC2_R1_N")
		)
		(pad "2" smd circle
			(at -0.40005 0)
			(size 0 0)
			(layers "B.Cu" "B.Mask" "B.Paste")
			(net "H_CPU_RMCA_LVC2_R2_N")
		)
	)
	(footprint ""
		(layer "B.Cu")
		(at 257.32867 -102.28834 90)
		(property "Reference" "C119"
			(at 0 0 90)
			(layer "B.SilkS")
			(hide yes)
			(effects
				(font
					(size 1.27 1.27)
				)
				(justify mirror)
			)
		)
		(property "Value" ""
			(at 0 0 90)
			(layer "B.Fab")
			(effects
				(font
					(size 1.27 1.27)
				)
				(justify mirror)
			)
		)
		(duplicate_pad_numbers_are_jumpers no)
		(fp_line
			(start 0.7874 -0.4064)
			(end -0.7874 -0.4064)
			(stroke
				(width 0.1524)
				(type default)
			)
			(layer "B.SilkS")
		)
		(fp_line
			(start -0.7874 -0.4064)
			(end -0.7874 0.4064)
			(stroke
				(width 0.1524)
				(type default)
			)
			(layer "B.SilkS")
		)
		(fp_line
			(start 0.7874 0.4064)
			(end 0.7874 -0.4064)
			(stroke
				(width 0.1524)
				(type default)
			)
			(layer "B.SilkS")
		)
		(fp_line
			(start -0.7874 0.4064)
			(end 0.7874 0.4064)
			(stroke
				(width 0.1524)
				(type default)
			)
			(layer "B.SilkS")
		)
		(fp_line
			(start 0.67945 -0.305054)
			(end 0.12065 -0.305054)
			(stroke
				(width 0.1)
				(type default)
			)
			(layer "B.Fab")
		)
		(fp_line
			(start 0.12065 -0.305054)
			(end 0.12065 -0.2794)
			(stroke
				(width 0.1)
				(type default)
			)
			(layer "B.Fab")
		)
		(fp_line
			(start -0.12065 -0.3048)
			(end -0.67945 -0.3048)
			(stroke
				(width 0.1)
				(type default)
			)
			(layer "B.Fab")
		)
		(fp_line
			(start -0.67945 -0.3048)
			(end -0.67945 0.3048)
			(stroke
				(width 0.1)
				(type default)
			)
			(layer "B.Fab")
		)
		(fp_line
			(start 0.12065 -0.2794)
			(end -0.12065 -0.2794)
			(stroke
				(width 0.1)
				(type default)
			)
			(layer "B.Fab")
		)
		(fp_line
			(start -0.12065 -0.2794)
			(end -0.12065 -0.3048)
			(stroke
				(width 0.1)
				(type default)
			)
			(layer "B.Fab")
		)
		(fp_line
			(start 0.12065 0.2794)
			(end 0.12065 0.3048)
			(stroke
				(width 0.1)
				(type default)
			)
			(layer "B.Fab")
		)
		(fp_line
			(start -0.120396 0.2794)
			(end 0.12065 0.2794)
			(stroke
				(width 0.1)
				(type default)
			)
			(layer "B.Fab")
		)
		(fp_line
			(start 0.67945 0.3048)
			(end 0.67945 -0.305054)
			(stroke
				(width 0.1)
				(type default)
			)
			(layer "B.Fab")
		)
		(fp_line
			(start 0.12065 0.3048)
			(end 0.67945 0.3048)
			(stroke
				(width 0.1)
				(type default)
			)
			(layer "B.Fab")
		)
		(fp_line
			(start -0.120396 0.3048)
			(end -0.120396 0.2794)
			(stroke
				(width 0.1)
				(type default)
			)
			(layer "B.Fab")
		)
		(fp_line
			(start -0.67945 0.3048)
			(end -0.120396 0.3048)
			(stroke
				(width 0.1)
				(type default)
			)
			(layer "B.Fab")
		)
		(pad "1" smd circle
			(at 0.40005 0 270)
			(size 0 0)
			(layers "B.Cu" "B.Mask" "B.Paste")
			(net "P3V3_AUX_CLK_GEN_VDDMXCK_CK440")
		)
		(pad "2" smd circle
			(at -0.40005 0 270)
			(size 0 0)
			(layers "B.Cu" "B.Mask" "B.Paste")
			(net "GND")
		)
	)
	(footprint ""
		(layer "B.Cu")
		(at 369.49888 -46.192948 180)
		(property "Reference" "R4114"
			(at 0 0 0)
			(layer "B.SilkS")
			(hide yes)
			(effects
				(font
					(size 1.27 1.27)
				)
				(justify mirror)
			)
		)
		(property "Value" ""
			(at 0 0 0)
			(layer "B.Fab")
			(effects
				(font
					(size 1.27 1.27)
				)
				(justify mirror)
			)
		)
		(duplicate_pad_numbers_are_jumpers no)
		(fp_line
			(start 0.7874 0.4064)
			(end 0.7874 -0.4064)
			(stroke
				(width 0.1524)
				(type default)
			)
			(layer "B.SilkS")
		)
		(fp_line
			(start 0.7874 -0.4064)
			(end -0.7874 -0.4064)
			(stroke
				(width 0.1524)
				(type default)
			)
			(layer "B.SilkS")
		)
		(fp_line
			(start -0.7874 0.4064)
			(end 0.7874 0.4064)
			(stroke
				(width 0.1524)
				(type default)
			)
			(layer "B.SilkS")
		)
		(fp_line
			(start -0.7874 -0.4064)
			(end -0.7874 0.4064)
			(stroke
				(width 0.1524)
				(type default)
			)
			(layer "B.SilkS")
		)
		(fp_line
			(start 0.67945 0.3048)
			(end 0.67945 -0.305054)
			(stroke
				(width 0.1)
				(type default)
			)
			(layer "B.Fab")
		)
		(fp_line
			(start 0.67945 -0.305054)
			(end 0.12065 -0.305054)
			(stroke
				(width 0.1)
				(type default)
			)
			(layer "B.Fab")
		)
		(fp_line
			(start 0.12065 0.3048)
			(end 0.67945 0.3048)
			(stroke
				(width 0.1)
				(type default)
			)
			(layer "B.Fab")
		)
		(fp_line
			(start 0.12065 0.2794)
			(end 0.12065 0.3048)
			(stroke
				(width 0.1)
				(type default)
			)
			(layer "B.Fab")
		)
		(fp_line
			(start 0.12065 -0.2794)
			(end -0.12065 -0.2794)
			(stroke
				(width 0.1)
				(type default)
			)
			(layer "B.Fab")
		)
		(fp_line
			(start 0.12065 -0.305054)
			(end 0.12065 -0.2794)
			(stroke
				(width 0.1)
				(type default)
			)
			(layer "B.Fab")
		)
		(fp_line
			(start -0.120396 0.3048)
			(end -0.120396 0.2794)
			(stroke
				(width 0.1)
				(type default)
			)
			(layer "B.Fab")
		)
		(fp_line
			(start -0.120396 0.2794)
			(end 0.12065 0.2794)
			(stroke
				(width 0.1)
				(type default)
			)
			(layer "B.Fab")
		)
		(fp_line
			(start -0.12065 -0.2794)
			(end -0.12065 -0.3048)
			(stroke
				(width 0.1)
				(type default)
			)
			(layer "B.Fab")
		)
		(fp_line
			(start -0.12065 -0.3048)
			(end -0.67945 -0.3048)
			(stroke
				(width 0.1)
				(type default)
			)
			(layer "B.Fab")
		)
		(fp_line
			(start -0.67945 0.3048)
			(end -0.120396 0.3048)
			(stroke
				(width 0.1)
				(type default)
			)
			(layer "B.Fab")
		)
		(fp_line
			(start -0.67945 -0.3048)
			(end -0.67945 0.3048)
			(stroke
				(width 0.1)
				(type default)
			)
			(layer "B.Fab")
		)
		(pad "1" smd circle
			(at 0.40005 0)
			(size 0 0)
			(layers "B.Cu" "B.Mask" "B.Paste")
			(net "PD_PCH_GPP_E_10")
		)
		(pad "2" smd circle
			(at -0.40005 0)
			(size 0 0)
			(layers "B.Cu" "B.Mask" "B.Paste")
			(net "GND")
		)
	)
	(footprint ""
		(layer "B.Cu")
		(at 321.206622 -36.185348 45)
		(property "Reference" "R1995"
			(at 0 0 45)
			(layer "B.SilkS")
			(hide yes)
			(effects
				(font
					(size 1.27 1.27)
				)
				(justify mirror)
			)
		)
		(property "Value" ""
			(at 0 0 45)
			(layer "B.Fab")
			(effects
				(font
					(size 1.27 1.27)
				)
				(justify mirror)
			)
		)
		(duplicate_pad_numbers_are_jumpers no)
		(fp_line
			(start -0.787389 -0.406267)
			(end -0.787389 0.406267)
			(stroke
				(width 0.1524)
				(type default)
			)
			(layer "B.SilkS")
		)
		(fp_line
			(start -0.787389 0.406267)
			(end 0.787389 0.406267)
			(stroke
				(width 0.1524)
				(type default)
			)
			(layer "B.SilkS")
		)
		(fp_line
			(start 0.787389 -0.406267)
			(end -0.787389 -0.406267)
			(stroke
				(width 0.1524)
				(type default)
			)
			(layer "B.SilkS")
		)
		(fp_line
			(start 0.787389 0.406267)
			(end 0.787389 -0.406267)
			(stroke
				(width 0.1524)
				(type default)
			)
			(layer "B.SilkS")
		)
		(fp_line
			(start -0.679446 -0.30479)
			(end -0.679446 0.30479)
			(stroke
				(width 0.1)
				(type default)
			)
			(layer "B.Fab")
		)
		(fp_line
			(start -0.120515 -0.30479)
			(end -0.679446 -0.30479)
			(stroke
				(width 0.1)
				(type default)
			)
			(layer "B.Fab")
		)
		(fp_line
			(start -0.120695 -0.279466)
			(end -0.120515 -0.30479)
			(stroke
				(width 0.1)
				(type default)
			)
			(layer "B.Fab")
		)
		(fp_line
			(start -0.679446 0.30479)
			(end -0.120515 0.30479)
			(stroke
				(width 0.1)
				(type default)
			)
			(layer "B.Fab")
		)
		(fp_line
			(start 0.120695 -0.304969)
			(end 0.120695 -0.279466)
			(stroke
				(width 0.1)
				(type default)
			)
			(layer "B.Fab")
		)
		(fp_line
			(start 0.120695 -0.279466)
			(end -0.120695 -0.279466)
			(stroke
				(width 0.1)
				(type default)
			)
			(layer "B.Fab")
		)
		(fp_line
			(start -0.120335 0.279466)
			(end 0.120695 0.279466)
			(stroke
				(width 0.1)
				(type default)
			)
			(layer "B.Fab")
		)
		(fp_line
			(start -0.120515 0.30479)
			(end -0.120335 0.279466)
			(stroke
				(width 0.1)
				(type default)
			)
			(layer "B.Fab")
		)
		(fp_line
			(start 0.679446 -0.305149)
			(end 0.120695 -0.304969)
			(stroke
				(width 0.1)
				(type default)
			)
			(layer "B.Fab")
		)
		(fp_line
			(start 0.120695 0.279466)
			(end 0.120515 0.30479)
			(stroke
				(width 0.1)
				(type default)
			)
			(layer "B.Fab")
		)
		(fp_line
			(start 0.120515 0.30479)
			(end 0.679446 0.30479)
			(stroke
				(width 0.1)
				(type default)
			)
			(layer "B.Fab")
		)
		(fp_line
			(start 0.679446 0.30479)
			(end 0.679446 -0.305149)
			(stroke
				(width 0.1)
				(type default)
			)
			(layer "B.Fab")
		)
		(pad "1" smd circle
			(at 0.40005 0 225)
			(size 0 0)
			(layers "B.Cu" "B.Mask" "B.Paste")
			(net "FM_PCH_SLP_S3_N")
		)
		(pad "2" smd circle
			(at -0.40005 0 225)
			(size 0 0)
			(layers "B.Cu" "B.Mask" "B.Paste")
			(net "FM_SLPS3_PLD_N")
		)
	)
	(footprint ""
		(layer "B.Cu")
		(at 293.544498 -403.031452 90)
		(property "Reference" "PR2513"
			(at 0 0 90)
			(layer "B.SilkS")
			(hide yes)
			(effects
				(font
					(size 1.27 1.27)
				)
				(justify mirror)
			)
		)
		(property "Value" ""
			(at 0 0 90)
			(layer "B.Fab")
			(effects
				(font
					(size 1.27 1.27)
				)
				(justify mirror)
			)
		)
		(duplicate_pad_numbers_are_jumpers no)
		(fp_line
			(start 0.7874 -0.4064)
			(end -0.7874 -0.4064)
			(stroke
				(width 0.1524)
				(type default)
			)
			(layer "B.SilkS")
		)
		(fp_line
			(start -0.7874 -0.4064)
			(end -0.7874 0.4064)
			(stroke
				(width 0.1524)
				(type default)
			)
			(layer "B.SilkS")
		)
		(fp_line
			(start 0.7874 0.4064)
			(end 0.7874 -0.4064)
			(stroke
				(width 0.1524)
				(type default)
			)
			(layer "B.SilkS")
		)
		(fp_line
			(start -0.7874 0.4064)
			(end 0.7874 0.4064)
			(stroke
				(width 0.1524)
				(type default)
			)
			(layer "B.SilkS")
		)
		(fp_line
			(start 0.67945 -0.305054)
			(end 0.12065 -0.305054)
			(stroke
				(width 0.1)
				(type default)
			)
			(layer "B.Fab")
		)
		(fp_line
			(start 0.12065 -0.305054)
			(end 0.12065 -0.2794)
			(stroke
				(width 0.1)
				(type default)
			)
			(layer "B.Fab")
		)
		(fp_line
			(start -0.12065 -0.3048)
			(end -0.67945 -0.3048)
			(stroke
				(width 0.1)
				(type default)
			)
			(layer "B.Fab")
		)
		(fp_line
			(start -0.67945 -0.3048)
			(end -0.67945 0.3048)
			(stroke
				(width 0.1)
				(type default)
			)
			(layer "B.Fab")
		)
		(fp_line
			(start 0.12065 -0.2794)
			(end -0.12065 -0.2794)
			(stroke
				(width 0.1)
				(type default)
			)
			(layer "B.Fab")
		)
		(fp_line
			(start -0.12065 -0.2794)
			(end -0.12065 -0.3048)
			(stroke
				(width 0.1)
				(type default)
			)
			(layer "B.Fab")
		)
		(fp_line
			(start 0.12065 0.2794)
			(end 0.12065 0.3048)
			(stroke
				(width 0.1)
				(type default)
			)
			(layer "B.Fab")
		)
		(fp_line
			(start -0.120396 0.2794)
			(end 0.12065 0.2794)
			(stroke
				(width 0.1)
				(type default)
			)
			(layer "B.Fab")
		)
		(fp_line
			(start 0.67945 0.3048)
			(end 0.67945 -0.305054)
			(stroke
				(width 0.1)
				(type default)
			)
			(layer "B.Fab")
		)
		(fp_line
			(start 0.12065 0.3048)
			(end 0.67945 0.3048)
			(stroke
				(width 0.1)
				(type default)
			)
			(layer "B.Fab")
		)
		(fp_line
			(start -0.120396 0.3048)
			(end -0.120396 0.2794)
			(stroke
				(width 0.1)
				(type default)
			)
			(layer "B.Fab")
		)
		(fp_line
			(start -0.67945 0.3048)
			(end -0.120396 0.3048)
			(stroke
				(width 0.1)
				(type default)
			)
			(layer "B.Fab")
		)
		(pad "1" smd circle
			(at 0.40005 0 270)
			(size 0 0)
			(layers "B.Cu" "B.Mask" "B.Paste")
			(net "P12V_HSC_ADC_P")
		)
		(pad "2" smd circle
			(at -0.40005 0 270)
			(size 0 0)
			(layers "B.Cu" "B.Mask" "B.Paste")
			(net "P12V_HSC_SENSE2_R4_P")
		)
	)
	(footprint ""
		(layer "B.Cu")
		(at 103.25608 -359.070148 180)
		(property "Reference" "R2523"
			(at 0 0 0)
			(layer "B.SilkS")
			(hide yes)
			(effects
				(font
					(size 1.27 1.27)
				)
				(justify mirror)
			)
		)
		(property "Value" ""
			(at 0 0 0)
			(layer "B.Fab")
			(effects
				(font
					(size 1.27 1.27)
				)
				(justify mirror)
			)
		)
		(duplicate_pad_numbers_are_jumpers no)
		(fp_line
			(start 0.7874 0.4064)
			(end 0.7874 -0.4064)
			(stroke
				(width 0.1524)
				(type default)
			)
			(layer "B.SilkS")
		)
		(fp_line
			(start 0.7874 -0.4064)
			(end -0.7874 -0.4064)
			(stroke
				(width 0.1524)
				(type default)
			)
			(layer "B.SilkS")
		)
		(fp_line
			(start -0.7874 0.4064)
			(end 0.7874 0.4064)
			(stroke
				(width 0.1524)
				(type default)
			)
			(layer "B.SilkS")
		)
		(fp_line
			(start -0.7874 -0.4064)
			(end -0.7874 0.4064)
			(stroke
				(width 0.1524)
				(type default)
			)
			(layer "B.SilkS")
		)
		(fp_line
			(start 0.67945 0.3048)
			(end 0.67945 -0.305054)
			(stroke
				(width 0.1)
				(type default)
			)
			(layer "B.Fab")
		)
		(fp_line
			(start 0.67945 -0.305054)
			(end 0.12065 -0.305054)
			(stroke
				(width 0.1)
				(type default)
			)
			(layer "B.Fab")
		)
		(fp_line
			(start 0.12065 0.3048)
			(end 0.67945 0.3048)
			(stroke
				(width 0.1)
				(type default)
			)
			(layer "B.Fab")
		)
		(fp_line
			(start 0.12065 0.2794)
			(end 0.12065 0.3048)
			(stroke
				(width 0.1)
				(type default)
			)
			(layer "B.Fab")
		)
		(fp_line
			(start 0.12065 -0.2794)
			(end -0.12065 -0.2794)
			(stroke
				(width 0.1)
				(type default)
			)
			(layer "B.Fab")
		)
		(fp_line
			(start 0.12065 -0.305054)
			(end 0.12065 -0.2794)
			(stroke
				(width 0.1)
				(type default)
			)
			(layer "B.Fab")
		)
		(fp_line
			(start -0.120396 0.3048)
			(end -0.120396 0.2794)
			(stroke
				(width 0.1)
				(type default)
			)
			(layer "B.Fab")
		)
		(fp_line
			(start -0.120396 0.2794)
			(end 0.12065 0.2794)
			(stroke
				(width 0.1)
				(type default)
			)
			(layer "B.Fab")
		)
		(fp_line
			(start -0.12065 -0.2794)
			(end -0.12065 -0.3048)
			(stroke
				(width 0.1)
				(type default)
			)
			(layer "B.Fab")
		)
		(fp_line
			(start -0.12065 -0.3048)
			(end -0.67945 -0.3048)
			(stroke
				(width 0.1)
				(type default)
			)
			(layer "B.Fab")
		)
		(fp_line
			(start -0.67945 0.3048)
			(end -0.120396 0.3048)
			(stroke
				(width 0.1)
				(type default)
			)
			(layer "B.Fab")
		)
		(fp_line
			(start -0.67945 -0.3048)
			(end -0.67945 0.3048)
			(stroke
				(width 0.1)
				(type default)
			)
			(layer "B.Fab")
		)
		(pad "1" smd circle
			(at 0.40005 0)
			(size 0 0)
			(layers "B.Cu" "B.Mask" "B.Paste")
			(net "IRQ_PVCCIN_CPU1_VRHOT_R_N")
		)
		(pad "2" smd circle
			(at -0.40005 0)
			(size 0 0)
			(layers "B.Cu" "B.Mask" "B.Paste")
			(net "IRQ_PVCCIN_CPU1_VRHOT_N")
		)
	)
	(footprint ""
		(layer "B.Cu")
		(at 203.877926 -79.444342)
		(property "Reference" "C1826"
			(at 0 0 0)
			(layer "B.SilkS")
			(hide yes)
			(effects
				(font
					(size 1.27 1.27)
				)
				(justify mirror)
			)
		)
		(property "Value" ""
			(at 0 0 0)
			(layer "B.Fab")
			(effects
				(font
					(size 1.27 1.27)
				)
				(justify mirror)
			)
		)
		(duplicate_pad_numbers_are_jumpers no)
		(fp_line
			(start -0.7874 -0.4064)
			(end -0.7874 0.4064)
			(stroke
				(width 0.1524)
				(type default)
			)
			(layer "B.SilkS")
		)
		(fp_line
			(start -0.7874 0.4064)
			(end 0.7874 0.4064)
			(stroke
				(width 0.1524)
				(type default)
			)
			(layer "B.SilkS")
		)
		(fp_line
			(start 0.7874 -0.4064)
			(end -0.7874 -0.4064)
			(stroke
				(width 0.1524)
				(type default)
			)
			(layer "B.SilkS")
		)
		(fp_line
			(start 0.7874 0.4064)
			(end 0.7874 -0.4064)
			(stroke
				(width 0.1524)
				(type default)
			)
			(layer "B.SilkS")
		)
		(fp_line
			(start -0.67945 -0.3048)
			(end -0.67945 0.3048)
			(stroke
				(width 0.1)
				(type default)
			)
			(layer "B.Fab")
		)
		(fp_line
			(start -0.67945 0.3048)
			(end -0.120396 0.3048)
			(stroke
				(width 0.1)
				(type default)
			)
			(layer "B.Fab")
		)
		(fp_line
			(start -0.12065 -0.3048)
			(end -0.67945 -0.3048)
			(stroke
				(width 0.1)
				(type default)
			)
			(layer "B.Fab")
		)
		(fp_line
			(start -0.12065 -0.2794)
			(end -0.12065 -0.3048)
			(stroke
				(width 0.1)
				(type default)
			)
			(layer "B.Fab")
		)
		(fp_line
			(start -0.120396 0.2794)
			(end 0.12065 0.2794)
			(stroke
				(width 0.1)
				(type default)
			)
			(layer "B.Fab")
		)
		(fp_line
			(start -0.120396 0.3048)
			(end -0.120396 0.2794)
			(stroke
				(width 0.1)
				(type default)
			)
			(layer "B.Fab")
		)
		(fp_line
			(start 0.12065 -0.305054)
			(end 0.12065 -0.2794)
			(stroke
				(width 0.1)
				(type default)
			)
			(layer "B.Fab")
		)
		(fp_line
			(start 0.12065 -0.2794)
			(end -0.12065 -0.2794)
			(stroke
				(width 0.1)
				(type default)
			)
			(layer "B.Fab")
		)
		(fp_line
			(start 0.12065 0.2794)
			(end 0.12065 0.3048)
			(stroke
				(width 0.1)
				(type default)
			)
			(layer "B.Fab")
		)
		(fp_line
			(start 0.12065 0.3048)
			(end 0.67945 0.3048)
			(stroke
				(width 0.1)
				(type default)
			)
			(layer "B.Fab")
		)
		(fp_line
			(start 0.67945 -0.305054)
			(end 0.12065 -0.305054)
			(stroke
				(width 0.1)
				(type default)
			)
			(layer "B.Fab")
		)
		(fp_line
			(start 0.67945 0.3048)
			(end 0.67945 -0.305054)
			(stroke
				(width 0.1)
				(type default)
			)
			(layer "B.Fab")
		)
		(pad "1" smd circle
			(at 0.40005 0 180)
			(size 0 0)
			(layers "B.Cu" "B.Mask" "B.Paste")
			(net "P3V3_AUX")
		)
		(pad "2" smd circle
			(at -0.40005 0 180)
			(size 0 0)
			(layers "B.Cu" "B.Mask" "B.Paste")
			(net "GND")
		)
	)
	(footprint ""
		(layer "B.Cu")
		(at 11.80592 -400.030188)
		(property "Reference" ""
			(at 0 0 0)
			(layer "B.SilkS")
			(hide yes)
			(effects
				(font
					(size 1.27 1.27)
				)
				(justify mirror)
			)
		)
		(property "Value" ""
			(at 0 0 0)
			(layer "B.Fab")
			(effects
				(font
					(size 1.27 1.27)
				)
				(justify mirror)
			)
		)
		(duplicate_pad_numbers_are_jumpers no)
		(pad "1" smd circle
			(at 0 0 180)
			(size 0.9906 0.9906)
			(layers "B.Cu" "B.Mask" "B.Paste")
			(net "Net_288")
		)
		(zone
			(layer "B.Cu")
			(hatch none 0.5)
			(connect_pads
				(clearance 0)
			)
			(min_thickness 0.25)
			(keepout
				(tracks not_allowed)
				(vias allowed)
				(pads allowed)
				(copperpour not_allowed)
				(footprints allowed)
			)
			(placement
				(enabled no)
				(sheetname "")
			)
			(fill
				(thermal_gap 0.5)
				(thermal_bridge_width 0.5)
				(island_removal_mode 0)
			)
			(polygon
				(pts
					(arc
						(start 13.43152 -400.030188)
						(mid 10.18032 -400.030188)
						(end 13.43152 -400.030188)
					)
				)
			)
		)
	)
	(footprint ""
		(layer "B.Cu")
		(at 54.510178 -353.567492 90)
		(property "Reference" "PC406_P1_2"
			(at 0 0 90)
			(layer "B.SilkS")
			(hide yes)
			(effects
				(font
					(size 1.27 1.27)
				)
				(justify mirror)
			)
		)
		(property "Value" ""
			(at 0 0 90)
			(layer "B.Fab")
			(effects
				(font
					(size 1.27 1.27)
				)
				(justify mirror)
			)
		)
		(duplicate_pad_numbers_are_jumpers no)
		(fp_line
			(start 1.524 -0.762)
			(end -1.524 -0.762)
			(stroke
				(width 0.1524)
				(type default)
			)
			(layer "B.SilkS")
		)
		(fp_line
			(start -1.524 -0.762)
			(end -1.524 0.762)
			(stroke
				(width 0.1524)
				(type default)
			)
			(layer "B.SilkS")
		)
		(fp_line
			(start 1.524 0.762)
			(end 1.524 -0.762)
			(stroke
				(width 0.1524)
				(type default)
			)
			(layer "B.SilkS")
		)
		(fp_line
			(start -1.524 0.762)
			(end 1.524 0.762)
			(stroke
				(width 0.1524)
				(type default)
			)
			(layer "B.SilkS")
		)
		(fp_line
			(start 1.1049 -0.724916)
			(end 1.1049 0.724916)
			(stroke
				(width 0.1)
				(type default)
			)
			(layer "B.Fab")
		)
		(fp_line
			(start -1.1049 -0.724916)
			(end 1.1049 -0.724916)
			(stroke
				(width 0.1)
				(type default)
			)
			(layer "B.Fab")
		)
		(fp_line
			(start 1.1049 0.724916)
			(end -1.1049 0.724916)
			(stroke
				(width 0.1)
				(type default)
			)
			(layer "B.Fab")
		)
		(fp_line
			(start -1.1049 0.724916)
			(end -1.1049 -0.724916)
			(stroke
				(width 0.1)
				(type default)
			)
			(layer "B.Fab")
		)
		(pad "1" smd rect
			(at 0.889 0 90)
			(size 1.016 1.27)
			(layers "B.Cu" "B.Mask" "B.Paste")
			(net "SW_P12V_PVCCFA_EHV_FIVRA_CPU1_L")
		)
		(pad "2" smd rect
			(at -0.889 0 90)
			(size 1.016 1.27)
			(layers "B.Cu" "B.Mask" "B.Paste")
			(net "GND")
		)
	)
	(footprint ""
		(layer "B.Cu")
		(at 81.798414 -342.936576 90)
		(property "Reference" "PC494_P1_7"
			(at 0 0 90)
			(layer "B.SilkS")
			(hide yes)
			(effects
				(font
					(size 1.27 1.27)
				)
				(justify mirror)
			)
		)
		(property "Value" ""
			(at 0 0 90)
			(layer "B.Fab")
			(effects
				(font
					(size 1.27 1.27)
				)
				(justify mirror)
			)
		)
		(duplicate_pad_numbers_are_jumpers no)
		(fp_line
			(start 1.524 -0.762)
			(end -1.524 -0.762)
			(stroke
				(width 0.1524)
				(type default)
			)
			(layer "B.SilkS")
		)
		(fp_line
			(start -1.524 -0.762)
			(end -1.524 0.762)
			(stroke
				(width 0.1524)
				(type default)
			)
			(layer "B.SilkS")
		)
		(fp_line
			(start 1.524 0.762)
			(end 1.524 -0.762)
			(stroke
				(width 0.1524)
				(type default)
			)
			(layer "B.SilkS")
		)
		(fp_line
			(start -1.524 0.762)
			(end 1.524 0.762)
			(stroke
				(width 0.1524)
				(type default)
			)
			(layer "B.SilkS")
		)
		(fp_line
			(start 1.1049 -0.724916)
			(end 1.1049 0.724916)
			(stroke
				(width 0.1)
				(type default)
			)
			(layer "B.Fab")
		)
		(fp_line
			(start -1.1049 -0.724916)
			(end 1.1049 -0.724916)
			(stroke
				(width 0.1)
				(type default)
			)
			(layer "B.Fab")
		)
		(fp_line
			(start 1.1049 0.724916)
			(end -1.1049 0.724916)
			(stroke
				(width 0.1)
				(type default)
			)
			(layer "B.Fab")
		)
		(fp_line
			(start -1.1049 0.724916)
			(end -1.1049 -0.724916)
			(stroke
				(width 0.1)
				(type default)
			)
			(layer "B.Fab")
		)
		(pad "1" smd rect
			(at 0.889 0 90)
			(size 1.016 1.27)
			(layers "B.Cu" "B.Mask" "B.Paste")
			(net "SW_P12V_PVCCIN_CPU1_FLT")
		)
		(pad "2" smd rect
			(at -0.889 0 90)
			(size 1.016 1.27)
			(layers "B.Cu" "B.Mask" "B.Paste")
			(net "GND")
		)
	)
	(footprint ""
		(layer "B.Cu")
		(at 180.8734 -21.364448 -90)
		(property "Reference" "R3062"
			(at 0 0 90)
			(layer "B.SilkS")
			(hide yes)
			(effects
				(font
					(size 1.27 1.27)
				)
				(justify mirror)
			)
		)
		(property "Value" ""
			(at 0 0 90)
			(layer "B.Fab")
			(effects
				(font
					(size 1.27 1.27)
				)
				(justify mirror)
			)
		)
		(duplicate_pad_numbers_are_jumpers no)
		(fp_line
			(start -0.7874 0.4064)
			(end 0.7874 0.4064)
			(stroke
				(width 0.1524)
				(type default)
			)
			(layer "B.SilkS")
		)
		(fp_line
			(start 0.7874 0.4064)
			(end 0.7874 -0.4064)
			(stroke
				(width 0.1524)
				(type default)
			)
			(layer "B.SilkS")
		)
		(fp_line
			(start -0.7874 -0.4064)
			(end -0.7874 0.4064)
			(stroke
				(width 0.1524)
				(type default)
			)
			(layer "B.SilkS")
		)
		(fp_line
			(start 0.7874 -0.4064)
			(end -0.7874 -0.4064)
			(stroke
				(width 0.1524)
				(type default)
			)
			(layer "B.SilkS")
		)
		(fp_line
			(start -0.67945 0.3048)
			(end -0.120396 0.3048)
			(stroke
				(width 0.1)
				(type default)
			)
			(layer "B.Fab")
		)
		(fp_line
			(start -0.120396 0.3048)
			(end -0.120396 0.2794)
			(stroke
				(width 0.1)
				(type default)
			)
			(layer "B.Fab")
		)
		(fp_line
			(start 0.12065 0.3048)
			(end 0.67945 0.3048)
			(stroke
				(width 0.1)
				(type default)
			)
			(layer "B.Fab")
		)
		(fp_line
			(start 0.67945 0.3048)
			(end 0.67945 -0.305054)
			(stroke
				(width 0.1)
				(type default)
			)
			(layer "B.Fab")
		)
		(fp_line
			(start -0.120396 0.2794)
			(end 0.12065 0.2794)
			(stroke
				(width 0.1)
				(type default)
			)
			(layer "B.Fab")
		)
		(fp_line
			(start 0.12065 0.2794)
			(end 0.12065 0.3048)
			(stroke
				(width 0.1)
				(type default)
			)
			(layer "B.Fab")
		)
		(fp_line
			(start -0.12065 -0.2794)
			(end -0.12065 -0.3048)
			(stroke
				(width 0.1)
				(type default)
			)
			(layer "B.Fab")
		)
		(fp_line
			(start 0.12065 -0.2794)
			(end -0.12065 -0.2794)
			(stroke
				(width 0.1)
				(type default)
			)
			(layer "B.Fab")
		)
		(fp_line
			(start -0.67945 -0.3048)
			(end -0.67945 0.3048)
			(stroke
				(width 0.1)
				(type default)
			)
			(layer "B.Fab")
		)
		(fp_line
			(start -0.12065 -0.3048)
			(end -0.67945 -0.3048)
			(stroke
				(width 0.1)
				(type default)
			)
			(layer "B.Fab")
		)
		(fp_line
			(start 0.12065 -0.305054)
			(end 0.12065 -0.2794)
			(stroke
				(width 0.1)
				(type default)
			)
			(layer "B.Fab")
		)
		(fp_line
			(start 0.67945 -0.305054)
			(end 0.12065 -0.305054)
			(stroke
				(width 0.1)
				(type default)
			)
			(layer "B.Fab")
		)
		(pad "1" smd circle
			(at 0.40005 0 90)
			(size 0 0)
			(layers "B.Cu" "B.Mask" "B.Paste")
			(net "SMB_HOST_3V3AUX_SDA")
		)
		(pad "2" smd circle
			(at -0.40005 0 90)
			(size 0 0)
			(layers "B.Cu" "B.Mask" "B.Paste")
			(net "P3V3_AUX")
		)
	)
	(footprint ""
		(layer "B.Cu")
		(at 438.4802 -434.365908)
		(property "Reference" ""
			(at 0 0 0)
			(layer "B.SilkS")
			(hide yes)
			(effects
				(font
					(size 1.27 1.27)
				)
				(justify mirror)
			)
		)
		(property "Value" ""
			(at 0 0 0)
			(layer "B.Fab")
			(effects
				(font
					(size 1.27 1.27)
				)
				(justify mirror)
			)
		)
		(duplicate_pad_numbers_are_jumpers no)
		(pad "1" smd circle
			(at 0 0 180)
			(size 0.9906 0.9906)
			(layers "B.Cu" "B.Mask" "B.Paste")
			(net "Net_287")
		)
		(zone
			(layer "B.Cu")
			(hatch none 0.5)
			(connect_pads
				(clearance 0)
			)
			(min_thickness 0.25)
			(keepout
				(tracks not_allowed)
				(vias allowed)
				(pads allowed)
				(copperpour not_allowed)
				(footprints allowed)
			)
			(placement
				(enabled no)
				(sheetname "")
			)
			(fill
				(thermal_gap 0.5)
				(thermal_bridge_width 0.5)
				(island_removal_mode 0)
			)
			(polygon
				(pts
					(arc
						(start 440.1058 -434.365908)
						(mid 436.8546 -434.365908)
						(end 440.1058 -434.365908)
					)
				)
			)
		)
	)
	(footprint ""
		(layer "B.Cu")
		(at 30.163516 -130.297682 180)
		(property "Reference" "PC1292"
			(at 0 0 0)
			(layer "B.SilkS")
			(hide yes)
			(effects
				(font
					(size 1.27 1.27)
				)
				(justify mirror)
			)
		)
		(property "Value" ""
			(at 0 0 0)
			(layer "B.Fab")
			(effects
				(font
					(size 1.27 1.27)
				)
				(justify mirror)
			)
		)
		(duplicate_pad_numbers_are_jumpers no)
		(fp_line
			(start 0.7874 0.4064)
			(end 0.7874 -0.4064)
			(stroke
				(width 0.1524)
				(type default)
			)
			(layer "B.SilkS")
		)
		(fp_line
			(start 0.7874 -0.4064)
			(end -0.7874 -0.4064)
			(stroke
				(width 0.1524)
				(type default)
			)
			(layer "B.SilkS")
		)
		(fp_line
			(start -0.7874 0.4064)
			(end 0.7874 0.4064)
			(stroke
				(width 0.1524)
				(type default)
			)
			(layer "B.SilkS")
		)
		(fp_line
			(start -0.7874 -0.4064)
			(end -0.7874 0.4064)
			(stroke
				(width 0.1524)
				(type default)
			)
			(layer "B.SilkS")
		)
		(fp_line
			(start 0.67945 0.3048)
			(end 0.67945 -0.305054)
			(stroke
				(width 0.1)
				(type default)
			)
			(layer "B.Fab")
		)
		(fp_line
			(start 0.67945 -0.305054)
			(end 0.12065 -0.305054)
			(stroke
				(width 0.1)
				(type default)
			)
			(layer "B.Fab")
		)
		(fp_line
			(start 0.12065 0.3048)
			(end 0.67945 0.3048)
			(stroke
				(width 0.1)
				(type default)
			)
			(layer "B.Fab")
		)
		(fp_line
			(start 0.12065 0.2794)
			(end 0.12065 0.3048)
			(stroke
				(width 0.1)
				(type default)
			)
			(layer "B.Fab")
		)
		(fp_line
			(start 0.12065 -0.2794)
			(end -0.12065 -0.2794)
			(stroke
				(width 0.1)
				(type default)
			)
			(layer "B.Fab")
		)
		(fp_line
			(start 0.12065 -0.305054)
			(end 0.12065 -0.2794)
			(stroke
				(width 0.1)
				(type default)
			)
			(layer "B.Fab")
		)
		(fp_line
			(start -0.120396 0.3048)
			(end -0.120396 0.2794)
			(stroke
				(width 0.1)
				(type default)
			)
			(layer "B.Fab")
		)
		(fp_line
			(start -0.120396 0.2794)
			(end 0.12065 0.2794)
			(stroke
				(width 0.1)
				(type default)
			)
			(layer "B.Fab")
		)
		(fp_line
			(start -0.12065 -0.2794)
			(end -0.12065 -0.3048)
			(stroke
				(width 0.1)
				(type default)
			)
			(layer "B.Fab")
		)
		(fp_line
			(start -0.12065 -0.3048)
			(end -0.67945 -0.3048)
			(stroke
				(width 0.1)
				(type default)
			)
			(layer "B.Fab")
		)
		(fp_line
			(start -0.67945 0.3048)
			(end -0.120396 0.3048)
			(stroke
				(width 0.1)
				(type default)
			)
			(layer "B.Fab")
		)
		(fp_line
			(start -0.67945 -0.3048)
			(end -0.67945 0.3048)
			(stroke
				(width 0.1)
				(type default)
			)
			(layer "B.Fab")
		)
		(pad "1" smd circle
			(at 0.40005 0)
			(size 0 0)
			(layers "B.Cu" "B.Mask" "B.Paste")
			(net "PVCCFA_EHV_CPU1_BTSEN")
		)
		(pad "2" smd circle
			(at -0.40005 0)
			(size 0 0)
			(layers "B.Cu" "B.Mask" "B.Paste")
			(net "GND")
		)
	)
	(footprint ""
		(layer "B.Cu")
		(at 12.217146 -321.554856 -90)
		(property "Reference" "C69"
			(at 0 0 90)
			(layer "B.SilkS")
			(hide yes)
			(effects
				(font
					(size 1.27 1.27)
				)
				(justify mirror)
			)
		)
		(property "Value" ""
			(at 0 0 90)
			(layer "B.Fab")
			(effects
				(font
					(size 1.27 1.27)
				)
				(justify mirror)
			)
		)
		(duplicate_pad_numbers_are_jumpers no)
		(fp_line
			(start -1.524 0.762)
			(end 1.524 0.762)
			(stroke
				(width 0.1524)
				(type default)
			)
			(layer "B.SilkS")
		)
		(fp_line
			(start 1.524 0.762)
			(end 1.524 -0.762)
			(stroke
				(width 0.1524)
				(type default)
			)
			(layer "B.SilkS")
		)
		(fp_line
			(start -1.524 -0.762)
			(end -1.524 0.762)
			(stroke
				(width 0.1524)
				(type default)
			)
			(layer "B.SilkS")
		)
		(fp_line
			(start 1.524 -0.762)
			(end -1.524 -0.762)
			(stroke
				(width 0.1524)
				(type default)
			)
			(layer "B.SilkS")
		)
		(fp_line
			(start -1.1049 0.724916)
			(end -1.1049 -0.724916)
			(stroke
				(width 0.1)
				(type default)
			)
			(layer "B.Fab")
		)
		(fp_line
			(start 1.1049 0.724916)
			(end -1.1049 0.724916)
			(stroke
				(width 0.1)
				(type default)
			)
			(layer "B.Fab")
		)
		(fp_line
			(start -1.1049 -0.724916)
			(end 1.1049 -0.724916)
			(stroke
				(width 0.1)
				(type default)
			)
			(layer "B.Fab")
		)
		(fp_line
			(start 1.1049 -0.724916)
			(end 1.1049 0.724916)
			(stroke
				(width 0.1)
				(type default)
			)
			(layer "B.Fab")
		)
		(pad "1" smd rect
			(at 0.889 0 270)
			(size 1.016 1.27)
			(layers "B.Cu" "B.Mask" "B.Paste")
			(net "P12V_S3_AUX_CPU1_NVDIMM")
		)
		(pad "2" smd rect
			(at -0.889 0 270)
			(size 1.016 1.27)
			(layers "B.Cu" "B.Mask" "B.Paste")
			(net "GND")
		)
	)
	(footprint ""
		(layer "B.Cu")
		(at 364.342934 -237.717838 90)
		(property "Reference" "C363"
			(at 0 0 90)
			(layer "B.SilkS")
			(hide yes)
			(effects
				(font
					(size 1.27 1.27)
				)
				(justify mirror)
			)
		)
		(property "Value" ""
			(at 0 0 90)
			(layer "B.Fab")
			(effects
				(font
					(size 1.27 1.27)
				)
				(justify mirror)
			)
		)
		(duplicate_pad_numbers_are_jumpers no)
		(fp_line
			(start 1.524 -0.762)
			(end -1.524 -0.762)
			(stroke
				(width 0.1524)
				(type default)
			)
			(layer "B.SilkS")
		)
		(fp_line
			(start -1.524 -0.762)
			(end -1.524 0.762)
			(stroke
				(width 0.1524)
				(type default)
			)
			(layer "B.SilkS")
		)
		(fp_line
			(start 1.524 0.762)
			(end 1.524 -0.762)
			(stroke
				(width 0.1524)
				(type default)
			)
			(layer "B.SilkS")
		)
		(fp_line
			(start -1.524 0.762)
			(end 1.524 0.762)
			(stroke
				(width 0.1524)
				(type default)
			)
			(layer "B.SilkS")
		)
		(fp_line
			(start 1.1049 -0.724916)
			(end 1.1049 0.724916)
			(stroke
				(width 0.1)
				(type default)
			)
			(layer "B.Fab")
		)
		(fp_line
			(start -1.1049 -0.724916)
			(end 1.1049 -0.724916)
			(stroke
				(width 0.1)
				(type default)
			)
			(layer "B.Fab")
		)
		(fp_line
			(start 1.1049 0.724916)
			(end -1.1049 0.724916)
			(stroke
				(width 0.1)
				(type default)
			)
			(layer "B.Fab")
		)
		(fp_line
			(start -1.1049 0.724916)
			(end -1.1049 -0.724916)
			(stroke
				(width 0.1)
				(type default)
			)
			(layer "B.Fab")
		)
		(pad "1" smd rect
			(at 0.889 0 90)
			(size 1.016 1.27)
			(layers "B.Cu" "B.Mask" "B.Paste")
			(net "PVCCIN_CPU0")
		)
		(pad "2" smd rect
			(at -0.889 0 90)
			(size 1.016 1.27)
			(layers "B.Cu" "B.Mask" "B.Paste")
			(net "GND")
		)
	)
	(footprint ""
		(layer "B.Cu")
		(at 254.824484 -107.361228 180)
		(property "Reference" "R1267"
			(at 0 0 0)
			(layer "B.SilkS")
			(hide yes)
			(effects
				(font
					(size 1.27 1.27)
				)
				(justify mirror)
			)
		)
		(property "Value" ""
			(at 0 0 0)
			(layer "B.Fab")
			(effects
				(font
					(size 1.27 1.27)
				)
				(justify mirror)
			)
		)
		(duplicate_pad_numbers_are_jumpers no)
		(fp_line
			(start 0.7874 0.4064)
			(end 0.7874 -0.4064)
			(stroke
				(width 0.1524)
				(type default)
			)
			(layer "B.SilkS")
		)
		(fp_line
			(start 0.7874 -0.4064)
			(end -0.7874 -0.4064)
			(stroke
				(width 0.1524)
				(type default)
			)
			(layer "B.SilkS")
		)
		(fp_line
			(start -0.7874 0.4064)
			(end 0.7874 0.4064)
			(stroke
				(width 0.1524)
				(type default)
			)
			(layer "B.SilkS")
		)
		(fp_line
			(start -0.7874 -0.4064)
			(end -0.7874 0.4064)
			(stroke
				(width 0.1524)
				(type default)
			)
			(layer "B.SilkS")
		)
		(fp_line
			(start 0.67945 0.3048)
			(end 0.67945 -0.305054)
			(stroke
				(width 0.1)
				(type default)
			)
			(layer "B.Fab")
		)
		(fp_line
			(start 0.67945 -0.305054)
			(end 0.12065 -0.305054)
			(stroke
				(width 0.1)
				(type default)
			)
			(layer "B.Fab")
		)
		(fp_line
			(start 0.12065 0.3048)
			(end 0.67945 0.3048)
			(stroke
				(width 0.1)
				(type default)
			)
			(layer "B.Fab")
		)
		(fp_line
			(start 0.12065 0.2794)
			(end 0.12065 0.3048)
			(stroke
				(width 0.1)
				(type default)
			)
			(layer "B.Fab")
		)
		(fp_line
			(start 0.12065 -0.2794)
			(end -0.12065 -0.2794)
			(stroke
				(width 0.1)
				(type default)
			)
			(layer "B.Fab")
		)
		(fp_line
			(start 0.12065 -0.305054)
			(end 0.12065 -0.2794)
			(stroke
				(width 0.1)
				(type default)
			)
			(layer "B.Fab")
		)
		(fp_line
			(start -0.120396 0.3048)
			(end -0.120396 0.2794)
			(stroke
				(width 0.1)
				(type default)
			)
			(layer "B.Fab")
		)
		(fp_line
			(start -0.120396 0.2794)
			(end 0.12065 0.2794)
			(stroke
				(width 0.1)
				(type default)
			)
			(layer "B.Fab")
		)
		(fp_line
			(start -0.12065 -0.2794)
			(end -0.12065 -0.3048)
			(stroke
				(width 0.1)
				(type default)
			)
			(layer "B.Fab")
		)
		(fp_line
			(start -0.12065 -0.3048)
			(end -0.67945 -0.3048)
			(stroke
				(width 0.1)
				(type default)
			)
			(layer "B.Fab")
		)
		(fp_line
			(start -0.67945 0.3048)
			(end -0.120396 0.3048)
			(stroke
				(width 0.1)
				(type default)
			)
			(layer "B.Fab")
		)
		(fp_line
			(start -0.67945 -0.3048)
			(end -0.67945 0.3048)
			(stroke
				(width 0.1)
				(type default)
			)
			(layer "B.Fab")
		)
		(pad "1" smd circle
			(at 0.40005 0)
			(size 0 0)
			(layers "B.Cu" "B.Mask" "B.Paste")
			(net "PU_CK440_SHFT_LD_N")
		)
		(pad "2" smd circle
			(at -0.40005 0)
			(size 0 0)
			(layers "B.Cu" "B.Mask" "B.Paste")
			(net "GND")
		)
	)
	(footprint ""
		(layer "B.Cu")
		(at 60.926218 -319.393824 180)
		(property "Reference" "C53"
			(at 0 0 0)
			(layer "B.SilkS")
			(hide yes)
			(effects
				(font
					(size 1.27 1.27)
				)
				(justify mirror)
			)
		)
		(property "Value" ""
			(at 0 0 0)
			(layer "B.Fab")
			(effects
				(font
					(size 1.27 1.27)
				)
				(justify mirror)
			)
		)
		(duplicate_pad_numbers_are_jumpers no)
		(fp_line
			(start 0.7874 0.4064)
			(end 0.7874 -0.4064)
			(stroke
				(width 0.1524)
				(type default)
			)
			(layer "B.SilkS")
		)
		(fp_line
			(start 0.7874 -0.4064)
			(end -0.7874 -0.4064)
			(stroke
				(width 0.1524)
				(type default)
			)
			(layer "B.SilkS")
		)
		(fp_line
			(start -0.7874 0.4064)
			(end 0.7874 0.4064)
			(stroke
				(width 0.1524)
				(type default)
			)
			(layer "B.SilkS")
		)
		(fp_line
			(start -0.7874 -0.4064)
			(end -0.7874 0.4064)
			(stroke
				(width 0.1524)
				(type default)
			)
			(layer "B.SilkS")
		)
		(fp_line
			(start 0.67945 0.3048)
			(end 0.67945 -0.305054)
			(stroke
				(width 0.1)
				(type default)
			)
			(layer "B.Fab")
		)
		(fp_line
			(start 0.67945 -0.305054)
			(end 0.12065 -0.305054)
			(stroke
				(width 0.1)
				(type default)
			)
			(layer "B.Fab")
		)
		(fp_line
			(start 0.12065 0.3048)
			(end 0.67945 0.3048)
			(stroke
				(width 0.1)
				(type default)
			)
			(layer "B.Fab")
		)
		(fp_line
			(start 0.12065 0.2794)
			(end 0.12065 0.3048)
			(stroke
				(width 0.1)
				(type default)
			)
			(layer "B.Fab")
		)
		(fp_line
			(start 0.12065 -0.2794)
			(end -0.12065 -0.2794)
			(stroke
				(width 0.1)
				(type default)
			)
			(layer "B.Fab")
		)
		(fp_line
			(start 0.12065 -0.305054)
			(end 0.12065 -0.2794)
			(stroke
				(width 0.1)
				(type default)
			)
			(layer "B.Fab")
		)
		(fp_line
			(start -0.120396 0.3048)
			(end -0.120396 0.2794)
			(stroke
				(width 0.1)
				(type default)
			)
			(layer "B.Fab")
		)
		(fp_line
			(start -0.120396 0.2794)
			(end 0.12065 0.2794)
			(stroke
				(width 0.1)
				(type default)
			)
			(layer "B.Fab")
		)
		(fp_line
			(start -0.12065 -0.2794)
			(end -0.12065 -0.3048)
			(stroke
				(width 0.1)
				(type default)
			)
			(layer "B.Fab")
		)
		(fp_line
			(start -0.12065 -0.3048)
			(end -0.67945 -0.3048)
			(stroke
				(width 0.1)
				(type default)
			)
			(layer "B.Fab")
		)
		(fp_line
			(start -0.67945 0.3048)
			(end -0.120396 0.3048)
			(stroke
				(width 0.1)
				(type default)
			)
			(layer "B.Fab")
		)
		(fp_line
			(start -0.67945 -0.3048)
			(end -0.67945 0.3048)
			(stroke
				(width 0.1)
				(type default)
			)
			(layer "B.Fab")
		)
		(pad "1" smd circle
			(at 0.40005 0)
			(size 0 0)
			(layers "B.Cu" "B.Mask" "B.Paste")
			(net "P3V3_AUX")
		)
		(pad "2" smd circle
			(at -0.40005 0)
			(size 0 0)
			(layers "B.Cu" "B.Mask" "B.Paste")
			(net "GND")
		)
	)
	(footprint ""
		(layer "B.Cu")
		(at 358.80421 -357.578406)
		(property "Reference" "PR171"
			(at 0 0 0)
			(layer "B.SilkS")
			(hide yes)
			(effects
				(font
					(size 1.27 1.27)
				)
				(justify mirror)
			)
		)
		(property "Value" ""
			(at 0 0 0)
			(layer "B.Fab")
			(effects
				(font
					(size 1.27 1.27)
				)
				(justify mirror)
			)
		)
		(duplicate_pad_numbers_are_jumpers no)
		(fp_line
			(start -0.7874 -0.4064)
			(end -0.7874 0.4064)
			(stroke
				(width 0.1524)
				(type default)
			)
			(layer "B.SilkS")
		)
		(fp_line
			(start -0.7874 0.4064)
			(end 0.7874 0.4064)
			(stroke
				(width 0.1524)
				(type default)
			)
			(layer "B.SilkS")
		)
		(fp_line
			(start 0.7874 -0.4064)
			(end -0.7874 -0.4064)
			(stroke
				(width 0.1524)
				(type default)
			)
			(layer "B.SilkS")
		)
		(fp_line
			(start 0.7874 0.4064)
			(end 0.7874 -0.4064)
			(stroke
				(width 0.1524)
				(type default)
			)
			(layer "B.SilkS")
		)
		(fp_line
			(start -0.67945 -0.3048)
			(end -0.67945 0.3048)
			(stroke
				(width 0.1)
				(type default)
			)
			(layer "B.Fab")
		)
		(fp_line
			(start -0.67945 0.3048)
			(end -0.120396 0.3048)
			(stroke
				(width 0.1)
				(type default)
			)
			(layer "B.Fab")
		)
		(fp_line
			(start -0.12065 -0.3048)
			(end -0.67945 -0.3048)
			(stroke
				(width 0.1)
				(type default)
			)
			(layer "B.Fab")
		)
		(fp_line
			(start -0.12065 -0.2794)
			(end -0.12065 -0.3048)
			(stroke
				(width 0.1)
				(type default)
			)
			(layer "B.Fab")
		)
		(fp_line
			(start -0.120396 0.2794)
			(end 0.12065 0.2794)
			(stroke
				(width 0.1)
				(type default)
			)
			(layer "B.Fab")
		)
		(fp_line
			(start -0.120396 0.3048)
			(end -0.120396 0.2794)
			(stroke
				(width 0.1)
				(type default)
			)
			(layer "B.Fab")
		)
		(fp_line
			(start 0.12065 -0.305054)
			(end 0.12065 -0.2794)
			(stroke
				(width 0.1)
				(type default)
			)
			(layer "B.Fab")
		)
		(fp_line
			(start 0.12065 -0.2794)
			(end -0.12065 -0.2794)
			(stroke
				(width 0.1)
				(type default)
			)
			(layer "B.Fab")
		)
		(fp_line
			(start 0.12065 0.2794)
			(end 0.12065 0.3048)
			(stroke
				(width 0.1)
				(type default)
			)
			(layer "B.Fab")
		)
		(fp_line
			(start 0.12065 0.3048)
			(end 0.67945 0.3048)
			(stroke
				(width 0.1)
				(type default)
			)
			(layer "B.Fab")
		)
		(fp_line
			(start 0.67945 -0.305054)
			(end 0.12065 -0.305054)
			(stroke
				(width 0.1)
				(type default)
			)
			(layer "B.Fab")
		)
		(fp_line
			(start 0.67945 0.3048)
			(end 0.67945 -0.305054)
			(stroke
				(width 0.1)
				(type default)
			)
			(layer "B.Fab")
		)
		(pad "1" smd circle
			(at 0.40005 0 180)
			(size 0 0)
			(layers "B.Cu" "B.Mask" "B.Paste")
			(net "PVCCIN_CPU0_ADDR")
		)
		(pad "2" smd circle
			(at -0.40005 0 180)
			(size 0 0)
			(layers "B.Cu" "B.Mask" "B.Paste")
			(net "GND")
		)
	)
	(footprint ""
		(layer "B.Cu")
		(at 177.443638 -13.762228 90)
		(property "Reference" "R2423"
			(at 0 0 90)
			(layer "B.SilkS")
			(hide yes)
			(effects
				(font
					(size 1.27 1.27)
				)
				(justify mirror)
			)
		)
		(property "Value" ""
			(at 0 0 90)
			(layer "B.Fab")
			(effects
				(font
					(size 1.27 1.27)
				)
				(justify mirror)
			)
		)
		(duplicate_pad_numbers_are_jumpers no)
		(fp_line
			(start 0.7874 -0.4064)
			(end -0.7874 -0.4064)
			(stroke
				(width 0.1524)
				(type default)
			)
			(layer "B.SilkS")
		)
		(fp_line
			(start -0.7874 -0.4064)
			(end -0.7874 0.4064)
			(stroke
				(width 0.1524)
				(type default)
			)
			(layer "B.SilkS")
		)
		(fp_line
			(start 0.7874 0.4064)
			(end 0.7874 -0.4064)
			(stroke
				(width 0.1524)
				(type default)
			)
			(layer "B.SilkS")
		)
		(fp_line
			(start -0.7874 0.4064)
			(end 0.7874 0.4064)
			(stroke
				(width 0.1524)
				(type default)
			)
			(layer "B.SilkS")
		)
		(fp_line
			(start 0.67945 -0.305054)
			(end 0.12065 -0.305054)
			(stroke
				(width 0.1)
				(type default)
			)
			(layer "B.Fab")
		)
		(fp_line
			(start 0.12065 -0.305054)
			(end 0.12065 -0.2794)
			(stroke
				(width 0.1)
				(type default)
			)
			(layer "B.Fab")
		)
		(fp_line
			(start -0.12065 -0.3048)
			(end -0.67945 -0.3048)
			(stroke
				(width 0.1)
				(type default)
			)
			(layer "B.Fab")
		)
		(fp_line
			(start -0.67945 -0.3048)
			(end -0.67945 0.3048)
			(stroke
				(width 0.1)
				(type default)
			)
			(layer "B.Fab")
		)
		(fp_line
			(start 0.12065 -0.2794)
			(end -0.12065 -0.2794)
			(stroke
				(width 0.1)
				(type default)
			)
			(layer "B.Fab")
		)
		(fp_line
			(start -0.12065 -0.2794)
			(end -0.12065 -0.3048)
			(stroke
				(width 0.1)
				(type default)
			)
			(layer "B.Fab")
		)
		(fp_line
			(start 0.12065 0.2794)
			(end 0.12065 0.3048)
			(stroke
				(width 0.1)
				(type default)
			)
			(layer "B.Fab")
		)
		(fp_line
			(start -0.120396 0.2794)
			(end 0.12065 0.2794)
			(stroke
				(width 0.1)
				(type default)
			)
			(layer "B.Fab")
		)
		(fp_line
			(start 0.67945 0.3048)
			(end 0.67945 -0.305054)
			(stroke
				(width 0.1)
				(type default)
			)
			(layer "B.Fab")
		)
		(fp_line
			(start 0.12065 0.3048)
			(end 0.67945 0.3048)
			(stroke
				(width 0.1)
				(type default)
			)
			(layer "B.Fab")
		)
		(fp_line
			(start -0.120396 0.3048)
			(end -0.120396 0.2794)
			(stroke
				(width 0.1)
				(type default)
			)
			(layer "B.Fab")
		)
		(fp_line
			(start -0.67945 0.3048)
			(end -0.120396 0.3048)
			(stroke
				(width 0.1)
				(type default)
			)
			(layer "B.Fab")
		)
		(pad "1" smd circle
			(at 0.40005 0 270)
			(size 0 0)
			(layers "B.Cu" "B.Mask" "B.Paste")
			(net "SMB_SML1_PMBUS_3V3AUX_PCH_SCL")
		)
		(pad "2" smd circle
			(at -0.40005 0 270)
			(size 0 0)
			(layers "B.Cu" "B.Mask" "B.Paste")
			(net "SMB_SML1_PMBUS_3V3AUX_PCH_SCL_R")
		)
	)
	(footprint ""
		(layer "B.Cu")
		(at 119.95912 -255.8542 -90)
		(property "Reference" "C335"
			(at 0 0 90)
			(layer "B.SilkS")
			(hide yes)
			(effects
				(font
					(size 1.27 1.27)
				)
				(justify mirror)
			)
		)
		(property "Value" ""
			(at 0 0 90)
			(layer "B.Fab")
			(effects
				(font
					(size 1.27 1.27)
				)
				(justify mirror)
			)
		)
		(duplicate_pad_numbers_are_jumpers no)
		(fp_line
			(start -1.524 0.762)
			(end 1.524 0.762)
			(stroke
				(width 0.1524)
				(type default)
			)
			(layer "B.SilkS")
		)
		(fp_line
			(start 1.524 0.762)
			(end 1.524 -0.762)
			(stroke
				(width 0.1524)
				(type default)
			)
			(layer "B.SilkS")
		)
		(fp_line
			(start -1.524 -0.762)
			(end -1.524 0.762)
			(stroke
				(width 0.1524)
				(type default)
			)
			(layer "B.SilkS")
		)
		(fp_line
			(start 1.524 -0.762)
			(end -1.524 -0.762)
			(stroke
				(width 0.1524)
				(type default)
			)
			(layer "B.SilkS")
		)
		(fp_line
			(start -1.1049 0.724916)
			(end -1.1049 -0.724916)
			(stroke
				(width 0.1)
				(type default)
			)
			(layer "B.Fab")
		)
		(fp_line
			(start 1.1049 0.724916)
			(end -1.1049 0.724916)
			(stroke
				(width 0.1)
				(type default)
			)
			(layer "B.Fab")
		)
		(fp_line
			(start -1.1049 -0.724916)
			(end 1.1049 -0.724916)
			(stroke
				(width 0.1)
				(type default)
			)
			(layer "B.Fab")
		)
		(fp_line
			(start 1.1049 -0.724916)
			(end 1.1049 0.724916)
			(stroke
				(width 0.1)
				(type default)
			)
			(layer "B.Fab")
		)
		(pad "1" smd rect
			(at 0.889 0 270)
			(size 1.016 1.27)
			(layers "B.Cu" "B.Mask" "B.Paste")
			(net "PVCCIN_CPU1")
		)
		(pad "2" smd rect
			(at -0.889 0 270)
			(size 1.016 1.27)
			(layers "B.Cu" "B.Mask" "B.Paste")
			(net "GND")
		)
	)
	(footprint ""
		(layer "B.Cu")
		(at 36.583366 -192.924176 -90)
		(property "Reference" "R816"
			(at 0 0 90)
			(layer "B.SilkS")
			(hide yes)
			(effects
				(font
					(size 1.27 1.27)
				)
				(justify mirror)
			)
		)
		(property "Value" ""
			(at 0 0 90)
			(layer "B.Fab")
			(effects
				(font
					(size 1.27 1.27)
				)
				(justify mirror)
			)
		)
		(duplicate_pad_numbers_are_jumpers no)
		(fp_line
			(start -0.7874 0.4064)
			(end 0.7874 0.4064)
			(stroke
				(width 0.1524)
				(type default)
			)
			(layer "B.SilkS")
		)
		(fp_line
			(start 0.7874 0.4064)
			(end 0.7874 -0.4064)
			(stroke
				(width 0.1524)
				(type default)
			)
			(layer "B.SilkS")
		)
		(fp_line
			(start -0.7874 -0.4064)
			(end -0.7874 0.4064)
			(stroke
				(width 0.1524)
				(type default)
			)
			(layer "B.SilkS")
		)
		(fp_line
			(start 0.7874 -0.4064)
			(end -0.7874 -0.4064)
			(stroke
				(width 0.1524)
				(type default)
			)
			(layer "B.SilkS")
		)
		(fp_line
			(start -0.67945 0.3048)
			(end -0.120396 0.3048)
			(stroke
				(width 0.1)
				(type default)
			)
			(layer "B.Fab")
		)
		(fp_line
			(start -0.120396 0.3048)
			(end -0.120396 0.2794)
			(stroke
				(width 0.1)
				(type default)
			)
			(layer "B.Fab")
		)
		(fp_line
			(start 0.12065 0.3048)
			(end 0.67945 0.3048)
			(stroke
				(width 0.1)
				(type default)
			)
			(layer "B.Fab")
		)
		(fp_line
			(start 0.67945 0.3048)
			(end 0.67945 -0.305054)
			(stroke
				(width 0.1)
				(type default)
			)
			(layer "B.Fab")
		)
		(fp_line
			(start -0.120396 0.2794)
			(end 0.12065 0.2794)
			(stroke
				(width 0.1)
				(type default)
			)
			(layer "B.Fab")
		)
		(fp_line
			(start 0.12065 0.2794)
			(end 0.12065 0.3048)
			(stroke
				(width 0.1)
				(type default)
			)
			(layer "B.Fab")
		)
		(fp_line
			(start -0.12065 -0.2794)
			(end -0.12065 -0.3048)
			(stroke
				(width 0.1)
				(type default)
			)
			(layer "B.Fab")
		)
		(fp_line
			(start 0.12065 -0.2794)
			(end -0.12065 -0.2794)
			(stroke
				(width 0.1)
				(type default)
			)
			(layer "B.Fab")
		)
		(fp_line
			(start -0.67945 -0.3048)
			(end -0.67945 0.3048)
			(stroke
				(width 0.1)
				(type default)
			)
			(layer "B.Fab")
		)
		(fp_line
			(start -0.12065 -0.3048)
			(end -0.67945 -0.3048)
			(stroke
				(width 0.1)
				(type default)
			)
			(layer "B.Fab")
		)
		(fp_line
			(start 0.12065 -0.305054)
			(end 0.12065 -0.2794)
			(stroke
				(width 0.1)
				(type default)
			)
			(layer "B.Fab")
		)
		(fp_line
			(start 0.67945 -0.305054)
			(end 0.12065 -0.305054)
			(stroke
				(width 0.1)
				(type default)
			)
			(layer "B.Fab")
		)
		(pad "1" smd circle
			(at 0.40005 0 90)
			(size 0 0)
			(layers "B.Cu" "B.Mask" "B.Paste")
			(net "RST_PLD_CPU1_DRAM_AB_N")
		)
		(pad "2" smd circle
			(at -0.40005 0 90)
			(size 0 0)
			(layers "B.Cu" "B.Mask" "B.Paste")
			(net "RST_M_AB_CPU1_FPGA_N")
		)
	)
	(footprint ""
		(layer "B.Cu")
		(at 376.468132 -74.614024 180)
		(property "Reference" "PC1240"
			(at 0 0 0)
			(layer "B.SilkS")
			(hide yes)
			(effects
				(font
					(size 1.27 1.27)
				)
				(justify mirror)
			)
		)
		(property "Value" ""
			(at 0 0 0)
			(layer "B.Fab")
			(effects
				(font
					(size 1.27 1.27)
				)
				(justify mirror)
			)
		)
		(duplicate_pad_numbers_are_jumpers no)
		(fp_line
			(start 1.524 0.762)
			(end 1.524 -0.762)
			(stroke
				(width 0.1524)
				(type default)
			)
			(layer "B.SilkS")
		)
		(fp_line
			(start 1.524 -0.762)
			(end -1.524 -0.762)
			(stroke
				(width 0.1524)
				(type default)
			)
			(layer "B.SilkS")
		)
		(fp_line
			(start -1.524 0.762)
			(end 1.524 0.762)
			(stroke
				(width 0.1524)
				(type default)
			)
			(layer "B.SilkS")
		)
		(fp_line
			(start -1.524 -0.762)
			(end -1.524 0.762)
			(stroke
				(width 0.1524)
				(type default)
			)
			(layer "B.SilkS")
		)
		(fp_line
			(start 1.1049 0.724916)
			(end -1.1049 0.724916)
			(stroke
				(width 0.1)
				(type default)
			)
			(layer "B.Fab")
		)
		(fp_line
			(start 1.1049 -0.724916)
			(end 1.1049 0.724916)
			(stroke
				(width 0.1)
				(type default)
			)
			(layer "B.Fab")
		)
		(fp_line
			(start -1.1049 0.724916)
			(end -1.1049 -0.724916)
			(stroke
				(width 0.1)
				(type default)
			)
			(layer "B.Fab")
		)
		(fp_line
			(start -1.1049 -0.724916)
			(end 1.1049 -0.724916)
			(stroke
				(width 0.1)
				(type default)
			)
			(layer "B.Fab")
		)
		(pad "1" smd rect
			(at 0.889 0 180)
			(size 1.016 1.27)
			(layers "B.Cu" "B.Mask" "B.Paste")
			(net "P1V8_PCH_AUX")
		)
		(pad "2" smd rect
			(at -0.889 0 180)
			(size 1.016 1.27)
			(layers "B.Cu" "B.Mask" "B.Paste")
			(net "GND")
		)
	)
	(footprint ""
		(layer "B.Cu")
		(at 110.051596 -324.792086 -90)
		(property "Reference" "PC544_P1_3"
			(at 0 0 90)
			(layer "B.SilkS")
			(hide yes)
			(effects
				(font
					(size 1.27 1.27)
				)
				(justify mirror)
			)
		)
		(property "Value" ""
			(at 0 0 90)
			(layer "B.Fab")
			(effects
				(font
					(size 1.27 1.27)
				)
				(justify mirror)
			)
		)
		(duplicate_pad_numbers_are_jumpers no)
		(fp_line
			(start -1.524 0.762)
			(end 1.524 0.762)
			(stroke
				(width 0.1524)
				(type default)
			)
			(layer "B.SilkS")
		)
		(fp_line
			(start 1.524 0.762)
			(end 1.524 -0.762)
			(stroke
				(width 0.1524)
				(type default)
			)
			(layer "B.SilkS")
		)
		(fp_line
			(start -1.524 -0.762)
			(end -1.524 0.762)
			(stroke
				(width 0.1524)
				(type default)
			)
			(layer "B.SilkS")
		)
		(fp_line
			(start 1.524 -0.762)
			(end -1.524 -0.762)
			(stroke
				(width 0.1524)
				(type default)
			)
			(layer "B.SilkS")
		)
		(fp_line
			(start -1.1049 0.724916)
			(end -1.1049 -0.724916)
			(stroke
				(width 0.1)
				(type default)
			)
			(layer "B.Fab")
		)
		(fp_line
			(start 1.1049 0.724916)
			(end -1.1049 0.724916)
			(stroke
				(width 0.1)
				(type default)
			)
			(layer "B.Fab")
		)
		(fp_line
			(start -1.1049 -0.724916)
			(end 1.1049 -0.724916)
			(stroke
				(width 0.1)
				(type default)
			)
			(layer "B.Fab")
		)
		(fp_line
			(start 1.1049 -0.724916)
			(end 1.1049 0.724916)
			(stroke
				(width 0.1)
				(type default)
			)
			(layer "B.Fab")
		)
		(pad "1" smd rect
			(at 0.889 0 270)
			(size 1.016 1.27)
			(layers "B.Cu" "B.Mask" "B.Paste")
			(net "PVCCIN_CPU1")
		)
		(pad "2" smd rect
			(at -0.889 0 270)
			(size 1.016 1.27)
			(layers "B.Cu" "B.Mask" "B.Paste")
			(net "GND")
		)
	)
	(footprint ""
		(layer "B.Cu")
		(at 289.988498 -403.031452 90)
		(property "Reference" "PR2516"
			(at 0 0 90)
			(layer "B.SilkS")
			(hide yes)
			(effects
				(font
					(size 1.27 1.27)
				)
				(justify mirror)
			)
		)
		(property "Value" ""
			(at 0 0 90)
			(layer "B.Fab")
			(effects
				(font
					(size 1.27 1.27)
				)
				(justify mirror)
			)
		)
		(duplicate_pad_numbers_are_jumpers no)
		(fp_line
			(start 0.7874 -0.4064)
			(end -0.7874 -0.4064)
			(stroke
				(width 0.1524)
				(type default)
			)
			(layer "B.SilkS")
		)
		(fp_line
			(start -0.7874 -0.4064)
			(end -0.7874 0.4064)
			(stroke
				(width 0.1524)
				(type default)
			)
			(layer "B.SilkS")
		)
		(fp_line
			(start 0.7874 0.4064)
			(end 0.7874 -0.4064)
			(stroke
				(width 0.1524)
				(type default)
			)
			(layer "B.SilkS")
		)
		(fp_line
			(start -0.7874 0.4064)
			(end 0.7874 0.4064)
			(stroke
				(width 0.1524)
				(type default)
			)
			(layer "B.SilkS")
		)
		(fp_line
			(start 0.67945 -0.305054)
			(end 0.12065 -0.305054)
			(stroke
				(width 0.1)
				(type default)
			)
			(layer "B.Fab")
		)
		(fp_line
			(start 0.12065 -0.305054)
			(end 0.12065 -0.2794)
			(stroke
				(width 0.1)
				(type default)
			)
			(layer "B.Fab")
		)
		(fp_line
			(start -0.12065 -0.3048)
			(end -0.67945 -0.3048)
			(stroke
				(width 0.1)
				(type default)
			)
			(layer "B.Fab")
		)
		(fp_line
			(start -0.67945 -0.3048)
			(end -0.67945 0.3048)
			(stroke
				(width 0.1)
				(type default)
			)
			(layer "B.Fab")
		)
		(fp_line
			(start 0.12065 -0.2794)
			(end -0.12065 -0.2794)
			(stroke
				(width 0.1)
				(type default)
			)
			(layer "B.Fab")
		)
		(fp_line
			(start -0.12065 -0.2794)
			(end -0.12065 -0.3048)
			(stroke
				(width 0.1)
				(type default)
			)
			(layer "B.Fab")
		)
		(fp_line
			(start 0.12065 0.2794)
			(end 0.12065 0.3048)
			(stroke
				(width 0.1)
				(type default)
			)
			(layer "B.Fab")
		)
		(fp_line
			(start -0.120396 0.2794)
			(end 0.12065 0.2794)
			(stroke
				(width 0.1)
				(type default)
			)
			(layer "B.Fab")
		)
		(fp_line
			(start 0.67945 0.3048)
			(end 0.67945 -0.305054)
			(stroke
				(width 0.1)
				(type default)
			)
			(layer "B.Fab")
		)
		(fp_line
			(start 0.12065 0.3048)
			(end 0.67945 0.3048)
			(stroke
				(width 0.1)
				(type default)
			)
			(layer "B.Fab")
		)
		(fp_line
			(start -0.120396 0.3048)
			(end -0.120396 0.2794)
			(stroke
				(width 0.1)
				(type default)
			)
			(layer "B.Fab")
		)
		(fp_line
			(start -0.67945 0.3048)
			(end -0.120396 0.3048)
			(stroke
				(width 0.1)
				(type default)
			)
			(layer "B.Fab")
		)
		(pad "1" smd circle
			(at 0.40005 0 270)
			(size 0 0)
			(layers "B.Cu" "B.Mask" "B.Paste")
			(net "P12V_HSC_ADC_N")
		)
		(pad "2" smd circle
			(at -0.40005 0 270)
			(size 0 0)
			(layers "B.Cu" "B.Mask" "B.Paste")
			(net "P12V_HSC_SENSE2_R2_N")
		)
	)
	(footprint ""
		(layer "B.Cu")
		(at 331.540358 -190.82893 90)
		(property "Reference" "R24"
			(at 0 0 90)
			(layer "B.SilkS")
			(hide yes)
			(effects
				(font
					(size 1.27 1.27)
				)
				(justify mirror)
			)
		)
		(property "Value" ""
			(at 0 0 90)
			(layer "B.Fab")
			(effects
				(font
					(size 1.27 1.27)
				)
				(justify mirror)
			)
		)
		(duplicate_pad_numbers_are_jumpers no)
		(fp_line
			(start 0.7874 -0.4064)
			(end -0.7874 -0.4064)
			(stroke
				(width 0.1524)
				(type default)
			)
			(layer "B.SilkS")
		)
		(fp_line
			(start -0.7874 -0.4064)
			(end -0.7874 0.4064)
			(stroke
				(width 0.1524)
				(type default)
			)
			(layer "B.SilkS")
		)
		(fp_line
			(start 0.7874 0.4064)
			(end 0.7874 -0.4064)
			(stroke
				(width 0.1524)
				(type default)
			)
			(layer "B.SilkS")
		)
		(fp_line
			(start -0.7874 0.4064)
			(end 0.7874 0.4064)
			(stroke
				(width 0.1524)
				(type default)
			)
			(layer "B.SilkS")
		)
		(fp_line
			(start 0.67945 -0.305054)
			(end 0.12065 -0.305054)
			(stroke
				(width 0.1)
				(type default)
			)
			(layer "B.Fab")
		)
		(fp_line
			(start 0.12065 -0.305054)
			(end 0.12065 -0.2794)
			(stroke
				(width 0.1)
				(type default)
			)
			(layer "B.Fab")
		)
		(fp_line
			(start -0.12065 -0.3048)
			(end -0.67945 -0.3048)
			(stroke
				(width 0.1)
				(type default)
			)
			(layer "B.Fab")
		)
		(fp_line
			(start -0.67945 -0.3048)
			(end -0.67945 0.3048)
			(stroke
				(width 0.1)
				(type default)
			)
			(layer "B.Fab")
		)
		(fp_line
			(start 0.12065 -0.2794)
			(end -0.12065 -0.2794)
			(stroke
				(width 0.1)
				(type default)
			)
			(layer "B.Fab")
		)
		(fp_line
			(start -0.12065 -0.2794)
			(end -0.12065 -0.3048)
			(stroke
				(width 0.1)
				(type default)
			)
			(layer "B.Fab")
		)
		(fp_line
			(start 0.12065 0.2794)
			(end 0.12065 0.3048)
			(stroke
				(width 0.1)
				(type default)
			)
			(layer "B.Fab")
		)
		(fp_line
			(start -0.120396 0.2794)
			(end 0.12065 0.2794)
			(stroke
				(width 0.1)
				(type default)
			)
			(layer "B.Fab")
		)
		(fp_line
			(start 0.67945 0.3048)
			(end 0.67945 -0.305054)
			(stroke
				(width 0.1)
				(type default)
			)
			(layer "B.Fab")
		)
		(fp_line
			(start 0.12065 0.3048)
			(end 0.67945 0.3048)
			(stroke
				(width 0.1)
				(type default)
			)
			(layer "B.Fab")
		)
		(fp_line
			(start -0.120396 0.3048)
			(end -0.120396 0.2794)
			(stroke
				(width 0.1)
				(type default)
			)
			(layer "B.Fab")
		)
		(fp_line
			(start -0.67945 0.3048)
			(end -0.120396 0.3048)
			(stroke
				(width 0.1)
				(type default)
			)
			(layer "B.Fab")
		)
		(pad "1" smd circle
			(at 0.40005 0 270)
			(size 0 0)
			(layers "B.Cu" "B.Mask" "B.Paste")
			(net "DBP_CPU0_HOOK8_MBP2_GTL_QS_R_N")
		)
		(pad "2" smd circle
			(at -0.40005 0 270)
			(size 0 0)
			(layers "B.Cu" "B.Mask" "B.Paste")
			(net "DBP_CPU_HOOK8_MBP2_GTL_QS_N")
		)
	)
	(footprint ""
		(layer "B.Cu")
		(at 180.555646 -115.775486 90)
		(property "Reference" "C1906"
			(at 0 0 90)
			(layer "B.SilkS")
			(hide yes)
			(effects
				(font
					(size 1.27 1.27)
				)
				(justify mirror)
			)
		)
		(property "Value" ""
			(at 0 0 90)
			(layer "B.Fab")
			(effects
				(font
					(size 1.27 1.27)
				)
				(justify mirror)
			)
		)
		(duplicate_pad_numbers_are_jumpers no)
		(fp_line
			(start 0.69215 -0.2921)
			(end -0.69215 -0.2921)
			(stroke
				(width 0.1524)
				(type default)
			)
			(layer "B.SilkS")
		)
		(fp_line
			(start -0.69215 -0.2921)
			(end -0.69215 0.2921)
			(stroke
				(width 0.1524)
				(type default)
			)
			(layer "B.SilkS")
		)
		(fp_line
			(start 0.69215 0.2921)
			(end 0.69215 -0.2921)
			(stroke
				(width 0.1524)
				(type default)
			)
			(layer "B.SilkS")
		)
		(fp_line
			(start -0.69215 0.2921)
			(end 0.69215 0.2921)
			(stroke
				(width 0.1524)
				(type default)
			)
			(layer "B.SilkS")
		)
		(fp_line
			(start 0.51435 -0.2794)
			(end -0.51435 -0.2794)
			(stroke
				(width 0.1)
				(type default)
			)
			(layer "B.Fab")
		)
		(fp_line
			(start -0.51435 -0.2794)
			(end -0.51435 0.2794)
			(stroke
				(width 0.1)
				(type default)
			)
			(layer "B.Fab")
		)
		(fp_line
			(start 0.51435 0.2794)
			(end 0.51435 -0.2794)
			(stroke
				(width 0.1)
				(type default)
			)
			(layer "B.Fab")
		)
		(fp_line
			(start -0.51435 0.2794)
			(end 0.51435 0.2794)
			(stroke
				(width 0.1)
				(type default)
			)
			(layer "B.Fab")
		)
		(pad "1" smd circle
			(at 0.40005 0 270)
			(size 0 0)
			(layers "B.Cu" "B.Mask" "B.Paste")
			(net "P3V3_AUX_FPGA_VCCIO1")
		)
		(pad "2" smd circle
			(at -0.40005 0 270)
			(size 0 0)
			(layers "B.Cu" "B.Mask" "B.Paste")
			(net "GND")
		)
		(zone
			(layer "B.Cu")
			(hatch none 0.5)
			(connect_pads
				(clearance 0)
			)
			(min_thickness 0.25)
			(keepout
				(tracks not_allowed)
				(vias allowed)
				(pads allowed)
				(copperpour not_allowed)
				(footprints allowed)
			)
			(placement
				(enabled no)
				(sheetname "")
			)
			(fill
				(thermal_gap 0.5)
				(thermal_bridge_width 0.5)
				(island_removal_mode 0)
			)
			(polygon
				(pts
					(xy 180.643276 -115.965986) (xy 180.701442 -115.874546) (xy 180.701442 -115.675156) (xy 180.643276 -115.584986)
					(xy 180.468016 -115.584986) (xy 180.409596 -115.675156) (xy 180.409596 -115.874546) (xy 180.467762 -115.965986)
				)
			)
		)
	)
	(footprint ""
		(layer "B.Cu")
		(at 73.902062 -181.81955 90)
		(property "Reference" "R299"
			(at 0 0 90)
			(layer "B.SilkS")
			(hide yes)
			(effects
				(font
					(size 1.27 1.27)
				)
				(justify mirror)
			)
		)
		(property "Value" ""
			(at 0 0 90)
			(layer "B.Fab")
			(effects
				(font
					(size 1.27 1.27)
				)
				(justify mirror)
			)
		)
		(duplicate_pad_numbers_are_jumpers no)
		(fp_line
			(start 0.7874 -0.4064)
			(end -0.7874 -0.4064)
			(stroke
				(width 0.1524)
				(type default)
			)
			(layer "B.SilkS")
		)
		(fp_line
			(start -0.7874 -0.4064)
			(end -0.7874 0.4064)
			(stroke
				(width 0.1524)
				(type default)
			)
			(layer "B.SilkS")
		)
		(fp_line
			(start 0.7874 0.4064)
			(end 0.7874 -0.4064)
			(stroke
				(width 0.1524)
				(type default)
			)
			(layer "B.SilkS")
		)
		(fp_line
			(start -0.7874 0.4064)
			(end 0.7874 0.4064)
			(stroke
				(width 0.1524)
				(type default)
			)
			(layer "B.SilkS")
		)
		(fp_line
			(start 0.67945 -0.305054)
			(end 0.12065 -0.305054)
			(stroke
				(width 0.1)
				(type default)
			)
			(layer "B.Fab")
		)
		(fp_line
			(start 0.12065 -0.305054)
			(end 0.12065 -0.2794)
			(stroke
				(width 0.1)
				(type default)
			)
			(layer "B.Fab")
		)
		(fp_line
			(start -0.12065 -0.3048)
			(end -0.67945 -0.3048)
			(stroke
				(width 0.1)
				(type default)
			)
			(layer "B.Fab")
		)
		(fp_line
			(start -0.67945 -0.3048)
			(end -0.67945 0.3048)
			(stroke
				(width 0.1)
				(type default)
			)
			(layer "B.Fab")
		)
		(fp_line
			(start 0.12065 -0.2794)
			(end -0.12065 -0.2794)
			(stroke
				(width 0.1)
				(type default)
			)
			(layer "B.Fab")
		)
		(fp_line
			(start -0.12065 -0.2794)
			(end -0.12065 -0.3048)
			(stroke
				(width 0.1)
				(type default)
			)
			(layer "B.Fab")
		)
		(fp_line
			(start 0.12065 0.2794)
			(end 0.12065 0.3048)
			(stroke
				(width 0.1)
				(type default)
			)
			(layer "B.Fab")
		)
		(fp_line
			(start -0.120396 0.2794)
			(end 0.12065 0.2794)
			(stroke
				(width 0.1)
				(type default)
			)
			(layer "B.Fab")
		)
		(fp_line
			(start 0.67945 0.3048)
			(end 0.67945 -0.305054)
			(stroke
				(width 0.1)
				(type default)
			)
			(layer "B.Fab")
		)
		(fp_line
			(start 0.12065 0.3048)
			(end 0.67945 0.3048)
			(stroke
				(width 0.1)
				(type default)
			)
			(layer "B.Fab")
		)
		(fp_line
			(start -0.120396 0.3048)
			(end -0.120396 0.2794)
			(stroke
				(width 0.1)
				(type default)
			)
			(layer "B.Fab")
		)
		(fp_line
			(start -0.67945 0.3048)
			(end -0.120396 0.3048)
			(stroke
				(width 0.1)
				(type default)
			)
			(layer "B.Fab")
		)
		(pad "1" smd circle
			(at 0.40005 0 270)
			(size 0 0)
			(layers "B.Cu" "B.Mask" "B.Paste")
			(net "H_CPU1_CATERR_LVC1_R_N")
		)
		(pad "2" smd circle
			(at -0.40005 0 270)
			(size 0 0)
			(layers "B.Cu" "B.Mask" "B.Paste")
			(net "H_CPU_CATERR_LVC1_R_N")
		)
	)
	(footprint ""
		(layer "B.Cu")
		(at 213.841838 -195.58635)
		(property "Reference" "C544"
			(at 0 0 0)
			(layer "B.SilkS")
			(hide yes)
			(effects
				(font
					(size 1.27 1.27)
				)
				(justify mirror)
			)
		)
		(property "Value" ""
			(at 0 0 0)
			(layer "B.Fab")
			(effects
				(font
					(size 1.27 1.27)
				)
				(justify mirror)
			)
		)
		(duplicate_pad_numbers_are_jumpers no)
		(fp_line
			(start -0.7874 -0.4064)
			(end -0.7874 0.4064)
			(stroke
				(width 0.1524)
				(type default)
			)
			(layer "B.SilkS")
		)
		(fp_line
			(start -0.7874 0.4064)
			(end 0.7874 0.4064)
			(stroke
				(width 0.1524)
				(type default)
			)
			(layer "B.SilkS")
		)
		(fp_line
			(start 0.7874 -0.4064)
			(end -0.7874 -0.4064)
			(stroke
				(width 0.1524)
				(type default)
			)
			(layer "B.SilkS")
		)
		(fp_line
			(start 0.7874 0.4064)
			(end 0.7874 -0.4064)
			(stroke
				(width 0.1524)
				(type default)
			)
			(layer "B.SilkS")
		)
		(fp_line
			(start -0.67945 -0.3048)
			(end -0.67945 0.3048)
			(stroke
				(width 0.1)
				(type default)
			)
			(layer "B.Fab")
		)
		(fp_line
			(start -0.67945 0.3048)
			(end -0.120396 0.3048)
			(stroke
				(width 0.1)
				(type default)
			)
			(layer "B.Fab")
		)
		(fp_line
			(start -0.12065 -0.3048)
			(end -0.67945 -0.3048)
			(stroke
				(width 0.1)
				(type default)
			)
			(layer "B.Fab")
		)
		(fp_line
			(start -0.12065 -0.2794)
			(end -0.12065 -0.3048)
			(stroke
				(width 0.1)
				(type default)
			)
			(layer "B.Fab")
		)
		(fp_line
			(start -0.120396 0.2794)
			(end 0.12065 0.2794)
			(stroke
				(width 0.1)
				(type default)
			)
			(layer "B.Fab")
		)
		(fp_line
			(start -0.120396 0.3048)
			(end -0.120396 0.2794)
			(stroke
				(width 0.1)
				(type default)
			)
			(layer "B.Fab")
		)
		(fp_line
			(start 0.12065 -0.305054)
			(end 0.12065 -0.2794)
			(stroke
				(width 0.1)
				(type default)
			)
			(layer "B.Fab")
		)
		(fp_line
			(start 0.12065 -0.2794)
			(end -0.12065 -0.2794)
			(stroke
				(width 0.1)
				(type default)
			)
			(layer "B.Fab")
		)
		(fp_line
			(start 0.12065 0.2794)
			(end 0.12065 0.3048)
			(stroke
				(width 0.1)
				(type default)
			)
			(layer "B.Fab")
		)
		(fp_line
			(start 0.12065 0.3048)
			(end 0.67945 0.3048)
			(stroke
				(width 0.1)
				(type default)
			)
			(layer "B.Fab")
		)
		(fp_line
			(start 0.67945 -0.305054)
			(end 0.12065 -0.305054)
			(stroke
				(width 0.1)
				(type default)
			)
			(layer "B.Fab")
		)
		(fp_line
			(start 0.67945 0.3048)
			(end 0.67945 -0.305054)
			(stroke
				(width 0.1)
				(type default)
			)
			(layer "B.Fab")
		)
		(pad "1" smd circle
			(at 0.40005 0 180)
			(size 0 0)
			(layers "B.Cu" "B.Mask" "B.Paste")
			(net "P3V3_AUX")
		)
		(pad "2" smd circle
			(at -0.40005 0 180)
			(size 0 0)
			(layers "B.Cu" "B.Mask" "B.Paste")
			(net "GND")
		)
	)
	(footprint ""
		(layer "B.Cu")
		(at 230.48468 -118.760748 -90)
		(property "Reference" "R3636"
			(at 0 0 90)
			(layer "B.SilkS")
			(hide yes)
			(effects
				(font
					(size 1.27 1.27)
				)
				(justify mirror)
			)
		)
		(property "Value" ""
			(at 0 0 90)
			(layer "B.Fab")
			(effects
				(font
					(size 1.27 1.27)
				)
				(justify mirror)
			)
		)
		(duplicate_pad_numbers_are_jumpers no)
		(fp_line
			(start -0.7874 0.4064)
			(end 0.7874 0.4064)
			(stroke
				(width 0.1524)
				(type default)
			)
			(layer "B.SilkS")
		)
		(fp_line
			(start 0.7874 0.4064)
			(end 0.7874 -0.4064)
			(stroke
				(width 0.1524)
				(type default)
			)
			(layer "B.SilkS")
		)
		(fp_line
			(start -0.7874 -0.4064)
			(end -0.7874 0.4064)
			(stroke
				(width 0.1524)
				(type default)
			)
			(layer "B.SilkS")
		)
		(fp_line
			(start 0.7874 -0.4064)
			(end -0.7874 -0.4064)
			(stroke
				(width 0.1524)
				(type default)
			)
			(layer "B.SilkS")
		)
		(fp_line
			(start -0.67945 0.3048)
			(end -0.120396 0.3048)
			(stroke
				(width 0.1)
				(type default)
			)
			(layer "B.Fab")
		)
		(fp_line
			(start -0.120396 0.3048)
			(end -0.120396 0.2794)
			(stroke
				(width 0.1)
				(type default)
			)
			(layer "B.Fab")
		)
		(fp_line
			(start 0.12065 0.3048)
			(end 0.67945 0.3048)
			(stroke
				(width 0.1)
				(type default)
			)
			(layer "B.Fab")
		)
		(fp_line
			(start 0.67945 0.3048)
			(end 0.67945 -0.305054)
			(stroke
				(width 0.1)
				(type default)
			)
			(layer "B.Fab")
		)
		(fp_line
			(start -0.120396 0.2794)
			(end 0.12065 0.2794)
			(stroke
				(width 0.1)
				(type default)
			)
			(layer "B.Fab")
		)
		(fp_line
			(start 0.12065 0.2794)
			(end 0.12065 0.3048)
			(stroke
				(width 0.1)
				(type default)
			)
			(layer "B.Fab")
		)
		(fp_line
			(start -0.12065 -0.2794)
			(end -0.12065 -0.3048)
			(stroke
				(width 0.1)
				(type default)
			)
			(layer "B.Fab")
		)
		(fp_line
			(start 0.12065 -0.2794)
			(end -0.12065 -0.2794)
			(stroke
				(width 0.1)
				(type default)
			)
			(layer "B.Fab")
		)
		(fp_line
			(start -0.67945 -0.3048)
			(end -0.67945 0.3048)
			(stroke
				(width 0.1)
				(type default)
			)
			(layer "B.Fab")
		)
		(fp_line
			(start -0.12065 -0.3048)
			(end -0.67945 -0.3048)
			(stroke
				(width 0.1)
				(type default)
			)
			(layer "B.Fab")
		)
		(fp_line
			(start 0.12065 -0.305054)
			(end 0.12065 -0.2794)
			(stroke
				(width 0.1)
				(type default)
			)
			(layer "B.Fab")
		)
		(fp_line
			(start 0.67945 -0.305054)
			(end 0.12065 -0.305054)
			(stroke
				(width 0.1)
				(type default)
			)
			(layer "B.Fab")
		)
		(pad "1" smd circle
			(at 0.40005 0 90)
			(size 0 0)
			(layers "B.Cu" "B.Mask" "B.Paste")
			(net "OCP_SFF_CLK_OE_N")
		)
		(pad "2" smd circle
			(at -0.40005 0 90)
			(size 0 0)
			(layers "B.Cu" "B.Mask" "B.Paste")
			(net "FM_DB2000_11_OE_N")
		)
	)
	(footprint ""
		(layer "B.Cu")
		(at 197.437502 -109.89691 180)
		(property "Reference" "R1388"
			(at 0 0 0)
			(layer "B.SilkS")
			(hide yes)
			(effects
				(font
					(size 1.27 1.27)
				)
				(justify mirror)
			)
		)
		(property "Value" ""
			(at 0 0 0)
			(layer "B.Fab")
			(effects
				(font
					(size 1.27 1.27)
				)
				(justify mirror)
			)
		)
		(duplicate_pad_numbers_are_jumpers no)
		(fp_line
			(start 0.7874 0.4064)
			(end 0.7874 -0.4064)
			(stroke
				(width 0.1524)
				(type default)
			)
			(layer "B.SilkS")
		)
		(fp_line
			(start 0.7874 -0.4064)
			(end -0.7874 -0.4064)
			(stroke
				(width 0.1524)
				(type default)
			)
			(layer "B.SilkS")
		)
		(fp_line
			(start -0.7874 0.4064)
			(end 0.7874 0.4064)
			(stroke
				(width 0.1524)
				(type default)
			)
			(layer "B.SilkS")
		)
		(fp_line
			(start -0.7874 -0.4064)
			(end -0.7874 0.4064)
			(stroke
				(width 0.1524)
				(type default)
			)
			(layer "B.SilkS")
		)
		(fp_line
			(start 0.67945 0.3048)
			(end 0.67945 -0.305054)
			(stroke
				(width 0.1)
				(type default)
			)
			(layer "B.Fab")
		)
		(fp_line
			(start 0.67945 -0.305054)
			(end 0.12065 -0.305054)
			(stroke
				(width 0.1)
				(type default)
			)
			(layer "B.Fab")
		)
		(fp_line
			(start 0.12065 0.3048)
			(end 0.67945 0.3048)
			(stroke
				(width 0.1)
				(type default)
			)
			(layer "B.Fab")
		)
		(fp_line
			(start 0.12065 0.2794)
			(end 0.12065 0.3048)
			(stroke
				(width 0.1)
				(type default)
			)
			(layer "B.Fab")
		)
		(fp_line
			(start 0.12065 -0.2794)
			(end -0.12065 -0.2794)
			(stroke
				(width 0.1)
				(type default)
			)
			(layer "B.Fab")
		)
		(fp_line
			(start 0.12065 -0.305054)
			(end 0.12065 -0.2794)
			(stroke
				(width 0.1)
				(type default)
			)
			(layer "B.Fab")
		)
		(fp_line
			(start -0.120396 0.3048)
			(end -0.120396 0.2794)
			(stroke
				(width 0.1)
				(type default)
			)
			(layer "B.Fab")
		)
		(fp_line
			(start -0.120396 0.2794)
			(end 0.12065 0.2794)
			(stroke
				(width 0.1)
				(type default)
			)
			(layer "B.Fab")
		)
		(fp_line
			(start -0.12065 -0.2794)
			(end -0.12065 -0.3048)
			(stroke
				(width 0.1)
				(type default)
			)
			(layer "B.Fab")
		)
		(fp_line
			(start -0.12065 -0.3048)
			(end -0.67945 -0.3048)
			(stroke
				(width 0.1)
				(type default)
			)
			(layer "B.Fab")
		)
		(fp_line
			(start -0.67945 0.3048)
			(end -0.120396 0.3048)
			(stroke
				(width 0.1)
				(type default)
			)
			(layer "B.Fab")
		)
		(fp_line
			(start -0.67945 -0.3048)
			(end -0.67945 0.3048)
			(stroke
				(width 0.1)
				(type default)
			)
			(layer "B.Fab")
		)
		(pad "1" smd circle
			(at 0.40005 0)
			(size 0 0)
			(layers "B.Cu" "B.Mask" "B.Paste")
			(net "PWRGD_DRAMPWRGD_CPU1_EF_R_LVC1")
		)
		(pad "2" smd circle
			(at -0.40005 0)
			(size 0 0)
			(layers "B.Cu" "B.Mask" "B.Paste")
			(net "GND")
		)
	)
	(footprint ""
		(layer "B.Cu")
		(at 160.83788 -117.566948)
		(property "Reference" "R920"
			(at 0 0 0)
			(layer "B.SilkS")
			(hide yes)
			(effects
				(font
					(size 1.27 1.27)
				)
				(justify mirror)
			)
		)
		(property "Value" ""
			(at 0 0 0)
			(layer "B.Fab")
			(effects
				(font
					(size 1.27 1.27)
				)
				(justify mirror)
			)
		)
		(duplicate_pad_numbers_are_jumpers no)
		(fp_line
			(start -0.7874 -0.4064)
			(end -0.7874 0.4064)
			(stroke
				(width 0.1524)
				(type default)
			)
			(layer "B.SilkS")
		)
		(fp_line
			(start -0.7874 0.4064)
			(end 0.7874 0.4064)
			(stroke
				(width 0.1524)
				(type default)
			)
			(layer "B.SilkS")
		)
		(fp_line
			(start 0.7874 -0.4064)
			(end -0.7874 -0.4064)
			(stroke
				(width 0.1524)
				(type default)
			)
			(layer "B.SilkS")
		)
		(fp_line
			(start 0.7874 0.4064)
			(end 0.7874 -0.4064)
			(stroke
				(width 0.1524)
				(type default)
			)
			(layer "B.SilkS")
		)
		(fp_line
			(start -0.67945 -0.3048)
			(end -0.67945 0.3048)
			(stroke
				(width 0.1)
				(type default)
			)
			(layer "B.Fab")
		)
		(fp_line
			(start -0.67945 0.3048)
			(end -0.120396 0.3048)
			(stroke
				(width 0.1)
				(type default)
			)
			(layer "B.Fab")
		)
		(fp_line
			(start -0.12065 -0.3048)
			(end -0.67945 -0.3048)
			(stroke
				(width 0.1)
				(type default)
			)
			(layer "B.Fab")
		)
		(fp_line
			(start -0.12065 -0.2794)
			(end -0.12065 -0.3048)
			(stroke
				(width 0.1)
				(type default)
			)
			(layer "B.Fab")
		)
		(fp_line
			(start -0.120396 0.2794)
			(end 0.12065 0.2794)
			(stroke
				(width 0.1)
				(type default)
			)
			(layer "B.Fab")
		)
		(fp_line
			(start -0.120396 0.3048)
			(end -0.120396 0.2794)
			(stroke
				(width 0.1)
				(type default)
			)
			(layer "B.Fab")
		)
		(fp_line
			(start 0.12065 -0.305054)
			(end 0.12065 -0.2794)
			(stroke
				(width 0.1)
				(type default)
			)
			(layer "B.Fab")
		)
		(fp_line
			(start 0.12065 -0.2794)
			(end -0.12065 -0.2794)
			(stroke
				(width 0.1)
				(type default)
			)
			(layer "B.Fab")
		)
		(fp_line
			(start 0.12065 0.2794)
			(end 0.12065 0.3048)
			(stroke
				(width 0.1)
				(type default)
			)
			(layer "B.Fab")
		)
		(fp_line
			(start 0.12065 0.3048)
			(end 0.67945 0.3048)
			(stroke
				(width 0.1)
				(type default)
			)
			(layer "B.Fab")
		)
		(fp_line
			(start 0.67945 -0.305054)
			(end 0.12065 -0.305054)
			(stroke
				(width 0.1)
				(type default)
			)
			(layer "B.Fab")
		)
		(fp_line
			(start 0.67945 0.3048)
			(end 0.67945 -0.305054)
			(stroke
				(width 0.1)
				(type default)
			)
			(layer "B.Fab")
		)
		(pad "1" smd circle
			(at 0.40005 0 180)
			(size 0 0)
			(layers "B.Cu" "B.Mask" "B.Paste")
			(net "JTAG_PLD_JTAGEN")
		)
		(pad "2" smd circle
			(at -0.40005 0 180)
			(size 0 0)
			(layers "B.Cu" "B.Mask" "B.Paste")
			(net "GND")
		)
	)
	(footprint ""
		(layer "B.Cu")
		(at 129.545588 -329.921616 -90)
		(property "Reference" "PC587"
			(at 0 0 90)
			(layer "B.SilkS")
			(hide yes)
			(effects
				(font
					(size 1.27 1.27)
				)
				(justify mirror)
			)
		)
		(property "Value" ""
			(at 0 0 90)
			(layer "B.Fab")
			(effects
				(font
					(size 1.27 1.27)
				)
				(justify mirror)
			)
		)
		(duplicate_pad_numbers_are_jumpers no)
		(fp_line
			(start -4.533392 2.249932)
			(end 4.533392 2.249932)
			(stroke
				(width 0.1524)
				(type default)
			)
			(layer "B.SilkS")
		)
		(fp_line
			(start 4.533392 2.249932)
			(end 4.533392 -2.249932)
			(stroke
				(width 0.1524)
				(type default)
			)
			(layer "B.SilkS")
		)
		(fp_line
			(start -4.533392 -2.249932)
			(end -4.533392 2.249932)
			(stroke
				(width 0.1524)
				(type default)
			)
			(layer "B.SilkS")
		)
		(fp_line
			(start 4.533392 -2.249932)
			(end -4.533392 -2.249932)
			(stroke
				(width 0.1524)
				(type default)
			)
			(layer "B.SilkS")
		)
		(fp_rect
			(start 5.39242 2.326132)
			(end 4.533392 -2.326132)
			(stroke
				(width 0)
				(type default)
			)
			(fill yes)
			(layer "B.SilkS")
		)
		(fp_line
			(start -3.750056 2.249932)
			(end 3.750056 2.249932)
			(stroke
				(width 0.1)
				(type default)
			)
			(layer "B.Fab")
		)
		(fp_line
			(start 3.750056 2.249932)
			(end 3.750056 -2.249932)
			(stroke
				(width 0.1)
				(type default)
			)
			(layer "B.Fab")
		)
		(fp_line
			(start -3.750056 -2.249932)
			(end -3.750056 2.249932)
			(stroke
				(width 0.1)
				(type default)
			)
			(layer "B.Fab")
		)
		(fp_line
			(start 3.750056 -2.249932)
			(end -3.750056 -2.249932)
			(stroke
				(width 0.1)
				(type default)
			)
			(layer "B.Fab")
		)
		(fp_text user "-"
			(at -4.507992 1.355598 270)
			(unlocked yes)
			(layer "B.SilkS")
			(effects
				(font
					(size 1.905 1.4224)
					(thickness 0.1524)
				)
				(justify left mirror)
			)
		)
		(fp_text user "+"
			(at 6.322314 0.786384 180)
			(unlocked yes)
			(layer "B.SilkS")
			(effects
				(font
					(size 1.905 1.4224)
					(thickness 0.1524)
				)
				(justify left mirror)
			)
		)
		(fp_text user "+"
			(at 6.322314 0.786384 180)
			(unlocked yes)
			(layer "B.Fab")
			(effects
				(font
					(size 1.905 1.4224)
					(thickness 0.1524)
				)
				(justify left mirror)
			)
		)
		(fp_text user "-"
			(at -4.8514 -0.14605 270)
			(unlocked yes)
			(layer "B.Fab")
			(effects
				(font
					(size 1.905 1.4224)
					(thickness 0.1524)
				)
				(justify left mirror)
			)
		)
		(pad "1" smd rect
			(at 3.199892 0 90)
			(size 2.413 2.8194)
			(layers "B.Cu" "B.Mask" "B.Paste")
			(net "PVCCIN_CPU1")
		)
		(pad "2" smd rect
			(at -3.199892 0 90)
			(size 2.413 2.8194)
			(layers "B.Cu" "B.Mask" "B.Paste")
			(net "GND")
		)
	)
	(footprint ""
		(layer "B.Cu")
		(at 286.2834 -363.79277 -90)
		(property "Reference" "PR1300"
			(at 0 0 90)
			(layer "B.SilkS")
			(hide yes)
			(effects
				(font
					(size 1.27 1.27)
				)
				(justify mirror)
			)
		)
		(property "Value" ""
			(at 0 0 90)
			(layer "B.Fab")
			(effects
				(font
					(size 1.27 1.27)
				)
				(justify mirror)
			)
		)
		(duplicate_pad_numbers_are_jumpers no)
		(fp_line
			(start -0.7874 0.4064)
			(end 0.7874 0.4064)
			(stroke
				(width 0.1524)
				(type default)
			)
			(layer "B.SilkS")
		)
		(fp_line
			(start 0.7874 0.4064)
			(end 0.7874 -0.4064)
			(stroke
				(width 0.1524)
				(type default)
			)
			(layer "B.SilkS")
		)
		(fp_line
			(start -0.7874 -0.4064)
			(end -0.7874 0.4064)
			(stroke
				(width 0.1524)
				(type default)
			)
			(layer "B.SilkS")
		)
		(fp_line
			(start 0.7874 -0.4064)
			(end -0.7874 -0.4064)
			(stroke
				(width 0.1524)
				(type default)
			)
			(layer "B.SilkS")
		)
		(fp_line
			(start -0.67945 0.3048)
			(end -0.120396 0.3048)
			(stroke
				(width 0.1)
				(type default)
			)
			(layer "B.Fab")
		)
		(fp_line
			(start -0.120396 0.3048)
			(end -0.120396 0.2794)
			(stroke
				(width 0.1)
				(type default)
			)
			(layer "B.Fab")
		)
		(fp_line
			(start 0.12065 0.3048)
			(end 0.67945 0.3048)
			(stroke
				(width 0.1)
				(type default)
			)
			(layer "B.Fab")
		)
		(fp_line
			(start 0.67945 0.3048)
			(end 0.67945 -0.305054)
			(stroke
				(width 0.1)
				(type default)
			)
			(layer "B.Fab")
		)
		(fp_line
			(start -0.120396 0.2794)
			(end 0.12065 0.2794)
			(stroke
				(width 0.1)
				(type default)
			)
			(layer "B.Fab")
		)
		(fp_line
			(start 0.12065 0.2794)
			(end 0.12065 0.3048)
			(stroke
				(width 0.1)
				(type default)
			)
			(layer "B.Fab")
		)
		(fp_line
			(start -0.12065 -0.2794)
			(end -0.12065 -0.3048)
			(stroke
				(width 0.1)
				(type default)
			)
			(layer "B.Fab")
		)
		(fp_line
			(start 0.12065 -0.2794)
			(end -0.12065 -0.2794)
			(stroke
				(width 0.1)
				(type default)
			)
			(layer "B.Fab")
		)
		(fp_line
			(start -0.67945 -0.3048)
			(end -0.67945 0.3048)
			(stroke
				(width 0.1)
				(type default)
			)
			(layer "B.Fab")
		)
		(fp_line
			(start -0.12065 -0.3048)
			(end -0.67945 -0.3048)
			(stroke
				(width 0.1)
				(type default)
			)
			(layer "B.Fab")
		)
		(fp_line
			(start 0.12065 -0.305054)
			(end 0.12065 -0.2794)
			(stroke
				(width 0.1)
				(type default)
			)
			(layer "B.Fab")
		)
		(fp_line
			(start 0.67945 -0.305054)
			(end 0.12065 -0.305054)
			(stroke
				(width 0.1)
				(type default)
			)
			(layer "B.Fab")
		)
		(pad "1" smd circle
			(at 0.40005 0 90)
			(size 0 0)
			(layers "B.Cu" "B.Mask" "B.Paste")
			(net "PVCCFA_EHV_FIVRA_CPU0_PVCC2")
		)
		(pad "2" smd circle
			(at -0.40005 0 90)
			(size 0 0)
			(layers "B.Cu" "B.Mask" "B.Paste")
			(net "PVCCFA_EHV_FIVRA_CPU0_VDD4")
		)
	)
	(footprint ""
		(layer "B.Cu")
		(at 73.84288 -11.267948 -90)
		(property "Reference" "R3162"
			(at 0 0 90)
			(layer "B.SilkS")
			(hide yes)
			(effects
				(font
					(size 1.27 1.27)
				)
				(justify mirror)
			)
		)
		(property "Value" ""
			(at 0 0 90)
			(layer "B.Fab")
			(effects
				(font
					(size 1.27 1.27)
				)
				(justify mirror)
			)
		)
		(duplicate_pad_numbers_are_jumpers no)
		(fp_line
			(start -0.7874 0.4064)
			(end 0.7874 0.4064)
			(stroke
				(width 0.1524)
				(type default)
			)
			(layer "B.SilkS")
		)
		(fp_line
			(start 0.7874 0.4064)
			(end 0.7874 -0.4064)
			(stroke
				(width 0.1524)
				(type default)
			)
			(layer "B.SilkS")
		)
		(fp_line
			(start -0.7874 -0.4064)
			(end -0.7874 0.4064)
			(stroke
				(width 0.1524)
				(type default)
			)
			(layer "B.SilkS")
		)
		(fp_line
			(start 0.7874 -0.4064)
			(end -0.7874 -0.4064)
			(stroke
				(width 0.1524)
				(type default)
			)
			(layer "B.SilkS")
		)
		(fp_line
			(start -0.67945 0.3048)
			(end -0.120396 0.3048)
			(stroke
				(width 0.1)
				(type default)
			)
			(layer "B.Fab")
		)
		(fp_line
			(start -0.120396 0.3048)
			(end -0.120396 0.2794)
			(stroke
				(width 0.1)
				(type default)
			)
			(layer "B.Fab")
		)
		(fp_line
			(start 0.12065 0.3048)
			(end 0.67945 0.3048)
			(stroke
				(width 0.1)
				(type default)
			)
			(layer "B.Fab")
		)
		(fp_line
			(start 0.67945 0.3048)
			(end 0.67945 -0.305054)
			(stroke
				(width 0.1)
				(type default)
			)
			(layer "B.Fab")
		)
		(fp_line
			(start -0.120396 0.2794)
			(end 0.12065 0.2794)
			(stroke
				(width 0.1)
				(type default)
			)
			(layer "B.Fab")
		)
		(fp_line
			(start 0.12065 0.2794)
			(end 0.12065 0.3048)
			(stroke
				(width 0.1)
				(type default)
			)
			(layer "B.Fab")
		)
		(fp_line
			(start -0.12065 -0.2794)
			(end -0.12065 -0.3048)
			(stroke
				(width 0.1)
				(type default)
			)
			(layer "B.Fab")
		)
		(fp_line
			(start 0.12065 -0.2794)
			(end -0.12065 -0.2794)
			(stroke
				(width 0.1)
				(type default)
			)
			(layer "B.Fab")
		)
		(fp_line
			(start -0.67945 -0.3048)
			(end -0.67945 0.3048)
			(stroke
				(width 0.1)
				(type default)
			)
			(layer "B.Fab")
		)
		(fp_line
			(start -0.12065 -0.3048)
			(end -0.67945 -0.3048)
			(stroke
				(width 0.1)
				(type default)
			)
			(layer "B.Fab")
		)
		(fp_line
			(start 0.12065 -0.305054)
			(end 0.12065 -0.2794)
			(stroke
				(width 0.1)
				(type default)
			)
			(layer "B.Fab")
		)
		(fp_line
			(start 0.67945 -0.305054)
			(end 0.12065 -0.305054)
			(stroke
				(width 0.1)
				(type default)
			)
			(layer "B.Fab")
		)
		(pad "1" smd circle
			(at 0.40005 0 90)
			(size 0 0)
			(layers "B.Cu" "B.Mask" "B.Paste")
			(net "P3V3_OCP_V3_2")
		)
		(pad "2" smd circle
			(at -0.40005 0 90)
			(size 0 0)
			(layers "B.Cu" "B.Mask" "B.Paste")
			(net "OCP_V3_2_ID0")
		)
	)
	(footprint ""
		(layer "B.Cu")
		(at 237.001812 -135.401558)
		(property "Reference" "R1019"
			(at 0 0 0)
			(layer "B.SilkS")
			(hide yes)
			(effects
				(font
					(size 1.27 1.27)
				)
				(justify mirror)
			)
		)
		(property "Value" ""
			(at 0 0 0)
			(layer "B.Fab")
			(effects
				(font
					(size 1.27 1.27)
				)
				(justify mirror)
			)
		)
		(duplicate_pad_numbers_are_jumpers no)
		(fp_line
			(start -0.7874 -0.4064)
			(end -0.7874 0.4064)
			(stroke
				(width 0.1524)
				(type default)
			)
			(layer "B.SilkS")
		)
		(fp_line
			(start -0.7874 0.4064)
			(end -0.344932 0.4064)
			(stroke
				(width 0.1524)
				(type default)
			)
			(layer "B.SilkS")
		)
		(fp_line
			(start 0.305308 0.4064)
			(end 0.7874 0.4064)
			(stroke
				(width 0.1524)
				(type default)
			)
			(layer "B.SilkS")
		)
		(fp_line
			(start 0.7874 -0.4064)
			(end -0.7874 -0.4064)
			(stroke
				(width 0.1524)
				(type default)
			)
			(layer "B.SilkS")
		)
		(fp_line
			(start 0.7874 -0.19177)
			(end 0.7874 -0.4064)
			(stroke
				(width 0.1524)
				(type default)
			)
			(layer "B.SilkS")
		)
		(fp_line
			(start 0.7874 0.4064)
			(end 0.7874 0.21971)
			(stroke
				(width 0.1524)
				(type default)
			)
			(layer "B.SilkS")
		)
		(fp_line
			(start -0.67945 -0.3048)
			(end -0.67945 0.3048)
			(stroke
				(width 0.1)
				(type default)
			)
			(layer "B.Fab")
		)
		(fp_line
			(start -0.67945 0.3048)
			(end -0.120396 0.3048)
			(stroke
				(width 0.1)
				(type default)
			)
			(layer "B.Fab")
		)
		(fp_line
			(start -0.12065 -0.3048)
			(end -0.67945 -0.3048)
			(stroke
				(width 0.1)
				(type default)
			)
			(layer "B.Fab")
		)
		(fp_line
			(start -0.12065 -0.2794)
			(end -0.12065 -0.3048)
			(stroke
				(width 0.1)
				(type default)
			)
			(layer "B.Fab")
		)
		(fp_line
			(start -0.120396 0.2794)
			(end 0.12065 0.2794)
			(stroke
				(width 0.1)
				(type default)
			)
			(layer "B.Fab")
		)
		(fp_line
			(start -0.120396 0.3048)
			(end -0.120396 0.2794)
			(stroke
				(width 0.1)
				(type default)
			)
			(layer "B.Fab")
		)
		(fp_line
			(start 0.12065 -0.305054)
			(end 0.12065 -0.2794)
			(stroke
				(width 0.1)
				(type default)
			)
			(layer "B.Fab")
		)
		(fp_line
			(start 0.12065 -0.2794)
			(end -0.12065 -0.2794)
			(stroke
				(width 0.1)
				(type default)
			)
			(layer "B.Fab")
		)
		(fp_line
			(start 0.12065 0.2794)
			(end 0.12065 0.3048)
			(stroke
				(width 0.1)
				(type default)
			)
			(layer "B.Fab")
		)
		(fp_line
			(start 0.12065 0.3048)
			(end 0.67945 0.3048)
			(stroke
				(width 0.1)
				(type default)
			)
			(layer "B.Fab")
		)
		(fp_line
			(start 0.67945 -0.305054)
			(end 0.12065 -0.305054)
			(stroke
				(width 0.1)
				(type default)
			)
			(layer "B.Fab")
		)
		(fp_line
			(start 0.67945 0.3048)
			(end 0.67945 -0.305054)
			(stroke
				(width 0.1)
				(type default)
			)
			(layer "B.Fab")
		)
		(pad "1" smd rect
			(at 0.40005 0)
			(size 0.4572 0.508)
			(layers "B.Cu" "B.Mask" "B.Paste")
			(net "CLK_25M_PCH_CPU1_DN")
		)
		(pad "2" smd rect
			(at -0.40005 0)
			(size 0.4572 0.508)
			(layers "B.Cu" "B.Mask" "B.Paste")
			(net "CLK_25M_NSSC_CPU1_DN")
		)
	)
	(footprint ""
		(layer "B.Cu")
		(at 325.193914 -62.004956 -90)
		(property "Reference" "R1675"
			(at 0 0 90)
			(layer "B.SilkS")
			(hide yes)
			(effects
				(font
					(size 1.27 1.27)
				)
				(justify mirror)
			)
		)
		(property "Value" ""
			(at 0 0 90)
			(layer "B.Fab")
			(effects
				(font
					(size 1.27 1.27)
				)
				(justify mirror)
			)
		)
		(duplicate_pad_numbers_are_jumpers no)
		(fp_line
			(start -0.7874 0.4064)
			(end 0.7874 0.4064)
			(stroke
				(width 0.1524)
				(type default)
			)
			(layer "B.SilkS")
		)
		(fp_line
			(start 0.7874 0.4064)
			(end 0.7874 -0.4064)
			(stroke
				(width 0.1524)
				(type default)
			)
			(layer "B.SilkS")
		)
		(fp_line
			(start -0.7874 -0.4064)
			(end -0.7874 0.4064)
			(stroke
				(width 0.1524)
				(type default)
			)
			(layer "B.SilkS")
		)
		(fp_line
			(start 0.7874 -0.4064)
			(end -0.7874 -0.4064)
			(stroke
				(width 0.1524)
				(type default)
			)
			(layer "B.SilkS")
		)
		(fp_line
			(start -0.67945 0.3048)
			(end -0.120396 0.3048)
			(stroke
				(width 0.1)
				(type default)
			)
			(layer "B.Fab")
		)
		(fp_line
			(start -0.120396 0.3048)
			(end -0.120396 0.2794)
			(stroke
				(width 0.1)
				(type default)
			)
			(layer "B.Fab")
		)
		(fp_line
			(start 0.12065 0.3048)
			(end 0.67945 0.3048)
			(stroke
				(width 0.1)
				(type default)
			)
			(layer "B.Fab")
		)
		(fp_line
			(start 0.67945 0.3048)
			(end 0.67945 -0.305054)
			(stroke
				(width 0.1)
				(type default)
			)
			(layer "B.Fab")
		)
		(fp_line
			(start -0.120396 0.2794)
			(end 0.12065 0.2794)
			(stroke
				(width 0.1)
				(type default)
			)
			(layer "B.Fab")
		)
		(fp_line
			(start 0.12065 0.2794)
			(end 0.12065 0.3048)
			(stroke
				(width 0.1)
				(type default)
			)
			(layer "B.Fab")
		)
		(fp_line
			(start -0.12065 -0.2794)
			(end -0.12065 -0.3048)
			(stroke
				(width 0.1)
				(type default)
			)
			(layer "B.Fab")
		)
		(fp_line
			(start 0.12065 -0.2794)
			(end -0.12065 -0.2794)
			(stroke
				(width 0.1)
				(type default)
			)
			(layer "B.Fab")
		)
		(fp_line
			(start -0.67945 -0.3048)
			(end -0.67945 0.3048)
			(stroke
				(width 0.1)
				(type default)
			)
			(layer "B.Fab")
		)
		(fp_line
			(start -0.12065 -0.3048)
			(end -0.67945 -0.3048)
			(stroke
				(width 0.1)
				(type default)
			)
			(layer "B.Fab")
		)
		(fp_line
			(start 0.12065 -0.305054)
			(end 0.12065 -0.2794)
			(stroke
				(width 0.1)
				(type default)
			)
			(layer "B.Fab")
		)
		(fp_line
			(start 0.67945 -0.305054)
			(end 0.12065 -0.305054)
			(stroke
				(width 0.1)
				(type default)
			)
			(layer "B.Fab")
		)
		(pad "1" smd circle
			(at 0.40005 0 90)
			(size 0 0)
			(layers "B.Cu" "B.Mask" "B.Paste")
			(net "FM_PCIE_EV_BIF_EN")
		)
		(pad "2" smd circle
			(at -0.40005 0 90)
			(size 0 0)
			(layers "B.Cu" "B.Mask" "B.Paste")
			(net "P3V3_AUX")
		)
	)
	(footprint ""
		(layer "B.Cu")
		(at 47.650908 -193.25971 -90)
		(property "Reference" "R257"
			(at 0 0 90)
			(layer "B.SilkS")
			(hide yes)
			(effects
				(font
					(size 1.27 1.27)
				)
				(justify mirror)
			)
		)
		(property "Value" ""
			(at 0 0 90)
			(layer "B.Fab")
			(effects
				(font
					(size 1.27 1.27)
				)
				(justify mirror)
			)
		)
		(duplicate_pad_numbers_are_jumpers no)
		(fp_line
			(start -0.7874 0.4064)
			(end 0.7874 0.4064)
			(stroke
				(width 0.1524)
				(type default)
			)
			(layer "B.SilkS")
		)
		(fp_line
			(start 0.7874 0.4064)
			(end 0.7874 -0.4064)
			(stroke
				(width 0.1524)
				(type default)
			)
			(layer "B.SilkS")
		)
		(fp_line
			(start -0.7874 -0.4064)
			(end -0.7874 0.4064)
			(stroke
				(width 0.1524)
				(type default)
			)
			(layer "B.SilkS")
		)
		(fp_line
			(start 0.7874 -0.4064)
			(end -0.7874 -0.4064)
			(stroke
				(width 0.1524)
				(type default)
			)
			(layer "B.SilkS")
		)
		(fp_line
			(start -0.67945 0.3048)
			(end -0.120396 0.3048)
			(stroke
				(width 0.1)
				(type default)
			)
			(layer "B.Fab")
		)
		(fp_line
			(start -0.120396 0.3048)
			(end -0.120396 0.2794)
			(stroke
				(width 0.1)
				(type default)
			)
			(layer "B.Fab")
		)
		(fp_line
			(start 0.12065 0.3048)
			(end 0.67945 0.3048)
			(stroke
				(width 0.1)
				(type default)
			)
			(layer "B.Fab")
		)
		(fp_line
			(start 0.67945 0.3048)
			(end 0.67945 -0.305054)
			(stroke
				(width 0.1)
				(type default)
			)
			(layer "B.Fab")
		)
		(fp_line
			(start -0.120396 0.2794)
			(end 0.12065 0.2794)
			(stroke
				(width 0.1)
				(type default)
			)
			(layer "B.Fab")
		)
		(fp_line
			(start 0.12065 0.2794)
			(end 0.12065 0.3048)
			(stroke
				(width 0.1)
				(type default)
			)
			(layer "B.Fab")
		)
		(fp_line
			(start -0.12065 -0.2794)
			(end -0.12065 -0.3048)
			(stroke
				(width 0.1)
				(type default)
			)
			(layer "B.Fab")
		)
		(fp_line
			(start 0.12065 -0.2794)
			(end -0.12065 -0.2794)
			(stroke
				(width 0.1)
				(type default)
			)
			(layer "B.Fab")
		)
		(fp_line
			(start -0.67945 -0.3048)
			(end -0.67945 0.3048)
			(stroke
				(width 0.1)
				(type default)
			)
			(layer "B.Fab")
		)
		(fp_line
			(start -0.12065 -0.3048)
			(end -0.67945 -0.3048)
			(stroke
				(width 0.1)
				(type default)
			)
			(layer "B.Fab")
		)
		(fp_line
			(start 0.12065 -0.305054)
			(end 0.12065 -0.2794)
			(stroke
				(width 0.1)
				(type default)
			)
			(layer "B.Fab")
		)
		(fp_line
			(start 0.67945 -0.305054)
			(end 0.12065 -0.305054)
			(stroke
				(width 0.1)
				(type default)
			)
			(layer "B.Fab")
		)
		(pad "1" smd circle
			(at 0.40005 0 90)
			(size 0 0)
			(layers "B.Cu" "B.Mask" "B.Paste")
			(net "PVNN_TERM_CPU1")
		)
		(pad "2" smd circle
			(at -0.40005 0 90)
			(size 0 0)
			(layers "B.Cu" "B.Mask" "B.Paste")
			(net "FM_S3M_CPU1_LVC1_GPIO_4")
		)
	)
	(footprint ""
		(layer "B.Cu")
		(at 338.133182 -64.315848 90)
		(property "Reference" "C170"
			(at 0 0 90)
			(layer "B.SilkS")
			(hide yes)
			(effects
				(font
					(size 1.27 1.27)
				)
				(justify mirror)
			)
		)
		(property "Value" ""
			(at 0 0 90)
			(layer "B.Fab")
			(effects
				(font
					(size 1.27 1.27)
				)
				(justify mirror)
			)
		)
		(duplicate_pad_numbers_are_jumpers no)
		(fp_line
			(start 0.299974 -0.150114)
			(end -0.299974 -0.150114)
			(stroke
				(width 0.1)
				(type default)
			)
			(layer "B.Fab")
		)
		(fp_line
			(start -0.299974 -0.150114)
			(end -0.299974 0.150114)
			(stroke
				(width 0.1)
				(type default)
			)
			(layer "B.Fab")
		)
		(fp_line
			(start 0.299974 0.150114)
			(end 0.299974 -0.150114)
			(stroke
				(width 0.1)
				(type default)
			)
			(layer "B.Fab")
		)
		(fp_line
			(start -0.299974 0.150114)
			(end 0.299974 0.150114)
			(stroke
				(width 0.1)
				(type default)
			)
			(layer "B.Fab")
		)
		(pad "1" smd rect
			(at 0.2667 0 270)
			(size 0.3048 0.381)
			(layers "B.Cu" "B.Mask" "B.Paste")
			(net "DMI_CPU0_PCH_RX_C_DP<0>")
		)
		(pad "2" smd rect
			(at -0.2667 0 270)
			(size 0.3048 0.381)
			(layers "B.Cu" "B.Mask" "B.Paste")
			(net "DMI_CPU0_PCH_RX_DP<0>")
		)
	)
	(footprint ""
		(layer "B.Cu")
		(at 31.9024 -164.292788 180)
		(property "Reference" "PR410"
			(at 0 0 0)
			(layer "B.SilkS")
			(hide yes)
			(effects
				(font
					(size 1.27 1.27)
				)
				(justify mirror)
			)
		)
		(property "Value" ""
			(at 0 0 0)
			(layer "B.Fab")
			(effects
				(font
					(size 1.27 1.27)
				)
				(justify mirror)
			)
		)
		(duplicate_pad_numbers_are_jumpers no)
		(fp_line
			(start 0.7874 0.4064)
			(end 0.7874 -0.4064)
			(stroke
				(width 0.1524)
				(type default)
			)
			(layer "B.SilkS")
		)
		(fp_line
			(start 0.7874 -0.4064)
			(end -0.7874 -0.4064)
			(stroke
				(width 0.1524)
				(type default)
			)
			(layer "B.SilkS")
		)
		(fp_line
			(start -0.7874 0.4064)
			(end 0.7874 0.4064)
			(stroke
				(width 0.1524)
				(type default)
			)
			(layer "B.SilkS")
		)
		(fp_line
			(start -0.7874 -0.4064)
			(end -0.7874 0.4064)
			(stroke
				(width 0.1524)
				(type default)
			)
			(layer "B.SilkS")
		)
		(fp_line
			(start 0.67945 0.3048)
			(end 0.67945 -0.305054)
			(stroke
				(width 0.1)
				(type default)
			)
			(layer "B.Fab")
		)
		(fp_line
			(start 0.67945 -0.305054)
			(end 0.12065 -0.305054)
			(stroke
				(width 0.1)
				(type default)
			)
			(layer "B.Fab")
		)
		(fp_line
			(start 0.12065 0.3048)
			(end 0.67945 0.3048)
			(stroke
				(width 0.1)
				(type default)
			)
			(layer "B.Fab")
		)
		(fp_line
			(start 0.12065 0.2794)
			(end 0.12065 0.3048)
			(stroke
				(width 0.1)
				(type default)
			)
			(layer "B.Fab")
		)
		(fp_line
			(start 0.12065 -0.2794)
			(end -0.12065 -0.2794)
			(stroke
				(width 0.1)
				(type default)
			)
			(layer "B.Fab")
		)
		(fp_line
			(start 0.12065 -0.305054)
			(end 0.12065 -0.2794)
			(stroke
				(width 0.1)
				(type default)
			)
			(layer "B.Fab")
		)
		(fp_line
			(start -0.120396 0.3048)
			(end -0.120396 0.2794)
			(stroke
				(width 0.1)
				(type default)
			)
			(layer "B.Fab")
		)
		(fp_line
			(start -0.120396 0.2794)
			(end 0.12065 0.2794)
			(stroke
				(width 0.1)
				(type default)
			)
			(layer "B.Fab")
		)
		(fp_line
			(start -0.12065 -0.2794)
			(end -0.12065 -0.3048)
			(stroke
				(width 0.1)
				(type default)
			)
			(layer "B.Fab")
		)
		(fp_line
			(start -0.12065 -0.3048)
			(end -0.67945 -0.3048)
			(stroke
				(width 0.1)
				(type default)
			)
			(layer "B.Fab")
		)
		(fp_line
			(start -0.67945 0.3048)
			(end -0.120396 0.3048)
			(stroke
				(width 0.1)
				(type default)
			)
			(layer "B.Fab")
		)
		(fp_line
			(start -0.67945 -0.3048)
			(end -0.67945 0.3048)
			(stroke
				(width 0.1)
				(type default)
			)
			(layer "B.Fab")
		)
		(pad "1" smd circle
			(at 0.40005 0)
			(size 0 0)
			(layers "B.Cu" "B.Mask" "B.Paste")
			(net "PVCCD_HV_CPU1_ISYS_R")
		)
		(pad "2" smd circle
			(at -0.40005 0)
			(size 0 0)
			(layers "B.Cu" "B.Mask" "B.Paste")
			(net "PVCCD_HV_CPU1_NVDIMM_ISENSE")
		)
	)
	(footprint ""
		(layer "B.Cu")
		(at 340.406228 -62.056264 90)
		(property "Reference" "C165"
			(at 0 0 90)
			(layer "B.SilkS")
			(hide yes)
			(effects
				(font
					(size 1.27 1.27)
				)
				(justify mirror)
			)
		)
		(property "Value" ""
			(at 0 0 90)
			(layer "B.Fab")
			(effects
				(font
					(size 1.27 1.27)
				)
				(justify mirror)
			)
		)
		(duplicate_pad_numbers_are_jumpers no)
		(fp_line
			(start 0.299974 -0.150114)
			(end -0.299974 -0.150114)
			(stroke
				(width 0.1)
				(type default)
			)
			(layer "B.Fab")
		)
		(fp_line
			(start -0.299974 -0.150114)
			(end -0.299974 0.150114)
			(stroke
				(width 0.1)
				(type default)
			)
			(layer "B.Fab")
		)
		(fp_line
			(start 0.299974 0.150114)
			(end 0.299974 -0.150114)
			(stroke
				(width 0.1)
				(type default)
			)
			(layer "B.Fab")
		)
		(fp_line
			(start -0.299974 0.150114)
			(end 0.299974 0.150114)
			(stroke
				(width 0.1)
				(type default)
			)
			(layer "B.Fab")
		)
		(pad "1" smd rect
			(at 0.2667 0 270)
			(size 0.3048 0.381)
			(layers "B.Cu" "B.Mask" "B.Paste")
			(net "DMI_CPU0_PCH_RX_C_DN<2>")
		)
		(pad "2" smd rect
			(at -0.2667 0 270)
			(size 0.3048 0.381)
			(layers "B.Cu" "B.Mask" "B.Paste")
			(net "DMI_CPU0_PCH_RX_DN<2>")
		)
	)
	(footprint ""
		(layer "B.Cu")
		(at 151.99487 -13.762228 90)
		(property "Reference" "R2417"
			(at 0 0 90)
			(layer "B.SilkS")
			(hide yes)
			(effects
				(font
					(size 1.27 1.27)
				)
				(justify mirror)
			)
		)
		(property "Value" ""
			(at 0 0 90)
			(layer "B.Fab")
			(effects
				(font
					(size 1.27 1.27)
				)
				(justify mirror)
			)
		)
		(duplicate_pad_numbers_are_jumpers no)
		(fp_line
			(start 0.7874 -0.4064)
			(end -0.7874 -0.4064)
			(stroke
				(width 0.1524)
				(type default)
			)
			(layer "B.SilkS")
		)
		(fp_line
			(start -0.7874 -0.4064)
			(end -0.7874 0.4064)
			(stroke
				(width 0.1524)
				(type default)
			)
			(layer "B.SilkS")
		)
		(fp_line
			(start 0.7874 0.4064)
			(end 0.7874 -0.4064)
			(stroke
				(width 0.1524)
				(type default)
			)
			(layer "B.SilkS")
		)
		(fp_line
			(start -0.7874 0.4064)
			(end 0.7874 0.4064)
			(stroke
				(width 0.1524)
				(type default)
			)
			(layer "B.SilkS")
		)
		(fp_line
			(start 0.67945 -0.305054)
			(end 0.12065 -0.305054)
			(stroke
				(width 0.1)
				(type default)
			)
			(layer "B.Fab")
		)
		(fp_line
			(start 0.12065 -0.305054)
			(end 0.12065 -0.2794)
			(stroke
				(width 0.1)
				(type default)
			)
			(layer "B.Fab")
		)
		(fp_line
			(start -0.12065 -0.3048)
			(end -0.67945 -0.3048)
			(stroke
				(width 0.1)
				(type default)
			)
			(layer "B.Fab")
		)
		(fp_line
			(start -0.67945 -0.3048)
			(end -0.67945 0.3048)
			(stroke
				(width 0.1)
				(type default)
			)
			(layer "B.Fab")
		)
		(fp_line
			(start 0.12065 -0.2794)
			(end -0.12065 -0.2794)
			(stroke
				(width 0.1)
				(type default)
			)
			(layer "B.Fab")
		)
		(fp_line
			(start -0.12065 -0.2794)
			(end -0.12065 -0.3048)
			(stroke
				(width 0.1)
				(type default)
			)
			(layer "B.Fab")
		)
		(fp_line
			(start 0.12065 0.2794)
			(end 0.12065 0.3048)
			(stroke
				(width 0.1)
				(type default)
			)
			(layer "B.Fab")
		)
		(fp_line
			(start -0.120396 0.2794)
			(end 0.12065 0.2794)
			(stroke
				(width 0.1)
				(type default)
			)
			(layer "B.Fab")
		)
		(fp_line
			(start 0.67945 0.3048)
			(end 0.67945 -0.305054)
			(stroke
				(width 0.1)
				(type default)
			)
			(layer "B.Fab")
		)
		(fp_line
			(start 0.12065 0.3048)
			(end 0.67945 0.3048)
			(stroke
				(width 0.1)
				(type default)
			)
			(layer "B.Fab")
		)
		(fp_line
			(start -0.120396 0.3048)
			(end -0.120396 0.2794)
			(stroke
				(width 0.1)
				(type default)
			)
			(layer "B.Fab")
		)
		(fp_line
			(start -0.67945 0.3048)
			(end -0.120396 0.3048)
			(stroke
				(width 0.1)
				(type default)
			)
			(layer "B.Fab")
		)
		(pad "1" smd circle
			(at 0.40005 0 270)
			(size 0 0)
			(layers "B.Cu" "B.Mask" "B.Paste")
			(net "SMB_S3M_CPU_3V3AUX_SCL")
		)
		(pad "2" smd circle
			(at -0.40005 0 270)
			(size 0 0)
			(layers "B.Cu" "B.Mask" "B.Paste")
			(net "SMB_S3M_CPU_3V3AUX_SCL_R0")
		)
	)
	(footprint ""
		(layer "B.Cu")
		(at 178.55565 -118.575328)
		(property "Reference" "C1902"
			(at 0 0 0)
			(layer "B.SilkS")
			(hide yes)
			(effects
				(font
					(size 1.27 1.27)
				)
				(justify mirror)
			)
		)
		(property "Value" ""
			(at 0 0 0)
			(layer "B.Fab")
			(effects
				(font
					(size 1.27 1.27)
				)
				(justify mirror)
			)
		)
		(duplicate_pad_numbers_are_jumpers no)
		(fp_line
			(start -0.69215 -0.2921)
			(end -0.69215 0.2921)
			(stroke
				(width 0.1524)
				(type default)
			)
			(layer "B.SilkS")
		)
		(fp_line
			(start -0.69215 0.2921)
			(end 0.69215 0.2921)
			(stroke
				(width 0.1524)
				(type default)
			)
			(layer "B.SilkS")
		)
		(fp_line
			(start 0.69215 -0.2921)
			(end -0.69215 -0.2921)
			(stroke
				(width 0.1524)
				(type default)
			)
			(layer "B.SilkS")
		)
		(fp_line
			(start 0.69215 0.2921)
			(end 0.69215 -0.2921)
			(stroke
				(width 0.1524)
				(type default)
			)
			(layer "B.SilkS")
		)
		(fp_line
			(start -0.51435 -0.2794)
			(end -0.51435 0.2794)
			(stroke
				(width 0.1)
				(type default)
			)
			(layer "B.Fab")
		)
		(fp_line
			(start -0.51435 0.2794)
			(end 0.51435 0.2794)
			(stroke
				(width 0.1)
				(type default)
			)
			(layer "B.Fab")
		)
		(fp_line
			(start 0.51435 -0.2794)
			(end -0.51435 -0.2794)
			(stroke
				(width 0.1)
				(type default)
			)
			(layer "B.Fab")
		)
		(fp_line
			(start 0.51435 0.2794)
			(end 0.51435 -0.2794)
			(stroke
				(width 0.1)
				(type default)
			)
			(layer "B.Fab")
		)
		(pad "1" smd circle
			(at 0.40005 0 180)
			(size 0 0)
			(layers "B.Cu" "B.Mask" "B.Paste")
			(net "P3V3_AUX_FPGA_VCCIO1")
		)
		(pad "2" smd circle
			(at -0.40005 0 180)
			(size 0 0)
			(layers "B.Cu" "B.Mask" "B.Paste")
			(net "GND")
		)
		(zone
			(layer "B.Cu")
			(hatch none 0.5)
			(connect_pads
				(clearance 0)
			)
			(min_thickness 0.25)
			(keepout
				(tracks not_allowed)
				(vias allowed)
				(pads allowed)
				(copperpour not_allowed)
				(footprints allowed)
			)
			(placement
				(enabled no)
				(sheetname "")
			)
			(fill
				(thermal_gap 0.5)
				(thermal_bridge_width 0.5)
				(island_removal_mode 0)
			)
			(polygon
				(pts
					(xy 178.74615 -118.487698) (xy 178.65471 -118.429532) (xy 178.45532 -118.429532) (xy 178.36515 -118.487698)
					(xy 178.36515 -118.662958) (xy 178.45532 -118.721378) (xy 178.65471 -118.721378) (xy 178.74615 -118.663212)
				)
			)
		)
	)
	(footprint ""
		(layer "B.Cu")
		(at 46.634908 -193.25971 -90)
		(property "Reference" "R256"
			(at 0 0 90)
			(layer "B.SilkS")
			(hide yes)
			(effects
				(font
					(size 1.27 1.27)
				)
				(justify mirror)
			)
		)
		(property "Value" ""
			(at 0 0 90)
			(layer "B.Fab")
			(effects
				(font
					(size 1.27 1.27)
				)
				(justify mirror)
			)
		)
		(duplicate_pad_numbers_are_jumpers no)
		(fp_line
			(start -0.7874 0.4064)
			(end 0.7874 0.4064)
			(stroke
				(width 0.1524)
				(type default)
			)
			(layer "B.SilkS")
		)
		(fp_line
			(start 0.7874 0.4064)
			(end 0.7874 -0.4064)
			(stroke
				(width 0.1524)
				(type default)
			)
			(layer "B.SilkS")
		)
		(fp_line
			(start -0.7874 -0.4064)
			(end -0.7874 0.4064)
			(stroke
				(width 0.1524)
				(type default)
			)
			(layer "B.SilkS")
		)
		(fp_line
			(start 0.7874 -0.4064)
			(end -0.7874 -0.4064)
			(stroke
				(width 0.1524)
				(type default)
			)
			(layer "B.SilkS")
		)
		(fp_line
			(start -0.67945 0.3048)
			(end -0.120396 0.3048)
			(stroke
				(width 0.1)
				(type default)
			)
			(layer "B.Fab")
		)
		(fp_line
			(start -0.120396 0.3048)
			(end -0.120396 0.2794)
			(stroke
				(width 0.1)
				(type default)
			)
			(layer "B.Fab")
		)
		(fp_line
			(start 0.12065 0.3048)
			(end 0.67945 0.3048)
			(stroke
				(width 0.1)
				(type default)
			)
			(layer "B.Fab")
		)
		(fp_line
			(start 0.67945 0.3048)
			(end 0.67945 -0.305054)
			(stroke
				(width 0.1)
				(type default)
			)
			(layer "B.Fab")
		)
		(fp_line
			(start -0.120396 0.2794)
			(end 0.12065 0.2794)
			(stroke
				(width 0.1)
				(type default)
			)
			(layer "B.Fab")
		)
		(fp_line
			(start 0.12065 0.2794)
			(end 0.12065 0.3048)
			(stroke
				(width 0.1)
				(type default)
			)
			(layer "B.Fab")
		)
		(fp_line
			(start -0.12065 -0.2794)
			(end -0.12065 -0.3048)
			(stroke
				(width 0.1)
				(type default)
			)
			(layer "B.Fab")
		)
		(fp_line
			(start 0.12065 -0.2794)
			(end -0.12065 -0.2794)
			(stroke
				(width 0.1)
				(type default)
			)
			(layer "B.Fab")
		)
		(fp_line
			(start -0.67945 -0.3048)
			(end -0.67945 0.3048)
			(stroke
				(width 0.1)
				(type default)
			)
			(layer "B.Fab")
		)
		(fp_line
			(start -0.12065 -0.3048)
			(end -0.67945 -0.3048)
			(stroke
				(width 0.1)
				(type default)
			)
			(layer "B.Fab")
		)
		(fp_line
			(start 0.12065 -0.305054)
			(end 0.12065 -0.2794)
			(stroke
				(width 0.1)
				(type default)
			)
			(layer "B.Fab")
		)
		(fp_line
			(start 0.67945 -0.305054)
			(end 0.12065 -0.305054)
			(stroke
				(width 0.1)
				(type default)
			)
			(layer "B.Fab")
		)
		(pad "1" smd circle
			(at 0.40005 0 90)
			(size 0 0)
			(layers "B.Cu" "B.Mask" "B.Paste")
			(net "PVNN_TERM_CPU1")
		)
		(pad "2" smd circle
			(at -0.40005 0 90)
			(size 0 0)
			(layers "B.Cu" "B.Mask" "B.Paste")
			(net "FM_S3M_CPU1_LVC1_GPIO_1")
		)
	)
	(footprint ""
		(layer "B.Cu")
		(at 312.989214 -250.785376 90)
		(property "Reference" "C529"
			(at 0 0 90)
			(layer "B.SilkS")
			(hide yes)
			(effects
				(font
					(size 1.27 1.27)
				)
				(justify mirror)
			)
		)
		(property "Value" ""
			(at 0 0 90)
			(layer "B.Fab")
			(effects
				(font
					(size 1.27 1.27)
				)
				(justify mirror)
			)
		)
		(duplicate_pad_numbers_are_jumpers no)
		(fp_line
			(start 1.524 -0.762)
			(end -1.524 -0.762)
			(stroke
				(width 0.1524)
				(type default)
			)
			(layer "B.SilkS")
		)
		(fp_line
			(start -1.524 -0.762)
			(end -1.524 0.762)
			(stroke
				(width 0.1524)
				(type default)
			)
			(layer "B.SilkS")
		)
		(fp_line
			(start 1.524 0.762)
			(end 1.524 -0.762)
			(stroke
				(width 0.1524)
				(type default)
			)
			(layer "B.SilkS")
		)
		(fp_line
			(start -1.524 0.762)
			(end 1.524 0.762)
			(stroke
				(width 0.1524)
				(type default)
			)
			(layer "B.SilkS")
		)
		(fp_line
			(start 1.1049 -0.724916)
			(end 1.1049 0.724916)
			(stroke
				(width 0.1)
				(type default)
			)
			(layer "B.Fab")
		)
		(fp_line
			(start -1.1049 -0.724916)
			(end 1.1049 -0.724916)
			(stroke
				(width 0.1)
				(type default)
			)
			(layer "B.Fab")
		)
		(fp_line
			(start 1.1049 0.724916)
			(end -1.1049 0.724916)
			(stroke
				(width 0.1)
				(type default)
			)
			(layer "B.Fab")
		)
		(fp_line
			(start -1.1049 0.724916)
			(end -1.1049 -0.724916)
			(stroke
				(width 0.1)
				(type default)
			)
			(layer "B.Fab")
		)
		(pad "1" smd rect
			(at 0.889 0 90)
			(size 1.016 1.27)
			(layers "B.Cu" "B.Mask" "B.Paste")
			(net "PVCCFA_EHV_FIVRA_CPU0")
		)
		(pad "2" smd rect
			(at -0.889 0 90)
			(size 1.016 1.27)
			(layers "B.Cu" "B.Mask" "B.Paste")
			(net "GND")
		)
	)
	(footprint ""
		(layer "B.Cu")
		(at 333.868014 -338.137246 -90)
		(property "Reference" "PR140"
			(at 0 0 90)
			(layer "B.SilkS")
			(hide yes)
			(effects
				(font
					(size 1.27 1.27)
				)
				(justify mirror)
			)
		)
		(property "Value" ""
			(at 0 0 90)
			(layer "B.Fab")
			(effects
				(font
					(size 1.27 1.27)
				)
				(justify mirror)
			)
		)
		(duplicate_pad_numbers_are_jumpers no)
		(fp_line
			(start -0.7874 0.4064)
			(end 0.7874 0.4064)
			(stroke
				(width 0.1524)
				(type default)
			)
			(layer "B.SilkS")
		)
		(fp_line
			(start 0.7874 0.4064)
			(end 0.7874 -0.4064)
			(stroke
				(width 0.1524)
				(type default)
			)
			(layer "B.SilkS")
		)
		(fp_line
			(start -0.7874 -0.4064)
			(end -0.7874 0.4064)
			(stroke
				(width 0.1524)
				(type default)
			)
			(layer "B.SilkS")
		)
		(fp_line
			(start 0.7874 -0.4064)
			(end -0.7874 -0.4064)
			(stroke
				(width 0.1524)
				(type default)
			)
			(layer "B.SilkS")
		)
		(fp_line
			(start -0.67945 0.3048)
			(end -0.120396 0.3048)
			(stroke
				(width 0.1)
				(type default)
			)
			(layer "B.Fab")
		)
		(fp_line
			(start -0.120396 0.3048)
			(end -0.120396 0.2794)
			(stroke
				(width 0.1)
				(type default)
			)
			(layer "B.Fab")
		)
		(fp_line
			(start 0.12065 0.3048)
			(end 0.67945 0.3048)
			(stroke
				(width 0.1)
				(type default)
			)
			(layer "B.Fab")
		)
		(fp_line
			(start 0.67945 0.3048)
			(end 0.67945 -0.305054)
			(stroke
				(width 0.1)
				(type default)
			)
			(layer "B.Fab")
		)
		(fp_line
			(start -0.120396 0.2794)
			(end 0.12065 0.2794)
			(stroke
				(width 0.1)
				(type default)
			)
			(layer "B.Fab")
		)
		(fp_line
			(start 0.12065 0.2794)
			(end 0.12065 0.3048)
			(stroke
				(width 0.1)
				(type default)
			)
			(layer "B.Fab")
		)
		(fp_line
			(start -0.12065 -0.2794)
			(end -0.12065 -0.3048)
			(stroke
				(width 0.1)
				(type default)
			)
			(layer "B.Fab")
		)
		(fp_line
			(start 0.12065 -0.2794)
			(end -0.12065 -0.2794)
			(stroke
				(width 0.1)
				(type default)
			)
			(layer "B.Fab")
		)
		(fp_line
			(start -0.67945 -0.3048)
			(end -0.67945 0.3048)
			(stroke
				(width 0.1)
				(type default)
			)
			(layer "B.Fab")
		)
		(fp_line
			(start -0.12065 -0.3048)
			(end -0.67945 -0.3048)
			(stroke
				(width 0.1)
				(type default)
			)
			(layer "B.Fab")
		)
		(fp_line
			(start 0.12065 -0.305054)
			(end 0.12065 -0.2794)
			(stroke
				(width 0.1)
				(type default)
			)
			(layer "B.Fab")
		)
		(fp_line
			(start 0.67945 -0.305054)
			(end 0.12065 -0.305054)
			(stroke
				(width 0.1)
				(type default)
			)
			(layer "B.Fab")
		)
		(pad "1" smd circle
			(at 0.40005 0 90)
			(size 0 0)
			(layers "B.Cu" "B.Mask" "B.Paste")
			(net "PVCCIN_CPU0_PVCC")
		)
		(pad "2" smd circle
			(at -0.40005 0 90)
			(size 0 0)
			(layers "B.Cu" "B.Mask" "B.Paste")
			(net "PVCCIN_CPU0_VDD6")
		)
	)
	(footprint ""
		(layer "B.Cu")
		(at 355.397308 -244.820186 -90)
		(property "Reference" "C393"
			(at 0 0 90)
			(layer "B.SilkS")
			(hide yes)
			(effects
				(font
					(size 1.27 1.27)
				)
				(justify mirror)
			)
		)
		(property "Value" ""
			(at 0 0 90)
			(layer "B.Fab")
			(effects
				(font
					(size 1.27 1.27)
				)
				(justify mirror)
			)
		)
		(duplicate_pad_numbers_are_jumpers no)
		(fp_line
			(start -1.524 0.762)
			(end 1.524 0.762)
			(stroke
				(width 0.1524)
				(type default)
			)
			(layer "B.SilkS")
		)
		(fp_line
			(start 1.524 0.762)
			(end 1.524 -0.762)
			(stroke
				(width 0.1524)
				(type default)
			)
			(layer "B.SilkS")
		)
		(fp_line
			(start -1.524 -0.762)
			(end -1.524 0.762)
			(stroke
				(width 0.1524)
				(type default)
			)
			(layer "B.SilkS")
		)
		(fp_line
			(start 1.524 -0.762)
			(end -1.524 -0.762)
			(stroke
				(width 0.1524)
				(type default)
			)
			(layer "B.SilkS")
		)
		(fp_line
			(start -1.1049 0.724916)
			(end -1.1049 -0.724916)
			(stroke
				(width 0.1)
				(type default)
			)
			(layer "B.Fab")
		)
		(fp_line
			(start 1.1049 0.724916)
			(end -1.1049 0.724916)
			(stroke
				(width 0.1)
				(type default)
			)
			(layer "B.Fab")
		)
		(fp_line
			(start -1.1049 -0.724916)
			(end 1.1049 -0.724916)
			(stroke
				(width 0.1)
				(type default)
			)
			(layer "B.Fab")
		)
		(fp_line
			(start 1.1049 -0.724916)
			(end 1.1049 0.724916)
			(stroke
				(width 0.1)
				(type default)
			)
			(layer "B.Fab")
		)
		(pad "1" smd rect
			(at 0.889 0 270)
			(size 1.016 1.27)
			(layers "B.Cu" "B.Mask" "B.Paste")
			(net "PVCCIN_CPU0")
		)
		(pad "2" smd rect
			(at -0.889 0 270)
			(size 1.016 1.27)
			(layers "B.Cu" "B.Mask" "B.Paste")
			(net "GND")
		)
	)
	(footprint ""
		(layer "B.Cu")
		(at 369.49888 -36.921948)
		(property "Reference" "R2510"
			(at 0 0 0)
			(layer "B.SilkS")
			(hide yes)
			(effects
				(font
					(size 1.27 1.27)
				)
				(justify mirror)
			)
		)
		(property "Value" ""
			(at 0 0 0)
			(layer "B.Fab")
			(effects
				(font
					(size 1.27 1.27)
				)
				(justify mirror)
			)
		)
		(duplicate_pad_numbers_are_jumpers no)
		(fp_line
			(start -0.7874 -0.4064)
			(end -0.7874 0.4064)
			(stroke
				(width 0.1524)
				(type default)
			)
			(layer "B.SilkS")
		)
		(fp_line
			(start -0.7874 0.4064)
			(end 0.7874 0.4064)
			(stroke
				(width 0.1524)
				(type default)
			)
			(layer "B.SilkS")
		)
		(fp_line
			(start 0.7874 -0.4064)
			(end -0.7874 -0.4064)
			(stroke
				(width 0.1524)
				(type default)
			)
			(layer "B.SilkS")
		)
		(fp_line
			(start 0.7874 0.4064)
			(end 0.7874 -0.4064)
			(stroke
				(width 0.1524)
				(type default)
			)
			(layer "B.SilkS")
		)
		(fp_line
			(start -0.67945 -0.3048)
			(end -0.67945 0.3048)
			(stroke
				(width 0.1)
				(type default)
			)
			(layer "B.Fab")
		)
		(fp_line
			(start -0.67945 0.3048)
			(end -0.120396 0.3048)
			(stroke
				(width 0.1)
				(type default)
			)
			(layer "B.Fab")
		)
		(fp_line
			(start -0.12065 -0.3048)
			(end -0.67945 -0.3048)
			(stroke
				(width 0.1)
				(type default)
			)
			(layer "B.Fab")
		)
		(fp_line
			(start -0.12065 -0.2794)
			(end -0.12065 -0.3048)
			(stroke
				(width 0.1)
				(type default)
			)
			(layer "B.Fab")
		)
		(fp_line
			(start -0.120396 0.2794)
			(end 0.12065 0.2794)
			(stroke
				(width 0.1)
				(type default)
			)
			(layer "B.Fab")
		)
		(fp_line
			(start -0.120396 0.3048)
			(end -0.120396 0.2794)
			(stroke
				(width 0.1)
				(type default)
			)
			(layer "B.Fab")
		)
		(fp_line
			(start 0.12065 -0.305054)
			(end 0.12065 -0.2794)
			(stroke
				(width 0.1)
				(type default)
			)
			(layer "B.Fab")
		)
		(fp_line
			(start 0.12065 -0.2794)
			(end -0.12065 -0.2794)
			(stroke
				(width 0.1)
				(type default)
			)
			(layer "B.Fab")
		)
		(fp_line
			(start 0.12065 0.2794)
			(end 0.12065 0.3048)
			(stroke
				(width 0.1)
				(type default)
			)
			(layer "B.Fab")
		)
		(fp_line
			(start 0.12065 0.3048)
			(end 0.67945 0.3048)
			(stroke
				(width 0.1)
				(type default)
			)
			(layer "B.Fab")
		)
		(fp_line
			(start 0.67945 -0.305054)
			(end 0.12065 -0.305054)
			(stroke
				(width 0.1)
				(type default)
			)
			(layer "B.Fab")
		)
		(fp_line
			(start 0.67945 0.3048)
			(end 0.67945 -0.305054)
			(stroke
				(width 0.1)
				(type default)
			)
			(layer "B.Fab")
		)
		(pad "1" smd circle
			(at 0.40005 0 180)
			(size 0 0)
			(layers "B.Cu" "B.Mask" "B.Paste")
			(net "P3V3_AUX")
		)
		(pad "2" smd circle
			(at -0.40005 0 180)
			(size 0 0)
			(layers "B.Cu" "B.Mask" "B.Paste")
			(net "FM_M2_E1S_E6_PEDET")
		)
	)
	(footprint ""
		(layer "B.Cu")
		(at 85.389466 -339.983572 -90)
		(property "Reference" "PR295"
			(at 0 0 90)
			(layer "B.SilkS")
			(hide yes)
			(effects
				(font
					(size 1.27 1.27)
				)
				(justify mirror)
			)
		)
		(property "Value" ""
			(at 0 0 90)
			(layer "B.Fab")
			(effects
				(font
					(size 1.27 1.27)
				)
				(justify mirror)
			)
		)
		(duplicate_pad_numbers_are_jumpers no)
		(fp_line
			(start -0.7874 0.4064)
			(end 0.7874 0.4064)
			(stroke
				(width 0.1524)
				(type default)
			)
			(layer "B.SilkS")
		)
		(fp_line
			(start 0.7874 0.4064)
			(end 0.7874 -0.4064)
			(stroke
				(width 0.1524)
				(type default)
			)
			(layer "B.SilkS")
		)
		(fp_line
			(start -0.7874 -0.4064)
			(end -0.7874 0.4064)
			(stroke
				(width 0.1524)
				(type default)
			)
			(layer "B.SilkS")
		)
		(fp_line
			(start 0.7874 -0.4064)
			(end -0.7874 -0.4064)
			(stroke
				(width 0.1524)
				(type default)
			)
			(layer "B.SilkS")
		)
		(fp_line
			(start -0.67945 0.3048)
			(end -0.120396 0.3048)
			(stroke
				(width 0.1)
				(type default)
			)
			(layer "B.Fab")
		)
		(fp_line
			(start -0.120396 0.3048)
			(end -0.120396 0.2794)
			(stroke
				(width 0.1)
				(type default)
			)
			(layer "B.Fab")
		)
		(fp_line
			(start 0.12065 0.3048)
			(end 0.67945 0.3048)
			(stroke
				(width 0.1)
				(type default)
			)
			(layer "B.Fab")
		)
		(fp_line
			(start 0.67945 0.3048)
			(end 0.67945 -0.305054)
			(stroke
				(width 0.1)
				(type default)
			)
			(layer "B.Fab")
		)
		(fp_line
			(start -0.120396 0.2794)
			(end 0.12065 0.2794)
			(stroke
				(width 0.1)
				(type default)
			)
			(layer "B.Fab")
		)
		(fp_line
			(start 0.12065 0.2794)
			(end 0.12065 0.3048)
			(stroke
				(width 0.1)
				(type default)
			)
			(layer "B.Fab")
		)
		(fp_line
			(start -0.12065 -0.2794)
			(end -0.12065 -0.3048)
			(stroke
				(width 0.1)
				(type default)
			)
			(layer "B.Fab")
		)
		(fp_line
			(start 0.12065 -0.2794)
			(end -0.12065 -0.2794)
			(stroke
				(width 0.1)
				(type default)
			)
			(layer "B.Fab")
		)
		(fp_line
			(start -0.67945 -0.3048)
			(end -0.67945 0.3048)
			(stroke
				(width 0.1)
				(type default)
			)
			(layer "B.Fab")
		)
		(fp_line
			(start -0.12065 -0.3048)
			(end -0.67945 -0.3048)
			(stroke
				(width 0.1)
				(type default)
			)
			(layer "B.Fab")
		)
		(fp_line
			(start 0.12065 -0.305054)
			(end 0.12065 -0.2794)
			(stroke
				(width 0.1)
				(type default)
			)
			(layer "B.Fab")
		)
		(fp_line
			(start 0.67945 -0.305054)
			(end 0.12065 -0.305054)
			(stroke
				(width 0.1)
				(type default)
			)
			(layer "B.Fab")
		)
		(pad "1" smd circle
			(at 0.40005 0 90)
			(size 0 0)
			(layers "B.Cu" "B.Mask" "B.Paste")
			(net "PVCCIN_CPU1_VOS6")
		)
		(pad "2" smd circle
			(at -0.40005 0 90)
			(size 0 0)
			(layers "B.Cu" "B.Mask" "B.Paste")
			(net "PVCCIN_CPU1")
		)
	)
	(footprint ""
		(layer "B.Cu")
		(at 158.697168 -319.363344)
		(property "Reference" "C90"
			(at 0 0 0)
			(layer "B.SilkS")
			(hide yes)
			(effects
				(font
					(size 1.27 1.27)
				)
				(justify mirror)
			)
		)
		(property "Value" ""
			(at 0 0 0)
			(layer "B.Fab")
			(effects
				(font
					(size 1.27 1.27)
				)
				(justify mirror)
			)
		)
		(duplicate_pad_numbers_are_jumpers no)
		(fp_line
			(start -0.7874 -0.4064)
			(end -0.7874 0.4064)
			(stroke
				(width 0.1524)
				(type default)
			)
			(layer "B.SilkS")
		)
		(fp_line
			(start -0.7874 0.4064)
			(end 0.7874 0.4064)
			(stroke
				(width 0.1524)
				(type default)
			)
			(layer "B.SilkS")
		)
		(fp_line
			(start 0.7874 -0.4064)
			(end -0.7874 -0.4064)
			(stroke
				(width 0.1524)
				(type default)
			)
			(layer "B.SilkS")
		)
		(fp_line
			(start 0.7874 0.4064)
			(end 0.7874 -0.4064)
			(stroke
				(width 0.1524)
				(type default)
			)
			(layer "B.SilkS")
		)
		(fp_line
			(start -0.67945 -0.3048)
			(end -0.67945 0.3048)
			(stroke
				(width 0.1)
				(type default)
			)
			(layer "B.Fab")
		)
		(fp_line
			(start -0.67945 0.3048)
			(end -0.120396 0.3048)
			(stroke
				(width 0.1)
				(type default)
			)
			(layer "B.Fab")
		)
		(fp_line
			(start -0.12065 -0.3048)
			(end -0.67945 -0.3048)
			(stroke
				(width 0.1)
				(type default)
			)
			(layer "B.Fab")
		)
		(fp_line
			(start -0.12065 -0.2794)
			(end -0.12065 -0.3048)
			(stroke
				(width 0.1)
				(type default)
			)
			(layer "B.Fab")
		)
		(fp_line
			(start -0.120396 0.2794)
			(end 0.12065 0.2794)
			(stroke
				(width 0.1)
				(type default)
			)
			(layer "B.Fab")
		)
		(fp_line
			(start -0.120396 0.3048)
			(end -0.120396 0.2794)
			(stroke
				(width 0.1)
				(type default)
			)
			(layer "B.Fab")
		)
		(fp_line
			(start 0.12065 -0.305054)
			(end 0.12065 -0.2794)
			(stroke
				(width 0.1)
				(type default)
			)
			(layer "B.Fab")
		)
		(fp_line
			(start 0.12065 -0.2794)
			(end -0.12065 -0.2794)
			(stroke
				(width 0.1)
				(type default)
			)
			(layer "B.Fab")
		)
		(fp_line
			(start 0.12065 0.2794)
			(end 0.12065 0.3048)
			(stroke
				(width 0.1)
				(type default)
			)
			(layer "B.Fab")
		)
		(fp_line
			(start 0.12065 0.3048)
			(end 0.67945 0.3048)
			(stroke
				(width 0.1)
				(type default)
			)
			(layer "B.Fab")
		)
		(fp_line
			(start 0.67945 -0.305054)
			(end 0.12065 -0.305054)
			(stroke
				(width 0.1)
				(type default)
			)
			(layer "B.Fab")
		)
		(fp_line
			(start 0.67945 0.3048)
			(end 0.67945 -0.305054)
			(stroke
				(width 0.1)
				(type default)
			)
			(layer "B.Fab")
		)
		(pad "1" smd circle
			(at 0.40005 0 180)
			(size 0 0)
			(layers "B.Cu" "B.Mask" "B.Paste")
			(net "P3V3_AUX")
		)
		(pad "2" smd circle
			(at -0.40005 0 180)
			(size 0 0)
			(layers "B.Cu" "B.Mask" "B.Paste")
			(net "GND")
		)
	)
	(footprint ""
		(layer "B.Cu")
		(at 108.845604 -294.01008 180)
		(property "Reference" "C328"
			(at 0 0 0)
			(layer "B.SilkS")
			(hide yes)
			(effects
				(font
					(size 1.27 1.27)
				)
				(justify mirror)
			)
		)
		(property "Value" ""
			(at 0 0 0)
			(layer "B.Fab")
			(effects
				(font
					(size 1.27 1.27)
				)
				(justify mirror)
			)
		)
		(duplicate_pad_numbers_are_jumpers no)
		(fp_line
			(start 1.524 0.762)
			(end 1.524 -0.762)
			(stroke
				(width 0.1524)
				(type default)
			)
			(layer "B.SilkS")
		)
		(fp_line
			(start 1.524 -0.762)
			(end -1.524 -0.762)
			(stroke
				(width 0.1524)
				(type default)
			)
			(layer "B.SilkS")
		)
		(fp_line
			(start -1.524 0.762)
			(end 1.524 0.762)
			(stroke
				(width 0.1524)
				(type default)
			)
			(layer "B.SilkS")
		)
		(fp_line
			(start -1.524 -0.762)
			(end -1.524 0.762)
			(stroke
				(width 0.1524)
				(type default)
			)
			(layer "B.SilkS")
		)
		(fp_line
			(start 1.1049 0.724916)
			(end -1.1049 0.724916)
			(stroke
				(width 0.1)
				(type default)
			)
			(layer "B.Fab")
		)
		(fp_line
			(start 1.1049 -0.724916)
			(end 1.1049 0.724916)
			(stroke
				(width 0.1)
				(type default)
			)
			(layer "B.Fab")
		)
		(fp_line
			(start -1.1049 0.724916)
			(end -1.1049 -0.724916)
			(stroke
				(width 0.1)
				(type default)
			)
			(layer "B.Fab")
		)
		(fp_line
			(start -1.1049 -0.724916)
			(end 1.1049 -0.724916)
			(stroke
				(width 0.1)
				(type default)
			)
			(layer "B.Fab")
		)
		(pad "1" smd rect
			(at 0.889 0 180)
			(size 1.016 1.27)
			(layers "B.Cu" "B.Mask" "B.Paste")
			(net "PVCCIN_CPU1")
		)
		(pad "2" smd rect
			(at -0.889 0 180)
			(size 1.016 1.27)
			(layers "B.Cu" "B.Mask" "B.Paste")
			(net "GND")
		)
	)
	(footprint ""
		(layer "B.Cu")
		(at 358.328214 -337.860386)
		(property "Reference" "PR149"
			(at 0 0 0)
			(layer "B.SilkS")
			(hide yes)
			(effects
				(font
					(size 1.27 1.27)
				)
				(justify mirror)
			)
		)
		(property "Value" ""
			(at 0 0 0)
			(layer "B.Fab")
			(effects
				(font
					(size 1.27 1.27)
				)
				(justify mirror)
			)
		)
		(duplicate_pad_numbers_are_jumpers no)
		(fp_line
			(start -0.7874 -0.4064)
			(end -0.7874 0.4064)
			(stroke
				(width 0.1524)
				(type default)
			)
			(layer "B.SilkS")
		)
		(fp_line
			(start -0.7874 0.4064)
			(end 0.7874 0.4064)
			(stroke
				(width 0.1524)
				(type default)
			)
			(layer "B.SilkS")
		)
		(fp_line
			(start 0.7874 -0.4064)
			(end -0.7874 -0.4064)
			(stroke
				(width 0.1524)
				(type default)
			)
			(layer "B.SilkS")
		)
		(fp_line
			(start 0.7874 0.4064)
			(end 0.7874 -0.4064)
			(stroke
				(width 0.1524)
				(type default)
			)
			(layer "B.SilkS")
		)
		(fp_line
			(start -0.67945 -0.3048)
			(end -0.67945 0.3048)
			(stroke
				(width 0.1)
				(type default)
			)
			(layer "B.Fab")
		)
		(fp_line
			(start -0.67945 0.3048)
			(end -0.120396 0.3048)
			(stroke
				(width 0.1)
				(type default)
			)
			(layer "B.Fab")
		)
		(fp_line
			(start -0.12065 -0.3048)
			(end -0.67945 -0.3048)
			(stroke
				(width 0.1)
				(type default)
			)
			(layer "B.Fab")
		)
		(fp_line
			(start -0.12065 -0.2794)
			(end -0.12065 -0.3048)
			(stroke
				(width 0.1)
				(type default)
			)
			(layer "B.Fab")
		)
		(fp_line
			(start -0.120396 0.2794)
			(end 0.12065 0.2794)
			(stroke
				(width 0.1)
				(type default)
			)
			(layer "B.Fab")
		)
		(fp_line
			(start -0.120396 0.3048)
			(end -0.120396 0.2794)
			(stroke
				(width 0.1)
				(type default)
			)
			(layer "B.Fab")
		)
		(fp_line
			(start 0.12065 -0.305054)
			(end 0.12065 -0.2794)
			(stroke
				(width 0.1)
				(type default)
			)
			(layer "B.Fab")
		)
		(fp_line
			(start 0.12065 -0.2794)
			(end -0.12065 -0.2794)
			(stroke
				(width 0.1)
				(type default)
			)
			(layer "B.Fab")
		)
		(fp_line
			(start 0.12065 0.2794)
			(end 0.12065 0.3048)
			(stroke
				(width 0.1)
				(type default)
			)
			(layer "B.Fab")
		)
		(fp_line
			(start 0.12065 0.3048)
			(end 0.67945 0.3048)
			(stroke
				(width 0.1)
				(type default)
			)
			(layer "B.Fab")
		)
		(fp_line
			(start 0.67945 -0.305054)
			(end 0.12065 -0.305054)
			(stroke
				(width 0.1)
				(type default)
			)
			(layer "B.Fab")
		)
		(fp_line
			(start 0.67945 0.3048)
			(end 0.67945 -0.305054)
			(stroke
				(width 0.1)
				(type default)
			)
			(layer "B.Fab")
		)
		(pad "1" smd circle
			(at 0.40005 0 180)
			(size 0 0)
			(layers "B.Cu" "B.Mask" "B.Paste")
			(net "PVCCIN_CPU0_VOS3")
		)
		(pad "2" smd circle
			(at -0.40005 0 180)
			(size 0 0)
			(layers "B.Cu" "B.Mask" "B.Paste")
			(net "PVCCIN_CPU0")
		)
	)
	(footprint ""
		(layer "B.Cu")
		(at 351.26803 -359.995216 180)
		(property "Reference" "R2591"
			(at 0 0 0)
			(layer "B.SilkS")
			(hide yes)
			(effects
				(font
					(size 1.27 1.27)
				)
				(justify mirror)
			)
		)
		(property "Value" ""
			(at 0 0 0)
			(layer "B.Fab")
			(effects
				(font
					(size 1.27 1.27)
				)
				(justify mirror)
			)
		)
		(duplicate_pad_numbers_are_jumpers no)
		(fp_line
			(start 0.7874 0.4064)
			(end 0.7874 -0.4064)
			(stroke
				(width 0.1524)
				(type default)
			)
			(layer "B.SilkS")
		)
		(fp_line
			(start 0.7874 -0.4064)
			(end -0.7874 -0.4064)
			(stroke
				(width 0.1524)
				(type default)
			)
			(layer "B.SilkS")
		)
		(fp_line
			(start -0.7874 0.4064)
			(end 0.7874 0.4064)
			(stroke
				(width 0.1524)
				(type default)
			)
			(layer "B.SilkS")
		)
		(fp_line
			(start -0.7874 -0.4064)
			(end -0.7874 0.4064)
			(stroke
				(width 0.1524)
				(type default)
			)
			(layer "B.SilkS")
		)
		(fp_line
			(start 0.67945 0.3048)
			(end 0.67945 -0.305054)
			(stroke
				(width 0.1)
				(type default)
			)
			(layer "B.Fab")
		)
		(fp_line
			(start 0.67945 -0.305054)
			(end 0.12065 -0.305054)
			(stroke
				(width 0.1)
				(type default)
			)
			(layer "B.Fab")
		)
		(fp_line
			(start 0.12065 0.3048)
			(end 0.67945 0.3048)
			(stroke
				(width 0.1)
				(type default)
			)
			(layer "B.Fab")
		)
		(fp_line
			(start 0.12065 0.2794)
			(end 0.12065 0.3048)
			(stroke
				(width 0.1)
				(type default)
			)
			(layer "B.Fab")
		)
		(fp_line
			(start 0.12065 -0.2794)
			(end -0.12065 -0.2794)
			(stroke
				(width 0.1)
				(type default)
			)
			(layer "B.Fab")
		)
		(fp_line
			(start 0.12065 -0.305054)
			(end 0.12065 -0.2794)
			(stroke
				(width 0.1)
				(type default)
			)
			(layer "B.Fab")
		)
		(fp_line
			(start -0.120396 0.3048)
			(end -0.120396 0.2794)
			(stroke
				(width 0.1)
				(type default)
			)
			(layer "B.Fab")
		)
		(fp_line
			(start -0.120396 0.2794)
			(end 0.12065 0.2794)
			(stroke
				(width 0.1)
				(type default)
			)
			(layer "B.Fab")
		)
		(fp_line
			(start -0.12065 -0.2794)
			(end -0.12065 -0.3048)
			(stroke
				(width 0.1)
				(type default)
			)
			(layer "B.Fab")
		)
		(fp_line
			(start -0.12065 -0.3048)
			(end -0.67945 -0.3048)
			(stroke
				(width 0.1)
				(type default)
			)
			(layer "B.Fab")
		)
		(fp_line
			(start -0.67945 0.3048)
			(end -0.120396 0.3048)
			(stroke
				(width 0.1)
				(type default)
			)
			(layer "B.Fab")
		)
		(fp_line
			(start -0.67945 -0.3048)
			(end -0.67945 0.3048)
			(stroke
				(width 0.1)
				(type default)
			)
			(layer "B.Fab")
		)
		(pad "1" smd circle
			(at 0.40005 0)
			(size 0 0)
			(layers "B.Cu" "B.Mask" "B.Paste")
			(net "FM_PVCCIN_CPU0_EN")
		)
		(pad "2" smd circle
			(at -0.40005 0)
			(size 0 0)
			(layers "B.Cu" "B.Mask" "B.Paste")
			(net "PVCCIN_CPU0_EN_R")
		)
	)
	(footprint ""
		(layer "B.Cu")
		(at 333.32928 -339.983572 -90)
		(property "Reference" "PR142"
			(at 0 0 90)
			(layer "B.SilkS")
			(hide yes)
			(effects
				(font
					(size 1.27 1.27)
				)
				(justify mirror)
			)
		)
		(property "Value" ""
			(at 0 0 90)
			(layer "B.Fab")
			(effects
				(font
					(size 1.27 1.27)
				)
				(justify mirror)
			)
		)
		(duplicate_pad_numbers_are_jumpers no)
		(fp_line
			(start -0.7874 0.4064)
			(end 0.7874 0.4064)
			(stroke
				(width 0.1524)
				(type default)
			)
			(layer "B.SilkS")
		)
		(fp_line
			(start 0.7874 0.4064)
			(end 0.7874 -0.4064)
			(stroke
				(width 0.1524)
				(type default)
			)
			(layer "B.SilkS")
		)
		(fp_line
			(start -0.7874 -0.4064)
			(end -0.7874 0.4064)
			(stroke
				(width 0.1524)
				(type default)
			)
			(layer "B.SilkS")
		)
		(fp_line
			(start 0.7874 -0.4064)
			(end -0.7874 -0.4064)
			(stroke
				(width 0.1524)
				(type default)
			)
			(layer "B.SilkS")
		)
		(fp_line
			(start -0.67945 0.3048)
			(end -0.120396 0.3048)
			(stroke
				(width 0.1)
				(type default)
			)
			(layer "B.Fab")
		)
		(fp_line
			(start -0.120396 0.3048)
			(end -0.120396 0.2794)
			(stroke
				(width 0.1)
				(type default)
			)
			(layer "B.Fab")
		)
		(fp_line
			(start 0.12065 0.3048)
			(end 0.67945 0.3048)
			(stroke
				(width 0.1)
				(type default)
			)
			(layer "B.Fab")
		)
		(fp_line
			(start 0.67945 0.3048)
			(end 0.67945 -0.305054)
			(stroke
				(width 0.1)
				(type default)
			)
			(layer "B.Fab")
		)
		(fp_line
			(start -0.120396 0.2794)
			(end 0.12065 0.2794)
			(stroke
				(width 0.1)
				(type default)
			)
			(layer "B.Fab")
		)
		(fp_line
			(start 0.12065 0.2794)
			(end 0.12065 0.3048)
			(stroke
				(width 0.1)
				(type default)
			)
			(layer "B.Fab")
		)
		(fp_line
			(start -0.12065 -0.2794)
			(end -0.12065 -0.3048)
			(stroke
				(width 0.1)
				(type default)
			)
			(layer "B.Fab")
		)
		(fp_line
			(start 0.12065 -0.2794)
			(end -0.12065 -0.2794)
			(stroke
				(width 0.1)
				(type default)
			)
			(layer "B.Fab")
		)
		(fp_line
			(start -0.67945 -0.3048)
			(end -0.67945 0.3048)
			(stroke
				(width 0.1)
				(type default)
			)
			(layer "B.Fab")
		)
		(fp_line
			(start -0.12065 -0.3048)
			(end -0.67945 -0.3048)
			(stroke
				(width 0.1)
				(type default)
			)
			(layer "B.Fab")
		)
		(fp_line
			(start 0.12065 -0.305054)
			(end 0.12065 -0.2794)
			(stroke
				(width 0.1)
				(type default)
			)
			(layer "B.Fab")
		)
		(fp_line
			(start 0.67945 -0.305054)
			(end 0.12065 -0.305054)
			(stroke
				(width 0.1)
				(type default)
			)
			(layer "B.Fab")
		)
		(pad "1" smd circle
			(at 0.40005 0 90)
			(size 0 0)
			(layers "B.Cu" "B.Mask" "B.Paste")
			(net "PVCCIN_CPU0_VOS6")
		)
		(pad "2" smd circle
			(at -0.40005 0 90)
			(size 0 0)
			(layers "B.Cu" "B.Mask" "B.Paste")
			(net "PVCCIN_CPU0")
		)
	)
	(footprint ""
		(layer "B.Cu")
		(at 157.24886 -11.250168 90)
		(property "Reference" "R3114"
			(at 0 0 90)
			(layer "B.SilkS")
			(hide yes)
			(effects
				(font
					(size 1.27 1.27)
				)
				(justify mirror)
			)
		)
		(property "Value" ""
			(at 0 0 90)
			(layer "B.Fab")
			(effects
				(font
					(size 1.27 1.27)
				)
				(justify mirror)
			)
		)
		(duplicate_pad_numbers_are_jumpers no)
		(fp_line
			(start 0.7874 -0.4064)
			(end -0.7874 -0.4064)
			(stroke
				(width 0.1524)
				(type default)
			)
			(layer "B.SilkS")
		)
		(fp_line
			(start -0.7874 -0.4064)
			(end -0.7874 0.4064)
			(stroke
				(width 0.1524)
				(type default)
			)
			(layer "B.SilkS")
		)
		(fp_line
			(start 0.7874 0.4064)
			(end 0.7874 -0.4064)
			(stroke
				(width 0.1524)
				(type default)
			)
			(layer "B.SilkS")
		)
		(fp_line
			(start -0.7874 0.4064)
			(end 0.7874 0.4064)
			(stroke
				(width 0.1524)
				(type default)
			)
			(layer "B.SilkS")
		)
		(fp_line
			(start 0.67945 -0.305054)
			(end 0.12065 -0.305054)
			(stroke
				(width 0.1)
				(type default)
			)
			(layer "B.Fab")
		)
		(fp_line
			(start 0.12065 -0.305054)
			(end 0.12065 -0.2794)
			(stroke
				(width 0.1)
				(type default)
			)
			(layer "B.Fab")
		)
		(fp_line
			(start -0.12065 -0.3048)
			(end -0.67945 -0.3048)
			(stroke
				(width 0.1)
				(type default)
			)
			(layer "B.Fab")
		)
		(fp_line
			(start -0.67945 -0.3048)
			(end -0.67945 0.3048)
			(stroke
				(width 0.1)
				(type default)
			)
			(layer "B.Fab")
		)
		(fp_line
			(start 0.12065 -0.2794)
			(end -0.12065 -0.2794)
			(stroke
				(width 0.1)
				(type default)
			)
			(layer "B.Fab")
		)
		(fp_line
			(start -0.12065 -0.2794)
			(end -0.12065 -0.3048)
			(stroke
				(width 0.1)
				(type default)
			)
			(layer "B.Fab")
		)
		(fp_line
			(start 0.12065 0.2794)
			(end 0.12065 0.3048)
			(stroke
				(width 0.1)
				(type default)
			)
			(layer "B.Fab")
		)
		(fp_line
			(start -0.120396 0.2794)
			(end 0.12065 0.2794)
			(stroke
				(width 0.1)
				(type default)
			)
			(layer "B.Fab")
		)
		(fp_line
			(start 0.67945 0.3048)
			(end 0.67945 -0.305054)
			(stroke
				(width 0.1)
				(type default)
			)
			(layer "B.Fab")
		)
		(fp_line
			(start 0.12065 0.3048)
			(end 0.67945 0.3048)
			(stroke
				(width 0.1)
				(type default)
			)
			(layer "B.Fab")
		)
		(fp_line
			(start -0.120396 0.3048)
			(end -0.120396 0.2794)
			(stroke
				(width 0.1)
				(type default)
			)
			(layer "B.Fab")
		)
		(fp_line
			(start -0.67945 0.3048)
			(end -0.120396 0.3048)
			(stroke
				(width 0.1)
				(type default)
			)
			(layer "B.Fab")
		)
		(pad "1" smd circle
			(at 0.40005 0 270)
			(size 0 0)
			(layers "B.Cu" "B.Mask" "B.Paste")
			(net "SMB_FAN_3V3AUX_SDA")
		)
		(pad "2" smd circle
			(at -0.40005 0 270)
			(size 0 0)
			(layers "B.Cu" "B.Mask" "B.Paste")
			(net "SMB_FAN_3V3AUX_R_SDA")
		)
	)
	(footprint ""
		(layer "B.Cu")
		(at 116.40312 -248.49836 -90)
		(property "Reference" "C314"
			(at 0 0 90)
			(layer "B.SilkS")
			(hide yes)
			(effects
				(font
					(size 1.27 1.27)
				)
				(justify mirror)
			)
		)
		(property "Value" ""
			(at 0 0 90)
			(layer "B.Fab")
			(effects
				(font
					(size 1.27 1.27)
				)
				(justify mirror)
			)
		)
		(duplicate_pad_numbers_are_jumpers no)
		(fp_line
			(start -1.524 0.762)
			(end 1.524 0.762)
			(stroke
				(width 0.1524)
				(type default)
			)
			(layer "B.SilkS")
		)
		(fp_line
			(start 1.524 0.762)
			(end 1.524 -0.762)
			(stroke
				(width 0.1524)
				(type default)
			)
			(layer "B.SilkS")
		)
		(fp_line
			(start -1.524 -0.762)
			(end -1.524 0.762)
			(stroke
				(width 0.1524)
				(type default)
			)
			(layer "B.SilkS")
		)
		(fp_line
			(start 1.524 -0.762)
			(end -1.524 -0.762)
			(stroke
				(width 0.1524)
				(type default)
			)
			(layer "B.SilkS")
		)
		(fp_line
			(start -1.1049 0.724916)
			(end -1.1049 -0.724916)
			(stroke
				(width 0.1)
				(type default)
			)
			(layer "B.Fab")
		)
		(fp_line
			(start 1.1049 0.724916)
			(end -1.1049 0.724916)
			(stroke
				(width 0.1)
				(type default)
			)
			(layer "B.Fab")
		)
		(fp_line
			(start -1.1049 -0.724916)
			(end 1.1049 -0.724916)
			(stroke
				(width 0.1)
				(type default)
			)
			(layer "B.Fab")
		)
		(fp_line
			(start 1.1049 -0.724916)
			(end 1.1049 0.724916)
			(stroke
				(width 0.1)
				(type default)
			)
			(layer "B.Fab")
		)
		(pad "1" smd rect
			(at 0.889 0 270)
			(size 1.016 1.27)
			(layers "B.Cu" "B.Mask" "B.Paste")
			(net "PVCCIN_CPU1")
		)
		(pad "2" smd rect
			(at -0.889 0 270)
			(size 1.016 1.27)
			(layers "B.Cu" "B.Mask" "B.Paste")
			(net "GND")
		)
	)
	(footprint ""
		(layer "B.Cu")
		(at 343.050368 -31.678372 180)
		(property "Reference" "R1458"
			(at 0 0 0)
			(layer "B.SilkS")
			(hide yes)
			(effects
				(font
					(size 1.27 1.27)
				)
				(justify mirror)
			)
		)
		(property "Value" ""
			(at 0 0 0)
			(layer "B.Fab")
			(effects
				(font
					(size 1.27 1.27)
				)
				(justify mirror)
			)
		)
		(duplicate_pad_numbers_are_jumpers no)
		(fp_line
			(start 0.7874 0.4064)
			(end 0.7874 -0.4064)
			(stroke
				(width 0.1524)
				(type default)
			)
			(layer "B.SilkS")
		)
		(fp_line
			(start 0.7874 -0.4064)
			(end -0.7874 -0.4064)
			(stroke
				(width 0.1524)
				(type default)
			)
			(layer "B.SilkS")
		)
		(fp_line
			(start -0.7874 0.4064)
			(end 0.7874 0.4064)
			(stroke
				(width 0.1524)
				(type default)
			)
			(layer "B.SilkS")
		)
		(fp_line
			(start -0.7874 -0.4064)
			(end -0.7874 0.4064)
			(stroke
				(width 0.1524)
				(type default)
			)
			(layer "B.SilkS")
		)
		(fp_line
			(start 0.67945 0.3048)
			(end 0.67945 -0.305054)
			(stroke
				(width 0.1)
				(type default)
			)
			(layer "B.Fab")
		)
		(fp_line
			(start 0.67945 -0.305054)
			(end 0.12065 -0.305054)
			(stroke
				(width 0.1)
				(type default)
			)
			(layer "B.Fab")
		)
		(fp_line
			(start 0.12065 0.3048)
			(end 0.67945 0.3048)
			(stroke
				(width 0.1)
				(type default)
			)
			(layer "B.Fab")
		)
		(fp_line
			(start 0.12065 0.2794)
			(end 0.12065 0.3048)
			(stroke
				(width 0.1)
				(type default)
			)
			(layer "B.Fab")
		)
		(fp_line
			(start 0.12065 -0.2794)
			(end -0.12065 -0.2794)
			(stroke
				(width 0.1)
				(type default)
			)
			(layer "B.Fab")
		)
		(fp_line
			(start 0.12065 -0.305054)
			(end 0.12065 -0.2794)
			(stroke
				(width 0.1)
				(type default)
			)
			(layer "B.Fab")
		)
		(fp_line
			(start -0.120396 0.3048)
			(end -0.120396 0.2794)
			(stroke
				(width 0.1)
				(type default)
			)
			(layer "B.Fab")
		)
		(fp_line
			(start -0.120396 0.2794)
			(end 0.12065 0.2794)
			(stroke
				(width 0.1)
				(type default)
			)
			(layer "B.Fab")
		)
		(fp_line
			(start -0.12065 -0.2794)
			(end -0.12065 -0.3048)
			(stroke
				(width 0.1)
				(type default)
			)
			(layer "B.Fab")
		)
		(fp_line
			(start -0.12065 -0.3048)
			(end -0.67945 -0.3048)
			(stroke
				(width 0.1)
				(type default)
			)
			(layer "B.Fab")
		)
		(fp_line
			(start -0.67945 0.3048)
			(end -0.120396 0.3048)
			(stroke
				(width 0.1)
				(type default)
			)
			(layer "B.Fab")
		)
		(fp_line
			(start -0.67945 -0.3048)
			(end -0.67945 0.3048)
			(stroke
				(width 0.1)
				(type default)
			)
			(layer "B.Fab")
		)
		(pad "1" smd circle
			(at 0.40005 0)
			(size 0 0)
			(layers "B.Cu" "B.Mask" "B.Paste")
			(net "P3V3_AUX")
		)
		(pad "2" smd circle
			(at -0.40005 0)
			(size 0 0)
			(layers "B.Cu" "B.Mask" "B.Paste")
			(net "IRQ_SMI_ACTIVE_N")
		)
	)
	(footprint ""
		(layer "B.Cu")
		(at 421.92448 -156.378148 90)
		(property "Reference" "PR443"
			(at 0 0 90)
			(layer "B.SilkS")
			(hide yes)
			(effects
				(font
					(size 1.27 1.27)
				)
				(justify mirror)
			)
		)
		(property "Value" ""
			(at 0 0 90)
			(layer "B.Fab")
			(effects
				(font
					(size 1.27 1.27)
				)
				(justify mirror)
			)
		)
		(duplicate_pad_numbers_are_jumpers no)
		(fp_line
			(start 0.7874 -0.4064)
			(end -0.7874 -0.4064)
			(stroke
				(width 0.1524)
				(type default)
			)
			(layer "B.SilkS")
		)
		(fp_line
			(start -0.7874 -0.4064)
			(end -0.7874 0.4064)
			(stroke
				(width 0.1524)
				(type default)
			)
			(layer "B.SilkS")
		)
		(fp_line
			(start 0.7874 0.4064)
			(end 0.7874 -0.4064)
			(stroke
				(width 0.1524)
				(type default)
			)
			(layer "B.SilkS")
		)
		(fp_line
			(start -0.7874 0.4064)
			(end 0.7874 0.4064)
			(stroke
				(width 0.1524)
				(type default)
			)
			(layer "B.SilkS")
		)
		(fp_line
			(start 0.67945 -0.305054)
			(end 0.12065 -0.305054)
			(stroke
				(width 0.1)
				(type default)
			)
			(layer "B.Fab")
		)
		(fp_line
			(start 0.12065 -0.305054)
			(end 0.12065 -0.2794)
			(stroke
				(width 0.1)
				(type default)
			)
			(layer "B.Fab")
		)
		(fp_line
			(start -0.12065 -0.3048)
			(end -0.67945 -0.3048)
			(stroke
				(width 0.1)
				(type default)
			)
			(layer "B.Fab")
		)
		(fp_line
			(start -0.67945 -0.3048)
			(end -0.67945 0.3048)
			(stroke
				(width 0.1)
				(type default)
			)
			(layer "B.Fab")
		)
		(fp_line
			(start 0.12065 -0.2794)
			(end -0.12065 -0.2794)
			(stroke
				(width 0.1)
				(type default)
			)
			(layer "B.Fab")
		)
		(fp_line
			(start -0.12065 -0.2794)
			(end -0.12065 -0.3048)
			(stroke
				(width 0.1)
				(type default)
			)
			(layer "B.Fab")
		)
		(fp_line
			(start 0.12065 0.2794)
			(end 0.12065 0.3048)
			(stroke
				(width 0.1)
				(type default)
			)
			(layer "B.Fab")
		)
		(fp_line
			(start -0.120396 0.2794)
			(end 0.12065 0.2794)
			(stroke
				(width 0.1)
				(type default)
			)
			(layer "B.Fab")
		)
		(fp_line
			(start 0.67945 0.3048)
			(end 0.67945 -0.305054)
			(stroke
				(width 0.1)
				(type default)
			)
			(layer "B.Fab")
		)
		(fp_line
			(start 0.12065 0.3048)
			(end 0.67945 0.3048)
			(stroke
				(width 0.1)
				(type default)
			)
			(layer "B.Fab")
		)
		(fp_line
			(start -0.120396 0.3048)
			(end -0.120396 0.2794)
			(stroke
				(width 0.1)
				(type default)
			)
			(layer "B.Fab")
		)
		(fp_line
			(start -0.67945 0.3048)
			(end -0.120396 0.3048)
			(stroke
				(width 0.1)
				(type default)
			)
			(layer "B.Fab")
		)
		(pad "1" smd circle
			(at 0.40005 0 270)
			(size 0 0)
			(layers "B.Cu" "B.Mask" "B.Paste")
			(net "P3V3")
		)
		(pad "2" smd circle
			(at -0.40005 0 270)
			(size 0 0)
			(layers "B.Cu" "B.Mask" "B.Paste")
			(net "PVCCFA_EHV_CPU0_PVCC")
		)
	)
	(footprint ""
		(layer "B.Cu")
		(at 367.898934 -248.498106 -90)
		(property "Reference" "C491"
			(at 0 0 90)
			(layer "B.SilkS")
			(hide yes)
			(effects
				(font
					(size 1.27 1.27)
				)
				(justify mirror)
			)
		)
		(property "Value" ""
			(at 0 0 90)
			(layer "B.Fab")
			(effects
				(font
					(size 1.27 1.27)
				)
				(justify mirror)
			)
		)
		(duplicate_pad_numbers_are_jumpers no)
		(fp_line
			(start -1.524 0.762)
			(end 1.524 0.762)
			(stroke
				(width 0.1524)
				(type default)
			)
			(layer "B.SilkS")
		)
		(fp_line
			(start 1.524 0.762)
			(end 1.524 -0.762)
			(stroke
				(width 0.1524)
				(type default)
			)
			(layer "B.SilkS")
		)
		(fp_line
			(start -1.524 -0.762)
			(end -1.524 0.762)
			(stroke
				(width 0.1524)
				(type default)
			)
			(layer "B.SilkS")
		)
		(fp_line
			(start 1.524 -0.762)
			(end -1.524 -0.762)
			(stroke
				(width 0.1524)
				(type default)
			)
			(layer "B.SilkS")
		)
		(fp_line
			(start -1.1049 0.724916)
			(end -1.1049 -0.724916)
			(stroke
				(width 0.1)
				(type default)
			)
			(layer "B.Fab")
		)
		(fp_line
			(start 1.1049 0.724916)
			(end -1.1049 0.724916)
			(stroke
				(width 0.1)
				(type default)
			)
			(layer "B.Fab")
		)
		(fp_line
			(start -1.1049 -0.724916)
			(end 1.1049 -0.724916)
			(stroke
				(width 0.1)
				(type default)
			)
			(layer "B.Fab")
		)
		(fp_line
			(start 1.1049 -0.724916)
			(end 1.1049 0.724916)
			(stroke
				(width 0.1)
				(type default)
			)
			(layer "B.Fab")
		)
		(pad "1" smd rect
			(at 0.889 0 270)
			(size 1.016 1.27)
			(layers "B.Cu" "B.Mask" "B.Paste")
			(net "PVCCD_HV_CPU0")
		)
		(pad "2" smd rect
			(at -0.889 0 270)
			(size 1.016 1.27)
			(layers "B.Cu" "B.Mask" "B.Paste")
			(net "GND")
		)
	)
	(footprint ""
		(layer "B.Cu")
		(at 138.5443 -22.943058 90)
		(property "Reference" "R4467"
			(at 0 0 90)
			(layer "B.SilkS")
			(hide yes)
			(effects
				(font
					(size 1.27 1.27)
				)
				(justify mirror)
			)
		)
		(property "Value" ""
			(at 0 0 90)
			(layer "B.Fab")
			(effects
				(font
					(size 1.27 1.27)
				)
				(justify mirror)
			)
		)
		(duplicate_pad_numbers_are_jumpers no)
		(fp_line
			(start 0.44323 -0.4064)
			(end -0.41275 -0.4064)
			(stroke
				(width 0.1524)
				(type default)
			)
			(layer "B.SilkS")
		)
		(fp_line
			(start -0.7874 -0.11938)
			(end -0.7874 0.4064)
			(stroke
				(width 0.1524)
				(type default)
			)
			(layer "B.SilkS")
		)
		(fp_line
			(start 0.7874 0.4064)
			(end 0.7874 0.04318)
			(stroke
				(width 0.1524)
				(type default)
			)
			(layer "B.SilkS")
		)
		(fp_line
			(start -0.7874 0.4064)
			(end 0.7874 0.4064)
			(stroke
				(width 0.1524)
				(type default)
			)
			(layer "B.SilkS")
		)
		(fp_line
			(start 0.67945 -0.305054)
			(end 0.12065 -0.305054)
			(stroke
				(width 0.1)
				(type default)
			)
			(layer "B.Fab")
		)
		(fp_line
			(start 0.12065 -0.305054)
			(end 0.12065 -0.2794)
			(stroke
				(width 0.1)
				(type default)
			)
			(layer "B.Fab")
		)
		(fp_line
			(start -0.12065 -0.3048)
			(end -0.67945 -0.3048)
			(stroke
				(width 0.1)
				(type default)
			)
			(layer "B.Fab")
		)
		(fp_line
			(start -0.67945 -0.3048)
			(end -0.67945 0.3048)
			(stroke
				(width 0.1)
				(type default)
			)
			(layer "B.Fab")
		)
		(fp_line
			(start 0.12065 -0.2794)
			(end -0.12065 -0.2794)
			(stroke
				(width 0.1)
				(type default)
			)
			(layer "B.Fab")
		)
		(fp_line
			(start -0.12065 -0.2794)
			(end -0.12065 -0.3048)
			(stroke
				(width 0.1)
				(type default)
			)
			(layer "B.Fab")
		)
		(fp_line
			(start 0.12065 0.2794)
			(end 0.12065 0.3048)
			(stroke
				(width 0.1)
				(type default)
			)
			(layer "B.Fab")
		)
		(fp_line
			(start -0.120396 0.2794)
			(end 0.12065 0.2794)
			(stroke
				(width 0.1)
				(type default)
			)
			(layer "B.Fab")
		)
		(fp_line
			(start 0.67945 0.3048)
			(end 0.67945 -0.305054)
			(stroke
				(width 0.1)
				(type default)
			)
			(layer "B.Fab")
		)
		(fp_line
			(start 0.12065 0.3048)
			(end 0.67945 0.3048)
			(stroke
				(width 0.1)
				(type default)
			)
			(layer "B.Fab")
		)
		(fp_line
			(start -0.120396 0.3048)
			(end -0.120396 0.2794)
			(stroke
				(width 0.1)
				(type default)
			)
			(layer "B.Fab")
		)
		(fp_line
			(start -0.67945 0.3048)
			(end -0.120396 0.3048)
			(stroke
				(width 0.1)
				(type default)
			)
			(layer "B.Fab")
		)
		(pad "1" smd circle
			(at 0.40005 0 270)
			(size 0 0)
			(layers "B.Cu" "B.Mask" "B.Paste")
			(net "USB2_HUB_2_BUF_EXT_R_DP")
		)
		(pad "2" smd circle
			(at -0.40005 0 270)
			(size 0 0)
			(layers "B.Cu" "B.Mask" "B.Paste")
			(net "USB2_HUB_2_BUF_EXT_DP")
		)
	)
	(footprint ""
		(layer "B.Cu")
		(at 454.077324 -13.09116 90)
		(property "Reference" "R429"
			(at 0 0 90)
			(layer "B.SilkS")
			(hide yes)
			(effects
				(font
					(size 1.27 1.27)
				)
				(justify mirror)
			)
		)
		(property "Value" ""
			(at 0 0 90)
			(layer "B.Fab")
			(effects
				(font
					(size 1.27 1.27)
				)
				(justify mirror)
			)
		)
		(duplicate_pad_numbers_are_jumpers no)
		(fp_line
			(start 0.7874 -0.4064)
			(end -0.7874 -0.4064)
			(stroke
				(width 0.1524)
				(type default)
			)
			(layer "B.SilkS")
		)
		(fp_line
			(start -0.7874 -0.4064)
			(end -0.7874 0.4064)
			(stroke
				(width 0.1524)
				(type default)
			)
			(layer "B.SilkS")
		)
		(fp_line
			(start 0.7874 0.4064)
			(end 0.7874 -0.4064)
			(stroke
				(width 0.1524)
				(type default)
			)
			(layer "B.SilkS")
		)
		(fp_line
			(start -0.7874 0.4064)
			(end 0.7874 0.4064)
			(stroke
				(width 0.1524)
				(type default)
			)
			(layer "B.SilkS")
		)
		(fp_line
			(start 0.67945 -0.305054)
			(end 0.12065 -0.305054)
			(stroke
				(width 0.1)
				(type default)
			)
			(layer "B.Fab")
		)
		(fp_line
			(start 0.12065 -0.305054)
			(end 0.12065 -0.2794)
			(stroke
				(width 0.1)
				(type default)
			)
			(layer "B.Fab")
		)
		(fp_line
			(start -0.12065 -0.3048)
			(end -0.67945 -0.3048)
			(stroke
				(width 0.1)
				(type default)
			)
			(layer "B.Fab")
		)
		(fp_line
			(start -0.67945 -0.3048)
			(end -0.67945 0.3048)
			(stroke
				(width 0.1)
				(type default)
			)
			(layer "B.Fab")
		)
		(fp_line
			(start 0.12065 -0.2794)
			(end -0.12065 -0.2794)
			(stroke
				(width 0.1)
				(type default)
			)
			(layer "B.Fab")
		)
		(fp_line
			(start -0.12065 -0.2794)
			(end -0.12065 -0.3048)
			(stroke
				(width 0.1)
				(type default)
			)
			(layer "B.Fab")
		)
		(fp_line
			(start 0.12065 0.2794)
			(end 0.12065 0.3048)
			(stroke
				(width 0.1)
				(type default)
			)
			(layer "B.Fab")
		)
		(fp_line
			(start -0.120396 0.2794)
			(end 0.12065 0.2794)
			(stroke
				(width 0.1)
				(type default)
			)
			(layer "B.Fab")
		)
		(fp_line
			(start 0.67945 0.3048)
			(end 0.67945 -0.305054)
			(stroke
				(width 0.1)
				(type default)
			)
			(layer "B.Fab")
		)
		(fp_line
			(start 0.12065 0.3048)
			(end 0.67945 0.3048)
			(stroke
				(width 0.1)
				(type default)
			)
			(layer "B.Fab")
		)
		(fp_line
			(start -0.120396 0.3048)
			(end -0.120396 0.2794)
			(stroke
				(width 0.1)
				(type default)
			)
			(layer "B.Fab")
		)
		(fp_line
			(start -0.67945 0.3048)
			(end -0.120396 0.3048)
			(stroke
				(width 0.1)
				(type default)
			)
			(layer "B.Fab")
		)
		(pad "1" smd circle
			(at 0.40005 0 270)
			(size 0 0)
			(layers "B.Cu" "B.Mask" "B.Paste")
			(net "OCP_SFF_MAIN_PWR_EN")
		)
		(pad "2" smd circle
			(at -0.40005 0 270)
			(size 0 0)
			(layers "B.Cu" "B.Mask" "B.Paste")
			(net "OCP_SFF_MAIN_PWR_EN_R")
		)
	)
	(footprint ""
		(layer "B.Cu")
		(at 75.363324 -190.705232 -90)
		(property "Reference" "R63"
			(at 0 0 90)
			(layer "B.SilkS")
			(hide yes)
			(effects
				(font
					(size 1.27 1.27)
				)
				(justify mirror)
			)
		)
		(property "Value" ""
			(at 0 0 90)
			(layer "B.Fab")
			(effects
				(font
					(size 1.27 1.27)
				)
				(justify mirror)
			)
		)
		(duplicate_pad_numbers_are_jumpers no)
		(fp_line
			(start -0.7874 0.4064)
			(end 0.7874 0.4064)
			(stroke
				(width 0.1524)
				(type default)
			)
			(layer "B.SilkS")
		)
		(fp_line
			(start 0.7874 0.4064)
			(end 0.7874 -0.4064)
			(stroke
				(width 0.1524)
				(type default)
			)
			(layer "B.SilkS")
		)
		(fp_line
			(start -0.7874 -0.4064)
			(end -0.7874 0.4064)
			(stroke
				(width 0.1524)
				(type default)
			)
			(layer "B.SilkS")
		)
		(fp_line
			(start 0.7874 -0.4064)
			(end -0.7874 -0.4064)
			(stroke
				(width 0.1524)
				(type default)
			)
			(layer "B.SilkS")
		)
		(fp_line
			(start -0.67945 0.3048)
			(end -0.120396 0.3048)
			(stroke
				(width 0.1)
				(type default)
			)
			(layer "B.Fab")
		)
		(fp_line
			(start -0.120396 0.3048)
			(end -0.120396 0.2794)
			(stroke
				(width 0.1)
				(type default)
			)
			(layer "B.Fab")
		)
		(fp_line
			(start 0.12065 0.3048)
			(end 0.67945 0.3048)
			(stroke
				(width 0.1)
				(type default)
			)
			(layer "B.Fab")
		)
		(fp_line
			(start 0.67945 0.3048)
			(end 0.67945 -0.305054)
			(stroke
				(width 0.1)
				(type default)
			)
			(layer "B.Fab")
		)
		(fp_line
			(start -0.120396 0.2794)
			(end 0.12065 0.2794)
			(stroke
				(width 0.1)
				(type default)
			)
			(layer "B.Fab")
		)
		(fp_line
			(start 0.12065 0.2794)
			(end 0.12065 0.3048)
			(stroke
				(width 0.1)
				(type default)
			)
			(layer "B.Fab")
		)
		(fp_line
			(start -0.12065 -0.2794)
			(end -0.12065 -0.3048)
			(stroke
				(width 0.1)
				(type default)
			)
			(layer "B.Fab")
		)
		(fp_line
			(start 0.12065 -0.2794)
			(end -0.12065 -0.2794)
			(stroke
				(width 0.1)
				(type default)
			)
			(layer "B.Fab")
		)
		(fp_line
			(start -0.67945 -0.3048)
			(end -0.67945 0.3048)
			(stroke
				(width 0.1)
				(type default)
			)
			(layer "B.Fab")
		)
		(fp_line
			(start -0.12065 -0.3048)
			(end -0.67945 -0.3048)
			(stroke
				(width 0.1)
				(type default)
			)
			(layer "B.Fab")
		)
		(fp_line
			(start 0.12065 -0.305054)
			(end 0.12065 -0.2794)
			(stroke
				(width 0.1)
				(type default)
			)
			(layer "B.Fab")
		)
		(fp_line
			(start 0.67945 -0.305054)
			(end 0.12065 -0.305054)
			(stroke
				(width 0.1)
				(type default)
			)
			(layer "B.Fab")
		)
		(pad "1" smd circle
			(at 0.40005 0 90)
			(size 0 0)
			(layers "B.Cu" "B.Mask" "B.Paste")
			(net "PECI_CPU_GTL")
		)
		(pad "2" smd circle
			(at -0.40005 0 90)
			(size 0 0)
			(layers "B.Cu" "B.Mask" "B.Paste")
			(net "PECI_CPU1_GTL_R")
		)
	)
	(footprint ""
		(layer "B.Cu")
		(at 155.18638 -13.764768 90)
		(property "Reference" "R2414"
			(at 0 0 90)
			(layer "B.SilkS")
			(hide yes)
			(effects
				(font
					(size 1.27 1.27)
				)
				(justify mirror)
			)
		)
		(property "Value" ""
			(at 0 0 90)
			(layer "B.Fab")
			(effects
				(font
					(size 1.27 1.27)
				)
				(justify mirror)
			)
		)
		(duplicate_pad_numbers_are_jumpers no)
		(fp_line
			(start 0.7874 -0.4064)
			(end -0.7874 -0.4064)
			(stroke
				(width 0.1524)
				(type default)
			)
			(layer "B.SilkS")
		)
		(fp_line
			(start -0.7874 -0.4064)
			(end -0.7874 0.4064)
			(stroke
				(width 0.1524)
				(type default)
			)
			(layer "B.SilkS")
		)
		(fp_line
			(start 0.7874 0.4064)
			(end 0.7874 -0.4064)
			(stroke
				(width 0.1524)
				(type default)
			)
			(layer "B.SilkS")
		)
		(fp_line
			(start -0.7874 0.4064)
			(end 0.7874 0.4064)
			(stroke
				(width 0.1524)
				(type default)
			)
			(layer "B.SilkS")
		)
		(fp_line
			(start 0.67945 -0.305054)
			(end 0.12065 -0.305054)
			(stroke
				(width 0.1)
				(type default)
			)
			(layer "B.Fab")
		)
		(fp_line
			(start 0.12065 -0.305054)
			(end 0.12065 -0.2794)
			(stroke
				(width 0.1)
				(type default)
			)
			(layer "B.Fab")
		)
		(fp_line
			(start -0.12065 -0.3048)
			(end -0.67945 -0.3048)
			(stroke
				(width 0.1)
				(type default)
			)
			(layer "B.Fab")
		)
		(fp_line
			(start -0.67945 -0.3048)
			(end -0.67945 0.3048)
			(stroke
				(width 0.1)
				(type default)
			)
			(layer "B.Fab")
		)
		(fp_line
			(start 0.12065 -0.2794)
			(end -0.12065 -0.2794)
			(stroke
				(width 0.1)
				(type default)
			)
			(layer "B.Fab")
		)
		(fp_line
			(start -0.12065 -0.2794)
			(end -0.12065 -0.3048)
			(stroke
				(width 0.1)
				(type default)
			)
			(layer "B.Fab")
		)
		(fp_line
			(start 0.12065 0.2794)
			(end 0.12065 0.3048)
			(stroke
				(width 0.1)
				(type default)
			)
			(layer "B.Fab")
		)
		(fp_line
			(start -0.120396 0.2794)
			(end 0.12065 0.2794)
			(stroke
				(width 0.1)
				(type default)
			)
			(layer "B.Fab")
		)
		(fp_line
			(start 0.67945 0.3048)
			(end 0.67945 -0.305054)
			(stroke
				(width 0.1)
				(type default)
			)
			(layer "B.Fab")
		)
		(fp_line
			(start 0.12065 0.3048)
			(end 0.67945 0.3048)
			(stroke
				(width 0.1)
				(type default)
			)
			(layer "B.Fab")
		)
		(fp_line
			(start -0.120396 0.3048)
			(end -0.120396 0.2794)
			(stroke
				(width 0.1)
				(type default)
			)
			(layer "B.Fab")
		)
		(fp_line
			(start -0.67945 0.3048)
			(end -0.120396 0.3048)
			(stroke
				(width 0.1)
				(type default)
			)
			(layer "B.Fab")
		)
		(pad "1" smd circle
			(at 0.40005 0 270)
			(size 0 0)
			(layers "B.Cu" "B.Mask" "B.Paste")
			(net "SMB_2_BMC_GPU_SDA")
		)
		(pad "2" smd circle
			(at -0.40005 0 270)
			(size 0 0)
			(layers "B.Cu" "B.Mask" "B.Paste")
			(net "SMB_PCIE2_3V3AUX_SDA_R0")
		)
	)
	(footprint ""
		(layer "B.Cu")
		(at 121.782078 -355.194108)
		(property "Reference" "C2445"
			(at 0 0 0)
			(layer "B.SilkS")
			(hide yes)
			(effects
				(font
					(size 1.27 1.27)
				)
				(justify mirror)
			)
		)
		(property "Value" ""
			(at 0 0 0)
			(layer "B.Fab")
			(effects
				(font
					(size 1.27 1.27)
				)
				(justify mirror)
			)
		)
		(duplicate_pad_numbers_are_jumpers no)
		(fp_line
			(start -0.7874 -0.4064)
			(end -0.7874 0.4064)
			(stroke
				(width 0.1524)
				(type default)
			)
			(layer "B.SilkS")
		)
		(fp_line
			(start -0.7874 0.4064)
			(end 0.7874 0.4064)
			(stroke
				(width 0.1524)
				(type default)
			)
			(layer "B.SilkS")
		)
		(fp_line
			(start 0.7874 -0.4064)
			(end -0.7874 -0.4064)
			(stroke
				(width 0.1524)
				(type default)
			)
			(layer "B.SilkS")
		)
		(fp_line
			(start 0.7874 0.4064)
			(end 0.7874 -0.4064)
			(stroke
				(width 0.1524)
				(type default)
			)
			(layer "B.SilkS")
		)
		(fp_line
			(start -0.67945 -0.3048)
			(end -0.67945 0.3048)
			(stroke
				(width 0.1)
				(type default)
			)
			(layer "B.Fab")
		)
		(fp_line
			(start -0.67945 0.3048)
			(end -0.120396 0.3048)
			(stroke
				(width 0.1)
				(type default)
			)
			(layer "B.Fab")
		)
		(fp_line
			(start -0.12065 -0.3048)
			(end -0.67945 -0.3048)
			(stroke
				(width 0.1)
				(type default)
			)
			(layer "B.Fab")
		)
		(fp_line
			(start -0.12065 -0.2794)
			(end -0.12065 -0.3048)
			(stroke
				(width 0.1)
				(type default)
			)
			(layer "B.Fab")
		)
		(fp_line
			(start -0.120396 0.2794)
			(end 0.12065 0.2794)
			(stroke
				(width 0.1)
				(type default)
			)
			(layer "B.Fab")
		)
		(fp_line
			(start -0.120396 0.3048)
			(end -0.120396 0.2794)
			(stroke
				(width 0.1)
				(type default)
			)
			(layer "B.Fab")
		)
		(fp_line
			(start 0.12065 -0.305054)
			(end 0.12065 -0.2794)
			(stroke
				(width 0.1)
				(type default)
			)
			(layer "B.Fab")
		)
		(fp_line
			(start 0.12065 -0.2794)
			(end -0.12065 -0.2794)
			(stroke
				(width 0.1)
				(type default)
			)
			(layer "B.Fab")
		)
		(fp_line
			(start 0.12065 0.2794)
			(end 0.12065 0.3048)
			(stroke
				(width 0.1)
				(type default)
			)
			(layer "B.Fab")
		)
		(fp_line
			(start 0.12065 0.3048)
			(end 0.67945 0.3048)
			(stroke
				(width 0.1)
				(type default)
			)
			(layer "B.Fab")
		)
		(fp_line
			(start 0.67945 -0.305054)
			(end 0.12065 -0.305054)
			(stroke
				(width 0.1)
				(type default)
			)
			(layer "B.Fab")
		)
		(fp_line
			(start 0.67945 0.3048)
			(end 0.67945 -0.305054)
			(stroke
				(width 0.1)
				(type default)
			)
			(layer "B.Fab")
		)
		(pad "1" smd circle
			(at 0.40005 0 180)
			(size 0 0)
			(layers "B.Cu" "B.Mask" "B.Paste")
			(net "FM_PVPP_HBM_CPU1_EN")
		)
		(pad "2" smd circle
			(at -0.40005 0 180)
			(size 0 0)
			(layers "B.Cu" "B.Mask" "B.Paste")
			(net "GND")
		)
	)
	(footprint ""
		(layer "B.Cu")
		(at 355.826822 -212.049614 180)
		(property "Reference" "C504"
			(at 0 0 0)
			(layer "B.SilkS")
			(hide yes)
			(effects
				(font
					(size 1.27 1.27)
				)
				(justify mirror)
			)
		)
		(property "Value" ""
			(at 0 0 0)
			(layer "B.Fab")
			(effects
				(font
					(size 1.27 1.27)
				)
				(justify mirror)
			)
		)
		(duplicate_pad_numbers_are_jumpers no)
		(fp_line
			(start 1.524 0.762)
			(end 1.524 -0.762)
			(stroke
				(width 0.1524)
				(type default)
			)
			(layer "B.SilkS")
		)
		(fp_line
			(start 1.524 -0.762)
			(end -1.524 -0.762)
			(stroke
				(width 0.1524)
				(type default)
			)
			(layer "B.SilkS")
		)
		(fp_line
			(start -1.524 0.762)
			(end 1.524 0.762)
			(stroke
				(width 0.1524)
				(type default)
			)
			(layer "B.SilkS")
		)
		(fp_line
			(start -1.524 -0.762)
			(end -1.524 0.762)
			(stroke
				(width 0.1524)
				(type default)
			)
			(layer "B.SilkS")
		)
		(fp_line
			(start 1.1049 0.724916)
			(end -1.1049 0.724916)
			(stroke
				(width 0.1)
				(type default)
			)
			(layer "B.Fab")
		)
		(fp_line
			(start 1.1049 -0.724916)
			(end 1.1049 0.724916)
			(stroke
				(width 0.1)
				(type default)
			)
			(layer "B.Fab")
		)
		(fp_line
			(start -1.1049 0.724916)
			(end -1.1049 -0.724916)
			(stroke
				(width 0.1)
				(type default)
			)
			(layer "B.Fab")
		)
		(fp_line
			(start -1.1049 -0.724916)
			(end 1.1049 -0.724916)
			(stroke
				(width 0.1)
				(type default)
			)
			(layer "B.Fab")
		)
		(pad "1" smd rect
			(at 0.889 0 180)
			(size 1.016 1.27)
			(layers "B.Cu" "B.Mask" "B.Paste")
			(net "PVCCFA_EHV_CPU0")
		)
		(pad "2" smd rect
			(at -0.889 0 180)
			(size 1.016 1.27)
			(layers "B.Cu" "B.Mask" "B.Paste")
			(net "GND")
		)
	)
	(footprint ""
		(layer "B.Cu")
		(at 262.1026 -107.039918 -90)
		(property "Reference" "C1314"
			(at 0 0 90)
			(layer "B.SilkS")
			(hide yes)
			(effects
				(font
					(size 1.27 1.27)
				)
				(justify mirror)
			)
		)
		(property "Value" ""
			(at 0 0 90)
			(layer "B.Fab")
			(effects
				(font
					(size 1.27 1.27)
				)
				(justify mirror)
			)
		)
		(duplicate_pad_numbers_are_jumpers no)
		(fp_line
			(start -1.2954 0.5842)
			(end 1.2954 0.5842)
			(stroke
				(width 0.1524)
				(type default)
			)
			(layer "B.SilkS")
		)
		(fp_line
			(start 1.2954 0.5842)
			(end 1.2954 -0.5842)
			(stroke
				(width 0.1524)
				(type default)
			)
			(layer "B.SilkS")
		)
		(fp_line
			(start -1.2954 -0.5842)
			(end -1.2954 0.5842)
			(stroke
				(width 0.1524)
				(type default)
			)
			(layer "B.SilkS")
		)
		(fp_line
			(start 0 -0.5842)
			(end 0 0.5842)
			(stroke
				(width 0.1524)
				(type default)
			)
			(layer "B.SilkS")
		)
		(fp_line
			(start 1.2954 -0.5842)
			(end -1.2954 -0.5842)
			(stroke
				(width 0.1524)
				(type default)
			)
			(layer "B.SilkS")
		)
		(fp_line
			(start -0.8636 0.4572)
			(end 0.8636 0.4572)
			(stroke
				(width 0.1)
				(type default)
			)
			(layer "B.Fab")
		)
		(fp_line
			(start 0.8636 0.4572)
			(end 0.8636 0.4064)
			(stroke
				(width 0.1)
				(type default)
			)
			(layer "B.Fab")
		)
		(fp_line
			(start -1.1938 0.4064)
			(end -0.8636 0.4064)
			(stroke
				(width 0.1)
				(type default)
			)
			(layer "B.Fab")
		)
		(fp_line
			(start -0.8636 0.4064)
			(end -0.8636 0.4572)
			(stroke
				(width 0.1)
				(type default)
			)
			(layer "B.Fab")
		)
		(fp_line
			(start 0.8636 0.4064)
			(end 1.1938 0.4064)
			(stroke
				(width 0.1)
				(type default)
			)
			(layer "B.Fab")
		)
		(fp_line
			(start 1.1938 0.4064)
			(end 1.1938 -0.4064)
			(stroke
				(width 0.1)
				(type default)
			)
			(layer "B.Fab")
		)
		(fp_line
			(start -1.1938 -0.4064)
			(end -1.1938 0.4064)
			(stroke
				(width 0.1)
				(type default)
			)
			(layer "B.Fab")
		)
		(fp_line
			(start -0.8636 -0.4064)
			(end -1.1938 -0.4064)
			(stroke
				(width 0.1)
				(type default)
			)
			(layer "B.Fab")
		)
		(fp_line
			(start 0.8636 -0.4064)
			(end 0.8636 -0.4572)
			(stroke
				(width 0.1)
				(type default)
			)
			(layer "B.Fab")
		)
		(fp_line
			(start 1.1938 -0.4064)
			(end 0.8636 -0.4064)
			(stroke
				(width 0.1)
				(type default)
			)
			(layer "B.Fab")
		)
		(fp_line
			(start -0.8636 -0.4572)
			(end -0.8636 -0.4064)
			(stroke
				(width 0.1)
				(type default)
			)
			(layer "B.Fab")
		)
		(fp_line
			(start 0.8636 -0.4572)
			(end -0.8636 -0.4572)
			(stroke
				(width 0.1)
				(type default)
			)
			(layer "B.Fab")
		)
		(pad "1" smd rect
			(at 0.7366 0 180)
			(size 0.7112 0.8128)
			(layers "B.Cu" "B.Mask" "B.Paste")
			(net "P3V3_AUX_CLK_GEN_VDDPT_CK440")
		)
		(pad "2" smd rect
			(at -0.7366 0 180)
			(size 0.7112 0.8128)
			(layers "B.Cu" "B.Mask" "B.Paste")
			(net "GND")
		)
	)
	(footprint ""
		(layer "B.Cu")
		(at 426.00118 -354.903786 -90)
		(property "Reference" "PC1187"
			(at 0 0 90)
			(layer "B.SilkS")
			(hide yes)
			(effects
				(font
					(size 1.27 1.27)
				)
				(justify mirror)
			)
		)
		(property "Value" ""
			(at 0 0 90)
			(layer "B.Fab")
			(effects
				(font
					(size 1.27 1.27)
				)
				(justify mirror)
			)
		)
		(duplicate_pad_numbers_are_jumpers no)
		(fp_line
			(start -4.533392 2.249932)
			(end 4.533392 2.249932)
			(stroke
				(width 0.1524)
				(type default)
			)
			(layer "B.SilkS")
		)
		(fp_line
			(start 4.533392 2.249932)
			(end 4.533392 -2.249932)
			(stroke
				(width 0.1524)
				(type default)
			)
			(layer "B.SilkS")
		)
		(fp_line
			(start -4.533392 -2.249932)
			(end -4.533392 2.249932)
			(stroke
				(width 0.1524)
				(type default)
			)
			(layer "B.SilkS")
		)
		(fp_line
			(start 4.533392 -2.249932)
			(end -4.533392 -2.249932)
			(stroke
				(width 0.1524)
				(type default)
			)
			(layer "B.SilkS")
		)
		(fp_rect
			(start 5.39242 2.326132)
			(end 4.533392 -2.326132)
			(stroke
				(width 0)
				(type default)
			)
			(fill yes)
			(layer "B.SilkS")
		)
		(fp_line
			(start -3.750056 2.249932)
			(end 3.750056 2.249932)
			(stroke
				(width 0.1)
				(type default)
			)
			(layer "B.Fab")
		)
		(fp_line
			(start 3.750056 2.249932)
			(end 3.750056 -2.249932)
			(stroke
				(width 0.1)
				(type default)
			)
			(layer "B.Fab")
		)
		(fp_line
			(start -3.750056 -2.249932)
			(end -3.750056 2.249932)
			(stroke
				(width 0.1)
				(type default)
			)
			(layer "B.Fab")
		)
		(fp_line
			(start 3.750056 -2.249932)
			(end -3.750056 -2.249932)
			(stroke
				(width 0.1)
				(type default)
			)
			(layer "B.Fab")
		)
		(fp_text user "-"
			(at -4.659122 1.76911 270)
			(unlocked yes)
			(layer "B.SilkS")
			(effects
				(font
					(size 1.905 1.4224)
					(thickness 0.1524)
				)
				(justify left mirror)
			)
		)
		(fp_text user "+"
			(at 6.322314 0.786384 180)
			(unlocked yes)
			(layer "B.SilkS")
			(effects
				(font
					(size 1.905 1.4224)
					(thickness 0.1524)
				)
				(justify left mirror)
			)
		)
		(fp_text user "+"
			(at 6.322314 0.786384 180)
			(unlocked yes)
			(layer "B.Fab")
			(effects
				(font
					(size 1.905 1.4224)
					(thickness 0.1524)
				)
				(justify left mirror)
			)
		)
		(fp_text user "-"
			(at -4.8514 -0.14605 270)
			(unlocked yes)
			(layer "B.Fab")
			(effects
				(font
					(size 1.905 1.4224)
					(thickness 0.1524)
				)
				(justify left mirror)
			)
		)
		(pad "1" smd rect
			(at 3.199892 0 90)
			(size 2.413 2.8194)
			(layers "B.Cu" "B.Mask" "B.Paste")
			(net "PVCCFA_EHV_FIVRA_CPU0")
		)
		(pad "2" smd rect
			(at -3.199892 0 90)
			(size 2.413 2.8194)
			(layers "B.Cu" "B.Mask" "B.Paste")
			(net "GND")
		)
	)
	(footprint ""
		(layer "B.Cu")
		(at 66.107564 -243.345462 180)
		(property "Reference" "R158"
			(at 0 0 0)
			(layer "B.SilkS")
			(hide yes)
			(effects
				(font
					(size 1.27 1.27)
				)
				(justify mirror)
			)
		)
		(property "Value" ""
			(at 0 0 0)
			(layer "B.Fab")
			(effects
				(font
					(size 1.27 1.27)
				)
				(justify mirror)
			)
		)
		(duplicate_pad_numbers_are_jumpers no)
		(fp_line
			(start 0.7874 0.4064)
			(end 0.7874 -0.4064)
			(stroke
				(width 0.1524)
				(type default)
			)
			(layer "B.SilkS")
		)
		(fp_line
			(start 0.7874 -0.4064)
			(end -0.7874 -0.4064)
			(stroke
				(width 0.1524)
				(type default)
			)
			(layer "B.SilkS")
		)
		(fp_line
			(start -0.7874 0.4064)
			(end 0.7874 0.4064)
			(stroke
				(width 0.1524)
				(type default)
			)
			(layer "B.SilkS")
		)
		(fp_line
			(start -0.7874 -0.4064)
			(end -0.7874 0.4064)
			(stroke
				(width 0.1524)
				(type default)
			)
			(layer "B.SilkS")
		)
		(fp_line
			(start 0.67945 0.3048)
			(end 0.67945 -0.305054)
			(stroke
				(width 0.1)
				(type default)
			)
			(layer "B.Fab")
		)
		(fp_line
			(start 0.67945 -0.305054)
			(end 0.12065 -0.305054)
			(stroke
				(width 0.1)
				(type default)
			)
			(layer "B.Fab")
		)
		(fp_line
			(start 0.12065 0.3048)
			(end 0.67945 0.3048)
			(stroke
				(width 0.1)
				(type default)
			)
			(layer "B.Fab")
		)
		(fp_line
			(start 0.12065 0.2794)
			(end 0.12065 0.3048)
			(stroke
				(width 0.1)
				(type default)
			)
			(layer "B.Fab")
		)
		(fp_line
			(start 0.12065 -0.2794)
			(end -0.12065 -0.2794)
			(stroke
				(width 0.1)
				(type default)
			)
			(layer "B.Fab")
		)
		(fp_line
			(start 0.12065 -0.305054)
			(end 0.12065 -0.2794)
			(stroke
				(width 0.1)
				(type default)
			)
			(layer "B.Fab")
		)
		(fp_line
			(start -0.120396 0.3048)
			(end -0.120396 0.2794)
			(stroke
				(width 0.1)
				(type default)
			)
			(layer "B.Fab")
		)
		(fp_line
			(start -0.120396 0.2794)
			(end 0.12065 0.2794)
			(stroke
				(width 0.1)
				(type default)
			)
			(layer "B.Fab")
		)
		(fp_line
			(start -0.12065 -0.2794)
			(end -0.12065 -0.3048)
			(stroke
				(width 0.1)
				(type default)
			)
			(layer "B.Fab")
		)
		(fp_line
			(start -0.12065 -0.3048)
			(end -0.67945 -0.3048)
			(stroke
				(width 0.1)
				(type default)
			)
			(layer "B.Fab")
		)
		(fp_line
			(start -0.67945 0.3048)
			(end -0.120396 0.3048)
			(stroke
				(width 0.1)
				(type default)
			)
			(layer "B.Fab")
		)
		(fp_line
			(start -0.67945 -0.3048)
			(end -0.67945 0.3048)
			(stroke
				(width 0.1)
				(type default)
			)
			(layer "B.Fab")
		)
		(pad "1" smd circle
			(at 0.40005 0)
			(size 0 0)
			(layers "B.Cu" "B.Mask" "B.Paste")
			(net "RST_CPU1_BUF_R_N")
		)
		(pad "2" smd circle
			(at -0.40005 0)
			(size 0 0)
			(layers "B.Cu" "B.Mask" "B.Paste")
			(net "RST_CPU1_LVC1_N")
		)
	)
	(footprint ""
		(layer "B.Cu")
		(at 120.858534 -324.792086 -90)
		(property "Reference" "PC541_P1_4"
			(at 0 0 90)
			(layer "B.SilkS")
			(hide yes)
			(effects
				(font
					(size 1.27 1.27)
				)
				(justify mirror)
			)
		)
		(property "Value" ""
			(at 0 0 90)
			(layer "B.Fab")
			(effects
				(font
					(size 1.27 1.27)
				)
				(justify mirror)
			)
		)
		(duplicate_pad_numbers_are_jumpers no)
		(fp_line
			(start -1.524 0.762)
			(end 1.524 0.762)
			(stroke
				(width 0.1524)
				(type default)
			)
			(layer "B.SilkS")
		)
		(fp_line
			(start 1.524 0.762)
			(end 1.524 -0.762)
			(stroke
				(width 0.1524)
				(type default)
			)
			(layer "B.SilkS")
		)
		(fp_line
			(start -1.524 -0.762)
			(end -1.524 0.762)
			(stroke
				(width 0.1524)
				(type default)
			)
			(layer "B.SilkS")
		)
		(fp_line
			(start 1.524 -0.762)
			(end -1.524 -0.762)
			(stroke
				(width 0.1524)
				(type default)
			)
			(layer "B.SilkS")
		)
		(fp_line
			(start -1.1049 0.724916)
			(end -1.1049 -0.724916)
			(stroke
				(width 0.1)
				(type default)
			)
			(layer "B.Fab")
		)
		(fp_line
			(start 1.1049 0.724916)
			(end -1.1049 0.724916)
			(stroke
				(width 0.1)
				(type default)
			)
			(layer "B.Fab")
		)
		(fp_line
			(start -1.1049 -0.724916)
			(end 1.1049 -0.724916)
			(stroke
				(width 0.1)
				(type default)
			)
			(layer "B.Fab")
		)
		(fp_line
			(start 1.1049 -0.724916)
			(end 1.1049 0.724916)
			(stroke
				(width 0.1)
				(type default)
			)
			(layer "B.Fab")
		)
		(pad "1" smd rect
			(at 0.889 0 270)
			(size 1.016 1.27)
			(layers "B.Cu" "B.Mask" "B.Paste")
			(net "PVCCIN_CPU1")
		)
		(pad "2" smd rect
			(at -0.889 0 270)
			(size 1.016 1.27)
			(layers "B.Cu" "B.Mask" "B.Paste")
			(net "GND")
		)
	)
	(footprint ""
		(layer "B.Cu")
		(at 177.355754 -110.975394 -90)
		(property "Reference" "C1904"
			(at 0 0 90)
			(layer "B.SilkS")
			(hide yes)
			(effects
				(font
					(size 1.27 1.27)
				)
				(justify mirror)
			)
		)
		(property "Value" ""
			(at 0 0 90)
			(layer "B.Fab")
			(effects
				(font
					(size 1.27 1.27)
				)
				(justify mirror)
			)
		)
		(duplicate_pad_numbers_are_jumpers no)
		(fp_line
			(start -0.69215 0.2921)
			(end 0.69215 0.2921)
			(stroke
				(width 0.1524)
				(type default)
			)
			(layer "B.SilkS")
		)
		(fp_line
			(start 0.69215 0.2921)
			(end 0.69215 -0.2921)
			(stroke
				(width 0.1524)
				(type default)
			)
			(layer "B.SilkS")
		)
		(fp_line
			(start -0.69215 -0.2921)
			(end -0.69215 0.2921)
			(stroke
				(width 0.1524)
				(type default)
			)
			(layer "B.SilkS")
		)
		(fp_line
			(start 0.69215 -0.2921)
			(end -0.69215 -0.2921)
			(stroke
				(width 0.1524)
				(type default)
			)
			(layer "B.SilkS")
		)
		(fp_line
			(start -0.51435 0.2794)
			(end 0.51435 0.2794)
			(stroke
				(width 0.1)
				(type default)
			)
			(layer "B.Fab")
		)
		(fp_line
			(start 0.51435 0.2794)
			(end 0.51435 -0.2794)
			(stroke
				(width 0.1)
				(type default)
			)
			(layer "B.Fab")
		)
		(fp_line
			(start -0.51435 -0.2794)
			(end -0.51435 0.2794)
			(stroke
				(width 0.1)
				(type default)
			)
			(layer "B.Fab")
		)
		(fp_line
			(start 0.51435 -0.2794)
			(end -0.51435 -0.2794)
			(stroke
				(width 0.1)
				(type default)
			)
			(layer "B.Fab")
		)
		(pad "1" smd circle
			(at 0.40005 0 90)
			(size 0 0)
			(layers "B.Cu" "B.Mask" "B.Paste")
			(net "P3V3_AUX_FPGA_VCCIO5")
		)
		(pad "2" smd circle
			(at -0.40005 0 90)
			(size 0 0)
			(layers "B.Cu" "B.Mask" "B.Paste")
			(net "GND")
		)
		(zone
			(layer "B.Cu")
			(hatch none 0.5)
			(connect_pads
				(clearance 0)
			)
			(min_thickness 0.25)
			(keepout
				(tracks not_allowed)
				(vias allowed)
				(pads allowed)
				(copperpour not_allowed)
				(footprints allowed)
			)
			(placement
				(enabled no)
				(sheetname "")
			)
			(fill
				(thermal_gap 0.5)
				(thermal_bridge_width 0.5)
				(island_removal_mode 0)
			)
			(polygon
				(pts
					(xy 177.268124 -110.784894) (xy 177.209958 -110.876334) (xy 177.209958 -111.075724) (xy 177.268124 -111.165894)
					(xy 177.443384 -111.165894) (xy 177.501804 -111.075724) (xy 177.501804 -110.876334) (xy 177.443638 -110.784894)
				)
			)
		)
	)
	(footprint ""
		(layer "B.Cu")
		(at 298.47413 -400.999452 -90)
		(property "Reference" "PR2520"
			(at 0 0 90)
			(layer "B.SilkS")
			(hide yes)
			(effects
				(font
					(size 1.27 1.27)
				)
				(justify mirror)
			)
		)
		(property "Value" ""
			(at 0 0 90)
			(layer "B.Fab")
			(effects
				(font
					(size 1.27 1.27)
				)
				(justify mirror)
			)
		)
		(duplicate_pad_numbers_are_jumpers no)
		(fp_line
			(start -0.7874 0.4064)
			(end 0.7874 0.4064)
			(stroke
				(width 0.1524)
				(type default)
			)
			(layer "B.SilkS")
		)
		(fp_line
			(start 0.7874 0.4064)
			(end 0.7874 -0.4064)
			(stroke
				(width 0.1524)
				(type default)
			)
			(layer "B.SilkS")
		)
		(fp_line
			(start -0.7874 -0.4064)
			(end -0.7874 0.4064)
			(stroke
				(width 0.1524)
				(type default)
			)
			(layer "B.SilkS")
		)
		(fp_line
			(start 0.7874 -0.4064)
			(end -0.7874 -0.4064)
			(stroke
				(width 0.1524)
				(type default)
			)
			(layer "B.SilkS")
		)
		(fp_line
			(start -0.67945 0.3048)
			(end -0.120396 0.3048)
			(stroke
				(width 0.1)
				(type default)
			)
			(layer "B.Fab")
		)
		(fp_line
			(start -0.120396 0.3048)
			(end -0.120396 0.2794)
			(stroke
				(width 0.1)
				(type default)
			)
			(layer "B.Fab")
		)
		(fp_line
			(start 0.12065 0.3048)
			(end 0.67945 0.3048)
			(stroke
				(width 0.1)
				(type default)
			)
			(layer "B.Fab")
		)
		(fp_line
			(start 0.67945 0.3048)
			(end 0.67945 -0.305054)
			(stroke
				(width 0.1)
				(type default)
			)
			(layer "B.Fab")
		)
		(fp_line
			(start -0.120396 0.2794)
			(end 0.12065 0.2794)
			(stroke
				(width 0.1)
				(type default)
			)
			(layer "B.Fab")
		)
		(fp_line
			(start 0.12065 0.2794)
			(end 0.12065 0.3048)
			(stroke
				(width 0.1)
				(type default)
			)
			(layer "B.Fab")
		)
		(fp_line
			(start -0.12065 -0.2794)
			(end -0.12065 -0.3048)
			(stroke
				(width 0.1)
				(type default)
			)
			(layer "B.Fab")
		)
		(fp_line
			(start 0.12065 -0.2794)
			(end -0.12065 -0.2794)
			(stroke
				(width 0.1)
				(type default)
			)
			(layer "B.Fab")
		)
		(fp_line
			(start -0.67945 -0.3048)
			(end -0.67945 0.3048)
			(stroke
				(width 0.1)
				(type default)
			)
			(layer "B.Fab")
		)
		(fp_line
			(start -0.12065 -0.3048)
			(end -0.67945 -0.3048)
			(stroke
				(width 0.1)
				(type default)
			)
			(layer "B.Fab")
		)
		(fp_line
			(start 0.12065 -0.305054)
			(end 0.12065 -0.2794)
			(stroke
				(width 0.1)
				(type default)
			)
			(layer "B.Fab")
		)
		(fp_line
			(start 0.67945 -0.305054)
			(end 0.12065 -0.305054)
			(stroke
				(width 0.1)
				(type default)
			)
			(layer "B.Fab")
		)
		(pad "1" smd circle
			(at 0.40005 0 90)
			(size 0 0)
			(layers "B.Cu" "B.Mask" "B.Paste")
			(net "P12V_HSC_SENSE2_P")
		)
		(pad "2" smd circle
			(at -0.40005 0 90)
			(size 0 0)
			(layers "B.Cu" "B.Mask" "B.Paste")
			(net "P12V_HSC_SENSE2_R1_P")
		)
	)
	(footprint ""
		(layer "B.Cu")
		(at 76.463652 -183.470296 -90)
		(property "Reference" "R62"
			(at 0 0 90)
			(layer "B.SilkS")
			(hide yes)
			(effects
				(font
					(size 1.27 1.27)
				)
				(justify mirror)
			)
		)
		(property "Value" ""
			(at 0 0 90)
			(layer "B.Fab")
			(effects
				(font
					(size 1.27 1.27)
				)
				(justify mirror)
			)
		)
		(duplicate_pad_numbers_are_jumpers no)
		(fp_line
			(start -0.7874 0.4064)
			(end 0.7874 0.4064)
			(stroke
				(width 0.1524)
				(type default)
			)
			(layer "B.SilkS")
		)
		(fp_line
			(start 0.7874 0.4064)
			(end 0.7874 -0.4064)
			(stroke
				(width 0.1524)
				(type default)
			)
			(layer "B.SilkS")
		)
		(fp_line
			(start -0.7874 -0.4064)
			(end -0.7874 0.4064)
			(stroke
				(width 0.1524)
				(type default)
			)
			(layer "B.SilkS")
		)
		(fp_line
			(start 0.7874 -0.4064)
			(end -0.7874 -0.4064)
			(stroke
				(width 0.1524)
				(type default)
			)
			(layer "B.SilkS")
		)
		(fp_line
			(start -0.67945 0.3048)
			(end -0.120396 0.3048)
			(stroke
				(width 0.1)
				(type default)
			)
			(layer "B.Fab")
		)
		(fp_line
			(start -0.120396 0.3048)
			(end -0.120396 0.2794)
			(stroke
				(width 0.1)
				(type default)
			)
			(layer "B.Fab")
		)
		(fp_line
			(start 0.12065 0.3048)
			(end 0.67945 0.3048)
			(stroke
				(width 0.1)
				(type default)
			)
			(layer "B.Fab")
		)
		(fp_line
			(start 0.67945 0.3048)
			(end 0.67945 -0.305054)
			(stroke
				(width 0.1)
				(type default)
			)
			(layer "B.Fab")
		)
		(fp_line
			(start -0.120396 0.2794)
			(end 0.12065 0.2794)
			(stroke
				(width 0.1)
				(type default)
			)
			(layer "B.Fab")
		)
		(fp_line
			(start 0.12065 0.2794)
			(end 0.12065 0.3048)
			(stroke
				(width 0.1)
				(type default)
			)
			(layer "B.Fab")
		)
		(fp_line
			(start -0.12065 -0.2794)
			(end -0.12065 -0.3048)
			(stroke
				(width 0.1)
				(type default)
			)
			(layer "B.Fab")
		)
		(fp_line
			(start 0.12065 -0.2794)
			(end -0.12065 -0.2794)
			(stroke
				(width 0.1)
				(type default)
			)
			(layer "B.Fab")
		)
		(fp_line
			(start -0.67945 -0.3048)
			(end -0.67945 0.3048)
			(stroke
				(width 0.1)
				(type default)
			)
			(layer "B.Fab")
		)
		(fp_line
			(start -0.12065 -0.3048)
			(end -0.67945 -0.3048)
			(stroke
				(width 0.1)
				(type default)
			)
			(layer "B.Fab")
		)
		(fp_line
			(start 0.12065 -0.305054)
			(end 0.12065 -0.2794)
			(stroke
				(width 0.1)
				(type default)
			)
			(layer "B.Fab")
		)
		(fp_line
			(start 0.67945 -0.305054)
			(end 0.12065 -0.305054)
			(stroke
				(width 0.1)
				(type default)
			)
			(layer "B.Fab")
		)
		(pad "1" smd circle
			(at 0.40005 0 90)
			(size 0 0)
			(layers "B.Cu" "B.Mask" "B.Paste")
			(net "H_CPU_PREQ_QS_GTL_N")
		)
		(pad "2" smd circle
			(at -0.40005 0 90)
			(size 0 0)
			(layers "B.Cu" "B.Mask" "B.Paste")
			(net "H_CPU1_PREQ_QS_GTL_R_N")
		)
	)
	(footprint ""
		(layer "B.Cu")
		(at 173.913546 -321.554856 -90)
		(property "Reference" "C86"
			(at 0 0 90)
			(layer "B.SilkS")
			(hide yes)
			(effects
				(font
					(size 1.27 1.27)
				)
				(justify mirror)
			)
		)
		(property "Value" ""
			(at 0 0 90)
			(layer "B.Fab")
			(effects
				(font
					(size 1.27 1.27)
				)
				(justify mirror)
			)
		)
		(duplicate_pad_numbers_are_jumpers no)
		(fp_line
			(start -1.524 0.762)
			(end 1.524 0.762)
			(stroke
				(width 0.1524)
				(type default)
			)
			(layer "B.SilkS")
		)
		(fp_line
			(start 1.524 0.762)
			(end 1.524 -0.762)
			(stroke
				(width 0.1524)
				(type default)
			)
			(layer "B.SilkS")
		)
		(fp_line
			(start -1.524 -0.762)
			(end -1.524 0.762)
			(stroke
				(width 0.1524)
				(type default)
			)
			(layer "B.SilkS")
		)
		(fp_line
			(start 1.524 -0.762)
			(end -1.524 -0.762)
			(stroke
				(width 0.1524)
				(type default)
			)
			(layer "B.SilkS")
		)
		(fp_line
			(start -1.1049 0.724916)
			(end -1.1049 -0.724916)
			(stroke
				(width 0.1)
				(type default)
			)
			(layer "B.Fab")
		)
		(fp_line
			(start 1.1049 0.724916)
			(end -1.1049 0.724916)
			(stroke
				(width 0.1)
				(type default)
			)
			(layer "B.Fab")
		)
		(fp_line
			(start -1.1049 -0.724916)
			(end 1.1049 -0.724916)
			(stroke
				(width 0.1)
				(type default)
			)
			(layer "B.Fab")
		)
		(fp_line
			(start 1.1049 -0.724916)
			(end 1.1049 0.724916)
			(stroke
				(width 0.1)
				(type default)
			)
			(layer "B.Fab")
		)
		(pad "1" smd rect
			(at 0.889 0 270)
			(size 1.016 1.27)
			(layers "B.Cu" "B.Mask" "B.Paste")
			(net "P12V_S3_AUX_CPU1_NVDIMM")
		)
		(pad "2" smd rect
			(at -0.889 0 270)
			(size 1.016 1.27)
			(layers "B.Cu" "B.Mask" "B.Paste")
			(net "GND")
		)
	)
	(footprint ""
		(layer "B.Cu")
		(at 423.338244 -193.353436 -90)
		(property "Reference" "R842"
			(at 0 0 90)
			(layer "B.SilkS")
			(hide yes)
			(effects
				(font
					(size 1.27 1.27)
				)
				(justify mirror)
			)
		)
		(property "Value" ""
			(at 0 0 90)
			(layer "B.Fab")
			(effects
				(font
					(size 1.27 1.27)
				)
				(justify mirror)
			)
		)
		(duplicate_pad_numbers_are_jumpers no)
		(fp_line
			(start -0.7874 0.4064)
			(end 0.7874 0.4064)
			(stroke
				(width 0.1524)
				(type default)
			)
			(layer "B.SilkS")
		)
		(fp_line
			(start 0.7874 0.4064)
			(end 0.7874 -0.4064)
			(stroke
				(width 0.1524)
				(type default)
			)
			(layer "B.SilkS")
		)
		(fp_line
			(start -0.7874 -0.4064)
			(end -0.7874 0.4064)
			(stroke
				(width 0.1524)
				(type default)
			)
			(layer "B.SilkS")
		)
		(fp_line
			(start 0.7874 -0.4064)
			(end -0.7874 -0.4064)
			(stroke
				(width 0.1524)
				(type default)
			)
			(layer "B.SilkS")
		)
		(fp_line
			(start -0.67945 0.3048)
			(end -0.120396 0.3048)
			(stroke
				(width 0.1)
				(type default)
			)
			(layer "B.Fab")
		)
		(fp_line
			(start -0.120396 0.3048)
			(end -0.120396 0.2794)
			(stroke
				(width 0.1)
				(type default)
			)
			(layer "B.Fab")
		)
		(fp_line
			(start 0.12065 0.3048)
			(end 0.67945 0.3048)
			(stroke
				(width 0.1)
				(type default)
			)
			(layer "B.Fab")
		)
		(fp_line
			(start 0.67945 0.3048)
			(end 0.67945 -0.305054)
			(stroke
				(width 0.1)
				(type default)
			)
			(layer "B.Fab")
		)
		(fp_line
			(start -0.120396 0.2794)
			(end 0.12065 0.2794)
			(stroke
				(width 0.1)
				(type default)
			)
			(layer "B.Fab")
		)
		(fp_line
			(start 0.12065 0.2794)
			(end 0.12065 0.3048)
			(stroke
				(width 0.1)
				(type default)
			)
			(layer "B.Fab")
		)
		(fp_line
			(start -0.12065 -0.2794)
			(end -0.12065 -0.3048)
			(stroke
				(width 0.1)
				(type default)
			)
			(layer "B.Fab")
		)
		(fp_line
			(start 0.12065 -0.2794)
			(end -0.12065 -0.2794)
			(stroke
				(width 0.1)
				(type default)
			)
			(layer "B.Fab")
		)
		(fp_line
			(start -0.67945 -0.3048)
			(end -0.67945 0.3048)
			(stroke
				(width 0.1)
				(type default)
			)
			(layer "B.Fab")
		)
		(fp_line
			(start -0.12065 -0.3048)
			(end -0.67945 -0.3048)
			(stroke
				(width 0.1)
				(type default)
			)
			(layer "B.Fab")
		)
		(fp_line
			(start 0.12065 -0.305054)
			(end 0.12065 -0.2794)
			(stroke
				(width 0.1)
				(type default)
			)
			(layer "B.Fab")
		)
		(fp_line
			(start 0.67945 -0.305054)
			(end 0.12065 -0.305054)
			(stroke
				(width 0.1)
				(type default)
			)
			(layer "B.Fab")
		)
		(pad "1" smd circle
			(at 0.40005 0 90)
			(size 0 0)
			(layers "B.Cu" "B.Mask" "B.Paste")
			(net "PVCCD_HV_CPU0")
		)
		(pad "2" smd circle
			(at -0.40005 0 90)
			(size 0 0)
			(layers "B.Cu" "B.Mask" "B.Paste")
			(net "RST_M_EF_CPU0_FPGA_N")
		)
	)
	(footprint ""
		(layer "B.Cu")
		(at 264.541 -98.008948 90)
		(property "Reference" "L1"
			(at 0 0 90)
			(layer "B.SilkS")
			(hide yes)
			(effects
				(font
					(size 1.27 1.27)
				)
				(justify mirror)
			)
		)
		(property "Value" ""
			(at 0 0 90)
			(layer "B.Fab")
			(effects
				(font
					(size 1.27 1.27)
				)
				(justify mirror)
			)
		)
		(duplicate_pad_numbers_are_jumpers no)
		(fp_line
			(start 1.63576 -0.8128)
			(end -1.63576 -0.8128)
			(stroke
				(width 0.1524)
				(type default)
			)
			(layer "B.SilkS")
		)
		(fp_line
			(start 1.63576 -0.8128)
			(end 1.63576 0.8128)
			(stroke
				(width 0.1524)
				(type default)
			)
			(layer "B.SilkS")
		)
		(fp_line
			(start -1.63576 -0.8128)
			(end -1.63576 0.8128)
			(stroke
				(width 0.1524)
				(type default)
			)
			(layer "B.SilkS")
		)
		(fp_line
			(start -1.63576 0.8128)
			(end 1.63576 0.8128)
			(stroke
				(width 0.1524)
				(type default)
			)
			(layer "B.SilkS")
		)
		(fp_line
			(start 1.56083 -0.738632)
			(end 1.56083 0.7366)
			(stroke
				(width 0.1)
				(type default)
			)
			(layer "B.Fab")
		)
		(fp_line
			(start -1.560576 -0.738632)
			(end 1.56083 -0.738632)
			(stroke
				(width 0.1)
				(type default)
			)
			(layer "B.Fab")
		)
		(fp_line
			(start 1.56083 0.7366)
			(end 1.524 0.7366)
			(stroke
				(width 0.1)
				(type default)
			)
			(layer "B.Fab")
		)
		(fp_line
			(start 1.524 0.7366)
			(end -1.524 0.7366)
			(stroke
				(width 0.1)
				(type default)
			)
			(layer "B.Fab")
		)
		(fp_line
			(start -1.524 0.7366)
			(end -1.560576 0.7366)
			(stroke
				(width 0.1)
				(type default)
			)
			(layer "B.Fab")
		)
		(fp_line
			(start -1.560576 0.7366)
			(end -1.560576 -0.738632)
			(stroke
				(width 0.1)
				(type default)
			)
			(layer "B.Fab")
		)
		(pad "1" smd rect
			(at 0.94996 0 90)
			(size 1.1176 1.3716)
			(layers "B.Cu" "B.Mask" "B.Paste")
			(net "P3V3_AUX")
		)
		(pad "2" smd rect
			(at -0.94996 0 90)
			(size 1.1176 1.3716)
			(layers "B.Cu" "B.Mask" "B.Paste")
			(net "P3V3_AUX_CLK_GEN_VDD_CK440")
		)
	)
	(footprint ""
		(layer "B.Cu")
		(at 178.10988 -101.564948 180)
		(property "Reference" "R3345"
			(at 0 0 0)
			(layer "B.SilkS")
			(hide yes)
			(effects
				(font
					(size 1.27 1.27)
				)
				(justify mirror)
			)
		)
		(property "Value" ""
			(at 0 0 0)
			(layer "B.Fab")
			(effects
				(font
					(size 1.27 1.27)
				)
				(justify mirror)
			)
		)
		(duplicate_pad_numbers_are_jumpers no)
		(fp_line
			(start 1.2954 0.5842)
			(end 1.2954 -0.5842)
			(stroke
				(width 0.1524)
				(type default)
			)
			(layer "B.SilkS")
		)
		(fp_line
			(start 1.2954 -0.5842)
			(end -1.2954 -0.5842)
			(stroke
				(width 0.1524)
				(type default)
			)
			(layer "B.SilkS")
		)
		(fp_line
			(start -1.2954 0.5842)
			(end 1.2954 0.5842)
			(stroke
				(width 0.1524)
				(type default)
			)
			(layer "B.SilkS")
		)
		(fp_line
			(start -1.2954 -0.5842)
			(end -1.2954 0.5842)
			(stroke
				(width 0.1524)
				(type default)
			)
			(layer "B.SilkS")
		)
		(fp_line
			(start 1.1938 0.4064)
			(end 1.1938 -0.406654)
			(stroke
				(width 0.1)
				(type default)
			)
			(layer "B.Fab")
		)
		(fp_line
			(start 1.1938 -0.406654)
			(end 0.8636 -0.406654)
			(stroke
				(width 0.1)
				(type default)
			)
			(layer "B.Fab")
		)
		(fp_line
			(start 0.8636 0.4572)
			(end 0.8636 0.4318)
			(stroke
				(width 0.1)
				(type default)
			)
			(layer "B.Fab")
		)
		(fp_line
			(start 0.8636 0.4318)
			(end 0.8636 0.4064)
			(stroke
				(width 0.1)
				(type default)
			)
			(layer "B.Fab")
		)
		(fp_line
			(start 0.8636 0.4064)
			(end 1.1938 0.4064)
			(stroke
				(width 0.1)
				(type default)
			)
			(layer "B.Fab")
		)
		(fp_line
			(start 0.8636 -0.406654)
			(end 0.8636 -0.4572)
			(stroke
				(width 0.1)
				(type default)
			)
			(layer "B.Fab")
		)
		(fp_line
			(start 0.8636 -0.4572)
			(end -0.8636 -0.4572)
			(stroke
				(width 0.1)
				(type default)
			)
			(layer "B.Fab")
		)
		(fp_line
			(start -0.8636 0.4572)
			(end 0.8636 0.4572)
			(stroke
				(width 0.1)
				(type default)
			)
			(layer "B.Fab")
		)
		(fp_line
			(start -0.8636 0.4064)
			(end -0.8636 0.4572)
			(stroke
				(width 0.1)
				(type default)
			)
			(layer "B.Fab")
		)
		(fp_line
			(start -0.8636 -0.406654)
			(end -1.1938 -0.406654)
			(stroke
				(width 0.1)
				(type default)
			)
			(layer "B.Fab")
		)
		(fp_line
			(start -0.8636 -0.4572)
			(end -0.8636 -0.406654)
			(stroke
				(width 0.1)
				(type default)
			)
			(layer "B.Fab")
		)
		(fp_line
			(start -1.1938 0.4064)
			(end -0.8636 0.4064)
			(stroke
				(width 0.1)
				(type default)
			)
			(layer "B.Fab")
		)
		(fp_line
			(start -1.1938 -0.406654)
			(end -1.1938 0.4064)
			(stroke
				(width 0.1)
				(type default)
			)
			(layer "B.Fab")
		)
		(pad "1" smd rect
			(at 0.7366 0 90)
			(size 0.7112 0.8128)
			(layers "B.Cu" "B.Mask" "B.Paste")
			(net "P3V3_AUX")
		)
		(pad "2" smd rect
			(at -0.7366 0 90)
			(size 0.7112 0.8128)
			(layers "B.Cu" "B.Mask" "B.Paste")
			(net "P3V3_AUX_FPGA_VCCIO4")
		)
	)
	(footprint ""
		(layer "B.Cu")
		(at 176.45888 -123.948698 -90)
		(property "Reference" "C1946"
			(at 0 0 90)
			(layer "B.SilkS")
			(hide yes)
			(effects
				(font
					(size 1.27 1.27)
				)
				(justify mirror)
			)
		)
		(property "Value" ""
			(at 0 0 90)
			(layer "B.Fab")
			(effects
				(font
					(size 1.27 1.27)
				)
				(justify mirror)
			)
		)
		(duplicate_pad_numbers_are_jumpers no)
		(fp_line
			(start -0.7874 0.4064)
			(end 0.7874 0.4064)
			(stroke
				(width 0.1524)
				(type default)
			)
			(layer "B.SilkS")
		)
		(fp_line
			(start 0.7874 0.4064)
			(end 0.7874 -0.4064)
			(stroke
				(width 0.1524)
				(type default)
			)
			(layer "B.SilkS")
		)
		(fp_line
			(start -0.7874 -0.4064)
			(end -0.7874 0.4064)
			(stroke
				(width 0.1524)
				(type default)
			)
			(layer "B.SilkS")
		)
		(fp_line
			(start 0.7874 -0.4064)
			(end -0.7874 -0.4064)
			(stroke
				(width 0.1524)
				(type default)
			)
			(layer "B.SilkS")
		)
		(fp_line
			(start -0.67945 0.3048)
			(end -0.120396 0.3048)
			(stroke
				(width 0.1)
				(type default)
			)
			(layer "B.Fab")
		)
		(fp_line
			(start -0.120396 0.3048)
			(end -0.120396 0.2794)
			(stroke
				(width 0.1)
				(type default)
			)
			(layer "B.Fab")
		)
		(fp_line
			(start 0.12065 0.3048)
			(end 0.67945 0.3048)
			(stroke
				(width 0.1)
				(type default)
			)
			(layer "B.Fab")
		)
		(fp_line
			(start 0.67945 0.3048)
			(end 0.67945 -0.305054)
			(stroke
				(width 0.1)
				(type default)
			)
			(layer "B.Fab")
		)
		(fp_line
			(start -0.120396 0.2794)
			(end 0.12065 0.2794)
			(stroke
				(width 0.1)
				(type default)
			)
			(layer "B.Fab")
		)
		(fp_line
			(start 0.12065 0.2794)
			(end 0.12065 0.3048)
			(stroke
				(width 0.1)
				(type default)
			)
			(layer "B.Fab")
		)
		(fp_line
			(start -0.12065 -0.2794)
			(end -0.12065 -0.3048)
			(stroke
				(width 0.1)
				(type default)
			)
			(layer "B.Fab")
		)
		(fp_line
			(start 0.12065 -0.2794)
			(end -0.12065 -0.2794)
			(stroke
				(width 0.1)
				(type default)
			)
			(layer "B.Fab")
		)
		(fp_line
			(start -0.67945 -0.3048)
			(end -0.67945 0.3048)
			(stroke
				(width 0.1)
				(type default)
			)
			(layer "B.Fab")
		)
		(fp_line
			(start -0.12065 -0.3048)
			(end -0.67945 -0.3048)
			(stroke
				(width 0.1)
				(type default)
			)
			(layer "B.Fab")
		)
		(fp_line
			(start 0.12065 -0.305054)
			(end 0.12065 -0.2794)
			(stroke
				(width 0.1)
				(type default)
			)
			(layer "B.Fab")
		)
		(fp_line
			(start 0.67945 -0.305054)
			(end 0.12065 -0.305054)
			(stroke
				(width 0.1)
				(type default)
			)
			(layer "B.Fab")
		)
		(pad "1" smd circle
			(at 0.40005 0 90)
			(size 0 0)
			(layers "B.Cu" "B.Mask" "B.Paste")
			(net "P3V3_AUX_FPGA_VCCIO1")
		)
		(pad "2" smd circle
			(at -0.40005 0 90)
			(size 0 0)
			(layers "B.Cu" "B.Mask" "B.Paste")
			(net "GND")
		)
	)
	(footprint ""
		(layer "B.Cu")
		(at 385.46405 -190.82131 90)
		(property "Reference" "R69"
			(at 0 0 90)
			(layer "B.SilkS")
			(hide yes)
			(effects
				(font
					(size 1.27 1.27)
				)
				(justify mirror)
			)
		)
		(property "Value" ""
			(at 0 0 90)
			(layer "B.Fab")
			(effects
				(font
					(size 1.27 1.27)
				)
				(justify mirror)
			)
		)
		(duplicate_pad_numbers_are_jumpers no)
		(fp_line
			(start 0.7874 -0.4064)
			(end -0.7874 -0.4064)
			(stroke
				(width 0.1524)
				(type default)
			)
			(layer "B.SilkS")
		)
		(fp_line
			(start -0.7874 -0.4064)
			(end -0.7874 0.4064)
			(stroke
				(width 0.1524)
				(type default)
			)
			(layer "B.SilkS")
		)
		(fp_line
			(start 0.7874 0.4064)
			(end 0.7874 -0.4064)
			(stroke
				(width 0.1524)
				(type default)
			)
			(layer "B.SilkS")
		)
		(fp_line
			(start -0.7874 0.4064)
			(end 0.7874 0.4064)
			(stroke
				(width 0.1524)
				(type default)
			)
			(layer "B.SilkS")
		)
		(fp_line
			(start 0.67945 -0.305054)
			(end 0.12065 -0.305054)
			(stroke
				(width 0.1)
				(type default)
			)
			(layer "B.Fab")
		)
		(fp_line
			(start 0.12065 -0.305054)
			(end 0.12065 -0.2794)
			(stroke
				(width 0.1)
				(type default)
			)
			(layer "B.Fab")
		)
		(fp_line
			(start -0.12065 -0.3048)
			(end -0.67945 -0.3048)
			(stroke
				(width 0.1)
				(type default)
			)
			(layer "B.Fab")
		)
		(fp_line
			(start -0.67945 -0.3048)
			(end -0.67945 0.3048)
			(stroke
				(width 0.1)
				(type default)
			)
			(layer "B.Fab")
		)
		(fp_line
			(start 0.12065 -0.2794)
			(end -0.12065 -0.2794)
			(stroke
				(width 0.1)
				(type default)
			)
			(layer "B.Fab")
		)
		(fp_line
			(start -0.12065 -0.2794)
			(end -0.12065 -0.3048)
			(stroke
				(width 0.1)
				(type default)
			)
			(layer "B.Fab")
		)
		(fp_line
			(start 0.12065 0.2794)
			(end 0.12065 0.3048)
			(stroke
				(width 0.1)
				(type default)
			)
			(layer "B.Fab")
		)
		(fp_line
			(start -0.120396 0.2794)
			(end 0.12065 0.2794)
			(stroke
				(width 0.1)
				(type default)
			)
			(layer "B.Fab")
		)
		(fp_line
			(start 0.67945 0.3048)
			(end 0.67945 -0.305054)
			(stroke
				(width 0.1)
				(type default)
			)
			(layer "B.Fab")
		)
		(fp_line
			(start 0.12065 0.3048)
			(end 0.67945 0.3048)
			(stroke
				(width 0.1)
				(type default)
			)
			(layer "B.Fab")
		)
		(fp_line
			(start -0.120396 0.3048)
			(end -0.120396 0.2794)
			(stroke
				(width 0.1)
				(type default)
			)
			(layer "B.Fab")
		)
		(fp_line
			(start -0.67945 0.3048)
			(end -0.120396 0.3048)
			(stroke
				(width 0.1)
				(type default)
			)
			(layer "B.Fab")
		)
		(pad "1" smd circle
			(at 0.40005 0 270)
			(size 0 0)
			(layers "B.Cu" "B.Mask" "B.Paste")
			(net "PWRGD_PLT_AUX_CPU0_LVT3")
		)
		(pad "2" smd circle
			(at -0.40005 0 270)
			(size 0 0)
			(layers "B.Cu" "B.Mask" "B.Paste")
			(net "GND")
		)
	)
	(footprint ""
		(layer "B.Cu")
		(at 203.33208 -35.372548 180)
		(property "Reference" "R3579"
			(at 0 0 0)
			(layer "B.SilkS")
			(hide yes)
			(effects
				(font
					(size 1.27 1.27)
				)
				(justify mirror)
			)
		)
		(property "Value" ""
			(at 0 0 0)
			(layer "B.Fab")
			(effects
				(font
					(size 1.27 1.27)
				)
				(justify mirror)
			)
		)
		(duplicate_pad_numbers_are_jumpers no)
		(fp_line
			(start 0.7874 0.4064)
			(end 0.7874 -0.4064)
			(stroke
				(width 0.1524)
				(type default)
			)
			(layer "B.SilkS")
		)
		(fp_line
			(start 0.7874 -0.4064)
			(end -0.7874 -0.4064)
			(stroke
				(width 0.1524)
				(type default)
			)
			(layer "B.SilkS")
		)
		(fp_line
			(start -0.7874 0.4064)
			(end 0.7874 0.4064)
			(stroke
				(width 0.1524)
				(type default)
			)
			(layer "B.SilkS")
		)
		(fp_line
			(start -0.7874 -0.4064)
			(end -0.7874 0.4064)
			(stroke
				(width 0.1524)
				(type default)
			)
			(layer "B.SilkS")
		)
		(fp_line
			(start 0.67945 0.3048)
			(end 0.67945 -0.305054)
			(stroke
				(width 0.1)
				(type default)
			)
			(layer "B.Fab")
		)
		(fp_line
			(start 0.67945 -0.305054)
			(end 0.12065 -0.305054)
			(stroke
				(width 0.1)
				(type default)
			)
			(layer "B.Fab")
		)
		(fp_line
			(start 0.12065 0.3048)
			(end 0.67945 0.3048)
			(stroke
				(width 0.1)
				(type default)
			)
			(layer "B.Fab")
		)
		(fp_line
			(start 0.12065 0.2794)
			(end 0.12065 0.3048)
			(stroke
				(width 0.1)
				(type default)
			)
			(layer "B.Fab")
		)
		(fp_line
			(start 0.12065 -0.2794)
			(end -0.12065 -0.2794)
			(stroke
				(width 0.1)
				(type default)
			)
			(layer "B.Fab")
		)
		(fp_line
			(start 0.12065 -0.305054)
			(end 0.12065 -0.2794)
			(stroke
				(width 0.1)
				(type default)
			)
			(layer "B.Fab")
		)
		(fp_line
			(start -0.120396 0.3048)
			(end -0.120396 0.2794)
			(stroke
				(width 0.1)
				(type default)
			)
			(layer "B.Fab")
		)
		(fp_line
			(start -0.120396 0.2794)
			(end 0.12065 0.2794)
			(stroke
				(width 0.1)
				(type default)
			)
			(layer "B.Fab")
		)
		(fp_line
			(start -0.12065 -0.2794)
			(end -0.12065 -0.3048)
			(stroke
				(width 0.1)
				(type default)
			)
			(layer "B.Fab")
		)
		(fp_line
			(start -0.12065 -0.3048)
			(end -0.67945 -0.3048)
			(stroke
				(width 0.1)
				(type default)
			)
			(layer "B.Fab")
		)
		(fp_line
			(start -0.67945 0.3048)
			(end -0.120396 0.3048)
			(stroke
				(width 0.1)
				(type default)
			)
			(layer "B.Fab")
		)
		(fp_line
			(start -0.67945 -0.3048)
			(end -0.67945 0.3048)
			(stroke
				(width 0.1)
				(type default)
			)
			(layer "B.Fab")
		)
		(pad "1" smd circle
			(at 0.40005 0)
			(size 0 0)
			(layers "B.Cu" "B.Mask" "B.Paste")
			(net "P12V_SCM")
		)
		(pad "2" smd circle
			(at -0.40005 0)
			(size 0 0)
			(layers "B.Cu" "B.Mask" "B.Paste")
			(net "VSENSE_P12V_INA230_5_INN")
		)
	)
	(footprint ""
		(layer "B.Cu")
		(at 38.328346 -319.268856 180)
		(property "Reference" "C56"
			(at 0 0 0)
			(layer "B.SilkS")
			(hide yes)
			(effects
				(font
					(size 1.27 1.27)
				)
				(justify mirror)
			)
		)
		(property "Value" ""
			(at 0 0 0)
			(layer "B.Fab")
			(effects
				(font
					(size 1.27 1.27)
				)
				(justify mirror)
			)
		)
		(duplicate_pad_numbers_are_jumpers no)
		(fp_line
			(start 0.7874 0.4064)
			(end 0.7874 -0.4064)
			(stroke
				(width 0.1524)
				(type default)
			)
			(layer "B.SilkS")
		)
		(fp_line
			(start 0.7874 -0.4064)
			(end -0.7874 -0.4064)
			(stroke
				(width 0.1524)
				(type default)
			)
			(layer "B.SilkS")
		)
		(fp_line
			(start -0.7874 0.4064)
			(end 0.7874 0.4064)
			(stroke
				(width 0.1524)
				(type default)
			)
			(layer "B.SilkS")
		)
		(fp_line
			(start -0.7874 -0.4064)
			(end -0.7874 0.4064)
			(stroke
				(width 0.1524)
				(type default)
			)
			(layer "B.SilkS")
		)
		(fp_line
			(start 0.67945 0.3048)
			(end 0.67945 -0.305054)
			(stroke
				(width 0.1)
				(type default)
			)
			(layer "B.Fab")
		)
		(fp_line
			(start 0.67945 -0.305054)
			(end 0.12065 -0.305054)
			(stroke
				(width 0.1)
				(type default)
			)
			(layer "B.Fab")
		)
		(fp_line
			(start 0.12065 0.3048)
			(end 0.67945 0.3048)
			(stroke
				(width 0.1)
				(type default)
			)
			(layer "B.Fab")
		)
		(fp_line
			(start 0.12065 0.2794)
			(end 0.12065 0.3048)
			(stroke
				(width 0.1)
				(type default)
			)
			(layer "B.Fab")
		)
		(fp_line
			(start 0.12065 -0.2794)
			(end -0.12065 -0.2794)
			(stroke
				(width 0.1)
				(type default)
			)
			(layer "B.Fab")
		)
		(fp_line
			(start 0.12065 -0.305054)
			(end 0.12065 -0.2794)
			(stroke
				(width 0.1)
				(type default)
			)
			(layer "B.Fab")
		)
		(fp_line
			(start -0.120396 0.3048)
			(end -0.120396 0.2794)
			(stroke
				(width 0.1)
				(type default)
			)
			(layer "B.Fab")
		)
		(fp_line
			(start -0.120396 0.2794)
			(end 0.12065 0.2794)
			(stroke
				(width 0.1)
				(type default)
			)
			(layer "B.Fab")
		)
		(fp_line
			(start -0.12065 -0.2794)
			(end -0.12065 -0.3048)
			(stroke
				(width 0.1)
				(type default)
			)
			(layer "B.Fab")
		)
		(fp_line
			(start -0.12065 -0.3048)
			(end -0.67945 -0.3048)
			(stroke
				(width 0.1)
				(type default)
			)
			(layer "B.Fab")
		)
		(fp_line
			(start -0.67945 0.3048)
			(end -0.120396 0.3048)
			(stroke
				(width 0.1)
				(type default)
			)
			(layer "B.Fab")
		)
		(fp_line
			(start -0.67945 -0.3048)
			(end -0.67945 0.3048)
			(stroke
				(width 0.1)
				(type default)
			)
			(layer "B.Fab")
		)
		(pad "1" smd circle
			(at 0.40005 0)
			(size 0 0)
			(layers "B.Cu" "B.Mask" "B.Paste")
			(net "P3V3_AUX")
		)
		(pad "2" smd circle
			(at -0.40005 0)
			(size 0 0)
			(layers "B.Cu" "B.Mask" "B.Paste")
			(net "GND")
		)
	)
	(footprint ""
		(layer "B.Cu")
		(at 185.368438 -315.458602 180)
		(property "Reference" "D48"
			(at 2.132838 -2.945384 0)
			(unlocked yes)
			(layer "B.SilkS")
			(effects
				(font
					(size 0.7874 0.5842)
					(thickness 0.1524)
				)
				(justify left mirror)
			)
		)
		(property "Value" ""
			(at 0 0 0)
			(layer "B.Fab")
			(effects
				(font
					(size 1.27 1.27)
				)
				(justify mirror)
			)
		)
		(duplicate_pad_numbers_are_jumpers no)
		(fp_line
			(start 2.050796 0.700024)
			(end 2.050796 -0.700024)
			(stroke
				(width 0.1524)
				(type default)
			)
			(layer "B.SilkS")
		)
		(fp_line
			(start 2.050796 -0.700024)
			(end -2.050796 -0.700024)
			(stroke
				(width 0.1524)
				(type default)
			)
			(layer "B.SilkS")
		)
		(fp_line
			(start 0.30607 0.500126)
			(end -0.193802 0)
			(stroke
				(width 0.1524)
				(type default)
			)
			(layer "B.SilkS")
		)
		(fp_line
			(start 0.30607 -0.500126)
			(end 0.30607 0.500126)
			(stroke
				(width 0.1524)
				(type default)
			)
			(layer "B.SilkS")
		)
		(fp_line
			(start -0.193802 0)
			(end 0.30607 -0.500126)
			(stroke
				(width 0.1524)
				(type default)
			)
			(layer "B.SilkS")
		)
		(fp_line
			(start -0.293878 -0.500126)
			(end -0.293878 0.500126)
			(stroke
				(width 0.1524)
				(type default)
			)
			(layer "B.SilkS")
		)
		(fp_line
			(start -2.050796 0.700024)
			(end 2.050796 0.700024)
			(stroke
				(width 0.1524)
				(type default)
			)
			(layer "B.SilkS")
		)
		(fp_line
			(start -2.050796 -0.700024)
			(end -2.050796 0.700024)
			(stroke
				(width 0.1524)
				(type default)
			)
			(layer "B.SilkS")
		)
		(fp_line
			(start -2.051304 0.6985)
			(end -2.051304 0.635)
			(stroke
				(width 0.1524)
				(type default)
			)
			(layer "B.SilkS")
		)
		(fp_line
			(start -2.051304 0.635)
			(end -2.152904 0.635)
			(stroke
				(width 0.1524)
				(type default)
			)
			(layer "B.SilkS")
		)
		(fp_line
			(start -2.064004 -0.6731)
			(end -2.064004 -0.6985)
			(stroke
				(width 0.1524)
				(type default)
			)
			(layer "B.SilkS")
		)
		(fp_line
			(start -2.064004 -0.6985)
			(end -2.229104 -0.6985)
			(stroke
				(width 0.1524)
				(type default)
			)
			(layer "B.SilkS")
		)
		(fp_line
			(start -2.152904 0.635)
			(end -2.152904 -0.6985)
			(stroke
				(width 0.1524)
				(type default)
			)
			(layer "B.SilkS")
		)
		(fp_line
			(start -2.152904 -0.6985)
			(end -2.343404 -0.6985)
			(stroke
				(width 0.1524)
				(type default)
			)
			(layer "B.SilkS")
		)
		(fp_line
			(start -2.229104 0.6985)
			(end -2.051304 0.6985)
			(stroke
				(width 0.1524)
				(type default)
			)
			(layer "B.SilkS")
		)
		(fp_line
			(start -2.229104 -0.6985)
			(end -2.229104 0.6985)
			(stroke
				(width 0.1524)
				(type default)
			)
			(layer "B.SilkS")
		)
		(fp_line
			(start -2.343404 0.6985)
			(end -2.216404 0.6985)
			(stroke
				(width 0.1524)
				(type default)
			)
			(layer "B.SilkS")
		)
		(fp_line
			(start -2.343404 -0.6985)
			(end -2.343404 0.6985)
			(stroke
				(width 0.1524)
				(type default)
			)
			(layer "B.SilkS")
		)
		(fp_line
			(start 0.899922 0.700024)
			(end 0.899922 -0.700024)
			(stroke
				(width 0.1)
				(type default)
			)
			(layer "B.Fab")
		)
		(fp_line
			(start 0.899922 -0.700024)
			(end -0.899922 -0.700024)
			(stroke
				(width 0.1)
				(type default)
			)
			(layer "B.Fab")
		)
		(fp_line
			(start -0.899922 0.700024)
			(end 0.899922 0.700024)
			(stroke
				(width 0.1)
				(type default)
			)
			(layer "B.Fab")
		)
		(fp_line
			(start -0.899922 -0.700024)
			(end -0.899922 0.700024)
			(stroke
				(width 0.1)
				(type default)
			)
			(layer "B.Fab")
		)
		(fp_text user "+"
			(at 3.123946 0.762 90)
			(unlocked yes)
			(layer "B.SilkS")
			(effects
				(font
					(size 1.905 1.4224)
					(thickness 0.1524)
				)
				(justify left mirror)
			)
		)
		(fp_text user "-"
			(at -3.869182 -0.885444 0)
			(unlocked yes)
			(layer "B.SilkS")
			(effects
				(font
					(size 1.905 1.4224)
					(thickness 0.1524)
				)
				(justify left mirror)
			)
		)
		(fp_text user "+"
			(at 3.123946 0.762 90)
			(unlocked yes)
			(layer "B.Fab")
			(effects
				(font
					(size 1.905 1.4224)
					(thickness 0.1524)
				)
				(justify left mirror)
			)
		)
		(fp_text user "-"
			(at -3.880104 0.23495 0)
			(unlocked yes)
			(layer "B.Fab")
			(effects
				(font
					(size 1.905 1.4224)
					(thickness 0.1524)
				)
				(justify left mirror)
			)
		)
		(pad "1" smd rect
			(at 1.199896 0 90)
			(size 0.6604 1.3716)
			(layers "B.Cu" "B.Mask" "B.Paste")
			(net "PWRGD_FAIL_CPU1_EF_R1")
		)
		(pad "2" smd rect
			(at -1.199896 0 270)
			(size 0.6604 1.3716)
			(layers "B.Cu" "B.Mask" "B.Paste")
			(net "P3V3_AUX")
		)
	)
	(footprint ""
		(layer "B.Cu")
		(at 371.676676 -366.755426 90)
		(property "Reference" "PC1257"
			(at 0 0 90)
			(layer "B.SilkS")
			(hide yes)
			(effects
				(font
					(size 1.27 1.27)
				)
				(justify mirror)
			)
		)
		(property "Value" ""
			(at 0 0 90)
			(layer "B.Fab")
			(effects
				(font
					(size 1.27 1.27)
				)
				(justify mirror)
			)
		)
		(duplicate_pad_numbers_are_jumpers no)
		(fp_line
			(start 1.524 -0.762)
			(end -1.524 -0.762)
			(stroke
				(width 0.1524)
				(type default)
			)
			(layer "B.SilkS")
		)
		(fp_line
			(start -1.524 -0.762)
			(end -1.524 0.762)
			(stroke
				(width 0.1524)
				(type default)
			)
			(layer "B.SilkS")
		)
		(fp_line
			(start 1.524 0.762)
			(end 1.524 -0.762)
			(stroke
				(width 0.1524)
				(type default)
			)
			(layer "B.SilkS")
		)
		(fp_line
			(start -1.524 0.762)
			(end 1.524 0.762)
			(stroke
				(width 0.1524)
				(type default)
			)
			(layer "B.SilkS")
		)
		(fp_line
			(start 1.1049 -0.724916)
			(end 1.1049 0.724916)
			(stroke
				(width 0.1)
				(type default)
			)
			(layer "B.Fab")
		)
		(fp_line
			(start -1.1049 -0.724916)
			(end 1.1049 -0.724916)
			(stroke
				(width 0.1)
				(type default)
			)
			(layer "B.Fab")
		)
		(fp_line
			(start 1.1049 0.724916)
			(end -1.1049 0.724916)
			(stroke
				(width 0.1)
				(type default)
			)
			(layer "B.Fab")
		)
		(fp_line
			(start -1.1049 0.724916)
			(end -1.1049 -0.724916)
			(stroke
				(width 0.1)
				(type default)
			)
			(layer "B.Fab")
		)
		(pad "1" smd rect
			(at 0.889 0 90)
			(size 1.016 1.27)
			(layers "B.Cu" "B.Mask" "B.Paste")
			(net "PVPP_HBM_CPU0")
		)
		(pad "2" smd rect
			(at -0.889 0 90)
			(size 1.016 1.27)
			(layers "B.Cu" "B.Mask" "B.Paste")
			(net "GND")
		)
	)
	(footprint ""
		(layer "B.Cu")
		(at 191.04864 -319.217548)
		(property "Reference" "R74"
			(at 0 0 0)
			(layer "B.SilkS")
			(hide yes)
			(effects
				(font
					(size 1.27 1.27)
				)
				(justify mirror)
			)
		)
		(property "Value" ""
			(at 0 0 0)
			(layer "B.Fab")
			(effects
				(font
					(size 1.27 1.27)
				)
				(justify mirror)
			)
		)
		(duplicate_pad_numbers_are_jumpers no)
		(fp_line
			(start -0.7874 -0.4064)
			(end -0.7874 0.4064)
			(stroke
				(width 0.1524)
				(type default)
			)
			(layer "B.SilkS")
		)
		(fp_line
			(start -0.7874 0.4064)
			(end 0.7874 0.4064)
			(stroke
				(width 0.1524)
				(type default)
			)
			(layer "B.SilkS")
		)
		(fp_line
			(start 0.7874 -0.4064)
			(end -0.7874 -0.4064)
			(stroke
				(width 0.1524)
				(type default)
			)
			(layer "B.SilkS")
		)
		(fp_line
			(start 0.7874 0.4064)
			(end 0.7874 -0.4064)
			(stroke
				(width 0.1524)
				(type default)
			)
			(layer "B.SilkS")
		)
		(fp_line
			(start -0.67945 -0.3048)
			(end -0.67945 0.3048)
			(stroke
				(width 0.1)
				(type default)
			)
			(layer "B.Fab")
		)
		(fp_line
			(start -0.67945 0.3048)
			(end -0.120396 0.3048)
			(stroke
				(width 0.1)
				(type default)
			)
			(layer "B.Fab")
		)
		(fp_line
			(start -0.12065 -0.3048)
			(end -0.67945 -0.3048)
			(stroke
				(width 0.1)
				(type default)
			)
			(layer "B.Fab")
		)
		(fp_line
			(start -0.12065 -0.2794)
			(end -0.12065 -0.3048)
			(stroke
				(width 0.1)
				(type default)
			)
			(layer "B.Fab")
		)
		(fp_line
			(start -0.120396 0.2794)
			(end 0.12065 0.2794)
			(stroke
				(width 0.1)
				(type default)
			)
			(layer "B.Fab")
		)
		(fp_line
			(start -0.120396 0.3048)
			(end -0.120396 0.2794)
			(stroke
				(width 0.1)
				(type default)
			)
			(layer "B.Fab")
		)
		(fp_line
			(start 0.12065 -0.305054)
			(end 0.12065 -0.2794)
			(stroke
				(width 0.1)
				(type default)
			)
			(layer "B.Fab")
		)
		(fp_line
			(start 0.12065 -0.2794)
			(end -0.12065 -0.2794)
			(stroke
				(width 0.1)
				(type default)
			)
			(layer "B.Fab")
		)
		(fp_line
			(start 0.12065 0.2794)
			(end 0.12065 0.3048)
			(stroke
				(width 0.1)
				(type default)
			)
			(layer "B.Fab")
		)
		(fp_line
			(start 0.12065 0.3048)
			(end 0.67945 0.3048)
			(stroke
				(width 0.1)
				(type default)
			)
			(layer "B.Fab")
		)
		(fp_line
			(start 0.67945 -0.305054)
			(end 0.12065 -0.305054)
			(stroke
				(width 0.1)
				(type default)
			)
			(layer "B.Fab")
		)
		(fp_line
			(start 0.67945 0.3048)
			(end 0.67945 -0.305054)
			(stroke
				(width 0.1)
				(type default)
			)
			(layer "B.Fab")
		)
		(pad "1" smd circle
			(at 0.40005 0 180)
			(size 0 0)
			(layers "B.Cu" "B.Mask" "B.Paste")
			(net "PD_CHG_CPU1_DIMM2_SAA")
		)
		(pad "2" smd circle
			(at -0.40005 0 180)
			(size 0 0)
			(layers "B.Cu" "B.Mask" "B.Paste")
			(net "GND")
		)
	)
	(footprint ""
		(layer "B.Cu")
		(at 362.736638 -182.33771 180)
		(property "Reference" "R1000"
			(at 0 0 0)
			(layer "B.SilkS")
			(hide yes)
			(effects
				(font
					(size 1.27 1.27)
				)
				(justify mirror)
			)
		)
		(property "Value" ""
			(at 0 0 0)
			(layer "B.Fab")
			(effects
				(font
					(size 1.27 1.27)
				)
				(justify mirror)
			)
		)
		(duplicate_pad_numbers_are_jumpers no)
		(fp_line
			(start 0.7874 0.4064)
			(end 0.7874 -0.4064)
			(stroke
				(width 0.1524)
				(type default)
			)
			(layer "B.SilkS")
		)
		(fp_line
			(start 0.7874 -0.4064)
			(end -0.7874 -0.4064)
			(stroke
				(width 0.1524)
				(type default)
			)
			(layer "B.SilkS")
		)
		(fp_line
			(start -0.7874 0.4064)
			(end 0.7874 0.4064)
			(stroke
				(width 0.1524)
				(type default)
			)
			(layer "B.SilkS")
		)
		(fp_line
			(start -0.7874 -0.4064)
			(end -0.7874 0.4064)
			(stroke
				(width 0.1524)
				(type default)
			)
			(layer "B.SilkS")
		)
		(fp_line
			(start 0.67945 0.3048)
			(end 0.67945 -0.305054)
			(stroke
				(width 0.1)
				(type default)
			)
			(layer "B.Fab")
		)
		(fp_line
			(start 0.67945 -0.305054)
			(end 0.12065 -0.305054)
			(stroke
				(width 0.1)
				(type default)
			)
			(layer "B.Fab")
		)
		(fp_line
			(start 0.12065 0.3048)
			(end 0.67945 0.3048)
			(stroke
				(width 0.1)
				(type default)
			)
			(layer "B.Fab")
		)
		(fp_line
			(start 0.12065 0.2794)
			(end 0.12065 0.3048)
			(stroke
				(width 0.1)
				(type default)
			)
			(layer "B.Fab")
		)
		(fp_line
			(start 0.12065 -0.2794)
			(end -0.12065 -0.2794)
			(stroke
				(width 0.1)
				(type default)
			)
			(layer "B.Fab")
		)
		(fp_line
			(start 0.12065 -0.305054)
			(end 0.12065 -0.2794)
			(stroke
				(width 0.1)
				(type default)
			)
			(layer "B.Fab")
		)
		(fp_line
			(start -0.120396 0.3048)
			(end -0.120396 0.2794)
			(stroke
				(width 0.1)
				(type default)
			)
			(layer "B.Fab")
		)
		(fp_line
			(start -0.120396 0.2794)
			(end 0.12065 0.2794)
			(stroke
				(width 0.1)
				(type default)
			)
			(layer "B.Fab")
		)
		(fp_line
			(start -0.12065 -0.2794)
			(end -0.12065 -0.3048)
			(stroke
				(width 0.1)
				(type default)
			)
			(layer "B.Fab")
		)
		(fp_line
			(start -0.12065 -0.3048)
			(end -0.67945 -0.3048)
			(stroke
				(width 0.1)
				(type default)
			)
			(layer "B.Fab")
		)
		(fp_line
			(start -0.67945 0.3048)
			(end -0.120396 0.3048)
			(stroke
				(width 0.1)
				(type default)
			)
			(layer "B.Fab")
		)
		(fp_line
			(start -0.67945 -0.3048)
			(end -0.67945 0.3048)
			(stroke
				(width 0.1)
				(type default)
			)
			(layer "B.Fab")
		)
		(pad "1" smd circle
			(at 0.40005 0)
			(size 0 0)
			(layers "B.Cu" "B.Mask" "B.Paste")
			(net "P3V3")
		)
		(pad "2" smd circle
			(at -0.40005 0)
			(size 0 0)
			(layers "B.Cu" "B.Mask" "B.Paste")
			(net "FM_SMB_PEHPCPU0_PCIE_ALERT_R_N")
		)
	)
	(footprint ""
		(layer "B.Cu")
		(at 362.380276 -333.73568 90)
		(property "Reference" "PC281_P0_3"
			(at 0 0 90)
			(layer "B.SilkS")
			(hide yes)
			(effects
				(font
					(size 1.27 1.27)
				)
				(justify mirror)
			)
		)
		(property "Value" ""
			(at 0 0 90)
			(layer "B.Fab")
			(effects
				(font
					(size 1.27 1.27)
				)
				(justify mirror)
			)
		)
		(duplicate_pad_numbers_are_jumpers no)
		(fp_line
			(start 1.524 -0.762)
			(end -1.524 -0.762)
			(stroke
				(width 0.1524)
				(type default)
			)
			(layer "B.SilkS")
		)
		(fp_line
			(start -1.524 -0.762)
			(end -1.524 0.762)
			(stroke
				(width 0.1524)
				(type default)
			)
			(layer "B.SilkS")
		)
		(fp_line
			(start 1.524 0.762)
			(end 1.524 -0.762)
			(stroke
				(width 0.1524)
				(type default)
			)
			(layer "B.SilkS")
		)
		(fp_line
			(start -1.524 0.762)
			(end 1.524 0.762)
			(stroke
				(width 0.1524)
				(type default)
			)
			(layer "B.SilkS")
		)
		(fp_line
			(start 1.1049 -0.724916)
			(end 1.1049 0.724916)
			(stroke
				(width 0.1)
				(type default)
			)
			(layer "B.Fab")
		)
		(fp_line
			(start -1.1049 -0.724916)
			(end 1.1049 -0.724916)
			(stroke
				(width 0.1)
				(type default)
			)
			(layer "B.Fab")
		)
		(fp_line
			(start 1.1049 0.724916)
			(end -1.1049 0.724916)
			(stroke
				(width 0.1)
				(type default)
			)
			(layer "B.Fab")
		)
		(fp_line
			(start -1.1049 0.724916)
			(end -1.1049 -0.724916)
			(stroke
				(width 0.1)
				(type default)
			)
			(layer "B.Fab")
		)
		(pad "1" smd rect
			(at 0.889 0 90)
			(size 1.016 1.27)
			(layers "B.Cu" "B.Mask" "B.Paste")
			(net "SW_P12V_PVCCIN_CPU0_FLT")
		)
		(pad "2" smd rect
			(at -0.889 0 90)
			(size 1.016 1.27)
			(layers "B.Cu" "B.Mask" "B.Paste")
			(net "GND")
		)
	)
	(footprint ""
		(layer "B.Cu")
		(at 187.88888 -103.723948 180)
		(property "Reference" "C1937"
			(at 0 0 0)
			(layer "B.SilkS")
			(hide yes)
			(effects
				(font
					(size 1.27 1.27)
				)
				(justify mirror)
			)
		)
		(property "Value" ""
			(at 0 0 0)
			(layer "B.Fab")
			(effects
				(font
					(size 1.27 1.27)
				)
				(justify mirror)
			)
		)
		(duplicate_pad_numbers_are_jumpers no)
		(fp_line
			(start 0.7874 0.4064)
			(end 0.7874 -0.4064)
			(stroke
				(width 0.1524)
				(type default)
			)
			(layer "B.SilkS")
		)
		(fp_line
			(start 0.7874 -0.4064)
			(end -0.7874 -0.4064)
			(stroke
				(width 0.1524)
				(type default)
			)
			(layer "B.SilkS")
		)
		(fp_line
			(start -0.7874 0.4064)
			(end 0.7874 0.4064)
			(stroke
				(width 0.1524)
				(type default)
			)
			(layer "B.SilkS")
		)
		(fp_line
			(start -0.7874 -0.4064)
			(end -0.7874 0.4064)
			(stroke
				(width 0.1524)
				(type default)
			)
			(layer "B.SilkS")
		)
		(fp_line
			(start 0.67945 0.3048)
			(end 0.67945 -0.305054)
			(stroke
				(width 0.1)
				(type default)
			)
			(layer "B.Fab")
		)
		(fp_line
			(start 0.67945 -0.305054)
			(end 0.12065 -0.305054)
			(stroke
				(width 0.1)
				(type default)
			)
			(layer "B.Fab")
		)
		(fp_line
			(start 0.12065 0.3048)
			(end 0.67945 0.3048)
			(stroke
				(width 0.1)
				(type default)
			)
			(layer "B.Fab")
		)
		(fp_line
			(start 0.12065 0.2794)
			(end 0.12065 0.3048)
			(stroke
				(width 0.1)
				(type default)
			)
			(layer "B.Fab")
		)
		(fp_line
			(start 0.12065 -0.2794)
			(end -0.12065 -0.2794)
			(stroke
				(width 0.1)
				(type default)
			)
			(layer "B.Fab")
		)
		(fp_line
			(start 0.12065 -0.305054)
			(end 0.12065 -0.2794)
			(stroke
				(width 0.1)
				(type default)
			)
			(layer "B.Fab")
		)
		(fp_line
			(start -0.120396 0.3048)
			(end -0.120396 0.2794)
			(stroke
				(width 0.1)
				(type default)
			)
			(layer "B.Fab")
		)
		(fp_line
			(start -0.120396 0.2794)
			(end 0.12065 0.2794)
			(stroke
				(width 0.1)
				(type default)
			)
			(layer "B.Fab")
		)
		(fp_line
			(start -0.12065 -0.2794)
			(end -0.12065 -0.3048)
			(stroke
				(width 0.1)
				(type default)
			)
			(layer "B.Fab")
		)
		(fp_line
			(start -0.12065 -0.3048)
			(end -0.67945 -0.3048)
			(stroke
				(width 0.1)
				(type default)
			)
			(layer "B.Fab")
		)
		(fp_line
			(start -0.67945 0.3048)
			(end -0.120396 0.3048)
			(stroke
				(width 0.1)
				(type default)
			)
			(layer "B.Fab")
		)
		(fp_line
			(start -0.67945 -0.3048)
			(end -0.67945 0.3048)
			(stroke
				(width 0.1)
				(type default)
			)
			(layer "B.Fab")
		)
		(pad "1" smd circle
			(at 0.40005 0)
			(size 0 0)
			(layers "B.Cu" "B.Mask" "B.Paste")
			(net "P3V3_AUX_FPGA_VCCIO2")
		)
		(pad "2" smd circle
			(at -0.40005 0)
			(size 0 0)
			(layers "B.Cu" "B.Mask" "B.Paste")
			(net "GND")
		)
	)
	(footprint ""
		(layer "B.Cu")
		(at 365.82604 -398.976088)
		(property "Reference" "C1708"
			(at 0 0 0)
			(layer "B.SilkS")
			(hide yes)
			(effects
				(font
					(size 1.27 1.27)
				)
				(justify mirror)
			)
		)
		(property "Value" ""
			(at 0 0 0)
			(layer "B.Fab")
			(effects
				(font
					(size 1.27 1.27)
				)
				(justify mirror)
			)
		)
		(duplicate_pad_numbers_are_jumpers no)
		(fp_line
			(start -0.7874 -0.4064)
			(end -0.7874 0.4064)
			(stroke
				(width 0.1524)
				(type default)
			)
			(layer "B.SilkS")
		)
		(fp_line
			(start -0.7874 0.4064)
			(end 0.7874 0.4064)
			(stroke
				(width 0.1524)
				(type default)
			)
			(layer "B.SilkS")
		)
		(fp_line
			(start 0.7874 -0.4064)
			(end -0.7874 -0.4064)
			(stroke
				(width 0.1524)
				(type default)
			)
			(layer "B.SilkS")
		)
		(fp_line
			(start 0.7874 0.4064)
			(end 0.7874 -0.4064)
			(stroke
				(width 0.1524)
				(type default)
			)
			(layer "B.SilkS")
		)
		(fp_line
			(start -0.67945 -0.3048)
			(end -0.67945 0.3048)
			(stroke
				(width 0.1)
				(type default)
			)
			(layer "B.Fab")
		)
		(fp_line
			(start -0.67945 0.3048)
			(end -0.120396 0.3048)
			(stroke
				(width 0.1)
				(type default)
			)
			(layer "B.Fab")
		)
		(fp_line
			(start -0.12065 -0.3048)
			(end -0.67945 -0.3048)
			(stroke
				(width 0.1)
				(type default)
			)
			(layer "B.Fab")
		)
		(fp_line
			(start -0.12065 -0.2794)
			(end -0.12065 -0.3048)
			(stroke
				(width 0.1)
				(type default)
			)
			(layer "B.Fab")
		)
		(fp_line
			(start -0.120396 0.2794)
			(end 0.12065 0.2794)
			(stroke
				(width 0.1)
				(type default)
			)
			(layer "B.Fab")
		)
		(fp_line
			(start -0.120396 0.3048)
			(end -0.120396 0.2794)
			(stroke
				(width 0.1)
				(type default)
			)
			(layer "B.Fab")
		)
		(fp_line
			(start 0.12065 -0.305054)
			(end 0.12065 -0.2794)
			(stroke
				(width 0.1)
				(type default)
			)
			(layer "B.Fab")
		)
		(fp_line
			(start 0.12065 -0.2794)
			(end -0.12065 -0.2794)
			(stroke
				(width 0.1)
				(type default)
			)
			(layer "B.Fab")
		)
		(fp_line
			(start 0.12065 0.2794)
			(end 0.12065 0.3048)
			(stroke
				(width 0.1)
				(type default)
			)
			(layer "B.Fab")
		)
		(fp_line
			(start 0.12065 0.3048)
			(end 0.67945 0.3048)
			(stroke
				(width 0.1)
				(type default)
			)
			(layer "B.Fab")
		)
		(fp_line
			(start 0.67945 -0.305054)
			(end 0.12065 -0.305054)
			(stroke
				(width 0.1)
				(type default)
			)
			(layer "B.Fab")
		)
		(fp_line
			(start 0.67945 0.3048)
			(end 0.67945 -0.305054)
			(stroke
				(width 0.1)
				(type default)
			)
			(layer "B.Fab")
		)
		(pad "1" smd circle
			(at 0.40005 0 180)
			(size 0 0)
			(layers "B.Cu" "B.Mask" "B.Paste")
			(net "P3V3_AUX")
		)
		(pad "2" smd circle
			(at -0.40005 0 180)
			(size 0 0)
			(layers "B.Cu" "B.Mask" "B.Paste")
			(net "GND")
		)
	)
	(footprint ""
		(layer "B.Cu")
		(at 39.062406 -354.565204 -90)
		(property "Reference" "PR1307"
			(at 0 0 90)
			(layer "B.SilkS")
			(hide yes)
			(effects
				(font
					(size 1.27 1.27)
				)
				(justify mirror)
			)
		)
		(property "Value" ""
			(at 0 0 90)
			(layer "B.Fab")
			(effects
				(font
					(size 1.27 1.27)
				)
				(justify mirror)
			)
		)
		(duplicate_pad_numbers_are_jumpers no)
		(fp_line
			(start -0.7874 0.4064)
			(end 0.7874 0.4064)
			(stroke
				(width 0.1524)
				(type default)
			)
			(layer "B.SilkS")
		)
		(fp_line
			(start 0.7874 0.4064)
			(end 0.7874 -0.4064)
			(stroke
				(width 0.1524)
				(type default)
			)
			(layer "B.SilkS")
		)
		(fp_line
			(start -0.7874 -0.4064)
			(end -0.7874 0.4064)
			(stroke
				(width 0.1524)
				(type default)
			)
			(layer "B.SilkS")
		)
		(fp_line
			(start 0.7874 -0.4064)
			(end -0.7874 -0.4064)
			(stroke
				(width 0.1524)
				(type default)
			)
			(layer "B.SilkS")
		)
		(fp_line
			(start -0.67945 0.3048)
			(end -0.120396 0.3048)
			(stroke
				(width 0.1)
				(type default)
			)
			(layer "B.Fab")
		)
		(fp_line
			(start -0.120396 0.3048)
			(end -0.120396 0.2794)
			(stroke
				(width 0.1)
				(type default)
			)
			(layer "B.Fab")
		)
		(fp_line
			(start 0.12065 0.3048)
			(end 0.67945 0.3048)
			(stroke
				(width 0.1)
				(type default)
			)
			(layer "B.Fab")
		)
		(fp_line
			(start 0.67945 0.3048)
			(end 0.67945 -0.305054)
			(stroke
				(width 0.1)
				(type default)
			)
			(layer "B.Fab")
		)
		(fp_line
			(start -0.120396 0.2794)
			(end 0.12065 0.2794)
			(stroke
				(width 0.1)
				(type default)
			)
			(layer "B.Fab")
		)
		(fp_line
			(start 0.12065 0.2794)
			(end 0.12065 0.3048)
			(stroke
				(width 0.1)
				(type default)
			)
			(layer "B.Fab")
		)
		(fp_line
			(start -0.12065 -0.2794)
			(end -0.12065 -0.3048)
			(stroke
				(width 0.1)
				(type default)
			)
			(layer "B.Fab")
		)
		(fp_line
			(start 0.12065 -0.2794)
			(end -0.12065 -0.2794)
			(stroke
				(width 0.1)
				(type default)
			)
			(layer "B.Fab")
		)
		(fp_line
			(start -0.67945 -0.3048)
			(end -0.67945 0.3048)
			(stroke
				(width 0.1)
				(type default)
			)
			(layer "B.Fab")
		)
		(fp_line
			(start -0.12065 -0.3048)
			(end -0.67945 -0.3048)
			(stroke
				(width 0.1)
				(type default)
			)
			(layer "B.Fab")
		)
		(fp_line
			(start 0.12065 -0.305054)
			(end 0.12065 -0.2794)
			(stroke
				(width 0.1)
				(type default)
			)
			(layer "B.Fab")
		)
		(fp_line
			(start 0.67945 -0.305054)
			(end 0.12065 -0.305054)
			(stroke
				(width 0.1)
				(type default)
			)
			(layer "B.Fab")
		)
		(pad "1" smd circle
			(at 0.40005 0 90)
			(size 0 0)
			(layers "B.Cu" "B.Mask" "B.Paste")
			(net "PVCCFA_EHV_FIVRA_CPU1_PVCC2")
		)
		(pad "2" smd circle
			(at -0.40005 0 90)
			(size 0 0)
			(layers "B.Cu" "B.Mask" "B.Paste")
			(net "PVCCFA_EHV_FIVRA_CPU1_VDD4")
		)
	)
	(footprint ""
		(layer "B.Cu")
		(at 114.734086 -212.049868 180)
		(property "Reference" "C467"
			(at 0 0 0)
			(layer "B.SilkS")
			(hide yes)
			(effects
				(font
					(size 1.27 1.27)
				)
				(justify mirror)
			)
		)
		(property "Value" ""
			(at 0 0 0)
			(layer "B.Fab")
			(effects
				(font
					(size 1.27 1.27)
				)
				(justify mirror)
			)
		)
		(duplicate_pad_numbers_are_jumpers no)
		(fp_line
			(start 1.524 0.762)
			(end 1.524 -0.762)
			(stroke
				(width 0.1524)
				(type default)
			)
			(layer "B.SilkS")
		)
		(fp_line
			(start 1.524 -0.762)
			(end -1.524 -0.762)
			(stroke
				(width 0.1524)
				(type default)
			)
			(layer "B.SilkS")
		)
		(fp_line
			(start -1.524 0.762)
			(end 1.524 0.762)
			(stroke
				(width 0.1524)
				(type default)
			)
			(layer "B.SilkS")
		)
		(fp_line
			(start -1.524 -0.762)
			(end -1.524 0.762)
			(stroke
				(width 0.1524)
				(type default)
			)
			(layer "B.SilkS")
		)
		(fp_line
			(start 1.1049 0.724916)
			(end -1.1049 0.724916)
			(stroke
				(width 0.1)
				(type default)
			)
			(layer "B.Fab")
		)
		(fp_line
			(start 1.1049 -0.724916)
			(end 1.1049 0.724916)
			(stroke
				(width 0.1)
				(type default)
			)
			(layer "B.Fab")
		)
		(fp_line
			(start -1.1049 0.724916)
			(end -1.1049 -0.724916)
			(stroke
				(width 0.1)
				(type default)
			)
			(layer "B.Fab")
		)
		(fp_line
			(start -1.1049 -0.724916)
			(end 1.1049 -0.724916)
			(stroke
				(width 0.1)
				(type default)
			)
			(layer "B.Fab")
		)
		(pad "1" smd rect
			(at 0.889 0 180)
			(size 1.016 1.27)
			(layers "B.Cu" "B.Mask" "B.Paste")
			(net "PVCCD_HV_CPU1")
		)
		(pad "2" smd rect
			(at -0.889 0 180)
			(size 1.016 1.27)
			(layers "B.Cu" "B.Mask" "B.Paste")
			(net "GND")
		)
	)
	(footprint ""
		(layer "B.Cu")
		(at 122.794268 -337.546442 -90)
		(property "Reference" "PC533_P1_4"
			(at 0 0 90)
			(layer "B.SilkS")
			(hide yes)
			(effects
				(font
					(size 1.27 1.27)
				)
				(justify mirror)
			)
		)
		(property "Value" ""
			(at 0 0 90)
			(layer "B.Fab")
			(effects
				(font
					(size 1.27 1.27)
				)
				(justify mirror)
			)
		)
		(duplicate_pad_numbers_are_jumpers no)
		(fp_line
			(start -1.524 0.762)
			(end 1.524 0.762)
			(stroke
				(width 0.1524)
				(type default)
			)
			(layer "B.SilkS")
		)
		(fp_line
			(start 1.524 0.762)
			(end 1.524 -0.762)
			(stroke
				(width 0.1524)
				(type default)
			)
			(layer "B.SilkS")
		)
		(fp_line
			(start -1.524 -0.762)
			(end -1.524 0.762)
			(stroke
				(width 0.1524)
				(type default)
			)
			(layer "B.SilkS")
		)
		(fp_line
			(start 1.524 -0.762)
			(end -1.524 -0.762)
			(stroke
				(width 0.1524)
				(type default)
			)
			(layer "B.SilkS")
		)
		(fp_line
			(start -1.1049 0.724916)
			(end -1.1049 -0.724916)
			(stroke
				(width 0.1)
				(type default)
			)
			(layer "B.Fab")
		)
		(fp_line
			(start 1.1049 0.724916)
			(end -1.1049 0.724916)
			(stroke
				(width 0.1)
				(type default)
			)
			(layer "B.Fab")
		)
		(fp_line
			(start -1.1049 -0.724916)
			(end 1.1049 -0.724916)
			(stroke
				(width 0.1)
				(type default)
			)
			(layer "B.Fab")
		)
		(fp_line
			(start 1.1049 -0.724916)
			(end 1.1049 0.724916)
			(stroke
				(width 0.1)
				(type default)
			)
			(layer "B.Fab")
		)
		(pad "1" smd rect
			(at 0.889 0 270)
			(size 1.016 1.27)
			(layers "B.Cu" "B.Mask" "B.Paste")
			(net "SW_P12V_PVCCIN_CPU1_FLT")
		)
		(pad "2" smd rect
			(at -0.889 0 270)
			(size 1.016 1.27)
			(layers "B.Cu" "B.Mask" "B.Paste")
			(net "GND")
		)
	)
	(footprint ""
		(layer "B.Cu")
		(at 61.25464 -316.608968 90)
		(property "Reference" "R894"
			(at 0 0 90)
			(layer "B.SilkS")
			(hide yes)
			(effects
				(font
					(size 1.27 1.27)
				)
				(justify mirror)
			)
		)
		(property "Value" ""
			(at 0 0 90)
			(layer "B.Fab")
			(effects
				(font
					(size 1.27 1.27)
				)
				(justify mirror)
			)
		)
		(duplicate_pad_numbers_are_jumpers no)
		(fp_line
			(start 0.7874 -0.4064)
			(end -0.7874 -0.4064)
			(stroke
				(width 0.1524)
				(type default)
			)
			(layer "B.SilkS")
		)
		(fp_line
			(start -0.7874 -0.4064)
			(end -0.7874 0.4064)
			(stroke
				(width 0.1524)
				(type default)
			)
			(layer "B.SilkS")
		)
		(fp_line
			(start 0.7874 0.4064)
			(end 0.7874 -0.4064)
			(stroke
				(width 0.1524)
				(type default)
			)
			(layer "B.SilkS")
		)
		(fp_line
			(start -0.7874 0.4064)
			(end 0.7874 0.4064)
			(stroke
				(width 0.1524)
				(type default)
			)
			(layer "B.SilkS")
		)
		(fp_line
			(start 0.67945 -0.305054)
			(end 0.12065 -0.305054)
			(stroke
				(width 0.1)
				(type default)
			)
			(layer "B.Fab")
		)
		(fp_line
			(start 0.12065 -0.305054)
			(end 0.12065 -0.2794)
			(stroke
				(width 0.1)
				(type default)
			)
			(layer "B.Fab")
		)
		(fp_line
			(start -0.12065 -0.3048)
			(end -0.67945 -0.3048)
			(stroke
				(width 0.1)
				(type default)
			)
			(layer "B.Fab")
		)
		(fp_line
			(start -0.67945 -0.3048)
			(end -0.67945 0.3048)
			(stroke
				(width 0.1)
				(type default)
			)
			(layer "B.Fab")
		)
		(fp_line
			(start 0.12065 -0.2794)
			(end -0.12065 -0.2794)
			(stroke
				(width 0.1)
				(type default)
			)
			(layer "B.Fab")
		)
		(fp_line
			(start -0.12065 -0.2794)
			(end -0.12065 -0.3048)
			(stroke
				(width 0.1)
				(type default)
			)
			(layer "B.Fab")
		)
		(fp_line
			(start 0.12065 0.2794)
			(end 0.12065 0.3048)
			(stroke
				(width 0.1)
				(type default)
			)
			(layer "B.Fab")
		)
		(fp_line
			(start -0.120396 0.2794)
			(end 0.12065 0.2794)
			(stroke
				(width 0.1)
				(type default)
			)
			(layer "B.Fab")
		)
		(fp_line
			(start 0.67945 0.3048)
			(end 0.67945 -0.305054)
			(stroke
				(width 0.1)
				(type default)
			)
			(layer "B.Fab")
		)
		(fp_line
			(start 0.12065 0.3048)
			(end 0.67945 0.3048)
			(stroke
				(width 0.1)
				(type default)
			)
			(layer "B.Fab")
		)
		(fp_line
			(start -0.120396 0.3048)
			(end -0.120396 0.2794)
			(stroke
				(width 0.1)
				(type default)
			)
			(layer "B.Fab")
		)
		(fp_line
			(start -0.67945 0.3048)
			(end -0.120396 0.3048)
			(stroke
				(width 0.1)
				(type default)
			)
			(layer "B.Fab")
		)
		(pad "1" smd circle
			(at 0.40005 0 270)
			(size 0 0)
			(layers "B.Cu" "B.Mask" "B.Paste")
			(net "PWRGD_CHA_CPU1_DIMM2")
		)
		(pad "2" smd circle
			(at -0.40005 0 270)
			(size 0 0)
			(layers "B.Cu" "B.Mask" "B.Paste")
			(net "PWRGD_FAIL_CPU1_AB")
		)
	)
	(footprint ""
		(layer "B.Cu")
		(at 32.027368 -162.596322 -90)
		(property "Reference" "PR217"
			(at 0 0 90)
			(layer "B.SilkS")
			(hide yes)
			(effects
				(font
					(size 1.27 1.27)
				)
				(justify mirror)
			)
		)
		(property "Value" ""
			(at 0 0 90)
			(layer "B.Fab")
			(effects
				(font
					(size 1.27 1.27)
				)
				(justify mirror)
			)
		)
		(duplicate_pad_numbers_are_jumpers no)
		(fp_line
			(start -0.7874 0.4064)
			(end 0.7874 0.4064)
			(stroke
				(width 0.1524)
				(type default)
			)
			(layer "B.SilkS")
		)
		(fp_line
			(start 0.7874 0.4064)
			(end 0.7874 -0.4064)
			(stroke
				(width 0.1524)
				(type default)
			)
			(layer "B.SilkS")
		)
		(fp_line
			(start -0.7874 -0.4064)
			(end -0.7874 0.4064)
			(stroke
				(width 0.1524)
				(type default)
			)
			(layer "B.SilkS")
		)
		(fp_line
			(start 0.7874 -0.4064)
			(end -0.7874 -0.4064)
			(stroke
				(width 0.1524)
				(type default)
			)
			(layer "B.SilkS")
		)
		(fp_line
			(start -0.67945 0.3048)
			(end -0.120396 0.3048)
			(stroke
				(width 0.1)
				(type default)
			)
			(layer "B.Fab")
		)
		(fp_line
			(start -0.120396 0.3048)
			(end -0.120396 0.2794)
			(stroke
				(width 0.1)
				(type default)
			)
			(layer "B.Fab")
		)
		(fp_line
			(start 0.12065 0.3048)
			(end 0.67945 0.3048)
			(stroke
				(width 0.1)
				(type default)
			)
			(layer "B.Fab")
		)
		(fp_line
			(start 0.67945 0.3048)
			(end 0.67945 -0.305054)
			(stroke
				(width 0.1)
				(type default)
			)
			(layer "B.Fab")
		)
		(fp_line
			(start -0.120396 0.2794)
			(end 0.12065 0.2794)
			(stroke
				(width 0.1)
				(type default)
			)
			(layer "B.Fab")
		)
		(fp_line
			(start 0.12065 0.2794)
			(end 0.12065 0.3048)
			(stroke
				(width 0.1)
				(type default)
			)
			(layer "B.Fab")
		)
		(fp_line
			(start -0.12065 -0.2794)
			(end -0.12065 -0.3048)
			(stroke
				(width 0.1)
				(type default)
			)
			(layer "B.Fab")
		)
		(fp_line
			(start 0.12065 -0.2794)
			(end -0.12065 -0.2794)
			(stroke
				(width 0.1)
				(type default)
			)
			(layer "B.Fab")
		)
		(fp_line
			(start -0.67945 -0.3048)
			(end -0.67945 0.3048)
			(stroke
				(width 0.1)
				(type default)
			)
			(layer "B.Fab")
		)
		(fp_line
			(start -0.12065 -0.3048)
			(end -0.67945 -0.3048)
			(stroke
				(width 0.1)
				(type default)
			)
			(layer "B.Fab")
		)
		(fp_line
			(start 0.12065 -0.305054)
			(end 0.12065 -0.2794)
			(stroke
				(width 0.1)
				(type default)
			)
			(layer "B.Fab")
		)
		(fp_line
			(start 0.67945 -0.305054)
			(end 0.12065 -0.305054)
			(stroke
				(width 0.1)
				(type default)
			)
			(layer "B.Fab")
		)
		(pad "1" smd circle
			(at 0.40005 0 90)
			(size 0 0)
			(layers "B.Cu" "B.Mask" "B.Paste")
			(net "P3V3_AUX")
		)
		(pad "2" smd circle
			(at -0.40005 0 90)
			(size 0 0)
			(layers "B.Cu" "B.Mask" "B.Paste")
			(net "PVCCD_HV_CPU1_FAULT")
		)
	)
	(footprint ""
		(layer "B.Cu")
		(at 18.838926 -97.330768 -90)
		(property "Reference" "R3655"
			(at 0 0 90)
			(layer "B.SilkS")
			(hide yes)
			(effects
				(font
					(size 1.27 1.27)
				)
				(justify mirror)
			)
		)
		(property "Value" ""
			(at 0 0 90)
			(layer "B.Fab")
			(effects
				(font
					(size 1.27 1.27)
				)
				(justify mirror)
			)
		)
		(duplicate_pad_numbers_are_jumpers no)
		(fp_line
			(start -0.7874 0.4064)
			(end 0.7874 0.4064)
			(stroke
				(width 0.1524)
				(type default)
			)
			(layer "B.SilkS")
		)
		(fp_line
			(start 0.7874 0.4064)
			(end 0.7874 -0.4064)
			(stroke
				(width 0.1524)
				(type default)
			)
			(layer "B.SilkS")
		)
		(fp_line
			(start -0.7874 -0.4064)
			(end -0.7874 0.4064)
			(stroke
				(width 0.1524)
				(type default)
			)
			(layer "B.SilkS")
		)
		(fp_line
			(start 0.7874 -0.4064)
			(end -0.7874 -0.4064)
			(stroke
				(width 0.1524)
				(type default)
			)
			(layer "B.SilkS")
		)
		(fp_line
			(start -0.67945 0.3048)
			(end -0.120396 0.3048)
			(stroke
				(width 0.1)
				(type default)
			)
			(layer "B.Fab")
		)
		(fp_line
			(start -0.120396 0.3048)
			(end -0.120396 0.2794)
			(stroke
				(width 0.1)
				(type default)
			)
			(layer "B.Fab")
		)
		(fp_line
			(start 0.12065 0.3048)
			(end 0.67945 0.3048)
			(stroke
				(width 0.1)
				(type default)
			)
			(layer "B.Fab")
		)
		(fp_line
			(start 0.67945 0.3048)
			(end 0.67945 -0.305054)
			(stroke
				(width 0.1)
				(type default)
			)
			(layer "B.Fab")
		)
		(fp_line
			(start -0.120396 0.2794)
			(end 0.12065 0.2794)
			(stroke
				(width 0.1)
				(type default)
			)
			(layer "B.Fab")
		)
		(fp_line
			(start 0.12065 0.2794)
			(end 0.12065 0.3048)
			(stroke
				(width 0.1)
				(type default)
			)
			(layer "B.Fab")
		)
		(fp_line
			(start -0.12065 -0.2794)
			(end -0.12065 -0.3048)
			(stroke
				(width 0.1)
				(type default)
			)
			(layer "B.Fab")
		)
		(fp_line
			(start 0.12065 -0.2794)
			(end -0.12065 -0.2794)
			(stroke
				(width 0.1)
				(type default)
			)
			(layer "B.Fab")
		)
		(fp_line
			(start -0.67945 -0.3048)
			(end -0.67945 0.3048)
			(stroke
				(width 0.1)
				(type default)
			)
			(layer "B.Fab")
		)
		(fp_line
			(start -0.12065 -0.3048)
			(end -0.67945 -0.3048)
			(stroke
				(width 0.1)
				(type default)
			)
			(layer "B.Fab")
		)
		(fp_line
			(start 0.12065 -0.305054)
			(end 0.12065 -0.2794)
			(stroke
				(width 0.1)
				(type default)
			)
			(layer "B.Fab")
		)
		(fp_line
			(start 0.67945 -0.305054)
			(end 0.12065 -0.305054)
			(stroke
				(width 0.1)
				(type default)
			)
			(layer "B.Fab")
		)
		(pad "1" smd circle
			(at 0.40005 0 90)
			(size 0 0)
			(layers "B.Cu" "B.Mask" "B.Paste")
			(net "P3V3_AUX")
		)
		(pad "2" smd circle
			(at -0.40005 0 90)
			(size 0 0)
			(layers "B.Cu" "B.Mask" "B.Paste")
			(net "P3V3_AUX_USB_HUB")
		)
	)
	(footprint ""
		(layer "B.Cu")
		(at 61.52388 -8.981948 90)
		(property "Reference" "C1836"
			(at 0 0 90)
			(layer "B.SilkS")
			(hide yes)
			(effects
				(font
					(size 1.27 1.27)
				)
				(justify mirror)
			)
		)
		(property "Value" ""
			(at 0 0 90)
			(layer "B.Fab")
			(effects
				(font
					(size 1.27 1.27)
				)
				(justify mirror)
			)
		)
		(duplicate_pad_numbers_are_jumpers no)
		(fp_line
			(start 0.7874 -0.4064)
			(end -0.7874 -0.4064)
			(stroke
				(width 0.1524)
				(type default)
			)
			(layer "B.SilkS")
		)
		(fp_line
			(start -0.7874 -0.4064)
			(end -0.7874 0.4064)
			(stroke
				(width 0.1524)
				(type default)
			)
			(layer "B.SilkS")
		)
		(fp_line
			(start 0.7874 0.4064)
			(end 0.7874 -0.4064)
			(stroke
				(width 0.1524)
				(type default)
			)
			(layer "B.SilkS")
		)
		(fp_line
			(start -0.7874 0.4064)
			(end 0.7874 0.4064)
			(stroke
				(width 0.1524)
				(type default)
			)
			(layer "B.SilkS")
		)
		(fp_line
			(start 0.67945 -0.305054)
			(end 0.12065 -0.305054)
			(stroke
				(width 0.1)
				(type default)
			)
			(layer "B.Fab")
		)
		(fp_line
			(start 0.12065 -0.305054)
			(end 0.12065 -0.2794)
			(stroke
				(width 0.1)
				(type default)
			)
			(layer "B.Fab")
		)
		(fp_line
			(start -0.12065 -0.3048)
			(end -0.67945 -0.3048)
			(stroke
				(width 0.1)
				(type default)
			)
			(layer "B.Fab")
		)
		(fp_line
			(start -0.67945 -0.3048)
			(end -0.67945 0.3048)
			(stroke
				(width 0.1)
				(type default)
			)
			(layer "B.Fab")
		)
		(fp_line
			(start 0.12065 -0.2794)
			(end -0.12065 -0.2794)
			(stroke
				(width 0.1)
				(type default)
			)
			(layer "B.Fab")
		)
		(fp_line
			(start -0.12065 -0.2794)
			(end -0.12065 -0.3048)
			(stroke
				(width 0.1)
				(type default)
			)
			(layer "B.Fab")
		)
		(fp_line
			(start 0.12065 0.2794)
			(end 0.12065 0.3048)
			(stroke
				(width 0.1)
				(type default)
			)
			(layer "B.Fab")
		)
		(fp_line
			(start -0.120396 0.2794)
			(end 0.12065 0.2794)
			(stroke
				(width 0.1)
				(type default)
			)
			(layer "B.Fab")
		)
		(fp_line
			(start 0.67945 0.3048)
			(end 0.67945 -0.305054)
			(stroke
				(width 0.1)
				(type default)
			)
			(layer "B.Fab")
		)
		(fp_line
			(start 0.12065 0.3048)
			(end 0.67945 0.3048)
			(stroke
				(width 0.1)
				(type default)
			)
			(layer "B.Fab")
		)
		(fp_line
			(start -0.120396 0.3048)
			(end -0.120396 0.2794)
			(stroke
				(width 0.1)
				(type default)
			)
			(layer "B.Fab")
		)
		(fp_line
			(start -0.67945 0.3048)
			(end -0.120396 0.3048)
			(stroke
				(width 0.1)
				(type default)
			)
			(layer "B.Fab")
		)
		(pad "1" smd circle
			(at 0.40005 0 270)
			(size 0 0)
			(layers "B.Cu" "B.Mask" "B.Paste")
			(net "P3V3_OCP_V3_2")
		)
		(pad "2" smd circle
			(at -0.40005 0 270)
			(size 0 0)
			(layers "B.Cu" "B.Mask" "B.Paste")
			(net "GND")
		)
	)
	(footprint ""
		(layer "B.Cu")
		(at 450.482716 -10.594086 90)
		(property "Reference" "R422"
			(at 0 0 90)
			(layer "B.SilkS")
			(hide yes)
			(effects
				(font
					(size 1.27 1.27)
				)
				(justify mirror)
			)
		)
		(property "Value" ""
			(at 0 0 90)
			(layer "B.Fab")
			(effects
				(font
					(size 1.27 1.27)
				)
				(justify mirror)
			)
		)
		(duplicate_pad_numbers_are_jumpers no)
		(fp_line
			(start 0.7874 -0.4064)
			(end -0.7874 -0.4064)
			(stroke
				(width 0.1524)
				(type default)
			)
			(layer "B.SilkS")
		)
		(fp_line
			(start -0.7874 -0.4064)
			(end -0.7874 0.4064)
			(stroke
				(width 0.1524)
				(type default)
			)
			(layer "B.SilkS")
		)
		(fp_line
			(start 0.7874 0.4064)
			(end 0.7874 -0.4064)
			(stroke
				(width 0.1524)
				(type default)
			)
			(layer "B.SilkS")
		)
		(fp_line
			(start -0.7874 0.4064)
			(end 0.7874 0.4064)
			(stroke
				(width 0.1524)
				(type default)
			)
			(layer "B.SilkS")
		)
		(fp_line
			(start 0.67945 -0.305054)
			(end 0.12065 -0.305054)
			(stroke
				(width 0.1)
				(type default)
			)
			(layer "B.Fab")
		)
		(fp_line
			(start 0.12065 -0.305054)
			(end 0.12065 -0.2794)
			(stroke
				(width 0.1)
				(type default)
			)
			(layer "B.Fab")
		)
		(fp_line
			(start -0.12065 -0.3048)
			(end -0.67945 -0.3048)
			(stroke
				(width 0.1)
				(type default)
			)
			(layer "B.Fab")
		)
		(fp_line
			(start -0.67945 -0.3048)
			(end -0.67945 0.3048)
			(stroke
				(width 0.1)
				(type default)
			)
			(layer "B.Fab")
		)
		(fp_line
			(start 0.12065 -0.2794)
			(end -0.12065 -0.2794)
			(stroke
				(width 0.1)
				(type default)
			)
			(layer "B.Fab")
		)
		(fp_line
			(start -0.12065 -0.2794)
			(end -0.12065 -0.3048)
			(stroke
				(width 0.1)
				(type default)
			)
			(layer "B.Fab")
		)
		(fp_line
			(start 0.12065 0.2794)
			(end 0.12065 0.3048)
			(stroke
				(width 0.1)
				(type default)
			)
			(layer "B.Fab")
		)
		(fp_line
			(start -0.120396 0.2794)
			(end 0.12065 0.2794)
			(stroke
				(width 0.1)
				(type default)
			)
			(layer "B.Fab")
		)
		(fp_line
			(start 0.67945 0.3048)
			(end 0.67945 -0.305054)
			(stroke
				(width 0.1)
				(type default)
			)
			(layer "B.Fab")
		)
		(fp_line
			(start 0.12065 0.3048)
			(end 0.67945 0.3048)
			(stroke
				(width 0.1)
				(type default)
			)
			(layer "B.Fab")
		)
		(fp_line
			(start -0.120396 0.3048)
			(end -0.120396 0.2794)
			(stroke
				(width 0.1)
				(type default)
			)
			(layer "B.Fab")
		)
		(fp_line
			(start -0.67945 0.3048)
			(end -0.120396 0.3048)
			(stroke
				(width 0.1)
				(type default)
			)
			(layer "B.Fab")
		)
		(pad "1" smd circle
			(at 0.40005 0 270)
			(size 0 0)
			(layers "B.Cu" "B.Mask" "B.Paste")
			(net "SGPIO_OCP_SFF_DATAOUT")
		)
		(pad "2" smd circle
			(at -0.40005 0 270)
			(size 0 0)
			(layers "B.Cu" "B.Mask" "B.Paste")
			(net "GND")
		)
	)
	(footprint ""
		(layer "B.Cu")
		(at 297.45813 -403.031452 90)
		(property "Reference" "PR2515"
			(at 0 0 90)
			(layer "B.SilkS")
			(hide yes)
			(effects
				(font
					(size 1.27 1.27)
				)
				(justify mirror)
			)
		)
		(property "Value" ""
			(at 0 0 90)
			(layer "B.Fab")
			(effects
				(font
					(size 1.27 1.27)
				)
				(justify mirror)
			)
		)
		(duplicate_pad_numbers_are_jumpers no)
		(fp_line
			(start 0.7874 -0.4064)
			(end -0.7874 -0.4064)
			(stroke
				(width 0.1524)
				(type default)
			)
			(layer "B.SilkS")
		)
		(fp_line
			(start -0.7874 -0.4064)
			(end -0.7874 0.4064)
			(stroke
				(width 0.1524)
				(type default)
			)
			(layer "B.SilkS")
		)
		(fp_line
			(start 0.7874 0.4064)
			(end 0.7874 -0.4064)
			(stroke
				(width 0.1524)
				(type default)
			)
			(layer "B.SilkS")
		)
		(fp_line
			(start -0.7874 0.4064)
			(end 0.7874 0.4064)
			(stroke
				(width 0.1524)
				(type default)
			)
			(layer "B.SilkS")
		)
		(fp_line
			(start 0.67945 -0.305054)
			(end 0.12065 -0.305054)
			(stroke
				(width 0.1)
				(type default)
			)
			(layer "B.Fab")
		)
		(fp_line
			(start 0.12065 -0.305054)
			(end 0.12065 -0.2794)
			(stroke
				(width 0.1)
				(type default)
			)
			(layer "B.Fab")
		)
		(fp_line
			(start -0.12065 -0.3048)
			(end -0.67945 -0.3048)
			(stroke
				(width 0.1)
				(type default)
			)
			(layer "B.Fab")
		)
		(fp_line
			(start -0.67945 -0.3048)
			(end -0.67945 0.3048)
			(stroke
				(width 0.1)
				(type default)
			)
			(layer "B.Fab")
		)
		(fp_line
			(start 0.12065 -0.2794)
			(end -0.12065 -0.2794)
			(stroke
				(width 0.1)
				(type default)
			)
			(layer "B.Fab")
		)
		(fp_line
			(start -0.12065 -0.2794)
			(end -0.12065 -0.3048)
			(stroke
				(width 0.1)
				(type default)
			)
			(layer "B.Fab")
		)
		(fp_line
			(start 0.12065 0.2794)
			(end 0.12065 0.3048)
			(stroke
				(width 0.1)
				(type default)
			)
			(layer "B.Fab")
		)
		(fp_line
			(start -0.120396 0.2794)
			(end 0.12065 0.2794)
			(stroke
				(width 0.1)
				(type default)
			)
			(layer "B.Fab")
		)
		(fp_line
			(start 0.67945 0.3048)
			(end 0.67945 -0.305054)
			(stroke
				(width 0.1)
				(type default)
			)
			(layer "B.Fab")
		)
		(fp_line
			(start 0.12065 0.3048)
			(end 0.67945 0.3048)
			(stroke
				(width 0.1)
				(type default)
			)
			(layer "B.Fab")
		)
		(fp_line
			(start -0.120396 0.3048)
			(end -0.120396 0.2794)
			(stroke
				(width 0.1)
				(type default)
			)
			(layer "B.Fab")
		)
		(fp_line
			(start -0.67945 0.3048)
			(end -0.120396 0.3048)
			(stroke
				(width 0.1)
				(type default)
			)
			(layer "B.Fab")
		)
		(pad "1" smd circle
			(at 0.40005 0 270)
			(size 0 0)
			(layers "B.Cu" "B.Mask" "B.Paste")
			(net "P12V_HSC_ADC_N")
		)
		(pad "2" smd circle
			(at -0.40005 0 270)
			(size 0 0)
			(layers "B.Cu" "B.Mask" "B.Paste")
			(net "P12V_HSC_SENSE2_R1_N")
		)
	)
	(footprint ""
		(layer "B.Cu")
		(at 311.84088 -53.304948)
		(property "Reference" "R4106"
			(at 0 0 0)
			(layer "B.SilkS")
			(hide yes)
			(effects
				(font
					(size 1.27 1.27)
				)
				(justify mirror)
			)
		)
		(property "Value" ""
			(at 0 0 0)
			(layer "B.Fab")
			(effects
				(font
					(size 1.27 1.27)
				)
				(justify mirror)
			)
		)
		(duplicate_pad_numbers_are_jumpers no)
		(fp_line
			(start -0.7874 -0.4064)
			(end -0.7874 0.4064)
			(stroke
				(width 0.1524)
				(type default)
			)
			(layer "B.SilkS")
		)
		(fp_line
			(start -0.7874 0.4064)
			(end 0.7874 0.4064)
			(stroke
				(width 0.1524)
				(type default)
			)
			(layer "B.SilkS")
		)
		(fp_line
			(start 0.7874 -0.4064)
			(end -0.7874 -0.4064)
			(stroke
				(width 0.1524)
				(type default)
			)
			(layer "B.SilkS")
		)
		(fp_line
			(start 0.7874 0.4064)
			(end 0.7874 -0.4064)
			(stroke
				(width 0.1524)
				(type default)
			)
			(layer "B.SilkS")
		)
		(fp_line
			(start -0.67945 -0.3048)
			(end -0.67945 0.3048)
			(stroke
				(width 0.1)
				(type default)
			)
			(layer "B.Fab")
		)
		(fp_line
			(start -0.67945 0.3048)
			(end -0.120396 0.3048)
			(stroke
				(width 0.1)
				(type default)
			)
			(layer "B.Fab")
		)
		(fp_line
			(start -0.12065 -0.3048)
			(end -0.67945 -0.3048)
			(stroke
				(width 0.1)
				(type default)
			)
			(layer "B.Fab")
		)
		(fp_line
			(start -0.12065 -0.2794)
			(end -0.12065 -0.3048)
			(stroke
				(width 0.1)
				(type default)
			)
			(layer "B.Fab")
		)
		(fp_line
			(start -0.120396 0.2794)
			(end 0.12065 0.2794)
			(stroke
				(width 0.1)
				(type default)
			)
			(layer "B.Fab")
		)
		(fp_line
			(start -0.120396 0.3048)
			(end -0.120396 0.2794)
			(stroke
				(width 0.1)
				(type default)
			)
			(layer "B.Fab")
		)
		(fp_line
			(start 0.12065 -0.305054)
			(end 0.12065 -0.2794)
			(stroke
				(width 0.1)
				(type default)
			)
			(layer "B.Fab")
		)
		(fp_line
			(start 0.12065 -0.2794)
			(end -0.12065 -0.2794)
			(stroke
				(width 0.1)
				(type default)
			)
			(layer "B.Fab")
		)
		(fp_line
			(start 0.12065 0.2794)
			(end 0.12065 0.3048)
			(stroke
				(width 0.1)
				(type default)
			)
			(layer "B.Fab")
		)
		(fp_line
			(start 0.12065 0.3048)
			(end 0.67945 0.3048)
			(stroke
				(width 0.1)
				(type default)
			)
			(layer "B.Fab")
		)
		(fp_line
			(start 0.67945 -0.305054)
			(end 0.12065 -0.305054)
			(stroke
				(width 0.1)
				(type default)
			)
			(layer "B.Fab")
		)
		(fp_line
			(start 0.67945 0.3048)
			(end 0.67945 -0.305054)
			(stroke
				(width 0.1)
				(type default)
			)
			(layer "B.Fab")
		)
		(pad "1" smd circle
			(at 0.40005 0 180)
			(size 0 0)
			(layers "B.Cu" "B.Mask" "B.Paste")
			(net "PD_GPP_M_8")
		)
		(pad "2" smd circle
			(at -0.40005 0 180)
			(size 0 0)
			(layers "B.Cu" "B.Mask" "B.Paste")
			(net "GND")
		)
	)
	(footprint ""
		(layer "B.Cu")
		(at 147.70608 -13.782548 90)
		(property "Reference" "R4088"
			(at 0 0 90)
			(layer "B.SilkS")
			(hide yes)
			(effects
				(font
					(size 1.27 1.27)
				)
				(justify mirror)
			)
		)
		(property "Value" ""
			(at 0 0 90)
			(layer "B.Fab")
			(effects
				(font
					(size 1.27 1.27)
				)
				(justify mirror)
			)
		)
		(duplicate_pad_numbers_are_jumpers no)
		(fp_line
			(start 0.7874 -0.4064)
			(end -0.7874 -0.4064)
			(stroke
				(width 0.1524)
				(type default)
			)
			(layer "B.SilkS")
		)
		(fp_line
			(start -0.7874 -0.4064)
			(end -0.7874 0.4064)
			(stroke
				(width 0.1524)
				(type default)
			)
			(layer "B.SilkS")
		)
		(fp_line
			(start 0.7874 0.4064)
			(end 0.7874 -0.4064)
			(stroke
				(width 0.1524)
				(type default)
			)
			(layer "B.SilkS")
		)
		(fp_line
			(start -0.7874 0.4064)
			(end 0.7874 0.4064)
			(stroke
				(width 0.1524)
				(type default)
			)
			(layer "B.SilkS")
		)
		(fp_line
			(start 0.67945 -0.305054)
			(end 0.12065 -0.305054)
			(stroke
				(width 0.1)
				(type default)
			)
			(layer "B.Fab")
		)
		(fp_line
			(start 0.12065 -0.305054)
			(end 0.12065 -0.2794)
			(stroke
				(width 0.1)
				(type default)
			)
			(layer "B.Fab")
		)
		(fp_line
			(start -0.12065 -0.3048)
			(end -0.67945 -0.3048)
			(stroke
				(width 0.1)
				(type default)
			)
			(layer "B.Fab")
		)
		(fp_line
			(start -0.67945 -0.3048)
			(end -0.67945 0.3048)
			(stroke
				(width 0.1)
				(type default)
			)
			(layer "B.Fab")
		)
		(fp_line
			(start 0.12065 -0.2794)
			(end -0.12065 -0.2794)
			(stroke
				(width 0.1)
				(type default)
			)
			(layer "B.Fab")
		)
		(fp_line
			(start -0.12065 -0.2794)
			(end -0.12065 -0.3048)
			(stroke
				(width 0.1)
				(type default)
			)
			(layer "B.Fab")
		)
		(fp_line
			(start 0.12065 0.2794)
			(end 0.12065 0.3048)
			(stroke
				(width 0.1)
				(type default)
			)
			(layer "B.Fab")
		)
		(fp_line
			(start -0.120396 0.2794)
			(end 0.12065 0.2794)
			(stroke
				(width 0.1)
				(type default)
			)
			(layer "B.Fab")
		)
		(fp_line
			(start 0.67945 0.3048)
			(end 0.67945 -0.305054)
			(stroke
				(width 0.1)
				(type default)
			)
			(layer "B.Fab")
		)
		(fp_line
			(start 0.12065 0.3048)
			(end 0.67945 0.3048)
			(stroke
				(width 0.1)
				(type default)
			)
			(layer "B.Fab")
		)
		(fp_line
			(start -0.120396 0.3048)
			(end -0.120396 0.2794)
			(stroke
				(width 0.1)
				(type default)
			)
			(layer "B.Fab")
		)
		(fp_line
			(start -0.67945 0.3048)
			(end -0.120396 0.3048)
			(stroke
				(width 0.1)
				(type default)
			)
			(layer "B.Fab")
		)
		(pad "1" smd circle
			(at 0.40005 0 270)
			(size 0 0)
			(layers "B.Cu" "B.Mask" "B.Paste")
			(net "FM_JTAG_BMC_MUX_SEL_FROM_BMC_R")
		)
		(pad "2" smd circle
			(at -0.40005 0 270)
			(size 0 0)
			(layers "B.Cu" "B.Mask" "B.Paste")
			(net "FM_JTAG_BMC_MUX_SEL")
		)
	)
	(footprint ""
		(layer "B.Cu")
		(at 179.755546 -110.975394 -90)
		(property "Reference" "C1113"
			(at 0 0 90)
			(layer "B.SilkS")
			(hide yes)
			(effects
				(font
					(size 1.27 1.27)
				)
				(justify mirror)
			)
		)
		(property "Value" ""
			(at 0 0 90)
			(layer "B.Fab")
			(effects
				(font
					(size 1.27 1.27)
				)
				(justify mirror)
			)
		)
		(duplicate_pad_numbers_are_jumpers no)
		(fp_line
			(start -0.69215 0.2921)
			(end 0.69215 0.2921)
			(stroke
				(width 0.1524)
				(type default)
			)
			(layer "B.SilkS")
		)
		(fp_line
			(start 0.69215 0.2921)
			(end 0.69215 -0.2921)
			(stroke
				(width 0.1524)
				(type default)
			)
			(layer "B.SilkS")
		)
		(fp_line
			(start -0.69215 -0.2921)
			(end -0.69215 0.2921)
			(stroke
				(width 0.1524)
				(type default)
			)
			(layer "B.SilkS")
		)
		(fp_line
			(start 0.69215 -0.2921)
			(end -0.69215 -0.2921)
			(stroke
				(width 0.1524)
				(type default)
			)
			(layer "B.SilkS")
		)
		(fp_line
			(start -0.51435 0.2794)
			(end 0.51435 0.2794)
			(stroke
				(width 0.1)
				(type default)
			)
			(layer "B.Fab")
		)
		(fp_line
			(start 0.51435 0.2794)
			(end 0.51435 -0.2794)
			(stroke
				(width 0.1)
				(type default)
			)
			(layer "B.Fab")
		)
		(fp_line
			(start -0.51435 -0.2794)
			(end -0.51435 0.2794)
			(stroke
				(width 0.1)
				(type default)
			)
			(layer "B.Fab")
		)
		(fp_line
			(start 0.51435 -0.2794)
			(end -0.51435 -0.2794)
			(stroke
				(width 0.1)
				(type default)
			)
			(layer "B.Fab")
		)
		(pad "1" smd circle
			(at 0.40005 0 90)
			(size 0 0)
			(layers "B.Cu" "B.Mask" "B.Paste")
			(net "P3V3_AUX_FPGA_VCCIO3")
		)
		(pad "2" smd circle
			(at -0.40005 0 90)
			(size 0 0)
			(layers "B.Cu" "B.Mask" "B.Paste")
			(net "GND")
		)
		(zone
			(layer "B.Cu")
			(hatch none 0.5)
			(connect_pads
				(clearance 0)
			)
			(min_thickness 0.25)
			(keepout
				(tracks not_allowed)
				(vias allowed)
				(pads allowed)
				(copperpour not_allowed)
				(footprints allowed)
			)
			(placement
				(enabled no)
				(sheetname "")
			)
			(fill
				(thermal_gap 0.5)
				(thermal_bridge_width 0.5)
				(island_removal_mode 0)
			)
			(polygon
				(pts
					(xy 179.667916 -110.784894) (xy 179.60975 -110.876334) (xy 179.60975 -111.075724) (xy 179.667916 -111.165894)
					(xy 179.843176 -111.165894) (xy 179.901596 -111.075724) (xy 179.901596 -110.876334) (xy 179.84343 -110.784894)
				)
			)
		)
	)
	(footprint ""
		(layer "B.Cu")
		(at 157.02788 -9.830308)
		(property "Reference" "R588"
			(at 0 0 0)
			(layer "B.SilkS")
			(hide yes)
			(effects
				(font
					(size 1.27 1.27)
				)
				(justify mirror)
			)
		)
		(property "Value" ""
			(at 0 0 0)
			(layer "B.Fab")
			(effects
				(font
					(size 1.27 1.27)
				)
				(justify mirror)
			)
		)
		(duplicate_pad_numbers_are_jumpers no)
		(fp_line
			(start -0.7874 -0.4064)
			(end -0.7874 0.4064)
			(stroke
				(width 0.1524)
				(type default)
			)
			(layer "B.SilkS")
		)
		(fp_line
			(start -0.7874 0.4064)
			(end 0.7874 0.4064)
			(stroke
				(width 0.1524)
				(type default)
			)
			(layer "B.SilkS")
		)
		(fp_line
			(start 0.7874 -0.4064)
			(end -0.7874 -0.4064)
			(stroke
				(width 0.1524)
				(type default)
			)
			(layer "B.SilkS")
		)
		(fp_line
			(start 0.7874 0.4064)
			(end 0.7874 -0.4064)
			(stroke
				(width 0.1524)
				(type default)
			)
			(layer "B.SilkS")
		)
		(fp_line
			(start -0.67945 -0.3048)
			(end -0.67945 0.3048)
			(stroke
				(width 0.1)
				(type default)
			)
			(layer "B.Fab")
		)
		(fp_line
			(start -0.67945 0.3048)
			(end -0.120396 0.3048)
			(stroke
				(width 0.1)
				(type default)
			)
			(layer "B.Fab")
		)
		(fp_line
			(start -0.12065 -0.3048)
			(end -0.67945 -0.3048)
			(stroke
				(width 0.1)
				(type default)
			)
			(layer "B.Fab")
		)
		(fp_line
			(start -0.12065 -0.2794)
			(end -0.12065 -0.3048)
			(stroke
				(width 0.1)
				(type default)
			)
			(layer "B.Fab")
		)
		(fp_line
			(start -0.120396 0.2794)
			(end 0.12065 0.2794)
			(stroke
				(width 0.1)
				(type default)
			)
			(layer "B.Fab")
		)
		(fp_line
			(start -0.120396 0.3048)
			(end -0.120396 0.2794)
			(stroke
				(width 0.1)
				(type default)
			)
			(layer "B.Fab")
		)
		(fp_line
			(start 0.12065 -0.305054)
			(end 0.12065 -0.2794)
			(stroke
				(width 0.1)
				(type default)
			)
			(layer "B.Fab")
		)
		(fp_line
			(start 0.12065 -0.2794)
			(end -0.12065 -0.2794)
			(stroke
				(width 0.1)
				(type default)
			)
			(layer "B.Fab")
		)
		(fp_line
			(start 0.12065 0.2794)
			(end 0.12065 0.3048)
			(stroke
				(width 0.1)
				(type default)
			)
			(layer "B.Fab")
		)
		(fp_line
			(start 0.12065 0.3048)
			(end 0.67945 0.3048)
			(stroke
				(width 0.1)
				(type default)
			)
			(layer "B.Fab")
		)
		(fp_line
			(start 0.67945 -0.305054)
			(end 0.12065 -0.305054)
			(stroke
				(width 0.1)
				(type default)
			)
			(layer "B.Fab")
		)
		(fp_line
			(start 0.67945 0.3048)
			(end 0.67945 -0.305054)
			(stroke
				(width 0.1)
				(type default)
			)
			(layer "B.Fab")
		)
		(pad "1" smd circle
			(at 0.40005 0 180)
			(size 0 0)
			(layers "B.Cu" "B.Mask" "B.Paste")
			(net "SMB_PCIE0_3V3AUX_SCL")
		)
		(pad "2" smd circle
			(at -0.40005 0 180)
			(size 0 0)
			(layers "B.Cu" "B.Mask" "B.Paste")
			(net "SMB_PCIE0_3V3AUX_SCL_R")
		)
	)
	(footprint ""
		(layer "B.Cu")
		(at 312.13044 -193.74231 -90)
		(property "Reference" "R276"
			(at 0 0 90)
			(layer "B.SilkS")
			(hide yes)
			(effects
				(font
					(size 1.27 1.27)
				)
				(justify mirror)
			)
		)
		(property "Value" ""
			(at 0 0 90)
			(layer "B.Fab")
			(effects
				(font
					(size 1.27 1.27)
				)
				(justify mirror)
			)
		)
		(duplicate_pad_numbers_are_jumpers no)
		(fp_line
			(start -0.7874 0.4064)
			(end 0.7874 0.4064)
			(stroke
				(width 0.1524)
				(type default)
			)
			(layer "B.SilkS")
		)
		(fp_line
			(start 0.7874 0.4064)
			(end 0.7874 -0.4064)
			(stroke
				(width 0.1524)
				(type default)
			)
			(layer "B.SilkS")
		)
		(fp_line
			(start -0.7874 -0.4064)
			(end -0.7874 0.4064)
			(stroke
				(width 0.1524)
				(type default)
			)
			(layer "B.SilkS")
		)
		(fp_line
			(start 0.7874 -0.4064)
			(end -0.7874 -0.4064)
			(stroke
				(width 0.1524)
				(type default)
			)
			(layer "B.SilkS")
		)
		(fp_line
			(start -0.67945 0.3048)
			(end -0.120396 0.3048)
			(stroke
				(width 0.1)
				(type default)
			)
			(layer "B.Fab")
		)
		(fp_line
			(start -0.120396 0.3048)
			(end -0.120396 0.2794)
			(stroke
				(width 0.1)
				(type default)
			)
			(layer "B.Fab")
		)
		(fp_line
			(start 0.12065 0.3048)
			(end 0.67945 0.3048)
			(stroke
				(width 0.1)
				(type default)
			)
			(layer "B.Fab")
		)
		(fp_line
			(start 0.67945 0.3048)
			(end 0.67945 -0.305054)
			(stroke
				(width 0.1)
				(type default)
			)
			(layer "B.Fab")
		)
		(fp_line
			(start -0.120396 0.2794)
			(end 0.12065 0.2794)
			(stroke
				(width 0.1)
				(type default)
			)
			(layer "B.Fab")
		)
		(fp_line
			(start 0.12065 0.2794)
			(end 0.12065 0.3048)
			(stroke
				(width 0.1)
				(type default)
			)
			(layer "B.Fab")
		)
		(fp_line
			(start -0.12065 -0.2794)
			(end -0.12065 -0.3048)
			(stroke
				(width 0.1)
				(type default)
			)
			(layer "B.Fab")
		)
		(fp_line
			(start 0.12065 -0.2794)
			(end -0.12065 -0.2794)
			(stroke
				(width 0.1)
				(type default)
			)
			(layer "B.Fab")
		)
		(fp_line
			(start -0.67945 -0.3048)
			(end -0.67945 0.3048)
			(stroke
				(width 0.1)
				(type default)
			)
			(layer "B.Fab")
		)
		(fp_line
			(start -0.12065 -0.3048)
			(end -0.67945 -0.3048)
			(stroke
				(width 0.1)
				(type default)
			)
			(layer "B.Fab")
		)
		(fp_line
			(start 0.12065 -0.305054)
			(end 0.12065 -0.2794)
			(stroke
				(width 0.1)
				(type default)
			)
			(layer "B.Fab")
		)
		(fp_line
			(start 0.67945 -0.305054)
			(end 0.12065 -0.305054)
			(stroke
				(width 0.1)
				(type default)
			)
			(layer "B.Fab")
		)
		(pad "1" smd circle
			(at 0.40005 0 90)
			(size 0 0)
			(layers "B.Cu" "B.Mask" "B.Paste")
			(net "PVNN_TERM_CPU0")
		)
		(pad "2" smd circle
			(at -0.40005 0 90)
			(size 0 0)
			(layers "B.Cu" "B.Mask" "B.Paste")
			(net "PU_CPU0_SAFE_MODE_BOOT")
		)
	)
	(footprint ""
		(layer "B.Cu")
		(at 291.964618 -149.992588 -90)
		(property "Reference" "R87"
			(at 0 0 90)
			(layer "B.SilkS")
			(hide yes)
			(effects
				(font
					(size 1.27 1.27)
				)
				(justify mirror)
			)
		)
		(property "Value" ""
			(at 0 0 90)
			(layer "B.Fab")
			(effects
				(font
					(size 1.27 1.27)
				)
				(justify mirror)
			)
		)
		(duplicate_pad_numbers_are_jumpers no)
		(fp_line
			(start -0.7874 0.4064)
			(end 0.7874 0.4064)
			(stroke
				(width 0.1524)
				(type default)
			)
			(layer "B.SilkS")
		)
		(fp_line
			(start 0.7874 0.4064)
			(end 0.7874 -0.4064)
			(stroke
				(width 0.1524)
				(type default)
			)
			(layer "B.SilkS")
		)
		(fp_line
			(start -0.7874 -0.4064)
			(end -0.7874 0.4064)
			(stroke
				(width 0.1524)
				(type default)
			)
			(layer "B.SilkS")
		)
		(fp_line
			(start 0.7874 -0.4064)
			(end -0.7874 -0.4064)
			(stroke
				(width 0.1524)
				(type default)
			)
			(layer "B.SilkS")
		)
		(fp_line
			(start -0.67945 0.3048)
			(end -0.120396 0.3048)
			(stroke
				(width 0.1)
				(type default)
			)
			(layer "B.Fab")
		)
		(fp_line
			(start -0.120396 0.3048)
			(end -0.120396 0.2794)
			(stroke
				(width 0.1)
				(type default)
			)
			(layer "B.Fab")
		)
		(fp_line
			(start 0.12065 0.3048)
			(end 0.67945 0.3048)
			(stroke
				(width 0.1)
				(type default)
			)
			(layer "B.Fab")
		)
		(fp_line
			(start 0.67945 0.3048)
			(end 0.67945 -0.305054)
			(stroke
				(width 0.1)
				(type default)
			)
			(layer "B.Fab")
		)
		(fp_line
			(start -0.120396 0.2794)
			(end 0.12065 0.2794)
			(stroke
				(width 0.1)
				(type default)
			)
			(layer "B.Fab")
		)
		(fp_line
			(start 0.12065 0.2794)
			(end 0.12065 0.3048)
			(stroke
				(width 0.1)
				(type default)
			)
			(layer "B.Fab")
		)
		(fp_line
			(start -0.12065 -0.2794)
			(end -0.12065 -0.3048)
			(stroke
				(width 0.1)
				(type default)
			)
			(layer "B.Fab")
		)
		(fp_line
			(start 0.12065 -0.2794)
			(end -0.12065 -0.2794)
			(stroke
				(width 0.1)
				(type default)
			)
			(layer "B.Fab")
		)
		(fp_line
			(start -0.67945 -0.3048)
			(end -0.67945 0.3048)
			(stroke
				(width 0.1)
				(type default)
			)
			(layer "B.Fab")
		)
		(fp_line
			(start -0.12065 -0.3048)
			(end -0.67945 -0.3048)
			(stroke
				(width 0.1)
				(type default)
			)
			(layer "B.Fab")
		)
		(fp_line
			(start 0.12065 -0.305054)
			(end 0.12065 -0.2794)
			(stroke
				(width 0.1)
				(type default)
			)
			(layer "B.Fab")
		)
		(fp_line
			(start 0.67945 -0.305054)
			(end 0.12065 -0.305054)
			(stroke
				(width 0.1)
				(type default)
			)
			(layer "B.Fab")
		)
		(pad "1" smd circle
			(at 0.40005 0 90)
			(size 0 0)
			(layers "B.Cu" "B.Mask" "B.Paste")
			(net "P3V3_AUX")
		)
		(pad "2" smd circle
			(at -0.40005 0 90)
			(size 0 0)
			(layers "B.Cu" "B.Mask" "B.Paste")
			(net "FM_SPD_REMOTE_EN")
		)
	)
	(footprint ""
		(layer "B.Cu")
		(at 93.193108 -190.705232 90)
		(property "Reference" "R670"
			(at 0 0 90)
			(layer "B.SilkS")
			(hide yes)
			(effects
				(font
					(size 1.27 1.27)
				)
				(justify mirror)
			)
		)
		(property "Value" ""
			(at 0 0 90)
			(layer "B.Fab")
			(effects
				(font
					(size 1.27 1.27)
				)
				(justify mirror)
			)
		)
		(duplicate_pad_numbers_are_jumpers no)
		(fp_line
			(start 0.7874 -0.4064)
			(end -0.7874 -0.4064)
			(stroke
				(width 0.1524)
				(type default)
			)
			(layer "B.SilkS")
		)
		(fp_line
			(start -0.7874 -0.4064)
			(end -0.7874 0.4064)
			(stroke
				(width 0.1524)
				(type default)
			)
			(layer "B.SilkS")
		)
		(fp_line
			(start 0.7874 0.4064)
			(end 0.7874 -0.4064)
			(stroke
				(width 0.1524)
				(type default)
			)
			(layer "B.SilkS")
		)
		(fp_line
			(start -0.7874 0.4064)
			(end 0.7874 0.4064)
			(stroke
				(width 0.1524)
				(type default)
			)
			(layer "B.SilkS")
		)
		(fp_line
			(start 0.67945 -0.305054)
			(end 0.12065 -0.305054)
			(stroke
				(width 0.1)
				(type default)
			)
			(layer "B.Fab")
		)
		(fp_line
			(start 0.12065 -0.305054)
			(end 0.12065 -0.2794)
			(stroke
				(width 0.1)
				(type default)
			)
			(layer "B.Fab")
		)
		(fp_line
			(start -0.12065 -0.3048)
			(end -0.67945 -0.3048)
			(stroke
				(width 0.1)
				(type default)
			)
			(layer "B.Fab")
		)
		(fp_line
			(start -0.67945 -0.3048)
			(end -0.67945 0.3048)
			(stroke
				(width 0.1)
				(type default)
			)
			(layer "B.Fab")
		)
		(fp_line
			(start 0.12065 -0.2794)
			(end -0.12065 -0.2794)
			(stroke
				(width 0.1)
				(type default)
			)
			(layer "B.Fab")
		)
		(fp_line
			(start -0.12065 -0.2794)
			(end -0.12065 -0.3048)
			(stroke
				(width 0.1)
				(type default)
			)
			(layer "B.Fab")
		)
		(fp_line
			(start 0.12065 0.2794)
			(end 0.12065 0.3048)
			(stroke
				(width 0.1)
				(type default)
			)
			(layer "B.Fab")
		)
		(fp_line
			(start -0.120396 0.2794)
			(end 0.12065 0.2794)
			(stroke
				(width 0.1)
				(type default)
			)
			(layer "B.Fab")
		)
		(fp_line
			(start 0.67945 0.3048)
			(end 0.67945 -0.305054)
			(stroke
				(width 0.1)
				(type default)
			)
			(layer "B.Fab")
		)
		(fp_line
			(start 0.12065 0.3048)
			(end 0.67945 0.3048)
			(stroke
				(width 0.1)
				(type default)
			)
			(layer "B.Fab")
		)
		(fp_line
			(start -0.120396 0.3048)
			(end -0.120396 0.2794)
			(stroke
				(width 0.1)
				(type default)
			)
			(layer "B.Fab")
		)
		(fp_line
			(start -0.67945 0.3048)
			(end -0.120396 0.3048)
			(stroke
				(width 0.1)
				(type default)
			)
			(layer "B.Fab")
		)
		(pad "1" smd circle
			(at 0.40005 0 270)
			(size 0 0)
			(layers "B.Cu" "B.Mask" "B.Paste")
			(net "I3C_SPD_DDRABCD_CPU1_SCL")
		)
		(pad "2" smd circle
			(at -0.40005 0 270)
			(size 0 0)
			(layers "B.Cu" "B.Mask" "B.Paste")
			(net "I3C_SPD_DDRABCD_CPU1_R_SCL")
		)
	)
	(footprint ""
		(layer "B.Cu")
		(at 17.725136 -192.848484)
		(property "Reference" "R963"
			(at 0 0 0)
			(layer "B.SilkS")
			(hide yes)
			(effects
				(font
					(size 1.27 1.27)
				)
				(justify mirror)
			)
		)
		(property "Value" ""
			(at 0 0 0)
			(layer "B.Fab")
			(effects
				(font
					(size 1.27 1.27)
				)
				(justify mirror)
			)
		)
		(duplicate_pad_numbers_are_jumpers no)
		(fp_line
			(start -0.7874 -0.4064)
			(end -0.7874 0.4064)
			(stroke
				(width 0.1524)
				(type default)
			)
			(layer "B.SilkS")
		)
		(fp_line
			(start -0.7874 0.4064)
			(end 0.7874 0.4064)
			(stroke
				(width 0.1524)
				(type default)
			)
			(layer "B.SilkS")
		)
		(fp_line
			(start 0.7874 -0.4064)
			(end -0.7874 -0.4064)
			(stroke
				(width 0.1524)
				(type default)
			)
			(layer "B.SilkS")
		)
		(fp_line
			(start 0.7874 0.4064)
			(end 0.7874 -0.4064)
			(stroke
				(width 0.1524)
				(type default)
			)
			(layer "B.SilkS")
		)
		(fp_line
			(start -0.67945 -0.3048)
			(end -0.67945 0.3048)
			(stroke
				(width 0.1)
				(type default)
			)
			(layer "B.Fab")
		)
		(fp_line
			(start -0.67945 0.3048)
			(end -0.120396 0.3048)
			(stroke
				(width 0.1)
				(type default)
			)
			(layer "B.Fab")
		)
		(fp_line
			(start -0.12065 -0.3048)
			(end -0.67945 -0.3048)
			(stroke
				(width 0.1)
				(type default)
			)
			(layer "B.Fab")
		)
		(fp_line
			(start -0.12065 -0.2794)
			(end -0.12065 -0.3048)
			(stroke
				(width 0.1)
				(type default)
			)
			(layer "B.Fab")
		)
		(fp_line
			(start -0.120396 0.2794)
			(end 0.12065 0.2794)
			(stroke
				(width 0.1)
				(type default)
			)
			(layer "B.Fab")
		)
		(fp_line
			(start -0.120396 0.3048)
			(end -0.120396 0.2794)
			(stroke
				(width 0.1)
				(type default)
			)
			(layer "B.Fab")
		)
		(fp_line
			(start 0.12065 -0.305054)
			(end 0.12065 -0.2794)
			(stroke
				(width 0.1)
				(type default)
			)
			(layer "B.Fab")
		)
		(fp_line
			(start 0.12065 -0.2794)
			(end -0.12065 -0.2794)
			(stroke
				(width 0.1)
				(type default)
			)
			(layer "B.Fab")
		)
		(fp_line
			(start 0.12065 0.2794)
			(end 0.12065 0.3048)
			(stroke
				(width 0.1)
				(type default)
			)
			(layer "B.Fab")
		)
		(fp_line
			(start 0.12065 0.3048)
			(end 0.67945 0.3048)
			(stroke
				(width 0.1)
				(type default)
			)
			(layer "B.Fab")
		)
		(fp_line
			(start 0.67945 -0.305054)
			(end 0.12065 -0.305054)
			(stroke
				(width 0.1)
				(type default)
			)
			(layer "B.Fab")
		)
		(fp_line
			(start 0.67945 0.3048)
			(end 0.67945 -0.305054)
			(stroke
				(width 0.1)
				(type default)
			)
			(layer "B.Fab")
		)
		(pad "1" smd circle
			(at 0.40005 0 180)
			(size 0 0)
			(layers "B.Cu" "B.Mask" "B.Paste")
			(net "PVNN_TERM_CPU1")
		)
		(pad "2" smd circle
			(at -0.40005 0 180)
			(size 0 0)
			(layers "B.Cu" "B.Mask" "B.Paste")
			(net "SMB_PEHPCPU1_GTL_R_SCL")
		)
	)
	(footprint ""
		(layer "B.Cu")
		(at 421.138604 -353.117404 -90)
		(property "Reference" "PC612_P0_1"
			(at 0 0 90)
			(layer "B.SilkS")
			(hide yes)
			(effects
				(font
					(size 1.27 1.27)
				)
				(justify mirror)
			)
		)
		(property "Value" ""
			(at 0 0 90)
			(layer "B.Fab")
			(effects
				(font
					(size 1.27 1.27)
				)
				(justify mirror)
			)
		)
		(duplicate_pad_numbers_are_jumpers no)
		(fp_line
			(start -0.7874 0.4064)
			(end 0.7874 0.4064)
			(stroke
				(width 0.1524)
				(type default)
			)
			(layer "B.SilkS")
		)
		(fp_line
			(start 0.7874 0.4064)
			(end 0.7874 -0.4064)
			(stroke
				(width 0.1524)
				(type default)
			)
			(layer "B.SilkS")
		)
		(fp_line
			(start -0.7874 -0.4064)
			(end -0.7874 0.4064)
			(stroke
				(width 0.1524)
				(type default)
			)
			(layer "B.SilkS")
		)
		(fp_line
			(start 0.7874 -0.4064)
			(end -0.7874 -0.4064)
			(stroke
				(width 0.1524)
				(type default)
			)
			(layer "B.SilkS")
		)
		(fp_line
			(start -0.67945 0.3048)
			(end -0.120396 0.3048)
			(stroke
				(width 0.1)
				(type default)
			)
			(layer "B.Fab")
		)
		(fp_line
			(start -0.120396 0.3048)
			(end -0.120396 0.2794)
			(stroke
				(width 0.1)
				(type default)
			)
			(layer "B.Fab")
		)
		(fp_line
			(start 0.12065 0.3048)
			(end 0.67945 0.3048)
			(stroke
				(width 0.1)
				(type default)
			)
			(layer "B.Fab")
		)
		(fp_line
			(start 0.67945 0.3048)
			(end 0.67945 -0.305054)
			(stroke
				(width 0.1)
				(type default)
			)
			(layer "B.Fab")
		)
		(fp_line
			(start -0.120396 0.2794)
			(end 0.12065 0.2794)
			(stroke
				(width 0.1)
				(type default)
			)
			(layer "B.Fab")
		)
		(fp_line
			(start 0.12065 0.2794)
			(end 0.12065 0.3048)
			(stroke
				(width 0.1)
				(type default)
			)
			(layer "B.Fab")
		)
		(fp_line
			(start -0.12065 -0.2794)
			(end -0.12065 -0.3048)
			(stroke
				(width 0.1)
				(type default)
			)
			(layer "B.Fab")
		)
		(fp_line
			(start 0.12065 -0.2794)
			(end -0.12065 -0.2794)
			(stroke
				(width 0.1)
				(type default)
			)
			(layer "B.Fab")
		)
		(fp_line
			(start -0.67945 -0.3048)
			(end -0.67945 0.3048)
			(stroke
				(width 0.1)
				(type default)
			)
			(layer "B.Fab")
		)
		(fp_line
			(start -0.12065 -0.3048)
			(end -0.67945 -0.3048)
			(stroke
				(width 0.1)
				(type default)
			)
			(layer "B.Fab")
		)
		(fp_line
			(start 0.12065 -0.305054)
			(end 0.12065 -0.2794)
			(stroke
				(width 0.1)
				(type default)
			)
			(layer "B.Fab")
		)
		(fp_line
			(start 0.67945 -0.305054)
			(end 0.12065 -0.305054)
			(stroke
				(width 0.1)
				(type default)
			)
			(layer "B.Fab")
		)
		(pad "1" smd circle
			(at 0.40005 0 90)
			(size 0 0)
			(layers "B.Cu" "B.Mask" "B.Paste")
			(net "PVCCFA_EHV_FIVRA_CPU0")
		)
		(pad "2" smd circle
			(at -0.40005 0 90)
			(size 0 0)
			(layers "B.Cu" "B.Mask" "B.Paste")
			(net "GND")
		)
	)
	(footprint ""
		(layer "B.Cu")
		(at 86.473284 -190.705232 -90)
		(property "Reference" "R66"
			(at 0 0 90)
			(layer "B.SilkS")
			(hide yes)
			(effects
				(font
					(size 1.27 1.27)
				)
				(justify mirror)
			)
		)
		(property "Value" ""
			(at 0 0 90)
			(layer "B.Fab")
			(effects
				(font
					(size 1.27 1.27)
				)
				(justify mirror)
			)
		)
		(duplicate_pad_numbers_are_jumpers no)
		(fp_line
			(start -0.7874 0.4064)
			(end 0.7874 0.4064)
			(stroke
				(width 0.1524)
				(type default)
			)
			(layer "B.SilkS")
		)
		(fp_line
			(start 0.7874 0.4064)
			(end 0.7874 -0.4064)
			(stroke
				(width 0.1524)
				(type default)
			)
			(layer "B.SilkS")
		)
		(fp_line
			(start -0.7874 -0.4064)
			(end -0.7874 0.4064)
			(stroke
				(width 0.1524)
				(type default)
			)
			(layer "B.SilkS")
		)
		(fp_line
			(start 0.7874 -0.4064)
			(end -0.7874 -0.4064)
			(stroke
				(width 0.1524)
				(type default)
			)
			(layer "B.SilkS")
		)
		(fp_line
			(start -0.67945 0.3048)
			(end -0.120396 0.3048)
			(stroke
				(width 0.1)
				(type default)
			)
			(layer "B.Fab")
		)
		(fp_line
			(start -0.120396 0.3048)
			(end -0.120396 0.2794)
			(stroke
				(width 0.1)
				(type default)
			)
			(layer "B.Fab")
		)
		(fp_line
			(start 0.12065 0.3048)
			(end 0.67945 0.3048)
			(stroke
				(width 0.1)
				(type default)
			)
			(layer "B.Fab")
		)
		(fp_line
			(start 0.67945 0.3048)
			(end 0.67945 -0.305054)
			(stroke
				(width 0.1)
				(type default)
			)
			(layer "B.Fab")
		)
		(fp_line
			(start -0.120396 0.2794)
			(end 0.12065 0.2794)
			(stroke
				(width 0.1)
				(type default)
			)
			(layer "B.Fab")
		)
		(fp_line
			(start 0.12065 0.2794)
			(end 0.12065 0.3048)
			(stroke
				(width 0.1)
				(type default)
			)
			(layer "B.Fab")
		)
		(fp_line
			(start -0.12065 -0.2794)
			(end -0.12065 -0.3048)
			(stroke
				(width 0.1)
				(type default)
			)
			(layer "B.Fab")
		)
		(fp_line
			(start 0.12065 -0.2794)
			(end -0.12065 -0.2794)
			(stroke
				(width 0.1)
				(type default)
			)
			(layer "B.Fab")
		)
		(fp_line
			(start -0.67945 -0.3048)
			(end -0.67945 0.3048)
			(stroke
				(width 0.1)
				(type default)
			)
			(layer "B.Fab")
		)
		(fp_line
			(start -0.12065 -0.3048)
			(end -0.67945 -0.3048)
			(stroke
				(width 0.1)
				(type default)
			)
			(layer "B.Fab")
		)
		(fp_line
			(start 0.12065 -0.305054)
			(end 0.12065 -0.2794)
			(stroke
				(width 0.1)
				(type default)
			)
			(layer "B.Fab")
		)
		(fp_line
			(start 0.67945 -0.305054)
			(end 0.12065 -0.305054)
			(stroke
				(width 0.1)
				(type default)
			)
			(layer "B.Fab")
		)
		(pad "1" smd circle
			(at 0.40005 0 90)
			(size 0 0)
			(layers "B.Cu" "B.Mask" "B.Paste")
			(net "JTAG_DBP_CPU_QS_GTL_TMS")
		)
		(pad "2" smd circle
			(at -0.40005 0 90)
			(size 0 0)
			(layers "B.Cu" "B.Mask" "B.Paste")
			(net "JTAG_DBP_CPU1_QS_GTL_R_TMS")
		)
	)
	(footprint ""
		(layer "B.Cu")
		(at 308.899814 -321.549776 -90)
		(property "Reference" "C7"
			(at 0 0 90)
			(layer "B.SilkS")
			(hide yes)
			(effects
				(font
					(size 1.27 1.27)
				)
				(justify mirror)
			)
		)
		(property "Value" ""
			(at 0 0 90)
			(layer "B.Fab")
			(effects
				(font
					(size 1.27 1.27)
				)
				(justify mirror)
			)
		)
		(duplicate_pad_numbers_are_jumpers no)
		(fp_line
			(start -1.524 0.762)
			(end 1.524 0.762)
			(stroke
				(width 0.1524)
				(type default)
			)
			(layer "B.SilkS")
		)
		(fp_line
			(start 1.524 0.762)
			(end 1.524 -0.762)
			(stroke
				(width 0.1524)
				(type default)
			)
			(layer "B.SilkS")
		)
		(fp_line
			(start -1.524 -0.762)
			(end -1.524 0.762)
			(stroke
				(width 0.1524)
				(type default)
			)
			(layer "B.SilkS")
		)
		(fp_line
			(start 1.524 -0.762)
			(end -1.524 -0.762)
			(stroke
				(width 0.1524)
				(type default)
			)
			(layer "B.SilkS")
		)
		(fp_line
			(start -1.1049 0.724916)
			(end -1.1049 -0.724916)
			(stroke
				(width 0.1)
				(type default)
			)
			(layer "B.Fab")
		)
		(fp_line
			(start 1.1049 0.724916)
			(end -1.1049 0.724916)
			(stroke
				(width 0.1)
				(type default)
			)
			(layer "B.Fab")
		)
		(fp_line
			(start -1.1049 -0.724916)
			(end 1.1049 -0.724916)
			(stroke
				(width 0.1)
				(type default)
			)
			(layer "B.Fab")
		)
		(fp_line
			(start 1.1049 -0.724916)
			(end 1.1049 0.724916)
			(stroke
				(width 0.1)
				(type default)
			)
			(layer "B.Fab")
		)
		(pad "1" smd rect
			(at 0.889 0 270)
			(size 1.016 1.27)
			(layers "B.Cu" "B.Mask" "B.Paste")
			(net "P12V_S3_AUX_CPU0_NVDIMM")
		)
		(pad "2" smd rect
			(at -0.889 0 270)
			(size 1.016 1.27)
			(layers "B.Cu" "B.Mask" "B.Paste")
			(net "GND")
		)
	)
	(footprint ""
		(layer "B.Cu")
		(at 284.075378 -318.376046 180)
		(property "Reference" "R2491"
			(at 0 0 0)
			(layer "B.SilkS")
			(hide yes)
			(effects
				(font
					(size 1.27 1.27)
				)
				(justify mirror)
			)
		)
		(property "Value" ""
			(at 0 0 0)
			(layer "B.Fab")
			(effects
				(font
					(size 1.27 1.27)
				)
				(justify mirror)
			)
		)
		(duplicate_pad_numbers_are_jumpers no)
		(fp_line
			(start 0.7874 0.4064)
			(end 0.7874 -0.4064)
			(stroke
				(width 0.1524)
				(type default)
			)
			(layer "B.SilkS")
		)
		(fp_line
			(start 0.7874 -0.4064)
			(end -0.7874 -0.4064)
			(stroke
				(width 0.1524)
				(type default)
			)
			(layer "B.SilkS")
		)
		(fp_line
			(start -0.7874 0.4064)
			(end 0.7874 0.4064)
			(stroke
				(width 0.1524)
				(type default)
			)
			(layer "B.SilkS")
		)
		(fp_line
			(start -0.7874 -0.4064)
			(end -0.7874 0.4064)
			(stroke
				(width 0.1524)
				(type default)
			)
			(layer "B.SilkS")
		)
		(fp_line
			(start 0.67945 0.3048)
			(end 0.67945 -0.305054)
			(stroke
				(width 0.1)
				(type default)
			)
			(layer "B.Fab")
		)
		(fp_line
			(start 0.67945 -0.305054)
			(end 0.12065 -0.305054)
			(stroke
				(width 0.1)
				(type default)
			)
			(layer "B.Fab")
		)
		(fp_line
			(start 0.12065 0.3048)
			(end 0.67945 0.3048)
			(stroke
				(width 0.1)
				(type default)
			)
			(layer "B.Fab")
		)
		(fp_line
			(start 0.12065 0.2794)
			(end 0.12065 0.3048)
			(stroke
				(width 0.1)
				(type default)
			)
			(layer "B.Fab")
		)
		(fp_line
			(start 0.12065 -0.2794)
			(end -0.12065 -0.2794)
			(stroke
				(width 0.1)
				(type default)
			)
			(layer "B.Fab")
		)
		(fp_line
			(start 0.12065 -0.305054)
			(end 0.12065 -0.2794)
			(stroke
				(width 0.1)
				(type default)
			)
			(layer "B.Fab")
		)
		(fp_line
			(start -0.120396 0.3048)
			(end -0.120396 0.2794)
			(stroke
				(width 0.1)
				(type default)
			)
			(layer "B.Fab")
		)
		(fp_line
			(start -0.120396 0.2794)
			(end 0.12065 0.2794)
			(stroke
				(width 0.1)
				(type default)
			)
			(layer "B.Fab")
		)
		(fp_line
			(start -0.12065 -0.2794)
			(end -0.12065 -0.3048)
			(stroke
				(width 0.1)
				(type default)
			)
			(layer "B.Fab")
		)
		(fp_line
			(start -0.12065 -0.3048)
			(end -0.67945 -0.3048)
			(stroke
				(width 0.1)
				(type default)
			)
			(layer "B.Fab")
		)
		(fp_line
			(start -0.67945 0.3048)
			(end -0.120396 0.3048)
			(stroke
				(width 0.1)
				(type default)
			)
			(layer "B.Fab")
		)
		(fp_line
			(start -0.67945 -0.3048)
			(end -0.67945 0.3048)
			(stroke
				(width 0.1)
				(type default)
			)
			(layer "B.Fab")
		)
		(pad "1" smd circle
			(at 0.40005 0)
			(size 0 0)
			(layers "B.Cu" "B.Mask" "B.Paste")
			(net "PWRGD_FAIL_CPU0_CD")
		)
		(pad "2" smd circle
			(at -0.40005 0)
			(size 0 0)
			(layers "B.Cu" "B.Mask" "B.Paste")
			(net "PWRGD_FAIL_CPU0_CD_R1")
		)
	)
	(footprint ""
		(layer "B.Cu")
		(at 54.880002 -157.599634 180)
		(property "Reference" "PC450_P1_1"
			(at 0 0 0)
			(layer "B.SilkS")
			(hide yes)
			(effects
				(font
					(size 1.27 1.27)
				)
				(justify mirror)
			)
		)
		(property "Value" ""
			(at 0 0 0)
			(layer "B.Fab")
			(effects
				(font
					(size 1.27 1.27)
				)
				(justify mirror)
			)
		)
		(duplicate_pad_numbers_are_jumpers no)
		(fp_line
			(start 1.524 0.762)
			(end 1.524 -0.762)
			(stroke
				(width 0.1524)
				(type default)
			)
			(layer "B.SilkS")
		)
		(fp_line
			(start 1.524 -0.762)
			(end -1.524 -0.762)
			(stroke
				(width 0.1524)
				(type default)
			)
			(layer "B.SilkS")
		)
		(fp_line
			(start -1.524 0.762)
			(end 1.524 0.762)
			(stroke
				(width 0.1524)
				(type default)
			)
			(layer "B.SilkS")
		)
		(fp_line
			(start -1.524 -0.762)
			(end -1.524 0.762)
			(stroke
				(width 0.1524)
				(type default)
			)
			(layer "B.SilkS")
		)
		(fp_line
			(start 1.1049 0.724916)
			(end -1.1049 0.724916)
			(stroke
				(width 0.1)
				(type default)
			)
			(layer "B.Fab")
		)
		(fp_line
			(start 1.1049 -0.724916)
			(end 1.1049 0.724916)
			(stroke
				(width 0.1)
				(type default)
			)
			(layer "B.Fab")
		)
		(fp_line
			(start -1.1049 0.724916)
			(end -1.1049 -0.724916)
			(stroke
				(width 0.1)
				(type default)
			)
			(layer "B.Fab")
		)
		(fp_line
			(start -1.1049 -0.724916)
			(end 1.1049 -0.724916)
			(stroke
				(width 0.1)
				(type default)
			)
			(layer "B.Fab")
		)
		(pad "1" smd rect
			(at 0.889 0 180)
			(size 1.016 1.27)
			(layers "B.Cu" "B.Mask" "B.Paste")
			(net "SW_P12V_PVCCINFAON_CPU1_FLT")
		)
		(pad "2" smd rect
			(at -0.889 0 180)
			(size 1.016 1.27)
			(layers "B.Cu" "B.Mask" "B.Paste")
			(net "GND")
		)
	)
	(footprint ""
		(layer "B.Cu")
		(at 54.880002 -166.235634 180)
		(property "Reference" "PC377"
			(at 0 0 0)
			(layer "B.SilkS")
			(hide yes)
			(effects
				(font
					(size 1.27 1.27)
				)
				(justify mirror)
			)
		)
		(property "Value" ""
			(at 0 0 0)
			(layer "B.Fab")
			(effects
				(font
					(size 1.27 1.27)
				)
				(justify mirror)
			)
		)
		(duplicate_pad_numbers_are_jumpers no)
		(fp_line
			(start 1.524 0.762)
			(end 1.524 -0.762)
			(stroke
				(width 0.1524)
				(type default)
			)
			(layer "B.SilkS")
		)
		(fp_line
			(start 1.524 -0.762)
			(end -1.524 -0.762)
			(stroke
				(width 0.1524)
				(type default)
			)
			(layer "B.SilkS")
		)
		(fp_line
			(start -1.524 0.762)
			(end 1.524 0.762)
			(stroke
				(width 0.1524)
				(type default)
			)
			(layer "B.SilkS")
		)
		(fp_line
			(start -1.524 -0.762)
			(end -1.524 0.762)
			(stroke
				(width 0.1524)
				(type default)
			)
			(layer "B.SilkS")
		)
		(fp_line
			(start 1.1049 0.724916)
			(end -1.1049 0.724916)
			(stroke
				(width 0.1)
				(type default)
			)
			(layer "B.Fab")
		)
		(fp_line
			(start 1.1049 -0.724916)
			(end 1.1049 0.724916)
			(stroke
				(width 0.1)
				(type default)
			)
			(layer "B.Fab")
		)
		(fp_line
			(start -1.1049 0.724916)
			(end -1.1049 -0.724916)
			(stroke
				(width 0.1)
				(type default)
			)
			(layer "B.Fab")
		)
		(fp_line
			(start -1.1049 -0.724916)
			(end 1.1049 -0.724916)
			(stroke
				(width 0.1)
				(type default)
			)
			(layer "B.Fab")
		)
		(pad "1" smd rect
			(at 0.889 0 180)
			(size 1.016 1.27)
			(layers "B.Cu" "B.Mask" "B.Paste")
			(net "SW_P12V_PVCCINFAON_CPU1_FLT")
		)
		(pad "2" smd rect
			(at -0.889 0 180)
			(size 1.016 1.27)
			(layers "B.Cu" "B.Mask" "B.Paste")
			(net "GND")
		)
	)
	(footprint ""
		(layer "B.Cu")
		(at 25.343866 -193.152776 -90)
		(property "Reference" "C615"
			(at 0 0 90)
			(layer "B.SilkS")
			(hide yes)
			(effects
				(font
					(size 1.27 1.27)
				)
				(justify mirror)
			)
		)
		(property "Value" ""
			(at 0 0 90)
			(layer "B.Fab")
			(effects
				(font
					(size 1.27 1.27)
				)
				(justify mirror)
			)
		)
		(duplicate_pad_numbers_are_jumpers no)
		(fp_line
			(start -0.7874 0.4064)
			(end 0.7874 0.4064)
			(stroke
				(width 0.1524)
				(type default)
			)
			(layer "B.SilkS")
		)
		(fp_line
			(start 0.7874 0.4064)
			(end 0.7874 -0.4064)
			(stroke
				(width 0.1524)
				(type default)
			)
			(layer "B.SilkS")
		)
		(fp_line
			(start -0.7874 -0.4064)
			(end -0.7874 0.4064)
			(stroke
				(width 0.1524)
				(type default)
			)
			(layer "B.SilkS")
		)
		(fp_line
			(start 0.7874 -0.4064)
			(end -0.7874 -0.4064)
			(stroke
				(width 0.1524)
				(type default)
			)
			(layer "B.SilkS")
		)
		(fp_line
			(start -0.67945 0.3048)
			(end -0.120396 0.3048)
			(stroke
				(width 0.1)
				(type default)
			)
			(layer "B.Fab")
		)
		(fp_line
			(start -0.120396 0.3048)
			(end -0.120396 0.2794)
			(stroke
				(width 0.1)
				(type default)
			)
			(layer "B.Fab")
		)
		(fp_line
			(start 0.12065 0.3048)
			(end 0.67945 0.3048)
			(stroke
				(width 0.1)
				(type default)
			)
			(layer "B.Fab")
		)
		(fp_line
			(start 0.67945 0.3048)
			(end 0.67945 -0.305054)
			(stroke
				(width 0.1)
				(type default)
			)
			(layer "B.Fab")
		)
		(fp_line
			(start -0.120396 0.2794)
			(end 0.12065 0.2794)
			(stroke
				(width 0.1)
				(type default)
			)
			(layer "B.Fab")
		)
		(fp_line
			(start 0.12065 0.2794)
			(end 0.12065 0.3048)
			(stroke
				(width 0.1)
				(type default)
			)
			(layer "B.Fab")
		)
		(fp_line
			(start -0.12065 -0.2794)
			(end -0.12065 -0.3048)
			(stroke
				(width 0.1)
				(type default)
			)
			(layer "B.Fab")
		)
		(fp_line
			(start 0.12065 -0.2794)
			(end -0.12065 -0.2794)
			(stroke
				(width 0.1)
				(type default)
			)
			(layer "B.Fab")
		)
		(fp_line
			(start -0.67945 -0.3048)
			(end -0.67945 0.3048)
			(stroke
				(width 0.1)
				(type default)
			)
			(layer "B.Fab")
		)
		(fp_line
			(start -0.12065 -0.3048)
			(end -0.67945 -0.3048)
			(stroke
				(width 0.1)
				(type default)
			)
			(layer "B.Fab")
		)
		(fp_line
			(start 0.12065 -0.305054)
			(end 0.12065 -0.2794)
			(stroke
				(width 0.1)
				(type default)
			)
			(layer "B.Fab")
		)
		(fp_line
			(start 0.67945 -0.305054)
			(end 0.12065 -0.305054)
			(stroke
				(width 0.1)
				(type default)
			)
			(layer "B.Fab")
		)
		(pad "1" smd circle
			(at 0.40005 0 90)
			(size 0 0)
			(layers "B.Cu" "B.Mask" "B.Paste")
			(net "RST_PLD_CPU1_DRAM_CD_N")
		)
		(pad "2" smd circle
			(at -0.40005 0 90)
			(size 0 0)
			(layers "B.Cu" "B.Mask" "B.Paste")
			(net "GND")
		)
	)
	(footprint ""
		(layer "B.Cu")
		(at 366.086898 -241.16665 -90)
		(property "Reference" "C381"
			(at 0 0 90)
			(layer "B.SilkS")
			(hide yes)
			(effects
				(font
					(size 1.27 1.27)
				)
				(justify mirror)
			)
		)
		(property "Value" ""
			(at 0 0 90)
			(layer "B.Fab")
			(effects
				(font
					(size 1.27 1.27)
				)
				(justify mirror)
			)
		)
		(duplicate_pad_numbers_are_jumpers no)
		(fp_line
			(start -1.524 0.762)
			(end 1.524 0.762)
			(stroke
				(width 0.1524)
				(type default)
			)
			(layer "B.SilkS")
		)
		(fp_line
			(start 1.524 0.762)
			(end 1.524 -0.762)
			(stroke
				(width 0.1524)
				(type default)
			)
			(layer "B.SilkS")
		)
		(fp_line
			(start -1.524 -0.762)
			(end -1.524 0.762)
			(stroke
				(width 0.1524)
				(type default)
			)
			(layer "B.SilkS")
		)
		(fp_line
			(start 1.524 -0.762)
			(end -1.524 -0.762)
			(stroke
				(width 0.1524)
				(type default)
			)
			(layer "B.SilkS")
		)
		(fp_line
			(start -1.1049 0.724916)
			(end -1.1049 -0.724916)
			(stroke
				(width 0.1)
				(type default)
			)
			(layer "B.Fab")
		)
		(fp_line
			(start 1.1049 0.724916)
			(end -1.1049 0.724916)
			(stroke
				(width 0.1)
				(type default)
			)
			(layer "B.Fab")
		)
		(fp_line
			(start -1.1049 -0.724916)
			(end 1.1049 -0.724916)
			(stroke
				(width 0.1)
				(type default)
			)
			(layer "B.Fab")
		)
		(fp_line
			(start 1.1049 -0.724916)
			(end 1.1049 0.724916)
			(stroke
				(width 0.1)
				(type default)
			)
			(layer "B.Fab")
		)
		(pad "1" smd rect
			(at 0.889 0 270)
			(size 1.016 1.27)
			(layers "B.Cu" "B.Mask" "B.Paste")
			(net "PVCCIN_CPU0")
		)
		(pad "2" smd rect
			(at -0.889 0 270)
			(size 1.016 1.27)
			(layers "B.Cu" "B.Mask" "B.Paste")
			(net "GND")
		)
	)
	(footprint ""
		(layer "B.Cu")
		(at 74.04608 -4.251198 90)
		(property "Reference" "R3167"
			(at 0 0 90)
			(layer "B.SilkS")
			(hide yes)
			(effects
				(font
					(size 1.27 1.27)
				)
				(justify mirror)
			)
		)
		(property "Value" ""
			(at 0 0 90)
			(layer "B.Fab")
			(effects
				(font
					(size 1.27 1.27)
				)
				(justify mirror)
			)
		)
		(duplicate_pad_numbers_are_jumpers no)
		(fp_line
			(start 0.7874 -0.4064)
			(end -0.7874 -0.4064)
			(stroke
				(width 0.1524)
				(type default)
			)
			(layer "B.SilkS")
		)
		(fp_line
			(start -0.7874 -0.4064)
			(end -0.7874 0.4064)
			(stroke
				(width 0.1524)
				(type default)
			)
			(layer "B.SilkS")
		)
		(fp_line
			(start 0.7874 0.4064)
			(end 0.7874 -0.4064)
			(stroke
				(width 0.1524)
				(type default)
			)
			(layer "B.SilkS")
		)
		(fp_line
			(start -0.7874 0.4064)
			(end 0.7874 0.4064)
			(stroke
				(width 0.1524)
				(type default)
			)
			(layer "B.SilkS")
		)
		(fp_line
			(start 0.67945 -0.305054)
			(end 0.12065 -0.305054)
			(stroke
				(width 0.1)
				(type default)
			)
			(layer "B.Fab")
		)
		(fp_line
			(start 0.12065 -0.305054)
			(end 0.12065 -0.2794)
			(stroke
				(width 0.1)
				(type default)
			)
			(layer "B.Fab")
		)
		(fp_line
			(start -0.12065 -0.3048)
			(end -0.67945 -0.3048)
			(stroke
				(width 0.1)
				(type default)
			)
			(layer "B.Fab")
		)
		(fp_line
			(start -0.67945 -0.3048)
			(end -0.67945 0.3048)
			(stroke
				(width 0.1)
				(type default)
			)
			(layer "B.Fab")
		)
		(fp_line
			(start 0.12065 -0.2794)
			(end -0.12065 -0.2794)
			(stroke
				(width 0.1)
				(type default)
			)
			(layer "B.Fab")
		)
		(fp_line
			(start -0.12065 -0.2794)
			(end -0.12065 -0.3048)
			(stroke
				(width 0.1)
				(type default)
			)
			(layer "B.Fab")
		)
		(fp_line
			(start 0.12065 0.2794)
			(end 0.12065 0.3048)
			(stroke
				(width 0.1)
				(type default)
			)
			(layer "B.Fab")
		)
		(fp_line
			(start -0.120396 0.2794)
			(end 0.12065 0.2794)
			(stroke
				(width 0.1)
				(type default)
			)
			(layer "B.Fab")
		)
		(fp_line
			(start 0.67945 0.3048)
			(end 0.67945 -0.305054)
			(stroke
				(width 0.1)
				(type default)
			)
			(layer "B.Fab")
		)
		(fp_line
			(start 0.12065 0.3048)
			(end 0.67945 0.3048)
			(stroke
				(width 0.1)
				(type default)
			)
			(layer "B.Fab")
		)
		(fp_line
			(start -0.120396 0.3048)
			(end -0.120396 0.2794)
			(stroke
				(width 0.1)
				(type default)
			)
			(layer "B.Fab")
		)
		(fp_line
			(start -0.67945 0.3048)
			(end -0.120396 0.3048)
			(stroke
				(width 0.1)
				(type default)
			)
			(layer "B.Fab")
		)
		(pad "1" smd circle
			(at 0.40005 0 270)
			(size 0 0)
			(layers "B.Cu" "B.Mask" "B.Paste")
			(net "OCP_V3_2_ID1")
		)
		(pad "2" smd circle
			(at -0.40005 0 270)
			(size 0 0)
			(layers "B.Cu" "B.Mask" "B.Paste")
			(net "GND")
		)
	)
	(footprint ""
		(layer "B.Cu")
		(at 369.49888 -42.128948 180)
		(property "Reference" "R4110"
			(at 0 0 0)
			(layer "B.SilkS")
			(hide yes)
			(effects
				(font
					(size 1.27 1.27)
				)
				(justify mirror)
			)
		)
		(property "Value" ""
			(at 0 0 0)
			(layer "B.Fab")
			(effects
				(font
					(size 1.27 1.27)
				)
				(justify mirror)
			)
		)
		(duplicate_pad_numbers_are_jumpers no)
		(fp_line
			(start 0.7874 0.4064)
			(end 0.7874 -0.4064)
			(stroke
				(width 0.1524)
				(type default)
			)
			(layer "B.SilkS")
		)
		(fp_line
			(start 0.7874 -0.4064)
			(end -0.7874 -0.4064)
			(stroke
				(width 0.1524)
				(type default)
			)
			(layer "B.SilkS")
		)
		(fp_line
			(start -0.7874 0.4064)
			(end 0.7874 0.4064)
			(stroke
				(width 0.1524)
				(type default)
			)
			(layer "B.SilkS")
		)
		(fp_line
			(start -0.7874 -0.4064)
			(end -0.7874 0.4064)
			(stroke
				(width 0.1524)
				(type default)
			)
			(layer "B.SilkS")
		)
		(fp_line
			(start 0.67945 0.3048)
			(end 0.67945 -0.305054)
			(stroke
				(width 0.1)
				(type default)
			)
			(layer "B.Fab")
		)
		(fp_line
			(start 0.67945 -0.305054)
			(end 0.12065 -0.305054)
			(stroke
				(width 0.1)
				(type default)
			)
			(layer "B.Fab")
		)
		(fp_line
			(start 0.12065 0.3048)
			(end 0.67945 0.3048)
			(stroke
				(width 0.1)
				(type default)
			)
			(layer "B.Fab")
		)
		(fp_line
			(start 0.12065 0.2794)
			(end 0.12065 0.3048)
			(stroke
				(width 0.1)
				(type default)
			)
			(layer "B.Fab")
		)
		(fp_line
			(start 0.12065 -0.2794)
			(end -0.12065 -0.2794)
			(stroke
				(width 0.1)
				(type default)
			)
			(layer "B.Fab")
		)
		(fp_line
			(start 0.12065 -0.305054)
			(end 0.12065 -0.2794)
			(stroke
				(width 0.1)
				(type default)
			)
			(layer "B.Fab")
		)
		(fp_line
			(start -0.120396 0.3048)
			(end -0.120396 0.2794)
			(stroke
				(width 0.1)
				(type default)
			)
			(layer "B.Fab")
		)
		(fp_line
			(start -0.120396 0.2794)
			(end 0.12065 0.2794)
			(stroke
				(width 0.1)
				(type default)
			)
			(layer "B.Fab")
		)
		(fp_line
			(start -0.12065 -0.2794)
			(end -0.12065 -0.3048)
			(stroke
				(width 0.1)
				(type default)
			)
			(layer "B.Fab")
		)
		(fp_line
			(start -0.12065 -0.3048)
			(end -0.67945 -0.3048)
			(stroke
				(width 0.1)
				(type default)
			)
			(layer "B.Fab")
		)
		(fp_line
			(start -0.67945 0.3048)
			(end -0.120396 0.3048)
			(stroke
				(width 0.1)
				(type default)
			)
			(layer "B.Fab")
		)
		(fp_line
			(start -0.67945 -0.3048)
			(end -0.67945 0.3048)
			(stroke
				(width 0.1)
				(type default)
			)
			(layer "B.Fab")
		)
		(pad "1" smd circle
			(at 0.40005 0)
			(size 0 0)
			(layers "B.Cu" "B.Mask" "B.Paste")
			(net "PD_PCH_GPP_E_14")
		)
		(pad "2" smd circle
			(at -0.40005 0)
			(size 0 0)
			(layers "B.Cu" "B.Mask" "B.Paste")
			(net "GND")
		)
	)
	(footprint ""
		(layer "B.Cu")
		(at 236.982254 -134.048754)
		(property "Reference" "R1017"
			(at 0 0 0)
			(layer "B.SilkS")
			(hide yes)
			(effects
				(font
					(size 1.27 1.27)
				)
				(justify mirror)
			)
		)
		(property "Value" ""
			(at 0 0 0)
			(layer "B.Fab")
			(effects
				(font
					(size 1.27 1.27)
				)
				(justify mirror)
			)
		)
		(duplicate_pad_numbers_are_jumpers no)
		(fp_line
			(start -0.7874 -0.4064)
			(end -0.7874 0.4064)
			(stroke
				(width 0.1524)
				(type default)
			)
			(layer "B.SilkS")
		)
		(fp_line
			(start -0.7874 0.4064)
			(end 0.7874 0.4064)
			(stroke
				(width 0.1524)
				(type default)
			)
			(layer "B.SilkS")
		)
		(fp_line
			(start -0.559054 -0.4064)
			(end -0.7874 -0.4064)
			(stroke
				(width 0.1524)
				(type default)
			)
			(layer "B.SilkS")
		)
		(fp_line
			(start 0.7874 -0.4064)
			(end -0.223774 -0.4064)
			(stroke
				(width 0.1524)
				(type default)
			)
			(layer "B.SilkS")
		)
		(fp_line
			(start 0.7874 -0.226314)
			(end 0.7874 -0.4064)
			(stroke
				(width 0.1524)
				(type default)
			)
			(layer "B.SilkS")
		)
		(fp_line
			(start 0.7874 0.4064)
			(end 0.7874 0.253746)
			(stroke
				(width 0.1524)
				(type default)
			)
			(layer "B.SilkS")
		)
		(fp_line
			(start -0.67945 -0.3048)
			(end -0.67945 0.3048)
			(stroke
				(width 0.1)
				(type default)
			)
			(layer "B.Fab")
		)
		(fp_line
			(start -0.67945 0.3048)
			(end -0.120396 0.3048)
			(stroke
				(width 0.1)
				(type default)
			)
			(layer "B.Fab")
		)
		(fp_line
			(start -0.12065 -0.3048)
			(end -0.67945 -0.3048)
			(stroke
				(width 0.1)
				(type default)
			)
			(layer "B.Fab")
		)
		(fp_line
			(start -0.12065 -0.2794)
			(end -0.12065 -0.3048)
			(stroke
				(width 0.1)
				(type default)
			)
			(layer "B.Fab")
		)
		(fp_line
			(start -0.120396 0.2794)
			(end 0.12065 0.2794)
			(stroke
				(width 0.1)
				(type default)
			)
			(layer "B.Fab")
		)
		(fp_line
			(start -0.120396 0.3048)
			(end -0.120396 0.2794)
			(stroke
				(width 0.1)
				(type default)
			)
			(layer "B.Fab")
		)
		(fp_line
			(start 0.12065 -0.305054)
			(end 0.12065 -0.2794)
			(stroke
				(width 0.1)
				(type default)
			)
			(layer "B.Fab")
		)
		(fp_line
			(start 0.12065 -0.2794)
			(end -0.12065 -0.2794)
			(stroke
				(width 0.1)
				(type default)
			)
			(layer "B.Fab")
		)
		(fp_line
			(start 0.12065 0.2794)
			(end 0.12065 0.3048)
			(stroke
				(width 0.1)
				(type default)
			)
			(layer "B.Fab")
		)
		(fp_line
			(start 0.12065 0.3048)
			(end 0.67945 0.3048)
			(stroke
				(width 0.1)
				(type default)
			)
			(layer "B.Fab")
		)
		(fp_line
			(start 0.67945 -0.305054)
			(end 0.12065 -0.305054)
			(stroke
				(width 0.1)
				(type default)
			)
			(layer "B.Fab")
		)
		(fp_line
			(start 0.67945 0.3048)
			(end 0.67945 -0.305054)
			(stroke
				(width 0.1)
				(type default)
			)
			(layer "B.Fab")
		)
		(pad "1" smd rect
			(at 0.40005 0)
			(size 0.4572 0.508)
			(layers "B.Cu" "B.Mask" "B.Paste")
			(net "CLK_25M_PCH_CPU1_DP")
		)
		(pad "2" smd rect
			(at -0.40005 0)
			(size 0.4572 0.508)
			(layers "B.Cu" "B.Mask" "B.Paste")
			(net "CLK_25M_NSSC_CPU1_DP")
		)
	)
	(footprint ""
		(layer "B.Cu")
		(at 422.314624 -193.353436 -90)
		(property "Reference" "R838"
			(at 0 0 90)
			(layer "B.SilkS")
			(hide yes)
			(effects
				(font
					(size 1.27 1.27)
				)
				(justify mirror)
			)
		)
		(property "Value" ""
			(at 0 0 90)
			(layer "B.Fab")
			(effects
				(font
					(size 1.27 1.27)
				)
				(justify mirror)
			)
		)
		(duplicate_pad_numbers_are_jumpers no)
		(fp_line
			(start -0.7874 0.4064)
			(end 0.7874 0.4064)
			(stroke
				(width 0.1524)
				(type default)
			)
			(layer "B.SilkS")
		)
		(fp_line
			(start 0.7874 0.4064)
			(end 0.7874 -0.4064)
			(stroke
				(width 0.1524)
				(type default)
			)
			(layer "B.SilkS")
		)
		(fp_line
			(start -0.7874 -0.4064)
			(end -0.7874 0.4064)
			(stroke
				(width 0.1524)
				(type default)
			)
			(layer "B.SilkS")
		)
		(fp_line
			(start 0.7874 -0.4064)
			(end -0.7874 -0.4064)
			(stroke
				(width 0.1524)
				(type default)
			)
			(layer "B.SilkS")
		)
		(fp_line
			(start -0.67945 0.3048)
			(end -0.120396 0.3048)
			(stroke
				(width 0.1)
				(type default)
			)
			(layer "B.Fab")
		)
		(fp_line
			(start -0.120396 0.3048)
			(end -0.120396 0.2794)
			(stroke
				(width 0.1)
				(type default)
			)
			(layer "B.Fab")
		)
		(fp_line
			(start 0.12065 0.3048)
			(end 0.67945 0.3048)
			(stroke
				(width 0.1)
				(type default)
			)
			(layer "B.Fab")
		)
		(fp_line
			(start 0.67945 0.3048)
			(end 0.67945 -0.305054)
			(stroke
				(width 0.1)
				(type default)
			)
			(layer "B.Fab")
		)
		(fp_line
			(start -0.120396 0.2794)
			(end 0.12065 0.2794)
			(stroke
				(width 0.1)
				(type default)
			)
			(layer "B.Fab")
		)
		(fp_line
			(start 0.12065 0.2794)
			(end 0.12065 0.3048)
			(stroke
				(width 0.1)
				(type default)
			)
			(layer "B.Fab")
		)
		(fp_line
			(start -0.12065 -0.2794)
			(end -0.12065 -0.3048)
			(stroke
				(width 0.1)
				(type default)
			)
			(layer "B.Fab")
		)
		(fp_line
			(start 0.12065 -0.2794)
			(end -0.12065 -0.2794)
			(stroke
				(width 0.1)
				(type default)
			)
			(layer "B.Fab")
		)
		(fp_line
			(start -0.67945 -0.3048)
			(end -0.67945 0.3048)
			(stroke
				(width 0.1)
				(type default)
			)
			(layer "B.Fab")
		)
		(fp_line
			(start -0.12065 -0.3048)
			(end -0.67945 -0.3048)
			(stroke
				(width 0.1)
				(type default)
			)
			(layer "B.Fab")
		)
		(fp_line
			(start 0.12065 -0.305054)
			(end 0.12065 -0.2794)
			(stroke
				(width 0.1)
				(type default)
			)
			(layer "B.Fab")
		)
		(fp_line
			(start 0.67945 -0.305054)
			(end 0.12065 -0.305054)
			(stroke
				(width 0.1)
				(type default)
			)
			(layer "B.Fab")
		)
		(pad "1" smd circle
			(at 0.40005 0 90)
			(size 0 0)
			(layers "B.Cu" "B.Mask" "B.Paste")
			(net "RST_PLD_CPU0_DRAM_EF_N")
		)
		(pad "2" smd circle
			(at -0.40005 0 90)
			(size 0 0)
			(layers "B.Cu" "B.Mask" "B.Paste")
			(net "RST_M_EF_CPU0_FPGA_N")
		)
	)
	(footprint ""
		(layer "B.Cu")
		(at 173.04893 -103.723948)
		(property "Reference" "C1940"
			(at 0 0 0)
			(layer "B.SilkS")
			(hide yes)
			(effects
				(font
					(size 1.27 1.27)
				)
				(justify mirror)
			)
		)
		(property "Value" ""
			(at 0 0 0)
			(layer "B.Fab")
			(effects
				(font
					(size 1.27 1.27)
				)
				(justify mirror)
			)
		)
		(duplicate_pad_numbers_are_jumpers no)
		(fp_line
			(start -0.7874 -0.4064)
			(end -0.7874 0.4064)
			(stroke
				(width 0.1524)
				(type default)
			)
			(layer "B.SilkS")
		)
		(fp_line
			(start -0.7874 0.4064)
			(end 0.7874 0.4064)
			(stroke
				(width 0.1524)
				(type default)
			)
			(layer "B.SilkS")
		)
		(fp_line
			(start 0.7874 -0.4064)
			(end -0.7874 -0.4064)
			(stroke
				(width 0.1524)
				(type default)
			)
			(layer "B.SilkS")
		)
		(fp_line
			(start 0.7874 0.4064)
			(end 0.7874 -0.4064)
			(stroke
				(width 0.1524)
				(type default)
			)
			(layer "B.SilkS")
		)
		(fp_line
			(start -0.67945 -0.3048)
			(end -0.67945 0.3048)
			(stroke
				(width 0.1)
				(type default)
			)
			(layer "B.Fab")
		)
		(fp_line
			(start -0.67945 0.3048)
			(end -0.120396 0.3048)
			(stroke
				(width 0.1)
				(type default)
			)
			(layer "B.Fab")
		)
		(fp_line
			(start -0.12065 -0.3048)
			(end -0.67945 -0.3048)
			(stroke
				(width 0.1)
				(type default)
			)
			(layer "B.Fab")
		)
		(fp_line
			(start -0.12065 -0.2794)
			(end -0.12065 -0.3048)
			(stroke
				(width 0.1)
				(type default)
			)
			(layer "B.Fab")
		)
		(fp_line
			(start -0.120396 0.2794)
			(end 0.12065 0.2794)
			(stroke
				(width 0.1)
				(type default)
			)
			(layer "B.Fab")
		)
		(fp_line
			(start -0.120396 0.3048)
			(end -0.120396 0.2794)
			(stroke
				(width 0.1)
				(type default)
			)
			(layer "B.Fab")
		)
		(fp_line
			(start 0.12065 -0.305054)
			(end 0.12065 -0.2794)
			(stroke
				(width 0.1)
				(type default)
			)
			(layer "B.Fab")
		)
		(fp_line
			(start 0.12065 -0.2794)
			(end -0.12065 -0.2794)
			(stroke
				(width 0.1)
				(type default)
			)
			(layer "B.Fab")
		)
		(fp_line
			(start 0.12065 0.2794)
			(end 0.12065 0.3048)
			(stroke
				(width 0.1)
				(type default)
			)
			(layer "B.Fab")
		)
		(fp_line
			(start 0.12065 0.3048)
			(end 0.67945 0.3048)
			(stroke
				(width 0.1)
				(type default)
			)
			(layer "B.Fab")
		)
		(fp_line
			(start 0.67945 -0.305054)
			(end 0.12065 -0.305054)
			(stroke
				(width 0.1)
				(type default)
			)
			(layer "B.Fab")
		)
		(fp_line
			(start 0.67945 0.3048)
			(end 0.67945 -0.305054)
			(stroke
				(width 0.1)
				(type default)
			)
			(layer "B.Fab")
		)
		(pad "1" smd circle
			(at 0.40005 0 180)
			(size 0 0)
			(layers "B.Cu" "B.Mask" "B.Paste")
			(net "P3V3_AUX_FPGA_VCCIO5")
		)
		(pad "2" smd circle
			(at -0.40005 0 180)
			(size 0 0)
			(layers "B.Cu" "B.Mask" "B.Paste")
			(net "GND")
		)
	)
	(footprint ""
		(layer "B.Cu")
		(at 445.866012 -58.300112 -90)
		(property "Reference" "PC1869"
			(at 0 0 90)
			(layer "B.SilkS")
			(hide yes)
			(effects
				(font
					(size 1.27 1.27)
				)
				(justify mirror)
			)
		)
		(property "Value" ""
			(at 0 0 90)
			(layer "B.Fab")
			(effects
				(font
					(size 1.27 1.27)
				)
				(justify mirror)
			)
		)
		(duplicate_pad_numbers_are_jumpers no)
		(fp_line
			(start -0.7874 0.4064)
			(end 0.7874 0.4064)
			(stroke
				(width 0.1524)
				(type default)
			)
			(layer "B.SilkS")
		)
		(fp_line
			(start 0.7874 0.4064)
			(end 0.7874 -0.4064)
			(stroke
				(width 0.1524)
				(type default)
			)
			(layer "B.SilkS")
		)
		(fp_line
			(start -0.7874 -0.4064)
			(end -0.7874 0.4064)
			(stroke
				(width 0.1524)
				(type default)
			)
			(layer "B.SilkS")
		)
		(fp_line
			(start 0.7874 -0.4064)
			(end -0.7874 -0.4064)
			(stroke
				(width 0.1524)
				(type default)
			)
			(layer "B.SilkS")
		)
		(fp_line
			(start -0.67945 0.3048)
			(end -0.120396 0.3048)
			(stroke
				(width 0.1)
				(type default)
			)
			(layer "B.Fab")
		)
		(fp_line
			(start -0.120396 0.3048)
			(end -0.120396 0.2794)
			(stroke
				(width 0.1)
				(type default)
			)
			(layer "B.Fab")
		)
		(fp_line
			(start 0.12065 0.3048)
			(end 0.67945 0.3048)
			(stroke
				(width 0.1)
				(type default)
			)
			(layer "B.Fab")
		)
		(fp_line
			(start 0.67945 0.3048)
			(end 0.67945 -0.305054)
			(stroke
				(width 0.1)
				(type default)
			)
			(layer "B.Fab")
		)
		(fp_line
			(start -0.120396 0.2794)
			(end 0.12065 0.2794)
			(stroke
				(width 0.1)
				(type default)
			)
			(layer "B.Fab")
		)
		(fp_line
			(start 0.12065 0.2794)
			(end 0.12065 0.3048)
			(stroke
				(width 0.1)
				(type default)
			)
			(layer "B.Fab")
		)
		(fp_line
			(start -0.12065 -0.2794)
			(end -0.12065 -0.3048)
			(stroke
				(width 0.1)
				(type default)
			)
			(layer "B.Fab")
		)
		(fp_line
			(start 0.12065 -0.2794)
			(end -0.12065 -0.2794)
			(stroke
				(width 0.1)
				(type default)
			)
			(layer "B.Fab")
		)
		(fp_line
			(start -0.67945 -0.3048)
			(end -0.67945 0.3048)
			(stroke
				(width 0.1)
				(type default)
			)
			(layer "B.Fab")
		)
		(fp_line
			(start -0.12065 -0.3048)
			(end -0.67945 -0.3048)
			(stroke
				(width 0.1)
				(type default)
			)
			(layer "B.Fab")
		)
		(fp_line
			(start 0.12065 -0.305054)
			(end 0.12065 -0.2794)
			(stroke
				(width 0.1)
				(type default)
			)
			(layer "B.Fab")
		)
		(fp_line
			(start 0.67945 -0.305054)
			(end 0.12065 -0.305054)
			(stroke
				(width 0.1)
				(type default)
			)
			(layer "B.Fab")
		)
		(pad "1" smd circle
			(at 0.40005 0 90)
			(size 0 0)
			(layers "B.Cu" "B.Mask" "B.Paste")
			(net "P3V3_AUX")
		)
		(pad "2" smd circle
			(at -0.40005 0 90)
			(size 0 0)
			(layers "B.Cu" "B.Mask" "B.Paste")
			(net "GND")
		)
	)
	(footprint ""
		(layer "B.Cu")
		(at 108.42371 -417.069524 180)
		(property "Reference" "R4493"
			(at 0 0 0)
			(layer "B.SilkS")
			(hide yes)
			(effects
				(font
					(size 1.27 1.27)
				)
				(justify mirror)
			)
		)
		(property "Value" ""
			(at 0 0 0)
			(layer "B.Fab")
			(effects
				(font
					(size 1.27 1.27)
				)
				(justify mirror)
			)
		)
		(duplicate_pad_numbers_are_jumpers no)
		(fp_line
			(start 1.2954 0.5842)
			(end 1.2954 -0.5842)
			(stroke
				(width 0.1524)
				(type default)
			)
			(layer "B.SilkS")
		)
		(fp_line
			(start 1.2954 -0.5842)
			(end -1.2954 -0.5842)
			(stroke
				(width 0.1524)
				(type default)
			)
			(layer "B.SilkS")
		)
		(fp_line
			(start -1.2954 0.5842)
			(end 1.2954 0.5842)
			(stroke
				(width 0.1524)
				(type default)
			)
			(layer "B.SilkS")
		)
		(fp_line
			(start -1.2954 -0.5842)
			(end -1.2954 0.5842)
			(stroke
				(width 0.1524)
				(type default)
			)
			(layer "B.SilkS")
		)
		(fp_line
			(start 1.1938 0.4064)
			(end 1.1938 -0.406654)
			(stroke
				(width 0.1)
				(type default)
			)
			(layer "B.Fab")
		)
		(fp_line
			(start 1.1938 -0.406654)
			(end 0.8636 -0.406654)
			(stroke
				(width 0.1)
				(type default)
			)
			(layer "B.Fab")
		)
		(fp_line
			(start 0.8636 0.4572)
			(end 0.8636 0.4318)
			(stroke
				(width 0.1)
				(type default)
			)
			(layer "B.Fab")
		)
		(fp_line
			(start 0.8636 0.4318)
			(end 0.8636 0.4064)
			(stroke
				(width 0.1)
				(type default)
			)
			(layer "B.Fab")
		)
		(fp_line
			(start 0.8636 0.4064)
			(end 1.1938 0.4064)
			(stroke
				(width 0.1)
				(type default)
			)
			(layer "B.Fab")
		)
		(fp_line
			(start 0.8636 -0.406654)
			(end 0.8636 -0.4572)
			(stroke
				(width 0.1)
				(type default)
			)
			(layer "B.Fab")
		)
		(fp_line
			(start 0.8636 -0.4572)
			(end -0.8636 -0.4572)
			(stroke
				(width 0.1)
				(type default)
			)
			(layer "B.Fab")
		)
		(fp_line
			(start -0.8636 0.4572)
			(end 0.8636 0.4572)
			(stroke
				(width 0.1)
				(type default)
			)
			(layer "B.Fab")
		)
		(fp_line
			(start -0.8636 0.4064)
			(end -0.8636 0.4572)
			(stroke
				(width 0.1)
				(type default)
			)
			(layer "B.Fab")
		)
		(fp_line
			(start -0.8636 -0.406654)
			(end -1.1938 -0.406654)
			(stroke
				(width 0.1)
				(type default)
			)
			(layer "B.Fab")
		)
		(fp_line
			(start -0.8636 -0.4572)
			(end -0.8636 -0.406654)
			(stroke
				(width 0.1)
				(type default)
			)
			(layer "B.Fab")
		)
		(fp_line
			(start -1.1938 0.4064)
			(end -0.8636 0.4064)
			(stroke
				(width 0.1)
				(type default)
			)
			(layer "B.Fab")
		)
		(fp_line
			(start -1.1938 -0.406654)
			(end -1.1938 0.4064)
			(stroke
				(width 0.1)
				(type default)
			)
			(layer "B.Fab")
		)
		(pad "1" smd rect
			(at 0.7366 0 90)
			(size 0.7112 0.8128)
			(layers "B.Cu" "B.Mask" "B.Paste")
			(net "P3V3_9ZXL045")
		)
		(pad "2" smd rect
			(at -0.7366 0 90)
			(size 0.7112 0.8128)
			(layers "B.Cu" "B.Mask" "B.Paste")
			(net "P3V3_9ZXL045_VDDA")
		)
	)
	(footprint ""
		(layer "B.Cu")
		(at 53.912516 -154.081226)
		(property "Reference" "PR254"
			(at 0 0 0)
			(layer "B.SilkS")
			(hide yes)
			(effects
				(font
					(size 1.27 1.27)
				)
				(justify mirror)
			)
		)
		(property "Value" ""
			(at 0 0 0)
			(layer "B.Fab")
			(effects
				(font
					(size 1.27 1.27)
				)
				(justify mirror)
			)
		)
		(duplicate_pad_numbers_are_jumpers no)
		(fp_line
			(start -0.7874 -0.4064)
			(end -0.7874 0.4064)
			(stroke
				(width 0.1524)
				(type default)
			)
			(layer "B.SilkS")
		)
		(fp_line
			(start -0.7874 0.4064)
			(end 0.7874 0.4064)
			(stroke
				(width 0.1524)
				(type default)
			)
			(layer "B.SilkS")
		)
		(fp_line
			(start 0.7874 -0.4064)
			(end -0.7874 -0.4064)
			(stroke
				(width 0.1524)
				(type default)
			)
			(layer "B.SilkS")
		)
		(fp_line
			(start 0.7874 0.4064)
			(end 0.7874 -0.4064)
			(stroke
				(width 0.1524)
				(type default)
			)
			(layer "B.SilkS")
		)
		(fp_line
			(start -0.67945 -0.3048)
			(end -0.67945 0.3048)
			(stroke
				(width 0.1)
				(type default)
			)
			(layer "B.Fab")
		)
		(fp_line
			(start -0.67945 0.3048)
			(end -0.120396 0.3048)
			(stroke
				(width 0.1)
				(type default)
			)
			(layer "B.Fab")
		)
		(fp_line
			(start -0.12065 -0.3048)
			(end -0.67945 -0.3048)
			(stroke
				(width 0.1)
				(type default)
			)
			(layer "B.Fab")
		)
		(fp_line
			(start -0.12065 -0.2794)
			(end -0.12065 -0.3048)
			(stroke
				(width 0.1)
				(type default)
			)
			(layer "B.Fab")
		)
		(fp_line
			(start -0.120396 0.2794)
			(end 0.12065 0.2794)
			(stroke
				(width 0.1)
				(type default)
			)
			(layer "B.Fab")
		)
		(fp_line
			(start -0.120396 0.3048)
			(end -0.120396 0.2794)
			(stroke
				(width 0.1)
				(type default)
			)
			(layer "B.Fab")
		)
		(fp_line
			(start 0.12065 -0.305054)
			(end 0.12065 -0.2794)
			(stroke
				(width 0.1)
				(type default)
			)
			(layer "B.Fab")
		)
		(fp_line
			(start 0.12065 -0.2794)
			(end -0.12065 -0.2794)
			(stroke
				(width 0.1)
				(type default)
			)
			(layer "B.Fab")
		)
		(fp_line
			(start 0.12065 0.2794)
			(end 0.12065 0.3048)
			(stroke
				(width 0.1)
				(type default)
			)
			(layer "B.Fab")
		)
		(fp_line
			(start 0.12065 0.3048)
			(end 0.67945 0.3048)
			(stroke
				(width 0.1)
				(type default)
			)
			(layer "B.Fab")
		)
		(fp_line
			(start 0.67945 -0.305054)
			(end 0.12065 -0.305054)
			(stroke
				(width 0.1)
				(type default)
			)
			(layer "B.Fab")
		)
		(fp_line
			(start 0.67945 0.3048)
			(end 0.67945 -0.305054)
			(stroke
				(width 0.1)
				(type default)
			)
			(layer "B.Fab")
		)
		(pad "1" smd circle
			(at 0.40005 0 180)
			(size 0 0)
			(layers "B.Cu" "B.Mask" "B.Paste")
			(net "PVCCFA_EHV_CPU1_PVCC")
		)
		(pad "2" smd circle
			(at -0.40005 0 180)
			(size 0 0)
			(layers "B.Cu" "B.Mask" "B.Paste")
			(net "PVCCINFAON_CPU1_VDD1")
		)
	)
	(footprint ""
		(layer "B.Cu")
		(at 36.968938 -127.41656)
		(property "Reference" "R2558"
			(at 0 0 0)
			(layer "B.SilkS")
			(hide yes)
			(effects
				(font
					(size 1.27 1.27)
				)
				(justify mirror)
			)
		)
		(property "Value" ""
			(at 0 0 0)
			(layer "B.Fab")
			(effects
				(font
					(size 1.27 1.27)
				)
				(justify mirror)
			)
		)
		(duplicate_pad_numbers_are_jumpers no)
		(fp_line
			(start -0.7874 -0.4064)
			(end -0.7874 0.4064)
			(stroke
				(width 0.1524)
				(type default)
			)
			(layer "B.SilkS")
		)
		(fp_line
			(start -0.7874 0.4064)
			(end 0.7874 0.4064)
			(stroke
				(width 0.1524)
				(type default)
			)
			(layer "B.SilkS")
		)
		(fp_line
			(start 0.7874 -0.4064)
			(end -0.7874 -0.4064)
			(stroke
				(width 0.1524)
				(type default)
			)
			(layer "B.SilkS")
		)
		(fp_line
			(start 0.7874 0.4064)
			(end 0.7874 -0.4064)
			(stroke
				(width 0.1524)
				(type default)
			)
			(layer "B.SilkS")
		)
		(fp_line
			(start -0.67945 -0.3048)
			(end -0.67945 0.3048)
			(stroke
				(width 0.1)
				(type default)
			)
			(layer "B.Fab")
		)
		(fp_line
			(start -0.67945 0.3048)
			(end -0.120396 0.3048)
			(stroke
				(width 0.1)
				(type default)
			)
			(layer "B.Fab")
		)
		(fp_line
			(start -0.12065 -0.3048)
			(end -0.67945 -0.3048)
			(stroke
				(width 0.1)
				(type default)
			)
			(layer "B.Fab")
		)
		(fp_line
			(start -0.12065 -0.2794)
			(end -0.12065 -0.3048)
			(stroke
				(width 0.1)
				(type default)
			)
			(layer "B.Fab")
		)
		(fp_line
			(start -0.120396 0.2794)
			(end 0.12065 0.2794)
			(stroke
				(width 0.1)
				(type default)
			)
			(layer "B.Fab")
		)
		(fp_line
			(start -0.120396 0.3048)
			(end -0.120396 0.2794)
			(stroke
				(width 0.1)
				(type default)
			)
			(layer "B.Fab")
		)
		(fp_line
			(start 0.12065 -0.305054)
			(end 0.12065 -0.2794)
			(stroke
				(width 0.1)
				(type default)
			)
			(layer "B.Fab")
		)
		(fp_line
			(start 0.12065 -0.2794)
			(end -0.12065 -0.2794)
			(stroke
				(width 0.1)
				(type default)
			)
			(layer "B.Fab")
		)
		(fp_line
			(start 0.12065 0.2794)
			(end 0.12065 0.3048)
			(stroke
				(width 0.1)
				(type default)
			)
			(layer "B.Fab")
		)
		(fp_line
			(start 0.12065 0.3048)
			(end 0.67945 0.3048)
			(stroke
				(width 0.1)
				(type default)
			)
			(layer "B.Fab")
		)
		(fp_line
			(start 0.67945 -0.305054)
			(end 0.12065 -0.305054)
			(stroke
				(width 0.1)
				(type default)
			)
			(layer "B.Fab")
		)
		(fp_line
			(start 0.67945 0.3048)
			(end 0.67945 -0.305054)
			(stroke
				(width 0.1)
				(type default)
			)
			(layer "B.Fab")
		)
		(pad "1" smd circle
			(at 0.40005 0 180)
			(size 0 0)
			(layers "B.Cu" "B.Mask" "B.Paste")
			(net "FM_PVCCINFAON_CPU1_EN")
		)
		(pad "2" smd circle
			(at -0.40005 0 180)
			(size 0 0)
			(layers "B.Cu" "B.Mask" "B.Paste")
			(net "PVCCINFAON_CPU1_EN_R")
		)
	)
	(footprint ""
		(layer "B.Cu")
		(at 339.12048 -53.471826 90)
		(property "Reference" "R1463"
			(at 0 0 90)
			(layer "B.SilkS")
			(hide yes)
			(effects
				(font
					(size 1.27 1.27)
				)
				(justify mirror)
			)
		)
		(property "Value" ""
			(at 0 0 90)
			(layer "B.Fab")
			(effects
				(font
					(size 1.27 1.27)
				)
				(justify mirror)
			)
		)
		(duplicate_pad_numbers_are_jumpers no)
		(fp_line
			(start 0.7874 -0.4064)
			(end -0.7874 -0.4064)
			(stroke
				(width 0.1524)
				(type default)
			)
			(layer "B.SilkS")
		)
		(fp_line
			(start -0.7874 -0.4064)
			(end -0.7874 0.4064)
			(stroke
				(width 0.1524)
				(type default)
			)
			(layer "B.SilkS")
		)
		(fp_line
			(start 0.7874 0.4064)
			(end 0.7874 -0.4064)
			(stroke
				(width 0.1524)
				(type default)
			)
			(layer "B.SilkS")
		)
		(fp_line
			(start -0.7874 0.4064)
			(end 0.7874 0.4064)
			(stroke
				(width 0.1524)
				(type default)
			)
			(layer "B.SilkS")
		)
		(fp_line
			(start 0.67945 -0.305054)
			(end 0.12065 -0.305054)
			(stroke
				(width 0.1)
				(type default)
			)
			(layer "B.Fab")
		)
		(fp_line
			(start 0.12065 -0.305054)
			(end 0.12065 -0.2794)
			(stroke
				(width 0.1)
				(type default)
			)
			(layer "B.Fab")
		)
		(fp_line
			(start -0.12065 -0.3048)
			(end -0.67945 -0.3048)
			(stroke
				(width 0.1)
				(type default)
			)
			(layer "B.Fab")
		)
		(fp_line
			(start -0.67945 -0.3048)
			(end -0.67945 0.3048)
			(stroke
				(width 0.1)
				(type default)
			)
			(layer "B.Fab")
		)
		(fp_line
			(start 0.12065 -0.2794)
			(end -0.12065 -0.2794)
			(stroke
				(width 0.1)
				(type default)
			)
			(layer "B.Fab")
		)
		(fp_line
			(start -0.12065 -0.2794)
			(end -0.12065 -0.3048)
			(stroke
				(width 0.1)
				(type default)
			)
			(layer "B.Fab")
		)
		(fp_line
			(start 0.12065 0.2794)
			(end 0.12065 0.3048)
			(stroke
				(width 0.1)
				(type default)
			)
			(layer "B.Fab")
		)
		(fp_line
			(start -0.120396 0.2794)
			(end 0.12065 0.2794)
			(stroke
				(width 0.1)
				(type default)
			)
			(layer "B.Fab")
		)
		(fp_line
			(start 0.67945 0.3048)
			(end 0.67945 -0.305054)
			(stroke
				(width 0.1)
				(type default)
			)
			(layer "B.Fab")
		)
		(fp_line
			(start 0.12065 0.3048)
			(end 0.67945 0.3048)
			(stroke
				(width 0.1)
				(type default)
			)
			(layer "B.Fab")
		)
		(fp_line
			(start -0.120396 0.3048)
			(end -0.120396 0.2794)
			(stroke
				(width 0.1)
				(type default)
			)
			(layer "B.Fab")
		)
		(fp_line
			(start -0.67945 0.3048)
			(end -0.120396 0.3048)
			(stroke
				(width 0.1)
				(type default)
			)
			(layer "B.Fab")
		)
		(pad "1" smd circle
			(at 0.40005 0 270)
			(size 0 0)
			(layers "B.Cu" "B.Mask" "B.Paste")
			(net "P1V05_PCH_AUX")
		)
		(pad "2" smd circle
			(at -0.40005 0 270)
			(size 0 0)
			(layers "B.Cu" "B.Mask" "B.Paste")
			(net "P1V05_PCH_PLL_AUX")
		)
	)
	(footprint ""
		(layer "B.Cu")
		(at 107.77728 -356.504748 -90)
		(property "Reference" "PR4238"
			(at 0 0 90)
			(layer "B.SilkS")
			(hide yes)
			(effects
				(font
					(size 1.27 1.27)
				)
				(justify mirror)
			)
		)
		(property "Value" ""
			(at 0 0 90)
			(layer "B.Fab")
			(effects
				(font
					(size 1.27 1.27)
				)
				(justify mirror)
			)
		)
		(duplicate_pad_numbers_are_jumpers no)
		(fp_line
			(start -0.7874 0.4064)
			(end 0.7874 0.4064)
			(stroke
				(width 0.1524)
				(type default)
			)
			(layer "B.SilkS")
		)
		(fp_line
			(start 0.7874 0.4064)
			(end 0.7874 -0.4064)
			(stroke
				(width 0.1524)
				(type default)
			)
			(layer "B.SilkS")
		)
		(fp_line
			(start -0.7874 -0.4064)
			(end -0.7874 0.4064)
			(stroke
				(width 0.1524)
				(type default)
			)
			(layer "B.SilkS")
		)
		(fp_line
			(start 0.7874 -0.4064)
			(end -0.7874 -0.4064)
			(stroke
				(width 0.1524)
				(type default)
			)
			(layer "B.SilkS")
		)
		(fp_line
			(start -0.67945 0.3048)
			(end -0.120396 0.3048)
			(stroke
				(width 0.1)
				(type default)
			)
			(layer "B.Fab")
		)
		(fp_line
			(start -0.120396 0.3048)
			(end -0.120396 0.2794)
			(stroke
				(width 0.1)
				(type default)
			)
			(layer "B.Fab")
		)
		(fp_line
			(start 0.12065 0.3048)
			(end 0.67945 0.3048)
			(stroke
				(width 0.1)
				(type default)
			)
			(layer "B.Fab")
		)
		(fp_line
			(start 0.67945 0.3048)
			(end 0.67945 -0.305054)
			(stroke
				(width 0.1)
				(type default)
			)
			(layer "B.Fab")
		)
		(fp_line
			(start -0.120396 0.2794)
			(end 0.12065 0.2794)
			(stroke
				(width 0.1)
				(type default)
			)
			(layer "B.Fab")
		)
		(fp_line
			(start 0.12065 0.2794)
			(end 0.12065 0.3048)
			(stroke
				(width 0.1)
				(type default)
			)
			(layer "B.Fab")
		)
		(fp_line
			(start -0.12065 -0.2794)
			(end -0.12065 -0.3048)
			(stroke
				(width 0.1)
				(type default)
			)
			(layer "B.Fab")
		)
		(fp_line
			(start 0.12065 -0.2794)
			(end -0.12065 -0.2794)
			(stroke
				(width 0.1)
				(type default)
			)
			(layer "B.Fab")
		)
		(fp_line
			(start -0.67945 -0.3048)
			(end -0.67945 0.3048)
			(stroke
				(width 0.1)
				(type default)
			)
			(layer "B.Fab")
		)
		(fp_line
			(start -0.12065 -0.3048)
			(end -0.67945 -0.3048)
			(stroke
				(width 0.1)
				(type default)
			)
			(layer "B.Fab")
		)
		(fp_line
			(start 0.12065 -0.305054)
			(end 0.12065 -0.2794)
			(stroke
				(width 0.1)
				(type default)
			)
			(layer "B.Fab")
		)
		(fp_line
			(start 0.67945 -0.305054)
			(end 0.12065 -0.305054)
			(stroke
				(width 0.1)
				(type default)
			)
			(layer "B.Fab")
		)
		(pad "1" smd circle
			(at 0.40005 0 90)
			(size 0 0)
			(layers "B.Cu" "B.Mask" "B.Paste")
			(net "PVCCFA_EHV_FIVRA_CPU1_IMON4")
		)
		(pad "2" smd circle
			(at -0.40005 0 90)
			(size 0 0)
			(layers "B.Cu" "B.Mask" "B.Paste")
			(net "GND")
		)
	)
	(footprint ""
		(layer "B.Cu")
		(at 434.354478 -177.15611 -90)
		(property "Reference" "R2338"
			(at 0 0 90)
			(layer "B.SilkS")
			(hide yes)
			(effects
				(font
					(size 1.27 1.27)
				)
				(justify mirror)
			)
		)
		(property "Value" ""
			(at 0 0 90)
			(layer "B.Fab")
			(effects
				(font
					(size 1.27 1.27)
				)
				(justify mirror)
			)
		)
		(duplicate_pad_numbers_are_jumpers no)
		(fp_line
			(start -0.7874 0.4064)
			(end 0.7874 0.4064)
			(stroke
				(width 0.1524)
				(type default)
			)
			(layer "B.SilkS")
		)
		(fp_line
			(start 0.7874 0.4064)
			(end 0.7874 -0.4064)
			(stroke
				(width 0.1524)
				(type default)
			)
			(layer "B.SilkS")
		)
		(fp_line
			(start -0.7874 -0.4064)
			(end -0.7874 0.4064)
			(stroke
				(width 0.1524)
				(type default)
			)
			(layer "B.SilkS")
		)
		(fp_line
			(start 0.7874 -0.4064)
			(end -0.7874 -0.4064)
			(stroke
				(width 0.1524)
				(type default)
			)
			(layer "B.SilkS")
		)
		(fp_line
			(start -0.67945 0.3048)
			(end -0.120396 0.3048)
			(stroke
				(width 0.1)
				(type default)
			)
			(layer "B.Fab")
		)
		(fp_line
			(start -0.120396 0.3048)
			(end -0.120396 0.2794)
			(stroke
				(width 0.1)
				(type default)
			)
			(layer "B.Fab")
		)
		(fp_line
			(start 0.12065 0.3048)
			(end 0.67945 0.3048)
			(stroke
				(width 0.1)
				(type default)
			)
			(layer "B.Fab")
		)
		(fp_line
			(start 0.67945 0.3048)
			(end 0.67945 -0.305054)
			(stroke
				(width 0.1)
				(type default)
			)
			(layer "B.Fab")
		)
		(fp_line
			(start -0.120396 0.2794)
			(end 0.12065 0.2794)
			(stroke
				(width 0.1)
				(type default)
			)
			(layer "B.Fab")
		)
		(fp_line
			(start 0.12065 0.2794)
			(end 0.12065 0.3048)
			(stroke
				(width 0.1)
				(type default)
			)
			(layer "B.Fab")
		)
		(fp_line
			(start -0.12065 -0.2794)
			(end -0.12065 -0.3048)
			(stroke
				(width 0.1)
				(type default)
			)
			(layer "B.Fab")
		)
		(fp_line
			(start 0.12065 -0.2794)
			(end -0.12065 -0.2794)
			(stroke
				(width 0.1)
				(type default)
			)
			(layer "B.Fab")
		)
		(fp_line
			(start -0.67945 -0.3048)
			(end -0.67945 0.3048)
			(stroke
				(width 0.1)
				(type default)
			)
			(layer "B.Fab")
		)
		(fp_line
			(start -0.12065 -0.3048)
			(end -0.67945 -0.3048)
			(stroke
				(width 0.1)
				(type default)
			)
			(layer "B.Fab")
		)
		(fp_line
			(start 0.12065 -0.305054)
			(end 0.12065 -0.2794)
			(stroke
				(width 0.1)
				(type default)
			)
			(layer "B.Fab")
		)
		(fp_line
			(start 0.67945 -0.305054)
			(end 0.12065 -0.305054)
			(stroke
				(width 0.1)
				(type default)
			)
			(layer "B.Fab")
		)
		(pad "1" smd circle
			(at 0.40005 0 90)
			(size 0 0)
			(layers "B.Cu" "B.Mask" "B.Paste")
			(net "P3V3_AUX")
		)
		(pad "2" smd circle
			(at -0.40005 0 90)
			(size 0 0)
			(layers "B.Cu" "B.Mask" "B.Paste")
			(net "FM_PVNN_MAIN_CPU0_EN")
		)
	)
	(footprint ""
		(layer "B.Cu")
		(at 453.850756 -318.704976)
		(property "Reference" "R41"
			(at 0 0 0)
			(layer "B.SilkS")
			(hide yes)
			(effects
				(font
					(size 1.27 1.27)
				)
				(justify mirror)
			)
		)
		(property "Value" ""
			(at 0 0 0)
			(layer "B.Fab")
			(effects
				(font
					(size 1.27 1.27)
				)
				(justify mirror)
			)
		)
		(duplicate_pad_numbers_are_jumpers no)
		(fp_line
			(start -0.7874 -0.4064)
			(end -0.7874 0.4064)
			(stroke
				(width 0.1524)
				(type default)
			)
			(layer "B.SilkS")
		)
		(fp_line
			(start -0.7874 0.4064)
			(end 0.7874 0.4064)
			(stroke
				(width 0.1524)
				(type default)
			)
			(layer "B.SilkS")
		)
		(fp_line
			(start 0.7874 -0.4064)
			(end -0.7874 -0.4064)
			(stroke
				(width 0.1524)
				(type default)
			)
			(layer "B.SilkS")
		)
		(fp_line
			(start 0.7874 0.4064)
			(end 0.7874 -0.4064)
			(stroke
				(width 0.1524)
				(type default)
			)
			(layer "B.SilkS")
		)
		(fp_line
			(start -0.67945 -0.3048)
			(end -0.67945 0.3048)
			(stroke
				(width 0.1)
				(type default)
			)
			(layer "B.Fab")
		)
		(fp_line
			(start -0.67945 0.3048)
			(end -0.120396 0.3048)
			(stroke
				(width 0.1)
				(type default)
			)
			(layer "B.Fab")
		)
		(fp_line
			(start -0.12065 -0.3048)
			(end -0.67945 -0.3048)
			(stroke
				(width 0.1)
				(type default)
			)
			(layer "B.Fab")
		)
		(fp_line
			(start -0.12065 -0.2794)
			(end -0.12065 -0.3048)
			(stroke
				(width 0.1)
				(type default)
			)
			(layer "B.Fab")
		)
		(fp_line
			(start -0.120396 0.2794)
			(end 0.12065 0.2794)
			(stroke
				(width 0.1)
				(type default)
			)
			(layer "B.Fab")
		)
		(fp_line
			(start -0.120396 0.3048)
			(end -0.120396 0.2794)
			(stroke
				(width 0.1)
				(type default)
			)
			(layer "B.Fab")
		)
		(fp_line
			(start 0.12065 -0.305054)
			(end 0.12065 -0.2794)
			(stroke
				(width 0.1)
				(type default)
			)
			(layer "B.Fab")
		)
		(fp_line
			(start 0.12065 -0.2794)
			(end -0.12065 -0.2794)
			(stroke
				(width 0.1)
				(type default)
			)
			(layer "B.Fab")
		)
		(fp_line
			(start 0.12065 0.2794)
			(end 0.12065 0.3048)
			(stroke
				(width 0.1)
				(type default)
			)
			(layer "B.Fab")
		)
		(fp_line
			(start 0.12065 0.3048)
			(end 0.67945 0.3048)
			(stroke
				(width 0.1)
				(type default)
			)
			(layer "B.Fab")
		)
		(fp_line
			(start 0.67945 -0.305054)
			(end 0.12065 -0.305054)
			(stroke
				(width 0.1)
				(type default)
			)
			(layer "B.Fab")
		)
		(fp_line
			(start 0.67945 0.3048)
			(end 0.67945 -0.305054)
			(stroke
				(width 0.1)
				(type default)
			)
			(layer "B.Fab")
		)
		(pad "1" smd circle
			(at 0.40005 0 180)
			(size 0 0)
			(layers "B.Cu" "B.Mask" "B.Paste")
			(net "PD_CHH_CPU0_DIMM2_SAA")
		)
		(pad "2" smd circle
			(at -0.40005 0 180)
			(size 0 0)
			(layers "B.Cu" "B.Mask" "B.Paste")
			(net "GND")
		)
	)
	(footprint ""
		(layer "B.Cu")
		(at 336.167222 -33.20542 90)
		(property "Reference" "R916"
			(at 0 0 90)
			(layer "B.SilkS")
			(hide yes)
			(effects
				(font
					(size 1.27 1.27)
				)
				(justify mirror)
			)
		)
		(property "Value" ""
			(at 0 0 90)
			(layer "B.Fab")
			(effects
				(font
					(size 1.27 1.27)
				)
				(justify mirror)
			)
		)
		(duplicate_pad_numbers_are_jumpers no)
		(fp_line
			(start 0.7874 -0.4064)
			(end -0.7874 -0.4064)
			(stroke
				(width 0.1524)
				(type default)
			)
			(layer "B.SilkS")
		)
		(fp_line
			(start -0.7874 -0.4064)
			(end -0.7874 0.4064)
			(stroke
				(width 0.1524)
				(type default)
			)
			(layer "B.SilkS")
		)
		(fp_line
			(start 0.7874 0.4064)
			(end 0.7874 -0.4064)
			(stroke
				(width 0.1524)
				(type default)
			)
			(layer "B.SilkS")
		)
		(fp_line
			(start -0.7874 0.4064)
			(end 0.7874 0.4064)
			(stroke
				(width 0.1524)
				(type default)
			)
			(layer "B.SilkS")
		)
		(fp_line
			(start 0.67945 -0.305054)
			(end 0.12065 -0.305054)
			(stroke
				(width 0.1)
				(type default)
			)
			(layer "B.Fab")
		)
		(fp_line
			(start 0.12065 -0.305054)
			(end 0.12065 -0.2794)
			(stroke
				(width 0.1)
				(type default)
			)
			(layer "B.Fab")
		)
		(fp_line
			(start -0.12065 -0.3048)
			(end -0.67945 -0.3048)
			(stroke
				(width 0.1)
				(type default)
			)
			(layer "B.Fab")
		)
		(fp_line
			(start -0.67945 -0.3048)
			(end -0.67945 0.3048)
			(stroke
				(width 0.1)
				(type default)
			)
			(layer "B.Fab")
		)
		(fp_line
			(start 0.12065 -0.2794)
			(end -0.12065 -0.2794)
			(stroke
				(width 0.1)
				(type default)
			)
			(layer "B.Fab")
		)
		(fp_line
			(start -0.12065 -0.2794)
			(end -0.12065 -0.3048)
			(stroke
				(width 0.1)
				(type default)
			)
			(layer "B.Fab")
		)
		(fp_line
			(start 0.12065 0.2794)
			(end 0.12065 0.3048)
			(stroke
				(width 0.1)
				(type default)
			)
			(layer "B.Fab")
		)
		(fp_line
			(start -0.120396 0.2794)
			(end 0.12065 0.2794)
			(stroke
				(width 0.1)
				(type default)
			)
			(layer "B.Fab")
		)
		(fp_line
			(start 0.67945 0.3048)
			(end 0.67945 -0.305054)
			(stroke
				(width 0.1)
				(type default)
			)
			(layer "B.Fab")
		)
		(fp_line
			(start 0.12065 0.3048)
			(end 0.67945 0.3048)
			(stroke
				(width 0.1)
				(type default)
			)
			(layer "B.Fab")
		)
		(fp_line
			(start -0.120396 0.3048)
			(end -0.120396 0.2794)
			(stroke
				(width 0.1)
				(type default)
			)
			(layer "B.Fab")
		)
		(fp_line
			(start -0.67945 0.3048)
			(end -0.120396 0.3048)
			(stroke
				(width 0.1)
				(type default)
			)
			(layer "B.Fab")
		)
		(pad "1" smd circle
			(at 0.40005 0 270)
			(size 0 0)
			(layers "B.Cu" "B.Mask" "B.Paste")
			(net "SPI_PCH_IO1")
		)
		(pad "2" smd circle
			(at -0.40005 0 270)
			(size 0 0)
			(layers "B.Cu" "B.Mask" "B.Paste")
			(net "SPI_SYS_MISO")
		)
	)
	(footprint ""
		(layer "B.Cu")
		(at 326.00519 -28.84297 -90)
		(property "Reference" "R613"
			(at 0 0 90)
			(layer "B.SilkS")
			(hide yes)
			(effects
				(font
					(size 1.27 1.27)
				)
				(justify mirror)
			)
		)
		(property "Value" ""
			(at 0 0 90)
			(layer "B.Fab")
			(effects
				(font
					(size 1.27 1.27)
				)
				(justify mirror)
			)
		)
		(duplicate_pad_numbers_are_jumpers no)
		(fp_line
			(start -0.7874 0.4064)
			(end 0.7874 0.4064)
			(stroke
				(width 0.1524)
				(type default)
			)
			(layer "B.SilkS")
		)
		(fp_line
			(start 0.7874 0.4064)
			(end 0.7874 -0.4064)
			(stroke
				(width 0.1524)
				(type default)
			)
			(layer "B.SilkS")
		)
		(fp_line
			(start -0.7874 -0.4064)
			(end -0.7874 0.4064)
			(stroke
				(width 0.1524)
				(type default)
			)
			(layer "B.SilkS")
		)
		(fp_line
			(start 0.7874 -0.4064)
			(end -0.7874 -0.4064)
			(stroke
				(width 0.1524)
				(type default)
			)
			(layer "B.SilkS")
		)
		(fp_line
			(start -0.67945 0.3048)
			(end -0.120396 0.3048)
			(stroke
				(width 0.1)
				(type default)
			)
			(layer "B.Fab")
		)
		(fp_line
			(start -0.120396 0.3048)
			(end -0.120396 0.2794)
			(stroke
				(width 0.1)
				(type default)
			)
			(layer "B.Fab")
		)
		(fp_line
			(start 0.12065 0.3048)
			(end 0.67945 0.3048)
			(stroke
				(width 0.1)
				(type default)
			)
			(layer "B.Fab")
		)
		(fp_line
			(start 0.67945 0.3048)
			(end 0.67945 -0.305054)
			(stroke
				(width 0.1)
				(type default)
			)
			(layer "B.Fab")
		)
		(fp_line
			(start -0.120396 0.2794)
			(end 0.12065 0.2794)
			(stroke
				(width 0.1)
				(type default)
			)
			(layer "B.Fab")
		)
		(fp_line
			(start 0.12065 0.2794)
			(end 0.12065 0.3048)
			(stroke
				(width 0.1)
				(type default)
			)
			(layer "B.Fab")
		)
		(fp_line
			(start -0.12065 -0.2794)
			(end -0.12065 -0.3048)
			(stroke
				(width 0.1)
				(type default)
			)
			(layer "B.Fab")
		)
		(fp_line
			(start 0.12065 -0.2794)
			(end -0.12065 -0.2794)
			(stroke
				(width 0.1)
				(type default)
			)
			(layer "B.Fab")
		)
		(fp_line
			(start -0.67945 -0.3048)
			(end -0.67945 0.3048)
			(stroke
				(width 0.1)
				(type default)
			)
			(layer "B.Fab")
		)
		(fp_line
			(start -0.12065 -0.3048)
			(end -0.67945 -0.3048)
			(stroke
				(width 0.1)
				(type default)
			)
			(layer "B.Fab")
		)
		(fp_line
			(start 0.12065 -0.305054)
			(end 0.12065 -0.2794)
			(stroke
				(width 0.1)
				(type default)
			)
			(layer "B.Fab")
		)
		(fp_line
			(start 0.67945 -0.305054)
			(end 0.12065 -0.305054)
			(stroke
				(width 0.1)
				(type default)
			)
			(layer "B.Fab")
		)
		(pad "1" smd circle
			(at 0.40005 0 90)
			(size 0 0)
			(layers "B.Cu" "B.Mask" "B.Paste")
			(net "P3V3_AUX")
		)
		(pad "2" smd circle
			(at -0.40005 0 90)
			(size 0 0)
			(layers "B.Cu" "B.Mask" "B.Paste")
			(net "FM_JTAG_ODT_DISABLE")
		)
	)
	(footprint ""
		(layer "B.Cu")
		(at 180.26888 -124.170948 180)
		(property "Reference" "C1936"
			(at 0 0 0)
			(layer "B.SilkS")
			(hide yes)
			(effects
				(font
					(size 1.27 1.27)
				)
				(justify mirror)
			)
		)
		(property "Value" ""
			(at 0 0 0)
			(layer "B.Fab")
			(effects
				(font
					(size 1.27 1.27)
				)
				(justify mirror)
			)
		)
		(duplicate_pad_numbers_are_jumpers no)
		(fp_line
			(start 0.7874 0.4064)
			(end 0.7874 -0.4064)
			(stroke
				(width 0.1524)
				(type default)
			)
			(layer "B.SilkS")
		)
		(fp_line
			(start 0.7874 -0.4064)
			(end -0.7874 -0.4064)
			(stroke
				(width 0.1524)
				(type default)
			)
			(layer "B.SilkS")
		)
		(fp_line
			(start -0.7874 0.4064)
			(end 0.7874 0.4064)
			(stroke
				(width 0.1524)
				(type default)
			)
			(layer "B.SilkS")
		)
		(fp_line
			(start -0.7874 -0.4064)
			(end -0.7874 0.4064)
			(stroke
				(width 0.1524)
				(type default)
			)
			(layer "B.SilkS")
		)
		(fp_line
			(start 0.67945 0.3048)
			(end 0.67945 -0.305054)
			(stroke
				(width 0.1)
				(type default)
			)
			(layer "B.Fab")
		)
		(fp_line
			(start 0.67945 -0.305054)
			(end 0.12065 -0.305054)
			(stroke
				(width 0.1)
				(type default)
			)
			(layer "B.Fab")
		)
		(fp_line
			(start 0.12065 0.3048)
			(end 0.67945 0.3048)
			(stroke
				(width 0.1)
				(type default)
			)
			(layer "B.Fab")
		)
		(fp_line
			(start 0.12065 0.2794)
			(end 0.12065 0.3048)
			(stroke
				(width 0.1)
				(type default)
			)
			(layer "B.Fab")
		)
		(fp_line
			(start 0.12065 -0.2794)
			(end -0.12065 -0.2794)
			(stroke
				(width 0.1)
				(type default)
			)
			(layer "B.Fab")
		)
		(fp_line
			(start 0.12065 -0.305054)
			(end 0.12065 -0.2794)
			(stroke
				(width 0.1)
				(type default)
			)
			(layer "B.Fab")
		)
		(fp_line
			(start -0.120396 0.3048)
			(end -0.120396 0.2794)
			(stroke
				(width 0.1)
				(type default)
			)
			(layer "B.Fab")
		)
		(fp_line
			(start -0.120396 0.2794)
			(end 0.12065 0.2794)
			(stroke
				(width 0.1)
				(type default)
			)
			(layer "B.Fab")
		)
		(fp_line
			(start -0.12065 -0.2794)
			(end -0.12065 -0.3048)
			(stroke
				(width 0.1)
				(type default)
			)
			(layer "B.Fab")
		)
		(fp_line
			(start -0.12065 -0.3048)
			(end -0.67945 -0.3048)
			(stroke
				(width 0.1)
				(type default)
			)
			(layer "B.Fab")
		)
		(fp_line
			(start -0.67945 0.3048)
			(end -0.120396 0.3048)
			(stroke
				(width 0.1)
				(type default)
			)
			(layer "B.Fab")
		)
		(fp_line
			(start -0.67945 -0.3048)
			(end -0.67945 0.3048)
			(stroke
				(width 0.1)
				(type default)
			)
			(layer "B.Fab")
		)
		(pad "1" smd circle
			(at 0.40005 0)
			(size 0 0)
			(layers "B.Cu" "B.Mask" "B.Paste")
			(net "VCC_PLD_CORE")
		)
		(pad "2" smd circle
			(at -0.40005 0)
			(size 0 0)
			(layers "B.Cu" "B.Mask" "B.Paste")
			(net "GND")
		)
	)
	(footprint ""
		(layer "B.Cu")
		(at 373.546624 -190.703454 90)
		(property "Reference" "R960"
			(at 0 0 90)
			(layer "B.SilkS")
			(hide yes)
			(effects
				(font
					(size 1.27 1.27)
				)
				(justify mirror)
			)
		)
		(property "Value" ""
			(at 0 0 90)
			(layer "B.Fab")
			(effects
				(font
					(size 1.27 1.27)
				)
				(justify mirror)
			)
		)
		(duplicate_pad_numbers_are_jumpers no)
		(fp_line
			(start 0.7874 -0.4064)
			(end -0.7874 -0.4064)
			(stroke
				(width 0.1524)
				(type default)
			)
			(layer "B.SilkS")
		)
		(fp_line
			(start -0.7874 -0.4064)
			(end -0.7874 0.4064)
			(stroke
				(width 0.1524)
				(type default)
			)
			(layer "B.SilkS")
		)
		(fp_line
			(start 0.7874 0.4064)
			(end 0.7874 -0.4064)
			(stroke
				(width 0.1524)
				(type default)
			)
			(layer "B.SilkS")
		)
		(fp_line
			(start -0.7874 0.4064)
			(end 0.7874 0.4064)
			(stroke
				(width 0.1524)
				(type default)
			)
			(layer "B.SilkS")
		)
		(fp_line
			(start 0.67945 -0.305054)
			(end 0.12065 -0.305054)
			(stroke
				(width 0.1)
				(type default)
			)
			(layer "B.Fab")
		)
		(fp_line
			(start 0.12065 -0.305054)
			(end 0.12065 -0.2794)
			(stroke
				(width 0.1)
				(type default)
			)
			(layer "B.Fab")
		)
		(fp_line
			(start -0.12065 -0.3048)
			(end -0.67945 -0.3048)
			(stroke
				(width 0.1)
				(type default)
			)
			(layer "B.Fab")
		)
		(fp_line
			(start -0.67945 -0.3048)
			(end -0.67945 0.3048)
			(stroke
				(width 0.1)
				(type default)
			)
			(layer "B.Fab")
		)
		(fp_line
			(start 0.12065 -0.2794)
			(end -0.12065 -0.2794)
			(stroke
				(width 0.1)
				(type default)
			)
			(layer "B.Fab")
		)
		(fp_line
			(start -0.12065 -0.2794)
			(end -0.12065 -0.3048)
			(stroke
				(width 0.1)
				(type default)
			)
			(layer "B.Fab")
		)
		(fp_line
			(start 0.12065 0.2794)
			(end 0.12065 0.3048)
			(stroke
				(width 0.1)
				(type default)
			)
			(layer "B.Fab")
		)
		(fp_line
			(start -0.120396 0.2794)
			(end 0.12065 0.2794)
			(stroke
				(width 0.1)
				(type default)
			)
			(layer "B.Fab")
		)
		(fp_line
			(start 0.67945 0.3048)
			(end 0.67945 -0.305054)
			(stroke
				(width 0.1)
				(type default)
			)
			(layer "B.Fab")
		)
		(fp_line
			(start 0.12065 0.3048)
			(end 0.67945 0.3048)
			(stroke
				(width 0.1)
				(type default)
			)
			(layer "B.Fab")
		)
		(fp_line
			(start -0.120396 0.3048)
			(end -0.120396 0.2794)
			(stroke
				(width 0.1)
				(type default)
			)
			(layer "B.Fab")
		)
		(fp_line
			(start -0.67945 0.3048)
			(end -0.120396 0.3048)
			(stroke
				(width 0.1)
				(type default)
			)
			(layer "B.Fab")
		)
		(pad "1" smd circle
			(at 0.40005 0 270)
			(size 0 0)
			(layers "B.Cu" "B.Mask" "B.Paste")
			(net "SMB_PEHPCPU0_GTL_SCL")
		)
		(pad "2" smd circle
			(at -0.40005 0 270)
			(size 0 0)
			(layers "B.Cu" "B.Mask" "B.Paste")
			(net "SMB_PEHPCPU0_GTL_R_SCL")
		)
	)
	(footprint ""
		(layer "B.Cu")
		(at 181.865016 -346.586302 -90)
		(property "Reference" "PC1205"
			(at 0 0 90)
			(layer "B.SilkS")
			(hide yes)
			(effects
				(font
					(size 1.27 1.27)
				)
				(justify mirror)
			)
		)
		(property "Value" ""
			(at 0 0 90)
			(layer "B.Fab")
			(effects
				(font
					(size 1.27 1.27)
				)
				(justify mirror)
			)
		)
		(duplicate_pad_numbers_are_jumpers no)
		(fp_line
			(start -4.533392 2.249932)
			(end 4.533392 2.249932)
			(stroke
				(width 0.1524)
				(type default)
			)
			(layer "B.SilkS")
		)
		(fp_line
			(start 4.533392 2.249932)
			(end 4.533392 -2.249932)
			(stroke
				(width 0.1524)
				(type default)
			)
			(layer "B.SilkS")
		)
		(fp_line
			(start -4.533392 -2.249932)
			(end -4.533392 2.249932)
			(stroke
				(width 0.1524)
				(type default)
			)
			(layer "B.SilkS")
		)
		(fp_line
			(start 4.533392 -2.249932)
			(end -4.533392 -2.249932)
			(stroke
				(width 0.1524)
				(type default)
			)
			(layer "B.SilkS")
		)
		(fp_poly
			(pts
				(xy 4.533392 -2.326132) (xy 5.39242 -2.326132) (xy 5.39242 2.326132) (xy 4.533392 2.326132)
			)
			(stroke
				(width 0)
				(type default)
			)
			(fill yes)
			(layer "B.SilkS")
		)
		(fp_line
			(start -3.750056 2.249932)
			(end 3.750056 2.249932)
			(stroke
				(width 0.1)
				(type default)
			)
			(layer "B.Fab")
		)
		(fp_line
			(start 3.750056 2.249932)
			(end 3.750056 -2.249932)
			(stroke
				(width 0.1)
				(type default)
			)
			(layer "B.Fab")
		)
		(fp_line
			(start -3.750056 -2.249932)
			(end -3.750056 2.249932)
			(stroke
				(width 0.1)
				(type default)
			)
			(layer "B.Fab")
		)
		(fp_line
			(start 3.750056 -2.249932)
			(end -3.750056 -2.249932)
			(stroke
				(width 0.1)
				(type default)
			)
			(layer "B.Fab")
		)
		(fp_text user "+"
			(at 6.322314 0.786384 180)
			(unlocked yes)
			(layer "B.SilkS")
			(effects
				(font
					(size 1.905 1.4224)
					(thickness 0.1524)
				)
				(justify left mirror)
			)
		)
		(fp_text user "-"
			(at -4.8514 -0.14605 270)
			(unlocked yes)
			(layer "B.SilkS")
			(effects
				(font
					(size 1.905 1.4224)
					(thickness 0.1524)
				)
				(justify left mirror)
			)
		)
		(fp_text user "+"
			(at 6.322314 0.786384 180)
			(unlocked yes)
			(layer "B.Fab")
			(effects
				(font
					(size 1.905 1.4224)
					(thickness 0.1524)
				)
				(justify left mirror)
			)
		)
		(fp_text user "-"
			(at -4.8514 -0.14605 270)
			(unlocked yes)
			(layer "B.Fab")
			(effects
				(font
					(size 1.905 1.4224)
					(thickness 0.1524)
				)
				(justify left mirror)
			)
		)
		(pad "1" smd rect
			(at 3.199892 0 90)
			(size 2.413 2.8194)
			(layers "B.Cu" "B.Mask" "B.Paste")
			(net "PVCCFA_EHV_FIVRA_CPU1")
		)
		(pad "2" smd rect
			(at -3.199892 0 90)
			(size 2.413 2.8194)
			(layers "B.Cu" "B.Mask" "B.Paste")
			(net "GND")
		)
	)
	(footprint ""
		(layer "B.Cu")
		(at 190.25108 -18.938748 180)
		(property "Reference" "R1801"
			(at 0 0 0)
			(layer "B.SilkS")
			(hide yes)
			(effects
				(font
					(size 1.27 1.27)
				)
				(justify mirror)
			)
		)
		(property "Value" ""
			(at 0 0 0)
			(layer "B.Fab")
			(effects
				(font
					(size 1.27 1.27)
				)
				(justify mirror)
			)
		)
		(duplicate_pad_numbers_are_jumpers no)
		(fp_line
			(start 0.7874 0.4064)
			(end 0.7874 -0.4064)
			(stroke
				(width 0.1524)
				(type default)
			)
			(layer "B.SilkS")
		)
		(fp_line
			(start 0.7874 -0.4064)
			(end -0.7874 -0.4064)
			(stroke
				(width 0.1524)
				(type default)
			)
			(layer "B.SilkS")
		)
		(fp_line
			(start -0.7874 0.4064)
			(end 0.7874 0.4064)
			(stroke
				(width 0.1524)
				(type default)
			)
			(layer "B.SilkS")
		)
		(fp_line
			(start -0.7874 -0.4064)
			(end -0.7874 0.4064)
			(stroke
				(width 0.1524)
				(type default)
			)
			(layer "B.SilkS")
		)
		(fp_line
			(start 0.67945 0.3048)
			(end 0.67945 -0.305054)
			(stroke
				(width 0.1)
				(type default)
			)
			(layer "B.Fab")
		)
		(fp_line
			(start 0.67945 -0.305054)
			(end 0.12065 -0.305054)
			(stroke
				(width 0.1)
				(type default)
			)
			(layer "B.Fab")
		)
		(fp_line
			(start 0.12065 0.3048)
			(end 0.67945 0.3048)
			(stroke
				(width 0.1)
				(type default)
			)
			(layer "B.Fab")
		)
		(fp_line
			(start 0.12065 0.2794)
			(end 0.12065 0.3048)
			(stroke
				(width 0.1)
				(type default)
			)
			(layer "B.Fab")
		)
		(fp_line
			(start 0.12065 -0.2794)
			(end -0.12065 -0.2794)
			(stroke
				(width 0.1)
				(type default)
			)
			(layer "B.Fab")
		)
		(fp_line
			(start 0.12065 -0.305054)
			(end 0.12065 -0.2794)
			(stroke
				(width 0.1)
				(type default)
			)
			(layer "B.Fab")
		)
		(fp_line
			(start -0.120396 0.3048)
			(end -0.120396 0.2794)
			(stroke
				(width 0.1)
				(type default)
			)
			(layer "B.Fab")
		)
		(fp_line
			(start -0.120396 0.2794)
			(end 0.12065 0.2794)
			(stroke
				(width 0.1)
				(type default)
			)
			(layer "B.Fab")
		)
		(fp_line
			(start -0.12065 -0.2794)
			(end -0.12065 -0.3048)
			(stroke
				(width 0.1)
				(type default)
			)
			(layer "B.Fab")
		)
		(fp_line
			(start -0.12065 -0.3048)
			(end -0.67945 -0.3048)
			(stroke
				(width 0.1)
				(type default)
			)
			(layer "B.Fab")
		)
		(fp_line
			(start -0.67945 0.3048)
			(end -0.120396 0.3048)
			(stroke
				(width 0.1)
				(type default)
			)
			(layer "B.Fab")
		)
		(fp_line
			(start -0.67945 -0.3048)
			(end -0.67945 0.3048)
			(stroke
				(width 0.1)
				(type default)
			)
			(layer "B.Fab")
		)
		(pad "1" smd circle
			(at 0.40005 0)
			(size 0 0)
			(layers "B.Cu" "B.Mask" "B.Paste")
			(net "PRSNT0_N")
		)
		(pad "2" smd circle
			(at -0.40005 0)
			(size 0 0)
			(layers "B.Cu" "B.Mask" "B.Paste")
			(net "GND")
		)
	)
	(footprint ""
		(layer "B.Cu")
		(at 275.157184 -193.669666 -90)
		(property "Reference" "R250"
			(at 0 0 90)
			(layer "B.SilkS")
			(hide yes)
			(effects
				(font
					(size 1.27 1.27)
				)
				(justify mirror)
			)
		)
		(property "Value" ""
			(at 0 0 90)
			(layer "B.Fab")
			(effects
				(font
					(size 1.27 1.27)
				)
				(justify mirror)
			)
		)
		(duplicate_pad_numbers_are_jumpers no)
		(fp_line
			(start -0.7874 0.4064)
			(end 0.7874 0.4064)
			(stroke
				(width 0.1524)
				(type default)
			)
			(layer "B.SilkS")
		)
		(fp_line
			(start 0.7874 0.4064)
			(end 0.7874 -0.4064)
			(stroke
				(width 0.1524)
				(type default)
			)
			(layer "B.SilkS")
		)
		(fp_line
			(start -0.7874 -0.4064)
			(end -0.7874 0.4064)
			(stroke
				(width 0.1524)
				(type default)
			)
			(layer "B.SilkS")
		)
		(fp_line
			(start 0.7874 -0.4064)
			(end -0.7874 -0.4064)
			(stroke
				(width 0.1524)
				(type default)
			)
			(layer "B.SilkS")
		)
		(fp_line
			(start -0.67945 0.3048)
			(end -0.120396 0.3048)
			(stroke
				(width 0.1)
				(type default)
			)
			(layer "B.Fab")
		)
		(fp_line
			(start -0.120396 0.3048)
			(end -0.120396 0.2794)
			(stroke
				(width 0.1)
				(type default)
			)
			(layer "B.Fab")
		)
		(fp_line
			(start 0.12065 0.3048)
			(end 0.67945 0.3048)
			(stroke
				(width 0.1)
				(type default)
			)
			(layer "B.Fab")
		)
		(fp_line
			(start 0.67945 0.3048)
			(end 0.67945 -0.305054)
			(stroke
				(width 0.1)
				(type default)
			)
			(layer "B.Fab")
		)
		(fp_line
			(start -0.120396 0.2794)
			(end 0.12065 0.2794)
			(stroke
				(width 0.1)
				(type default)
			)
			(layer "B.Fab")
		)
		(fp_line
			(start 0.12065 0.2794)
			(end 0.12065 0.3048)
			(stroke
				(width 0.1)
				(type default)
			)
			(layer "B.Fab")
		)
		(fp_line
			(start -0.12065 -0.2794)
			(end -0.12065 -0.3048)
			(stroke
				(width 0.1)
				(type default)
			)
			(layer "B.Fab")
		)
		(fp_line
			(start 0.12065 -0.2794)
			(end -0.12065 -0.2794)
			(stroke
				(width 0.1)
				(type default)
			)
			(layer "B.Fab")
		)
		(fp_line
			(start -0.67945 -0.3048)
			(end -0.67945 0.3048)
			(stroke
				(width 0.1)
				(type default)
			)
			(layer "B.Fab")
		)
		(fp_line
			(start -0.12065 -0.3048)
			(end -0.67945 -0.3048)
			(stroke
				(width 0.1)
				(type default)
			)
			(layer "B.Fab")
		)
		(fp_line
			(start 0.12065 -0.305054)
			(end 0.12065 -0.2794)
			(stroke
				(width 0.1)
				(type default)
			)
			(layer "B.Fab")
		)
		(fp_line
			(start 0.67945 -0.305054)
			(end 0.12065 -0.305054)
			(stroke
				(width 0.1)
				(type default)
			)
			(layer "B.Fab")
		)
		(pad "1" smd circle
			(at 0.40005 0 90)
			(size 0 0)
			(layers "B.Cu" "B.Mask" "B.Paste")
			(net "PVNN_TERM_CPU0")
		)
		(pad "2" smd circle
			(at -0.40005 0 90)
			(size 0 0)
			(layers "B.Cu" "B.Mask" "B.Paste")
			(net "FM_S3M_CPU0_LVC1_GPIO_1")
		)
	)
	(footprint ""
		(layer "B.Cu")
		(at 324.35292 -331.626718 90)
		(property "Reference" "PR531"
			(at 0 0 90)
			(layer "B.SilkS")
			(hide yes)
			(effects
				(font
					(size 1.27 1.27)
				)
				(justify mirror)
			)
		)
		(property "Value" ""
			(at 0 0 90)
			(layer "B.Fab")
			(effects
				(font
					(size 1.27 1.27)
				)
				(justify mirror)
			)
		)
		(duplicate_pad_numbers_are_jumpers no)
		(fp_line
			(start 0.7874 -0.4064)
			(end -0.7874 -0.4064)
			(stroke
				(width 0.1524)
				(type default)
			)
			(layer "B.SilkS")
		)
		(fp_line
			(start -0.7874 -0.4064)
			(end -0.7874 0.4064)
			(stroke
				(width 0.1524)
				(type default)
			)
			(layer "B.SilkS")
		)
		(fp_line
			(start 0.7874 0.4064)
			(end 0.7874 -0.4064)
			(stroke
				(width 0.1524)
				(type default)
			)
			(layer "B.SilkS")
		)
		(fp_line
			(start -0.7874 0.4064)
			(end 0.7874 0.4064)
			(stroke
				(width 0.1524)
				(type default)
			)
			(layer "B.SilkS")
		)
		(fp_line
			(start 0.67945 -0.305054)
			(end 0.12065 -0.305054)
			(stroke
				(width 0.1)
				(type default)
			)
			(layer "B.Fab")
		)
		(fp_line
			(start 0.12065 -0.305054)
			(end 0.12065 -0.2794)
			(stroke
				(width 0.1)
				(type default)
			)
			(layer "B.Fab")
		)
		(fp_line
			(start -0.12065 -0.3048)
			(end -0.67945 -0.3048)
			(stroke
				(width 0.1)
				(type default)
			)
			(layer "B.Fab")
		)
		(fp_line
			(start -0.67945 -0.3048)
			(end -0.67945 0.3048)
			(stroke
				(width 0.1)
				(type default)
			)
			(layer "B.Fab")
		)
		(fp_line
			(start 0.12065 -0.2794)
			(end -0.12065 -0.2794)
			(stroke
				(width 0.1)
				(type default)
			)
			(layer "B.Fab")
		)
		(fp_line
			(start -0.12065 -0.2794)
			(end -0.12065 -0.3048)
			(stroke
				(width 0.1)
				(type default)
			)
			(layer "B.Fab")
		)
		(fp_line
			(start 0.12065 0.2794)
			(end 0.12065 0.3048)
			(stroke
				(width 0.1)
				(type default)
			)
			(layer "B.Fab")
		)
		(fp_line
			(start -0.120396 0.2794)
			(end 0.12065 0.2794)
			(stroke
				(width 0.1)
				(type default)
			)
			(layer "B.Fab")
		)
		(fp_line
			(start 0.67945 0.3048)
			(end 0.67945 -0.305054)
			(stroke
				(width 0.1)
				(type default)
			)
			(layer "B.Fab")
		)
		(fp_line
			(start 0.12065 0.3048)
			(end 0.67945 0.3048)
			(stroke
				(width 0.1)
				(type default)
			)
			(layer "B.Fab")
		)
		(fp_line
			(start -0.120396 0.3048)
			(end -0.120396 0.2794)
			(stroke
				(width 0.1)
				(type default)
			)
			(layer "B.Fab")
		)
		(fp_line
			(start -0.67945 0.3048)
			(end -0.120396 0.3048)
			(stroke
				(width 0.1)
				(type default)
			)
			(layer "B.Fab")
		)
		(pad "1" smd circle
			(at 0.40005 0 270)
			(size 0 0)
			(layers "B.Cu" "B.Mask" "B.Paste")
			(net "VSENSE_PVCCIN_CPU0_DP")
		)
		(pad "2" smd circle
			(at -0.40005 0 270)
			(size 0 0)
			(layers "B.Cu" "B.Mask" "B.Paste")
			(net "PVCCIN_CPU0")
		)
	)
	(footprint ""
		(layer "B.Cu")
		(at 291.004498 -403.031452 90)
		(property "Reference" "PR2511"
			(at 0 0 90)
			(layer "B.SilkS")
			(hide yes)
			(effects
				(font
					(size 1.27 1.27)
				)
				(justify mirror)
			)
		)
		(property "Value" ""
			(at 0 0 90)
			(layer "B.Fab")
			(effects
				(font
					(size 1.27 1.27)
				)
				(justify mirror)
			)
		)
		(duplicate_pad_numbers_are_jumpers no)
		(fp_line
			(start 0.7874 -0.4064)
			(end -0.7874 -0.4064)
			(stroke
				(width 0.1524)
				(type default)
			)
			(layer "B.SilkS")
		)
		(fp_line
			(start -0.7874 -0.4064)
			(end -0.7874 0.4064)
			(stroke
				(width 0.1524)
				(type default)
			)
			(layer "B.SilkS")
		)
		(fp_line
			(start 0.7874 0.4064)
			(end 0.7874 -0.4064)
			(stroke
				(width 0.1524)
				(type default)
			)
			(layer "B.SilkS")
		)
		(fp_line
			(start -0.7874 0.4064)
			(end 0.7874 0.4064)
			(stroke
				(width 0.1524)
				(type default)
			)
			(layer "B.SilkS")
		)
		(fp_line
			(start 0.67945 -0.305054)
			(end 0.12065 -0.305054)
			(stroke
				(width 0.1)
				(type default)
			)
			(layer "B.Fab")
		)
		(fp_line
			(start 0.12065 -0.305054)
			(end 0.12065 -0.2794)
			(stroke
				(width 0.1)
				(type default)
			)
			(layer "B.Fab")
		)
		(fp_line
			(start -0.12065 -0.3048)
			(end -0.67945 -0.3048)
			(stroke
				(width 0.1)
				(type default)
			)
			(layer "B.Fab")
		)
		(fp_line
			(start -0.67945 -0.3048)
			(end -0.67945 0.3048)
			(stroke
				(width 0.1)
				(type default)
			)
			(layer "B.Fab")
		)
		(fp_line
			(start 0.12065 -0.2794)
			(end -0.12065 -0.2794)
			(stroke
				(width 0.1)
				(type default)
			)
			(layer "B.Fab")
		)
		(fp_line
			(start -0.12065 -0.2794)
			(end -0.12065 -0.3048)
			(stroke
				(width 0.1)
				(type default)
			)
			(layer "B.Fab")
		)
		(fp_line
			(start 0.12065 0.2794)
			(end 0.12065 0.3048)
			(stroke
				(width 0.1)
				(type default)
			)
			(layer "B.Fab")
		)
		(fp_line
			(start -0.120396 0.2794)
			(end 0.12065 0.2794)
			(stroke
				(width 0.1)
				(type default)
			)
			(layer "B.Fab")
		)
		(fp_line
			(start 0.67945 0.3048)
			(end 0.67945 -0.305054)
			(stroke
				(width 0.1)
				(type default)
			)
			(layer "B.Fab")
		)
		(fp_line
			(start 0.12065 0.3048)
			(end 0.67945 0.3048)
			(stroke
				(width 0.1)
				(type default)
			)
			(layer "B.Fab")
		)
		(fp_line
			(start -0.120396 0.3048)
			(end -0.120396 0.2794)
			(stroke
				(width 0.1)
				(type default)
			)
			(layer "B.Fab")
		)
		(fp_line
			(start -0.67945 0.3048)
			(end -0.120396 0.3048)
			(stroke
				(width 0.1)
				(type default)
			)
			(layer "B.Fab")
		)
		(pad "1" smd circle
			(at 0.40005 0 270)
			(size 0 0)
			(layers "B.Cu" "B.Mask" "B.Paste")
			(net "P12V_HSC_ADC_P")
		)
		(pad "2" smd circle
			(at -0.40005 0 270)
			(size 0 0)
			(layers "B.Cu" "B.Mask" "B.Paste")
			(net "P12V_HSC_SENSE2_R2_P")
		)
	)
	(footprint ""
		(layer "B.Cu")
		(at 452.028814 -319.263776 180)
		(property "Reference" "C47"
			(at 0 0 0)
			(layer "B.SilkS")
			(hide yes)
			(effects
				(font
					(size 1.27 1.27)
				)
				(justify mirror)
			)
		)
		(property "Value" ""
			(at 0 0 0)
			(layer "B.Fab")
			(effects
				(font
					(size 1.27 1.27)
				)
				(justify mirror)
			)
		)
		(duplicate_pad_numbers_are_jumpers no)
		(fp_line
			(start 0.7874 0.4064)
			(end 0.7874 -0.4064)
			(stroke
				(width 0.1524)
				(type default)
			)
			(layer "B.SilkS")
		)
		(fp_line
			(start 0.7874 -0.4064)
			(end -0.7874 -0.4064)
			(stroke
				(width 0.1524)
				(type default)
			)
			(layer "B.SilkS")
		)
		(fp_line
			(start -0.7874 0.4064)
			(end 0.7874 0.4064)
			(stroke
				(width 0.1524)
				(type default)
			)
			(layer "B.SilkS")
		)
		(fp_line
			(start -0.7874 -0.4064)
			(end -0.7874 0.4064)
			(stroke
				(width 0.1524)
				(type default)
			)
			(layer "B.SilkS")
		)
		(fp_line
			(start 0.67945 0.3048)
			(end 0.67945 -0.305054)
			(stroke
				(width 0.1)
				(type default)
			)
			(layer "B.Fab")
		)
		(fp_line
			(start 0.67945 -0.305054)
			(end 0.12065 -0.305054)
			(stroke
				(width 0.1)
				(type default)
			)
			(layer "B.Fab")
		)
		(fp_line
			(start 0.12065 0.3048)
			(end 0.67945 0.3048)
			(stroke
				(width 0.1)
				(type default)
			)
			(layer "B.Fab")
		)
		(fp_line
			(start 0.12065 0.2794)
			(end 0.12065 0.3048)
			(stroke
				(width 0.1)
				(type default)
			)
			(layer "B.Fab")
		)
		(fp_line
			(start 0.12065 -0.2794)
			(end -0.12065 -0.2794)
			(stroke
				(width 0.1)
				(type default)
			)
			(layer "B.Fab")
		)
		(fp_line
			(start 0.12065 -0.305054)
			(end 0.12065 -0.2794)
			(stroke
				(width 0.1)
				(type default)
			)
			(layer "B.Fab")
		)
		(fp_line
			(start -0.120396 0.3048)
			(end -0.120396 0.2794)
			(stroke
				(width 0.1)
				(type default)
			)
			(layer "B.Fab")
		)
		(fp_line
			(start -0.120396 0.2794)
			(end 0.12065 0.2794)
			(stroke
				(width 0.1)
				(type default)
			)
			(layer "B.Fab")
		)
		(fp_line
			(start -0.12065 -0.2794)
			(end -0.12065 -0.3048)
			(stroke
				(width 0.1)
				(type default)
			)
			(layer "B.Fab")
		)
		(fp_line
			(start -0.12065 -0.3048)
			(end -0.67945 -0.3048)
			(stroke
				(width 0.1)
				(type default)
			)
			(layer "B.Fab")
		)
		(fp_line
			(start -0.67945 0.3048)
			(end -0.120396 0.3048)
			(stroke
				(width 0.1)
				(type default)
			)
			(layer "B.Fab")
		)
		(fp_line
			(start -0.67945 -0.3048)
			(end -0.67945 0.3048)
			(stroke
				(width 0.1)
				(type default)
			)
			(layer "B.Fab")
		)
		(pad "1" smd circle
			(at 0.40005 0)
			(size 0 0)
			(layers "B.Cu" "B.Mask" "B.Paste")
			(net "P3V3_AUX")
		)
		(pad "2" smd circle
			(at -0.40005 0)
			(size 0 0)
			(layers "B.Cu" "B.Mask" "B.Paste")
			(net "GND")
		)
	)
	(footprint ""
		(layer "B.Cu")
		(at 339.58022 -31.929578 90)
		(property "Reference" "R1311"
			(at 0 0 90)
			(layer "B.SilkS")
			(hide yes)
			(effects
				(font
					(size 1.27 1.27)
				)
				(justify mirror)
			)
		)
		(property "Value" ""
			(at 0 0 90)
			(layer "B.Fab")
			(effects
				(font
					(size 1.27 1.27)
				)
				(justify mirror)
			)
		)
		(duplicate_pad_numbers_are_jumpers no)
		(fp_line
			(start 0.7874 -0.4064)
			(end -0.7874 -0.4064)
			(stroke
				(width 0.1524)
				(type default)
			)
			(layer "B.SilkS")
		)
		(fp_line
			(start -0.7874 -0.4064)
			(end -0.7874 0.4064)
			(stroke
				(width 0.1524)
				(type default)
			)
			(layer "B.SilkS")
		)
		(fp_line
			(start 0.7874 0.4064)
			(end 0.7874 -0.4064)
			(stroke
				(width 0.1524)
				(type default)
			)
			(layer "B.SilkS")
		)
		(fp_line
			(start -0.7874 0.4064)
			(end 0.7874 0.4064)
			(stroke
				(width 0.1524)
				(type default)
			)
			(layer "B.SilkS")
		)
		(fp_line
			(start 0.67945 -0.305054)
			(end 0.12065 -0.305054)
			(stroke
				(width 0.1)
				(type default)
			)
			(layer "B.Fab")
		)
		(fp_line
			(start 0.12065 -0.305054)
			(end 0.12065 -0.2794)
			(stroke
				(width 0.1)
				(type default)
			)
			(layer "B.Fab")
		)
		(fp_line
			(start -0.12065 -0.3048)
			(end -0.67945 -0.3048)
			(stroke
				(width 0.1)
				(type default)
			)
			(layer "B.Fab")
		)
		(fp_line
			(start -0.67945 -0.3048)
			(end -0.67945 0.3048)
			(stroke
				(width 0.1)
				(type default)
			)
			(layer "B.Fab")
		)
		(fp_line
			(start 0.12065 -0.2794)
			(end -0.12065 -0.2794)
			(stroke
				(width 0.1)
				(type default)
			)
			(layer "B.Fab")
		)
		(fp_line
			(start -0.12065 -0.2794)
			(end -0.12065 -0.3048)
			(stroke
				(width 0.1)
				(type default)
			)
			(layer "B.Fab")
		)
		(fp_line
			(start 0.12065 0.2794)
			(end 0.12065 0.3048)
			(stroke
				(width 0.1)
				(type default)
			)
			(layer "B.Fab")
		)
		(fp_line
			(start -0.120396 0.2794)
			(end 0.12065 0.2794)
			(stroke
				(width 0.1)
				(type default)
			)
			(layer "B.Fab")
		)
		(fp_line
			(start 0.67945 0.3048)
			(end 0.67945 -0.305054)
			(stroke
				(width 0.1)
				(type default)
			)
			(layer "B.Fab")
		)
		(fp_line
			(start 0.12065 0.3048)
			(end 0.67945 0.3048)
			(stroke
				(width 0.1)
				(type default)
			)
			(layer "B.Fab")
		)
		(fp_line
			(start -0.120396 0.3048)
			(end -0.120396 0.2794)
			(stroke
				(width 0.1)
				(type default)
			)
			(layer "B.Fab")
		)
		(fp_line
			(start -0.67945 0.3048)
			(end -0.120396 0.3048)
			(stroke
				(width 0.1)
				(type default)
			)
			(layer "B.Fab")
		)
		(pad "1" smd circle
			(at 0.40005 0 270)
			(size 0 0)
			(layers "B.Cu" "B.Mask" "B.Paste")
			(net "FM_XTAL_INPUT_FREQUENCY_0_MGPIO")
		)
		(pad "2" smd circle
			(at -0.40005 0 270)
			(size 0 0)
			(layers "B.Cu" "B.Mask" "B.Paste")
			(net "GND")
		)
	)
	(footprint ""
		(layer "B.Cu")
		(at 127.7874 -21.003768 90)
		(property "Reference" "R4288"
			(at 0 0 90)
			(layer "B.SilkS")
			(hide yes)
			(effects
				(font
					(size 1.27 1.27)
				)
				(justify mirror)
			)
		)
		(property "Value" ""
			(at 0 0 90)
			(layer "B.Fab")
			(effects
				(font
					(size 1.27 1.27)
				)
				(justify mirror)
			)
		)
		(duplicate_pad_numbers_are_jumpers no)
		(fp_line
			(start 0.7874 -0.4064)
			(end -0.7874 -0.4064)
			(stroke
				(width 0.1524)
				(type default)
			)
			(layer "B.SilkS")
		)
		(fp_line
			(start -0.7874 -0.4064)
			(end -0.7874 0.4064)
			(stroke
				(width 0.1524)
				(type default)
			)
			(layer "B.SilkS")
		)
		(fp_line
			(start 0.7874 0.4064)
			(end 0.7874 -0.4064)
			(stroke
				(width 0.1524)
				(type default)
			)
			(layer "B.SilkS")
		)
		(fp_line
			(start -0.7874 0.4064)
			(end 0.7874 0.4064)
			(stroke
				(width 0.1524)
				(type default)
			)
			(layer "B.SilkS")
		)
		(fp_line
			(start 0.67945 -0.305054)
			(end 0.12065 -0.305054)
			(stroke
				(width 0.1)
				(type default)
			)
			(layer "B.Fab")
		)
		(fp_line
			(start 0.12065 -0.305054)
			(end 0.12065 -0.2794)
			(stroke
				(width 0.1)
				(type default)
			)
			(layer "B.Fab")
		)
		(fp_line
			(start -0.12065 -0.3048)
			(end -0.67945 -0.3048)
			(stroke
				(width 0.1)
				(type default)
			)
			(layer "B.Fab")
		)
		(fp_line
			(start -0.67945 -0.3048)
			(end -0.67945 0.3048)
			(stroke
				(width 0.1)
				(type default)
			)
			(layer "B.Fab")
		)
		(fp_line
			(start 0.12065 -0.2794)
			(end -0.12065 -0.2794)
			(stroke
				(width 0.1)
				(type default)
			)
			(layer "B.Fab")
		)
		(fp_line
			(start -0.12065 -0.2794)
			(end -0.12065 -0.3048)
			(stroke
				(width 0.1)
				(type default)
			)
			(layer "B.Fab")
		)
		(fp_line
			(start 0.12065 0.2794)
			(end 0.12065 0.3048)
			(stroke
				(width 0.1)
				(type default)
			)
			(layer "B.Fab")
		)
		(fp_line
			(start -0.120396 0.2794)
			(end 0.12065 0.2794)
			(stroke
				(width 0.1)
				(type default)
			)
			(layer "B.Fab")
		)
		(fp_line
			(start 0.67945 0.3048)
			(end 0.67945 -0.305054)
			(stroke
				(width 0.1)
				(type default)
			)
			(layer "B.Fab")
		)
		(fp_line
			(start 0.12065 0.3048)
			(end 0.67945 0.3048)
			(stroke
				(width 0.1)
				(type default)
			)
			(layer "B.Fab")
		)
		(fp_line
			(start -0.120396 0.3048)
			(end -0.120396 0.2794)
			(stroke
				(width 0.1)
				(type default)
			)
			(layer "B.Fab")
		)
		(fp_line
			(start -0.67945 0.3048)
			(end -0.120396 0.3048)
			(stroke
				(width 0.1)
				(type default)
			)
			(layer "B.Fab")
		)
		(pad "1" smd circle
			(at 0.40005 0 270)
			(size 0 0)
			(layers "B.Cu" "B.Mask" "B.Paste")
			(net "FM_USB3_1_SWA")
		)
		(pad "2" smd circle
			(at -0.40005 0 270)
			(size 0 0)
			(layers "B.Cu" "B.Mask" "B.Paste")
			(net "GND")
		)
	)
	(footprint ""
		(layer "B.Cu")
		(at 324.98919 -28.45435 90)
		(property "Reference" "R614"
			(at 0 0 90)
			(layer "B.SilkS")
			(hide yes)
			(effects
				(font
					(size 1.27 1.27)
				)
				(justify mirror)
			)
		)
		(property "Value" ""
			(at 0 0 90)
			(layer "B.Fab")
			(effects
				(font
					(size 1.27 1.27)
				)
				(justify mirror)
			)
		)
		(duplicate_pad_numbers_are_jumpers no)
		(fp_line
			(start 0.7874 -0.4064)
			(end -0.7874 -0.4064)
			(stroke
				(width 0.1524)
				(type default)
			)
			(layer "B.SilkS")
		)
		(fp_line
			(start -0.7874 -0.4064)
			(end -0.7874 0.4064)
			(stroke
				(width 0.1524)
				(type default)
			)
			(layer "B.SilkS")
		)
		(fp_line
			(start 0.7874 0.4064)
			(end 0.7874 -0.4064)
			(stroke
				(width 0.1524)
				(type default)
			)
			(layer "B.SilkS")
		)
		(fp_line
			(start -0.7874 0.4064)
			(end 0.7874 0.4064)
			(stroke
				(width 0.1524)
				(type default)
			)
			(layer "B.SilkS")
		)
		(fp_line
			(start 0.67945 -0.305054)
			(end 0.12065 -0.305054)
			(stroke
				(width 0.1)
				(type default)
			)
			(layer "B.Fab")
		)
		(fp_line
			(start 0.12065 -0.305054)
			(end 0.12065 -0.2794)
			(stroke
				(width 0.1)
				(type default)
			)
			(layer "B.Fab")
		)
		(fp_line
			(start -0.12065 -0.3048)
			(end -0.67945 -0.3048)
			(stroke
				(width 0.1)
				(type default)
			)
			(layer "B.Fab")
		)
		(fp_line
			(start -0.67945 -0.3048)
			(end -0.67945 0.3048)
			(stroke
				(width 0.1)
				(type default)
			)
			(layer "B.Fab")
		)
		(fp_line
			(start 0.12065 -0.2794)
			(end -0.12065 -0.2794)
			(stroke
				(width 0.1)
				(type default)
			)
			(layer "B.Fab")
		)
		(fp_line
			(start -0.12065 -0.2794)
			(end -0.12065 -0.3048)
			(stroke
				(width 0.1)
				(type default)
			)
			(layer "B.Fab")
		)
		(fp_line
			(start 0.12065 0.2794)
			(end 0.12065 0.3048)
			(stroke
				(width 0.1)
				(type default)
			)
			(layer "B.Fab")
		)
		(fp_line
			(start -0.120396 0.2794)
			(end 0.12065 0.2794)
			(stroke
				(width 0.1)
				(type default)
			)
			(layer "B.Fab")
		)
		(fp_line
			(start 0.67945 0.3048)
			(end 0.67945 -0.305054)
			(stroke
				(width 0.1)
				(type default)
			)
			(layer "B.Fab")
		)
		(fp_line
			(start 0.12065 0.3048)
			(end 0.67945 0.3048)
			(stroke
				(width 0.1)
				(type default)
			)
			(layer "B.Fab")
		)
		(fp_line
			(start -0.120396 0.3048)
			(end -0.120396 0.2794)
			(stroke
				(width 0.1)
				(type default)
			)
			(layer "B.Fab")
		)
		(fp_line
			(start -0.67945 0.3048)
			(end -0.120396 0.3048)
			(stroke
				(width 0.1)
				(type default)
			)
			(layer "B.Fab")
		)
		(pad "1" smd circle
			(at 0.40005 0 270)
			(size 0 0)
			(layers "B.Cu" "B.Mask" "B.Paste")
			(net "FM_JTAG_ODT_DISABLE")
		)
		(pad "2" smd circle
			(at -0.40005 0 270)
			(size 0 0)
			(layers "B.Cu" "B.Mask" "B.Paste")
			(net "GND")
		)
	)
	(footprint ""
		(layer "B.Cu")
		(at 211.836 -70.852792 180)
		(property "Reference" "U68"
			(at -0.51562 -3.679698 0)
			(unlocked yes)
			(layer "B.SilkS")
			(effects
				(font
					(size 0.7874 0.5842)
					(thickness 0.1524)
				)
				(justify left mirror)
			)
		)
		(property "Value" ""
			(at 0 0 0)
			(layer "B.Fab")
			(effects
				(font
					(size 1.27 1.27)
				)
				(justify mirror)
			)
		)
		(duplicate_pad_numbers_are_jumpers no)
		(fp_line
			(start 2.0066 2.5527)
			(end 2.0066 -2.5527)
			(stroke
				(width 0.1524)
				(type default)
			)
			(layer "B.SilkS")
		)
		(fp_line
			(start 2.0066 -2.5527)
			(end 0.5715 -2.5527)
			(stroke
				(width 0.1524)
				(type default)
			)
			(layer "B.SilkS")
		)
		(fp_line
			(start 0.5715 -2.5527)
			(end 0 -1.9812)
			(stroke
				(width 0.1524)
				(type default)
			)
			(layer "B.SilkS")
		)
		(fp_line
			(start 0 -1.9812)
			(end -0.5715 -2.5527)
			(stroke
				(width 0.1524)
				(type default)
			)
			(layer "B.SilkS")
		)
		(fp_line
			(start -0.5715 -2.5527)
			(end -2.0066 -2.5527)
			(stroke
				(width 0.1524)
				(type default)
			)
			(layer "B.SilkS")
		)
		(fp_line
			(start -2.0066 2.5527)
			(end 2.0066 2.5527)
			(stroke
				(width 0.1524)
				(type default)
			)
			(layer "B.SilkS")
		)
		(fp_line
			(start -2.0066 -2.5527)
			(end -2.0066 2.5527)
			(stroke
				(width 0.1524)
				(type default)
			)
			(layer "B.SilkS")
		)
		(fp_poly
			(pts
				(xy 3.81 -1.905) (xy 4.36372 -2.233168) (xy 4.36372 -1.608328)
			)
			(stroke
				(width 0)
				(type default)
			)
			(fill yes)
			(layer "B.SilkS")
		)
		(fp_line
			(start 2.249932 2.549906)
			(end 2.249932 -2.549906)
			(stroke
				(width 0.1)
				(type default)
			)
			(layer "B.Fab")
		)
		(fp_line
			(start 2.249932 -2.549906)
			(end -2.249932 -2.549906)
			(stroke
				(width 0.1)
				(type default)
			)
			(layer "B.Fab")
		)
		(fp_line
			(start -2.249932 2.549906)
			(end 2.249932 2.549906)
			(stroke
				(width 0.1)
				(type default)
			)
			(layer "B.Fab")
		)
		(fp_line
			(start -2.249932 -2.549906)
			(end -2.249932 2.549906)
			(stroke
				(width 0.1)
				(type default)
			)
			(layer "B.Fab")
		)
		(fp_poly
			(pts
				(xy 4.36372 -1.608328) (xy 4.36372 -2.233168) (xy 3.81 -1.905)
			)
			(stroke
				(width 0)
				(type default)
			)
			(fill yes)
			(layer "B.Fab")
		)
		(pad "1" smd rect
			(at 2.921 -1.949958 90)
			(size 0.3556 1.4986)
			(layers "B.Cu" "B.Mask" "B.Paste")
			(net "FB_BMC_ISOLATE")
		)
		(pad "2" smd rect
			(at 2.921 -1.299972 90)
			(size 0.3556 1.4986)
			(layers "B.Cu" "B.Mask" "B.Paste")
			(net "NCSI_BMC_TXD1_R")
		)
		(pad "3" smd rect
			(at 2.921 -0.649986 90)
			(size 0.3556 1.4986)
			(layers "B.Cu" "B.Mask" "B.Paste")
			(net "NCSI_OCP_SFF_TXD1")
		)
		(pad "4" smd rect
			(at 2.921 0 90)
			(size 0.3556 1.4986)
			(layers "B.Cu" "B.Mask" "B.Paste")
			(net "FB_BMC_ISOLATE")
		)
		(pad "5" smd rect
			(at 2.921 0.649986 90)
			(size 0.3556 1.4986)
			(layers "B.Cu" "B.Mask" "B.Paste")
			(net "NCSI_BMC_TXD0_R")
		)
		(pad "6" smd rect
			(at 2.921 1.299972 90)
			(size 0.3556 1.4986)
			(layers "B.Cu" "B.Mask" "B.Paste")
			(net "NCSI_OCP_SFF_TXD0")
		)
		(pad "7" smd rect
			(at 2.921 1.949958 90)
			(size 0.3556 1.4986)
			(layers "B.Cu" "B.Mask" "B.Paste")
			(net "GND")
		)
		(pad "8" smd rect
			(at -2.921 1.949958 90)
			(size 0.3556 1.4986)
			(layers "B.Cu" "B.Mask" "B.Paste")
			(net "NCSI_OCP_SFF_TX_EN")
		)
		(pad "9" smd rect
			(at -2.921 1.299972 90)
			(size 0.3556 1.4986)
			(layers "B.Cu" "B.Mask" "B.Paste")
			(net "NCSI_BMC_TX_EN_R")
		)
		(pad "10" smd rect
			(at -2.921 0.649986 90)
			(size 0.3556 1.4986)
			(layers "B.Cu" "B.Mask" "B.Paste")
			(net "FB_BMC_ISOLATE")
		)
		(pad "11" smd rect
			(at -2.921 0 90)
			(size 0.3556 1.4986)
			(layers "B.Cu" "B.Mask" "B.Paste")
			(net "OCP_SFF_ISO2_RBT_ARB_OUT")
		)
		(pad "12" smd rect
			(at -2.921 -0.649986 90)
			(size 0.3556 1.4986)
			(layers "B.Cu" "B.Mask" "B.Paste")
			(net "OCP_SFF_RBT_ARB_OUT")
		)
		(pad "13" smd rect
			(at -2.921 -1.299972 90)
			(size 0.3556 1.4986)
			(layers "B.Cu" "B.Mask" "B.Paste")
			(net "FB_BMC_ISOLATE")
		)
		(pad "14" smd rect
			(at -2.921 -1.949958 90)
			(size 0.3556 1.4986)
			(layers "B.Cu" "B.Mask" "B.Paste")
			(net "P3V3_AUX")
		)
	)
	(footprint ""
		(layer "B.Cu")
		(at 159.766508 -41.805098 -90)
		(property "Reference" "C2313"
			(at 0 0 90)
			(layer "B.SilkS")
			(hide yes)
			(effects
				(font
					(size 1.27 1.27)
				)
				(justify mirror)
			)
		)
		(property "Value" ""
			(at 0 0 90)
			(layer "B.Fab")
			(effects
				(font
					(size 1.27 1.27)
				)
				(justify mirror)
			)
		)
		(duplicate_pad_numbers_are_jumpers no)
		(fp_line
			(start -0.7874 0.4064)
			(end 0.7874 0.4064)
			(stroke
				(width 0.1524)
				(type default)
			)
			(layer "B.SilkS")
		)
		(fp_line
			(start 0.7874 0.4064)
			(end 0.7874 -0.4064)
			(stroke
				(width 0.1524)
				(type default)
			)
			(layer "B.SilkS")
		)
		(fp_line
			(start -0.7874 -0.4064)
			(end -0.7874 0.4064)
			(stroke
				(width 0.1524)
				(type default)
			)
			(layer "B.SilkS")
		)
		(fp_line
			(start 0.7874 -0.4064)
			(end -0.7874 -0.4064)
			(stroke
				(width 0.1524)
				(type default)
			)
			(layer "B.SilkS")
		)
		(fp_line
			(start -0.67945 0.3048)
			(end -0.120396 0.3048)
			(stroke
				(width 0.1)
				(type default)
			)
			(layer "B.Fab")
		)
		(fp_line
			(start -0.120396 0.3048)
			(end -0.120396 0.2794)
			(stroke
				(width 0.1)
				(type default)
			)
			(layer "B.Fab")
		)
		(fp_line
			(start 0.12065 0.3048)
			(end 0.67945 0.3048)
			(stroke
				(width 0.1)
				(type default)
			)
			(layer "B.Fab")
		)
		(fp_line
			(start 0.67945 0.3048)
			(end 0.67945 -0.305054)
			(stroke
				(width 0.1)
				(type default)
			)
			(layer "B.Fab")
		)
		(fp_line
			(start -0.120396 0.2794)
			(end 0.12065 0.2794)
			(stroke
				(width 0.1)
				(type default)
			)
			(layer "B.Fab")
		)
		(fp_line
			(start 0.12065 0.2794)
			(end 0.12065 0.3048)
			(stroke
				(width 0.1)
				(type default)
			)
			(layer "B.Fab")
		)
		(fp_line
			(start -0.12065 -0.2794)
			(end -0.12065 -0.3048)
			(stroke
				(width 0.1)
				(type default)
			)
			(layer "B.Fab")
		)
		(fp_line
			(start 0.12065 -0.2794)
			(end -0.12065 -0.2794)
			(stroke
				(width 0.1)
				(type default)
			)
			(layer "B.Fab")
		)
		(fp_line
			(start -0.67945 -0.3048)
			(end -0.67945 0.3048)
			(stroke
				(width 0.1)
				(type default)
			)
			(layer "B.Fab")
		)
		(fp_line
			(start -0.12065 -0.3048)
			(end -0.67945 -0.3048)
			(stroke
				(width 0.1)
				(type default)
			)
			(layer "B.Fab")
		)
		(fp_line
			(start 0.12065 -0.305054)
			(end 0.12065 -0.2794)
			(stroke
				(width 0.1)
				(type default)
			)
			(layer "B.Fab")
		)
		(fp_line
			(start 0.67945 -0.305054)
			(end 0.12065 -0.305054)
			(stroke
				(width 0.1)
				(type default)
			)
			(layer "B.Fab")
		)
		(pad "1" smd circle
			(at 0.40005 0 90)
			(size 0 0)
			(layers "B.Cu" "B.Mask" "B.Paste")
			(net "P3V3_AUX_USB_HUB_2")
		)
		(pad "2" smd circle
			(at -0.40005 0 90)
			(size 0 0)
			(layers "B.Cu" "B.Mask" "B.Paste")
			(net "GND")
		)
	)
	(footprint ""
		(layer "B.Cu")
		(at 378.099574 8.003794)
		(property "Reference" "J116"
			(at 4.524756 1.521206 270)
			(unlocked yes)
			(layer "B.SilkS")
			(effects
				(font
					(size 0.7874 0.5842)
					(thickness 0.1524)
				)
				(justify left mirror)
			)
		)
		(property "Value" ""
			(at 0 0 0)
			(layer "B.Fab")
			(effects
				(font
					(size 1.27 1.27)
				)
				(justify mirror)
			)
		)
		(duplicate_pad_numbers_are_jumpers no)
		(fp_line
			(start -1.2192 -2.1082)
			(end -1.2192 2.1082)
			(stroke
				(width 0.1524)
				(type default)
			)
			(layer "B.SilkS")
		)
		(fp_line
			(start -1.2192 2.1082)
			(end 1.2192 2.1082)
			(stroke
				(width 0.1524)
				(type default)
			)
			(layer "B.SilkS")
		)
		(fp_line
			(start 1.2192 -2.1082)
			(end -1.2192 -2.1082)
			(stroke
				(width 0.1524)
				(type default)
			)
			(layer "B.SilkS")
		)
		(fp_line
			(start 1.2192 2.1082)
			(end 1.2192 -2.1082)
			(stroke
				(width 0.1524)
				(type default)
			)
			(layer "B.SilkS")
		)
		(pad "" np_thru_hole circle
			(at -3.4671 -1.27 270)
			(size 1.0414 1.0414)
			(drill 1.0414)
			(layers "*.Cu" "*.Mask")
			(clearance 0.381)
			(thermal_gap 0.381)
		)
		(pad "" np_thru_hole circle
			(at -3.4671 1.27 270)
			(size 1.0414 1.0414)
			(drill 1.0414)
			(layers "*.Cu" "*.Mask")
			(clearance 0.381)
			(thermal_gap 0.381)
		)
		(pad "" np_thru_hole circle
			(at 2.8829 -1.27 270)
			(size 1.0414 1.0414)
			(drill 1.0414)
			(layers "*.Cu" "*.Mask")
			(clearance 0.381)
			(thermal_gap 0.381)
		)
		(pad "" np_thru_hole circle
			(at 2.8829 1.27 270)
			(size 1.0414 1.0414)
			(drill 1.0414)
			(layers "*.Cu" "*.Mask")
			(clearance 0.381)
			(thermal_gap 0.381)
		)
		(pad "1" smd rect
			(at -0.8255 -0.249936 270)
			(size 0.3048 0.508)
			(layers "B.Cu" "B.Mask" "B.Paste")
			(net "DELTA_L_85_5INCH_IN5_DN")
		)
		(pad "2" smd rect
			(at -0.8255 0.249936 270)
			(size 0.3048 0.508)
			(layers "B.Cu" "B.Mask" "B.Paste")
			(net "DELTA_L_85_5INCH_IN5_DP")
		)
		(pad "3" smd circle
			(at 0 0 180)
			(size 0 0)
			(layers "B.Cu" "B.Mask" "B.Paste")
			(net "DELTA_L_GND_1")
		)
		(zone
			(layers "F.Cu" "B.Cu" "In1.Cu" "In2.Cu" "In3.Cu" "In4.Cu" "In5.Cu" "In6.Cu"
				"In7.Cu" "In8.Cu" "In9.Cu" "In10.Cu" "In11.Cu" "In12.Cu" "In13.Cu" "In14.Cu"
				"In15.Cu" "In16.Cu"
			)
			(hatch none 0.5)
			(connect_pads
				(clearance 0)
			)
			(min_thickness 0.25)
			(keepout
				(tracks not_allowed)
				(vias allowed)
				(pads allowed)
				(copperpour not_allowed)
				(footprints allowed)
			)
			(placement
				(enabled no)
				(sheetname "")
			)
			(fill
				(thermal_gap 0.5)
				(thermal_bridge_width 0.5)
				(island_removal_mode 0)
			)
			(polygon
				(pts
					(arc
						(start 375.559574 6.733794)
						(mid 373.705374 6.733794)
						(end 375.559574 6.733794)
					)
				)
			)
		)
		(zone
			(layers "F.Cu" "B.Cu" "In1.Cu" "In2.Cu" "In3.Cu" "In4.Cu" "In5.Cu" "In6.Cu"
				"In7.Cu" "In8.Cu" "In9.Cu" "In10.Cu" "In11.Cu" "In12.Cu" "In13.Cu" "In14.Cu"
				"In15.Cu" "In16.Cu"
			)
			(hatch none 0.5)
			(connect_pads
				(clearance 0)
			)
			(min_thickness 0.25)
			(keepout
				(tracks not_allowed)
				(vias allowed)
				(pads allowed)
				(copperpour not_allowed)
				(footprints allowed)
			)
			(placement
				(enabled no)
				(sheetname "")
			)
			(fill
				(thermal_gap 0.5)
				(thermal_bridge_width 0.5)
				(island_removal_mode 0)
			)
			(polygon
				(pts
					(arc
						(start 375.559574 9.273794)
						(mid 373.705374 9.273794)
						(end 375.559574 9.273794)
					)
				)
			)
		)
		(zone
			(layers "F.Cu" "B.Cu" "In1.Cu" "In2.Cu" "In3.Cu" "In4.Cu" "In5.Cu" "In6.Cu"
				"In7.Cu" "In8.Cu" "In9.Cu" "In10.Cu" "In11.Cu" "In12.Cu" "In13.Cu" "In14.Cu"
				"In15.Cu" "In16.Cu"
			)
			(hatch none 0.5)
			(connect_pads
				(clearance 0)
			)
			(min_thickness 0.25)
			(keepout
				(tracks not_allowed)
				(vias allowed)
				(pads allowed)
				(copperpour not_allowed)
				(footprints allowed)
			)
			(placement
				(enabled no)
				(sheetname "")
			)
			(fill
				(thermal_gap 0.5)
				(thermal_bridge_width 0.5)
				(island_removal_mode 0)
			)
			(polygon
				(pts
					(arc
						(start 381.909574 6.733794)
						(mid 380.055374 6.733794)
						(end 381.909574 6.733794)
					)
				)
			)
		)
		(zone
			(layers "F.Cu" "B.Cu" "In1.Cu" "In2.Cu" "In3.Cu" "In4.Cu" "In5.Cu" "In6.Cu"
				"In7.Cu" "In8.Cu" "In9.Cu" "In10.Cu" "In11.Cu" "In12.Cu" "In13.Cu" "In14.Cu"
				"In15.Cu" "In16.Cu"
			)
			(hatch none 0.5)
			(connect_pads
				(clearance 0)
			)
			(min_thickness 0.25)
			(keepout
				(tracks not_allowed)
				(vias allowed)
				(pads allowed)
				(copperpour not_allowed)
				(footprints allowed)
			)
			(placement
				(enabled no)
				(sheetname "")
			)
			(fill
				(thermal_gap 0.5)
				(thermal_bridge_width 0.5)
				(island_removal_mode 0)
			)
			(polygon
				(pts
					(arc
						(start 381.909574 9.273794)
						(mid 380.055374 9.273794)
						(end 381.909574 9.273794)
					)
				)
			)
		)
		(zone
			(layer "B.Cu")
			(hatch none 0.5)
			(connect_pads
				(clearance 0)
			)
			(min_thickness 0.25)
			(keepout
				(tracks not_allowed)
				(vias allowed)
				(pads allowed)
				(copperpour not_allowed)
				(footprints allowed)
			)
			(placement
				(enabled no)
				(sheetname "")
			)
			(fill
				(thermal_gap 0.5)
				(thermal_bridge_width 0.5)
				(island_removal_mode 0)
			)
			(polygon
				(pts
					(xy 376.981974 7.455154) (xy 376.981974 7.550658) (xy 377.578874 7.550658) (xy 377.578874 7.957058)
					(xy 376.981974 7.957058) (xy 376.981974 8.05053) (xy 377.578874 8.05053) (xy 377.578874 8.45693)
					(xy 376.981974 8.45693) (xy 376.981974 8.552434) (xy 377.680474 8.552434) (xy 377.680474 7.455154)
				)
			)
		)
	)
	(footprint ""
		(layer "B.Cu")
		(at 231.288336 -125.377194 180)
		(property "Reference" "R1543"
			(at 0 0 0)
			(layer "B.SilkS")
			(hide yes)
			(effects
				(font
					(size 1.27 1.27)
				)
				(justify mirror)
			)
		)
		(property "Value" ""
			(at 0 0 0)
			(layer "B.Fab")
			(effects
				(font
					(size 1.27 1.27)
				)
				(justify mirror)
			)
		)
		(duplicate_pad_numbers_are_jumpers no)
		(fp_line
			(start 0.7874 0.4064)
			(end 0.7874 -0.4064)
			(stroke
				(width 0.1524)
				(type default)
			)
			(layer "B.SilkS")
		)
		(fp_line
			(start 0.7874 -0.4064)
			(end -0.7874 -0.4064)
			(stroke
				(width 0.1524)
				(type default)
			)
			(layer "B.SilkS")
		)
		(fp_line
			(start -0.7874 0.4064)
			(end 0.7874 0.4064)
			(stroke
				(width 0.1524)
				(type default)
			)
			(layer "B.SilkS")
		)
		(fp_line
			(start -0.7874 -0.4064)
			(end -0.7874 0.4064)
			(stroke
				(width 0.1524)
				(type default)
			)
			(layer "B.SilkS")
		)
		(fp_line
			(start 0.67945 0.3048)
			(end 0.67945 -0.305054)
			(stroke
				(width 0.1)
				(type default)
			)
			(layer "B.Fab")
		)
		(fp_line
			(start 0.67945 -0.305054)
			(end 0.12065 -0.305054)
			(stroke
				(width 0.1)
				(type default)
			)
			(layer "B.Fab")
		)
		(fp_line
			(start 0.12065 0.3048)
			(end 0.67945 0.3048)
			(stroke
				(width 0.1)
				(type default)
			)
			(layer "B.Fab")
		)
		(fp_line
			(start 0.12065 0.2794)
			(end 0.12065 0.3048)
			(stroke
				(width 0.1)
				(type default)
			)
			(layer "B.Fab")
		)
		(fp_line
			(start 0.12065 -0.2794)
			(end -0.12065 -0.2794)
			(stroke
				(width 0.1)
				(type default)
			)
			(layer "B.Fab")
		)
		(fp_line
			(start 0.12065 -0.305054)
			(end 0.12065 -0.2794)
			(stroke
				(width 0.1)
				(type default)
			)
			(layer "B.Fab")
		)
		(fp_line
			(start -0.120396 0.3048)
			(end -0.120396 0.2794)
			(stroke
				(width 0.1)
				(type default)
			)
			(layer "B.Fab")
		)
		(fp_line
			(start -0.120396 0.2794)
			(end 0.12065 0.2794)
			(stroke
				(width 0.1)
				(type default)
			)
			(layer "B.Fab")
		)
		(fp_line
			(start -0.12065 -0.2794)
			(end -0.12065 -0.3048)
			(stroke
				(width 0.1)
				(type default)
			)
			(layer "B.Fab")
		)
		(fp_line
			(start -0.12065 -0.3048)
			(end -0.67945 -0.3048)
			(stroke
				(width 0.1)
				(type default)
			)
			(layer "B.Fab")
		)
		(fp_line
			(start -0.67945 0.3048)
			(end -0.120396 0.3048)
			(stroke
				(width 0.1)
				(type default)
			)
			(layer "B.Fab")
		)
		(fp_line
			(start -0.67945 -0.3048)
			(end -0.67945 0.3048)
			(stroke
				(width 0.1)
				(type default)
			)
			(layer "B.Fab")
		)
		(pad "1" smd circle
			(at 0.40005 0)
			(size 0 0)
			(layers "B.Cu" "B.Mask" "B.Paste")
			(net "OCP_SFF_CLK_OE_N")
		)
		(pad "2" smd circle
			(at -0.40005 0)
			(size 0 0)
			(layers "B.Cu" "B.Mask" "B.Paste")
			(net "FM_DB2000_9_OE_N")
		)
	)
	(footprint ""
		(layer "B.Cu")
		(at 111.621316 -360.847386)
		(property "Reference" "PR313"
			(at 0 0 0)
			(layer "B.SilkS")
			(hide yes)
			(effects
				(font
					(size 1.27 1.27)
				)
				(justify mirror)
			)
		)
		(property "Value" ""
			(at 0 0 0)
			(layer "B.Fab")
			(effects
				(font
					(size 1.27 1.27)
				)
				(justify mirror)
			)
		)
		(duplicate_pad_numbers_are_jumpers no)
		(fp_line
			(start -0.7874 -0.4064)
			(end -0.7874 0.4064)
			(stroke
				(width 0.1524)
				(type default)
			)
			(layer "B.SilkS")
		)
		(fp_line
			(start -0.7874 0.4064)
			(end 0.7874 0.4064)
			(stroke
				(width 0.1524)
				(type default)
			)
			(layer "B.SilkS")
		)
		(fp_line
			(start 0.7874 -0.4064)
			(end -0.7874 -0.4064)
			(stroke
				(width 0.1524)
				(type default)
			)
			(layer "B.SilkS")
		)
		(fp_line
			(start 0.7874 0.4064)
			(end 0.7874 -0.4064)
			(stroke
				(width 0.1524)
				(type default)
			)
			(layer "B.SilkS")
		)
		(fp_line
			(start -0.67945 -0.3048)
			(end -0.67945 0.3048)
			(stroke
				(width 0.1)
				(type default)
			)
			(layer "B.Fab")
		)
		(fp_line
			(start -0.67945 0.3048)
			(end -0.120396 0.3048)
			(stroke
				(width 0.1)
				(type default)
			)
			(layer "B.Fab")
		)
		(fp_line
			(start -0.12065 -0.3048)
			(end -0.67945 -0.3048)
			(stroke
				(width 0.1)
				(type default)
			)
			(layer "B.Fab")
		)
		(fp_line
			(start -0.12065 -0.2794)
			(end -0.12065 -0.3048)
			(stroke
				(width 0.1)
				(type default)
			)
			(layer "B.Fab")
		)
		(fp_line
			(start -0.120396 0.2794)
			(end 0.12065 0.2794)
			(stroke
				(width 0.1)
				(type default)
			)
			(layer "B.Fab")
		)
		(fp_line
			(start -0.120396 0.3048)
			(end -0.120396 0.2794)
			(stroke
				(width 0.1)
				(type default)
			)
			(layer "B.Fab")
		)
		(fp_line
			(start 0.12065 -0.305054)
			(end 0.12065 -0.2794)
			(stroke
				(width 0.1)
				(type default)
			)
			(layer "B.Fab")
		)
		(fp_line
			(start 0.12065 -0.2794)
			(end -0.12065 -0.2794)
			(stroke
				(width 0.1)
				(type default)
			)
			(layer "B.Fab")
		)
		(fp_line
			(start 0.12065 0.2794)
			(end 0.12065 0.3048)
			(stroke
				(width 0.1)
				(type default)
			)
			(layer "B.Fab")
		)
		(fp_line
			(start 0.12065 0.3048)
			(end 0.67945 0.3048)
			(stroke
				(width 0.1)
				(type default)
			)
			(layer "B.Fab")
		)
		(fp_line
			(start 0.67945 -0.305054)
			(end 0.12065 -0.305054)
			(stroke
				(width 0.1)
				(type default)
			)
			(layer "B.Fab")
		)
		(fp_line
			(start 0.67945 0.3048)
			(end 0.67945 -0.305054)
			(stroke
				(width 0.1)
				(type default)
			)
			(layer "B.Fab")
		)
		(pad "1" smd circle
			(at 0.40005 0 180)
			(size 0 0)
			(layers "B.Cu" "B.Mask" "B.Paste")
			(net "PVCCIN_CPU1_VIN_CSNIN")
		)
		(pad "2" smd circle
			(at -0.40005 0 180)
			(size 0 0)
			(layers "B.Cu" "B.Mask" "B.Paste")
			(net "GND")
		)
	)
	(footprint ""
		(layer "B.Cu")
		(at 158.707074 -41.816528 -90)
		(property "Reference" "C2314"
			(at 0 0 90)
			(layer "B.SilkS")
			(hide yes)
			(effects
				(font
					(size 1.27 1.27)
				)
				(justify mirror)
			)
		)
		(property "Value" ""
			(at 0 0 90)
			(layer "B.Fab")
			(effects
				(font
					(size 1.27 1.27)
				)
				(justify mirror)
			)
		)
		(duplicate_pad_numbers_are_jumpers no)
		(fp_line
			(start -0.7874 0.4064)
			(end 0.7874 0.4064)
			(stroke
				(width 0.1524)
				(type default)
			)
			(layer "B.SilkS")
		)
		(fp_line
			(start 0.7874 0.4064)
			(end 0.7874 -0.4064)
			(stroke
				(width 0.1524)
				(type default)
			)
			(layer "B.SilkS")
		)
		(fp_line
			(start -0.7874 -0.4064)
			(end -0.7874 0.4064)
			(stroke
				(width 0.1524)
				(type default)
			)
			(layer "B.SilkS")
		)
		(fp_line
			(start 0.7874 -0.4064)
			(end -0.7874 -0.4064)
			(stroke
				(width 0.1524)
				(type default)
			)
			(layer "B.SilkS")
		)
		(fp_line
			(start -0.67945 0.3048)
			(end -0.120396 0.3048)
			(stroke
				(width 0.1)
				(type default)
			)
			(layer "B.Fab")
		)
		(fp_line
			(start -0.120396 0.3048)
			(end -0.120396 0.2794)
			(stroke
				(width 0.1)
				(type default)
			)
			(layer "B.Fab")
		)
		(fp_line
			(start 0.12065 0.3048)
			(end 0.67945 0.3048)
			(stroke
				(width 0.1)
				(type default)
			)
			(layer "B.Fab")
		)
		(fp_line
			(start 0.67945 0.3048)
			(end 0.67945 -0.305054)
			(stroke
				(width 0.1)
				(type default)
			)
			(layer "B.Fab")
		)
		(fp_line
			(start -0.120396 0.2794)
			(end 0.12065 0.2794)
			(stroke
				(width 0.1)
				(type default)
			)
			(layer "B.Fab")
		)
		(fp_line
			(start 0.12065 0.2794)
			(end 0.12065 0.3048)
			(stroke
				(width 0.1)
				(type default)
			)
			(layer "B.Fab")
		)
		(fp_line
			(start -0.12065 -0.2794)
			(end -0.12065 -0.3048)
			(stroke
				(width 0.1)
				(type default)
			)
			(layer "B.Fab")
		)
		(fp_line
			(start 0.12065 -0.2794)
			(end -0.12065 -0.2794)
			(stroke
				(width 0.1)
				(type default)
			)
			(layer "B.Fab")
		)
		(fp_line
			(start -0.67945 -0.3048)
			(end -0.67945 0.3048)
			(stroke
				(width 0.1)
				(type default)
			)
			(layer "B.Fab")
		)
		(fp_line
			(start -0.12065 -0.3048)
			(end -0.67945 -0.3048)
			(stroke
				(width 0.1)
				(type default)
			)
			(layer "B.Fab")
		)
		(fp_line
			(start 0.12065 -0.305054)
			(end 0.12065 -0.2794)
			(stroke
				(width 0.1)
				(type default)
			)
			(layer "B.Fab")
		)
		(fp_line
			(start 0.67945 -0.305054)
			(end 0.12065 -0.305054)
			(stroke
				(width 0.1)
				(type default)
			)
			(layer "B.Fab")
		)
		(pad "1" smd circle
			(at 0.40005 0 90)
			(size 0 0)
			(layers "B.Cu" "B.Mask" "B.Paste")
			(net "P3V3_AUX_USB_HUB_2")
		)
		(pad "2" smd circle
			(at -0.40005 0 90)
			(size 0 0)
			(layers "B.Cu" "B.Mask" "B.Paste")
			(net "GND")
		)
	)
	(footprint ""
		(layer "B.Cu")
		(at 96.8248 -128.91516)
		(property "Reference" "ME3"
			(at 9.652 -9.540748 0)
			(unlocked yes)
			(layer "B.SilkS")
			(effects
				(font
					(size 0.7874 0.5842)
					(thickness 0.1524)
				)
				(justify left mirror)
			)
		)
		(property "Value" ""
			(at 0 0 0)
			(layer "B.Fab")
			(effects
				(font
					(size 1.27 1.27)
				)
				(justify mirror)
			)
		)
		(duplicate_pad_numbers_are_jumpers no)
		(zone
			(layer "B.Cu")
			(hatch none 0.5)
			(connect_pads
				(clearance 0)
			)
			(min_thickness 0.25)
			(keepout
				(tracks allowed)
				(vias allowed)
				(pads allowed)
				(copperpour allowed)
				(footprints not_allowed)
			)
			(placement
				(enabled no)
				(sheetname "")
			)
			(fill
				(thermal_gap 0.5)
				(thermal_bridge_width 0.5)
				(island_removal_mode 0)
			)
			(polygon
				(pts
					(arc
						(start 106.82478 -128.91516)
						(mid 86.82482 -128.91516)
						(end 106.82478 -128.91516)
					)
				)
			)
		)
	)
	(footprint ""
		(layer "B.Cu")
		(at 92.177108 -190.705232 -90)
		(property "Reference" "R662"
			(at 0 0 90)
			(layer "B.SilkS")
			(hide yes)
			(effects
				(font
					(size 1.27 1.27)
				)
				(justify mirror)
			)
		)
		(property "Value" ""
			(at 0 0 90)
			(layer "B.Fab")
			(effects
				(font
					(size 1.27 1.27)
				)
				(justify mirror)
			)
		)
		(duplicate_pad_numbers_are_jumpers no)
		(fp_line
			(start -0.7874 0.4064)
			(end 0.7874 0.4064)
			(stroke
				(width 0.1524)
				(type default)
			)
			(layer "B.SilkS")
		)
		(fp_line
			(start 0.7874 0.4064)
			(end 0.7874 -0.4064)
			(stroke
				(width 0.1524)
				(type default)
			)
			(layer "B.SilkS")
		)
		(fp_line
			(start -0.7874 -0.4064)
			(end -0.7874 0.4064)
			(stroke
				(width 0.1524)
				(type default)
			)
			(layer "B.SilkS")
		)
		(fp_line
			(start 0.7874 -0.4064)
			(end -0.7874 -0.4064)
			(stroke
				(width 0.1524)
				(type default)
			)
			(layer "B.SilkS")
		)
		(fp_line
			(start -0.67945 0.3048)
			(end -0.120396 0.3048)
			(stroke
				(width 0.1)
				(type default)
			)
			(layer "B.Fab")
		)
		(fp_line
			(start -0.120396 0.3048)
			(end -0.120396 0.2794)
			(stroke
				(width 0.1)
				(type default)
			)
			(layer "B.Fab")
		)
		(fp_line
			(start 0.12065 0.3048)
			(end 0.67945 0.3048)
			(stroke
				(width 0.1)
				(type default)
			)
			(layer "B.Fab")
		)
		(fp_line
			(start 0.67945 0.3048)
			(end 0.67945 -0.305054)
			(stroke
				(width 0.1)
				(type default)
			)
			(layer "B.Fab")
		)
		(fp_line
			(start -0.120396 0.2794)
			(end 0.12065 0.2794)
			(stroke
				(width 0.1)
				(type default)
			)
			(layer "B.Fab")
		)
		(fp_line
			(start 0.12065 0.2794)
			(end 0.12065 0.3048)
			(stroke
				(width 0.1)
				(type default)
			)
			(layer "B.Fab")
		)
		(fp_line
			(start -0.12065 -0.2794)
			(end -0.12065 -0.3048)
			(stroke
				(width 0.1)
				(type default)
			)
			(layer "B.Fab")
		)
		(fp_line
			(start 0.12065 -0.2794)
			(end -0.12065 -0.2794)
			(stroke
				(width 0.1)
				(type default)
			)
			(layer "B.Fab")
		)
		(fp_line
			(start -0.67945 -0.3048)
			(end -0.67945 0.3048)
			(stroke
				(width 0.1)
				(type default)
			)
			(layer "B.Fab")
		)
		(fp_line
			(start -0.12065 -0.3048)
			(end -0.67945 -0.3048)
			(stroke
				(width 0.1)
				(type default)
			)
			(layer "B.Fab")
		)
		(fp_line
			(start 0.12065 -0.305054)
			(end 0.12065 -0.2794)
			(stroke
				(width 0.1)
				(type default)
			)
			(layer "B.Fab")
		)
		(fp_line
			(start 0.67945 -0.305054)
			(end 0.12065 -0.305054)
			(stroke
				(width 0.1)
				(type default)
			)
			(layer "B.Fab")
		)
		(pad "1" smd circle
			(at 0.40005 0 90)
			(size 0 0)
			(layers "B.Cu" "B.Mask" "B.Paste")
			(net "PVNN_TERM_CPU1")
		)
		(pad "2" smd circle
			(at -0.40005 0 90)
			(size 0 0)
			(layers "B.Cu" "B.Mask" "B.Paste")
			(net "I3C_SPD_DDRABCD_CPU1_SCL")
		)
	)
	(footprint ""
		(layer "B.Cu")
		(at 440.08802 -20.412456)
		(property "Reference" "PC2080"
			(at 0 0 0)
			(layer "B.SilkS")
			(hide yes)
			(effects
				(font
					(size 1.27 1.27)
				)
				(justify mirror)
			)
		)
		(property "Value" ""
			(at 0 0 0)
			(layer "B.Fab")
			(effects
				(font
					(size 1.27 1.27)
				)
				(justify mirror)
			)
		)
		(duplicate_pad_numbers_are_jumpers no)
		(fp_line
			(start -1.524 -0.762)
			(end -1.524 0.762)
			(stroke
				(width 0.1524)
				(type default)
			)
			(layer "B.SilkS")
		)
		(fp_line
			(start -1.524 0.762)
			(end 1.524 0.762)
			(stroke
				(width 0.1524)
				(type default)
			)
			(layer "B.SilkS")
		)
		(fp_line
			(start 1.524 -0.762)
			(end -1.524 -0.762)
			(stroke
				(width 0.1524)
				(type default)
			)
			(layer "B.SilkS")
		)
		(fp_line
			(start 1.524 0.762)
			(end 1.524 -0.762)
			(stroke
				(width 0.1524)
				(type default)
			)
			(layer "B.SilkS")
		)
		(fp_line
			(start -1.1049 -0.724916)
			(end 1.1049 -0.724916)
			(stroke
				(width 0.1)
				(type default)
			)
			(layer "B.Fab")
		)
		(fp_line
			(start -1.1049 0.724916)
			(end -1.1049 -0.724916)
			(stroke
				(width 0.1)
				(type default)
			)
			(layer "B.Fab")
		)
		(fp_line
			(start 1.1049 -0.724916)
			(end 1.1049 0.724916)
			(stroke
				(width 0.1)
				(type default)
			)
			(layer "B.Fab")
		)
		(fp_line
			(start 1.1049 0.724916)
			(end -1.1049 0.724916)
			(stroke
				(width 0.1)
				(type default)
			)
			(layer "B.Fab")
		)
		(pad "1" smd rect
			(at 0.889 0)
			(size 1.016 1.27)
			(layers "B.Cu" "B.Mask" "B.Paste")
			(net "P12V_OCP_SFF")
		)
		(pad "2" smd rect
			(at -0.889 0)
			(size 1.016 1.27)
			(layers "B.Cu" "B.Mask" "B.Paste")
			(net "GND")
		)
	)
	(footprint ""
		(layer "B.Cu")
		(at 64.990218 -317.897256 180)
		(property "Reference" "R2494"
			(at 0 0 0)
			(layer "B.SilkS")
			(hide yes)
			(effects
				(font
					(size 1.27 1.27)
				)
				(justify mirror)
			)
		)
		(property "Value" ""
			(at 0 0 0)
			(layer "B.Fab")
			(effects
				(font
					(size 1.27 1.27)
				)
				(justify mirror)
			)
		)
		(duplicate_pad_numbers_are_jumpers no)
		(fp_line
			(start 0.7874 0.4064)
			(end 0.7874 -0.4064)
			(stroke
				(width 0.1524)
				(type default)
			)
			(layer "B.SilkS")
		)
		(fp_line
			(start 0.7874 -0.4064)
			(end -0.7874 -0.4064)
			(stroke
				(width 0.1524)
				(type default)
			)
			(layer "B.SilkS")
		)
		(fp_line
			(start -0.7874 0.4064)
			(end 0.7874 0.4064)
			(stroke
				(width 0.1524)
				(type default)
			)
			(layer "B.SilkS")
		)
		(fp_line
			(start -0.7874 -0.4064)
			(end -0.7874 0.4064)
			(stroke
				(width 0.1524)
				(type default)
			)
			(layer "B.SilkS")
		)
		(fp_line
			(start 0.67945 0.3048)
			(end 0.67945 -0.305054)
			(stroke
				(width 0.1)
				(type default)
			)
			(layer "B.Fab")
		)
		(fp_line
			(start 0.67945 -0.305054)
			(end 0.12065 -0.305054)
			(stroke
				(width 0.1)
				(type default)
			)
			(layer "B.Fab")
		)
		(fp_line
			(start 0.12065 0.3048)
			(end 0.67945 0.3048)
			(stroke
				(width 0.1)
				(type default)
			)
			(layer "B.Fab")
		)
		(fp_line
			(start 0.12065 0.2794)
			(end 0.12065 0.3048)
			(stroke
				(width 0.1)
				(type default)
			)
			(layer "B.Fab")
		)
		(fp_line
			(start 0.12065 -0.2794)
			(end -0.12065 -0.2794)
			(stroke
				(width 0.1)
				(type default)
			)
			(layer "B.Fab")
		)
		(fp_line
			(start 0.12065 -0.305054)
			(end 0.12065 -0.2794)
			(stroke
				(width 0.1)
				(type default)
			)
			(layer "B.Fab")
		)
		(fp_line
			(start -0.120396 0.3048)
			(end -0.120396 0.2794)
			(stroke
				(width 0.1)
				(type default)
			)
			(layer "B.Fab")
		)
		(fp_line
			(start -0.120396 0.2794)
			(end 0.12065 0.2794)
			(stroke
				(width 0.1)
				(type default)
			)
			(layer "B.Fab")
		)
		(fp_line
			(start -0.12065 -0.2794)
			(end -0.12065 -0.3048)
			(stroke
				(width 0.1)
				(type default)
			)
			(layer "B.Fab")
		)
		(fp_line
			(start -0.12065 -0.3048)
			(end -0.67945 -0.3048)
			(stroke
				(width 0.1)
				(type default)
			)
			(layer "B.Fab")
		)
		(fp_line
			(start -0.67945 0.3048)
			(end -0.120396 0.3048)
			(stroke
				(width 0.1)
				(type default)
			)
			(layer "B.Fab")
		)
		(fp_line
			(start -0.67945 -0.3048)
			(end -0.67945 0.3048)
			(stroke
				(width 0.1)
				(type default)
			)
			(layer "B.Fab")
		)
		(pad "1" smd circle
			(at 0.40005 0)
			(size 0 0)
			(layers "B.Cu" "B.Mask" "B.Paste")
			(net "PWRGD_FAIL_CPU1_AB")
		)
		(pad "2" smd circle
			(at -0.40005 0)
			(size 0 0)
			(layers "B.Cu" "B.Mask" "B.Paste")
			(net "PWRGD_FAIL_CPU1_AB_R1")
		)
	)
	(footprint ""
		(layer "B.Cu")
		(at 170.673268 -196.013578 -90)
		(property "Reference" "R4302"
			(at 0 0 90)
			(layer "B.SilkS")
			(hide yes)
			(effects
				(font
					(size 1.27 1.27)
				)
				(justify mirror)
			)
		)
		(property "Value" ""
			(at 0 0 90)
			(layer "B.Fab")
			(effects
				(font
					(size 1.27 1.27)
				)
				(justify mirror)
			)
		)
		(duplicate_pad_numbers_are_jumpers no)
		(fp_line
			(start -0.7874 0.4064)
			(end 0.7874 0.4064)
			(stroke
				(width 0.1524)
				(type default)
			)
			(layer "B.SilkS")
		)
		(fp_line
			(start 0.7874 0.4064)
			(end 0.7874 -0.4064)
			(stroke
				(width 0.1524)
				(type default)
			)
			(layer "B.SilkS")
		)
		(fp_line
			(start -0.7874 -0.4064)
			(end -0.7874 0.4064)
			(stroke
				(width 0.1524)
				(type default)
			)
			(layer "B.SilkS")
		)
		(fp_line
			(start 0.7874 -0.4064)
			(end -0.7874 -0.4064)
			(stroke
				(width 0.1524)
				(type default)
			)
			(layer "B.SilkS")
		)
		(fp_line
			(start -0.67945 0.3048)
			(end -0.120396 0.3048)
			(stroke
				(width 0.1)
				(type default)
			)
			(layer "B.Fab")
		)
		(fp_line
			(start -0.120396 0.3048)
			(end -0.120396 0.2794)
			(stroke
				(width 0.1)
				(type default)
			)
			(layer "B.Fab")
		)
		(fp_line
			(start 0.12065 0.3048)
			(end 0.67945 0.3048)
			(stroke
				(width 0.1)
				(type default)
			)
			(layer "B.Fab")
		)
		(fp_line
			(start 0.67945 0.3048)
			(end 0.67945 -0.305054)
			(stroke
				(width 0.1)
				(type default)
			)
			(layer "B.Fab")
		)
		(fp_line
			(start -0.120396 0.2794)
			(end 0.12065 0.2794)
			(stroke
				(width 0.1)
				(type default)
			)
			(layer "B.Fab")
		)
		(fp_line
			(start 0.12065 0.2794)
			(end 0.12065 0.3048)
			(stroke
				(width 0.1)
				(type default)
			)
			(layer "B.Fab")
		)
		(fp_line
			(start -0.12065 -0.2794)
			(end -0.12065 -0.3048)
			(stroke
				(width 0.1)
				(type default)
			)
			(layer "B.Fab")
		)
		(fp_line
			(start 0.12065 -0.2794)
			(end -0.12065 -0.2794)
			(stroke
				(width 0.1)
				(type default)
			)
			(layer "B.Fab")
		)
		(fp_line
			(start -0.67945 -0.3048)
			(end -0.67945 0.3048)
			(stroke
				(width 0.1)
				(type default)
			)
			(layer "B.Fab")
		)
		(fp_line
			(start -0.12065 -0.3048)
			(end -0.67945 -0.3048)
			(stroke
				(width 0.1)
				(type default)
			)
			(layer "B.Fab")
		)
		(fp_line
			(start 0.12065 -0.305054)
			(end 0.12065 -0.2794)
			(stroke
				(width 0.1)
				(type default)
			)
			(layer "B.Fab")
		)
		(fp_line
			(start 0.67945 -0.305054)
			(end 0.12065 -0.305054)
			(stroke
				(width 0.1)
				(type default)
			)
			(layer "B.Fab")
		)
		(pad "1" smd circle
			(at 0.40005 0 90)
			(size 0 0)
			(layers "B.Cu" "B.Mask" "B.Paste")
			(net "PWRGD_DRAMPWRGD_CPU1_GH_LVC1_R2")
		)
		(pad "2" smd circle
			(at -0.40005 0 90)
			(size 0 0)
			(layers "B.Cu" "B.Mask" "B.Paste")
			(net "PWRGD_DRAMPWRGD_CPU1_GH_LVC1_R")
		)
	)
	(footprint ""
		(layer "B.Cu")
		(at 89.958926 -337.145884 90)
		(property "Reference" "PC515_P1_6"
			(at 0 0 90)
			(layer "B.SilkS")
			(hide yes)
			(effects
				(font
					(size 1.27 1.27)
				)
				(justify mirror)
			)
		)
		(property "Value" ""
			(at 0 0 90)
			(layer "B.Fab")
			(effects
				(font
					(size 1.27 1.27)
				)
				(justify mirror)
			)
		)
		(duplicate_pad_numbers_are_jumpers no)
		(fp_line
			(start 1.524 -0.762)
			(end -1.524 -0.762)
			(stroke
				(width 0.1524)
				(type default)
			)
			(layer "B.SilkS")
		)
		(fp_line
			(start -1.524 -0.762)
			(end -1.524 0.762)
			(stroke
				(width 0.1524)
				(type default)
			)
			(layer "B.SilkS")
		)
		(fp_line
			(start 1.524 0.762)
			(end 1.524 -0.762)
			(stroke
				(width 0.1524)
				(type default)
			)
			(layer "B.SilkS")
		)
		(fp_line
			(start -1.524 0.762)
			(end 1.524 0.762)
			(stroke
				(width 0.1524)
				(type default)
			)
			(layer "B.SilkS")
		)
		(fp_line
			(start 1.1049 -0.724916)
			(end 1.1049 0.724916)
			(stroke
				(width 0.1)
				(type default)
			)
			(layer "B.Fab")
		)
		(fp_line
			(start -1.1049 -0.724916)
			(end 1.1049 -0.724916)
			(stroke
				(width 0.1)
				(type default)
			)
			(layer "B.Fab")
		)
		(fp_line
			(start 1.1049 0.724916)
			(end -1.1049 0.724916)
			(stroke
				(width 0.1)
				(type default)
			)
			(layer "B.Fab")
		)
		(fp_line
			(start -1.1049 0.724916)
			(end -1.1049 -0.724916)
			(stroke
				(width 0.1)
				(type default)
			)
			(layer "B.Fab")
		)
		(pad "1" smd rect
			(at 0.889 0 90)
			(size 1.016 1.27)
			(layers "B.Cu" "B.Mask" "B.Paste")
			(net "SW_P12V_PVCCIN_CPU1_FLT")
		)
		(pad "2" smd rect
			(at -0.889 0 90)
			(size 1.016 1.27)
			(layers "B.Cu" "B.Mask" "B.Paste")
			(net "GND")
		)
	)
	(footprint ""
		(layer "B.Cu")
		(at 76.809854 -345.830144 -90)
		(property "Reference" "PR290"
			(at 0 0 90)
			(layer "B.SilkS")
			(hide yes)
			(effects
				(font
					(size 1.27 1.27)
				)
				(justify mirror)
			)
		)
		(property "Value" ""
			(at 0 0 90)
			(layer "B.Fab")
			(effects
				(font
					(size 1.27 1.27)
				)
				(justify mirror)
			)
		)
		(duplicate_pad_numbers_are_jumpers no)
		(fp_line
			(start -0.7874 0.4064)
			(end 0.7874 0.4064)
			(stroke
				(width 0.1524)
				(type default)
			)
			(layer "B.SilkS")
		)
		(fp_line
			(start 0.7874 0.4064)
			(end 0.7874 -0.4064)
			(stroke
				(width 0.1524)
				(type default)
			)
			(layer "B.SilkS")
		)
		(fp_line
			(start -0.7874 -0.4064)
			(end -0.7874 0.4064)
			(stroke
				(width 0.1524)
				(type default)
			)
			(layer "B.SilkS")
		)
		(fp_line
			(start 0.7874 -0.4064)
			(end -0.7874 -0.4064)
			(stroke
				(width 0.1524)
				(type default)
			)
			(layer "B.SilkS")
		)
		(fp_line
			(start -0.67945 0.3048)
			(end -0.120396 0.3048)
			(stroke
				(width 0.1)
				(type default)
			)
			(layer "B.Fab")
		)
		(fp_line
			(start -0.120396 0.3048)
			(end -0.120396 0.2794)
			(stroke
				(width 0.1)
				(type default)
			)
			(layer "B.Fab")
		)
		(fp_line
			(start 0.12065 0.3048)
			(end 0.67945 0.3048)
			(stroke
				(width 0.1)
				(type default)
			)
			(layer "B.Fab")
		)
		(fp_line
			(start 0.67945 0.3048)
			(end 0.67945 -0.305054)
			(stroke
				(width 0.1)
				(type default)
			)
			(layer "B.Fab")
		)
		(fp_line
			(start -0.120396 0.2794)
			(end 0.12065 0.2794)
			(stroke
				(width 0.1)
				(type default)
			)
			(layer "B.Fab")
		)
		(fp_line
			(start 0.12065 0.2794)
			(end 0.12065 0.3048)
			(stroke
				(width 0.1)
				(type default)
			)
			(layer "B.Fab")
		)
		(fp_line
			(start -0.12065 -0.2794)
			(end -0.12065 -0.3048)
			(stroke
				(width 0.1)
				(type default)
			)
			(layer "B.Fab")
		)
		(fp_line
			(start 0.12065 -0.2794)
			(end -0.12065 -0.2794)
			(stroke
				(width 0.1)
				(type default)
			)
			(layer "B.Fab")
		)
		(fp_line
			(start -0.67945 -0.3048)
			(end -0.67945 0.3048)
			(stroke
				(width 0.1)
				(type default)
			)
			(layer "B.Fab")
		)
		(fp_line
			(start -0.12065 -0.3048)
			(end -0.67945 -0.3048)
			(stroke
				(width 0.1)
				(type default)
			)
			(layer "B.Fab")
		)
		(fp_line
			(start 0.12065 -0.305054)
			(end 0.12065 -0.2794)
			(stroke
				(width 0.1)
				(type default)
			)
			(layer "B.Fab")
		)
		(fp_line
			(start 0.67945 -0.305054)
			(end 0.12065 -0.305054)
			(stroke
				(width 0.1)
				(type default)
			)
			(layer "B.Fab")
		)
		(pad "1" smd circle
			(at 0.40005 0 90)
			(size 0 0)
			(layers "B.Cu" "B.Mask" "B.Paste")
			(net "PVCCIN_CPU1_VOS7")
		)
		(pad "2" smd circle
			(at -0.40005 0 90)
			(size 0 0)
			(layers "B.Cu" "B.Mask" "B.Paste")
			(net "PVCCIN_CPU1")
		)
	)
	(footprint ""
		(layer "B.Cu")
		(at 178.689 -19.522948 -90)
		(property "Reference" "R4504"
			(at 0 0 90)
			(layer "B.SilkS")
			(hide yes)
			(effects
				(font
					(size 1.27 1.27)
				)
				(justify mirror)
			)
		)
		(property "Value" ""
			(at 0 0 90)
			(layer "B.Fab")
			(effects
				(font
					(size 1.27 1.27)
				)
				(justify mirror)
			)
		)
		(duplicate_pad_numbers_are_jumpers no)
		(fp_line
			(start -0.7874 0.4064)
			(end 0.7874 0.4064)
			(stroke
				(width 0.1524)
				(type default)
			)
			(layer "B.SilkS")
		)
		(fp_line
			(start 0.7874 0.4064)
			(end 0.7874 -0.4064)
			(stroke
				(width 0.1524)
				(type default)
			)
			(layer "B.SilkS")
		)
		(fp_line
			(start -0.7874 -0.4064)
			(end -0.7874 0.4064)
			(stroke
				(width 0.1524)
				(type default)
			)
			(layer "B.SilkS")
		)
		(fp_line
			(start 0.7874 -0.4064)
			(end -0.7874 -0.4064)
			(stroke
				(width 0.1524)
				(type default)
			)
			(layer "B.SilkS")
		)
		(fp_line
			(start -0.67945 0.3048)
			(end -0.120396 0.3048)
			(stroke
				(width 0.1)
				(type default)
			)
			(layer "B.Fab")
		)
		(fp_line
			(start -0.120396 0.3048)
			(end -0.120396 0.2794)
			(stroke
				(width 0.1)
				(type default)
			)
			(layer "B.Fab")
		)
		(fp_line
			(start 0.12065 0.3048)
			(end 0.67945 0.3048)
			(stroke
				(width 0.1)
				(type default)
			)
			(layer "B.Fab")
		)
		(fp_line
			(start 0.67945 0.3048)
			(end 0.67945 -0.305054)
			(stroke
				(width 0.1)
				(type default)
			)
			(layer "B.Fab")
		)
		(fp_line
			(start -0.120396 0.2794)
			(end 0.12065 0.2794)
			(stroke
				(width 0.1)
				(type default)
			)
			(layer "B.Fab")
		)
		(fp_line
			(start 0.12065 0.2794)
			(end 0.12065 0.3048)
			(stroke
				(width 0.1)
				(type default)
			)
			(layer "B.Fab")
		)
		(fp_line
			(start -0.12065 -0.2794)
			(end -0.12065 -0.3048)
			(stroke
				(width 0.1)
				(type default)
			)
			(layer "B.Fab")
		)
		(fp_line
			(start 0.12065 -0.2794)
			(end -0.12065 -0.2794)
			(stroke
				(width 0.1)
				(type default)
			)
			(layer "B.Fab")
		)
		(fp_line
			(start -0.67945 -0.3048)
			(end -0.67945 0.3048)
			(stroke
				(width 0.1)
				(type default)
			)
			(layer "B.Fab")
		)
		(fp_line
			(start -0.12065 -0.3048)
			(end -0.67945 -0.3048)
			(stroke
				(width 0.1)
				(type default)
			)
			(layer "B.Fab")
		)
		(fp_line
			(start 0.12065 -0.305054)
			(end 0.12065 -0.2794)
			(stroke
				(width 0.1)
				(type default)
			)
			(layer "B.Fab")
		)
		(fp_line
			(start 0.67945 -0.305054)
			(end 0.12065 -0.305054)
			(stroke
				(width 0.1)
				(type default)
			)
			(layer "B.Fab")
		)
		(pad "1" smd circle
			(at 0.40005 0 90)
			(size 0 0)
			(layers "B.Cu" "B.Mask" "B.Paste")
			(net "SMB_SML1_PMBUS_3V3AUX_PCH_SDA")
		)
		(pad "2" smd circle
			(at -0.40005 0 90)
			(size 0 0)
			(layers "B.Cu" "B.Mask" "B.Paste")
			(net "SMB_SML1_PMBUS_3V3AUX_PCH_SDA_1")
		)
	)
	(footprint ""
		(layer "B.Cu")
		(at 271.180814 -319.263776 180)
		(property "Reference" "C14"
			(at 0 0 0)
			(layer "B.SilkS")
			(hide yes)
			(effects
				(font
					(size 1.27 1.27)
				)
				(justify mirror)
			)
		)
		(property "Value" ""
			(at 0 0 0)
			(layer "B.Fab")
			(effects
				(font
					(size 1.27 1.27)
				)
				(justify mirror)
			)
		)
		(duplicate_pad_numbers_are_jumpers no)
		(fp_line
			(start 0.7874 0.4064)
			(end 0.7874 -0.4064)
			(stroke
				(width 0.1524)
				(type default)
			)
			(layer "B.SilkS")
		)
		(fp_line
			(start 0.7874 -0.4064)
			(end -0.7874 -0.4064)
			(stroke
				(width 0.1524)
				(type default)
			)
			(layer "B.SilkS")
		)
		(fp_line
			(start -0.7874 0.4064)
			(end 0.7874 0.4064)
			(stroke
				(width 0.1524)
				(type default)
			)
			(layer "B.SilkS")
		)
		(fp_line
			(start -0.7874 -0.4064)
			(end -0.7874 0.4064)
			(stroke
				(width 0.1524)
				(type default)
			)
			(layer "B.SilkS")
		)
		(fp_line
			(start 0.67945 0.3048)
			(end 0.67945 -0.305054)
			(stroke
				(width 0.1)
				(type default)
			)
			(layer "B.Fab")
		)
		(fp_line
			(start 0.67945 -0.305054)
			(end 0.12065 -0.305054)
			(stroke
				(width 0.1)
				(type default)
			)
			(layer "B.Fab")
		)
		(fp_line
			(start 0.12065 0.3048)
			(end 0.67945 0.3048)
			(stroke
				(width 0.1)
				(type default)
			)
			(layer "B.Fab")
		)
		(fp_line
			(start 0.12065 0.2794)
			(end 0.12065 0.3048)
			(stroke
				(width 0.1)
				(type default)
			)
			(layer "B.Fab")
		)
		(fp_line
			(start 0.12065 -0.2794)
			(end -0.12065 -0.2794)
			(stroke
				(width 0.1)
				(type default)
			)
			(layer "B.Fab")
		)
		(fp_line
			(start 0.12065 -0.305054)
			(end 0.12065 -0.2794)
			(stroke
				(width 0.1)
				(type default)
			)
			(layer "B.Fab")
		)
		(fp_line
			(start -0.120396 0.3048)
			(end -0.120396 0.2794)
			(stroke
				(width 0.1)
				(type default)
			)
			(layer "B.Fab")
		)
		(fp_line
			(start -0.120396 0.2794)
			(end 0.12065 0.2794)
			(stroke
				(width 0.1)
				(type default)
			)
			(layer "B.Fab")
		)
		(fp_line
			(start -0.12065 -0.2794)
			(end -0.12065 -0.3048)
			(stroke
				(width 0.1)
				(type default)
			)
			(layer "B.Fab")
		)
		(fp_line
			(start -0.12065 -0.3048)
			(end -0.67945 -0.3048)
			(stroke
				(width 0.1)
				(type default)
			)
			(layer "B.Fab")
		)
		(fp_line
			(start -0.67945 0.3048)
			(end -0.120396 0.3048)
			(stroke
				(width 0.1)
				(type default)
			)
			(layer "B.Fab")
		)
		(fp_line
			(start -0.67945 -0.3048)
			(end -0.67945 0.3048)
			(stroke
				(width 0.1)
				(type default)
			)
			(layer "B.Fab")
		)
		(pad "1" smd circle
			(at 0.40005 0)
			(size 0 0)
			(layers "B.Cu" "B.Mask" "B.Paste")
			(net "P3V3_AUX")
		)
		(pad "2" smd circle
			(at -0.40005 0)
			(size 0 0)
			(layers "B.Cu" "B.Mask" "B.Paste")
			(net "GND")
		)
	)
	(footprint ""
		(layer "B.Cu")
		(at 182.83428 -353.573842 90)
		(property "Reference" "PC1199_P1_3"
			(at 0 0 90)
			(layer "B.SilkS")
			(hide yes)
			(effects
				(font
					(size 1.27 1.27)
				)
				(justify mirror)
			)
		)
		(property "Value" ""
			(at 0 0 90)
			(layer "B.Fab")
			(effects
				(font
					(size 1.27 1.27)
				)
				(justify mirror)
			)
		)
		(duplicate_pad_numbers_are_jumpers no)
		(fp_line
			(start 1.524 -0.762)
			(end -1.524 -0.762)
			(stroke
				(width 0.1524)
				(type default)
			)
			(layer "B.SilkS")
		)
		(fp_line
			(start -1.524 -0.762)
			(end -1.524 0.762)
			(stroke
				(width 0.1524)
				(type default)
			)
			(layer "B.SilkS")
		)
		(fp_line
			(start 1.524 0.762)
			(end 1.524 -0.762)
			(stroke
				(width 0.1524)
				(type default)
			)
			(layer "B.SilkS")
		)
		(fp_line
			(start -1.524 0.762)
			(end 1.524 0.762)
			(stroke
				(width 0.1524)
				(type default)
			)
			(layer "B.SilkS")
		)
		(fp_line
			(start 1.1049 -0.724916)
			(end 1.1049 0.724916)
			(stroke
				(width 0.1)
				(type default)
			)
			(layer "B.Fab")
		)
		(fp_line
			(start -1.1049 -0.724916)
			(end 1.1049 -0.724916)
			(stroke
				(width 0.1)
				(type default)
			)
			(layer "B.Fab")
		)
		(fp_line
			(start 1.1049 0.724916)
			(end -1.1049 0.724916)
			(stroke
				(width 0.1)
				(type default)
			)
			(layer "B.Fab")
		)
		(fp_line
			(start -1.1049 0.724916)
			(end -1.1049 -0.724916)
			(stroke
				(width 0.1)
				(type default)
			)
			(layer "B.Fab")
		)
		(pad "1" smd rect
			(at 0.889 0 90)
			(size 1.016 1.27)
			(layers "B.Cu" "B.Mask" "B.Paste")
			(net "SW_P12V_PVCCFA_EHV_FIVRA_CPU1_R")
		)
		(pad "2" smd rect
			(at -0.889 0 90)
			(size 1.016 1.27)
			(layers "B.Cu" "B.Mask" "B.Paste")
			(net "GND")
		)
	)
	(footprint ""
		(layer "B.Cu")
		(at 27.0383 -129.380996 180)
		(property "Reference" "PR260"
			(at 0 0 0)
			(layer "B.SilkS")
			(hide yes)
			(effects
				(font
					(size 1.27 1.27)
				)
				(justify mirror)
			)
		)
		(property "Value" ""
			(at 0 0 0)
			(layer "B.Fab")
			(effects
				(font
					(size 1.27 1.27)
				)
				(justify mirror)
			)
		)
		(duplicate_pad_numbers_are_jumpers no)
		(fp_line
			(start 0.7874 0.4064)
			(end 0.7874 -0.4064)
			(stroke
				(width 0.1524)
				(type default)
			)
			(layer "B.SilkS")
		)
		(fp_line
			(start 0.7874 -0.4064)
			(end -0.7874 -0.4064)
			(stroke
				(width 0.1524)
				(type default)
			)
			(layer "B.SilkS")
		)
		(fp_line
			(start -0.7874 0.4064)
			(end 0.7874 0.4064)
			(stroke
				(width 0.1524)
				(type default)
			)
			(layer "B.SilkS")
		)
		(fp_line
			(start -0.7874 -0.4064)
			(end -0.7874 0.4064)
			(stroke
				(width 0.1524)
				(type default)
			)
			(layer "B.SilkS")
		)
		(fp_line
			(start 0.67945 0.3048)
			(end 0.67945 -0.305054)
			(stroke
				(width 0.1)
				(type default)
			)
			(layer "B.Fab")
		)
		(fp_line
			(start 0.67945 -0.305054)
			(end 0.12065 -0.305054)
			(stroke
				(width 0.1)
				(type default)
			)
			(layer "B.Fab")
		)
		(fp_line
			(start 0.12065 0.3048)
			(end 0.67945 0.3048)
			(stroke
				(width 0.1)
				(type default)
			)
			(layer "B.Fab")
		)
		(fp_line
			(start 0.12065 0.2794)
			(end 0.12065 0.3048)
			(stroke
				(width 0.1)
				(type default)
			)
			(layer "B.Fab")
		)
		(fp_line
			(start 0.12065 -0.2794)
			(end -0.12065 -0.2794)
			(stroke
				(width 0.1)
				(type default)
			)
			(layer "B.Fab")
		)
		(fp_line
			(start 0.12065 -0.305054)
			(end 0.12065 -0.2794)
			(stroke
				(width 0.1)
				(type default)
			)
			(layer "B.Fab")
		)
		(fp_line
			(start -0.120396 0.3048)
			(end -0.120396 0.2794)
			(stroke
				(width 0.1)
				(type default)
			)
			(layer "B.Fab")
		)
		(fp_line
			(start -0.120396 0.2794)
			(end 0.12065 0.2794)
			(stroke
				(width 0.1)
				(type default)
			)
			(layer "B.Fab")
		)
		(fp_line
			(start -0.12065 -0.2794)
			(end -0.12065 -0.3048)
			(stroke
				(width 0.1)
				(type default)
			)
			(layer "B.Fab")
		)
		(fp_line
			(start -0.12065 -0.3048)
			(end -0.67945 -0.3048)
			(stroke
				(width 0.1)
				(type default)
			)
			(layer "B.Fab")
		)
		(fp_line
			(start -0.67945 0.3048)
			(end -0.120396 0.3048)
			(stroke
				(width 0.1)
				(type default)
			)
			(layer "B.Fab")
		)
		(fp_line
			(start -0.67945 -0.3048)
			(end -0.67945 0.3048)
			(stroke
				(width 0.1)
				(type default)
			)
			(layer "B.Fab")
		)
		(pad "1" smd circle
			(at 0.40005 0)
			(size 0 0)
			(layers "B.Cu" "B.Mask" "B.Paste")
			(net "P12V_AUX")
		)
		(pad "2" smd circle
			(at -0.40005 0)
			(size 0 0)
			(layers "B.Cu" "B.Mask" "B.Paste")
			(net "PVCCINFAON_CPU1_CSPIN")
		)
	)
	(footprint ""
		(layer "B.Cu")
		(at 328.092816 -28.852876 -90)
		(property "Reference" "R609"
			(at 0 0 90)
			(layer "B.SilkS")
			(hide yes)
			(effects
				(font
					(size 1.27 1.27)
				)
				(justify mirror)
			)
		)
		(property "Value" ""
			(at 0 0 90)
			(layer "B.Fab")
			(effects
				(font
					(size 1.27 1.27)
				)
				(justify mirror)
			)
		)
		(duplicate_pad_numbers_are_jumpers no)
		(fp_line
			(start -0.7874 0.4064)
			(end 0.7874 0.4064)
			(stroke
				(width 0.1524)
				(type default)
			)
			(layer "B.SilkS")
		)
		(fp_line
			(start 0.7874 0.4064)
			(end 0.7874 -0.4064)
			(stroke
				(width 0.1524)
				(type default)
			)
			(layer "B.SilkS")
		)
		(fp_line
			(start -0.7874 -0.4064)
			(end -0.7874 0.4064)
			(stroke
				(width 0.1524)
				(type default)
			)
			(layer "B.SilkS")
		)
		(fp_line
			(start 0.7874 -0.4064)
			(end -0.7874 -0.4064)
			(stroke
				(width 0.1524)
				(type default)
			)
			(layer "B.SilkS")
		)
		(fp_line
			(start -0.67945 0.3048)
			(end -0.120396 0.3048)
			(stroke
				(width 0.1)
				(type default)
			)
			(layer "B.Fab")
		)
		(fp_line
			(start -0.120396 0.3048)
			(end -0.120396 0.2794)
			(stroke
				(width 0.1)
				(type default)
			)
			(layer "B.Fab")
		)
		(fp_line
			(start 0.12065 0.3048)
			(end 0.67945 0.3048)
			(stroke
				(width 0.1)
				(type default)
			)
			(layer "B.Fab")
		)
		(fp_line
			(start 0.67945 0.3048)
			(end 0.67945 -0.305054)
			(stroke
				(width 0.1)
				(type default)
			)
			(layer "B.Fab")
		)
		(fp_line
			(start -0.120396 0.2794)
			(end 0.12065 0.2794)
			(stroke
				(width 0.1)
				(type default)
			)
			(layer "B.Fab")
		)
		(fp_line
			(start 0.12065 0.2794)
			(end 0.12065 0.3048)
			(stroke
				(width 0.1)
				(type default)
			)
			(layer "B.Fab")
		)
		(fp_line
			(start -0.12065 -0.2794)
			(end -0.12065 -0.3048)
			(stroke
				(width 0.1)
				(type default)
			)
			(layer "B.Fab")
		)
		(fp_line
			(start 0.12065 -0.2794)
			(end -0.12065 -0.2794)
			(stroke
				(width 0.1)
				(type default)
			)
			(layer "B.Fab")
		)
		(fp_line
			(start -0.67945 -0.3048)
			(end -0.67945 0.3048)
			(stroke
				(width 0.1)
				(type default)
			)
			(layer "B.Fab")
		)
		(fp_line
			(start -0.12065 -0.3048)
			(end -0.67945 -0.3048)
			(stroke
				(width 0.1)
				(type default)
			)
			(layer "B.Fab")
		)
		(fp_line
			(start 0.12065 -0.305054)
			(end 0.12065 -0.2794)
			(stroke
				(width 0.1)
				(type default)
			)
			(layer "B.Fab")
		)
		(fp_line
			(start 0.67945 -0.305054)
			(end 0.12065 -0.305054)
			(stroke
				(width 0.1)
				(type default)
			)
			(layer "B.Fab")
		)
		(pad "1" smd circle
			(at 0.40005 0 90)
			(size 0 0)
			(layers "B.Cu" "B.Mask" "B.Paste")
			(net "P3V3_AUX")
		)
		(pad "2" smd circle
			(at -0.40005 0 90)
			(size 0 0)
			(layers "B.Cu" "B.Mask" "B.Paste")
			(net "FM_ESPI_CS_SWIZZLE")
		)
	)
	(footprint ""
		(layer "B.Cu")
		(at 179.887626 -415.633154 -90)
		(property "Reference" "R2807"
			(at 0 0 90)
			(layer "B.SilkS")
			(hide yes)
			(effects
				(font
					(size 1.27 1.27)
				)
				(justify mirror)
			)
		)
		(property "Value" ""
			(at 0 0 90)
			(layer "B.Fab")
			(effects
				(font
					(size 1.27 1.27)
				)
				(justify mirror)
			)
		)
		(duplicate_pad_numbers_are_jumpers no)
		(fp_line
			(start -0.7874 0.4064)
			(end 0.7874 0.4064)
			(stroke
				(width 0.1524)
				(type default)
			)
			(layer "B.SilkS")
		)
		(fp_line
			(start 0.7874 0.4064)
			(end 0.7874 -0.4064)
			(stroke
				(width 0.1524)
				(type default)
			)
			(layer "B.SilkS")
		)
		(fp_line
			(start -0.7874 -0.4064)
			(end -0.7874 0.4064)
			(stroke
				(width 0.1524)
				(type default)
			)
			(layer "B.SilkS")
		)
		(fp_line
			(start 0.7874 -0.4064)
			(end -0.7874 -0.4064)
			(stroke
				(width 0.1524)
				(type default)
			)
			(layer "B.SilkS")
		)
		(fp_line
			(start -0.67945 0.3048)
			(end -0.120396 0.3048)
			(stroke
				(width 0.1)
				(type default)
			)
			(layer "B.Fab")
		)
		(fp_line
			(start -0.120396 0.3048)
			(end -0.120396 0.2794)
			(stroke
				(width 0.1)
				(type default)
			)
			(layer "B.Fab")
		)
		(fp_line
			(start 0.12065 0.3048)
			(end 0.67945 0.3048)
			(stroke
				(width 0.1)
				(type default)
			)
			(layer "B.Fab")
		)
		(fp_line
			(start 0.67945 0.3048)
			(end 0.67945 -0.305054)
			(stroke
				(width 0.1)
				(type default)
			)
			(layer "B.Fab")
		)
		(fp_line
			(start -0.120396 0.2794)
			(end 0.12065 0.2794)
			(stroke
				(width 0.1)
				(type default)
			)
			(layer "B.Fab")
		)
		(fp_line
			(start 0.12065 0.2794)
			(end 0.12065 0.3048)
			(stroke
				(width 0.1)
				(type default)
			)
			(layer "B.Fab")
		)
		(fp_line
			(start -0.12065 -0.2794)
			(end -0.12065 -0.3048)
			(stroke
				(width 0.1)
				(type default)
			)
			(layer "B.Fab")
		)
		(fp_line
			(start 0.12065 -0.2794)
			(end -0.12065 -0.2794)
			(stroke
				(width 0.1)
				(type default)
			)
			(layer "B.Fab")
		)
		(fp_line
			(start -0.67945 -0.3048)
			(end -0.67945 0.3048)
			(stroke
				(width 0.1)
				(type default)
			)
			(layer "B.Fab")
		)
		(fp_line
			(start -0.12065 -0.3048)
			(end -0.67945 -0.3048)
			(stroke
				(width 0.1)
				(type default)
			)
			(layer "B.Fab")
		)
		(fp_line
			(start 0.12065 -0.305054)
			(end 0.12065 -0.2794)
			(stroke
				(width 0.1)
				(type default)
			)
			(layer "B.Fab")
		)
		(fp_line
			(start 0.67945 -0.305054)
			(end 0.12065 -0.305054)
			(stroke
				(width 0.1)
				(type default)
			)
			(layer "B.Fab")
		)
		(pad "1" smd circle
			(at 0.40005 0 90)
			(size 0 0)
			(layers "B.Cu" "B.Mask" "B.Paste")
			(net "P3V3_AUX")
		)
		(pad "2" smd circle
			(at -0.40005 0 90)
			(size 0 0)
			(layers "B.Cu" "B.Mask" "B.Paste")
			(net "SMB_FAN_3V3AUX_BUF_SDA")
		)
	)
	(footprint ""
		(layer "B.Cu")
		(at 294.91813 -403.031452 90)
		(property "Reference" "PR2517"
			(at 0 0 90)
			(layer "B.SilkS")
			(hide yes)
			(effects
				(font
					(size 1.27 1.27)
				)
				(justify mirror)
			)
		)
		(property "Value" ""
			(at 0 0 90)
			(layer "B.Fab")
			(effects
				(font
					(size 1.27 1.27)
				)
				(justify mirror)
			)
		)
		(duplicate_pad_numbers_are_jumpers no)
		(fp_line
			(start 0.7874 -0.4064)
			(end -0.7874 -0.4064)
			(stroke
				(width 0.1524)
				(type default)
			)
			(layer "B.SilkS")
		)
		(fp_line
			(start -0.7874 -0.4064)
			(end -0.7874 0.4064)
			(stroke
				(width 0.1524)
				(type default)
			)
			(layer "B.SilkS")
		)
		(fp_line
			(start 0.7874 0.4064)
			(end 0.7874 -0.4064)
			(stroke
				(width 0.1524)
				(type default)
			)
			(layer "B.SilkS")
		)
		(fp_line
			(start -0.7874 0.4064)
			(end 0.7874 0.4064)
			(stroke
				(width 0.1524)
				(type default)
			)
			(layer "B.SilkS")
		)
		(fp_line
			(start 0.67945 -0.305054)
			(end 0.12065 -0.305054)
			(stroke
				(width 0.1)
				(type default)
			)
			(layer "B.Fab")
		)
		(fp_line
			(start 0.12065 -0.305054)
			(end 0.12065 -0.2794)
			(stroke
				(width 0.1)
				(type default)
			)
			(layer "B.Fab")
		)
		(fp_line
			(start -0.12065 -0.3048)
			(end -0.67945 -0.3048)
			(stroke
				(width 0.1)
				(type default)
			)
			(layer "B.Fab")
		)
		(fp_line
			(start -0.67945 -0.3048)
			(end -0.67945 0.3048)
			(stroke
				(width 0.1)
				(type default)
			)
			(layer "B.Fab")
		)
		(fp_line
			(start 0.12065 -0.2794)
			(end -0.12065 -0.2794)
			(stroke
				(width 0.1)
				(type default)
			)
			(layer "B.Fab")
		)
		(fp_line
			(start -0.12065 -0.2794)
			(end -0.12065 -0.3048)
			(stroke
				(width 0.1)
				(type default)
			)
			(layer "B.Fab")
		)
		(fp_line
			(start 0.12065 0.2794)
			(end 0.12065 0.3048)
			(stroke
				(width 0.1)
				(type default)
			)
			(layer "B.Fab")
		)
		(fp_line
			(start -0.120396 0.2794)
			(end 0.12065 0.2794)
			(stroke
				(width 0.1)
				(type default)
			)
			(layer "B.Fab")
		)
		(fp_line
			(start 0.67945 0.3048)
			(end 0.67945 -0.305054)
			(stroke
				(width 0.1)
				(type default)
			)
			(layer "B.Fab")
		)
		(fp_line
			(start 0.12065 0.3048)
			(end 0.67945 0.3048)
			(stroke
				(width 0.1)
				(type default)
			)
			(layer "B.Fab")
		)
		(fp_line
			(start -0.120396 0.3048)
			(end -0.120396 0.2794)
			(stroke
				(width 0.1)
				(type default)
			)
			(layer "B.Fab")
		)
		(fp_line
			(start -0.67945 0.3048)
			(end -0.120396 0.3048)
			(stroke
				(width 0.1)
				(type default)
			)
			(layer "B.Fab")
		)
		(pad "1" smd circle
			(at 0.40005 0 270)
			(size 0 0)
			(layers "B.Cu" "B.Mask" "B.Paste")
			(net "P12V_HSC_ADC_N")
		)
		(pad "2" smd circle
			(at -0.40005 0 270)
			(size 0 0)
			(layers "B.Cu" "B.Mask" "B.Paste")
			(net "P12V_HSC_SENSE2_R3_N")
		)
	)
	(footprint ""
		(layer "B.Cu")
		(at 62.246764 -318.993774 -90)
		(property "Reference" "R43"
			(at 0 0 90)
			(layer "B.SilkS")
			(hide yes)
			(effects
				(font
					(size 1.27 1.27)
				)
				(justify mirror)
			)
		)
		(property "Value" ""
			(at 0 0 90)
			(layer "B.Fab")
			(effects
				(font
					(size 1.27 1.27)
				)
				(justify mirror)
			)
		)
		(duplicate_pad_numbers_are_jumpers no)
		(fp_line
			(start -0.7874 0.4064)
			(end 0.7874 0.4064)
			(stroke
				(width 0.1524)
				(type default)
			)
			(layer "B.SilkS")
		)
		(fp_line
			(start 0.7874 0.4064)
			(end 0.7874 -0.4064)
			(stroke
				(width 0.1524)
				(type default)
			)
			(layer "B.SilkS")
		)
		(fp_line
			(start -0.7874 -0.4064)
			(end -0.7874 0.4064)
			(stroke
				(width 0.1524)
				(type default)
			)
			(layer "B.SilkS")
		)
		(fp_line
			(start 0.7874 -0.4064)
			(end -0.7874 -0.4064)
			(stroke
				(width 0.1524)
				(type default)
			)
			(layer "B.SilkS")
		)
		(fp_line
			(start -0.67945 0.3048)
			(end -0.120396 0.3048)
			(stroke
				(width 0.1)
				(type default)
			)
			(layer "B.Fab")
		)
		(fp_line
			(start -0.120396 0.3048)
			(end -0.120396 0.2794)
			(stroke
				(width 0.1)
				(type default)
			)
			(layer "B.Fab")
		)
		(fp_line
			(start 0.12065 0.3048)
			(end 0.67945 0.3048)
			(stroke
				(width 0.1)
				(type default)
			)
			(layer "B.Fab")
		)
		(fp_line
			(start 0.67945 0.3048)
			(end 0.67945 -0.305054)
			(stroke
				(width 0.1)
				(type default)
			)
			(layer "B.Fab")
		)
		(fp_line
			(start -0.120396 0.2794)
			(end 0.12065 0.2794)
			(stroke
				(width 0.1)
				(type default)
			)
			(layer "B.Fab")
		)
		(fp_line
			(start 0.12065 0.2794)
			(end 0.12065 0.3048)
			(stroke
				(width 0.1)
				(type default)
			)
			(layer "B.Fab")
		)
		(fp_line
			(start -0.12065 -0.2794)
			(end -0.12065 -0.3048)
			(stroke
				(width 0.1)
				(type default)
			)
			(layer "B.Fab")
		)
		(fp_line
			(start 0.12065 -0.2794)
			(end -0.12065 -0.2794)
			(stroke
				(width 0.1)
				(type default)
			)
			(layer "B.Fab")
		)
		(fp_line
			(start -0.67945 -0.3048)
			(end -0.67945 0.3048)
			(stroke
				(width 0.1)
				(type default)
			)
			(layer "B.Fab")
		)
		(fp_line
			(start -0.12065 -0.3048)
			(end -0.67945 -0.3048)
			(stroke
				(width 0.1)
				(type default)
			)
			(layer "B.Fab")
		)
		(fp_line
			(start 0.12065 -0.305054)
			(end 0.12065 -0.2794)
			(stroke
				(width 0.1)
				(type default)
			)
			(layer "B.Fab")
		)
		(fp_line
			(start 0.67945 -0.305054)
			(end 0.12065 -0.305054)
			(stroke
				(width 0.1)
				(type default)
			)
			(layer "B.Fab")
		)
		(pad "1" smd circle
			(at 0.40005 0 90)
			(size 0 0)
			(layers "B.Cu" "B.Mask" "B.Paste")
			(net "PD_CHA_CPU1_DIMM2_SAA")
		)
		(pad "2" smd circle
			(at -0.40005 0 90)
			(size 0 0)
			(layers "B.Cu" "B.Mask" "B.Paste")
			(net "GND")
		)
	)
	(footprint ""
		(layer "B.Cu")
		(at 62.996572 -153.08326)
		(property "Reference" "PC455_P1_1"
			(at 0 0 0)
			(layer "B.SilkS")
			(hide yes)
			(effects
				(font
					(size 1.27 1.27)
				)
				(justify mirror)
			)
		)
		(property "Value" ""
			(at 0 0 0)
			(layer "B.Fab")
			(effects
				(font
					(size 1.27 1.27)
				)
				(justify mirror)
			)
		)
		(duplicate_pad_numbers_are_jumpers no)
		(fp_line
			(start -1.524 -0.762)
			(end -1.524 0.762)
			(stroke
				(width 0.1524)
				(type default)
			)
			(layer "B.SilkS")
		)
		(fp_line
			(start -1.524 0.762)
			(end 1.524 0.762)
			(stroke
				(width 0.1524)
				(type default)
			)
			(layer "B.SilkS")
		)
		(fp_line
			(start 1.524 -0.762)
			(end -1.524 -0.762)
			(stroke
				(width 0.1524)
				(type default)
			)
			(layer "B.SilkS")
		)
		(fp_line
			(start 1.524 0.762)
			(end 1.524 -0.762)
			(stroke
				(width 0.1524)
				(type default)
			)
			(layer "B.SilkS")
		)
		(fp_line
			(start -1.1049 -0.724916)
			(end 1.1049 -0.724916)
			(stroke
				(width 0.1)
				(type default)
			)
			(layer "B.Fab")
		)
		(fp_line
			(start -1.1049 0.724916)
			(end -1.1049 -0.724916)
			(stroke
				(width 0.1)
				(type default)
			)
			(layer "B.Fab")
		)
		(fp_line
			(start 1.1049 -0.724916)
			(end 1.1049 0.724916)
			(stroke
				(width 0.1)
				(type default)
			)
			(layer "B.Fab")
		)
		(fp_line
			(start 1.1049 0.724916)
			(end -1.1049 0.724916)
			(stroke
				(width 0.1)
				(type default)
			)
			(layer "B.Fab")
		)
		(pad "1" smd rect
			(at 0.889 0)
			(size 1.016 1.27)
			(layers "B.Cu" "B.Mask" "B.Paste")
			(net "PVCCINFAON_CPU1")
		)
		(pad "2" smd rect
			(at -0.889 0)
			(size 1.016 1.27)
			(layers "B.Cu" "B.Mask" "B.Paste")
			(net "GND")
		)
	)
	(footprint ""
		(layer "B.Cu")
		(at 378.7013 -337.145884 90)
		(property "Reference" "PC259_P0_5"
			(at 0 0 90)
			(layer "B.SilkS")
			(hide yes)
			(effects
				(font
					(size 1.27 1.27)
				)
				(justify mirror)
			)
		)
		(property "Value" ""
			(at 0 0 90)
			(layer "B.Fab")
			(effects
				(font
					(size 1.27 1.27)
				)
				(justify mirror)
			)
		)
		(duplicate_pad_numbers_are_jumpers no)
		(fp_line
			(start 1.524 -0.762)
			(end -1.524 -0.762)
			(stroke
				(width 0.1524)
				(type default)
			)
			(layer "B.SilkS")
		)
		(fp_line
			(start -1.524 -0.762)
			(end -1.524 0.762)
			(stroke
				(width 0.1524)
				(type default)
			)
			(layer "B.SilkS")
		)
		(fp_line
			(start 1.524 0.762)
			(end 1.524 -0.762)
			(stroke
				(width 0.1524)
				(type default)
			)
			(layer "B.SilkS")
		)
		(fp_line
			(start -1.524 0.762)
			(end 1.524 0.762)
			(stroke
				(width 0.1524)
				(type default)
			)
			(layer "B.SilkS")
		)
		(fp_line
			(start 1.1049 -0.724916)
			(end 1.1049 0.724916)
			(stroke
				(width 0.1)
				(type default)
			)
			(layer "B.Fab")
		)
		(fp_line
			(start -1.1049 -0.724916)
			(end 1.1049 -0.724916)
			(stroke
				(width 0.1)
				(type default)
			)
			(layer "B.Fab")
		)
		(fp_line
			(start 1.1049 0.724916)
			(end -1.1049 0.724916)
			(stroke
				(width 0.1)
				(type default)
			)
			(layer "B.Fab")
		)
		(fp_line
			(start -1.1049 0.724916)
			(end -1.1049 -0.724916)
			(stroke
				(width 0.1)
				(type default)
			)
			(layer "B.Fab")
		)
		(pad "1" smd rect
			(at 0.889 0 90)
			(size 1.016 1.27)
			(layers "B.Cu" "B.Mask" "B.Paste")
			(net "SW_P12V_PVCCIN_CPU0_FLT")
		)
		(pad "2" smd rect
			(at -0.889 0 90)
			(size 1.016 1.27)
			(layers "B.Cu" "B.Mask" "B.Paste")
			(net "GND")
		)
	)
	(footprint ""
		(layer "B.Cu")
		(at 409.140152 -193.08953 -90)
		(property "Reference" "R280"
			(at 0 0 90)
			(layer "B.SilkS")
			(hide yes)
			(effects
				(font
					(size 1.27 1.27)
				)
				(justify mirror)
			)
		)
		(property "Value" ""
			(at 0 0 90)
			(layer "B.Fab")
			(effects
				(font
					(size 1.27 1.27)
				)
				(justify mirror)
			)
		)
		(duplicate_pad_numbers_are_jumpers no)
		(fp_line
			(start -0.7874 0.4064)
			(end 0.7874 0.4064)
			(stroke
				(width 0.1524)
				(type default)
			)
			(layer "B.SilkS")
		)
		(fp_line
			(start 0.7874 0.4064)
			(end 0.7874 -0.4064)
			(stroke
				(width 0.1524)
				(type default)
			)
			(layer "B.SilkS")
		)
		(fp_line
			(start -0.7874 -0.4064)
			(end -0.7874 0.4064)
			(stroke
				(width 0.1524)
				(type default)
			)
			(layer "B.SilkS")
		)
		(fp_line
			(start 0.7874 -0.4064)
			(end -0.7874 -0.4064)
			(stroke
				(width 0.1524)
				(type default)
			)
			(layer "B.SilkS")
		)
		(fp_line
			(start -0.67945 0.3048)
			(end -0.120396 0.3048)
			(stroke
				(width 0.1)
				(type default)
			)
			(layer "B.Fab")
		)
		(fp_line
			(start -0.120396 0.3048)
			(end -0.120396 0.2794)
			(stroke
				(width 0.1)
				(type default)
			)
			(layer "B.Fab")
		)
		(fp_line
			(start 0.12065 0.3048)
			(end 0.67945 0.3048)
			(stroke
				(width 0.1)
				(type default)
			)
			(layer "B.Fab")
		)
		(fp_line
			(start 0.67945 0.3048)
			(end 0.67945 -0.305054)
			(stroke
				(width 0.1)
				(type default)
			)
			(layer "B.Fab")
		)
		(fp_line
			(start -0.120396 0.2794)
			(end 0.12065 0.2794)
			(stroke
				(width 0.1)
				(type default)
			)
			(layer "B.Fab")
		)
		(fp_line
			(start 0.12065 0.2794)
			(end 0.12065 0.3048)
			(stroke
				(width 0.1)
				(type default)
			)
			(layer "B.Fab")
		)
		(fp_line
			(start -0.12065 -0.2794)
			(end -0.12065 -0.3048)
			(stroke
				(width 0.1)
				(type default)
			)
			(layer "B.Fab")
		)
		(fp_line
			(start 0.12065 -0.2794)
			(end -0.12065 -0.2794)
			(stroke
				(width 0.1)
				(type default)
			)
			(layer "B.Fab")
		)
		(fp_line
			(start -0.67945 -0.3048)
			(end -0.67945 0.3048)
			(stroke
				(width 0.1)
				(type default)
			)
			(layer "B.Fab")
		)
		(fp_line
			(start -0.12065 -0.3048)
			(end -0.67945 -0.3048)
			(stroke
				(width 0.1)
				(type default)
			)
			(layer "B.Fab")
		)
		(fp_line
			(start 0.12065 -0.305054)
			(end 0.12065 -0.2794)
			(stroke
				(width 0.1)
				(type default)
			)
			(layer "B.Fab")
		)
		(fp_line
			(start 0.67945 -0.305054)
			(end 0.12065 -0.305054)
			(stroke
				(width 0.1)
				(type default)
			)
			(layer "B.Fab")
		)
		(pad "1" smd circle
			(at 0.40005 0 90)
			(size 0 0)
			(layers "B.Cu" "B.Mask" "B.Paste")
			(net "PVNN_TERM_CPU0")
		)
		(pad "2" smd circle
			(at -0.40005 0 90)
			(size 0 0)
			(layers "B.Cu" "B.Mask" "B.Paste")
			(net "PU_CPU0_SOCKET_ID1")
		)
	)
	(footprint ""
		(layer "B.Cu")
		(at 12.666472 -184.625996)
		(property "Reference" "R2479"
			(at 0 0 0)
			(layer "B.SilkS")
			(hide yes)
			(effects
				(font
					(size 1.27 1.27)
				)
				(justify mirror)
			)
		)
		(property "Value" ""
			(at 0 0 0)
			(layer "B.Fab")
			(effects
				(font
					(size 1.27 1.27)
				)
				(justify mirror)
			)
		)
		(duplicate_pad_numbers_are_jumpers no)
		(fp_line
			(start -0.7874 -0.4064)
			(end -0.7874 0.4064)
			(stroke
				(width 0.1524)
				(type default)
			)
			(layer "B.SilkS")
		)
		(fp_line
			(start -0.7874 0.4064)
			(end 0.7874 0.4064)
			(stroke
				(width 0.1524)
				(type default)
			)
			(layer "B.SilkS")
		)
		(fp_line
			(start 0.7874 -0.4064)
			(end -0.7874 -0.4064)
			(stroke
				(width 0.1524)
				(type default)
			)
			(layer "B.SilkS")
		)
		(fp_line
			(start 0.7874 0.4064)
			(end 0.7874 -0.4064)
			(stroke
				(width 0.1524)
				(type default)
			)
			(layer "B.SilkS")
		)
		(fp_line
			(start -0.67945 -0.3048)
			(end -0.67945 0.3048)
			(stroke
				(width 0.1)
				(type default)
			)
			(layer "B.Fab")
		)
		(fp_line
			(start -0.67945 0.3048)
			(end -0.120396 0.3048)
			(stroke
				(width 0.1)
				(type default)
			)
			(layer "B.Fab")
		)
		(fp_line
			(start -0.12065 -0.3048)
			(end -0.67945 -0.3048)
			(stroke
				(width 0.1)
				(type default)
			)
			(layer "B.Fab")
		)
		(fp_line
			(start -0.12065 -0.2794)
			(end -0.12065 -0.3048)
			(stroke
				(width 0.1)
				(type default)
			)
			(layer "B.Fab")
		)
		(fp_line
			(start -0.120396 0.2794)
			(end 0.12065 0.2794)
			(stroke
				(width 0.1)
				(type default)
			)
			(layer "B.Fab")
		)
		(fp_line
			(start -0.120396 0.3048)
			(end -0.120396 0.2794)
			(stroke
				(width 0.1)
				(type default)
			)
			(layer "B.Fab")
		)
		(fp_line
			(start 0.12065 -0.305054)
			(end 0.12065 -0.2794)
			(stroke
				(width 0.1)
				(type default)
			)
			(layer "B.Fab")
		)
		(fp_line
			(start 0.12065 -0.2794)
			(end -0.12065 -0.2794)
			(stroke
				(width 0.1)
				(type default)
			)
			(layer "B.Fab")
		)
		(fp_line
			(start 0.12065 0.2794)
			(end 0.12065 0.3048)
			(stroke
				(width 0.1)
				(type default)
			)
			(layer "B.Fab")
		)
		(fp_line
			(start 0.12065 0.3048)
			(end 0.67945 0.3048)
			(stroke
				(width 0.1)
				(type default)
			)
			(layer "B.Fab")
		)
		(fp_line
			(start 0.67945 -0.305054)
			(end 0.12065 -0.305054)
			(stroke
				(width 0.1)
				(type default)
			)
			(layer "B.Fab")
		)
		(fp_line
			(start 0.67945 0.3048)
			(end 0.67945 -0.305054)
			(stroke
				(width 0.1)
				(type default)
			)
			(layer "B.Fab")
		)
		(pad "1" smd circle
			(at 0.40005 0 180)
			(size 0 0)
			(layers "B.Cu" "B.Mask" "B.Paste")
			(net "SMB_PEHPCPU1_LVC3_SCL_R0")
		)
		(pad "2" smd circle
			(at -0.40005 0 180)
			(size 0 0)
			(layers "B.Cu" "B.Mask" "B.Paste")
			(net "SMB_PEHPCPU1_LVC3_SCL")
		)
	)
	(footprint ""
		(layer "B.Cu")
		(at 380.977648 -328.65187 -90)
		(property "Reference" "PC269_P0_5"
			(at 0 0 90)
			(layer "B.SilkS")
			(hide yes)
			(effects
				(font
					(size 1.27 1.27)
				)
				(justify mirror)
			)
		)
		(property "Value" ""
			(at 0 0 90)
			(layer "B.Fab")
			(effects
				(font
					(size 1.27 1.27)
				)
				(justify mirror)
			)
		)
		(duplicate_pad_numbers_are_jumpers no)
		(fp_line
			(start -1.524 0.762)
			(end 1.524 0.762)
			(stroke
				(width 0.1524)
				(type default)
			)
			(layer "B.SilkS")
		)
		(fp_line
			(start 1.524 0.762)
			(end 1.524 -0.762)
			(stroke
				(width 0.1524)
				(type default)
			)
			(layer "B.SilkS")
		)
		(fp_line
			(start -1.524 -0.762)
			(end -1.524 0.762)
			(stroke
				(width 0.1524)
				(type default)
			)
			(layer "B.SilkS")
		)
		(fp_line
			(start 1.524 -0.762)
			(end -1.524 -0.762)
			(stroke
				(width 0.1524)
				(type default)
			)
			(layer "B.SilkS")
		)
		(fp_line
			(start -1.1049 0.724916)
			(end -1.1049 -0.724916)
			(stroke
				(width 0.1)
				(type default)
			)
			(layer "B.Fab")
		)
		(fp_line
			(start 1.1049 0.724916)
			(end -1.1049 0.724916)
			(stroke
				(width 0.1)
				(type default)
			)
			(layer "B.Fab")
		)
		(fp_line
			(start -1.1049 -0.724916)
			(end 1.1049 -0.724916)
			(stroke
				(width 0.1)
				(type default)
			)
			(layer "B.Fab")
		)
		(fp_line
			(start 1.1049 -0.724916)
			(end 1.1049 0.724916)
			(stroke
				(width 0.1)
				(type default)
			)
			(layer "B.Fab")
		)
		(pad "1" smd rect
			(at 0.889 0 270)
			(size 1.016 1.27)
			(layers "B.Cu" "B.Mask" "B.Paste")
			(net "PVCCIN_CPU0")
		)
		(pad "2" smd rect
			(at -0.889 0 270)
			(size 1.016 1.27)
			(layers "B.Cu" "B.Mask" "B.Paste")
			(net "GND")
		)
	)
	(footprint ""
		(layer "B.Cu")
		(at 256.09169 -319.48374 180)
		(property "Reference" "C20"
			(at 0 0 0)
			(layer "B.SilkS")
			(hide yes)
			(effects
				(font
					(size 1.27 1.27)
				)
				(justify mirror)
			)
		)
		(property "Value" ""
			(at 0 0 0)
			(layer "B.Fab")
			(effects
				(font
					(size 1.27 1.27)
				)
				(justify mirror)
			)
		)
		(duplicate_pad_numbers_are_jumpers no)
		(fp_line
			(start 0.7874 0.4064)
			(end 0.7874 -0.4064)
			(stroke
				(width 0.1524)
				(type default)
			)
			(layer "B.SilkS")
		)
		(fp_line
			(start 0.7874 -0.4064)
			(end -0.7874 -0.4064)
			(stroke
				(width 0.1524)
				(type default)
			)
			(layer "B.SilkS")
		)
		(fp_line
			(start -0.7874 0.4064)
			(end 0.7874 0.4064)
			(stroke
				(width 0.1524)
				(type default)
			)
			(layer "B.SilkS")
		)
		(fp_line
			(start -0.7874 -0.4064)
			(end -0.7874 0.4064)
			(stroke
				(width 0.1524)
				(type default)
			)
			(layer "B.SilkS")
		)
		(fp_line
			(start 0.67945 0.3048)
			(end 0.67945 -0.305054)
			(stroke
				(width 0.1)
				(type default)
			)
			(layer "B.Fab")
		)
		(fp_line
			(start 0.67945 -0.305054)
			(end 0.12065 -0.305054)
			(stroke
				(width 0.1)
				(type default)
			)
			(layer "B.Fab")
		)
		(fp_line
			(start 0.12065 0.3048)
			(end 0.67945 0.3048)
			(stroke
				(width 0.1)
				(type default)
			)
			(layer "B.Fab")
		)
		(fp_line
			(start 0.12065 0.2794)
			(end 0.12065 0.3048)
			(stroke
				(width 0.1)
				(type default)
			)
			(layer "B.Fab")
		)
		(fp_line
			(start 0.12065 -0.2794)
			(end -0.12065 -0.2794)
			(stroke
				(width 0.1)
				(type default)
			)
			(layer "B.Fab")
		)
		(fp_line
			(start 0.12065 -0.305054)
			(end 0.12065 -0.2794)
			(stroke
				(width 0.1)
				(type default)
			)
			(layer "B.Fab")
		)
		(fp_line
			(start -0.120396 0.3048)
			(end -0.120396 0.2794)
			(stroke
				(width 0.1)
				(type default)
			)
			(layer "B.Fab")
		)
		(fp_line
			(start -0.120396 0.2794)
			(end 0.12065 0.2794)
			(stroke
				(width 0.1)
				(type default)
			)
			(layer "B.Fab")
		)
		(fp_line
			(start -0.12065 -0.2794)
			(end -0.12065 -0.3048)
			(stroke
				(width 0.1)
				(type default)
			)
			(layer "B.Fab")
		)
		(fp_line
			(start -0.12065 -0.3048)
			(end -0.67945 -0.3048)
			(stroke
				(width 0.1)
				(type default)
			)
			(layer "B.Fab")
		)
		(fp_line
			(start -0.67945 0.3048)
			(end -0.120396 0.3048)
			(stroke
				(width 0.1)
				(type default)
			)
			(layer "B.Fab")
		)
		(fp_line
			(start -0.67945 -0.3048)
			(end -0.67945 0.3048)
			(stroke
				(width 0.1)
				(type default)
			)
			(layer "B.Fab")
		)
		(pad "1" smd circle
			(at 0.40005 0)
			(size 0 0)
			(layers "B.Cu" "B.Mask" "B.Paste")
			(net "P3V3_AUX")
		)
		(pad "2" smd circle
			(at -0.40005 0)
			(size 0 0)
			(layers "B.Cu" "B.Mask" "B.Paste")
			(net "GND")
		)
	)
	(footprint ""
		(layer "B.Cu")
		(at 346.497148 -32.58439 180)
		(property "Reference" "R2342"
			(at 0 0 0)
			(layer "B.SilkS")
			(hide yes)
			(effects
				(font
					(size 1.27 1.27)
				)
				(justify mirror)
			)
		)
		(property "Value" ""
			(at 0 0 0)
			(layer "B.Fab")
			(effects
				(font
					(size 1.27 1.27)
				)
				(justify mirror)
			)
		)
		(duplicate_pad_numbers_are_jumpers no)
		(fp_line
			(start 0.7874 0.4064)
			(end 0.7874 -0.4064)
			(stroke
				(width 0.1524)
				(type default)
			)
			(layer "B.SilkS")
		)
		(fp_line
			(start 0.7874 -0.4064)
			(end -0.7874 -0.4064)
			(stroke
				(width 0.1524)
				(type default)
			)
			(layer "B.SilkS")
		)
		(fp_line
			(start -0.7874 0.4064)
			(end 0.7874 0.4064)
			(stroke
				(width 0.1524)
				(type default)
			)
			(layer "B.SilkS")
		)
		(fp_line
			(start -0.7874 -0.4064)
			(end -0.7874 0.4064)
			(stroke
				(width 0.1524)
				(type default)
			)
			(layer "B.SilkS")
		)
		(fp_line
			(start 0.67945 0.3048)
			(end 0.67945 -0.305054)
			(stroke
				(width 0.1)
				(type default)
			)
			(layer "B.Fab")
		)
		(fp_line
			(start 0.67945 -0.305054)
			(end 0.12065 -0.305054)
			(stroke
				(width 0.1)
				(type default)
			)
			(layer "B.Fab")
		)
		(fp_line
			(start 0.12065 0.3048)
			(end 0.67945 0.3048)
			(stroke
				(width 0.1)
				(type default)
			)
			(layer "B.Fab")
		)
		(fp_line
			(start 0.12065 0.2794)
			(end 0.12065 0.3048)
			(stroke
				(width 0.1)
				(type default)
			)
			(layer "B.Fab")
		)
		(fp_line
			(start 0.12065 -0.2794)
			(end -0.12065 -0.2794)
			(stroke
				(width 0.1)
				(type default)
			)
			(layer "B.Fab")
		)
		(fp_line
			(start 0.12065 -0.305054)
			(end 0.12065 -0.2794)
			(stroke
				(width 0.1)
				(type default)
			)
			(layer "B.Fab")
		)
		(fp_line
			(start -0.120396 0.3048)
			(end -0.120396 0.2794)
			(stroke
				(width 0.1)
				(type default)
			)
			(layer "B.Fab")
		)
		(fp_line
			(start -0.120396 0.2794)
			(end 0.12065 0.2794)
			(stroke
				(width 0.1)
				(type default)
			)
			(layer "B.Fab")
		)
		(fp_line
			(start -0.12065 -0.2794)
			(end -0.12065 -0.3048)
			(stroke
				(width 0.1)
				(type default)
			)
			(layer "B.Fab")
		)
		(fp_line
			(start -0.12065 -0.3048)
			(end -0.67945 -0.3048)
			(stroke
				(width 0.1)
				(type default)
			)
			(layer "B.Fab")
		)
		(fp_line
			(start -0.67945 0.3048)
			(end -0.120396 0.3048)
			(stroke
				(width 0.1)
				(type default)
			)
			(layer "B.Fab")
		)
		(fp_line
			(start -0.67945 -0.3048)
			(end -0.67945 0.3048)
			(stroke
				(width 0.1)
				(type default)
			)
			(layer "B.Fab")
		)
		(pad "1" smd circle
			(at 0.40005 0)
			(size 0 0)
			(layers "B.Cu" "B.Mask" "B.Paste")
			(net "P3V3_AUX")
		)
		(pad "2" smd circle
			(at -0.40005 0)
			(size 0 0)
			(layers "B.Cu" "B.Mask" "B.Paste")
			(net "FM_DEBUG_PORT_PRSNT_R_N")
		)
	)
	(footprint ""
		(layer "B.Cu")
		(at 327.060814 -28.84297 -90)
		(property "Reference" "R1461"
			(at 0 0 90)
			(layer "B.SilkS")
			(hide yes)
			(effects
				(font
					(size 1.27 1.27)
				)
				(justify mirror)
			)
		)
		(property "Value" ""
			(at 0 0 90)
			(layer "B.Fab")
			(effects
				(font
					(size 1.27 1.27)
				)
				(justify mirror)
			)
		)
		(duplicate_pad_numbers_are_jumpers no)
		(fp_line
			(start -0.7874 0.4064)
			(end 0.7874 0.4064)
			(stroke
				(width 0.1524)
				(type default)
			)
			(layer "B.SilkS")
		)
		(fp_line
			(start 0.7874 0.4064)
			(end 0.7874 -0.4064)
			(stroke
				(width 0.1524)
				(type default)
			)
			(layer "B.SilkS")
		)
		(fp_line
			(start -0.7874 -0.4064)
			(end -0.7874 0.4064)
			(stroke
				(width 0.1524)
				(type default)
			)
			(layer "B.SilkS")
		)
		(fp_line
			(start 0.7874 -0.4064)
			(end -0.7874 -0.4064)
			(stroke
				(width 0.1524)
				(type default)
			)
			(layer "B.SilkS")
		)
		(fp_line
			(start -0.67945 0.3048)
			(end -0.120396 0.3048)
			(stroke
				(width 0.1)
				(type default)
			)
			(layer "B.Fab")
		)
		(fp_line
			(start -0.120396 0.3048)
			(end -0.120396 0.2794)
			(stroke
				(width 0.1)
				(type default)
			)
			(layer "B.Fab")
		)
		(fp_line
			(start 0.12065 0.3048)
			(end 0.67945 0.3048)
			(stroke
				(width 0.1)
				(type default)
			)
			(layer "B.Fab")
		)
		(fp_line
			(start 0.67945 0.3048)
			(end 0.67945 -0.305054)
			(stroke
				(width 0.1)
				(type default)
			)
			(layer "B.Fab")
		)
		(fp_line
			(start -0.120396 0.2794)
			(end 0.12065 0.2794)
			(stroke
				(width 0.1)
				(type default)
			)
			(layer "B.Fab")
		)
		(fp_line
			(start 0.12065 0.2794)
			(end 0.12065 0.3048)
			(stroke
				(width 0.1)
				(type default)
			)
			(layer "B.Fab")
		)
		(fp_line
			(start -0.12065 -0.2794)
			(end -0.12065 -0.3048)
			(stroke
				(width 0.1)
				(type default)
			)
			(layer "B.Fab")
		)
		(fp_line
			(start 0.12065 -0.2794)
			(end -0.12065 -0.2794)
			(stroke
				(width 0.1)
				(type default)
			)
			(layer "B.Fab")
		)
		(fp_line
			(start -0.67945 -0.3048)
			(end -0.67945 0.3048)
			(stroke
				(width 0.1)
				(type default)
			)
			(layer "B.Fab")
		)
		(fp_line
			(start -0.12065 -0.3048)
			(end -0.67945 -0.3048)
			(stroke
				(width 0.1)
				(type default)
			)
			(layer "B.Fab")
		)
		(fp_line
			(start 0.12065 -0.305054)
			(end 0.12065 -0.2794)
			(stroke
				(width 0.1)
				(type default)
			)
			(layer "B.Fab")
		)
		(fp_line
			(start 0.67945 -0.305054)
			(end 0.12065 -0.305054)
			(stroke
				(width 0.1)
				(type default)
			)
			(layer "B.Fab")
		)
		(pad "1" smd circle
			(at 0.40005 0 90)
			(size 0 0)
			(layers "B.Cu" "B.Mask" "B.Paste")
			(net "FM_EUP_LOT6_N")
		)
		(pad "2" smd circle
			(at -0.40005 0 90)
			(size 0 0)
			(layers "B.Cu" "B.Mask" "B.Paste")
			(net "FM_SUSACK_N")
		)
	)
	(footprint ""
		(layer "B.Cu")
		(at 337.166712 -31.693358 90)
		(property "Reference" "R917"
			(at 0 0 90)
			(layer "B.SilkS")
			(hide yes)
			(effects
				(font
					(size 1.27 1.27)
				)
				(justify mirror)
			)
		)
		(property "Value" ""
			(at 0 0 90)
			(layer "B.Fab")
			(effects
				(font
					(size 1.27 1.27)
				)
				(justify mirror)
			)
		)
		(duplicate_pad_numbers_are_jumpers no)
		(fp_line
			(start 0.7874 -0.4064)
			(end -0.7874 -0.4064)
			(stroke
				(width 0.1524)
				(type default)
			)
			(layer "B.SilkS")
		)
		(fp_line
			(start -0.7874 -0.4064)
			(end -0.7874 0.4064)
			(stroke
				(width 0.1524)
				(type default)
			)
			(layer "B.SilkS")
		)
		(fp_line
			(start 0.7874 0.4064)
			(end 0.7874 -0.4064)
			(stroke
				(width 0.1524)
				(type default)
			)
			(layer "B.SilkS")
		)
		(fp_line
			(start -0.7874 0.4064)
			(end 0.7874 0.4064)
			(stroke
				(width 0.1524)
				(type default)
			)
			(layer "B.SilkS")
		)
		(fp_line
			(start 0.67945 -0.305054)
			(end 0.12065 -0.305054)
			(stroke
				(width 0.1)
				(type default)
			)
			(layer "B.Fab")
		)
		(fp_line
			(start 0.12065 -0.305054)
			(end 0.12065 -0.2794)
			(stroke
				(width 0.1)
				(type default)
			)
			(layer "B.Fab")
		)
		(fp_line
			(start -0.12065 -0.3048)
			(end -0.67945 -0.3048)
			(stroke
				(width 0.1)
				(type default)
			)
			(layer "B.Fab")
		)
		(fp_line
			(start -0.67945 -0.3048)
			(end -0.67945 0.3048)
			(stroke
				(width 0.1)
				(type default)
			)
			(layer "B.Fab")
		)
		(fp_line
			(start 0.12065 -0.2794)
			(end -0.12065 -0.2794)
			(stroke
				(width 0.1)
				(type default)
			)
			(layer "B.Fab")
		)
		(fp_line
			(start -0.12065 -0.2794)
			(end -0.12065 -0.3048)
			(stroke
				(width 0.1)
				(type default)
			)
			(layer "B.Fab")
		)
		(fp_line
			(start 0.12065 0.2794)
			(end 0.12065 0.3048)
			(stroke
				(width 0.1)
				(type default)
			)
			(layer "B.Fab")
		)
		(fp_line
			(start -0.120396 0.2794)
			(end 0.12065 0.2794)
			(stroke
				(width 0.1)
				(type default)
			)
			(layer "B.Fab")
		)
		(fp_line
			(start 0.67945 0.3048)
			(end 0.67945 -0.305054)
			(stroke
				(width 0.1)
				(type default)
			)
			(layer "B.Fab")
		)
		(fp_line
			(start 0.12065 0.3048)
			(end 0.67945 0.3048)
			(stroke
				(width 0.1)
				(type default)
			)
			(layer "B.Fab")
		)
		(fp_line
			(start -0.120396 0.3048)
			(end -0.120396 0.2794)
			(stroke
				(width 0.1)
				(type default)
			)
			(layer "B.Fab")
		)
		(fp_line
			(start -0.67945 0.3048)
			(end -0.120396 0.3048)
			(stroke
				(width 0.1)
				(type default)
			)
			(layer "B.Fab")
		)
		(pad "1" smd circle
			(at 0.40005 0 270)
			(size 0 0)
			(layers "B.Cu" "B.Mask" "B.Paste")
			(net "SPI_PCH_IO3")
		)
		(pad "2" smd circle
			(at -0.40005 0 270)
			(size 0 0)
			(layers "B.Cu" "B.Mask" "B.Paste")
			(net "SPI_SYS_HOLD_IO3")
		)
	)
	(footprint ""
		(layer "B.Cu")
		(at 325.707502 -343.927938 -90)
		(property "Reference" "PR135"
			(at 0 0 90)
			(layer "B.SilkS")
			(hide yes)
			(effects
				(font
					(size 1.27 1.27)
				)
				(justify mirror)
			)
		)
		(property "Value" ""
			(at 0 0 90)
			(layer "B.Fab")
			(effects
				(font
					(size 1.27 1.27)
				)
				(justify mirror)
			)
		)
		(duplicate_pad_numbers_are_jumpers no)
		(fp_line
			(start -0.7874 0.4064)
			(end 0.7874 0.4064)
			(stroke
				(width 0.1524)
				(type default)
			)
			(layer "B.SilkS")
		)
		(fp_line
			(start 0.7874 0.4064)
			(end 0.7874 -0.4064)
			(stroke
				(width 0.1524)
				(type default)
			)
			(layer "B.SilkS")
		)
		(fp_line
			(start -0.7874 -0.4064)
			(end -0.7874 0.4064)
			(stroke
				(width 0.1524)
				(type default)
			)
			(layer "B.SilkS")
		)
		(fp_line
			(start 0.7874 -0.4064)
			(end -0.7874 -0.4064)
			(stroke
				(width 0.1524)
				(type default)
			)
			(layer "B.SilkS")
		)
		(fp_line
			(start -0.67945 0.3048)
			(end -0.120396 0.3048)
			(stroke
				(width 0.1)
				(type default)
			)
			(layer "B.Fab")
		)
		(fp_line
			(start -0.120396 0.3048)
			(end -0.120396 0.2794)
			(stroke
				(width 0.1)
				(type default)
			)
			(layer "B.Fab")
		)
		(fp_line
			(start 0.12065 0.3048)
			(end 0.67945 0.3048)
			(stroke
				(width 0.1)
				(type default)
			)
			(layer "B.Fab")
		)
		(fp_line
			(start 0.67945 0.3048)
			(end 0.67945 -0.305054)
			(stroke
				(width 0.1)
				(type default)
			)
			(layer "B.Fab")
		)
		(fp_line
			(start -0.120396 0.2794)
			(end 0.12065 0.2794)
			(stroke
				(width 0.1)
				(type default)
			)
			(layer "B.Fab")
		)
		(fp_line
			(start 0.12065 0.2794)
			(end 0.12065 0.3048)
			(stroke
				(width 0.1)
				(type default)
			)
			(layer "B.Fab")
		)
		(fp_line
			(start -0.12065 -0.2794)
			(end -0.12065 -0.3048)
			(stroke
				(width 0.1)
				(type default)
			)
			(layer "B.Fab")
		)
		(fp_line
			(start 0.12065 -0.2794)
			(end -0.12065 -0.2794)
			(stroke
				(width 0.1)
				(type default)
			)
			(layer "B.Fab")
		)
		(fp_line
			(start -0.67945 -0.3048)
			(end -0.67945 0.3048)
			(stroke
				(width 0.1)
				(type default)
			)
			(layer "B.Fab")
		)
		(fp_line
			(start -0.12065 -0.3048)
			(end -0.67945 -0.3048)
			(stroke
				(width 0.1)
				(type default)
			)
			(layer "B.Fab")
		)
		(fp_line
			(start 0.12065 -0.305054)
			(end 0.12065 -0.2794)
			(stroke
				(width 0.1)
				(type default)
			)
			(layer "B.Fab")
		)
		(fp_line
			(start 0.67945 -0.305054)
			(end 0.12065 -0.305054)
			(stroke
				(width 0.1)
				(type default)
			)
			(layer "B.Fab")
		)
		(pad "1" smd circle
			(at 0.40005 0 90)
			(size 0 0)
			(layers "B.Cu" "B.Mask" "B.Paste")
			(net "PVCCIN_CPU0_PVCC")
		)
		(pad "2" smd circle
			(at -0.40005 0 90)
			(size 0 0)
			(layers "B.Cu" "B.Mask" "B.Paste")
			(net "PVCCIN_CPU0_VDD7")
		)
	)
	(footprint ""
		(layer "B.Cu")
		(at 271.180814 -317.824358 180)
		(property "Reference" "R3879"
			(at 0 0 0)
			(layer "B.SilkS")
			(hide yes)
			(effects
				(font
					(size 1.27 1.27)
				)
				(justify mirror)
			)
		)
		(property "Value" ""
			(at 0 0 0)
			(layer "B.Fab")
			(effects
				(font
					(size 1.27 1.27)
				)
				(justify mirror)
			)
		)
		(duplicate_pad_numbers_are_jumpers no)
		(fp_line
			(start 0.7874 0.4064)
			(end 0.7874 -0.4064)
			(stroke
				(width 0.1524)
				(type default)
			)
			(layer "B.SilkS")
		)
		(fp_line
			(start 0.7874 -0.4064)
			(end -0.7874 -0.4064)
			(stroke
				(width 0.1524)
				(type default)
			)
			(layer "B.SilkS")
		)
		(fp_line
			(start -0.7874 0.4064)
			(end 0.7874 0.4064)
			(stroke
				(width 0.1524)
				(type default)
			)
			(layer "B.SilkS")
		)
		(fp_line
			(start -0.7874 -0.4064)
			(end -0.7874 0.4064)
			(stroke
				(width 0.1524)
				(type default)
			)
			(layer "B.SilkS")
		)
		(fp_line
			(start 0.67945 0.3048)
			(end 0.67945 -0.305054)
			(stroke
				(width 0.1)
				(type default)
			)
			(layer "B.Fab")
		)
		(fp_line
			(start 0.67945 -0.305054)
			(end 0.12065 -0.305054)
			(stroke
				(width 0.1)
				(type default)
			)
			(layer "B.Fab")
		)
		(fp_line
			(start 0.12065 0.3048)
			(end 0.67945 0.3048)
			(stroke
				(width 0.1)
				(type default)
			)
			(layer "B.Fab")
		)
		(fp_line
			(start 0.12065 0.2794)
			(end 0.12065 0.3048)
			(stroke
				(width 0.1)
				(type default)
			)
			(layer "B.Fab")
		)
		(fp_line
			(start 0.12065 -0.2794)
			(end -0.12065 -0.2794)
			(stroke
				(width 0.1)
				(type default)
			)
			(layer "B.Fab")
		)
		(fp_line
			(start 0.12065 -0.305054)
			(end 0.12065 -0.2794)
			(stroke
				(width 0.1)
				(type default)
			)
			(layer "B.Fab")
		)
		(fp_line
			(start -0.120396 0.3048)
			(end -0.120396 0.2794)
			(stroke
				(width 0.1)
				(type default)
			)
			(layer "B.Fab")
		)
		(fp_line
			(start -0.120396 0.2794)
			(end 0.12065 0.2794)
			(stroke
				(width 0.1)
				(type default)
			)
			(layer "B.Fab")
		)
		(fp_line
			(start -0.12065 -0.2794)
			(end -0.12065 -0.3048)
			(stroke
				(width 0.1)
				(type default)
			)
			(layer "B.Fab")
		)
		(fp_line
			(start -0.12065 -0.3048)
			(end -0.67945 -0.3048)
			(stroke
				(width 0.1)
				(type default)
			)
			(layer "B.Fab")
		)
		(fp_line
			(start -0.67945 0.3048)
			(end -0.120396 0.3048)
			(stroke
				(width 0.1)
				(type default)
			)
			(layer "B.Fab")
		)
		(fp_line
			(start -0.67945 -0.3048)
			(end -0.67945 0.3048)
			(stroke
				(width 0.1)
				(type default)
			)
			(layer "B.Fab")
		)
		(pad "1" smd circle
			(at 0.40005 0)
			(size 0 0)
			(layers "B.Cu" "B.Mask" "B.Paste")
			(net "I3C_SPD_DDRABCD_CPU0_LVC1_SCL_4")
		)
		(pad "2" smd circle
			(at -0.40005 0)
			(size 0 0)
			(layers "B.Cu" "B.Mask" "B.Paste")
			(net "I3C_SPD_DDRABCD_CPU0_LVC1_SCL")
		)
	)
	(footprint ""
		(layer "B.Cu")
		(at 100.306886 -357.53167)
		(property "Reference" "R2554"
			(at 0 0 0)
			(layer "B.SilkS")
			(hide yes)
			(effects
				(font
					(size 1.27 1.27)
				)
				(justify mirror)
			)
		)
		(property "Value" ""
			(at 0 0 0)
			(layer "B.Fab")
			(effects
				(font
					(size 1.27 1.27)
				)
				(justify mirror)
			)
		)
		(duplicate_pad_numbers_are_jumpers no)
		(fp_line
			(start -0.7874 -0.4064)
			(end -0.7874 0.4064)
			(stroke
				(width 0.1524)
				(type default)
			)
			(layer "B.SilkS")
		)
		(fp_line
			(start -0.7874 0.4064)
			(end 0.7874 0.4064)
			(stroke
				(width 0.1524)
				(type default)
			)
			(layer "B.SilkS")
		)
		(fp_line
			(start 0.7874 -0.4064)
			(end -0.7874 -0.4064)
			(stroke
				(width 0.1524)
				(type default)
			)
			(layer "B.SilkS")
		)
		(fp_line
			(start 0.7874 0.4064)
			(end 0.7874 -0.4064)
			(stroke
				(width 0.1524)
				(type default)
			)
			(layer "B.SilkS")
		)
		(fp_line
			(start -0.67945 -0.3048)
			(end -0.67945 0.3048)
			(stroke
				(width 0.1)
				(type default)
			)
			(layer "B.Fab")
		)
		(fp_line
			(start -0.67945 0.3048)
			(end -0.120396 0.3048)
			(stroke
				(width 0.1)
				(type default)
			)
			(layer "B.Fab")
		)
		(fp_line
			(start -0.12065 -0.3048)
			(end -0.67945 -0.3048)
			(stroke
				(width 0.1)
				(type default)
			)
			(layer "B.Fab")
		)
		(fp_line
			(start -0.12065 -0.2794)
			(end -0.12065 -0.3048)
			(stroke
				(width 0.1)
				(type default)
			)
			(layer "B.Fab")
		)
		(fp_line
			(start -0.120396 0.2794)
			(end 0.12065 0.2794)
			(stroke
				(width 0.1)
				(type default)
			)
			(layer "B.Fab")
		)
		(fp_line
			(start -0.120396 0.3048)
			(end -0.120396 0.2794)
			(stroke
				(width 0.1)
				(type default)
			)
			(layer "B.Fab")
		)
		(fp_line
			(start 0.12065 -0.305054)
			(end 0.12065 -0.2794)
			(stroke
				(width 0.1)
				(type default)
			)
			(layer "B.Fab")
		)
		(fp_line
			(start 0.12065 -0.2794)
			(end -0.12065 -0.2794)
			(stroke
				(width 0.1)
				(type default)
			)
			(layer "B.Fab")
		)
		(fp_line
			(start 0.12065 0.2794)
			(end 0.12065 0.3048)
			(stroke
				(width 0.1)
				(type default)
			)
			(layer "B.Fab")
		)
		(fp_line
			(start 0.12065 0.3048)
			(end 0.67945 0.3048)
			(stroke
				(width 0.1)
				(type default)
			)
			(layer "B.Fab")
		)
		(fp_line
			(start 0.67945 -0.305054)
			(end 0.12065 -0.305054)
			(stroke
				(width 0.1)
				(type default)
			)
			(layer "B.Fab")
		)
		(fp_line
			(start 0.67945 0.3048)
			(end 0.67945 -0.305054)
			(stroke
				(width 0.1)
				(type default)
			)
			(layer "B.Fab")
		)
		(pad "1" smd circle
			(at 0.40005 0 180)
			(size 0 0)
			(layers "B.Cu" "B.Mask" "B.Paste")
			(net "SVID_CLK0_CPU1_R")
		)
		(pad "2" smd circle
			(at -0.40005 0 180)
			(size 0 0)
			(layers "B.Cu" "B.Mask" "B.Paste")
			(net "PVNN_TERM_CPU1")
		)
	)
	(footprint ""
		(layer "B.Cu")
		(at 279.119584 -193.669666 -90)
		(property "Reference" "R1391"
			(at 0 0 90)
			(layer "B.SilkS")
			(hide yes)
			(effects
				(font
					(size 1.27 1.27)
				)
				(justify mirror)
			)
		)
		(property "Value" ""
			(at 0 0 90)
			(layer "B.Fab")
			(effects
				(font
					(size 1.27 1.27)
				)
				(justify mirror)
			)
		)
		(duplicate_pad_numbers_are_jumpers no)
		(fp_line
			(start -0.7874 0.4064)
			(end 0.7874 0.4064)
			(stroke
				(width 0.1524)
				(type default)
			)
			(layer "B.SilkS")
		)
		(fp_line
			(start 0.7874 0.4064)
			(end 0.7874 -0.4064)
			(stroke
				(width 0.1524)
				(type default)
			)
			(layer "B.SilkS")
		)
		(fp_line
			(start -0.7874 -0.4064)
			(end -0.7874 0.4064)
			(stroke
				(width 0.1524)
				(type default)
			)
			(layer "B.SilkS")
		)
		(fp_line
			(start 0.7874 -0.4064)
			(end -0.7874 -0.4064)
			(stroke
				(width 0.1524)
				(type default)
			)
			(layer "B.SilkS")
		)
		(fp_line
			(start -0.67945 0.3048)
			(end -0.120396 0.3048)
			(stroke
				(width 0.1)
				(type default)
			)
			(layer "B.Fab")
		)
		(fp_line
			(start -0.120396 0.3048)
			(end -0.120396 0.2794)
			(stroke
				(width 0.1)
				(type default)
			)
			(layer "B.Fab")
		)
		(fp_line
			(start 0.12065 0.3048)
			(end 0.67945 0.3048)
			(stroke
				(width 0.1)
				(type default)
			)
			(layer "B.Fab")
		)
		(fp_line
			(start 0.67945 0.3048)
			(end 0.67945 -0.305054)
			(stroke
				(width 0.1)
				(type default)
			)
			(layer "B.Fab")
		)
		(fp_line
			(start -0.120396 0.2794)
			(end 0.12065 0.2794)
			(stroke
				(width 0.1)
				(type default)
			)
			(layer "B.Fab")
		)
		(fp_line
			(start 0.12065 0.2794)
			(end 0.12065 0.3048)
			(stroke
				(width 0.1)
				(type default)
			)
			(layer "B.Fab")
		)
		(fp_line
			(start -0.12065 -0.2794)
			(end -0.12065 -0.3048)
			(stroke
				(width 0.1)
				(type default)
			)
			(layer "B.Fab")
		)
		(fp_line
			(start 0.12065 -0.2794)
			(end -0.12065 -0.2794)
			(stroke
				(width 0.1)
				(type default)
			)
			(layer "B.Fab")
		)
		(fp_line
			(start -0.67945 -0.3048)
			(end -0.67945 0.3048)
			(stroke
				(width 0.1)
				(type default)
			)
			(layer "B.Fab")
		)
		(fp_line
			(start -0.12065 -0.3048)
			(end -0.67945 -0.3048)
			(stroke
				(width 0.1)
				(type default)
			)
			(layer "B.Fab")
		)
		(fp_line
			(start 0.12065 -0.305054)
			(end 0.12065 -0.2794)
			(stroke
				(width 0.1)
				(type default)
			)
			(layer "B.Fab")
		)
		(fp_line
			(start 0.67945 -0.305054)
			(end 0.12065 -0.305054)
			(stroke
				(width 0.1)
				(type default)
			)
			(layer "B.Fab")
		)
		(pad "1" smd circle
			(at 0.40005 0 90)
			(size 0 0)
			(layers "B.Cu" "B.Mask" "B.Paste")
			(net "GND")
		)
		(pad "2" smd circle
			(at -0.40005 0 90)
			(size 0 0)
			(layers "B.Cu" "B.Mask" "B.Paste")
			(net "FM_S3M_CPU0_LVC1_GPIO_2")
		)
	)
	(footprint ""
		(layer "B.Cu")
		(at 105.679494 -255.8542 -90)
		(property "Reference" "C321"
			(at 0 0 90)
			(layer "B.SilkS")
			(hide yes)
			(effects
				(font
					(size 1.27 1.27)
				)
				(justify mirror)
			)
		)
		(property "Value" ""
			(at 0 0 90)
			(layer "B.Fab")
			(effects
				(font
					(size 1.27 1.27)
				)
				(justify mirror)
			)
		)
		(duplicate_pad_numbers_are_jumpers no)
		(fp_line
			(start -1.524 0.762)
			(end 1.524 0.762)
			(stroke
				(width 0.1524)
				(type default)
			)
			(layer "B.SilkS")
		)
		(fp_line
			(start 1.524 0.762)
			(end 1.524 -0.762)
			(stroke
				(width 0.1524)
				(type default)
			)
			(layer "B.SilkS")
		)
		(fp_line
			(start -1.524 -0.762)
			(end -1.524 0.762)
			(stroke
				(width 0.1524)
				(type default)
			)
			(layer "B.SilkS")
		)
		(fp_line
			(start 1.524 -0.762)
			(end -1.524 -0.762)
			(stroke
				(width 0.1524)
				(type default)
			)
			(layer "B.SilkS")
		)
		(fp_line
			(start -1.1049 0.724916)
			(end -1.1049 -0.724916)
			(stroke
				(width 0.1)
				(type default)
			)
			(layer "B.Fab")
		)
		(fp_line
			(start 1.1049 0.724916)
			(end -1.1049 0.724916)
			(stroke
				(width 0.1)
				(type default)
			)
			(layer "B.Fab")
		)
		(fp_line
			(start -1.1049 -0.724916)
			(end 1.1049 -0.724916)
			(stroke
				(width 0.1)
				(type default)
			)
			(layer "B.Fab")
		)
		(fp_line
			(start 1.1049 -0.724916)
			(end 1.1049 0.724916)
			(stroke
				(width 0.1)
				(type default)
			)
			(layer "B.Fab")
		)
		(pad "1" smd rect
			(at 0.889 0 270)
			(size 1.016 1.27)
			(layers "B.Cu" "B.Mask" "B.Paste")
			(net "PVCCIN_CPU1")
		)
		(pad "2" smd rect
			(at -0.889 0 270)
			(size 1.016 1.27)
			(layers "B.Cu" "B.Mask" "B.Paste")
			(net "GND")
		)
	)
	(footprint ""
		(layer "B.Cu")
		(at 204.133958 -192.95491)
		(property "Reference" "C541"
			(at 0 0 0)
			(layer "B.SilkS")
			(hide yes)
			(effects
				(font
					(size 1.27 1.27)
				)
				(justify mirror)
			)
		)
		(property "Value" ""
			(at 0 0 0)
			(layer "B.Fab")
			(effects
				(font
					(size 1.27 1.27)
				)
				(justify mirror)
			)
		)
		(duplicate_pad_numbers_are_jumpers no)
		(fp_line
			(start -0.7874 -0.4064)
			(end -0.7874 0.4064)
			(stroke
				(width 0.1524)
				(type default)
			)
			(layer "B.SilkS")
		)
		(fp_line
			(start -0.7874 0.4064)
			(end 0.7874 0.4064)
			(stroke
				(width 0.1524)
				(type default)
			)
			(layer "B.SilkS")
		)
		(fp_line
			(start 0.7874 -0.4064)
			(end -0.7874 -0.4064)
			(stroke
				(width 0.1524)
				(type default)
			)
			(layer "B.SilkS")
		)
		(fp_line
			(start 0.7874 0.4064)
			(end 0.7874 -0.4064)
			(stroke
				(width 0.1524)
				(type default)
			)
			(layer "B.SilkS")
		)
		(fp_line
			(start -0.67945 -0.3048)
			(end -0.67945 0.3048)
			(stroke
				(width 0.1)
				(type default)
			)
			(layer "B.Fab")
		)
		(fp_line
			(start -0.67945 0.3048)
			(end -0.120396 0.3048)
			(stroke
				(width 0.1)
				(type default)
			)
			(layer "B.Fab")
		)
		(fp_line
			(start -0.12065 -0.3048)
			(end -0.67945 -0.3048)
			(stroke
				(width 0.1)
				(type default)
			)
			(layer "B.Fab")
		)
		(fp_line
			(start -0.12065 -0.2794)
			(end -0.12065 -0.3048)
			(stroke
				(width 0.1)
				(type default)
			)
			(layer "B.Fab")
		)
		(fp_line
			(start -0.120396 0.2794)
			(end 0.12065 0.2794)
			(stroke
				(width 0.1)
				(type default)
			)
			(layer "B.Fab")
		)
		(fp_line
			(start -0.120396 0.3048)
			(end -0.120396 0.2794)
			(stroke
				(width 0.1)
				(type default)
			)
			(layer "B.Fab")
		)
		(fp_line
			(start 0.12065 -0.305054)
			(end 0.12065 -0.2794)
			(stroke
				(width 0.1)
				(type default)
			)
			(layer "B.Fab")
		)
		(fp_line
			(start 0.12065 -0.2794)
			(end -0.12065 -0.2794)
			(stroke
				(width 0.1)
				(type default)
			)
			(layer "B.Fab")
		)
		(fp_line
			(start 0.12065 0.2794)
			(end 0.12065 0.3048)
			(stroke
				(width 0.1)
				(type default)
			)
			(layer "B.Fab")
		)
		(fp_line
			(start 0.12065 0.3048)
			(end 0.67945 0.3048)
			(stroke
				(width 0.1)
				(type default)
			)
			(layer "B.Fab")
		)
		(fp_line
			(start 0.67945 -0.305054)
			(end 0.12065 -0.305054)
			(stroke
				(width 0.1)
				(type default)
			)
			(layer "B.Fab")
		)
		(fp_line
			(start 0.67945 0.3048)
			(end 0.67945 -0.305054)
			(stroke
				(width 0.1)
				(type default)
			)
			(layer "B.Fab")
		)
		(pad "1" smd circle
			(at 0.40005 0 180)
			(size 0 0)
			(layers "B.Cu" "B.Mask" "B.Paste")
			(net "P3V3_AUX")
		)
		(pad "2" smd circle
			(at -0.40005 0 180)
			(size 0 0)
			(layers "B.Cu" "B.Mask" "B.Paste")
			(net "GND")
		)
	)
	(footprint ""
		(layer "B.Cu")
		(at 150.387304 -190.36411 90)
		(property "Reference" "R672"
			(at 0 0 90)
			(layer "B.SilkS")
			(hide yes)
			(effects
				(font
					(size 1.27 1.27)
				)
				(justify mirror)
			)
		)
		(property "Value" ""
			(at 0 0 90)
			(layer "B.Fab")
			(effects
				(font
					(size 1.27 1.27)
				)
				(justify mirror)
			)
		)
		(duplicate_pad_numbers_are_jumpers no)
		(fp_line
			(start 0.7874 -0.4064)
			(end -0.7874 -0.4064)
			(stroke
				(width 0.1524)
				(type default)
			)
			(layer "B.SilkS")
		)
		(fp_line
			(start -0.7874 -0.4064)
			(end -0.7874 0.4064)
			(stroke
				(width 0.1524)
				(type default)
			)
			(layer "B.SilkS")
		)
		(fp_line
			(start 0.7874 0.4064)
			(end 0.7874 -0.4064)
			(stroke
				(width 0.1524)
				(type default)
			)
			(layer "B.SilkS")
		)
		(fp_line
			(start -0.7874 0.4064)
			(end 0.7874 0.4064)
			(stroke
				(width 0.1524)
				(type default)
			)
			(layer "B.SilkS")
		)
		(fp_line
			(start 0.67945 -0.305054)
			(end 0.12065 -0.305054)
			(stroke
				(width 0.1)
				(type default)
			)
			(layer "B.Fab")
		)
		(fp_line
			(start 0.12065 -0.305054)
			(end 0.12065 -0.2794)
			(stroke
				(width 0.1)
				(type default)
			)
			(layer "B.Fab")
		)
		(fp_line
			(start -0.12065 -0.3048)
			(end -0.67945 -0.3048)
			(stroke
				(width 0.1)
				(type default)
			)
			(layer "B.Fab")
		)
		(fp_line
			(start -0.67945 -0.3048)
			(end -0.67945 0.3048)
			(stroke
				(width 0.1)
				(type default)
			)
			(layer "B.Fab")
		)
		(fp_line
			(start 0.12065 -0.2794)
			(end -0.12065 -0.2794)
			(stroke
				(width 0.1)
				(type default)
			)
			(layer "B.Fab")
		)
		(fp_line
			(start -0.12065 -0.2794)
			(end -0.12065 -0.3048)
			(stroke
				(width 0.1)
				(type default)
			)
			(layer "B.Fab")
		)
		(fp_line
			(start 0.12065 0.2794)
			(end 0.12065 0.3048)
			(stroke
				(width 0.1)
				(type default)
			)
			(layer "B.Fab")
		)
		(fp_line
			(start -0.120396 0.2794)
			(end 0.12065 0.2794)
			(stroke
				(width 0.1)
				(type default)
			)
			(layer "B.Fab")
		)
		(fp_line
			(start 0.67945 0.3048)
			(end 0.67945 -0.305054)
			(stroke
				(width 0.1)
				(type default)
			)
			(layer "B.Fab")
		)
		(fp_line
			(start 0.12065 0.3048)
			(end 0.67945 0.3048)
			(stroke
				(width 0.1)
				(type default)
			)
			(layer "B.Fab")
		)
		(fp_line
			(start -0.120396 0.3048)
			(end -0.120396 0.2794)
			(stroke
				(width 0.1)
				(type default)
			)
			(layer "B.Fab")
		)
		(fp_line
			(start -0.67945 0.3048)
			(end -0.120396 0.3048)
			(stroke
				(width 0.1)
				(type default)
			)
			(layer "B.Fab")
		)
		(pad "1" smd circle
			(at 0.40005 0 270)
			(size 0 0)
			(layers "B.Cu" "B.Mask" "B.Paste")
			(net "I3C_SPD_DDREFGH_CPU1_SCL")
		)
		(pad "2" smd circle
			(at -0.40005 0 270)
			(size 0 0)
			(layers "B.Cu" "B.Mask" "B.Paste")
			(net "I3C_SPD_DDREFGH_CPU1_R_SCL")
		)
	)
	(footprint ""
		(layer "B.Cu")
		(at 184.059576 -13.60043 -90)
		(property "Reference" "R599"
			(at 0 0 90)
			(layer "B.SilkS")
			(hide yes)
			(effects
				(font
					(size 1.27 1.27)
				)
				(justify mirror)
			)
		)
		(property "Value" ""
			(at 0 0 90)
			(layer "B.Fab")
			(effects
				(font
					(size 1.27 1.27)
				)
				(justify mirror)
			)
		)
		(duplicate_pad_numbers_are_jumpers no)
		(fp_line
			(start -0.7874 0.4064)
			(end 0.7874 0.4064)
			(stroke
				(width 0.1524)
				(type default)
			)
			(layer "B.SilkS")
		)
		(fp_line
			(start 0.7874 0.4064)
			(end 0.7874 -0.4064)
			(stroke
				(width 0.1524)
				(type default)
			)
			(layer "B.SilkS")
		)
		(fp_line
			(start -0.7874 -0.4064)
			(end -0.7874 0.4064)
			(stroke
				(width 0.1524)
				(type default)
			)
			(layer "B.SilkS")
		)
		(fp_line
			(start 0.7874 -0.4064)
			(end -0.7874 -0.4064)
			(stroke
				(width 0.1524)
				(type default)
			)
			(layer "B.SilkS")
		)
		(fp_line
			(start -0.67945 0.3048)
			(end -0.120396 0.3048)
			(stroke
				(width 0.1)
				(type default)
			)
			(layer "B.Fab")
		)
		(fp_line
			(start -0.120396 0.3048)
			(end -0.120396 0.2794)
			(stroke
				(width 0.1)
				(type default)
			)
			(layer "B.Fab")
		)
		(fp_line
			(start 0.12065 0.3048)
			(end 0.67945 0.3048)
			(stroke
				(width 0.1)
				(type default)
			)
			(layer "B.Fab")
		)
		(fp_line
			(start 0.67945 0.3048)
			(end 0.67945 -0.305054)
			(stroke
				(width 0.1)
				(type default)
			)
			(layer "B.Fab")
		)
		(fp_line
			(start -0.120396 0.2794)
			(end 0.12065 0.2794)
			(stroke
				(width 0.1)
				(type default)
			)
			(layer "B.Fab")
		)
		(fp_line
			(start 0.12065 0.2794)
			(end 0.12065 0.3048)
			(stroke
				(width 0.1)
				(type default)
			)
			(layer "B.Fab")
		)
		(fp_line
			(start -0.12065 -0.2794)
			(end -0.12065 -0.3048)
			(stroke
				(width 0.1)
				(type default)
			)
			(layer "B.Fab")
		)
		(fp_line
			(start 0.12065 -0.2794)
			(end -0.12065 -0.2794)
			(stroke
				(width 0.1)
				(type default)
			)
			(layer "B.Fab")
		)
		(fp_line
			(start -0.67945 -0.3048)
			(end -0.67945 0.3048)
			(stroke
				(width 0.1)
				(type default)
			)
			(layer "B.Fab")
		)
		(fp_line
			(start -0.12065 -0.3048)
			(end -0.67945 -0.3048)
			(stroke
				(width 0.1)
				(type default)
			)
			(layer "B.Fab")
		)
		(fp_line
			(start 0.12065 -0.305054)
			(end 0.12065 -0.2794)
			(stroke
				(width 0.1)
				(type default)
			)
			(layer "B.Fab")
		)
		(fp_line
			(start 0.67945 -0.305054)
			(end 0.12065 -0.305054)
			(stroke
				(width 0.1)
				(type default)
			)
			(layer "B.Fab")
		)
		(pad "1" smd circle
			(at 0.40005 0 90)
			(size 0 0)
			(layers "B.Cu" "B.Mask" "B.Paste")
			(net "I3C_SPD_DDREFGH_CPU1_BMC_R_SCL")
		)
		(pad "2" smd circle
			(at -0.40005 0 90)
			(size 0 0)
			(layers "B.Cu" "B.Mask" "B.Paste")
			(net "I3C_SPD_DDREFGH_CPU1_BMC_SCL")
		)
	)
	(footprint ""
		(layer "B.Cu")
		(at 152.9969 -13.762228 90)
		(property "Reference" "R2416"
			(at 0 0 90)
			(layer "B.SilkS")
			(hide yes)
			(effects
				(font
					(size 1.27 1.27)
				)
				(justify mirror)
			)
		)
		(property "Value" ""
			(at 0 0 90)
			(layer "B.Fab")
			(effects
				(font
					(size 1.27 1.27)
				)
				(justify mirror)
			)
		)
		(duplicate_pad_numbers_are_jumpers no)
		(fp_line
			(start 0.7874 -0.4064)
			(end -0.7874 -0.4064)
			(stroke
				(width 0.1524)
				(type default)
			)
			(layer "B.SilkS")
		)
		(fp_line
			(start -0.7874 -0.4064)
			(end -0.7874 0.4064)
			(stroke
				(width 0.1524)
				(type default)
			)
			(layer "B.SilkS")
		)
		(fp_line
			(start 0.7874 0.4064)
			(end 0.7874 -0.4064)
			(stroke
				(width 0.1524)
				(type default)
			)
			(layer "B.SilkS")
		)
		(fp_line
			(start -0.7874 0.4064)
			(end 0.7874 0.4064)
			(stroke
				(width 0.1524)
				(type default)
			)
			(layer "B.SilkS")
		)
		(fp_line
			(start 0.67945 -0.305054)
			(end 0.12065 -0.305054)
			(stroke
				(width 0.1)
				(type default)
			)
			(layer "B.Fab")
		)
		(fp_line
			(start 0.12065 -0.305054)
			(end 0.12065 -0.2794)
			(stroke
				(width 0.1)
				(type default)
			)
			(layer "B.Fab")
		)
		(fp_line
			(start -0.12065 -0.3048)
			(end -0.67945 -0.3048)
			(stroke
				(width 0.1)
				(type default)
			)
			(layer "B.Fab")
		)
		(fp_line
			(start -0.67945 -0.3048)
			(end -0.67945 0.3048)
			(stroke
				(width 0.1)
				(type default)
			)
			(layer "B.Fab")
		)
		(fp_line
			(start 0.12065 -0.2794)
			(end -0.12065 -0.2794)
			(stroke
				(width 0.1)
				(type default)
			)
			(layer "B.Fab")
		)
		(fp_line
			(start -0.12065 -0.2794)
			(end -0.12065 -0.3048)
			(stroke
				(width 0.1)
				(type default)
			)
			(layer "B.Fab")
		)
		(fp_line
			(start 0.12065 0.2794)
			(end 0.12065 0.3048)
			(stroke
				(width 0.1)
				(type default)
			)
			(layer "B.Fab")
		)
		(fp_line
			(start -0.120396 0.2794)
			(end 0.12065 0.2794)
			(stroke
				(width 0.1)
				(type default)
			)
			(layer "B.Fab")
		)
		(fp_line
			(start 0.67945 0.3048)
			(end 0.67945 -0.305054)
			(stroke
				(width 0.1)
				(type default)
			)
			(layer "B.Fab")
		)
		(fp_line
			(start 0.12065 0.3048)
			(end 0.67945 0.3048)
			(stroke
				(width 0.1)
				(type default)
			)
			(layer "B.Fab")
		)
		(fp_line
			(start -0.120396 0.3048)
			(end -0.120396 0.2794)
			(stroke
				(width 0.1)
				(type default)
			)
			(layer "B.Fab")
		)
		(fp_line
			(start -0.67945 0.3048)
			(end -0.120396 0.3048)
			(stroke
				(width 0.1)
				(type default)
			)
			(layer "B.Fab")
		)
		(pad "1" smd circle
			(at 0.40005 0 270)
			(size 0 0)
			(layers "B.Cu" "B.Mask" "B.Paste")
			(net "SMB_1_BMC_GPU_SDA")
		)
		(pad "2" smd circle
			(at -0.40005 0 270)
			(size 0 0)
			(layers "B.Cu" "B.Mask" "B.Paste")
			(net "SMB_PCIE3_3V3AUX_SDA_R")
		)
	)
	(footprint ""
		(layer "B.Cu")
		(at 450.542914 -8.344916 90)
		(property "Reference" "R414"
			(at 0 0 90)
			(layer "B.SilkS")
			(hide yes)
			(effects
				(font
					(size 1.27 1.27)
				)
				(justify mirror)
			)
		)
		(property "Value" ""
			(at 0 0 90)
			(layer "B.Fab")
			(effects
				(font
					(size 1.27 1.27)
				)
				(justify mirror)
			)
		)
		(duplicate_pad_numbers_are_jumpers no)
		(fp_line
			(start 0.7874 -0.4064)
			(end -0.7874 -0.4064)
			(stroke
				(width 0.1524)
				(type default)
			)
			(layer "B.SilkS")
		)
		(fp_line
			(start -0.7874 -0.4064)
			(end -0.7874 0.4064)
			(stroke
				(width 0.1524)
				(type default)
			)
			(layer "B.SilkS")
		)
		(fp_line
			(start 0.7874 0.4064)
			(end 0.7874 -0.4064)
			(stroke
				(width 0.1524)
				(type default)
			)
			(layer "B.SilkS")
		)
		(fp_line
			(start -0.7874 0.4064)
			(end 0.7874 0.4064)
			(stroke
				(width 0.1524)
				(type default)
			)
			(layer "B.SilkS")
		)
		(fp_line
			(start 0.67945 -0.305054)
			(end 0.12065 -0.305054)
			(stroke
				(width 0.1)
				(type default)
			)
			(layer "B.Fab")
		)
		(fp_line
			(start 0.12065 -0.305054)
			(end 0.12065 -0.2794)
			(stroke
				(width 0.1)
				(type default)
			)
			(layer "B.Fab")
		)
		(fp_line
			(start -0.12065 -0.3048)
			(end -0.67945 -0.3048)
			(stroke
				(width 0.1)
				(type default)
			)
			(layer "B.Fab")
		)
		(fp_line
			(start -0.67945 -0.3048)
			(end -0.67945 0.3048)
			(stroke
				(width 0.1)
				(type default)
			)
			(layer "B.Fab")
		)
		(fp_line
			(start 0.12065 -0.2794)
			(end -0.12065 -0.2794)
			(stroke
				(width 0.1)
				(type default)
			)
			(layer "B.Fab")
		)
		(fp_line
			(start -0.12065 -0.2794)
			(end -0.12065 -0.3048)
			(stroke
				(width 0.1)
				(type default)
			)
			(layer "B.Fab")
		)
		(fp_line
			(start 0.12065 0.2794)
			(end 0.12065 0.3048)
			(stroke
				(width 0.1)
				(type default)
			)
			(layer "B.Fab")
		)
		(fp_line
			(start -0.120396 0.2794)
			(end 0.12065 0.2794)
			(stroke
				(width 0.1)
				(type default)
			)
			(layer "B.Fab")
		)
		(fp_line
			(start 0.67945 0.3048)
			(end 0.67945 -0.305054)
			(stroke
				(width 0.1)
				(type default)
			)
			(layer "B.Fab")
		)
		(fp_line
			(start 0.12065 0.3048)
			(end 0.67945 0.3048)
			(stroke
				(width 0.1)
				(type default)
			)
			(layer "B.Fab")
		)
		(fp_line
			(start -0.120396 0.3048)
			(end -0.120396 0.2794)
			(stroke
				(width 0.1)
				(type default)
			)
			(layer "B.Fab")
		)
		(fp_line
			(start -0.67945 0.3048)
			(end -0.120396 0.3048)
			(stroke
				(width 0.1)
				(type default)
			)
			(layer "B.Fab")
		)
		(pad "1" smd circle
			(at 0.40005 0 270)
			(size 0 0)
			(layers "B.Cu" "B.Mask" "B.Paste")
			(net "P3V3_OCP_SFF")
		)
		(pad "2" smd circle
			(at -0.40005 0 270)
			(size 0 0)
			(layers "B.Cu" "B.Mask" "B.Paste")
			(net "OCP_SFF_ID1")
		)
	)
	(footprint ""
		(layer "B.Cu")
		(at 81.446624 -185.874152 90)
		(property "Reference" "R198"
			(at 0 0 90)
			(layer "B.SilkS")
			(hide yes)
			(effects
				(font
					(size 1.27 1.27)
				)
				(justify mirror)
			)
		)
		(property "Value" ""
			(at 0 0 90)
			(layer "B.Fab")
			(effects
				(font
					(size 1.27 1.27)
				)
				(justify mirror)
			)
		)
		(duplicate_pad_numbers_are_jumpers no)
		(fp_line
			(start 0.7874 -0.4064)
			(end -0.7874 -0.4064)
			(stroke
				(width 0.1524)
				(type default)
			)
			(layer "B.SilkS")
		)
		(fp_line
			(start -0.7874 -0.4064)
			(end -0.7874 0.4064)
			(stroke
				(width 0.1524)
				(type default)
			)
			(layer "B.SilkS")
		)
		(fp_line
			(start 0.7874 0.4064)
			(end 0.7874 -0.4064)
			(stroke
				(width 0.1524)
				(type default)
			)
			(layer "B.SilkS")
		)
		(fp_line
			(start -0.7874 0.4064)
			(end 0.7874 0.4064)
			(stroke
				(width 0.1524)
				(type default)
			)
			(layer "B.SilkS")
		)
		(fp_line
			(start 0.67945 -0.305054)
			(end 0.12065 -0.305054)
			(stroke
				(width 0.1)
				(type default)
			)
			(layer "B.Fab")
		)
		(fp_line
			(start 0.12065 -0.305054)
			(end 0.12065 -0.2794)
			(stroke
				(width 0.1)
				(type default)
			)
			(layer "B.Fab")
		)
		(fp_line
			(start -0.12065 -0.3048)
			(end -0.67945 -0.3048)
			(stroke
				(width 0.1)
				(type default)
			)
			(layer "B.Fab")
		)
		(fp_line
			(start -0.67945 -0.3048)
			(end -0.67945 0.3048)
			(stroke
				(width 0.1)
				(type default)
			)
			(layer "B.Fab")
		)
		(fp_line
			(start 0.12065 -0.2794)
			(end -0.12065 -0.2794)
			(stroke
				(width 0.1)
				(type default)
			)
			(layer "B.Fab")
		)
		(fp_line
			(start -0.12065 -0.2794)
			(end -0.12065 -0.3048)
			(stroke
				(width 0.1)
				(type default)
			)
			(layer "B.Fab")
		)
		(fp_line
			(start 0.12065 0.2794)
			(end 0.12065 0.3048)
			(stroke
				(width 0.1)
				(type default)
			)
			(layer "B.Fab")
		)
		(fp_line
			(start -0.120396 0.2794)
			(end 0.12065 0.2794)
			(stroke
				(width 0.1)
				(type default)
			)
			(layer "B.Fab")
		)
		(fp_line
			(start 0.67945 0.3048)
			(end 0.67945 -0.305054)
			(stroke
				(width 0.1)
				(type default)
			)
			(layer "B.Fab")
		)
		(fp_line
			(start 0.12065 0.3048)
			(end 0.67945 0.3048)
			(stroke
				(width 0.1)
				(type default)
			)
			(layer "B.Fab")
		)
		(fp_line
			(start -0.120396 0.3048)
			(end -0.120396 0.2794)
			(stroke
				(width 0.1)
				(type default)
			)
			(layer "B.Fab")
		)
		(fp_line
			(start -0.67945 0.3048)
			(end -0.120396 0.3048)
			(stroke
				(width 0.1)
				(type default)
			)
			(layer "B.Fab")
		)
		(pad "1" smd circle
			(at 0.40005 0 270)
			(size 0 0)
			(layers "B.Cu" "B.Mask" "B.Paste")
			(net "PVNN_TERM_CPU1")
		)
		(pad "2" smd circle
			(at -0.40005 0 270)
			(size 0 0)
			(layers "B.Cu" "B.Mask" "B.Paste")
			(net "H_CPU1_NMI_LVC1_N")
		)
	)
	(footprint ""
		(layer "B.Cu")
		(at 257.48488 -78.577948 90)
		(property "Reference" "R2357"
			(at 0 0 90)
			(layer "B.SilkS")
			(hide yes)
			(effects
				(font
					(size 1.27 1.27)
				)
				(justify mirror)
			)
		)
		(property "Value" ""
			(at 0 0 90)
			(layer "B.Fab")
			(effects
				(font
					(size 1.27 1.27)
				)
				(justify mirror)
			)
		)
		(duplicate_pad_numbers_are_jumpers no)
		(fp_line
			(start 0.7874 -0.4064)
			(end -0.7874 -0.4064)
			(stroke
				(width 0.1524)
				(type default)
			)
			(layer "B.SilkS")
		)
		(fp_line
			(start -0.7874 -0.4064)
			(end -0.7874 0.4064)
			(stroke
				(width 0.1524)
				(type default)
			)
			(layer "B.SilkS")
		)
		(fp_line
			(start 0.7874 0.4064)
			(end 0.7874 -0.4064)
			(stroke
				(width 0.1524)
				(type default)
			)
			(layer "B.SilkS")
		)
		(fp_line
			(start -0.7874 0.4064)
			(end 0.7874 0.4064)
			(stroke
				(width 0.1524)
				(type default)
			)
			(layer "B.SilkS")
		)
		(fp_line
			(start 0.67945 -0.305054)
			(end 0.12065 -0.305054)
			(stroke
				(width 0.1)
				(type default)
			)
			(layer "B.Fab")
		)
		(fp_line
			(start 0.12065 -0.305054)
			(end 0.12065 -0.2794)
			(stroke
				(width 0.1)
				(type default)
			)
			(layer "B.Fab")
		)
		(fp_line
			(start -0.12065 -0.3048)
			(end -0.67945 -0.3048)
			(stroke
				(width 0.1)
				(type default)
			)
			(layer "B.Fab")
		)
		(fp_line
			(start -0.67945 -0.3048)
			(end -0.67945 0.3048)
			(stroke
				(width 0.1)
				(type default)
			)
			(layer "B.Fab")
		)
		(fp_line
			(start 0.12065 -0.2794)
			(end -0.12065 -0.2794)
			(stroke
				(width 0.1)
				(type default)
			)
			(layer "B.Fab")
		)
		(fp_line
			(start -0.12065 -0.2794)
			(end -0.12065 -0.3048)
			(stroke
				(width 0.1)
				(type default)
			)
			(layer "B.Fab")
		)
		(fp_line
			(start 0.12065 0.2794)
			(end 0.12065 0.3048)
			(stroke
				(width 0.1)
				(type default)
			)
			(layer "B.Fab")
		)
		(fp_line
			(start -0.120396 0.2794)
			(end 0.12065 0.2794)
			(stroke
				(width 0.1)
				(type default)
			)
			(layer "B.Fab")
		)
		(fp_line
			(start 0.67945 0.3048)
			(end 0.67945 -0.305054)
			(stroke
				(width 0.1)
				(type default)
			)
			(layer "B.Fab")
		)
		(fp_line
			(start 0.12065 0.3048)
			(end 0.67945 0.3048)
			(stroke
				(width 0.1)
				(type default)
			)
			(layer "B.Fab")
		)
		(fp_line
			(start -0.120396 0.3048)
			(end -0.120396 0.2794)
			(stroke
				(width 0.1)
				(type default)
			)
			(layer "B.Fab")
		)
		(fp_line
			(start -0.67945 0.3048)
			(end -0.120396 0.3048)
			(stroke
				(width 0.1)
				(type default)
			)
			(layer "B.Fab")
		)
		(pad "1" smd circle
			(at 0.40005 0 270)
			(size 0 0)
			(layers "B.Cu" "B.Mask" "B.Paste")
			(net "P3V3_AUX")
		)
		(pad "2" smd circle
			(at -0.40005 0 270)
			(size 0 0)
			(layers "B.Cu" "B.Mask" "B.Paste")
			(net "PWRGD_P1V05_PCH_AUX_R")
		)
	)
	(footprint ""
		(layer "B.Cu")
		(at 181.755542 -112.97539)
		(property "Reference" "C1122"
			(at 0 0 0)
			(layer "B.SilkS")
			(hide yes)
			(effects
				(font
					(size 1.27 1.27)
				)
				(justify mirror)
			)
		)
		(property "Value" ""
			(at 0 0 0)
			(layer "B.Fab")
			(effects
				(font
					(size 1.27 1.27)
				)
				(justify mirror)
			)
		)
		(duplicate_pad_numbers_are_jumpers no)
		(fp_line
			(start -0.69215 -0.2921)
			(end -0.69215 0.2921)
			(stroke
				(width 0.1524)
				(type default)
			)
			(layer "B.SilkS")
		)
		(fp_line
			(start -0.69215 0.2921)
			(end 0.69215 0.2921)
			(stroke
				(width 0.1524)
				(type default)
			)
			(layer "B.SilkS")
		)
		(fp_line
			(start 0.69215 -0.2921)
			(end -0.69215 -0.2921)
			(stroke
				(width 0.1524)
				(type default)
			)
			(layer "B.SilkS")
		)
		(fp_line
			(start 0.69215 0.2921)
			(end 0.69215 -0.2921)
			(stroke
				(width 0.1524)
				(type default)
			)
			(layer "B.SilkS")
		)
		(fp_line
			(start -0.51435 -0.2794)
			(end -0.51435 0.2794)
			(stroke
				(width 0.1)
				(type default)
			)
			(layer "B.Fab")
		)
		(fp_line
			(start -0.51435 0.2794)
			(end 0.51435 0.2794)
			(stroke
				(width 0.1)
				(type default)
			)
			(layer "B.Fab")
		)
		(fp_line
			(start 0.51435 -0.2794)
			(end -0.51435 -0.2794)
			(stroke
				(width 0.1)
				(type default)
			)
			(layer "B.Fab")
		)
		(fp_line
			(start 0.51435 0.2794)
			(end 0.51435 -0.2794)
			(stroke
				(width 0.1)
				(type default)
			)
			(layer "B.Fab")
		)
		(pad "1" smd circle
			(at 0.40005 0 180)
			(size 0 0)
			(layers "B.Cu" "B.Mask" "B.Paste")
			(net "P3V3_AUX_FPGA_VCCIO2")
		)
		(pad "2" smd circle
			(at -0.40005 0 180)
			(size 0 0)
			(layers "B.Cu" "B.Mask" "B.Paste")
			(net "GND")
		)
		(zone
			(layer "B.Cu")
			(hatch none 0.5)
			(connect_pads
				(clearance 0)
			)
			(min_thickness 0.25)
			(keepout
				(tracks not_allowed)
				(vias allowed)
				(pads allowed)
				(copperpour not_allowed)
				(footprints allowed)
			)
			(placement
				(enabled no)
				(sheetname "")
			)
			(fill
				(thermal_gap 0.5)
				(thermal_bridge_width 0.5)
				(island_removal_mode 0)
			)
			(polygon
				(pts
					(xy 181.946042 -112.88776) (xy 181.854602 -112.829594) (xy 181.655212 -112.829594) (xy 181.565042 -112.88776)
					(xy 181.565042 -113.06302) (xy 181.655212 -113.12144) (xy 181.854602 -113.12144) (xy 181.946042 -113.063274)
				)
			)
		)
	)
	(footprint ""
		(layer "B.Cu")
		(at 434.86832 -47.98314 -90)
		(property "Reference" "Q236"
			(at 1.4224 -1.768348 270)
			(unlocked yes)
			(layer "B.SilkS")
			(effects
				(font
					(size 0.7874 0.5842)
					(thickness 0.1524)
				)
				(justify left mirror)
			)
		)
		(property "Value" ""
			(at 0 0 90)
			(layer "B.Fab")
			(effects
				(font
					(size 1.27 1.27)
				)
				(justify mirror)
			)
		)
		(duplicate_pad_numbers_are_jumpers no)
		(fp_line
			(start -1.332738 1.100074)
			(end 1.332738 1.100074)
			(stroke
				(width 0.1524)
				(type default)
			)
			(layer "B.SilkS")
		)
		(fp_line
			(start 1.332738 1.100074)
			(end 1.332738 -1.100074)
			(stroke
				(width 0.1524)
				(type default)
			)
			(layer "B.SilkS")
		)
		(fp_line
			(start 0 -0.541274)
			(end -0.4826 -1.100074)
			(stroke
				(width 0.1524)
				(type default)
			)
			(layer "B.SilkS")
		)
		(fp_line
			(start -1.332738 -1.100074)
			(end -1.332738 1.100074)
			(stroke
				(width 0.1524)
				(type default)
			)
			(layer "B.SilkS")
		)
		(fp_line
			(start -0.4826 -1.100074)
			(end -1.332738 -1.100074)
			(stroke
				(width 0.1524)
				(type default)
			)
			(layer "B.SilkS")
		)
		(fp_line
			(start 0.4826 -1.100074)
			(end 0 -0.541274)
			(stroke
				(width 0.1524)
				(type default)
			)
			(layer "B.SilkS")
		)
		(fp_line
			(start 1.332738 -1.100074)
			(end 0.4826 -1.100074)
			(stroke
				(width 0.1524)
				(type default)
			)
			(layer "B.SilkS")
		)
		(fp_poly
			(pts
				(xy 2.2352 -0.298958) (xy 2.2352 -1.001014) (xy 1.533144 -0.649986)
			)
			(stroke
				(width 0)
				(type default)
			)
			(fill yes)
			(layer "B.SilkS")
		)
		(fp_line
			(start -0.674878 1.100074)
			(end 0.674878 1.100074)
			(stroke
				(width 0.1)
				(type default)
			)
			(layer "B.Fab")
		)
		(fp_line
			(start 0.674878 1.100074)
			(end 0.674878 -1.100074)
			(stroke
				(width 0.1)
				(type default)
			)
			(layer "B.Fab")
		)
		(fp_line
			(start -0.674878 -1.100074)
			(end -0.674878 1.100074)
			(stroke
				(width 0.1)
				(type default)
			)
			(layer "B.Fab")
		)
		(fp_line
			(start 0.674878 -1.100074)
			(end -0.674878 -1.100074)
			(stroke
				(width 0.1)
				(type default)
			)
			(layer "B.Fab")
		)
		(fp_poly
			(pts
				(xy 2.2352 -0.298958) (xy 2.2352 -1.001014) (xy 1.533144 -0.649986)
			)
			(stroke
				(width 0)
				(type default)
			)
			(fill yes)
			(layer "B.Fab")
		)
		(pad "1" smd rect
			(at 0.94996 -0.649986)
			(size 0.4318 0.508)
			(layers "B.Cu" "B.Mask" "B.Paste")
			(net "GND")
		)
		(pad "2" smd rect
			(at 0.94996 0)
			(size 0.4318 0.508)
			(layers "B.Cu" "B.Mask" "B.Paste")
			(net "PWRGD_P5V")
		)
		(pad "3" smd rect
			(at 0.94996 0.649986)
			(size 0.4318 0.508)
			(layers "B.Cu" "B.Mask" "B.Paste")
			(net "PWRGD_P5V_ISO")
		)
		(pad "4" smd rect
			(at -0.94996 0.649986)
			(size 0.4318 0.508)
			(layers "B.Cu" "B.Mask" "B.Paste")
			(net "GND")
		)
		(pad "5" smd rect
			(at -0.94996 0)
			(size 0.4318 0.508)
			(layers "B.Cu" "B.Mask" "B.Paste")
			(net "PWRGD_P5V_N")
		)
		(pad "6" smd rect
			(at -0.94996 -0.649986)
			(size 0.4318 0.508)
			(layers "B.Cu" "B.Mask" "B.Paste")
			(net "PWRGD_P5V_N")
		)
	)
	(footprint ""
		(layer "B.Cu")
		(at 183.011826 -318.352424)
		(property "Reference" "R77"
			(at 0 0 0)
			(layer "B.SilkS")
			(hide yes)
			(effects
				(font
					(size 1.27 1.27)
				)
				(justify mirror)
			)
		)
		(property "Value" ""
			(at 0 0 0)
			(layer "B.Fab")
			(effects
				(font
					(size 1.27 1.27)
				)
				(justify mirror)
			)
		)
		(duplicate_pad_numbers_are_jumpers no)
		(fp_line
			(start -0.7874 -0.4064)
			(end -0.7874 0.4064)
			(stroke
				(width 0.1524)
				(type default)
			)
			(layer "B.SilkS")
		)
		(fp_line
			(start -0.7874 0.4064)
			(end 0.7874 0.4064)
			(stroke
				(width 0.1524)
				(type default)
			)
			(layer "B.SilkS")
		)
		(fp_line
			(start 0.7874 -0.4064)
			(end -0.7874 -0.4064)
			(stroke
				(width 0.1524)
				(type default)
			)
			(layer "B.SilkS")
		)
		(fp_line
			(start 0.7874 0.4064)
			(end 0.7874 -0.4064)
			(stroke
				(width 0.1524)
				(type default)
			)
			(layer "B.SilkS")
		)
		(fp_line
			(start -0.67945 -0.3048)
			(end -0.67945 0.3048)
			(stroke
				(width 0.1)
				(type default)
			)
			(layer "B.Fab")
		)
		(fp_line
			(start -0.67945 0.3048)
			(end -0.120396 0.3048)
			(stroke
				(width 0.1)
				(type default)
			)
			(layer "B.Fab")
		)
		(fp_line
			(start -0.12065 -0.3048)
			(end -0.67945 -0.3048)
			(stroke
				(width 0.1)
				(type default)
			)
			(layer "B.Fab")
		)
		(fp_line
			(start -0.12065 -0.2794)
			(end -0.12065 -0.3048)
			(stroke
				(width 0.1)
				(type default)
			)
			(layer "B.Fab")
		)
		(fp_line
			(start -0.120396 0.2794)
			(end 0.12065 0.2794)
			(stroke
				(width 0.1)
				(type default)
			)
			(layer "B.Fab")
		)
		(fp_line
			(start -0.120396 0.3048)
			(end -0.120396 0.2794)
			(stroke
				(width 0.1)
				(type default)
			)
			(layer "B.Fab")
		)
		(fp_line
			(start 0.12065 -0.305054)
			(end 0.12065 -0.2794)
			(stroke
				(width 0.1)
				(type default)
			)
			(layer "B.Fab")
		)
		(fp_line
			(start 0.12065 -0.2794)
			(end -0.12065 -0.2794)
			(stroke
				(width 0.1)
				(type default)
			)
			(layer "B.Fab")
		)
		(fp_line
			(start 0.12065 0.2794)
			(end 0.12065 0.3048)
			(stroke
				(width 0.1)
				(type default)
			)
			(layer "B.Fab")
		)
		(fp_line
			(start 0.12065 0.3048)
			(end 0.67945 0.3048)
			(stroke
				(width 0.1)
				(type default)
			)
			(layer "B.Fab")
		)
		(fp_line
			(start 0.67945 -0.305054)
			(end 0.12065 -0.305054)
			(stroke
				(width 0.1)
				(type default)
			)
			(layer "B.Fab")
		)
		(fp_line
			(start 0.67945 0.3048)
			(end 0.67945 -0.305054)
			(stroke
				(width 0.1)
				(type default)
			)
			(layer "B.Fab")
		)
		(pad "1" smd circle
			(at 0.40005 0 180)
			(size 0 0)
			(layers "B.Cu" "B.Mask" "B.Paste")
			(net "PD_CHF_CPU1_DIMM1_SAA")
		)
		(pad "2" smd circle
			(at -0.40005 0 180)
			(size 0 0)
			(layers "B.Cu" "B.Mask" "B.Paste")
			(net "GND")
		)
	)
	(footprint ""
		(layer "B.Cu")
		(at 127.84074 -26.276808 -90)
		(property "Reference" "U309"
			(at 0 0 90)
			(layer "B.SilkS")
			(hide yes)
			(effects
				(font
					(size 1.27 1.27)
				)
				(justify mirror)
			)
		)
		(property "Value" ""
			(at 0 0 90)
			(layer "B.Fab")
			(effects
				(font
					(size 1.27 1.27)
				)
				(justify mirror)
			)
		)
		(duplicate_pad_numbers_are_jumpers no)
		(fp_line
			(start -1.618742 1.618742)
			(end -1.17856 1.618742)
			(stroke
				(width 0.1524)
				(type default)
			)
			(layer "B.SilkS")
		)
		(fp_line
			(start -0.42418 1.618742)
			(end 0.37592 1.618742)
			(stroke
				(width 0.1524)
				(type default)
			)
			(layer "B.SilkS")
		)
		(fp_line
			(start 1.32588 1.618742)
			(end 1.618742 1.618742)
			(stroke
				(width 0.1524)
				(type default)
			)
			(layer "B.SilkS")
		)
		(fp_line
			(start 1.618742 1.618742)
			(end 1.618742 -1.618742)
			(stroke
				(width 0.1524)
				(type default)
			)
			(layer "B.SilkS")
		)
		(fp_line
			(start -1.618742 -1.618742)
			(end -1.618742 1.618742)
			(stroke
				(width 0.1524)
				(type default)
			)
			(layer "B.SilkS")
		)
		(fp_line
			(start -1.27 -1.618742)
			(end -1.618742 -1.618742)
			(stroke
				(width 0.1524)
				(type default)
			)
			(layer "B.SilkS")
		)
		(fp_line
			(start 0.42164 -1.618742)
			(end -0.29464 -1.618742)
			(stroke
				(width 0.1524)
				(type default)
			)
			(layer "B.SilkS")
		)
		(fp_line
			(start 1.618742 -1.618742)
			(end 1.52146 -1.618742)
			(stroke
				(width 0.1524)
				(type default)
			)
			(layer "B.SilkS")
		)
		(fp_poly
			(pts
				(xy 2.663952 -1.172972) (xy 1.855724 -0.903478) (xy 2.124964 -1.711706)
			)
			(stroke
				(width 0)
				(type default)
			)
			(fill yes)
			(layer "B.SilkS")
		)
		(fp_line
			(start -1.27508 1.27508)
			(end -1.27508 -1.27508)
			(stroke
				(width 0.1)
				(type default)
			)
			(layer "B.Fab")
		)
		(fp_line
			(start 1.27508 1.27508)
			(end -1.27508 1.27508)
			(stroke
				(width 0.1)
				(type default)
			)
			(layer "B.Fab")
		)
		(fp_line
			(start -1.27508 -1.27508)
			(end 1.27508 -1.27508)
			(stroke
				(width 0.1)
				(type default)
			)
			(layer "B.Fab")
		)
		(fp_line
			(start 1.27508 -1.27508)
			(end 1.27508 1.27508)
			(stroke
				(width 0.1)
				(type default)
			)
			(layer "B.Fab")
		)
		(fp_poly
			(pts
				(xy 2.4892 -1.081024) (xy 2.4892 -0.319024) (xy 1.7272 -0.700024)
			)
			(stroke
				(width 0)
				(type default)
			)
			(fill yes)
			(layer "B.Fab")
		)
		(pad "1" smd rect
			(at 1.225042 -0.700024)
			(size 0.127 0.508)
			(layers "B.Cu" "B.Mask" "B.Paste")
			(net "FM_USB3_1_EQA")
		)
		(pad "2" smd rect
			(at 1.225042 -0.350012)
			(size 0.127 0.508)
			(layers "B.Cu" "B.Mask" "B.Paste")
			(net "FM_USB3_1_FGA")
		)
		(pad "3" smd rect
			(at 1.225042 0)
			(size 0.127 0.508)
			(layers "B.Cu" "B.Mask" "B.Paste")
			(net "FM_USB3_1_SWA")
		)
		(pad "4" smd rect
			(at 1.225042 0.350012)
			(size 0.127 0.508)
			(layers "B.Cu" "B.Mask" "B.Paste")
			(net "FM_USB3_1_EN_N")
		)
		(pad "5" smd rect
			(at 1.225042 0.700024)
			(size 0.127 0.508)
			(layers "B.Cu" "B.Mask" "B.Paste")
			(net "P3V3_AUX_USB_BUF")
		)
		(pad "6" smd rect
			(at 1.050036 1.225042 90)
			(size 0.127 0.508)
			(layers "B.Cu" "B.Mask" "B.Paste")
			(net "USB3_PCH_TX_C_DP<4>")
		)
		(pad "7" smd rect
			(at 0.700024 1.225042 90)
			(size 0.127 0.508)
			(layers "B.Cu" "B.Mask" "B.Paste")
			(net "USB3_PCH_TX_C_DN<4>")
		)
		(pad "8" smd rect
			(at 0.350012 1.225042 90)
			(size 0.127 0.508)
			(layers "B.Cu" "B.Mask" "B.Paste")
			(net "GND")
		)
		(pad "9" smd rect
			(at 0 1.225042 90)
			(size 0.127 0.508)
			(layers "B.Cu" "B.Mask" "B.Paste")
			(net "GND")
		)
		(pad "10" smd rect
			(at -0.350012 1.225042 90)
			(size 0.127 0.508)
			(layers "B.Cu" "B.Mask" "B.Paste")
			(net "GND")
		)
		(pad "11" smd rect
			(at -0.700024 1.225042 90)
			(size 0.127 0.508)
			(layers "B.Cu" "B.Mask" "B.Paste")
			(net "USB3_PCH_RX_BUF_C_DN<4>")
		)
		(pad "12" smd rect
			(at -1.050036 1.225042 90)
			(size 0.127 0.508)
			(layers "B.Cu" "B.Mask" "B.Paste")
			(net "USB3_PCH_RX_BUF_C_DP<4>")
		)
		(pad "13" smd rect
			(at -1.225042 0.700024)
			(size 0.127 0.508)
			(layers "B.Cu" "B.Mask" "B.Paste")
			(net "FM_USB3_1_RXDET_EN")
		)
		(pad "14" smd rect
			(at -1.225042 0.350012)
			(size 0.127 0.508)
			(layers "B.Cu" "B.Mask" "B.Paste")
			(net "FM_USB3_1_SWB")
		)
		(pad "15" smd rect
			(at -1.225042 0)
			(size 0.127 0.508)
			(layers "B.Cu" "B.Mask" "B.Paste")
			(net "FM_USB3_1_FGB")
		)
		(pad "16" smd rect
			(at -1.225042 -0.350012)
			(size 0.127 0.508)
			(layers "B.Cu" "B.Mask" "B.Paste")
			(net "FM_USB3_1_EQB")
		)
		(pad "17" smd rect
			(at -1.225042 -0.700024)
			(size 0.127 0.508)
			(layers "B.Cu" "B.Mask" "B.Paste")
			(net "P3V3_AUX_USB_BUF")
		)
		(pad "18" smd rect
			(at -1.050036 -1.225042 90)
			(size 0.127 0.508)
			(layers "B.Cu" "B.Mask" "B.Paste")
			(net "USB3_PCH_RX_C_DP<4>")
		)
		(pad "19" smd rect
			(at -0.700024 -1.225042 90)
			(size 0.127 0.508)
			(layers "B.Cu" "B.Mask" "B.Paste")
			(net "USB3_PCH_RX_C_DN<4>")
		)
		(pad "20" smd rect
			(at -0.350012 -1.225042 90)
			(size 0.127 0.508)
			(layers "B.Cu" "B.Mask" "B.Paste")
			(net "GND")
		)
		(pad "21" smd rect
			(at 0 -1.225042 90)
			(size 0.127 0.508)
			(layers "B.Cu" "B.Mask" "B.Paste")
			(net "GND")
		)
		(pad "22" smd rect
			(at 0.350012 -1.225042 90)
			(size 0.127 0.508)
			(layers "B.Cu" "B.Mask" "B.Paste")
			(net "GND")
		)
		(pad "23" smd rect
			(at 0.700024 -1.225042 90)
			(size 0.127 0.508)
			(layers "B.Cu" "B.Mask" "B.Paste")
			(net "USB3_PCH_TX_BUF_DN<4>")
		)
		(pad "24" smd rect
			(at 1.050036 -1.225042 90)
			(size 0.127 0.508)
			(layers "B.Cu" "B.Mask" "B.Paste")
			(net "USB3_PCH_TX_BUF_DP<4>")
		)
		(pad "TH" smd rect
			(at 0 0 90)
			(size 1.4224 1.4224)
			(layers "B.Cu" "B.Mask" "B.Paste")
			(net "GND")
		)
	)
	(footprint ""
		(layer "B.Cu")
		(at 330.16698 -64.260984 45)
		(property "Reference" "C1254"
			(at 0 0 45)
			(layer "B.SilkS")
			(hide yes)
			(effects
				(font
					(size 1.27 1.27)
				)
				(justify mirror)
			)
		)
		(property "Value" ""
			(at 0 0 45)
			(layer "B.Fab")
			(effects
				(font
					(size 1.27 1.27)
				)
				(justify mirror)
			)
		)
		(duplicate_pad_numbers_are_jumpers no)
		(fp_line
			(start -1.295492 -0.584255)
			(end -1.295492 0.584255)
			(stroke
				(width 0.1524)
				(type default)
			)
			(layer "B.SilkS")
		)
		(fp_line
			(start -1.295492 0.584255)
			(end 1.295492 0.584255)
			(stroke
				(width 0.1524)
				(type default)
			)
			(layer "B.SilkS")
		)
		(fp_line
			(start 0 -0.584076)
			(end 0 0.584076)
			(stroke
				(width 0.1524)
				(type default)
			)
			(layer "B.SilkS")
		)
		(fp_line
			(start 1.295492 -0.584255)
			(end -1.295492 -0.584255)
			(stroke
				(width 0.1524)
				(type default)
			)
			(layer "B.SilkS")
		)
		(fp_line
			(start 1.295492 0.584255)
			(end 1.295492 -0.584255)
			(stroke
				(width 0.1524)
				(type default)
			)
			(layer "B.SilkS")
		)
		(fp_line
			(start -1.193835 -0.406446)
			(end -1.193835 0.406446)
			(stroke
				(width 0.1)
				(type default)
			)
			(layer "B.Fab")
		)
		(fp_line
			(start -0.863541 -0.457275)
			(end -0.863721 -0.406446)
			(stroke
				(width 0.1)
				(type default)
			)
			(layer "B.Fab")
		)
		(fp_line
			(start -0.863721 -0.406446)
			(end -1.193835 -0.406446)
			(stroke
				(width 0.1)
				(type default)
			)
			(layer "B.Fab")
		)
		(fp_line
			(start -1.193835 0.406446)
			(end -0.863721 0.406446)
			(stroke
				(width 0.1)
				(type default)
			)
			(layer "B.Fab")
		)
		(fp_line
			(start -0.863721 0.406446)
			(end -0.863541 0.457275)
			(stroke
				(width 0.1)
				(type default)
			)
			(layer "B.Fab")
		)
		(fp_line
			(start -0.863541 0.457275)
			(end 0.863541 0.457275)
			(stroke
				(width 0.1)
				(type default)
			)
			(layer "B.Fab")
		)
		(fp_line
			(start 0.863541 -0.457275)
			(end -0.863541 -0.457275)
			(stroke
				(width 0.1)
				(type default)
			)
			(layer "B.Fab")
		)
		(fp_line
			(start 0.863721 -0.406446)
			(end 0.863541 -0.457275)
			(stroke
				(width 0.1)
				(type default)
			)
			(layer "B.Fab")
		)
		(fp_line
			(start 1.193835 -0.406446)
			(end 0.863721 -0.406446)
			(stroke
				(width 0.1)
				(type default)
			)
			(layer "B.Fab")
		)
		(fp_line
			(start 0.863721 0.406446)
			(end 1.193835 0.406446)
			(stroke
				(width 0.1)
				(type default)
			)
			(layer "B.Fab")
		)
		(fp_line
			(start 0.863541 0.457275)
			(end 0.863721 0.406446)
			(stroke
				(width 0.1)
				(type default)
			)
			(layer "B.Fab")
		)
		(fp_line
			(start 1.193835 0.406446)
			(end 1.193835 -0.406446)
			(stroke
				(width 0.1)
				(type default)
			)
			(layer "B.Fab")
		)
		(pad "1" smd rect
			(at 0.7366 0 315)
			(size 0.7112 0.8128)
			(layers "B.Cu" "B.Mask" "B.Paste")
			(net "P1V05_PCH_PLL_AUX")
		)
		(pad "2" smd rect
			(at -0.7366 0 315)
			(size 0.7112 0.8128)
			(layers "B.Cu" "B.Mask" "B.Paste")
			(net "GND")
		)
	)
	(footprint ""
		(layer "B.Cu")
		(at 235.811822 -132.103114 90)
		(property "Reference" "R107"
			(at 0 0 90)
			(layer "B.SilkS")
			(hide yes)
			(effects
				(font
					(size 1.27 1.27)
				)
				(justify mirror)
			)
		)
		(property "Value" ""
			(at 0 0 90)
			(layer "B.Fab")
			(effects
				(font
					(size 1.27 1.27)
				)
				(justify mirror)
			)
		)
		(duplicate_pad_numbers_are_jumpers no)
		(fp_line
			(start 0.7874 -0.4064)
			(end -0.7874 -0.4064)
			(stroke
				(width 0.1524)
				(type default)
			)
			(layer "B.SilkS")
		)
		(fp_line
			(start -0.7874 -0.4064)
			(end -0.7874 0.4064)
			(stroke
				(width 0.1524)
				(type default)
			)
			(layer "B.SilkS")
		)
		(fp_line
			(start 0.7874 0.4064)
			(end 0.7874 -0.4064)
			(stroke
				(width 0.1524)
				(type default)
			)
			(layer "B.SilkS")
		)
		(fp_line
			(start -0.7874 0.4064)
			(end 0.7874 0.4064)
			(stroke
				(width 0.1524)
				(type default)
			)
			(layer "B.SilkS")
		)
		(fp_line
			(start 0.67945 -0.305054)
			(end 0.12065 -0.305054)
			(stroke
				(width 0.1)
				(type default)
			)
			(layer "B.Fab")
		)
		(fp_line
			(start 0.12065 -0.305054)
			(end 0.12065 -0.2794)
			(stroke
				(width 0.1)
				(type default)
			)
			(layer "B.Fab")
		)
		(fp_line
			(start -0.12065 -0.3048)
			(end -0.67945 -0.3048)
			(stroke
				(width 0.1)
				(type default)
			)
			(layer "B.Fab")
		)
		(fp_line
			(start -0.67945 -0.3048)
			(end -0.67945 0.3048)
			(stroke
				(width 0.1)
				(type default)
			)
			(layer "B.Fab")
		)
		(fp_line
			(start 0.12065 -0.2794)
			(end -0.12065 -0.2794)
			(stroke
				(width 0.1)
				(type default)
			)
			(layer "B.Fab")
		)
		(fp_line
			(start -0.12065 -0.2794)
			(end -0.12065 -0.3048)
			(stroke
				(width 0.1)
				(type default)
			)
			(layer "B.Fab")
		)
		(fp_line
			(start 0.12065 0.2794)
			(end 0.12065 0.3048)
			(stroke
				(width 0.1)
				(type default)
			)
			(layer "B.Fab")
		)
		(fp_line
			(start -0.120396 0.2794)
			(end 0.12065 0.2794)
			(stroke
				(width 0.1)
				(type default)
			)
			(layer "B.Fab")
		)
		(fp_line
			(start 0.67945 0.3048)
			(end 0.67945 -0.305054)
			(stroke
				(width 0.1)
				(type default)
			)
			(layer "B.Fab")
		)
		(fp_line
			(start 0.12065 0.3048)
			(end 0.67945 0.3048)
			(stroke
				(width 0.1)
				(type default)
			)
			(layer "B.Fab")
		)
		(fp_line
			(start -0.120396 0.3048)
			(end -0.120396 0.2794)
			(stroke
				(width 0.1)
				(type default)
			)
			(layer "B.Fab")
		)
		(fp_line
			(start -0.67945 0.3048)
			(end -0.120396 0.3048)
			(stroke
				(width 0.1)
				(type default)
			)
			(layer "B.Fab")
		)
		(pad "1" smd circle
			(at 0.40005 0 270)
			(size 0 0)
			(layers "B.Cu" "B.Mask" "B.Paste")
			(net "SMB_HOST_3V3AUX_SCL_R")
		)
		(pad "2" smd circle
			(at -0.40005 0 270)
			(size 0 0)
			(layers "B.Cu" "B.Mask" "B.Paste")
			(net "SMB_HOST_CLK_BUF_3V3AUX_SCL")
		)
	)
	(footprint ""
		(layer "B.Cu")
		(at 450.43725 -45.288962)
		(property "Reference" "R424"
			(at 0 0 0)
			(layer "B.SilkS")
			(hide yes)
			(effects
				(font
					(size 1.27 1.27)
				)
				(justify mirror)
			)
		)
		(property "Value" ""
			(at 0 0 0)
			(layer "B.Fab")
			(effects
				(font
					(size 1.27 1.27)
				)
				(justify mirror)
			)
		)
		(duplicate_pad_numbers_are_jumpers no)
		(fp_line
			(start -0.7874 -0.4064)
			(end -0.7874 0.4064)
			(stroke
				(width 0.1524)
				(type default)
			)
			(layer "B.SilkS")
		)
		(fp_line
			(start -0.7874 0.4064)
			(end 0.7874 0.4064)
			(stroke
				(width 0.1524)
				(type default)
			)
			(layer "B.SilkS")
		)
		(fp_line
			(start 0.7874 -0.4064)
			(end -0.7874 -0.4064)
			(stroke
				(width 0.1524)
				(type default)
			)
			(layer "B.SilkS")
		)
		(fp_line
			(start 0.7874 0.4064)
			(end 0.7874 -0.4064)
			(stroke
				(width 0.1524)
				(type default)
			)
			(layer "B.SilkS")
		)
		(fp_line
			(start -0.67945 -0.3048)
			(end -0.67945 0.3048)
			(stroke
				(width 0.1)
				(type default)
			)
			(layer "B.Fab")
		)
		(fp_line
			(start -0.67945 0.3048)
			(end -0.120396 0.3048)
			(stroke
				(width 0.1)
				(type default)
			)
			(layer "B.Fab")
		)
		(fp_line
			(start -0.12065 -0.3048)
			(end -0.67945 -0.3048)
			(stroke
				(width 0.1)
				(type default)
			)
			(layer "B.Fab")
		)
		(fp_line
			(start -0.12065 -0.2794)
			(end -0.12065 -0.3048)
			(stroke
				(width 0.1)
				(type default)
			)
			(layer "B.Fab")
		)
		(fp_line
			(start -0.120396 0.2794)
			(end 0.12065 0.2794)
			(stroke
				(width 0.1)
				(type default)
			)
			(layer "B.Fab")
		)
		(fp_line
			(start -0.120396 0.3048)
			(end -0.120396 0.2794)
			(stroke
				(width 0.1)
				(type default)
			)
			(layer "B.Fab")
		)
		(fp_line
			(start 0.12065 -0.305054)
			(end 0.12065 -0.2794)
			(stroke
				(width 0.1)
				(type default)
			)
			(layer "B.Fab")
		)
		(fp_line
			(start 0.12065 -0.2794)
			(end -0.12065 -0.2794)
			(stroke
				(width 0.1)
				(type default)
			)
			(layer "B.Fab")
		)
		(fp_line
			(start 0.12065 0.2794)
			(end 0.12065 0.3048)
			(stroke
				(width 0.1)
				(type default)
			)
			(layer "B.Fab")
		)
		(fp_line
			(start 0.12065 0.3048)
			(end 0.67945 0.3048)
			(stroke
				(width 0.1)
				(type default)
			)
			(layer "B.Fab")
		)
		(fp_line
			(start 0.67945 -0.305054)
			(end 0.12065 -0.305054)
			(stroke
				(width 0.1)
				(type default)
			)
			(layer "B.Fab")
		)
		(fp_line
			(start 0.67945 0.3048)
			(end 0.67945 -0.305054)
			(stroke
				(width 0.1)
				(type default)
			)
			(layer "B.Fab")
		)
		(pad "1" smd circle
			(at 0.40005 0 180)
			(size 0 0)
			(layers "B.Cu" "B.Mask" "B.Paste")
			(net "SMB_OCP_SFF_3V3AUX_BUF_R_SCL")
		)
		(pad "2" smd circle
			(at -0.40005 0 180)
			(size 0 0)
			(layers "B.Cu" "B.Mask" "B.Paste")
			(net "SMB_OCP_SFF_3V3AUX_BUF_SCL")
		)
	)
	(footprint ""
		(layer "B.Cu")
		(at 195.246498 -191.307466 180)
		(property "Reference" "R745"
			(at 0 0 0)
			(layer "B.SilkS")
			(hide yes)
			(effects
				(font
					(size 1.27 1.27)
				)
				(justify mirror)
			)
		)
		(property "Value" ""
			(at 0 0 0)
			(layer "B.Fab")
			(effects
				(font
					(size 1.27 1.27)
				)
				(justify mirror)
			)
		)
		(duplicate_pad_numbers_are_jumpers no)
		(fp_line
			(start 0.7874 0.4064)
			(end 0.7874 -0.4064)
			(stroke
				(width 0.1524)
				(type default)
			)
			(layer "B.SilkS")
		)
		(fp_line
			(start 0.7874 -0.4064)
			(end -0.7874 -0.4064)
			(stroke
				(width 0.1524)
				(type default)
			)
			(layer "B.SilkS")
		)
		(fp_line
			(start -0.7874 0.4064)
			(end 0.7874 0.4064)
			(stroke
				(width 0.1524)
				(type default)
			)
			(layer "B.SilkS")
		)
		(fp_line
			(start -0.7874 -0.4064)
			(end -0.7874 0.4064)
			(stroke
				(width 0.1524)
				(type default)
			)
			(layer "B.SilkS")
		)
		(fp_line
			(start 0.67945 0.3048)
			(end 0.67945 -0.305054)
			(stroke
				(width 0.1)
				(type default)
			)
			(layer "B.Fab")
		)
		(fp_line
			(start 0.67945 -0.305054)
			(end 0.12065 -0.305054)
			(stroke
				(width 0.1)
				(type default)
			)
			(layer "B.Fab")
		)
		(fp_line
			(start 0.12065 0.3048)
			(end 0.67945 0.3048)
			(stroke
				(width 0.1)
				(type default)
			)
			(layer "B.Fab")
		)
		(fp_line
			(start 0.12065 0.2794)
			(end 0.12065 0.3048)
			(stroke
				(width 0.1)
				(type default)
			)
			(layer "B.Fab")
		)
		(fp_line
			(start 0.12065 -0.2794)
			(end -0.12065 -0.2794)
			(stroke
				(width 0.1)
				(type default)
			)
			(layer "B.Fab")
		)
		(fp_line
			(start 0.12065 -0.305054)
			(end 0.12065 -0.2794)
			(stroke
				(width 0.1)
				(type default)
			)
			(layer "B.Fab")
		)
		(fp_line
			(start -0.120396 0.3048)
			(end -0.120396 0.2794)
			(stroke
				(width 0.1)
				(type default)
			)
			(layer "B.Fab")
		)
		(fp_line
			(start -0.120396 0.2794)
			(end 0.12065 0.2794)
			(stroke
				(width 0.1)
				(type default)
			)
			(layer "B.Fab")
		)
		(fp_line
			(start -0.12065 -0.2794)
			(end -0.12065 -0.3048)
			(stroke
				(width 0.1)
				(type default)
			)
			(layer "B.Fab")
		)
		(fp_line
			(start -0.12065 -0.3048)
			(end -0.67945 -0.3048)
			(stroke
				(width 0.1)
				(type default)
			)
			(layer "B.Fab")
		)
		(fp_line
			(start -0.67945 0.3048)
			(end -0.120396 0.3048)
			(stroke
				(width 0.1)
				(type default)
			)
			(layer "B.Fab")
		)
		(fp_line
			(start -0.67945 -0.3048)
			(end -0.67945 0.3048)
			(stroke
				(width 0.1)
				(type default)
			)
			(layer "B.Fab")
		)
		(pad "1" smd circle
			(at 0.40005 0)
			(size 0 0)
			(layers "B.Cu" "B.Mask" "B.Paste")
			(net "FM_CPU_EN")
		)
		(pad "2" smd circle
			(at -0.40005 0)
			(size 0 0)
			(layers "B.Cu" "B.Mask" "B.Paste")
			(net "FM_CPU_EN_R")
		)
	)
	(footprint ""
		(layer "B.Cu")
		(at 195.253356 -423.657014 -90)
		(property "Reference" "R4707"
			(at 0 0 90)
			(layer "B.SilkS")
			(hide yes)
			(effects
				(font
					(size 1.27 1.27)
				)
				(justify mirror)
			)
		)
		(property "Value" ""
			(at 0 0 90)
			(layer "B.Fab")
			(effects
				(font
					(size 1.27 1.27)
				)
				(justify mirror)
			)
		)
		(duplicate_pad_numbers_are_jumpers no)
		(fp_line
			(start -0.7874 0.4064)
			(end 0.7874 0.4064)
			(stroke
				(width 0.1524)
				(type default)
			)
			(layer "B.SilkS")
		)
		(fp_line
			(start 0.7874 0.4064)
			(end 0.7874 -0.4064)
			(stroke
				(width 0.1524)
				(type default)
			)
			(layer "B.SilkS")
		)
		(fp_line
			(start -0.7874 -0.4064)
			(end -0.7874 0.4064)
			(stroke
				(width 0.1524)
				(type default)
			)
			(layer "B.SilkS")
		)
		(fp_line
			(start 0.7874 -0.4064)
			(end -0.7874 -0.4064)
			(stroke
				(width 0.1524)
				(type default)
			)
			(layer "B.SilkS")
		)
		(fp_line
			(start -0.67945 0.3048)
			(end -0.120396 0.3048)
			(stroke
				(width 0.1)
				(type default)
			)
			(layer "B.Fab")
		)
		(fp_line
			(start -0.120396 0.3048)
			(end -0.120396 0.2794)
			(stroke
				(width 0.1)
				(type default)
			)
			(layer "B.Fab")
		)
		(fp_line
			(start 0.12065 0.3048)
			(end 0.67945 0.3048)
			(stroke
				(width 0.1)
				(type default)
			)
			(layer "B.Fab")
		)
		(fp_line
			(start 0.67945 0.3048)
			(end 0.67945 -0.305054)
			(stroke
				(width 0.1)
				(type default)
			)
			(layer "B.Fab")
		)
		(fp_line
			(start -0.120396 0.2794)
			(end 0.12065 0.2794)
			(stroke
				(width 0.1)
				(type default)
			)
			(layer "B.Fab")
		)
		(fp_line
			(start 0.12065 0.2794)
			(end 0.12065 0.3048)
			(stroke
				(width 0.1)
				(type default)
			)
			(layer "B.Fab")
		)
		(fp_line
			(start -0.12065 -0.2794)
			(end -0.12065 -0.3048)
			(stroke
				(width 0.1)
				(type default)
			)
			(layer "B.Fab")
		)
		(fp_line
			(start 0.12065 -0.2794)
			(end -0.12065 -0.2794)
			(stroke
				(width 0.1)
				(type default)
			)
			(layer "B.Fab")
		)
		(fp_line
			(start -0.67945 -0.3048)
			(end -0.67945 0.3048)
			(stroke
				(width 0.1)
				(type default)
			)
			(layer "B.Fab")
		)
		(fp_line
			(start -0.12065 -0.3048)
			(end -0.67945 -0.3048)
			(stroke
				(width 0.1)
				(type default)
			)
			(layer "B.Fab")
		)
		(fp_line
			(start 0.12065 -0.305054)
			(end 0.12065 -0.2794)
			(stroke
				(width 0.1)
				(type default)
			)
			(layer "B.Fab")
		)
		(fp_line
			(start 0.67945 -0.305054)
			(end 0.12065 -0.305054)
			(stroke
				(width 0.1)
				(type default)
			)
			(layer "B.Fab")
		)
		(pad "1" smd circle
			(at 0.40005 0 90)
			(size 0 0)
			(layers "B.Cu" "B.Mask" "B.Paste")
			(net "LED_P12V_PSU_R3")
		)
		(pad "2" smd circle
			(at -0.40005 0 90)
			(size 0 0)
			(layers "B.Cu" "B.Mask" "B.Paste")
			(net "P12V_PSU")
		)
	)
	(footprint ""
		(layer "B.Cu")
		(at 78.223618 -184.110376 90)
		(property "Reference" "R341"
			(at 0 0 90)
			(layer "B.SilkS")
			(hide yes)
			(effects
				(font
					(size 1.27 1.27)
				)
				(justify mirror)
			)
		)
		(property "Value" ""
			(at 0 0 90)
			(layer "B.Fab")
			(effects
				(font
					(size 1.27 1.27)
				)
				(justify mirror)
			)
		)
		(duplicate_pad_numbers_are_jumpers no)
		(fp_line
			(start 0.7874 -0.4064)
			(end -0.7874 -0.4064)
			(stroke
				(width 0.1524)
				(type default)
			)
			(layer "B.SilkS")
		)
		(fp_line
			(start -0.7874 -0.4064)
			(end -0.7874 0.4064)
			(stroke
				(width 0.1524)
				(type default)
			)
			(layer "B.SilkS")
		)
		(fp_line
			(start 0.7874 0.4064)
			(end 0.7874 -0.4064)
			(stroke
				(width 0.1524)
				(type default)
			)
			(layer "B.SilkS")
		)
		(fp_line
			(start -0.7874 0.4064)
			(end 0.7874 0.4064)
			(stroke
				(width 0.1524)
				(type default)
			)
			(layer "B.SilkS")
		)
		(fp_line
			(start 0.67945 -0.305054)
			(end 0.12065 -0.305054)
			(stroke
				(width 0.1)
				(type default)
			)
			(layer "B.Fab")
		)
		(fp_line
			(start 0.12065 -0.305054)
			(end 0.12065 -0.2794)
			(stroke
				(width 0.1)
				(type default)
			)
			(layer "B.Fab")
		)
		(fp_line
			(start -0.12065 -0.3048)
			(end -0.67945 -0.3048)
			(stroke
				(width 0.1)
				(type default)
			)
			(layer "B.Fab")
		)
		(fp_line
			(start -0.67945 -0.3048)
			(end -0.67945 0.3048)
			(stroke
				(width 0.1)
				(type default)
			)
			(layer "B.Fab")
		)
		(fp_line
			(start 0.12065 -0.2794)
			(end -0.12065 -0.2794)
			(stroke
				(width 0.1)
				(type default)
			)
			(layer "B.Fab")
		)
		(fp_line
			(start -0.12065 -0.2794)
			(end -0.12065 -0.3048)
			(stroke
				(width 0.1)
				(type default)
			)
			(layer "B.Fab")
		)
		(fp_line
			(start 0.12065 0.2794)
			(end 0.12065 0.3048)
			(stroke
				(width 0.1)
				(type default)
			)
			(layer "B.Fab")
		)
		(fp_line
			(start -0.120396 0.2794)
			(end 0.12065 0.2794)
			(stroke
				(width 0.1)
				(type default)
			)
			(layer "B.Fab")
		)
		(fp_line
			(start 0.67945 0.3048)
			(end 0.67945 -0.305054)
			(stroke
				(width 0.1)
				(type default)
			)
			(layer "B.Fab")
		)
		(fp_line
			(start 0.12065 0.3048)
			(end 0.67945 0.3048)
			(stroke
				(width 0.1)
				(type default)
			)
			(layer "B.Fab")
		)
		(fp_line
			(start -0.120396 0.3048)
			(end -0.120396 0.2794)
			(stroke
				(width 0.1)
				(type default)
			)
			(layer "B.Fab")
		)
		(fp_line
			(start -0.67945 0.3048)
			(end -0.120396 0.3048)
			(stroke
				(width 0.1)
				(type default)
			)
			(layer "B.Fab")
		)
		(pad "1" smd circle
			(at 0.40005 0 270)
			(size 0 0)
			(layers "B.Cu" "B.Mask" "B.Paste")
			(net "H_CPU1_ERR1_LVC1_R_N")
		)
		(pad "2" smd circle
			(at -0.40005 0 270)
			(size 0 0)
			(layers "B.Cu" "B.Mask" "B.Paste")
			(net "H_CPU_ERR1_LVC1_R_N")
		)
	)
	(footprint ""
		(layer "B.Cu")
		(at 376.518932 -80.354424 180)
		(property "Reference" "PC1237"
			(at 0 0 0)
			(layer "B.SilkS")
			(hide yes)
			(effects
				(font
					(size 1.27 1.27)
				)
				(justify mirror)
			)
		)
		(property "Value" ""
			(at 0 0 0)
			(layer "B.Fab")
			(effects
				(font
					(size 1.27 1.27)
				)
				(justify mirror)
			)
		)
		(duplicate_pad_numbers_are_jumpers no)
		(fp_line
			(start 1.524 0.762)
			(end 1.524 -0.762)
			(stroke
				(width 0.1524)
				(type default)
			)
			(layer "B.SilkS")
		)
		(fp_line
			(start 1.524 -0.762)
			(end -1.524 -0.762)
			(stroke
				(width 0.1524)
				(type default)
			)
			(layer "B.SilkS")
		)
		(fp_line
			(start -1.524 0.762)
			(end 1.524 0.762)
			(stroke
				(width 0.1524)
				(type default)
			)
			(layer "B.SilkS")
		)
		(fp_line
			(start -1.524 -0.762)
			(end -1.524 0.762)
			(stroke
				(width 0.1524)
				(type default)
			)
			(layer "B.SilkS")
		)
		(fp_line
			(start 1.1049 0.724916)
			(end -1.1049 0.724916)
			(stroke
				(width 0.1)
				(type default)
			)
			(layer "B.Fab")
		)
		(fp_line
			(start 1.1049 -0.724916)
			(end 1.1049 0.724916)
			(stroke
				(width 0.1)
				(type default)
			)
			(layer "B.Fab")
		)
		(fp_line
			(start -1.1049 0.724916)
			(end -1.1049 -0.724916)
			(stroke
				(width 0.1)
				(type default)
			)
			(layer "B.Fab")
		)
		(fp_line
			(start -1.1049 -0.724916)
			(end 1.1049 -0.724916)
			(stroke
				(width 0.1)
				(type default)
			)
			(layer "B.Fab")
		)
		(pad "1" smd rect
			(at 0.889 0 180)
			(size 1.016 1.27)
			(layers "B.Cu" "B.Mask" "B.Paste")
			(net "P1V8_PCH_AUX")
		)
		(pad "2" smd rect
			(at -0.889 0 180)
			(size 1.016 1.27)
			(layers "B.Cu" "B.Mask" "B.Paste")
			(net "GND")
		)
	)
	(footprint ""
		(layer "B.Cu")
		(at 51.714908 -193.25971 -90)
		(property "Reference" "R260"
			(at 0 0 90)
			(layer "B.SilkS")
			(hide yes)
			(effects
				(font
					(size 1.27 1.27)
				)
				(justify mirror)
			)
		)
		(property "Value" ""
			(at 0 0 90)
			(layer "B.Fab")
			(effects
				(font
					(size 1.27 1.27)
				)
				(justify mirror)
			)
		)
		(duplicate_pad_numbers_are_jumpers no)
		(fp_line
			(start -0.7874 0.4064)
			(end 0.7874 0.4064)
			(stroke
				(width 0.1524)
				(type default)
			)
			(layer "B.SilkS")
		)
		(fp_line
			(start 0.7874 0.4064)
			(end 0.7874 -0.4064)
			(stroke
				(width 0.1524)
				(type default)
			)
			(layer "B.SilkS")
		)
		(fp_line
			(start -0.7874 -0.4064)
			(end -0.7874 0.4064)
			(stroke
				(width 0.1524)
				(type default)
			)
			(layer "B.SilkS")
		)
		(fp_line
			(start 0.7874 -0.4064)
			(end -0.7874 -0.4064)
			(stroke
				(width 0.1524)
				(type default)
			)
			(layer "B.SilkS")
		)
		(fp_line
			(start -0.67945 0.3048)
			(end -0.120396 0.3048)
			(stroke
				(width 0.1)
				(type default)
			)
			(layer "B.Fab")
		)
		(fp_line
			(start -0.120396 0.3048)
			(end -0.120396 0.2794)
			(stroke
				(width 0.1)
				(type default)
			)
			(layer "B.Fab")
		)
		(fp_line
			(start 0.12065 0.3048)
			(end 0.67945 0.3048)
			(stroke
				(width 0.1)
				(type default)
			)
			(layer "B.Fab")
		)
		(fp_line
			(start 0.67945 0.3048)
			(end 0.67945 -0.305054)
			(stroke
				(width 0.1)
				(type default)
			)
			(layer "B.Fab")
		)
		(fp_line
			(start -0.120396 0.2794)
			(end 0.12065 0.2794)
			(stroke
				(width 0.1)
				(type default)
			)
			(layer "B.Fab")
		)
		(fp_line
			(start 0.12065 0.2794)
			(end 0.12065 0.3048)
			(stroke
				(width 0.1)
				(type default)
			)
			(layer "B.Fab")
		)
		(fp_line
			(start -0.12065 -0.2794)
			(end -0.12065 -0.3048)
			(stroke
				(width 0.1)
				(type default)
			)
			(layer "B.Fab")
		)
		(fp_line
			(start 0.12065 -0.2794)
			(end -0.12065 -0.2794)
			(stroke
				(width 0.1)
				(type default)
			)
			(layer "B.Fab")
		)
		(fp_line
			(start -0.67945 -0.3048)
			(end -0.67945 0.3048)
			(stroke
				(width 0.1)
				(type default)
			)
			(layer "B.Fab")
		)
		(fp_line
			(start -0.12065 -0.3048)
			(end -0.67945 -0.3048)
			(stroke
				(width 0.1)
				(type default)
			)
			(layer "B.Fab")
		)
		(fp_line
			(start 0.12065 -0.305054)
			(end 0.12065 -0.2794)
			(stroke
				(width 0.1)
				(type default)
			)
			(layer "B.Fab")
		)
		(fp_line
			(start 0.67945 -0.305054)
			(end 0.12065 -0.305054)
			(stroke
				(width 0.1)
				(type default)
			)
			(layer "B.Fab")
		)
		(pad "1" smd circle
			(at 0.40005 0 90)
			(size 0 0)
			(layers "B.Cu" "B.Mask" "B.Paste")
			(net "PVNN_TERM_CPU1")
		)
		(pad "2" smd circle
			(at -0.40005 0 90)
			(size 0 0)
			(layers "B.Cu" "B.Mask" "B.Paste")
			(net "FM_S3M_CPU1_LVC1_GPIO_3")
		)
	)
	(footprint ""
		(layer "B.Cu")
		(at 155.031694 -36.950142 180)
		(property "Reference" "C2322"
			(at 0 0 0)
			(layer "B.SilkS")
			(hide yes)
			(effects
				(font
					(size 1.27 1.27)
				)
				(justify mirror)
			)
		)
		(property "Value" ""
			(at 0 0 0)
			(layer "B.Fab")
			(effects
				(font
					(size 1.27 1.27)
				)
				(justify mirror)
			)
		)
		(duplicate_pad_numbers_are_jumpers no)
		(fp_line
			(start 0.7874 0.4064)
			(end 0.7874 -0.4064)
			(stroke
				(width 0.1524)
				(type default)
			)
			(layer "B.SilkS")
		)
		(fp_line
			(start 0.7874 -0.4064)
			(end -0.7874 -0.4064)
			(stroke
				(width 0.1524)
				(type default)
			)
			(layer "B.SilkS")
		)
		(fp_line
			(start -0.7874 0.4064)
			(end 0.7874 0.4064)
			(stroke
				(width 0.1524)
				(type default)
			)
			(layer "B.SilkS")
		)
		(fp_line
			(start -0.7874 -0.4064)
			(end -0.7874 0.4064)
			(stroke
				(width 0.1524)
				(type default)
			)
			(layer "B.SilkS")
		)
		(fp_line
			(start 0.67945 0.3048)
			(end 0.67945 -0.305054)
			(stroke
				(width 0.1)
				(type default)
			)
			(layer "B.Fab")
		)
		(fp_line
			(start 0.67945 -0.305054)
			(end 0.12065 -0.305054)
			(stroke
				(width 0.1)
				(type default)
			)
			(layer "B.Fab")
		)
		(fp_line
			(start 0.12065 0.3048)
			(end 0.67945 0.3048)
			(stroke
				(width 0.1)
				(type default)
			)
			(layer "B.Fab")
		)
		(fp_line
			(start 0.12065 0.2794)
			(end 0.12065 0.3048)
			(stroke
				(width 0.1)
				(type default)
			)
			(layer "B.Fab")
		)
		(fp_line
			(start 0.12065 -0.2794)
			(end -0.12065 -0.2794)
			(stroke
				(width 0.1)
				(type default)
			)
			(layer "B.Fab")
		)
		(fp_line
			(start 0.12065 -0.305054)
			(end 0.12065 -0.2794)
			(stroke
				(width 0.1)
				(type default)
			)
			(layer "B.Fab")
		)
		(fp_line
			(start -0.120396 0.3048)
			(end -0.120396 0.2794)
			(stroke
				(width 0.1)
				(type default)
			)
			(layer "B.Fab")
		)
		(fp_line
			(start -0.120396 0.2794)
			(end 0.12065 0.2794)
			(stroke
				(width 0.1)
				(type default)
			)
			(layer "B.Fab")
		)
		(fp_line
			(start -0.12065 -0.2794)
			(end -0.12065 -0.3048)
			(stroke
				(width 0.1)
				(type default)
			)
			(layer "B.Fab")
		)
		(fp_line
			(start -0.12065 -0.3048)
			(end -0.67945 -0.3048)
			(stroke
				(width 0.1)
				(type default)
			)
			(layer "B.Fab")
		)
		(fp_line
			(start -0.67945 0.3048)
			(end -0.120396 0.3048)
			(stroke
				(width 0.1)
				(type default)
			)
			(layer "B.Fab")
		)
		(fp_line
			(start -0.67945 -0.3048)
			(end -0.67945 0.3048)
			(stroke
				(width 0.1)
				(type default)
			)
			(layer "B.Fab")
		)
		(pad "1" smd circle
			(at 0.40005 0)
			(size 0 0)
			(layers "B.Cu" "B.Mask" "B.Paste")
			(net "P3V3_AUX_USB_HUB_2")
		)
		(pad "2" smd circle
			(at -0.40005 0)
			(size 0 0)
			(layers "B.Cu" "B.Mask" "B.Paste")
			(net "GND")
		)
	)
	(footprint ""
		(layer "B.Cu")
		(at 337.218782 -64.315848 90)
		(property "Reference" "C169"
			(at 0 0 90)
			(layer "B.SilkS")
			(hide yes)
			(effects
				(font
					(size 1.27 1.27)
				)
				(justify mirror)
			)
		)
		(property "Value" ""
			(at 0 0 90)
			(layer "B.Fab")
			(effects
				(font
					(size 1.27 1.27)
				)
				(justify mirror)
			)
		)
		(duplicate_pad_numbers_are_jumpers no)
		(fp_line
			(start 0.299974 -0.150114)
			(end -0.299974 -0.150114)
			(stroke
				(width 0.1)
				(type default)
			)
			(layer "B.Fab")
		)
		(fp_line
			(start -0.299974 -0.150114)
			(end -0.299974 0.150114)
			(stroke
				(width 0.1)
				(type default)
			)
			(layer "B.Fab")
		)
		(fp_line
			(start 0.299974 0.150114)
			(end 0.299974 -0.150114)
			(stroke
				(width 0.1)
				(type default)
			)
			(layer "B.Fab")
		)
		(fp_line
			(start -0.299974 0.150114)
			(end 0.299974 0.150114)
			(stroke
				(width 0.1)
				(type default)
			)
			(layer "B.Fab")
		)
		(pad "1" smd rect
			(at 0.2667 0 270)
			(size 0.3048 0.381)
			(layers "B.Cu" "B.Mask" "B.Paste")
			(net "DMI_CPU0_PCH_RX_C_DN<0>")
		)
		(pad "2" smd rect
			(at -0.2667 0 270)
			(size 0.3048 0.381)
			(layers "B.Cu" "B.Mask" "B.Paste")
			(net "DMI_CPU0_PCH_RX_DN<0>")
		)
	)
	(footprint ""
		(layer "B.Cu")
		(at 341.272114 -31.678372)
		(property "Reference" "R8"
			(at 0 0 0)
			(layer "B.SilkS")
			(hide yes)
			(effects
				(font
					(size 1.27 1.27)
				)
				(justify mirror)
			)
		)
		(property "Value" ""
			(at 0 0 0)
			(layer "B.Fab")
			(effects
				(font
					(size 1.27 1.27)
				)
				(justify mirror)
			)
		)
		(duplicate_pad_numbers_are_jumpers no)
		(fp_line
			(start -0.7874 -0.4064)
			(end -0.7874 0.4064)
			(stroke
				(width 0.1524)
				(type default)
			)
			(layer "B.SilkS")
		)
		(fp_line
			(start -0.7874 0.4064)
			(end 0.7874 0.4064)
			(stroke
				(width 0.1524)
				(type default)
			)
			(layer "B.SilkS")
		)
		(fp_line
			(start 0.7874 -0.4064)
			(end -0.7874 -0.4064)
			(stroke
				(width 0.1524)
				(type default)
			)
			(layer "B.SilkS")
		)
		(fp_line
			(start 0.7874 0.4064)
			(end 0.7874 -0.4064)
			(stroke
				(width 0.1524)
				(type default)
			)
			(layer "B.SilkS")
		)
		(fp_line
			(start -0.67945 -0.3048)
			(end -0.67945 0.3048)
			(stroke
				(width 0.1)
				(type default)
			)
			(layer "B.Fab")
		)
		(fp_line
			(start -0.67945 0.3048)
			(end -0.120396 0.3048)
			(stroke
				(width 0.1)
				(type default)
			)
			(layer "B.Fab")
		)
		(fp_line
			(start -0.12065 -0.3048)
			(end -0.67945 -0.3048)
			(stroke
				(width 0.1)
				(type default)
			)
			(layer "B.Fab")
		)
		(fp_line
			(start -0.12065 -0.2794)
			(end -0.12065 -0.3048)
			(stroke
				(width 0.1)
				(type default)
			)
			(layer "B.Fab")
		)
		(fp_line
			(start -0.120396 0.2794)
			(end 0.12065 0.2794)
			(stroke
				(width 0.1)
				(type default)
			)
			(layer "B.Fab")
		)
		(fp_line
			(start -0.120396 0.3048)
			(end -0.120396 0.2794)
			(stroke
				(width 0.1)
				(type default)
			)
			(layer "B.Fab")
		)
		(fp_line
			(start 0.12065 -0.305054)
			(end 0.12065 -0.2794)
			(stroke
				(width 0.1)
				(type default)
			)
			(layer "B.Fab")
		)
		(fp_line
			(start 0.12065 -0.2794)
			(end -0.12065 -0.2794)
			(stroke
				(width 0.1)
				(type default)
			)
			(layer "B.Fab")
		)
		(fp_line
			(start 0.12065 0.2794)
			(end 0.12065 0.3048)
			(stroke
				(width 0.1)
				(type default)
			)
			(layer "B.Fab")
		)
		(fp_line
			(start 0.12065 0.3048)
			(end 0.67945 0.3048)
			(stroke
				(width 0.1)
				(type default)
			)
			(layer "B.Fab")
		)
		(fp_line
			(start 0.67945 -0.305054)
			(end 0.12065 -0.305054)
			(stroke
				(width 0.1)
				(type default)
			)
			(layer "B.Fab")
		)
		(fp_line
			(start 0.67945 0.3048)
			(end 0.67945 -0.305054)
			(stroke
				(width 0.1)
				(type default)
			)
			(layer "B.Fab")
		)
		(pad "1" smd circle
			(at 0.40005 0 180)
			(size 0 0)
			(layers "B.Cu" "B.Mask" "B.Paste")
			(net "P3V3_AUX")
		)
		(pad "2" smd circle
			(at -0.40005 0 180)
			(size 0 0)
			(layers "B.Cu" "B.Mask" "B.Paste")
			(net "FM_PS_PWROK_DLY_R_SEL")
		)
	)
	(footprint ""
		(layer "B.Cu")
		(at 258.50088 -78.577948 90)
		(property "Reference" "PR1647"
			(at 0 0 90)
			(layer "B.SilkS")
			(hide yes)
			(effects
				(font
					(size 1.27 1.27)
				)
				(justify mirror)
			)
		)
		(property "Value" ""
			(at 0 0 90)
			(layer "B.Fab")
			(effects
				(font
					(size 1.27 1.27)
				)
				(justify mirror)
			)
		)
		(duplicate_pad_numbers_are_jumpers no)
		(fp_line
			(start 0.7874 -0.4064)
			(end -0.7874 -0.4064)
			(stroke
				(width 0.1524)
				(type default)
			)
			(layer "B.SilkS")
		)
		(fp_line
			(start -0.7874 -0.4064)
			(end -0.7874 0.4064)
			(stroke
				(width 0.1524)
				(type default)
			)
			(layer "B.SilkS")
		)
		(fp_line
			(start 0.7874 0.4064)
			(end 0.7874 -0.4064)
			(stroke
				(width 0.1524)
				(type default)
			)
			(layer "B.SilkS")
		)
		(fp_line
			(start -0.7874 0.4064)
			(end 0.7874 0.4064)
			(stroke
				(width 0.1524)
				(type default)
			)
			(layer "B.SilkS")
		)
		(fp_line
			(start 0.67945 -0.305054)
			(end 0.12065 -0.305054)
			(stroke
				(width 0.1)
				(type default)
			)
			(layer "B.Fab")
		)
		(fp_line
			(start 0.12065 -0.305054)
			(end 0.12065 -0.2794)
			(stroke
				(width 0.1)
				(type default)
			)
			(layer "B.Fab")
		)
		(fp_line
			(start -0.12065 -0.3048)
			(end -0.67945 -0.3048)
			(stroke
				(width 0.1)
				(type default)
			)
			(layer "B.Fab")
		)
		(fp_line
			(start -0.67945 -0.3048)
			(end -0.67945 0.3048)
			(stroke
				(width 0.1)
				(type default)
			)
			(layer "B.Fab")
		)
		(fp_line
			(start 0.12065 -0.2794)
			(end -0.12065 -0.2794)
			(stroke
				(width 0.1)
				(type default)
			)
			(layer "B.Fab")
		)
		(fp_line
			(start -0.12065 -0.2794)
			(end -0.12065 -0.3048)
			(stroke
				(width 0.1)
				(type default)
			)
			(layer "B.Fab")
		)
		(fp_line
			(start 0.12065 0.2794)
			(end 0.12065 0.3048)
			(stroke
				(width 0.1)
				(type default)
			)
			(layer "B.Fab")
		)
		(fp_line
			(start -0.120396 0.2794)
			(end 0.12065 0.2794)
			(stroke
				(width 0.1)
				(type default)
			)
			(layer "B.Fab")
		)
		(fp_line
			(start 0.67945 0.3048)
			(end 0.67945 -0.305054)
			(stroke
				(width 0.1)
				(type default)
			)
			(layer "B.Fab")
		)
		(fp_line
			(start 0.12065 0.3048)
			(end 0.67945 0.3048)
			(stroke
				(width 0.1)
				(type default)
			)
			(layer "B.Fab")
		)
		(fp_line
			(start -0.120396 0.3048)
			(end -0.120396 0.2794)
			(stroke
				(width 0.1)
				(type default)
			)
			(layer "B.Fab")
		)
		(fp_line
			(start -0.67945 0.3048)
			(end -0.120396 0.3048)
			(stroke
				(width 0.1)
				(type default)
			)
			(layer "B.Fab")
		)
		(pad "1" smd circle
			(at 0.40005 0 270)
			(size 0 0)
			(layers "B.Cu" "B.Mask" "B.Paste")
			(net "P3V3_AUX")
		)
		(pad "2" smd circle
			(at -0.40005 0 270)
			(size 0 0)
			(layers "B.Cu" "B.Mask" "B.Paste")
			(net "FM_P1V05_PCH_AUX_R_EN")
		)
	)
	(footprint ""
		(layer "B.Cu")
		(at 72.401684 -188.458856 90)
		(property "Reference" "R60"
			(at 0 0 90)
			(layer "B.SilkS")
			(hide yes)
			(effects
				(font
					(size 1.27 1.27)
				)
				(justify mirror)
			)
		)
		(property "Value" ""
			(at 0 0 90)
			(layer "B.Fab")
			(effects
				(font
					(size 1.27 1.27)
				)
				(justify mirror)
			)
		)
		(duplicate_pad_numbers_are_jumpers no)
		(fp_line
			(start 0.7874 -0.4064)
			(end -0.7874 -0.4064)
			(stroke
				(width 0.1524)
				(type default)
			)
			(layer "B.SilkS")
		)
		(fp_line
			(start -0.7874 -0.4064)
			(end -0.7874 0.4064)
			(stroke
				(width 0.1524)
				(type default)
			)
			(layer "B.SilkS")
		)
		(fp_line
			(start 0.7874 0.4064)
			(end 0.7874 -0.4064)
			(stroke
				(width 0.1524)
				(type default)
			)
			(layer "B.SilkS")
		)
		(fp_line
			(start -0.7874 0.4064)
			(end 0.7874 0.4064)
			(stroke
				(width 0.1524)
				(type default)
			)
			(layer "B.SilkS")
		)
		(fp_line
			(start 0.67945 -0.305054)
			(end 0.12065 -0.305054)
			(stroke
				(width 0.1)
				(type default)
			)
			(layer "B.Fab")
		)
		(fp_line
			(start 0.12065 -0.305054)
			(end 0.12065 -0.2794)
			(stroke
				(width 0.1)
				(type default)
			)
			(layer "B.Fab")
		)
		(fp_line
			(start -0.12065 -0.3048)
			(end -0.67945 -0.3048)
			(stroke
				(width 0.1)
				(type default)
			)
			(layer "B.Fab")
		)
		(fp_line
			(start -0.67945 -0.3048)
			(end -0.67945 0.3048)
			(stroke
				(width 0.1)
				(type default)
			)
			(layer "B.Fab")
		)
		(fp_line
			(start 0.12065 -0.2794)
			(end -0.12065 -0.2794)
			(stroke
				(width 0.1)
				(type default)
			)
			(layer "B.Fab")
		)
		(fp_line
			(start -0.12065 -0.2794)
			(end -0.12065 -0.3048)
			(stroke
				(width 0.1)
				(type default)
			)
			(layer "B.Fab")
		)
		(fp_line
			(start 0.12065 0.2794)
			(end 0.12065 0.3048)
			(stroke
				(width 0.1)
				(type default)
			)
			(layer "B.Fab")
		)
		(fp_line
			(start -0.120396 0.2794)
			(end 0.12065 0.2794)
			(stroke
				(width 0.1)
				(type default)
			)
			(layer "B.Fab")
		)
		(fp_line
			(start 0.67945 0.3048)
			(end 0.67945 -0.305054)
			(stroke
				(width 0.1)
				(type default)
			)
			(layer "B.Fab")
		)
		(fp_line
			(start 0.12065 0.3048)
			(end 0.67945 0.3048)
			(stroke
				(width 0.1)
				(type default)
			)
			(layer "B.Fab")
		)
		(fp_line
			(start -0.120396 0.3048)
			(end -0.120396 0.2794)
			(stroke
				(width 0.1)
				(type default)
			)
			(layer "B.Fab")
		)
		(fp_line
			(start -0.67945 0.3048)
			(end -0.120396 0.3048)
			(stroke
				(width 0.1)
				(type default)
			)
			(layer "B.Fab")
		)
		(pad "1" smd circle
			(at 0.40005 0 270)
			(size 0 0)
			(layers "B.Cu" "B.Mask" "B.Paste")
			(net "SVID_ALERT1_CPU1_N")
		)
		(pad "2" smd circle
			(at -0.40005 0 270)
			(size 0 0)
			(layers "B.Cu" "B.Mask" "B.Paste")
			(net "SVID_ALERT1_CPU1_R_N")
		)
	)
	(footprint ""
		(layer "B.Cu")
		(at 359.960418 -296.054526)
		(property "Reference" "C392"
			(at 0 0 0)
			(layer "B.SilkS")
			(hide yes)
			(effects
				(font
					(size 1.27 1.27)
				)
				(justify mirror)
			)
		)
		(property "Value" ""
			(at 0 0 0)
			(layer "B.Fab")
			(effects
				(font
					(size 1.27 1.27)
				)
				(justify mirror)
			)
		)
		(duplicate_pad_numbers_are_jumpers no)
		(fp_line
			(start -1.524 -0.762)
			(end -1.524 0.762)
			(stroke
				(width 0.1524)
				(type default)
			)
			(layer "B.SilkS")
		)
		(fp_line
			(start -1.524 0.762)
			(end 1.524 0.762)
			(stroke
				(width 0.1524)
				(type default)
			)
			(layer "B.SilkS")
		)
		(fp_line
			(start 1.524 -0.762)
			(end -1.524 -0.762)
			(stroke
				(width 0.1524)
				(type default)
			)
			(layer "B.SilkS")
		)
		(fp_line
			(start 1.524 0.762)
			(end 1.524 -0.762)
			(stroke
				(width 0.1524)
				(type default)
			)
			(layer "B.SilkS")
		)
		(fp_line
			(start -1.1049 -0.724916)
			(end 1.1049 -0.724916)
			(stroke
				(width 0.1)
				(type default)
			)
			(layer "B.Fab")
		)
		(fp_line
			(start -1.1049 0.724916)
			(end -1.1049 -0.724916)
			(stroke
				(width 0.1)
				(type default)
			)
			(layer "B.Fab")
		)
		(fp_line
			(start 1.1049 -0.724916)
			(end 1.1049 0.724916)
			(stroke
				(width 0.1)
				(type default)
			)
			(layer "B.Fab")
		)
		(fp_line
			(start 1.1049 0.724916)
			(end -1.1049 0.724916)
			(stroke
				(width 0.1)
				(type default)
			)
			(layer "B.Fab")
		)
		(pad "1" smd rect
			(at 0.889 0)
			(size 1.016 1.27)
			(layers "B.Cu" "B.Mask" "B.Paste")
			(net "PVCCIN_CPU0")
		)
		(pad "2" smd rect
			(at -0.889 0)
			(size 1.016 1.27)
			(layers "B.Cu" "B.Mask" "B.Paste")
			(net "GND")
		)
	)
	(footprint ""
		(layer "B.Cu")
		(at 310.567578 -193.52895 -90)
		(property "Reference" "R3"
			(at 0 0 90)
			(layer "B.SilkS")
			(hide yes)
			(effects
				(font
					(size 1.27 1.27)
				)
				(justify mirror)
			)
		)
		(property "Value" ""
			(at 0 0 90)
			(layer "B.Fab")
			(effects
				(font
					(size 1.27 1.27)
				)
				(justify mirror)
			)
		)
		(duplicate_pad_numbers_are_jumpers no)
		(fp_line
			(start -0.7874 0.4064)
			(end 0.7874 0.4064)
			(stroke
				(width 0.1524)
				(type default)
			)
			(layer "B.SilkS")
		)
		(fp_line
			(start 0.7874 0.4064)
			(end 0.7874 -0.4064)
			(stroke
				(width 0.1524)
				(type default)
			)
			(layer "B.SilkS")
		)
		(fp_line
			(start -0.7874 -0.4064)
			(end -0.7874 0.4064)
			(stroke
				(width 0.1524)
				(type default)
			)
			(layer "B.SilkS")
		)
		(fp_line
			(start 0.7874 -0.4064)
			(end -0.7874 -0.4064)
			(stroke
				(width 0.1524)
				(type default)
			)
			(layer "B.SilkS")
		)
		(fp_line
			(start -0.67945 0.3048)
			(end -0.120396 0.3048)
			(stroke
				(width 0.1)
				(type default)
			)
			(layer "B.Fab")
		)
		(fp_line
			(start -0.120396 0.3048)
			(end -0.120396 0.2794)
			(stroke
				(width 0.1)
				(type default)
			)
			(layer "B.Fab")
		)
		(fp_line
			(start 0.12065 0.3048)
			(end 0.67945 0.3048)
			(stroke
				(width 0.1)
				(type default)
			)
			(layer "B.Fab")
		)
		(fp_line
			(start 0.67945 0.3048)
			(end 0.67945 -0.305054)
			(stroke
				(width 0.1)
				(type default)
			)
			(layer "B.Fab")
		)
		(fp_line
			(start -0.120396 0.2794)
			(end 0.12065 0.2794)
			(stroke
				(width 0.1)
				(type default)
			)
			(layer "B.Fab")
		)
		(fp_line
			(start 0.12065 0.2794)
			(end 0.12065 0.3048)
			(stroke
				(width 0.1)
				(type default)
			)
			(layer "B.Fab")
		)
		(fp_line
			(start -0.12065 -0.2794)
			(end -0.12065 -0.3048)
			(stroke
				(width 0.1)
				(type default)
			)
			(layer "B.Fab")
		)
		(fp_line
			(start 0.12065 -0.2794)
			(end -0.12065 -0.2794)
			(stroke
				(width 0.1)
				(type default)
			)
			(layer "B.Fab")
		)
		(fp_line
			(start -0.67945 -0.3048)
			(end -0.67945 0.3048)
			(stroke
				(width 0.1)
				(type default)
			)
			(layer "B.Fab")
		)
		(fp_line
			(start -0.12065 -0.3048)
			(end -0.67945 -0.3048)
			(stroke
				(width 0.1)
				(type default)
			)
			(layer "B.Fab")
		)
		(fp_line
			(start 0.12065 -0.305054)
			(end 0.12065 -0.2794)
			(stroke
				(width 0.1)
				(type default)
			)
			(layer "B.Fab")
		)
		(fp_line
			(start 0.67945 -0.305054)
			(end 0.12065 -0.305054)
			(stroke
				(width 0.1)
				(type default)
			)
			(layer "B.Fab")
		)
		(pad "1" smd circle
			(at 0.40005 0 90)
			(size 0 0)
			(layers "B.Cu" "B.Mask" "B.Paste")
			(net "PECI_CPU_GTL")
		)
		(pad "2" smd circle
			(at -0.40005 0 90)
			(size 0 0)
			(layers "B.Cu" "B.Mask" "B.Paste")
			(net "PECI_CPU0_GTL_R")
		)
	)
	(footprint ""
		(layer "B.Cu")
		(at 332.197456 -58.473086 -90)
		(property "Reference" "C1181"
			(at 0 0 90)
			(layer "B.SilkS")
			(hide yes)
			(effects
				(font
					(size 1.27 1.27)
				)
				(justify mirror)
			)
		)
		(property "Value" ""
			(at 0 0 90)
			(layer "B.Fab")
			(effects
				(font
					(size 1.27 1.27)
				)
				(justify mirror)
			)
		)
		(duplicate_pad_numbers_are_jumpers no)
		(fp_line
			(start -1.2954 0.5842)
			(end 1.2954 0.5842)
			(stroke
				(width 0.1524)
				(type default)
			)
			(layer "B.SilkS")
		)
		(fp_line
			(start 1.2954 0.5842)
			(end 1.2954 -0.5842)
			(stroke
				(width 0.1524)
				(type default)
			)
			(layer "B.SilkS")
		)
		(fp_line
			(start -1.2954 -0.5842)
			(end -1.2954 0.5842)
			(stroke
				(width 0.1524)
				(type default)
			)
			(layer "B.SilkS")
		)
		(fp_line
			(start 0 -0.5842)
			(end 0 0.5842)
			(stroke
				(width 0.1524)
				(type default)
			)
			(layer "B.SilkS")
		)
		(fp_line
			(start 1.2954 -0.5842)
			(end -1.2954 -0.5842)
			(stroke
				(width 0.1524)
				(type default)
			)
			(layer "B.SilkS")
		)
		(fp_line
			(start -0.8636 0.4572)
			(end 0.8636 0.4572)
			(stroke
				(width 0.1)
				(type default)
			)
			(layer "B.Fab")
		)
		(fp_line
			(start 0.8636 0.4572)
			(end 0.8636 0.4064)
			(stroke
				(width 0.1)
				(type default)
			)
			(layer "B.Fab")
		)
		(fp_line
			(start -1.1938 0.4064)
			(end -0.8636 0.4064)
			(stroke
				(width 0.1)
				(type default)
			)
			(layer "B.Fab")
		)
		(fp_line
			(start -0.8636 0.4064)
			(end -0.8636 0.4572)
			(stroke
				(width 0.1)
				(type default)
			)
			(layer "B.Fab")
		)
		(fp_line
			(start 0.8636 0.4064)
			(end 1.1938 0.4064)
			(stroke
				(width 0.1)
				(type default)
			)
			(layer "B.Fab")
		)
		(fp_line
			(start 1.1938 0.4064)
			(end 1.1938 -0.4064)
			(stroke
				(width 0.1)
				(type default)
			)
			(layer "B.Fab")
		)
		(fp_line
			(start -1.1938 -0.4064)
			(end -1.1938 0.4064)
			(stroke
				(width 0.1)
				(type default)
			)
			(layer "B.Fab")
		)
		(fp_line
			(start -0.8636 -0.4064)
			(end -1.1938 -0.4064)
			(stroke
				(width 0.1)
				(type default)
			)
			(layer "B.Fab")
		)
		(fp_line
			(start 0.8636 -0.4064)
			(end 0.8636 -0.4572)
			(stroke
				(width 0.1)
				(type default)
			)
			(layer "B.Fab")
		)
		(fp_line
			(start 1.1938 -0.4064)
			(end 0.8636 -0.4064)
			(stroke
				(width 0.1)
				(type default)
			)
			(layer "B.Fab")
		)
		(fp_line
			(start -0.8636 -0.4572)
			(end -0.8636 -0.4064)
			(stroke
				(width 0.1)
				(type default)
			)
			(layer "B.Fab")
		)
		(fp_line
			(start 0.8636 -0.4572)
			(end -0.8636 -0.4572)
			(stroke
				(width 0.1)
				(type default)
			)
			(layer "B.Fab")
		)
		(pad "1" smd rect
			(at 0.7366 0 180)
			(size 0.7112 0.8128)
			(layers "B.Cu" "B.Mask" "B.Paste")
			(net "P1V8_PCH_AUX")
		)
		(pad "2" smd rect
			(at -0.7366 0 180)
			(size 0.7112 0.8128)
			(layers "B.Cu" "B.Mask" "B.Paste")
			(net "GND")
		)
	)
	(footprint ""
		(layer "B.Cu")
		(at 380.80823 -190.82131 90)
		(property "Reference" "R1240"
			(at 0 0 90)
			(layer "B.SilkS")
			(hide yes)
			(effects
				(font
					(size 1.27 1.27)
				)
				(justify mirror)
			)
		)
		(property "Value" ""
			(at 0 0 90)
			(layer "B.Fab")
			(effects
				(font
					(size 1.27 1.27)
				)
				(justify mirror)
			)
		)
		(duplicate_pad_numbers_are_jumpers no)
		(fp_line
			(start 0.7874 -0.4064)
			(end -0.7874 -0.4064)
			(stroke
				(width 0.1524)
				(type default)
			)
			(layer "B.SilkS")
		)
		(fp_line
			(start -0.7874 -0.4064)
			(end -0.7874 0.4064)
			(stroke
				(width 0.1524)
				(type default)
			)
			(layer "B.SilkS")
		)
		(fp_line
			(start 0.7874 0.4064)
			(end 0.7874 -0.4064)
			(stroke
				(width 0.1524)
				(type default)
			)
			(layer "B.SilkS")
		)
		(fp_line
			(start -0.7874 0.4064)
			(end 0.7874 0.4064)
			(stroke
				(width 0.1524)
				(type default)
			)
			(layer "B.SilkS")
		)
		(fp_line
			(start 0.67945 -0.305054)
			(end 0.12065 -0.305054)
			(stroke
				(width 0.1)
				(type default)
			)
			(layer "B.Fab")
		)
		(fp_line
			(start 0.12065 -0.305054)
			(end 0.12065 -0.2794)
			(stroke
				(width 0.1)
				(type default)
			)
			(layer "B.Fab")
		)
		(fp_line
			(start -0.12065 -0.3048)
			(end -0.67945 -0.3048)
			(stroke
				(width 0.1)
				(type default)
			)
			(layer "B.Fab")
		)
		(fp_line
			(start -0.67945 -0.3048)
			(end -0.67945 0.3048)
			(stroke
				(width 0.1)
				(type default)
			)
			(layer "B.Fab")
		)
		(fp_line
			(start 0.12065 -0.2794)
			(end -0.12065 -0.2794)
			(stroke
				(width 0.1)
				(type default)
			)
			(layer "B.Fab")
		)
		(fp_line
			(start -0.12065 -0.2794)
			(end -0.12065 -0.3048)
			(stroke
				(width 0.1)
				(type default)
			)
			(layer "B.Fab")
		)
		(fp_line
			(start 0.12065 0.2794)
			(end 0.12065 0.3048)
			(stroke
				(width 0.1)
				(type default)
			)
			(layer "B.Fab")
		)
		(fp_line
			(start -0.120396 0.2794)
			(end 0.12065 0.2794)
			(stroke
				(width 0.1)
				(type default)
			)
			(layer "B.Fab")
		)
		(fp_line
			(start 0.67945 0.3048)
			(end 0.67945 -0.305054)
			(stroke
				(width 0.1)
				(type default)
			)
			(layer "B.Fab")
		)
		(fp_line
			(start 0.12065 0.3048)
			(end 0.67945 0.3048)
			(stroke
				(width 0.1)
				(type default)
			)
			(layer "B.Fab")
		)
		(fp_line
			(start -0.120396 0.3048)
			(end -0.120396 0.2794)
			(stroke
				(width 0.1)
				(type default)
			)
			(layer "B.Fab")
		)
		(fp_line
			(start -0.67945 0.3048)
			(end -0.120396 0.3048)
			(stroke
				(width 0.1)
				(type default)
			)
			(layer "B.Fab")
		)
		(pad "1" smd circle
			(at 0.40005 0 270)
			(size 0 0)
			(layers "B.Cu" "B.Mask" "B.Paste")
			(net "H_CPU0_PM_FAST_WAKE_N")
		)
		(pad "2" smd circle
			(at -0.40005 0 270)
			(size 0 0)
			(layers "B.Cu" "B.Mask" "B.Paste")
			(net "H_CPU_PM_FAST_WAKE_N")
		)
	)
	(footprint ""
		(layer "B.Cu")
		(at 206.162656 -70.31228 180)
		(property "Reference" "R3214"
			(at 0 0 0)
			(layer "B.SilkS")
			(hide yes)
			(effects
				(font
					(size 1.27 1.27)
				)
				(justify mirror)
			)
		)
		(property "Value" ""
			(at 0 0 0)
			(layer "B.Fab")
			(effects
				(font
					(size 1.27 1.27)
				)
				(justify mirror)
			)
		)
		(duplicate_pad_numbers_are_jumpers no)
		(fp_line
			(start 0.7874 0.4064)
			(end 0.7874 -0.4064)
			(stroke
				(width 0.1524)
				(type default)
			)
			(layer "B.SilkS")
		)
		(fp_line
			(start 0.7874 -0.4064)
			(end -0.7874 -0.4064)
			(stroke
				(width 0.1524)
				(type default)
			)
			(layer "B.SilkS")
		)
		(fp_line
			(start -0.7874 0.4064)
			(end 0.7874 0.4064)
			(stroke
				(width 0.1524)
				(type default)
			)
			(layer "B.SilkS")
		)
		(fp_line
			(start -0.7874 -0.4064)
			(end -0.7874 0.4064)
			(stroke
				(width 0.1524)
				(type default)
			)
			(layer "B.SilkS")
		)
		(fp_line
			(start 0.67945 0.3048)
			(end 0.67945 -0.305054)
			(stroke
				(width 0.1)
				(type default)
			)
			(layer "B.Fab")
		)
		(fp_line
			(start 0.67945 -0.305054)
			(end 0.12065 -0.305054)
			(stroke
				(width 0.1)
				(type default)
			)
			(layer "B.Fab")
		)
		(fp_line
			(start 0.12065 0.3048)
			(end 0.67945 0.3048)
			(stroke
				(width 0.1)
				(type default)
			)
			(layer "B.Fab")
		)
		(fp_line
			(start 0.12065 0.2794)
			(end 0.12065 0.3048)
			(stroke
				(width 0.1)
				(type default)
			)
			(layer "B.Fab")
		)
		(fp_line
			(start 0.12065 -0.2794)
			(end -0.12065 -0.2794)
			(stroke
				(width 0.1)
				(type default)
			)
			(layer "B.Fab")
		)
		(fp_line
			(start 0.12065 -0.305054)
			(end 0.12065 -0.2794)
			(stroke
				(width 0.1)
				(type default)
			)
			(layer "B.Fab")
		)
		(fp_line
			(start -0.120396 0.3048)
			(end -0.120396 0.2794)
			(stroke
				(width 0.1)
				(type default)
			)
			(layer "B.Fab")
		)
		(fp_line
			(start -0.120396 0.2794)
			(end 0.12065 0.2794)
			(stroke
				(width 0.1)
				(type default)
			)
			(layer "B.Fab")
		)
		(fp_line
			(start -0.12065 -0.2794)
			(end -0.12065 -0.3048)
			(stroke
				(width 0.1)
				(type default)
			)
			(layer "B.Fab")
		)
		(fp_line
			(start -0.12065 -0.3048)
			(end -0.67945 -0.3048)
			(stroke
				(width 0.1)
				(type default)
			)
			(layer "B.Fab")
		)
		(fp_line
			(start -0.67945 0.3048)
			(end -0.120396 0.3048)
			(stroke
				(width 0.1)
				(type default)
			)
			(layer "B.Fab")
		)
		(fp_line
			(start -0.67945 -0.3048)
			(end -0.67945 0.3048)
			(stroke
				(width 0.1)
				(type default)
			)
			(layer "B.Fab")
		)
		(pad "1" smd circle
			(at 0.40005 0)
			(size 0 0)
			(layers "B.Cu" "B.Mask" "B.Paste")
			(net "NCSI_BMC_TXD0_R1")
		)
		(pad "2" smd circle
			(at -0.40005 0)
			(size 0 0)
			(layers "B.Cu" "B.Mask" "B.Paste")
			(net "RMII_BMC_OCP_TXD_0")
		)
	)
	(footprint ""
		(layer "B.Cu")
		(at 402.336 -190.845948 -90)
		(property "Reference" "R4298"
			(at 0 0 90)
			(layer "B.SilkS")
			(hide yes)
			(effects
				(font
					(size 1.27 1.27)
				)
				(justify mirror)
			)
		)
		(property "Value" ""
			(at 0 0 90)
			(layer "B.Fab")
			(effects
				(font
					(size 1.27 1.27)
				)
				(justify mirror)
			)
		)
		(duplicate_pad_numbers_are_jumpers no)
		(fp_line
			(start -0.7874 0.4064)
			(end 0.7874 0.4064)
			(stroke
				(width 0.1524)
				(type default)
			)
			(layer "B.SilkS")
		)
		(fp_line
			(start 0.7874 0.4064)
			(end 0.7874 -0.4064)
			(stroke
				(width 0.1524)
				(type default)
			)
			(layer "B.SilkS")
		)
		(fp_line
			(start -0.7874 -0.4064)
			(end -0.7874 0.4064)
			(stroke
				(width 0.1524)
				(type default)
			)
			(layer "B.SilkS")
		)
		(fp_line
			(start 0.7874 -0.4064)
			(end -0.7874 -0.4064)
			(stroke
				(width 0.1524)
				(type default)
			)
			(layer "B.SilkS")
		)
		(fp_line
			(start -0.67945 0.3048)
			(end -0.120396 0.3048)
			(stroke
				(width 0.1)
				(type default)
			)
			(layer "B.Fab")
		)
		(fp_line
			(start -0.120396 0.3048)
			(end -0.120396 0.2794)
			(stroke
				(width 0.1)
				(type default)
			)
			(layer "B.Fab")
		)
		(fp_line
			(start 0.12065 0.3048)
			(end 0.67945 0.3048)
			(stroke
				(width 0.1)
				(type default)
			)
			(layer "B.Fab")
		)
		(fp_line
			(start 0.67945 0.3048)
			(end 0.67945 -0.305054)
			(stroke
				(width 0.1)
				(type default)
			)
			(layer "B.Fab")
		)
		(fp_line
			(start -0.120396 0.2794)
			(end 0.12065 0.2794)
			(stroke
				(width 0.1)
				(type default)
			)
			(layer "B.Fab")
		)
		(fp_line
			(start 0.12065 0.2794)
			(end 0.12065 0.3048)
			(stroke
				(width 0.1)
				(type default)
			)
			(layer "B.Fab")
		)
		(fp_line
			(start -0.12065 -0.2794)
			(end -0.12065 -0.3048)
			(stroke
				(width 0.1)
				(type default)
			)
			(layer "B.Fab")
		)
		(fp_line
			(start 0.12065 -0.2794)
			(end -0.12065 -0.2794)
			(stroke
				(width 0.1)
				(type default)
			)
			(layer "B.Fab")
		)
		(fp_line
			(start -0.67945 -0.3048)
			(end -0.67945 0.3048)
			(stroke
				(width 0.1)
				(type default)
			)
			(layer "B.Fab")
		)
		(fp_line
			(start -0.12065 -0.3048)
			(end -0.67945 -0.3048)
			(stroke
				(width 0.1)
				(type default)
			)
			(layer "B.Fab")
		)
		(fp_line
			(start 0.12065 -0.305054)
			(end 0.12065 -0.2794)
			(stroke
				(width 0.1)
				(type default)
			)
			(layer "B.Fab")
		)
		(fp_line
			(start 0.67945 -0.305054)
			(end 0.12065 -0.305054)
			(stroke
				(width 0.1)
				(type default)
			)
			(layer "B.Fab")
		)
		(pad "1" smd circle
			(at 0.40005 0 90)
			(size 0 0)
			(layers "B.Cu" "B.Mask" "B.Paste")
			(net "PWRGD_DRAMPWRGD_CPU0_GH_LVC1_R2")
		)
		(pad "2" smd circle
			(at -0.40005 0 90)
			(size 0 0)
			(layers "B.Cu" "B.Mask" "B.Paste")
			(net "PWRGD_DRAMPWRGD_CPU0_GH_LVC1_R")
		)
	)
	(footprint ""
		(layer "B.Cu")
		(at 338.441792 -137.832338)
		(property "Reference" "R1013"
			(at 0 0 0)
			(layer "B.SilkS")
			(hide yes)
			(effects
				(font
					(size 1.27 1.27)
				)
				(justify mirror)
			)
		)
		(property "Value" ""
			(at 0 0 0)
			(layer "B.Fab")
			(effects
				(font
					(size 1.27 1.27)
				)
				(justify mirror)
			)
		)
		(duplicate_pad_numbers_are_jumpers no)
		(fp_line
			(start -0.7874 -0.4064)
			(end -0.7874 0.4064)
			(stroke
				(width 0.1524)
				(type default)
			)
			(layer "B.SilkS")
		)
		(fp_line
			(start -0.7874 0.4064)
			(end -0.281432 0.4064)
			(stroke
				(width 0.1524)
				(type default)
			)
			(layer "B.SilkS")
		)
		(fp_line
			(start 0.333248 0.4064)
			(end 0.7874 0.4064)
			(stroke
				(width 0.1524)
				(type default)
			)
			(layer "B.SilkS")
		)
		(fp_line
			(start 0.7874 -0.4064)
			(end -0.7874 -0.4064)
			(stroke
				(width 0.1524)
				(type default)
			)
			(layer "B.SilkS")
		)
		(fp_line
			(start 0.7874 -0.18161)
			(end 0.7874 -0.4064)
			(stroke
				(width 0.1524)
				(type default)
			)
			(layer "B.SilkS")
		)
		(fp_line
			(start 0.7874 0.4064)
			(end 0.7874 0.21971)
			(stroke
				(width 0.1524)
				(type default)
			)
			(layer "B.SilkS")
		)
		(fp_line
			(start -0.67945 -0.3048)
			(end -0.67945 0.3048)
			(stroke
				(width 0.1)
				(type default)
			)
			(layer "B.Fab")
		)
		(fp_line
			(start -0.67945 0.3048)
			(end -0.120396 0.3048)
			(stroke
				(width 0.1)
				(type default)
			)
			(layer "B.Fab")
		)
		(fp_line
			(start -0.12065 -0.3048)
			(end -0.67945 -0.3048)
			(stroke
				(width 0.1)
				(type default)
			)
			(layer "B.Fab")
		)
		(fp_line
			(start -0.12065 -0.2794)
			(end -0.12065 -0.3048)
			(stroke
				(width 0.1)
				(type default)
			)
			(layer "B.Fab")
		)
		(fp_line
			(start -0.120396 0.2794)
			(end 0.12065 0.2794)
			(stroke
				(width 0.1)
				(type default)
			)
			(layer "B.Fab")
		)
		(fp_line
			(start -0.120396 0.3048)
			(end -0.120396 0.2794)
			(stroke
				(width 0.1)
				(type default)
			)
			(layer "B.Fab")
		)
		(fp_line
			(start 0.12065 -0.305054)
			(end 0.12065 -0.2794)
			(stroke
				(width 0.1)
				(type default)
			)
			(layer "B.Fab")
		)
		(fp_line
			(start 0.12065 -0.2794)
			(end -0.12065 -0.2794)
			(stroke
				(width 0.1)
				(type default)
			)
			(layer "B.Fab")
		)
		(fp_line
			(start 0.12065 0.2794)
			(end 0.12065 0.3048)
			(stroke
				(width 0.1)
				(type default)
			)
			(layer "B.Fab")
		)
		(fp_line
			(start 0.12065 0.3048)
			(end 0.67945 0.3048)
			(stroke
				(width 0.1)
				(type default)
			)
			(layer "B.Fab")
		)
		(fp_line
			(start 0.67945 -0.305054)
			(end 0.12065 -0.305054)
			(stroke
				(width 0.1)
				(type default)
			)
			(layer "B.Fab")
		)
		(fp_line
			(start 0.67945 0.3048)
			(end 0.67945 -0.305054)
			(stroke
				(width 0.1)
				(type default)
			)
			(layer "B.Fab")
		)
		(pad "1" smd rect
			(at 0.40005 0)
			(size 0.4572 0.508)
			(layers "B.Cu" "B.Mask" "B.Paste")
			(net "CLK_25M_PCH_CPU0_DP")
		)
		(pad "2" smd rect
			(at -0.40005 0)
			(size 0.4572 0.508)
			(layers "B.Cu" "B.Mask" "B.Paste")
			(net "CLK_25M_NSSC_CPU0_DP")
		)
	)
	(footprint ""
		(layer "B.Cu")
		(at 102.909624 -334.845152 -90)
		(property "Reference" "PR327"
			(at 0 0 90)
			(layer "B.SilkS")
			(hide yes)
			(effects
				(font
					(size 1.27 1.27)
				)
				(justify mirror)
			)
		)
		(property "Value" ""
			(at 0 0 90)
			(layer "B.Fab")
			(effects
				(font
					(size 1.27 1.27)
				)
				(justify mirror)
			)
		)
		(duplicate_pad_numbers_are_jumpers no)
		(fp_line
			(start -0.7874 0.4064)
			(end 0.7874 0.4064)
			(stroke
				(width 0.1524)
				(type default)
			)
			(layer "B.SilkS")
		)
		(fp_line
			(start 0.7874 0.4064)
			(end 0.7874 -0.4064)
			(stroke
				(width 0.1524)
				(type default)
			)
			(layer "B.SilkS")
		)
		(fp_line
			(start -0.7874 -0.4064)
			(end -0.7874 0.4064)
			(stroke
				(width 0.1524)
				(type default)
			)
			(layer "B.SilkS")
		)
		(fp_line
			(start 0.7874 -0.4064)
			(end -0.7874 -0.4064)
			(stroke
				(width 0.1524)
				(type default)
			)
			(layer "B.SilkS")
		)
		(fp_line
			(start -0.67945 0.3048)
			(end -0.120396 0.3048)
			(stroke
				(width 0.1)
				(type default)
			)
			(layer "B.Fab")
		)
		(fp_line
			(start -0.120396 0.3048)
			(end -0.120396 0.2794)
			(stroke
				(width 0.1)
				(type default)
			)
			(layer "B.Fab")
		)
		(fp_line
			(start 0.12065 0.3048)
			(end 0.67945 0.3048)
			(stroke
				(width 0.1)
				(type default)
			)
			(layer "B.Fab")
		)
		(fp_line
			(start 0.67945 0.3048)
			(end 0.67945 -0.305054)
			(stroke
				(width 0.1)
				(type default)
			)
			(layer "B.Fab")
		)
		(fp_line
			(start -0.120396 0.2794)
			(end 0.12065 0.2794)
			(stroke
				(width 0.1)
				(type default)
			)
			(layer "B.Fab")
		)
		(fp_line
			(start 0.12065 0.2794)
			(end 0.12065 0.3048)
			(stroke
				(width 0.1)
				(type default)
			)
			(layer "B.Fab")
		)
		(fp_line
			(start -0.12065 -0.2794)
			(end -0.12065 -0.3048)
			(stroke
				(width 0.1)
				(type default)
			)
			(layer "B.Fab")
		)
		(fp_line
			(start 0.12065 -0.2794)
			(end -0.12065 -0.2794)
			(stroke
				(width 0.1)
				(type default)
			)
			(layer "B.Fab")
		)
		(fp_line
			(start -0.67945 -0.3048)
			(end -0.67945 0.3048)
			(stroke
				(width 0.1)
				(type default)
			)
			(layer "B.Fab")
		)
		(fp_line
			(start -0.12065 -0.3048)
			(end -0.67945 -0.3048)
			(stroke
				(width 0.1)
				(type default)
			)
			(layer "B.Fab")
		)
		(fp_line
			(start 0.12065 -0.305054)
			(end 0.12065 -0.2794)
			(stroke
				(width 0.1)
				(type default)
			)
			(layer "B.Fab")
		)
		(fp_line
			(start 0.67945 -0.305054)
			(end 0.12065 -0.305054)
			(stroke
				(width 0.1)
				(type default)
			)
			(layer "B.Fab")
		)
		(pad "1" smd circle
			(at 0.40005 0 90)
			(size 0 0)
			(layers "B.Cu" "B.Mask" "B.Paste")
			(net "PVCCIN_CPU1_PVCC")
		)
		(pad "2" smd circle
			(at -0.40005 0 90)
			(size 0 0)
			(layers "B.Cu" "B.Mask" "B.Paste")
			(net "PVCCIN_CPU1_VDD2")
		)
	)
	(footprint ""
		(layer "B.Cu")
		(at 16.237712 -112.693958 180)
		(property "Reference" "C5236"
			(at 0 0 0)
			(layer "B.SilkS")
			(hide yes)
			(effects
				(font
					(size 1.27 1.27)
				)
				(justify mirror)
			)
		)
		(property "Value" ""
			(at 0 0 0)
			(layer "B.Fab")
			(effects
				(font
					(size 1.27 1.27)
				)
				(justify mirror)
			)
		)
		(duplicate_pad_numbers_are_jumpers no)
		(fp_line
			(start 0.7874 0.4064)
			(end 0.7874 -0.4064)
			(stroke
				(width 0.1524)
				(type default)
			)
			(layer "B.SilkS")
		)
		(fp_line
			(start 0.7874 -0.4064)
			(end -0.7874 -0.4064)
			(stroke
				(width 0.1524)
				(type default)
			)
			(layer "B.SilkS")
		)
		(fp_line
			(start -0.7874 0.4064)
			(end 0.7874 0.4064)
			(stroke
				(width 0.1524)
				(type default)
			)
			(layer "B.SilkS")
		)
		(fp_line
			(start -0.7874 -0.4064)
			(end -0.7874 0.4064)
			(stroke
				(width 0.1524)
				(type default)
			)
			(layer "B.SilkS")
		)
		(fp_line
			(start 0.67945 0.3048)
			(end 0.67945 -0.305054)
			(stroke
				(width 0.1)
				(type default)
			)
			(layer "B.Fab")
		)
		(fp_line
			(start 0.67945 -0.305054)
			(end 0.12065 -0.305054)
			(stroke
				(width 0.1)
				(type default)
			)
			(layer "B.Fab")
		)
		(fp_line
			(start 0.12065 0.3048)
			(end 0.67945 0.3048)
			(stroke
				(width 0.1)
				(type default)
			)
			(layer "B.Fab")
		)
		(fp_line
			(start 0.12065 0.2794)
			(end 0.12065 0.3048)
			(stroke
				(width 0.1)
				(type default)
			)
			(layer "B.Fab")
		)
		(fp_line
			(start 0.12065 -0.2794)
			(end -0.12065 -0.2794)
			(stroke
				(width 0.1)
				(type default)
			)
			(layer "B.Fab")
		)
		(fp_line
			(start 0.12065 -0.305054)
			(end 0.12065 -0.2794)
			(stroke
				(width 0.1)
				(type default)
			)
			(layer "B.Fab")
		)
		(fp_line
			(start -0.120396 0.3048)
			(end -0.120396 0.2794)
			(stroke
				(width 0.1)
				(type default)
			)
			(layer "B.Fab")
		)
		(fp_line
			(start -0.120396 0.2794)
			(end 0.12065 0.2794)
			(stroke
				(width 0.1)
				(type default)
			)
			(layer "B.Fab")
		)
		(fp_line
			(start -0.12065 -0.2794)
			(end -0.12065 -0.3048)
			(stroke
				(width 0.1)
				(type default)
			)
			(layer "B.Fab")
		)
		(fp_line
			(start -0.12065 -0.3048)
			(end -0.67945 -0.3048)
			(stroke
				(width 0.1)
				(type default)
			)
			(layer "B.Fab")
		)
		(fp_line
			(start -0.67945 0.3048)
			(end -0.120396 0.3048)
			(stroke
				(width 0.1)
				(type default)
			)
			(layer "B.Fab")
		)
		(fp_line
			(start -0.67945 -0.3048)
			(end -0.67945 0.3048)
			(stroke
				(width 0.1)
				(type default)
			)
			(layer "B.Fab")
		)
		(pad "1" smd circle
			(at 0.40005 0)
			(size 0 0)
			(layers "B.Cu" "B.Mask" "B.Paste")
			(net "PD_U5201_VREG")
		)
		(pad "2" smd circle
			(at -0.40005 0)
			(size 0 0)
			(layers "B.Cu" "B.Mask" "B.Paste")
			(net "GND")
		)
	)
	(footprint ""
		(layer "B.Cu")
		(at 299.609002 -317.243714 90)
		(property "Reference" "R3875"
			(at 0 0 90)
			(layer "B.SilkS")
			(hide yes)
			(effects
				(font
					(size 1.27 1.27)
				)
				(justify mirror)
			)
		)
		(property "Value" ""
			(at 0 0 90)
			(layer "B.Fab")
			(effects
				(font
					(size 1.27 1.27)
				)
				(justify mirror)
			)
		)
		(duplicate_pad_numbers_are_jumpers no)
		(fp_line
			(start 0.7874 -0.4064)
			(end -0.7874 -0.4064)
			(stroke
				(width 0.1524)
				(type default)
			)
			(layer "B.SilkS")
		)
		(fp_line
			(start -0.7874 -0.4064)
			(end -0.7874 0.4064)
			(stroke
				(width 0.1524)
				(type default)
			)
			(layer "B.SilkS")
		)
		(fp_line
			(start 0.7874 0.4064)
			(end 0.7874 -0.4064)
			(stroke
				(width 0.1524)
				(type default)
			)
			(layer "B.SilkS")
		)
		(fp_line
			(start -0.7874 0.4064)
			(end 0.7874 0.4064)
			(stroke
				(width 0.1524)
				(type default)
			)
			(layer "B.SilkS")
		)
		(fp_line
			(start 0.67945 -0.305054)
			(end 0.12065 -0.305054)
			(stroke
				(width 0.1)
				(type default)
			)
			(layer "B.Fab")
		)
		(fp_line
			(start 0.12065 -0.305054)
			(end 0.12065 -0.2794)
			(stroke
				(width 0.1)
				(type default)
			)
			(layer "B.Fab")
		)
		(fp_line
			(start -0.12065 -0.3048)
			(end -0.67945 -0.3048)
			(stroke
				(width 0.1)
				(type default)
			)
			(layer "B.Fab")
		)
		(fp_line
			(start -0.67945 -0.3048)
			(end -0.67945 0.3048)
			(stroke
				(width 0.1)
				(type default)
			)
			(layer "B.Fab")
		)
		(fp_line
			(start 0.12065 -0.2794)
			(end -0.12065 -0.2794)
			(stroke
				(width 0.1)
				(type default)
			)
			(layer "B.Fab")
		)
		(fp_line
			(start -0.12065 -0.2794)
			(end -0.12065 -0.3048)
			(stroke
				(width 0.1)
				(type default)
			)
			(layer "B.Fab")
		)
		(fp_line
			(start 0.12065 0.2794)
			(end 0.12065 0.3048)
			(stroke
				(width 0.1)
				(type default)
			)
			(layer "B.Fab")
		)
		(fp_line
			(start -0.120396 0.2794)
			(end 0.12065 0.2794)
			(stroke
				(width 0.1)
				(type default)
			)
			(layer "B.Fab")
		)
		(fp_line
			(start 0.67945 0.3048)
			(end 0.67945 -0.305054)
			(stroke
				(width 0.1)
				(type default)
			)
			(layer "B.Fab")
		)
		(fp_line
			(start 0.12065 0.3048)
			(end 0.67945 0.3048)
			(stroke
				(width 0.1)
				(type default)
			)
			(layer "B.Fab")
		)
		(fp_line
			(start -0.120396 0.3048)
			(end -0.120396 0.2794)
			(stroke
				(width 0.1)
				(type default)
			)
			(layer "B.Fab")
		)
		(fp_line
			(start -0.67945 0.3048)
			(end -0.120396 0.3048)
			(stroke
				(width 0.1)
				(type default)
			)
			(layer "B.Fab")
		)
		(pad "1" smd circle
			(at 0.40005 0 270)
			(size 0 0)
			(layers "B.Cu" "B.Mask" "B.Paste")
			(net "I3C_SPD_DDRABCD_CPU0_LVC1_SCL_R")
		)
		(pad "2" smd circle
			(at -0.40005 0 270)
			(size 0 0)
			(layers "B.Cu" "B.Mask" "B.Paste")
			(net "I3C_SPD_DDRABCD_CPU0_LVC1_SCL")
		)
	)
	(footprint ""
		(layer "B.Cu")
		(at 322.984622 -57.267348 180)
		(property "Reference" "R1200"
			(at 0 0 0)
			(layer "B.SilkS")
			(hide yes)
			(effects
				(font
					(size 1.27 1.27)
				)
				(justify mirror)
			)
		)
		(property "Value" ""
			(at 0 0 0)
			(layer "B.Fab")
			(effects
				(font
					(size 1.27 1.27)
				)
				(justify mirror)
			)
		)
		(duplicate_pad_numbers_are_jumpers no)
		(fp_line
			(start 0.7874 0.4064)
			(end 0.7874 -0.4064)
			(stroke
				(width 0.1524)
				(type default)
			)
			(layer "B.SilkS")
		)
		(fp_line
			(start 0.7874 -0.4064)
			(end -0.7874 -0.4064)
			(stroke
				(width 0.1524)
				(type default)
			)
			(layer "B.SilkS")
		)
		(fp_line
			(start -0.7874 0.4064)
			(end 0.7874 0.4064)
			(stroke
				(width 0.1524)
				(type default)
			)
			(layer "B.SilkS")
		)
		(fp_line
			(start -0.7874 -0.4064)
			(end -0.7874 0.4064)
			(stroke
				(width 0.1524)
				(type default)
			)
			(layer "B.SilkS")
		)
		(fp_line
			(start 0.67945 0.3048)
			(end 0.67945 -0.305054)
			(stroke
				(width 0.1)
				(type default)
			)
			(layer "B.Fab")
		)
		(fp_line
			(start 0.67945 -0.305054)
			(end 0.12065 -0.305054)
			(stroke
				(width 0.1)
				(type default)
			)
			(layer "B.Fab")
		)
		(fp_line
			(start 0.12065 0.3048)
			(end 0.67945 0.3048)
			(stroke
				(width 0.1)
				(type default)
			)
			(layer "B.Fab")
		)
		(fp_line
			(start 0.12065 0.2794)
			(end 0.12065 0.3048)
			(stroke
				(width 0.1)
				(type default)
			)
			(layer "B.Fab")
		)
		(fp_line
			(start 0.12065 -0.2794)
			(end -0.12065 -0.2794)
			(stroke
				(width 0.1)
				(type default)
			)
			(layer "B.Fab")
		)
		(fp_line
			(start 0.12065 -0.305054)
			(end 0.12065 -0.2794)
			(stroke
				(width 0.1)
				(type default)
			)
			(layer "B.Fab")
		)
		(fp_line
			(start -0.120396 0.3048)
			(end -0.120396 0.2794)
			(stroke
				(width 0.1)
				(type default)
			)
			(layer "B.Fab")
		)
		(fp_line
			(start -0.120396 0.2794)
			(end 0.12065 0.2794)
			(stroke
				(width 0.1)
				(type default)
			)
			(layer "B.Fab")
		)
		(fp_line
			(start -0.12065 -0.2794)
			(end -0.12065 -0.3048)
			(stroke
				(width 0.1)
				(type default)
			)
			(layer "B.Fab")
		)
		(fp_line
			(start -0.12065 -0.3048)
			(end -0.67945 -0.3048)
			(stroke
				(width 0.1)
				(type default)
			)
			(layer "B.Fab")
		)
		(fp_line
			(start -0.67945 0.3048)
			(end -0.120396 0.3048)
			(stroke
				(width 0.1)
				(type default)
			)
			(layer "B.Fab")
		)
		(fp_line
			(start -0.67945 -0.3048)
			(end -0.67945 0.3048)
			(stroke
				(width 0.1)
				(type default)
			)
			(layer "B.Fab")
		)
		(pad "1" smd circle
			(at 0.40005 0)
			(size 0 0)
			(layers "B.Cu" "B.Mask" "B.Paste")
			(net "FM_PCH_TRIGGER0_N")
		)
		(pad "2" smd circle
			(at -0.40005 0)
			(size 0 0)
			(layers "B.Cu" "B.Mask" "B.Paste")
			(net "FM_PCH_TRIGGER0_R_N")
		)
	)
	(footprint ""
		(layer "B.Cu")
		(at 49.936146 -321.554856 -90)
		(property "Reference" "C60"
			(at 0 0 90)
			(layer "B.SilkS")
			(hide yes)
			(effects
				(font
					(size 1.27 1.27)
				)
				(justify mirror)
			)
		)
		(property "Value" ""
			(at 0 0 90)
			(layer "B.Fab")
			(effects
				(font
					(size 1.27 1.27)
				)
				(justify mirror)
			)
		)
		(duplicate_pad_numbers_are_jumpers no)
		(fp_line
			(start -1.524 0.762)
			(end 1.524 0.762)
			(stroke
				(width 0.1524)
				(type default)
			)
			(layer "B.SilkS")
		)
		(fp_line
			(start 1.524 0.762)
			(end 1.524 -0.762)
			(stroke
				(width 0.1524)
				(type default)
			)
			(layer "B.SilkS")
		)
		(fp_line
			(start -1.524 -0.762)
			(end -1.524 0.762)
			(stroke
				(width 0.1524)
				(type default)
			)
			(layer "B.SilkS")
		)
		(fp_line
			(start 1.524 -0.762)
			(end -1.524 -0.762)
			(stroke
				(width 0.1524)
				(type default)
			)
			(layer "B.SilkS")
		)
		(fp_line
			(start -1.1049 0.724916)
			(end -1.1049 -0.724916)
			(stroke
				(width 0.1)
				(type default)
			)
			(layer "B.Fab")
		)
		(fp_line
			(start 1.1049 0.724916)
			(end -1.1049 0.724916)
			(stroke
				(width 0.1)
				(type default)
			)
			(layer "B.Fab")
		)
		(fp_line
			(start -1.1049 -0.724916)
			(end 1.1049 -0.724916)
			(stroke
				(width 0.1)
				(type default)
			)
			(layer "B.Fab")
		)
		(fp_line
			(start 1.1049 -0.724916)
			(end 1.1049 0.724916)
			(stroke
				(width 0.1)
				(type default)
			)
			(layer "B.Fab")
		)
		(pad "1" smd rect
			(at 0.889 0 270)
			(size 1.016 1.27)
			(layers "B.Cu" "B.Mask" "B.Paste")
			(net "P12V_S3_AUX_CPU1_NVDIMM")
		)
		(pad "2" smd rect
			(at -0.889 0 270)
			(size 1.016 1.27)
			(layers "B.Cu" "B.Mask" "B.Paste")
			(net "GND")
		)
	)
	(footprint ""
		(layer "B.Cu")
		(at 295.93413 -403.031452 90)
		(property "Reference" "PR2512"
			(at 0 0 90)
			(layer "B.SilkS")
			(hide yes)
			(effects
				(font
					(size 1.27 1.27)
				)
				(justify mirror)
			)
		)
		(property "Value" ""
			(at 0 0 90)
			(layer "B.Fab")
			(effects
				(font
					(size 1.27 1.27)
				)
				(justify mirror)
			)
		)
		(duplicate_pad_numbers_are_jumpers no)
		(fp_line
			(start 0.7874 -0.4064)
			(end -0.7874 -0.4064)
			(stroke
				(width 0.1524)
				(type default)
			)
			(layer "B.SilkS")
		)
		(fp_line
			(start -0.7874 -0.4064)
			(end -0.7874 0.4064)
			(stroke
				(width 0.1524)
				(type default)
			)
			(layer "B.SilkS")
		)
		(fp_line
			(start 0.7874 0.4064)
			(end 0.7874 -0.4064)
			(stroke
				(width 0.1524)
				(type default)
			)
			(layer "B.SilkS")
		)
		(fp_line
			(start -0.7874 0.4064)
			(end 0.7874 0.4064)
			(stroke
				(width 0.1524)
				(type default)
			)
			(layer "B.SilkS")
		)
		(fp_line
			(start 0.67945 -0.305054)
			(end 0.12065 -0.305054)
			(stroke
				(width 0.1)
				(type default)
			)
			(layer "B.Fab")
		)
		(fp_line
			(start 0.12065 -0.305054)
			(end 0.12065 -0.2794)
			(stroke
				(width 0.1)
				(type default)
			)
			(layer "B.Fab")
		)
		(fp_line
			(start -0.12065 -0.3048)
			(end -0.67945 -0.3048)
			(stroke
				(width 0.1)
				(type default)
			)
			(layer "B.Fab")
		)
		(fp_line
			(start -0.67945 -0.3048)
			(end -0.67945 0.3048)
			(stroke
				(width 0.1)
				(type default)
			)
			(layer "B.Fab")
		)
		(fp_line
			(start 0.12065 -0.2794)
			(end -0.12065 -0.2794)
			(stroke
				(width 0.1)
				(type default)
			)
			(layer "B.Fab")
		)
		(fp_line
			(start -0.12065 -0.2794)
			(end -0.12065 -0.3048)
			(stroke
				(width 0.1)
				(type default)
			)
			(layer "B.Fab")
		)
		(fp_line
			(start 0.12065 0.2794)
			(end 0.12065 0.3048)
			(stroke
				(width 0.1)
				(type default)
			)
			(layer "B.Fab")
		)
		(fp_line
			(start -0.120396 0.2794)
			(end 0.12065 0.2794)
			(stroke
				(width 0.1)
				(type default)
			)
			(layer "B.Fab")
		)
		(fp_line
			(start 0.67945 0.3048)
			(end 0.67945 -0.305054)
			(stroke
				(width 0.1)
				(type default)
			)
			(layer "B.Fab")
		)
		(fp_line
			(start 0.12065 0.3048)
			(end 0.67945 0.3048)
			(stroke
				(width 0.1)
				(type default)
			)
			(layer "B.Fab")
		)
		(fp_line
			(start -0.120396 0.3048)
			(end -0.120396 0.2794)
			(stroke
				(width 0.1)
				(type default)
			)
			(layer "B.Fab")
		)
		(fp_line
			(start -0.67945 0.3048)
			(end -0.120396 0.3048)
			(stroke
				(width 0.1)
				(type default)
			)
			(layer "B.Fab")
		)
		(pad "1" smd circle
			(at 0.40005 0 270)
			(size 0 0)
			(layers "B.Cu" "B.Mask" "B.Paste")
			(net "P12V_HSC_ADC_P")
		)
		(pad "2" smd circle
			(at -0.40005 0 270)
			(size 0 0)
			(layers "B.Cu" "B.Mask" "B.Paste")
			(net "P12V_HSC_SENSE2_R3_P")
		)
	)
	(footprint ""
		(layer "B.Cu")
		(at 417.282122 -362.107226 90)
		(property "Reference" "PC610_P0_1"
			(at 0 0 90)
			(layer "B.SilkS")
			(hide yes)
			(effects
				(font
					(size 1.27 1.27)
				)
				(justify mirror)
			)
		)
		(property "Value" ""
			(at 0 0 90)
			(layer "B.Fab")
			(effects
				(font
					(size 1.27 1.27)
				)
				(justify mirror)
			)
		)
		(duplicate_pad_numbers_are_jumpers no)
		(fp_line
			(start 1.524 -0.762)
			(end -1.524 -0.762)
			(stroke
				(width 0.1524)
				(type default)
			)
			(layer "B.SilkS")
		)
		(fp_line
			(start -1.524 -0.762)
			(end -1.524 0.762)
			(stroke
				(width 0.1524)
				(type default)
			)
			(layer "B.SilkS")
		)
		(fp_line
			(start 1.524 0.762)
			(end 1.524 -0.762)
			(stroke
				(width 0.1524)
				(type default)
			)
			(layer "B.SilkS")
		)
		(fp_line
			(start -1.524 0.762)
			(end 1.524 0.762)
			(stroke
				(width 0.1524)
				(type default)
			)
			(layer "B.SilkS")
		)
		(fp_line
			(start 1.1049 -0.724916)
			(end 1.1049 0.724916)
			(stroke
				(width 0.1)
				(type default)
			)
			(layer "B.Fab")
		)
		(fp_line
			(start -1.1049 -0.724916)
			(end 1.1049 -0.724916)
			(stroke
				(width 0.1)
				(type default)
			)
			(layer "B.Fab")
		)
		(fp_line
			(start 1.1049 0.724916)
			(end -1.1049 0.724916)
			(stroke
				(width 0.1)
				(type default)
			)
			(layer "B.Fab")
		)
		(fp_line
			(start -1.1049 0.724916)
			(end -1.1049 -0.724916)
			(stroke
				(width 0.1)
				(type default)
			)
			(layer "B.Fab")
		)
		(pad "1" smd rect
			(at 0.889 0 90)
			(size 1.016 1.27)
			(layers "B.Cu" "B.Mask" "B.Paste")
			(net "SW_P12V_PVCCFA_EHV_FIVRA_CPU0_R")
		)
		(pad "2" smd rect
			(at -0.889 0 90)
			(size 1.016 1.27)
			(layers "B.Cu" "B.Mask" "B.Paste")
			(net "GND")
		)
	)
	(footprint ""
		(layer "B.Cu")
		(at 103.901494 -259.533136 -90)
		(property "Reference" "C448"
			(at 0 0 90)
			(layer "B.SilkS")
			(hide yes)
			(effects
				(font
					(size 1.27 1.27)
				)
				(justify mirror)
			)
		)
		(property "Value" ""
			(at 0 0 90)
			(layer "B.Fab")
			(effects
				(font
					(size 1.27 1.27)
				)
				(justify mirror)
			)
		)
		(duplicate_pad_numbers_are_jumpers no)
		(fp_line
			(start -1.524 0.762)
			(end 1.524 0.762)
			(stroke
				(width 0.1524)
				(type default)
			)
			(layer "B.SilkS")
		)
		(fp_line
			(start 1.524 0.762)
			(end 1.524 -0.762)
			(stroke
				(width 0.1524)
				(type default)
			)
			(layer "B.SilkS")
		)
		(fp_line
			(start -1.524 -0.762)
			(end -1.524 0.762)
			(stroke
				(width 0.1524)
				(type default)
			)
			(layer "B.SilkS")
		)
		(fp_line
			(start 1.524 -0.762)
			(end -1.524 -0.762)
			(stroke
				(width 0.1524)
				(type default)
			)
			(layer "B.SilkS")
		)
		(fp_line
			(start -1.1049 0.724916)
			(end -1.1049 -0.724916)
			(stroke
				(width 0.1)
				(type default)
			)
			(layer "B.Fab")
		)
		(fp_line
			(start 1.1049 0.724916)
			(end -1.1049 0.724916)
			(stroke
				(width 0.1)
				(type default)
			)
			(layer "B.Fab")
		)
		(fp_line
			(start -1.1049 -0.724916)
			(end 1.1049 -0.724916)
			(stroke
				(width 0.1)
				(type default)
			)
			(layer "B.Fab")
		)
		(fp_line
			(start 1.1049 -0.724916)
			(end 1.1049 0.724916)
			(stroke
				(width 0.1)
				(type default)
			)
			(layer "B.Fab")
		)
		(pad "1" smd rect
			(at 0.889 0 270)
			(size 1.016 1.27)
			(layers "B.Cu" "B.Mask" "B.Paste")
			(net "PVCCFA_EHV_CPU1")
		)
		(pad "2" smd rect
			(at -0.889 0 270)
			(size 1.016 1.27)
			(layers "B.Cu" "B.Mask" "B.Paste")
			(net "GND")
		)
	)
	(footprint ""
		(layer "B.Cu")
		(at 341.511128 -336.278474 -90)
		(property "Reference" "PR155"
			(at 0 0 90)
			(layer "B.SilkS")
			(hide yes)
			(effects
				(font
					(size 1.27 1.27)
				)
				(justify mirror)
			)
		)
		(property "Value" ""
			(at 0 0 90)
			(layer "B.Fab")
			(effects
				(font
					(size 1.27 1.27)
				)
				(justify mirror)
			)
		)
		(duplicate_pad_numbers_are_jumpers no)
		(fp_line
			(start -0.7874 0.4064)
			(end 0.7874 0.4064)
			(stroke
				(width 0.1524)
				(type default)
			)
			(layer "B.SilkS")
		)
		(fp_line
			(start 0.7874 0.4064)
			(end 0.7874 -0.4064)
			(stroke
				(width 0.1524)
				(type default)
			)
			(layer "B.SilkS")
		)
		(fp_line
			(start -0.7874 -0.4064)
			(end -0.7874 0.4064)
			(stroke
				(width 0.1524)
				(type default)
			)
			(layer "B.SilkS")
		)
		(fp_line
			(start 0.7874 -0.4064)
			(end -0.7874 -0.4064)
			(stroke
				(width 0.1524)
				(type default)
			)
			(layer "B.SilkS")
		)
		(fp_line
			(start -0.67945 0.3048)
			(end -0.120396 0.3048)
			(stroke
				(width 0.1)
				(type default)
			)
			(layer "B.Fab")
		)
		(fp_line
			(start -0.120396 0.3048)
			(end -0.120396 0.2794)
			(stroke
				(width 0.1)
				(type default)
			)
			(layer "B.Fab")
		)
		(fp_line
			(start 0.12065 0.3048)
			(end 0.67945 0.3048)
			(stroke
				(width 0.1)
				(type default)
			)
			(layer "B.Fab")
		)
		(fp_line
			(start 0.67945 0.3048)
			(end 0.67945 -0.305054)
			(stroke
				(width 0.1)
				(type default)
			)
			(layer "B.Fab")
		)
		(fp_line
			(start -0.120396 0.2794)
			(end 0.12065 0.2794)
			(stroke
				(width 0.1)
				(type default)
			)
			(layer "B.Fab")
		)
		(fp_line
			(start 0.12065 0.2794)
			(end 0.12065 0.3048)
			(stroke
				(width 0.1)
				(type default)
			)
			(layer "B.Fab")
		)
		(fp_line
			(start -0.12065 -0.2794)
			(end -0.12065 -0.3048)
			(stroke
				(width 0.1)
				(type default)
			)
			(layer "B.Fab")
		)
		(fp_line
			(start 0.12065 -0.2794)
			(end -0.12065 -0.2794)
			(stroke
				(width 0.1)
				(type default)
			)
			(layer "B.Fab")
		)
		(fp_line
			(start -0.67945 -0.3048)
			(end -0.67945 0.3048)
			(stroke
				(width 0.1)
				(type default)
			)
			(layer "B.Fab")
		)
		(fp_line
			(start -0.12065 -0.3048)
			(end -0.67945 -0.3048)
			(stroke
				(width 0.1)
				(type default)
			)
			(layer "B.Fab")
		)
		(fp_line
			(start 0.12065 -0.305054)
			(end 0.12065 -0.2794)
			(stroke
				(width 0.1)
				(type default)
			)
			(layer "B.Fab")
		)
		(fp_line
			(start 0.67945 -0.305054)
			(end 0.12065 -0.305054)
			(stroke
				(width 0.1)
				(type default)
			)
			(layer "B.Fab")
		)
		(pad "1" smd circle
			(at 0.40005 0 90)
			(size 0 0)
			(layers "B.Cu" "B.Mask" "B.Paste")
			(net "PVCCIN_CPU0_VOS1")
		)
		(pad "2" smd circle
			(at -0.40005 0 90)
			(size 0 0)
			(layers "B.Cu" "B.Mask" "B.Paste")
			(net "PVCCIN_CPU0")
		)
	)
	(footprint ""
		(layer "B.Cu")
		(at 257.35407 -55.436262)
		(property "Reference" "R3942"
			(at 0 0 0)
			(layer "B.SilkS")
			(hide yes)
			(effects
				(font
					(size 1.27 1.27)
				)
				(justify mirror)
			)
		)
		(property "Value" ""
			(at 0 0 0)
			(layer "B.Fab")
			(effects
				(font
					(size 1.27 1.27)
				)
				(justify mirror)
			)
		)
		(duplicate_pad_numbers_are_jumpers no)
		(fp_line
			(start -0.7874 -0.4064)
			(end -0.7874 0.4064)
			(stroke
				(width 0.1524)
				(type default)
			)
			(layer "B.SilkS")
		)
		(fp_line
			(start -0.7874 0.4064)
			(end 0.7874 0.4064)
			(stroke
				(width 0.1524)
				(type default)
			)
			(layer "B.SilkS")
		)
		(fp_line
			(start 0.7874 -0.4064)
			(end -0.7874 -0.4064)
			(stroke
				(width 0.1524)
				(type default)
			)
			(layer "B.SilkS")
		)
		(fp_line
			(start 0.7874 0.4064)
			(end 0.7874 -0.4064)
			(stroke
				(width 0.1524)
				(type default)
			)
			(layer "B.SilkS")
		)
		(fp_line
			(start -0.67945 -0.3048)
			(end -0.67945 0.3048)
			(stroke
				(width 0.1)
				(type default)
			)
			(layer "B.Fab")
		)
		(fp_line
			(start -0.67945 0.3048)
			(end -0.120396 0.3048)
			(stroke
				(width 0.1)
				(type default)
			)
			(layer "B.Fab")
		)
		(fp_line
			(start -0.12065 -0.3048)
			(end -0.67945 -0.3048)
			(stroke
				(width 0.1)
				(type default)
			)
			(layer "B.Fab")
		)
		(fp_line
			(start -0.12065 -0.2794)
			(end -0.12065 -0.3048)
			(stroke
				(width 0.1)
				(type default)
			)
			(layer "B.Fab")
		)
		(fp_line
			(start -0.120396 0.2794)
			(end 0.12065 0.2794)
			(stroke
				(width 0.1)
				(type default)
			)
			(layer "B.Fab")
		)
		(fp_line
			(start -0.120396 0.3048)
			(end -0.120396 0.2794)
			(stroke
				(width 0.1)
				(type default)
			)
			(layer "B.Fab")
		)
		(fp_line
			(start 0.12065 -0.305054)
			(end 0.12065 -0.2794)
			(stroke
				(width 0.1)
				(type default)
			)
			(layer "B.Fab")
		)
		(fp_line
			(start 0.12065 -0.2794)
			(end -0.12065 -0.2794)
			(stroke
				(width 0.1)
				(type default)
			)
			(layer "B.Fab")
		)
		(fp_line
			(start 0.12065 0.2794)
			(end 0.12065 0.3048)
			(stroke
				(width 0.1)
				(type default)
			)
			(layer "B.Fab")
		)
		(fp_line
			(start 0.12065 0.3048)
			(end 0.67945 0.3048)
			(stroke
				(width 0.1)
				(type default)
			)
			(layer "B.Fab")
		)
		(fp_line
			(start 0.67945 -0.305054)
			(end 0.12065 -0.305054)
			(stroke
				(width 0.1)
				(type default)
			)
			(layer "B.Fab")
		)
		(fp_line
			(start 0.67945 0.3048)
			(end 0.67945 -0.305054)
			(stroke
				(width 0.1)
				(type default)
			)
			(layer "B.Fab")
		)
		(pad "1" smd rect
			(at 0.40005 0)
			(size 0.4572 0.508)
			(layers "B.Cu" "B.Mask" "B.Paste")
			(net "P12V_E1S_0_ISENSE_MPS_TIC")
		)
		(pad "2" smd rect
			(at -0.40005 0)
			(size 0.4572 0.508)
			(layers "B.Cu" "B.Mask" "B.Paste")
			(net "P12V_E1S_0_ISENSE_TIC")
		)
	)
	(footprint ""
		(layer "B.Cu")
		(at 205.446122 -108.490766 90)
		(property "Reference" "R4533"
			(at 0 0 90)
			(layer "B.SilkS")
			(hide yes)
			(effects
				(font
					(size 1.27 1.27)
				)
				(justify mirror)
			)
		)
		(property "Value" ""
			(at 0 0 90)
			(layer "B.Fab")
			(effects
				(font
					(size 1.27 1.27)
				)
				(justify mirror)
			)
		)
		(duplicate_pad_numbers_are_jumpers no)
		(fp_line
			(start 0.7874 -0.4064)
			(end -0.7874 -0.4064)
			(stroke
				(width 0.1524)
				(type default)
			)
			(layer "B.SilkS")
		)
		(fp_line
			(start -0.7874 -0.4064)
			(end -0.7874 0.4064)
			(stroke
				(width 0.1524)
				(type default)
			)
			(layer "B.SilkS")
		)
		(fp_line
			(start 0.7874 0.4064)
			(end 0.7874 -0.4064)
			(stroke
				(width 0.1524)
				(type default)
			)
			(layer "B.SilkS")
		)
		(fp_line
			(start -0.7874 0.4064)
			(end 0.7874 0.4064)
			(stroke
				(width 0.1524)
				(type default)
			)
			(layer "B.SilkS")
		)
		(fp_line
			(start 0.67945 -0.305054)
			(end 0.12065 -0.305054)
			(stroke
				(width 0.1)
				(type default)
			)
			(layer "B.Fab")
		)
		(fp_line
			(start 0.12065 -0.305054)
			(end 0.12065 -0.2794)
			(stroke
				(width 0.1)
				(type default)
			)
			(layer "B.Fab")
		)
		(fp_line
			(start -0.12065 -0.3048)
			(end -0.67945 -0.3048)
			(stroke
				(width 0.1)
				(type default)
			)
			(layer "B.Fab")
		)
		(fp_line
			(start -0.67945 -0.3048)
			(end -0.67945 0.3048)
			(stroke
				(width 0.1)
				(type default)
			)
			(layer "B.Fab")
		)
		(fp_line
			(start 0.12065 -0.2794)
			(end -0.12065 -0.2794)
			(stroke
				(width 0.1)
				(type default)
			)
			(layer "B.Fab")
		)
		(fp_line
			(start -0.12065 -0.2794)
			(end -0.12065 -0.3048)
			(stroke
				(width 0.1)
				(type default)
			)
			(layer "B.Fab")
		)
		(fp_line
			(start 0.12065 0.2794)
			(end 0.12065 0.3048)
			(stroke
				(width 0.1)
				(type default)
			)
			(layer "B.Fab")
		)
		(fp_line
			(start -0.120396 0.2794)
			(end 0.12065 0.2794)
			(stroke
				(width 0.1)
				(type default)
			)
			(layer "B.Fab")
		)
		(fp_line
			(start 0.67945 0.3048)
			(end 0.67945 -0.305054)
			(stroke
				(width 0.1)
				(type default)
			)
			(layer "B.Fab")
		)
		(fp_line
			(start 0.12065 0.3048)
			(end 0.67945 0.3048)
			(stroke
				(width 0.1)
				(type default)
			)
			(layer "B.Fab")
		)
		(fp_line
			(start -0.120396 0.3048)
			(end -0.120396 0.2794)
			(stroke
				(width 0.1)
				(type default)
			)
			(layer "B.Fab")
		)
		(fp_line
			(start -0.67945 0.3048)
			(end -0.120396 0.3048)
			(stroke
				(width 0.1)
				(type default)
			)
			(layer "B.Fab")
		)
		(pad "1" smd circle
			(at 0.40005 0 270)
			(size 0 0)
			(layers "B.Cu" "B.Mask" "B.Paste")
			(net "PWRGD_DRAMPWRGD_CPU1_GH_R_LVC1")
		)
		(pad "2" smd circle
			(at -0.40005 0 270)
			(size 0 0)
			(layers "B.Cu" "B.Mask" "B.Paste")
			(net "GND")
		)
	)
	(footprint ""
		(layer "B.Cu")
		(at 239.2934 -422.9862 90)
		(property "Reference" "C2293"
			(at 0 0 90)
			(layer "B.SilkS")
			(hide yes)
			(effects
				(font
					(size 1.27 1.27)
				)
				(justify mirror)
			)
		)
		(property "Value" ""
			(at 0 0 90)
			(layer "B.Fab")
			(effects
				(font
					(size 1.27 1.27)
				)
				(justify mirror)
			)
		)
		(duplicate_pad_numbers_are_jumpers no)
		(fp_line
			(start 0.7874 -0.4064)
			(end -0.7874 -0.4064)
			(stroke
				(width 0.1524)
				(type default)
			)
			(layer "B.SilkS")
		)
		(fp_line
			(start -0.7874 -0.4064)
			(end -0.7874 0.4064)
			(stroke
				(width 0.1524)
				(type default)
			)
			(layer "B.SilkS")
		)
		(fp_line
			(start 0.7874 0.4064)
			(end 0.7874 -0.4064)
			(stroke
				(width 0.1524)
				(type default)
			)
			(layer "B.SilkS")
		)
		(fp_line
			(start -0.7874 0.4064)
			(end 0.7874 0.4064)
			(stroke
				(width 0.1524)
				(type default)
			)
			(layer "B.SilkS")
		)
		(fp_line
			(start 0.67945 -0.305054)
			(end 0.12065 -0.305054)
			(stroke
				(width 0.1)
				(type default)
			)
			(layer "B.Fab")
		)
		(fp_line
			(start 0.12065 -0.305054)
			(end 0.12065 -0.2794)
			(stroke
				(width 0.1)
				(type default)
			)
			(layer "B.Fab")
		)
		(fp_line
			(start -0.12065 -0.3048)
			(end -0.67945 -0.3048)
			(stroke
				(width 0.1)
				(type default)
			)
			(layer "B.Fab")
		)
		(fp_line
			(start -0.67945 -0.3048)
			(end -0.67945 0.3048)
			(stroke
				(width 0.1)
				(type default)
			)
			(layer "B.Fab")
		)
		(fp_line
			(start 0.12065 -0.2794)
			(end -0.12065 -0.2794)
			(stroke
				(width 0.1)
				(type default)
			)
			(layer "B.Fab")
		)
		(fp_line
			(start -0.12065 -0.2794)
			(end -0.12065 -0.3048)
			(stroke
				(width 0.1)
				(type default)
			)
			(layer "B.Fab")
		)
		(fp_line
			(start 0.12065 0.2794)
			(end 0.12065 0.3048)
			(stroke
				(width 0.1)
				(type default)
			)
			(layer "B.Fab")
		)
		(fp_line
			(start -0.120396 0.2794)
			(end 0.12065 0.2794)
			(stroke
				(width 0.1)
				(type default)
			)
			(layer "B.Fab")
		)
		(fp_line
			(start 0.67945 0.3048)
			(end 0.67945 -0.305054)
			(stroke
				(width 0.1)
				(type default)
			)
			(layer "B.Fab")
		)
		(fp_line
			(start 0.12065 0.3048)
			(end 0.67945 0.3048)
			(stroke
				(width 0.1)
				(type default)
			)
			(layer "B.Fab")
		)
		(fp_line
			(start -0.120396 0.3048)
			(end -0.120396 0.2794)
			(stroke
				(width 0.1)
				(type default)
			)
			(layer "B.Fab")
		)
		(fp_line
			(start -0.67945 0.3048)
			(end -0.120396 0.3048)
			(stroke
				(width 0.1)
				(type default)
			)
			(layer "B.Fab")
		)
		(pad "1" smd circle
			(at 0.40005 0 270)
			(size 0 0)
			(layers "B.Cu" "B.Mask" "B.Paste")
			(net "RST_SMB_SWITCH_R_N")
		)
		(pad "2" smd circle
			(at -0.40005 0 270)
			(size 0 0)
			(layers "B.Cu" "B.Mask" "B.Paste")
			(net "GND")
		)
	)
	(footprint ""
		(layer "B.Cu")
		(at 345.5543 -64.088264 90)
		(property "Reference" "C160"
			(at 0 0 90)
			(layer "B.SilkS")
			(hide yes)
			(effects
				(font
					(size 1.27 1.27)
				)
				(justify mirror)
			)
		)
		(property "Value" ""
			(at 0 0 90)
			(layer "B.Fab")
			(effects
				(font
					(size 1.27 1.27)
				)
				(justify mirror)
			)
		)
		(duplicate_pad_numbers_are_jumpers no)
		(fp_line
			(start 0.299974 -0.150114)
			(end -0.299974 -0.150114)
			(stroke
				(width 0.1)
				(type default)
			)
			(layer "B.Fab")
		)
		(fp_line
			(start -0.299974 -0.150114)
			(end -0.299974 0.150114)
			(stroke
				(width 0.1)
				(type default)
			)
			(layer "B.Fab")
		)
		(fp_line
			(start 0.299974 0.150114)
			(end 0.299974 -0.150114)
			(stroke
				(width 0.1)
				(type default)
			)
			(layer "B.Fab")
		)
		(fp_line
			(start -0.299974 0.150114)
			(end 0.299974 0.150114)
			(stroke
				(width 0.1)
				(type default)
			)
			(layer "B.Fab")
		)
		(pad "1" smd rect
			(at 0.2667 0 270)
			(size 0.3048 0.381)
			(layers "B.Cu" "B.Mask" "B.Paste")
			(net "DMI_CPU0_PCH_RX_C_DP<5>")
		)
		(pad "2" smd rect
			(at -0.2667 0 270)
			(size 0.3048 0.381)
			(layers "B.Cu" "B.Mask" "B.Paste")
			(net "DMI_CPU0_PCH_RX_DP<5>")
		)
	)
	(footprint ""
		(layer "B.Cu")
		(at 156.580078 -101.637846)
		(property "Reference" "R1329"
			(at 0 0 0)
			(layer "B.SilkS")
			(hide yes)
			(effects
				(font
					(size 1.27 1.27)
				)
				(justify mirror)
			)
		)
		(property "Value" ""
			(at 0 0 0)
			(layer "B.Fab")
			(effects
				(font
					(size 1.27 1.27)
				)
				(justify mirror)
			)
		)
		(duplicate_pad_numbers_are_jumpers no)
		(fp_line
			(start -0.7874 -0.4064)
			(end -0.7874 0.4064)
			(stroke
				(width 0.1524)
				(type default)
			)
			(layer "B.SilkS")
		)
		(fp_line
			(start -0.7874 0.4064)
			(end 0.7874 0.4064)
			(stroke
				(width 0.1524)
				(type default)
			)
			(layer "B.SilkS")
		)
		(fp_line
			(start 0.7874 -0.4064)
			(end -0.7874 -0.4064)
			(stroke
				(width 0.1524)
				(type default)
			)
			(layer "B.SilkS")
		)
		(fp_line
			(start 0.7874 0.4064)
			(end 0.7874 -0.4064)
			(stroke
				(width 0.1524)
				(type default)
			)
			(layer "B.SilkS")
		)
		(fp_line
			(start -0.67945 -0.3048)
			(end -0.67945 0.3048)
			(stroke
				(width 0.1)
				(type default)
			)
			(layer "B.Fab")
		)
		(fp_line
			(start -0.67945 0.3048)
			(end -0.120396 0.3048)
			(stroke
				(width 0.1)
				(type default)
			)
			(layer "B.Fab")
		)
		(fp_line
			(start -0.12065 -0.3048)
			(end -0.67945 -0.3048)
			(stroke
				(width 0.1)
				(type default)
			)
			(layer "B.Fab")
		)
		(fp_line
			(start -0.12065 -0.2794)
			(end -0.12065 -0.3048)
			(stroke
				(width 0.1)
				(type default)
			)
			(layer "B.Fab")
		)
		(fp_line
			(start -0.120396 0.2794)
			(end 0.12065 0.2794)
			(stroke
				(width 0.1)
				(type default)
			)
			(layer "B.Fab")
		)
		(fp_line
			(start -0.120396 0.3048)
			(end -0.120396 0.2794)
			(stroke
				(width 0.1)
				(type default)
			)
			(layer "B.Fab")
		)
		(fp_line
			(start 0.12065 -0.305054)
			(end 0.12065 -0.2794)
			(stroke
				(width 0.1)
				(type default)
			)
			(layer "B.Fab")
		)
		(fp_line
			(start 0.12065 -0.2794)
			(end -0.12065 -0.2794)
			(stroke
				(width 0.1)
				(type default)
			)
			(layer "B.Fab")
		)
		(fp_line
			(start 0.12065 0.2794)
			(end 0.12065 0.3048)
			(stroke
				(width 0.1)
				(type default)
			)
			(layer "B.Fab")
		)
		(fp_line
			(start 0.12065 0.3048)
			(end 0.67945 0.3048)
			(stroke
				(width 0.1)
				(type default)
			)
			(layer "B.Fab")
		)
		(fp_line
			(start 0.67945 -0.305054)
			(end 0.12065 -0.305054)
			(stroke
				(width 0.1)
				(type default)
			)
			(layer "B.Fab")
		)
		(fp_line
			(start 0.67945 0.3048)
			(end 0.67945 -0.305054)
			(stroke
				(width 0.1)
				(type default)
			)
			(layer "B.Fab")
		)
		(pad "1" smd circle
			(at 0.40005 0 180)
			(size 0 0)
			(layers "B.Cu" "B.Mask" "B.Paste")
			(net "PWRGD_DRAMPWRGD_CPU1_AB_R_LVC1")
		)
		(pad "2" smd circle
			(at -0.40005 0 180)
			(size 0 0)
			(layers "B.Cu" "B.Mask" "B.Paste")
			(net "GND")
		)
	)
	(footprint ""
		(layer "B.Cu")
		(at 340.889844 -49.66462 180)
		(property "Reference" "C1263"
			(at 0 0 0)
			(layer "B.SilkS")
			(hide yes)
			(effects
				(font
					(size 1.27 1.27)
				)
				(justify mirror)
			)
		)
		(property "Value" ""
			(at 0 0 0)
			(layer "B.Fab")
			(effects
				(font
					(size 1.27 1.27)
				)
				(justify mirror)
			)
		)
		(duplicate_pad_numbers_are_jumpers no)
		(fp_line
			(start 0.7874 0.4064)
			(end 0.7874 -0.4064)
			(stroke
				(width 0.1524)
				(type default)
			)
			(layer "B.SilkS")
		)
		(fp_line
			(start 0.7874 -0.4064)
			(end -0.7874 -0.4064)
			(stroke
				(width 0.1524)
				(type default)
			)
			(layer "B.SilkS")
		)
		(fp_line
			(start -0.7874 0.4064)
			(end 0.7874 0.4064)
			(stroke
				(width 0.1524)
				(type default)
			)
			(layer "B.SilkS")
		)
		(fp_line
			(start -0.7874 -0.4064)
			(end -0.7874 0.4064)
			(stroke
				(width 0.1524)
				(type default)
			)
			(layer "B.SilkS")
		)
		(fp_line
			(start 0.67945 0.3048)
			(end 0.67945 -0.305054)
			(stroke
				(width 0.1)
				(type default)
			)
			(layer "B.Fab")
		)
		(fp_line
			(start 0.67945 -0.305054)
			(end 0.12065 -0.305054)
			(stroke
				(width 0.1)
				(type default)
			)
			(layer "B.Fab")
		)
		(fp_line
			(start 0.12065 0.3048)
			(end 0.67945 0.3048)
			(stroke
				(width 0.1)
				(type default)
			)
			(layer "B.Fab")
		)
		(fp_line
			(start 0.12065 0.2794)
			(end 0.12065 0.3048)
			(stroke
				(width 0.1)
				(type default)
			)
			(layer "B.Fab")
		)
		(fp_line
			(start 0.12065 -0.2794)
			(end -0.12065 -0.2794)
			(stroke
				(width 0.1)
				(type default)
			)
			(layer "B.Fab")
		)
		(fp_line
			(start 0.12065 -0.305054)
			(end 0.12065 -0.2794)
			(stroke
				(width 0.1)
				(type default)
			)
			(layer "B.Fab")
		)
		(fp_line
			(start -0.120396 0.3048)
			(end -0.120396 0.2794)
			(stroke
				(width 0.1)
				(type default)
			)
			(layer "B.Fab")
		)
		(fp_line
			(start -0.120396 0.2794)
			(end 0.12065 0.2794)
			(stroke
				(width 0.1)
				(type default)
			)
			(layer "B.Fab")
		)
		(fp_line
			(start -0.12065 -0.2794)
			(end -0.12065 -0.3048)
			(stroke
				(width 0.1)
				(type default)
			)
			(layer "B.Fab")
		)
		(fp_line
			(start -0.12065 -0.3048)
			(end -0.67945 -0.3048)
			(stroke
				(width 0.1)
				(type default)
			)
			(layer "B.Fab")
		)
		(fp_line
			(start -0.67945 0.3048)
			(end -0.120396 0.3048)
			(stroke
				(width 0.1)
				(type default)
			)
			(layer "B.Fab")
		)
		(fp_line
			(start -0.67945 -0.3048)
			(end -0.67945 0.3048)
			(stroke
				(width 0.1)
				(type default)
			)
			(layer "B.Fab")
		)
		(pad "1" smd circle
			(at 0.40005 0)
			(size 0 0)
			(layers "B.Cu" "B.Mask" "B.Paste")
			(net "P1V8_PCH_PLL_AUX")
		)
		(pad "2" smd circle
			(at -0.40005 0)
			(size 0 0)
			(layers "B.Cu" "B.Mask" "B.Paste")
			(net "GND")
		)
	)
	(footprint ""
		(layer "B.Cu")
		(at 276.147784 -193.669666 -90)
		(property "Reference" "R251"
			(at 0 0 90)
			(layer "B.SilkS")
			(hide yes)
			(effects
				(font
					(size 1.27 1.27)
				)
				(justify mirror)
			)
		)
		(property "Value" ""
			(at 0 0 90)
			(layer "B.Fab")
			(effects
				(font
					(size 1.27 1.27)
				)
				(justify mirror)
			)
		)
		(duplicate_pad_numbers_are_jumpers no)
		(fp_line
			(start -0.7874 0.4064)
			(end 0.7874 0.4064)
			(stroke
				(width 0.1524)
				(type default)
			)
			(layer "B.SilkS")
		)
		(fp_line
			(start 0.7874 0.4064)
			(end 0.7874 -0.4064)
			(stroke
				(width 0.1524)
				(type default)
			)
			(layer "B.SilkS")
		)
		(fp_line
			(start -0.7874 -0.4064)
			(end -0.7874 0.4064)
			(stroke
				(width 0.1524)
				(type default)
			)
			(layer "B.SilkS")
		)
		(fp_line
			(start 0.7874 -0.4064)
			(end -0.7874 -0.4064)
			(stroke
				(width 0.1524)
				(type default)
			)
			(layer "B.SilkS")
		)
		(fp_line
			(start -0.67945 0.3048)
			(end -0.120396 0.3048)
			(stroke
				(width 0.1)
				(type default)
			)
			(layer "B.Fab")
		)
		(fp_line
			(start -0.120396 0.3048)
			(end -0.120396 0.2794)
			(stroke
				(width 0.1)
				(type default)
			)
			(layer "B.Fab")
		)
		(fp_line
			(start 0.12065 0.3048)
			(end 0.67945 0.3048)
			(stroke
				(width 0.1)
				(type default)
			)
			(layer "B.Fab")
		)
		(fp_line
			(start 0.67945 0.3048)
			(end 0.67945 -0.305054)
			(stroke
				(width 0.1)
				(type default)
			)
			(layer "B.Fab")
		)
		(fp_line
			(start -0.120396 0.2794)
			(end 0.12065 0.2794)
			(stroke
				(width 0.1)
				(type default)
			)
			(layer "B.Fab")
		)
		(fp_line
			(start 0.12065 0.2794)
			(end 0.12065 0.3048)
			(stroke
				(width 0.1)
				(type default)
			)
			(layer "B.Fab")
		)
		(fp_line
			(start -0.12065 -0.2794)
			(end -0.12065 -0.3048)
			(stroke
				(width 0.1)
				(type default)
			)
			(layer "B.Fab")
		)
		(fp_line
			(start 0.12065 -0.2794)
			(end -0.12065 -0.2794)
			(stroke
				(width 0.1)
				(type default)
			)
			(layer "B.Fab")
		)
		(fp_line
			(start -0.67945 -0.3048)
			(end -0.67945 0.3048)
			(stroke
				(width 0.1)
				(type default)
			)
			(layer "B.Fab")
		)
		(fp_line
			(start -0.12065 -0.3048)
			(end -0.67945 -0.3048)
			(stroke
				(width 0.1)
				(type default)
			)
			(layer "B.Fab")
		)
		(fp_line
			(start 0.12065 -0.305054)
			(end 0.12065 -0.2794)
			(stroke
				(width 0.1)
				(type default)
			)
			(layer "B.Fab")
		)
		(fp_line
			(start 0.67945 -0.305054)
			(end 0.12065 -0.305054)
			(stroke
				(width 0.1)
				(type default)
			)
			(layer "B.Fab")
		)
		(pad "1" smd circle
			(at 0.40005 0 90)
			(size 0 0)
			(layers "B.Cu" "B.Mask" "B.Paste")
			(net "PVNN_TERM_CPU0")
		)
		(pad "2" smd circle
			(at -0.40005 0 90)
			(size 0 0)
			(layers "B.Cu" "B.Mask" "B.Paste")
			(net "FM_S3M_CPU0_LVC1_GPIO_4")
		)
	)
	(footprint ""
		(layer "B.Cu")
		(at 176.97704 -32.951928 -90)
		(property "Reference" "PR4540"
			(at 0 0 90)
			(layer "B.SilkS")
			(hide yes)
			(effects
				(font
					(size 1.27 1.27)
				)
				(justify mirror)
			)
		)
		(property "Value" ""
			(at 0 0 90)
			(layer "B.Fab")
			(effects
				(font
					(size 1.27 1.27)
				)
				(justify mirror)
			)
		)
		(duplicate_pad_numbers_are_jumpers no)
		(fp_line
			(start -0.7874 0.4064)
			(end 0.7874 0.4064)
			(stroke
				(width 0.1524)
				(type default)
			)
			(layer "B.SilkS")
		)
		(fp_line
			(start 0.7874 0.4064)
			(end 0.7874 -0.4064)
			(stroke
				(width 0.1524)
				(type default)
			)
			(layer "B.SilkS")
		)
		(fp_line
			(start -0.7874 -0.4064)
			(end -0.7874 0.4064)
			(stroke
				(width 0.1524)
				(type default)
			)
			(layer "B.SilkS")
		)
		(fp_line
			(start 0.7874 -0.4064)
			(end -0.7874 -0.4064)
			(stroke
				(width 0.1524)
				(type default)
			)
			(layer "B.SilkS")
		)
		(fp_line
			(start -0.67945 0.3048)
			(end -0.120396 0.3048)
			(stroke
				(width 0.1)
				(type default)
			)
			(layer "B.Fab")
		)
		(fp_line
			(start -0.120396 0.3048)
			(end -0.120396 0.2794)
			(stroke
				(width 0.1)
				(type default)
			)
			(layer "B.Fab")
		)
		(fp_line
			(start 0.12065 0.3048)
			(end 0.67945 0.3048)
			(stroke
				(width 0.1)
				(type default)
			)
			(layer "B.Fab")
		)
		(fp_line
			(start 0.67945 0.3048)
			(end 0.67945 -0.305054)
			(stroke
				(width 0.1)
				(type default)
			)
			(layer "B.Fab")
		)
		(fp_line
			(start -0.120396 0.2794)
			(end 0.12065 0.2794)
			(stroke
				(width 0.1)
				(type default)
			)
			(layer "B.Fab")
		)
		(fp_line
			(start 0.12065 0.2794)
			(end 0.12065 0.3048)
			(stroke
				(width 0.1)
				(type default)
			)
			(layer "B.Fab")
		)
		(fp_line
			(start -0.12065 -0.2794)
			(end -0.12065 -0.3048)
			(stroke
				(width 0.1)
				(type default)
			)
			(layer "B.Fab")
		)
		(fp_line
			(start 0.12065 -0.2794)
			(end -0.12065 -0.2794)
			(stroke
				(width 0.1)
				(type default)
			)
			(layer "B.Fab")
		)
		(fp_line
			(start -0.67945 -0.3048)
			(end -0.67945 0.3048)
			(stroke
				(width 0.1)
				(type default)
			)
			(layer "B.Fab")
		)
		(fp_line
			(start -0.12065 -0.3048)
			(end -0.67945 -0.3048)
			(stroke
				(width 0.1)
				(type default)
			)
			(layer "B.Fab")
		)
		(fp_line
			(start 0.12065 -0.305054)
			(end 0.12065 -0.2794)
			(stroke
				(width 0.1)
				(type default)
			)
			(layer "B.Fab")
		)
		(fp_line
			(start 0.67945 -0.305054)
			(end 0.12065 -0.305054)
			(stroke
				(width 0.1)
				(type default)
			)
			(layer "B.Fab")
		)
		(pad "1" smd circle
			(at 0.40005 0 90)
			(size 0 0)
			(layers "B.Cu" "B.Mask" "B.Paste")
			(net "P12V_SCM_ISET")
		)
		(pad "2" smd circle
			(at -0.40005 0 90)
			(size 0 0)
			(layers "B.Cu" "B.Mask" "B.Paste")
			(net "P12V_SCM_ISET_R")
		)
	)
	(footprint ""
		(layer "B.Cu")
		(at 368.158522 -261.953502 -90)
		(property "Reference" "C534"
			(at 0 0 90)
			(layer "B.SilkS")
			(hide yes)
			(effects
				(font
					(size 1.27 1.27)
				)
				(justify mirror)
			)
		)
		(property "Value" ""
			(at 0 0 90)
			(layer "B.Fab")
			(effects
				(font
					(size 1.27 1.27)
				)
				(justify mirror)
			)
		)
		(duplicate_pad_numbers_are_jumpers no)
		(fp_line
			(start -0.7874 0.4064)
			(end 0.7874 0.4064)
			(stroke
				(width 0.1524)
				(type default)
			)
			(layer "B.SilkS")
		)
		(fp_line
			(start 0.7874 0.4064)
			(end 0.7874 -0.4064)
			(stroke
				(width 0.1524)
				(type default)
			)
			(layer "B.SilkS")
		)
		(fp_line
			(start -0.7874 -0.4064)
			(end -0.7874 0.4064)
			(stroke
				(width 0.1524)
				(type default)
			)
			(layer "B.SilkS")
		)
		(fp_line
			(start 0.7874 -0.4064)
			(end -0.7874 -0.4064)
			(stroke
				(width 0.1524)
				(type default)
			)
			(layer "B.SilkS")
		)
		(fp_line
			(start -0.67945 0.3048)
			(end -0.120396 0.3048)
			(stroke
				(width 0.1)
				(type default)
			)
			(layer "B.Fab")
		)
		(fp_line
			(start -0.120396 0.3048)
			(end -0.120396 0.2794)
			(stroke
				(width 0.1)
				(type default)
			)
			(layer "B.Fab")
		)
		(fp_line
			(start 0.12065 0.3048)
			(end 0.67945 0.3048)
			(stroke
				(width 0.1)
				(type default)
			)
			(layer "B.Fab")
		)
		(fp_line
			(start 0.67945 0.3048)
			(end 0.67945 -0.305054)
			(stroke
				(width 0.1)
				(type default)
			)
			(layer "B.Fab")
		)
		(fp_line
			(start -0.120396 0.2794)
			(end 0.12065 0.2794)
			(stroke
				(width 0.1)
				(type default)
			)
			(layer "B.Fab")
		)
		(fp_line
			(start 0.12065 0.2794)
			(end 0.12065 0.3048)
			(stroke
				(width 0.1)
				(type default)
			)
			(layer "B.Fab")
		)
		(fp_line
			(start -0.12065 -0.2794)
			(end -0.12065 -0.3048)
			(stroke
				(width 0.1)
				(type default)
			)
			(layer "B.Fab")
		)
		(fp_line
			(start 0.12065 -0.2794)
			(end -0.12065 -0.2794)
			(stroke
				(width 0.1)
				(type default)
			)
			(layer "B.Fab")
		)
		(fp_line
			(start -0.67945 -0.3048)
			(end -0.67945 0.3048)
			(stroke
				(width 0.1)
				(type default)
			)
			(layer "B.Fab")
		)
		(fp_line
			(start -0.12065 -0.3048)
			(end -0.67945 -0.3048)
			(stroke
				(width 0.1)
				(type default)
			)
			(layer "B.Fab")
		)
		(fp_line
			(start 0.12065 -0.305054)
			(end 0.12065 -0.2794)
			(stroke
				(width 0.1)
				(type default)
			)
			(layer "B.Fab")
		)
		(fp_line
			(start 0.67945 -0.305054)
			(end 0.12065 -0.305054)
			(stroke
				(width 0.1)
				(type default)
			)
			(layer "B.Fab")
		)
		(pad "1" smd circle
			(at 0.40005 0 90)
			(size 0 0)
			(layers "B.Cu" "B.Mask" "B.Paste")
			(net "PVCCINFAON_CPU0")
		)
		(pad "2" smd circle
			(at -0.40005 0 90)
			(size 0 0)
			(layers "B.Cu" "B.Mask" "B.Paste")
			(net "GND")
		)
	)
	(footprint ""
		(layer "B.Cu")
		(at 354.221288 -359.47985 180)
		(property "Reference" "C3267"
			(at 0 0 0)
			(layer "B.SilkS")
			(hide yes)
			(effects
				(font
					(size 1.27 1.27)
				)
				(justify mirror)
			)
		)
		(property "Value" ""
			(at 0 0 0)
			(layer "B.Fab")
			(effects
				(font
					(size 1.27 1.27)
				)
				(justify mirror)
			)
		)
		(duplicate_pad_numbers_are_jumpers no)
		(fp_line
			(start 0.7874 0.4064)
			(end 0.7874 -0.4064)
			(stroke
				(width 0.1524)
				(type default)
			)
			(layer "B.SilkS")
		)
		(fp_line
			(start 0.7874 -0.4064)
			(end -0.7874 -0.4064)
			(stroke
				(width 0.1524)
				(type default)
			)
			(layer "B.SilkS")
		)
		(fp_line
			(start -0.7874 0.4064)
			(end 0.7874 0.4064)
			(stroke
				(width 0.1524)
				(type default)
			)
			(layer "B.SilkS")
		)
		(fp_line
			(start -0.7874 -0.4064)
			(end -0.7874 0.4064)
			(stroke
				(width 0.1524)
				(type default)
			)
			(layer "B.SilkS")
		)
		(fp_line
			(start 0.67945 0.3048)
			(end 0.67945 -0.305054)
			(stroke
				(width 0.1)
				(type default)
			)
			(layer "B.Fab")
		)
		(fp_line
			(start 0.67945 -0.305054)
			(end 0.12065 -0.305054)
			(stroke
				(width 0.1)
				(type default)
			)
			(layer "B.Fab")
		)
		(fp_line
			(start 0.12065 0.3048)
			(end 0.67945 0.3048)
			(stroke
				(width 0.1)
				(type default)
			)
			(layer "B.Fab")
		)
		(fp_line
			(start 0.12065 0.2794)
			(end 0.12065 0.3048)
			(stroke
				(width 0.1)
				(type default)
			)
			(layer "B.Fab")
		)
		(fp_line
			(start 0.12065 -0.2794)
			(end -0.12065 -0.2794)
			(stroke
				(width 0.1)
				(type default)
			)
			(layer "B.Fab")
		)
		(fp_line
			(start 0.12065 -0.305054)
			(end 0.12065 -0.2794)
			(stroke
				(width 0.1)
				(type default)
			)
			(layer "B.Fab")
		)
		(fp_line
			(start -0.120396 0.3048)
			(end -0.120396 0.2794)
			(stroke
				(width 0.1)
				(type default)
			)
			(layer "B.Fab")
		)
		(fp_line
			(start -0.120396 0.2794)
			(end 0.12065 0.2794)
			(stroke
				(width 0.1)
				(type default)
			)
			(layer "B.Fab")
		)
		(fp_line
			(start -0.12065 -0.2794)
			(end -0.12065 -0.3048)
			(stroke
				(width 0.1)
				(type default)
			)
			(layer "B.Fab")
		)
		(fp_line
			(start -0.12065 -0.3048)
			(end -0.67945 -0.3048)
			(stroke
				(width 0.1)
				(type default)
			)
			(layer "B.Fab")
		)
		(fp_line
			(start -0.67945 0.3048)
			(end -0.120396 0.3048)
			(stroke
				(width 0.1)
				(type default)
			)
			(layer "B.Fab")
		)
		(fp_line
			(start -0.67945 -0.3048)
			(end -0.67945 0.3048)
			(stroke
				(width 0.1)
				(type default)
			)
			(layer "B.Fab")
		)
		(pad "1" smd circle
			(at 0.40005 0)
			(size 0 0)
			(layers "B.Cu" "B.Mask" "B.Paste")
			(net "PVCCIN_CPU0_EN_R")
		)
		(pad "2" smd circle
			(at -0.40005 0)
			(size 0 0)
			(layers "B.Cu" "B.Mask" "B.Paste")
			(net "GND")
		)
	)
	(footprint ""
		(layer "B.Cu")
		(at 105.696258 -358.05491 -90)
		(property "Reference" "R309"
			(at 0 0 90)
			(layer "B.SilkS")
			(hide yes)
			(effects
				(font
					(size 1.27 1.27)
				)
				(justify mirror)
			)
		)
		(property "Value" ""
			(at 0 0 90)
			(layer "B.Fab")
			(effects
				(font
					(size 1.27 1.27)
				)
				(justify mirror)
			)
		)
		(duplicate_pad_numbers_are_jumpers no)
		(fp_line
			(start -0.7874 0.4064)
			(end 0.7874 0.4064)
			(stroke
				(width 0.1524)
				(type default)
			)
			(layer "B.SilkS")
		)
		(fp_line
			(start 0.7874 0.4064)
			(end 0.7874 -0.4064)
			(stroke
				(width 0.1524)
				(type default)
			)
			(layer "B.SilkS")
		)
		(fp_line
			(start -0.7874 -0.4064)
			(end -0.7874 0.4064)
			(stroke
				(width 0.1524)
				(type default)
			)
			(layer "B.SilkS")
		)
		(fp_line
			(start 0.7874 -0.4064)
			(end -0.7874 -0.4064)
			(stroke
				(width 0.1524)
				(type default)
			)
			(layer "B.SilkS")
		)
		(fp_line
			(start -0.67945 0.3048)
			(end -0.120396 0.3048)
			(stroke
				(width 0.1)
				(type default)
			)
			(layer "B.Fab")
		)
		(fp_line
			(start -0.120396 0.3048)
			(end -0.120396 0.2794)
			(stroke
				(width 0.1)
				(type default)
			)
			(layer "B.Fab")
		)
		(fp_line
			(start 0.12065 0.3048)
			(end 0.67945 0.3048)
			(stroke
				(width 0.1)
				(type default)
			)
			(layer "B.Fab")
		)
		(fp_line
			(start 0.67945 0.3048)
			(end 0.67945 -0.305054)
			(stroke
				(width 0.1)
				(type default)
			)
			(layer "B.Fab")
		)
		(fp_line
			(start -0.120396 0.2794)
			(end 0.12065 0.2794)
			(stroke
				(width 0.1)
				(type default)
			)
			(layer "B.Fab")
		)
		(fp_line
			(start 0.12065 0.2794)
			(end 0.12065 0.3048)
			(stroke
				(width 0.1)
				(type default)
			)
			(layer "B.Fab")
		)
		(fp_line
			(start -0.12065 -0.2794)
			(end -0.12065 -0.3048)
			(stroke
				(width 0.1)
				(type default)
			)
			(layer "B.Fab")
		)
		(fp_line
			(start 0.12065 -0.2794)
			(end -0.12065 -0.2794)
			(stroke
				(width 0.1)
				(type default)
			)
			(layer "B.Fab")
		)
		(fp_line
			(start -0.67945 -0.3048)
			(end -0.67945 0.3048)
			(stroke
				(width 0.1)
				(type default)
			)
			(layer "B.Fab")
		)
		(fp_line
			(start -0.12065 -0.3048)
			(end -0.67945 -0.3048)
			(stroke
				(width 0.1)
				(type default)
			)
			(layer "B.Fab")
		)
		(fp_line
			(start 0.12065 -0.305054)
			(end 0.12065 -0.2794)
			(stroke
				(width 0.1)
				(type default)
			)
			(layer "B.Fab")
		)
		(fp_line
			(start 0.67945 -0.305054)
			(end 0.12065 -0.305054)
			(stroke
				(width 0.1)
				(type default)
			)
			(layer "B.Fab")
		)
		(pad "1" smd circle
			(at 0.40005 0 90)
			(size 0 0)
			(layers "B.Cu" "B.Mask" "B.Paste")
			(net "FM_PVCCIN_CPU1_EN")
		)
		(pad "2" smd circle
			(at -0.40005 0 90)
			(size 0 0)
			(layers "B.Cu" "B.Mask" "B.Paste")
			(net "PVCCIN_CPU1_EN_R")
		)
	)
	(footprint ""
		(layer "B.Cu")
		(at 421.853614 -321.549776 -90)
		(property "Reference" "C36"
			(at 0 0 90)
			(layer "B.SilkS")
			(hide yes)
			(effects
				(font
					(size 1.27 1.27)
				)
				(justify mirror)
			)
		)
		(property "Value" ""
			(at 0 0 90)
			(layer "B.Fab")
			(effects
				(font
					(size 1.27 1.27)
				)
				(justify mirror)
			)
		)
		(duplicate_pad_numbers_are_jumpers no)
		(fp_line
			(start -1.524 0.762)
			(end 1.524 0.762)
			(stroke
				(width 0.1524)
				(type default)
			)
			(layer "B.SilkS")
		)
		(fp_line
			(start 1.524 0.762)
			(end 1.524 -0.762)
			(stroke
				(width 0.1524)
				(type default)
			)
			(layer "B.SilkS")
		)
		(fp_line
			(start -1.524 -0.762)
			(end -1.524 0.762)
			(stroke
				(width 0.1524)
				(type default)
			)
			(layer "B.SilkS")
		)
		(fp_line
			(start 1.524 -0.762)
			(end -1.524 -0.762)
			(stroke
				(width 0.1524)
				(type default)
			)
			(layer "B.SilkS")
		)
		(fp_line
			(start -1.1049 0.724916)
			(end -1.1049 -0.724916)
			(stroke
				(width 0.1)
				(type default)
			)
			(layer "B.Fab")
		)
		(fp_line
			(start 1.1049 0.724916)
			(end -1.1049 0.724916)
			(stroke
				(width 0.1)
				(type default)
			)
			(layer "B.Fab")
		)
		(fp_line
			(start -1.1049 -0.724916)
			(end 1.1049 -0.724916)
			(stroke
				(width 0.1)
				(type default)
			)
			(layer "B.Fab")
		)
		(fp_line
			(start 1.1049 -0.724916)
			(end 1.1049 0.724916)
			(stroke
				(width 0.1)
				(type default)
			)
			(layer "B.Fab")
		)
		(pad "1" smd rect
			(at 0.889 0 270)
			(size 1.016 1.27)
			(layers "B.Cu" "B.Mask" "B.Paste")
			(net "P12V_S3_AUX_CPU0_NVDIMM")
		)
		(pad "2" smd rect
			(at -0.889 0 270)
			(size 1.016 1.27)
			(layers "B.Cu" "B.Mask" "B.Paste")
			(net "GND")
		)
	)
	(footprint ""
		(layer "B.Cu")
		(at 62.996572 -151.23668)
		(property "Reference" "PC458_P1_2"
			(at 0 0 0)
			(layer "B.SilkS")
			(hide yes)
			(effects
				(font
					(size 1.27 1.27)
				)
				(justify mirror)
			)
		)
		(property "Value" ""
			(at 0 0 0)
			(layer "B.Fab")
			(effects
				(font
					(size 1.27 1.27)
				)
				(justify mirror)
			)
		)
		(duplicate_pad_numbers_are_jumpers no)
		(fp_line
			(start -1.524 -0.762)
			(end -1.524 0.762)
			(stroke
				(width 0.1524)
				(type default)
			)
			(layer "B.SilkS")
		)
		(fp_line
			(start -1.524 0.762)
			(end 1.524 0.762)
			(stroke
				(width 0.1524)
				(type default)
			)
			(layer "B.SilkS")
		)
		(fp_line
			(start 1.524 -0.762)
			(end -1.524 -0.762)
			(stroke
				(width 0.1524)
				(type default)
			)
			(layer "B.SilkS")
		)
		(fp_line
			(start 1.524 0.762)
			(end 1.524 -0.762)
			(stroke
				(width 0.1524)
				(type default)
			)
			(layer "B.SilkS")
		)
		(fp_line
			(start -1.1049 -0.724916)
			(end 1.1049 -0.724916)
			(stroke
				(width 0.1)
				(type default)
			)
			(layer "B.Fab")
		)
		(fp_line
			(start -1.1049 0.724916)
			(end -1.1049 -0.724916)
			(stroke
				(width 0.1)
				(type default)
			)
			(layer "B.Fab")
		)
		(fp_line
			(start 1.1049 -0.724916)
			(end 1.1049 0.724916)
			(stroke
				(width 0.1)
				(type default)
			)
			(layer "B.Fab")
		)
		(fp_line
			(start 1.1049 0.724916)
			(end -1.1049 0.724916)
			(stroke
				(width 0.1)
				(type default)
			)
			(layer "B.Fab")
		)
		(pad "1" smd rect
			(at 0.889 0)
			(size 1.016 1.27)
			(layers "B.Cu" "B.Mask" "B.Paste")
			(net "PVCCINFAON_CPU1")
		)
		(pad "2" smd rect
			(at -0.889 0)
			(size 1.016 1.27)
			(layers "B.Cu" "B.Mask" "B.Paste")
			(net "GND")
		)
	)
	(footprint ""
		(layer "B.Cu")
		(at 319.073022 -185.96991 -90)
		(property "Reference" "R195"
			(at 0 0 90)
			(layer "B.SilkS")
			(hide yes)
			(effects
				(font
					(size 1.27 1.27)
				)
				(justify mirror)
			)
		)
		(property "Value" ""
			(at 0 0 90)
			(layer "B.Fab")
			(effects
				(font
					(size 1.27 1.27)
				)
				(justify mirror)
			)
		)
		(duplicate_pad_numbers_are_jumpers no)
		(fp_line
			(start -0.7874 0.4064)
			(end 0.7874 0.4064)
			(stroke
				(width 0.1524)
				(type default)
			)
			(layer "B.SilkS")
		)
		(fp_line
			(start 0.7874 0.4064)
			(end 0.7874 -0.4064)
			(stroke
				(width 0.1524)
				(type default)
			)
			(layer "B.SilkS")
		)
		(fp_line
			(start -0.7874 -0.4064)
			(end -0.7874 0.4064)
			(stroke
				(width 0.1524)
				(type default)
			)
			(layer "B.SilkS")
		)
		(fp_line
			(start 0.7874 -0.4064)
			(end -0.7874 -0.4064)
			(stroke
				(width 0.1524)
				(type default)
			)
			(layer "B.SilkS")
		)
		(fp_line
			(start -0.67945 0.3048)
			(end -0.120396 0.3048)
			(stroke
				(width 0.1)
				(type default)
			)
			(layer "B.Fab")
		)
		(fp_line
			(start -0.120396 0.3048)
			(end -0.120396 0.2794)
			(stroke
				(width 0.1)
				(type default)
			)
			(layer "B.Fab")
		)
		(fp_line
			(start 0.12065 0.3048)
			(end 0.67945 0.3048)
			(stroke
				(width 0.1)
				(type default)
			)
			(layer "B.Fab")
		)
		(fp_line
			(start 0.67945 0.3048)
			(end 0.67945 -0.305054)
			(stroke
				(width 0.1)
				(type default)
			)
			(layer "B.Fab")
		)
		(fp_line
			(start -0.120396 0.2794)
			(end 0.12065 0.2794)
			(stroke
				(width 0.1)
				(type default)
			)
			(layer "B.Fab")
		)
		(fp_line
			(start 0.12065 0.2794)
			(end 0.12065 0.3048)
			(stroke
				(width 0.1)
				(type default)
			)
			(layer "B.Fab")
		)
		(fp_line
			(start -0.12065 -0.2794)
			(end -0.12065 -0.3048)
			(stroke
				(width 0.1)
				(type default)
			)
			(layer "B.Fab")
		)
		(fp_line
			(start 0.12065 -0.2794)
			(end -0.12065 -0.2794)
			(stroke
				(width 0.1)
				(type default)
			)
			(layer "B.Fab")
		)
		(fp_line
			(start -0.67945 -0.3048)
			(end -0.67945 0.3048)
			(stroke
				(width 0.1)
				(type default)
			)
			(layer "B.Fab")
		)
		(fp_line
			(start -0.12065 -0.3048)
			(end -0.67945 -0.3048)
			(stroke
				(width 0.1)
				(type default)
			)
			(layer "B.Fab")
		)
		(fp_line
			(start 0.12065 -0.305054)
			(end 0.12065 -0.2794)
			(stroke
				(width 0.1)
				(type default)
			)
			(layer "B.Fab")
		)
		(fp_line
			(start 0.67945 -0.305054)
			(end 0.12065 -0.305054)
			(stroke
				(width 0.1)
				(type default)
			)
			(layer "B.Fab")
		)
		(pad "1" smd circle
			(at 0.40005 0 90)
			(size 0 0)
			(layers "B.Cu" "B.Mask" "B.Paste")
			(net "H_CPU_NMI_LVC1_N")
		)
		(pad "2" smd circle
			(at -0.40005 0 90)
			(size 0 0)
			(layers "B.Cu" "B.Mask" "B.Paste")
			(net "H_CPU0_NMI_LVC1_N")
		)
	)
	(footprint ""
		(layer "B.Cu")
		(at 260.731508 2.923794 180)
		(property "Reference" "J121"
			(at 4.218178 -1.394206 270)
			(unlocked yes)
			(layer "B.SilkS")
			(effects
				(font
					(size 0.7874 0.5842)
					(thickness 0.1524)
				)
				(justify left mirror)
			)
		)
		(property "Value" ""
			(at 0 0 0)
			(layer "B.Fab")
			(effects
				(font
					(size 1.27 1.27)
				)
				(justify mirror)
			)
		)
		(duplicate_pad_numbers_are_jumpers no)
		(fp_line
			(start 1.2192 2.1082)
			(end 1.2192 -2.1082)
			(stroke
				(width 0.1524)
				(type default)
			)
			(layer "B.SilkS")
		)
		(fp_line
			(start 1.2192 -2.1082)
			(end -1.2192 -2.1082)
			(stroke
				(width 0.1524)
				(type default)
			)
			(layer "B.SilkS")
		)
		(fp_line
			(start -1.2192 2.1082)
			(end 1.2192 2.1082)
			(stroke
				(width 0.1524)
				(type default)
			)
			(layer "B.SilkS")
		)
		(fp_line
			(start -1.2192 -2.1082)
			(end -1.2192 2.1082)
			(stroke
				(width 0.1524)
				(type default)
			)
			(layer "B.SilkS")
		)
		(pad "" np_thru_hole circle
			(at -3.4671 -1.27 90)
			(size 1.0414 1.0414)
			(drill 1.0414)
			(layers "*.Cu" "*.Mask")
			(clearance 0.381)
			(thermal_gap 0.381)
		)
		(pad "" np_thru_hole circle
			(at -3.4671 1.27 90)
			(size 1.0414 1.0414)
			(drill 1.0414)
			(layers "*.Cu" "*.Mask")
			(clearance 0.381)
			(thermal_gap 0.381)
		)
		(pad "" np_thru_hole circle
			(at 2.8829 -1.27 90)
			(size 1.0414 1.0414)
			(drill 1.0414)
			(layers "*.Cu" "*.Mask")
			(clearance 0.381)
			(thermal_gap 0.381)
		)
		(pad "" np_thru_hole circle
			(at 2.8829 1.27 90)
			(size 1.0414 1.0414)
			(drill 1.0414)
			(layers "*.Cu" "*.Mask")
			(clearance 0.381)
			(thermal_gap 0.381)
		)
		(pad "1" smd rect
			(at -0.8255 -0.249936 90)
			(size 0.3048 0.508)
			(layers "B.Cu" "B.Mask" "B.Paste")
			(net "DELTA_L_85_10INCH_IN6_DN")
		)
		(pad "2" smd rect
			(at -0.8255 0.249936 90)
			(size 0.3048 0.508)
			(layers "B.Cu" "B.Mask" "B.Paste")
			(net "DELTA_L_85_10INCH_IN6_DP")
		)
		(pad "3" smd circle
			(at 0 0)
			(size 0 0)
			(layers "B.Cu" "B.Mask" "B.Paste")
			(net "DELTA_L_GND_1")
		)
		(zone
			(layers "F.Cu" "B.Cu" "In1.Cu" "In2.Cu" "In3.Cu" "In4.Cu" "In5.Cu" "In6.Cu"
				"In7.Cu" "In8.Cu" "In9.Cu" "In10.Cu" "In11.Cu" "In12.Cu" "In13.Cu" "In14.Cu"
				"In15.Cu" "In16.Cu"
			)
			(hatch none 0.5)
			(connect_pads
				(clearance 0)
			)
			(min_thickness 0.25)
			(keepout
				(tracks not_allowed)
				(vias allowed)
				(pads allowed)
				(copperpour not_allowed)
				(footprints allowed)
			)
			(placement
				(enabled no)
				(sheetname "")
			)
			(fill
				(thermal_gap 0.5)
				(thermal_bridge_width 0.5)
				(island_removal_mode 0)
			)
			(polygon
				(pts
					(arc
						(start 258.775708 1.653794)
						(mid 256.921508 1.653794)
						(end 258.775708 1.653794)
					)
				)
			)
		)
		(zone
			(layers "F.Cu" "B.Cu" "In1.Cu" "In2.Cu" "In3.Cu" "In4.Cu" "In5.Cu" "In6.Cu"
				"In7.Cu" "In8.Cu" "In9.Cu" "In10.Cu" "In11.Cu" "In12.Cu" "In13.Cu" "In14.Cu"
				"In15.Cu" "In16.Cu"
			)
			(hatch none 0.5)
			(connect_pads
				(clearance 0)
			)
			(min_thickness 0.25)
			(keepout
				(tracks not_allowed)
				(vias allowed)
				(pads allowed)
				(copperpour not_allowed)
				(footprints allowed)
			)
			(placement
				(enabled no)
				(sheetname "")
			)
			(fill
				(thermal_gap 0.5)
				(thermal_bridge_width 0.5)
				(island_removal_mode 0)
			)
			(polygon
				(pts
					(arc
						(start 258.775708 4.193794)
						(mid 256.921508 4.193794)
						(end 258.775708 4.193794)
					)
				)
			)
		)
		(zone
			(layers "F.Cu" "B.Cu" "In1.Cu" "In2.Cu" "In3.Cu" "In4.Cu" "In5.Cu" "In6.Cu"
				"In7.Cu" "In8.Cu" "In9.Cu" "In10.Cu" "In11.Cu" "In12.Cu" "In13.Cu" "In14.Cu"
				"In15.Cu" "In16.Cu"
			)
			(hatch none 0.5)
			(connect_pads
				(clearance 0)
			)
			(min_thickness 0.25)
			(keepout
				(tracks not_allowed)
				(vias allowed)
				(pads allowed)
				(copperpour not_allowed)
				(footprints allowed)
			)
			(placement
				(enabled no)
				(sheetname "")
			)
			(fill
				(thermal_gap 0.5)
				(thermal_bridge_width 0.5)
				(island_removal_mode 0)
			)
			(polygon
				(pts
					(arc
						(start 265.125708 1.653794)
						(mid 263.271508 1.653794)
						(end 265.125708 1.653794)
					)
				)
			)
		)
		(zone
			(layers "F.Cu" "B.Cu" "In1.Cu" "In2.Cu" "In3.Cu" "In4.Cu" "In5.Cu" "In6.Cu"
				"In7.Cu" "In8.Cu" "In9.Cu" "In10.Cu" "In11.Cu" "In12.Cu" "In13.Cu" "In14.Cu"
				"In15.Cu" "In16.Cu"
			)
			(hatch none 0.5)
			(connect_pads
				(clearance 0)
			)
			(min_thickness 0.25)
			(keepout
				(tracks not_allowed)
				(vias allowed)
				(pads allowed)
				(copperpour not_allowed)
				(footprints allowed)
			)
			(placement
				(enabled no)
				(sheetname "")
			)
			(fill
				(thermal_gap 0.5)
				(thermal_bridge_width 0.5)
				(island_removal_mode 0)
			)
			(polygon
				(pts
					(arc
						(start 265.125708 4.193794)
						(mid 263.271508 4.193794)
						(end 265.125708 4.193794)
					)
				)
			)
		)
		(zone
			(layer "B.Cu")
			(hatch none 0.5)
			(connect_pads
				(clearance 0)
			)
			(min_thickness 0.25)
			(keepout
				(tracks not_allowed)
				(vias allowed)
				(pads allowed)
				(copperpour not_allowed)
				(footprints allowed)
			)
			(placement
				(enabled no)
				(sheetname "")
			)
			(fill
				(thermal_gap 0.5)
				(thermal_bridge_width 0.5)
				(island_removal_mode 0)
			)
			(polygon
				(pts
					(xy 261.849108 3.472434) (xy 261.849108 3.37693) (xy 261.252208 3.37693) (xy 261.252208 2.97053)
					(xy 261.849108 2.97053) (xy 261.849108 2.877058) (xy 261.252208 2.877058) (xy 261.252208 2.470658)
					(xy 261.849108 2.470658) (xy 261.849108 2.375154) (xy 261.150608 2.375154) (xy 261.150608 3.472434)
				)
			)
		)
	)
	(footprint ""
		(layer "B.Cu")
		(at 157.686756 -39.871904 90)
		(property "Reference" "C2319"
			(at 0 0 90)
			(layer "B.SilkS")
			(hide yes)
			(effects
				(font
					(size 1.27 1.27)
				)
				(justify mirror)
			)
		)
		(property "Value" ""
			(at 0 0 90)
			(layer "B.Fab")
			(effects
				(font
					(size 1.27 1.27)
				)
				(justify mirror)
			)
		)
		(duplicate_pad_numbers_are_jumpers no)
		(fp_line
			(start 0.7874 -0.4064)
			(end -0.7874 -0.4064)
			(stroke
				(width 0.1524)
				(type default)
			)
			(layer "B.SilkS")
		)
		(fp_line
			(start -0.7874 -0.4064)
			(end -0.7874 0.4064)
			(stroke
				(width 0.1524)
				(type default)
			)
			(layer "B.SilkS")
		)
		(fp_line
			(start 0.7874 0.4064)
			(end 0.7874 -0.4064)
			(stroke
				(width 0.1524)
				(type default)
			)
			(layer "B.SilkS")
		)
		(fp_line
			(start -0.7874 0.4064)
			(end 0.7874 0.4064)
			(stroke
				(width 0.1524)
				(type default)
			)
			(layer "B.SilkS")
		)
		(fp_line
			(start 0.67945 -0.305054)
			(end 0.12065 -0.305054)
			(stroke
				(width 0.1)
				(type default)
			)
			(layer "B.Fab")
		)
		(fp_line
			(start 0.12065 -0.305054)
			(end 0.12065 -0.2794)
			(stroke
				(width 0.1)
				(type default)
			)
			(layer "B.Fab")
		)
		(fp_line
			(start -0.12065 -0.3048)
			(end -0.67945 -0.3048)
			(stroke
				(width 0.1)
				(type default)
			)
			(layer "B.Fab")
		)
		(fp_line
			(start -0.67945 -0.3048)
			(end -0.67945 0.3048)
			(stroke
				(width 0.1)
				(type default)
			)
			(layer "B.Fab")
		)
		(fp_line
			(start 0.12065 -0.2794)
			(end -0.12065 -0.2794)
			(stroke
				(width 0.1)
				(type default)
			)
			(layer "B.Fab")
		)
		(fp_line
			(start -0.12065 -0.2794)
			(end -0.12065 -0.3048)
			(stroke
				(width 0.1)
				(type default)
			)
			(layer "B.Fab")
		)
		(fp_line
			(start 0.12065 0.2794)
			(end 0.12065 0.3048)
			(stroke
				(width 0.1)
				(type default)
			)
			(layer "B.Fab")
		)
		(fp_line
			(start -0.120396 0.2794)
			(end 0.12065 0.2794)
			(stroke
				(width 0.1)
				(type default)
			)
			(layer "B.Fab")
		)
		(fp_line
			(start 0.67945 0.3048)
			(end 0.67945 -0.305054)
			(stroke
				(width 0.1)
				(type default)
			)
			(layer "B.Fab")
		)
		(fp_line
			(start 0.12065 0.3048)
			(end 0.67945 0.3048)
			(stroke
				(width 0.1)
				(type default)
			)
			(layer "B.Fab")
		)
		(fp_line
			(start -0.120396 0.3048)
			(end -0.120396 0.2794)
			(stroke
				(width 0.1)
				(type default)
			)
			(layer "B.Fab")
		)
		(fp_line
			(start -0.67945 0.3048)
			(end -0.120396 0.3048)
			(stroke
				(width 0.1)
				(type default)
			)
			(layer "B.Fab")
		)
		(pad "1" smd circle
			(at 0.40005 0 270)
			(size 0 0)
			(layers "B.Cu" "B.Mask" "B.Paste")
			(net "P3V3_AUX_USB_HUB_2")
		)
		(pad "2" smd circle
			(at -0.40005 0 270)
			(size 0 0)
			(layers "B.Cu" "B.Mask" "B.Paste")
			(net "GND")
		)
	)
	(footprint ""
		(layer "B.Cu")
		(at 375.578624 -190.703454 -90)
		(property "Reference" "R295"
			(at 0 0 90)
			(layer "B.SilkS")
			(hide yes)
			(effects
				(font
					(size 1.27 1.27)
				)
				(justify mirror)
			)
		)
		(property "Value" ""
			(at 0 0 90)
			(layer "B.Fab")
			(effects
				(font
					(size 1.27 1.27)
				)
				(justify mirror)
			)
		)
		(duplicate_pad_numbers_are_jumpers no)
		(fp_line
			(start -0.7874 0.4064)
			(end 0.7874 0.4064)
			(stroke
				(width 0.1524)
				(type default)
			)
			(layer "B.SilkS")
		)
		(fp_line
			(start 0.7874 0.4064)
			(end 0.7874 -0.4064)
			(stroke
				(width 0.1524)
				(type default)
			)
			(layer "B.SilkS")
		)
		(fp_line
			(start -0.7874 -0.4064)
			(end -0.7874 0.4064)
			(stroke
				(width 0.1524)
				(type default)
			)
			(layer "B.SilkS")
		)
		(fp_line
			(start 0.7874 -0.4064)
			(end -0.7874 -0.4064)
			(stroke
				(width 0.1524)
				(type default)
			)
			(layer "B.SilkS")
		)
		(fp_line
			(start -0.67945 0.3048)
			(end -0.120396 0.3048)
			(stroke
				(width 0.1)
				(type default)
			)
			(layer "B.Fab")
		)
		(fp_line
			(start -0.120396 0.3048)
			(end -0.120396 0.2794)
			(stroke
				(width 0.1)
				(type default)
			)
			(layer "B.Fab")
		)
		(fp_line
			(start 0.12065 0.3048)
			(end 0.67945 0.3048)
			(stroke
				(width 0.1)
				(type default)
			)
			(layer "B.Fab")
		)
		(fp_line
			(start 0.67945 0.3048)
			(end 0.67945 -0.305054)
			(stroke
				(width 0.1)
				(type default)
			)
			(layer "B.Fab")
		)
		(fp_line
			(start -0.120396 0.2794)
			(end 0.12065 0.2794)
			(stroke
				(width 0.1)
				(type default)
			)
			(layer "B.Fab")
		)
		(fp_line
			(start 0.12065 0.2794)
			(end 0.12065 0.3048)
			(stroke
				(width 0.1)
				(type default)
			)
			(layer "B.Fab")
		)
		(fp_line
			(start -0.12065 -0.2794)
			(end -0.12065 -0.3048)
			(stroke
				(width 0.1)
				(type default)
			)
			(layer "B.Fab")
		)
		(fp_line
			(start 0.12065 -0.2794)
			(end -0.12065 -0.2794)
			(stroke
				(width 0.1)
				(type default)
			)
			(layer "B.Fab")
		)
		(fp_line
			(start -0.67945 -0.3048)
			(end -0.67945 0.3048)
			(stroke
				(width 0.1)
				(type default)
			)
			(layer "B.Fab")
		)
		(fp_line
			(start -0.12065 -0.3048)
			(end -0.67945 -0.3048)
			(stroke
				(width 0.1)
				(type default)
			)
			(layer "B.Fab")
		)
		(fp_line
			(start 0.12065 -0.305054)
			(end 0.12065 -0.2794)
			(stroke
				(width 0.1)
				(type default)
			)
			(layer "B.Fab")
		)
		(fp_line
			(start 0.67945 -0.305054)
			(end 0.12065 -0.305054)
			(stroke
				(width 0.1)
				(type default)
			)
			(layer "B.Fab")
		)
		(pad "1" smd circle
			(at 0.40005 0 90)
			(size 0 0)
			(layers "B.Cu" "B.Mask" "B.Paste")
			(net "GND")
		)
		(pad "2" smd circle
			(at -0.40005 0 90)
			(size 0 0)
			(layers "B.Cu" "B.Mask" "B.Paste")
			(net "PD_CPU0_ENH_MCECC_DIS")
		)
	)
	(footprint ""
		(layer "B.Cu")
		(at 8.22198 -37.551868)
		(property "Reference" ""
			(at 0 0 0)
			(layer "B.SilkS")
			(hide yes)
			(effects
				(font
					(size 1.27 1.27)
				)
				(justify mirror)
			)
		)
		(property "Value" ""
			(at 0 0 0)
			(layer "B.Fab")
			(effects
				(font
					(size 1.27 1.27)
				)
				(justify mirror)
			)
		)
		(duplicate_pad_numbers_are_jumpers no)
		(pad "1" smd circle
			(at 0 0 180)
			(size 0.9906 0.9906)
			(layers "B.Cu" "B.Mask" "B.Paste")
			(net "Net_291")
		)
		(zone
			(layer "B.Cu")
			(hatch none 0.5)
			(connect_pads
				(clearance 0)
			)
			(min_thickness 0.25)
			(keepout
				(tracks not_allowed)
				(vias allowed)
				(pads allowed)
				(copperpour not_allowed)
				(footprints allowed)
			)
			(placement
				(enabled no)
				(sheetname "")
			)
			(fill
				(thermal_gap 0.5)
				(thermal_bridge_width 0.5)
				(island_removal_mode 0)
			)
			(polygon
				(pts
					(arc
						(start 9.84758 -37.551868)
						(mid 6.59638 -37.551868)
						(end 9.84758 -37.551868)
					)
				)
			)
		)
	)
	(footprint ""
		(layer "B.Cu")
		(at 311.84088 -54.320948)
		(property "Reference" "R4105"
			(at 0 0 0)
			(layer "B.SilkS")
			(hide yes)
			(effects
				(font
					(size 1.27 1.27)
				)
				(justify mirror)
			)
		)
		(property "Value" ""
			(at 0 0 0)
			(layer "B.Fab")
			(effects
				(font
					(size 1.27 1.27)
				)
				(justify mirror)
			)
		)
		(duplicate_pad_numbers_are_jumpers no)
		(fp_line
			(start -0.7874 -0.4064)
			(end -0.7874 0.4064)
			(stroke
				(width 0.1524)
				(type default)
			)
			(layer "B.SilkS")
		)
		(fp_line
			(start -0.7874 0.4064)
			(end 0.7874 0.4064)
			(stroke
				(width 0.1524)
				(type default)
			)
			(layer "B.SilkS")
		)
		(fp_line
			(start 0.7874 -0.4064)
			(end -0.7874 -0.4064)
			(stroke
				(width 0.1524)
				(type default)
			)
			(layer "B.SilkS")
		)
		(fp_line
			(start 0.7874 0.4064)
			(end 0.7874 -0.4064)
			(stroke
				(width 0.1524)
				(type default)
			)
			(layer "B.SilkS")
		)
		(fp_line
			(start -0.67945 -0.3048)
			(end -0.67945 0.3048)
			(stroke
				(width 0.1)
				(type default)
			)
			(layer "B.Fab")
		)
		(fp_line
			(start -0.67945 0.3048)
			(end -0.120396 0.3048)
			(stroke
				(width 0.1)
				(type default)
			)
			(layer "B.Fab")
		)
		(fp_line
			(start -0.12065 -0.3048)
			(end -0.67945 -0.3048)
			(stroke
				(width 0.1)
				(type default)
			)
			(layer "B.Fab")
		)
		(fp_line
			(start -0.12065 -0.2794)
			(end -0.12065 -0.3048)
			(stroke
				(width 0.1)
				(type default)
			)
			(layer "B.Fab")
		)
		(fp_line
			(start -0.120396 0.2794)
			(end 0.12065 0.2794)
			(stroke
				(width 0.1)
				(type default)
			)
			(layer "B.Fab")
		)
		(fp_line
			(start -0.120396 0.3048)
			(end -0.120396 0.2794)
			(stroke
				(width 0.1)
				(type default)
			)
			(layer "B.Fab")
		)
		(fp_line
			(start 0.12065 -0.305054)
			(end 0.12065 -0.2794)
			(stroke
				(width 0.1)
				(type default)
			)
			(layer "B.Fab")
		)
		(fp_line
			(start 0.12065 -0.2794)
			(end -0.12065 -0.2794)
			(stroke
				(width 0.1)
				(type default)
			)
			(layer "B.Fab")
		)
		(fp_line
			(start 0.12065 0.2794)
			(end 0.12065 0.3048)
			(stroke
				(width 0.1)
				(type default)
			)
			(layer "B.Fab")
		)
		(fp_line
			(start 0.12065 0.3048)
			(end 0.67945 0.3048)
			(stroke
				(width 0.1)
				(type default)
			)
			(layer "B.Fab")
		)
		(fp_line
			(start 0.67945 -0.305054)
			(end 0.12065 -0.305054)
			(stroke
				(width 0.1)
				(type default)
			)
			(layer "B.Fab")
		)
		(fp_line
			(start 0.67945 0.3048)
			(end 0.67945 -0.305054)
			(stroke
				(width 0.1)
				(type default)
			)
			(layer "B.Fab")
		)
		(pad "1" smd circle
			(at 0.40005 0 180)
			(size 0 0)
			(layers "B.Cu" "B.Mask" "B.Paste")
			(net "PD_GPP_M_15")
		)
		(pad "2" smd circle
			(at -0.40005 0 180)
			(size 0 0)
			(layers "B.Cu" "B.Mask" "B.Paste")
			(net "GND")
		)
	)
	(footprint ""
		(layer "B.Cu")
		(at 46.412658 -344.729054 -90)
		(property "Reference" "PC1203_P1_4"
			(at 0 0 90)
			(layer "B.SilkS")
			(hide yes)
			(effects
				(font
					(size 1.27 1.27)
				)
				(justify mirror)
			)
		)
		(property "Value" ""
			(at 0 0 90)
			(layer "B.Fab")
			(effects
				(font
					(size 1.27 1.27)
				)
				(justify mirror)
			)
		)
		(duplicate_pad_numbers_are_jumpers no)
		(fp_line
			(start -0.7874 0.4064)
			(end 0.7874 0.4064)
			(stroke
				(width 0.1524)
				(type default)
			)
			(layer "B.SilkS")
		)
		(fp_line
			(start 0.7874 0.4064)
			(end 0.7874 -0.4064)
			(stroke
				(width 0.1524)
				(type default)
			)
			(layer "B.SilkS")
		)
		(fp_line
			(start -0.7874 -0.4064)
			(end -0.7874 0.4064)
			(stroke
				(width 0.1524)
				(type default)
			)
			(layer "B.SilkS")
		)
		(fp_line
			(start 0.7874 -0.4064)
			(end -0.7874 -0.4064)
			(stroke
				(width 0.1524)
				(type default)
			)
			(layer "B.SilkS")
		)
		(fp_line
			(start -0.67945 0.3048)
			(end -0.120396 0.3048)
			(stroke
				(width 0.1)
				(type default)
			)
			(layer "B.Fab")
		)
		(fp_line
			(start -0.120396 0.3048)
			(end -0.120396 0.2794)
			(stroke
				(width 0.1)
				(type default)
			)
			(layer "B.Fab")
		)
		(fp_line
			(start 0.12065 0.3048)
			(end 0.67945 0.3048)
			(stroke
				(width 0.1)
				(type default)
			)
			(layer "B.Fab")
		)
		(fp_line
			(start 0.67945 0.3048)
			(end 0.67945 -0.305054)
			(stroke
				(width 0.1)
				(type default)
			)
			(layer "B.Fab")
		)
		(fp_line
			(start -0.120396 0.2794)
			(end 0.12065 0.2794)
			(stroke
				(width 0.1)
				(type default)
			)
			(layer "B.Fab")
		)
		(fp_line
			(start 0.12065 0.2794)
			(end 0.12065 0.3048)
			(stroke
				(width 0.1)
				(type default)
			)
			(layer "B.Fab")
		)
		(fp_line
			(start -0.12065 -0.2794)
			(end -0.12065 -0.3048)
			(stroke
				(width 0.1)
				(type default)
			)
			(layer "B.Fab")
		)
		(fp_line
			(start 0.12065 -0.2794)
			(end -0.12065 -0.2794)
			(stroke
				(width 0.1)
				(type default)
			)
			(layer "B.Fab")
		)
		(fp_line
			(start -0.67945 -0.3048)
			(end -0.67945 0.3048)
			(stroke
				(width 0.1)
				(type default)
			)
			(layer "B.Fab")
		)
		(fp_line
			(start -0.12065 -0.3048)
			(end -0.67945 -0.3048)
			(stroke
				(width 0.1)
				(type default)
			)
			(layer "B.Fab")
		)
		(fp_line
			(start 0.12065 -0.305054)
			(end 0.12065 -0.2794)
			(stroke
				(width 0.1)
				(type default)
			)
			(layer "B.Fab")
		)
		(fp_line
			(start 0.67945 -0.305054)
			(end 0.12065 -0.305054)
			(stroke
				(width 0.1)
				(type default)
			)
			(layer "B.Fab")
		)
		(pad "1" smd circle
			(at 0.40005 0 90)
			(size 0 0)
			(layers "B.Cu" "B.Mask" "B.Paste")
			(net "PVCCFA_EHV_FIVRA_CPU1")
		)
		(pad "2" smd circle
			(at -0.40005 0 90)
			(size 0 0)
			(layers "B.Cu" "B.Mask" "B.Paste")
			(net "GND")
		)
	)
	(footprint ""
		(layer "B.Cu")
		(at 337.622134 -136.479534 180)
		(property "Reference" "R1021"
			(at 0 0 0)
			(layer "B.SilkS")
			(hide yes)
			(effects
				(font
					(size 1.27 1.27)
				)
				(justify mirror)
			)
		)
		(property "Value" ""
			(at 0 0 0)
			(layer "B.Fab")
			(effects
				(font
					(size 1.27 1.27)
				)
				(justify mirror)
			)
		)
		(duplicate_pad_numbers_are_jumpers no)
		(fp_line
			(start 0.7874 -0.083566)
			(end 0.7874 -0.4064)
			(stroke
				(width 0.1524)
				(type default)
			)
			(layer "B.SilkS")
		)
		(fp_line
			(start 0.7874 -0.4064)
			(end -0.7874 -0.4064)
			(stroke
				(width 0.1524)
				(type default)
			)
			(layer "B.SilkS")
		)
		(fp_line
			(start -0.169926 0.4064)
			(end 0.495554 0.4064)
			(stroke
				(width 0.1524)
				(type default)
			)
			(layer "B.SilkS")
		)
		(fp_line
			(start -0.7874 0.4064)
			(end -0.604266 0.4064)
			(stroke
				(width 0.1524)
				(type default)
			)
			(layer "B.SilkS")
		)
		(fp_line
			(start -0.7874 -0.4064)
			(end -0.7874 0.4064)
			(stroke
				(width 0.1524)
				(type default)
			)
			(layer "B.SilkS")
		)
		(fp_line
			(start 0.67945 0.3048)
			(end 0.67945 -0.305054)
			(stroke
				(width 0.1)
				(type default)
			)
			(layer "B.Fab")
		)
		(fp_line
			(start 0.67945 -0.305054)
			(end 0.12065 -0.305054)
			(stroke
				(width 0.1)
				(type default)
			)
			(layer "B.Fab")
		)
		(fp_line
			(start 0.12065 0.3048)
			(end 0.67945 0.3048)
			(stroke
				(width 0.1)
				(type default)
			)
			(layer "B.Fab")
		)
		(fp_line
			(start 0.12065 0.2794)
			(end 0.12065 0.3048)
			(stroke
				(width 0.1)
				(type default)
			)
			(layer "B.Fab")
		)
		(fp_line
			(start 0.12065 -0.2794)
			(end -0.12065 -0.2794)
			(stroke
				(width 0.1)
				(type default)
			)
			(layer "B.Fab")
		)
		(fp_line
			(start 0.12065 -0.305054)
			(end 0.12065 -0.2794)
			(stroke
				(width 0.1)
				(type default)
			)
			(layer "B.Fab")
		)
		(fp_line
			(start -0.120396 0.3048)
			(end -0.120396 0.2794)
			(stroke
				(width 0.1)
				(type default)
			)
			(layer "B.Fab")
		)
		(fp_line
			(start -0.120396 0.2794)
			(end 0.12065 0.2794)
			(stroke
				(width 0.1)
				(type default)
			)
			(layer "B.Fab")
		)
		(fp_line
			(start -0.12065 -0.2794)
			(end -0.12065 -0.3048)
			(stroke
				(width 0.1)
				(type default)
			)
			(layer "B.Fab")
		)
		(fp_line
			(start -0.12065 -0.3048)
			(end -0.67945 -0.3048)
			(stroke
				(width 0.1)
				(type default)
			)
			(layer "B.Fab")
		)
		(fp_line
			(start -0.67945 0.3048)
			(end -0.120396 0.3048)
			(stroke
				(width 0.1)
				(type default)
			)
			(layer "B.Fab")
		)
		(fp_line
			(start -0.67945 -0.3048)
			(end -0.67945 0.3048)
			(stroke
				(width 0.1)
				(type default)
			)
			(layer "B.Fab")
		)
		(pad "1" smd rect
			(at 0.40005 0 180)
			(size 0.4572 0.508)
			(layers "B.Cu" "B.Mask" "B.Paste")
			(net "CLK_25M_CK440_CPU0_R_DN")
		)
		(pad "2" smd rect
			(at -0.40005 0 180)
			(size 0.4572 0.508)
			(layers "B.Cu" "B.Mask" "B.Paste")
			(net "CLK_25M_NSSC_CPU0_DN")
		)
	)
	(footprint ""
		(layer "B.Cu")
		(at 308.901846 -316.14999 -90)
		(property "Reference" "D42"
			(at 1.284732 1.231646 0)
			(unlocked yes)
			(layer "B.SilkS")
			(effects
				(font
					(size 0.7874 0.5842)
					(thickness 0.1524)
				)
				(justify left mirror)
			)
		)
		(property "Value" ""
			(at 0 0 90)
			(layer "B.Fab")
			(effects
				(font
					(size 1.27 1.27)
				)
				(justify mirror)
			)
		)
		(duplicate_pad_numbers_are_jumpers no)
		(fp_line
			(start -2.050796 0.700024)
			(end 2.050796 0.700024)
			(stroke
				(width 0.1524)
				(type default)
			)
			(layer "B.SilkS")
		)
		(fp_line
			(start 2.050796 0.700024)
			(end 2.050796 -0.700024)
			(stroke
				(width 0.1524)
				(type default)
			)
			(layer "B.SilkS")
		)
		(fp_line
			(start -2.343404 0.6985)
			(end -2.216404 0.6985)
			(stroke
				(width 0.1524)
				(type default)
			)
			(layer "B.SilkS")
		)
		(fp_line
			(start -2.229104 0.6985)
			(end -2.051304 0.6985)
			(stroke
				(width 0.1524)
				(type default)
			)
			(layer "B.SilkS")
		)
		(fp_line
			(start -2.051304 0.6985)
			(end -2.051304 0.635)
			(stroke
				(width 0.1524)
				(type default)
			)
			(layer "B.SilkS")
		)
		(fp_line
			(start -2.152904 0.635)
			(end -2.152904 -0.6985)
			(stroke
				(width 0.1524)
				(type default)
			)
			(layer "B.SilkS")
		)
		(fp_line
			(start -2.051304 0.635)
			(end -2.152904 0.635)
			(stroke
				(width 0.1524)
				(type default)
			)
			(layer "B.SilkS")
		)
		(fp_line
			(start 0.30607 0.500126)
			(end -0.193802 0)
			(stroke
				(width 0.1524)
				(type default)
			)
			(layer "B.SilkS")
		)
		(fp_line
			(start -0.193802 0)
			(end 0.30607 -0.500126)
			(stroke
				(width 0.1524)
				(type default)
			)
			(layer "B.SilkS")
		)
		(fp_line
			(start -0.293878 -0.500126)
			(end -0.293878 0.500126)
			(stroke
				(width 0.1524)
				(type default)
			)
			(layer "B.SilkS")
		)
		(fp_line
			(start 0.30607 -0.500126)
			(end 0.30607 0.500126)
			(stroke
				(width 0.1524)
				(type default)
			)
			(layer "B.SilkS")
		)
		(fp_line
			(start -2.064004 -0.6731)
			(end -2.064004 -0.6985)
			(stroke
				(width 0.1524)
				(type default)
			)
			(layer "B.SilkS")
		)
		(fp_line
			(start -2.343404 -0.6985)
			(end -2.343404 0.6985)
			(stroke
				(width 0.1524)
				(type default)
			)
			(layer "B.SilkS")
		)
		(fp_line
			(start -2.229104 -0.6985)
			(end -2.229104 0.6985)
			(stroke
				(width 0.1524)
				(type default)
			)
			(layer "B.SilkS")
		)
		(fp_line
			(start -2.152904 -0.6985)
			(end -2.343404 -0.6985)
			(stroke
				(width 0.1524)
				(type default)
			)
			(layer "B.SilkS")
		)
		(fp_line
			(start -2.064004 -0.6985)
			(end -2.229104 -0.6985)
			(stroke
				(width 0.1524)
				(type default)
			)
			(layer "B.SilkS")
		)
		(fp_line
			(start -2.050796 -0.700024)
			(end -2.050796 0.700024)
			(stroke
				(width 0.1524)
				(type default)
			)
			(layer "B.SilkS")
		)
		(fp_line
			(start 2.050796 -0.700024)
			(end -2.050796 -0.700024)
			(stroke
				(width 0.1524)
				(type default)
			)
			(layer "B.SilkS")
		)
		(fp_line
			(start -0.899922 0.700024)
			(end 0.899922 0.700024)
			(stroke
				(width 0.1)
				(type default)
			)
			(layer "B.Fab")
		)
		(fp_line
			(start 0.899922 0.700024)
			(end 0.899922 -0.700024)
			(stroke
				(width 0.1)
				(type default)
			)
			(layer "B.Fab")
		)
		(fp_line
			(start -0.899922 -0.700024)
			(end -0.899922 0.700024)
			(stroke
				(width 0.1)
				(type default)
			)
			(layer "B.Fab")
		)
		(fp_line
			(start 0.899922 -0.700024)
			(end -0.899922 -0.700024)
			(stroke
				(width 0.1)
				(type default)
			)
			(layer "B.Fab")
		)
		(fp_text user "-"
			(at -3.65633 0.895096 90)
			(unlocked yes)
			(layer "B.SilkS")
			(effects
				(font
					(size 1.905 1.4224)
					(thickness 0.1524)
				)
				(justify left mirror)
			)
		)
		(fp_text user "+"
			(at 3.123946 0.762 180)
			(unlocked yes)
			(layer "B.SilkS")
			(effects
				(font
					(size 1.905 1.4224)
					(thickness 0.1524)
				)
				(justify left mirror)
			)
		)
		(fp_text user "+"
			(at 3.123946 0.762 180)
			(unlocked yes)
			(layer "B.Fab")
			(effects
				(font
					(size 1.905 1.4224)
					(thickness 0.1524)
				)
				(justify left mirror)
			)
		)
		(fp_text user "-"
			(at -3.880104 0.23495 90)
			(unlocked yes)
			(layer "B.Fab")
			(effects
				(font
					(size 1.905 1.4224)
					(thickness 0.1524)
				)
				(justify left mirror)
			)
		)
		(pad "1" smd rect
			(at 1.199896 0 180)
			(size 0.6604 1.3716)
			(layers "B.Cu" "B.Mask" "B.Paste")
			(net "PWRGD_FAIL_CPU0_AB_R1")
		)
		(pad "2" smd rect
			(at -1.199896 0)
			(size 0.6604 1.3716)
			(layers "B.Cu" "B.Mask" "B.Paste")
			(net "P3V3_AUX")
		)
	)
	(footprint ""
		(layer "B.Cu")
		(at 213.79688 -54.447948 90)
		(property "Reference" "R3751"
			(at 0 0 90)
			(layer "B.SilkS")
			(hide yes)
			(effects
				(font
					(size 1.27 1.27)
				)
				(justify mirror)
			)
		)
		(property "Value" ""
			(at 0 0 90)
			(layer "B.Fab")
			(effects
				(font
					(size 1.27 1.27)
				)
				(justify mirror)
			)
		)
		(duplicate_pad_numbers_are_jumpers no)
		(fp_line
			(start 0.7874 -0.4064)
			(end -0.7874 -0.4064)
			(stroke
				(width 0.1524)
				(type default)
			)
			(layer "B.SilkS")
		)
		(fp_line
			(start -0.7874 -0.4064)
			(end -0.7874 0.4064)
			(stroke
				(width 0.1524)
				(type default)
			)
			(layer "B.SilkS")
		)
		(fp_line
			(start 0.7874 0.4064)
			(end 0.7874 -0.4064)
			(stroke
				(width 0.1524)
				(type default)
			)
			(layer "B.SilkS")
		)
		(fp_line
			(start -0.7874 0.4064)
			(end 0.7874 0.4064)
			(stroke
				(width 0.1524)
				(type default)
			)
			(layer "B.SilkS")
		)
		(fp_line
			(start 0.67945 -0.305054)
			(end 0.12065 -0.305054)
			(stroke
				(width 0.1)
				(type default)
			)
			(layer "B.Fab")
		)
		(fp_line
			(start 0.12065 -0.305054)
			(end 0.12065 -0.2794)
			(stroke
				(width 0.1)
				(type default)
			)
			(layer "B.Fab")
		)
		(fp_line
			(start -0.12065 -0.3048)
			(end -0.67945 -0.3048)
			(stroke
				(width 0.1)
				(type default)
			)
			(layer "B.Fab")
		)
		(fp_line
			(start -0.67945 -0.3048)
			(end -0.67945 0.3048)
			(stroke
				(width 0.1)
				(type default)
			)
			(layer "B.Fab")
		)
		(fp_line
			(start 0.12065 -0.2794)
			(end -0.12065 -0.2794)
			(stroke
				(width 0.1)
				(type default)
			)
			(layer "B.Fab")
		)
		(fp_line
			(start -0.12065 -0.2794)
			(end -0.12065 -0.3048)
			(stroke
				(width 0.1)
				(type default)
			)
			(layer "B.Fab")
		)
		(fp_line
			(start 0.12065 0.2794)
			(end 0.12065 0.3048)
			(stroke
				(width 0.1)
				(type default)
			)
			(layer "B.Fab")
		)
		(fp_line
			(start -0.120396 0.2794)
			(end 0.12065 0.2794)
			(stroke
				(width 0.1)
				(type default)
			)
			(layer "B.Fab")
		)
		(fp_line
			(start 0.67945 0.3048)
			(end 0.67945 -0.305054)
			(stroke
				(width 0.1)
				(type default)
			)
			(layer "B.Fab")
		)
		(fp_line
			(start 0.12065 0.3048)
			(end 0.67945 0.3048)
			(stroke
				(width 0.1)
				(type default)
			)
			(layer "B.Fab")
		)
		(fp_line
			(start -0.120396 0.3048)
			(end -0.120396 0.2794)
			(stroke
				(width 0.1)
				(type default)
			)
			(layer "B.Fab")
		)
		(fp_line
			(start -0.67945 0.3048)
			(end -0.120396 0.3048)
			(stroke
				(width 0.1)
				(type default)
			)
			(layer "B.Fab")
		)
		(pad "1" smd circle
			(at 0.40005 0 270)
			(size 0 0)
			(layers "B.Cu" "B.Mask" "B.Paste")
			(net "INA230_2_A0")
		)
		(pad "2" smd circle
			(at -0.40005 0 270)
			(size 0 0)
			(layers "B.Cu" "B.Mask" "B.Paste")
			(net "SMB_INA230_2_3V3AUX_SDA_R1")
		)
	)
	(footprint ""
		(layer "B.Cu")
		(at 156.720032 -39.8653 90)
		(property "Reference" "C2318"
			(at 0 0 90)
			(layer "B.SilkS")
			(hide yes)
			(effects
				(font
					(size 1.27 1.27)
				)
				(justify mirror)
			)
		)
		(property "Value" ""
			(at 0 0 90)
			(layer "B.Fab")
			(effects
				(font
					(size 1.27 1.27)
				)
				(justify mirror)
			)
		)
		(duplicate_pad_numbers_are_jumpers no)
		(fp_line
			(start 0.7874 -0.4064)
			(end -0.7874 -0.4064)
			(stroke
				(width 0.1524)
				(type default)
			)
			(layer "B.SilkS")
		)
		(fp_line
			(start -0.7874 -0.4064)
			(end -0.7874 0.4064)
			(stroke
				(width 0.1524)
				(type default)
			)
			(layer "B.SilkS")
		)
		(fp_line
			(start 0.7874 0.4064)
			(end 0.7874 -0.4064)
			(stroke
				(width 0.1524)
				(type default)
			)
			(layer "B.SilkS")
		)
		(fp_line
			(start -0.7874 0.4064)
			(end 0.7874 0.4064)
			(stroke
				(width 0.1524)
				(type default)
			)
			(layer "B.SilkS")
		)
		(fp_line
			(start 0.67945 -0.305054)
			(end 0.12065 -0.305054)
			(stroke
				(width 0.1)
				(type default)
			)
			(layer "B.Fab")
		)
		(fp_line
			(start 0.12065 -0.305054)
			(end 0.12065 -0.2794)
			(stroke
				(width 0.1)
				(type default)
			)
			(layer "B.Fab")
		)
		(fp_line
			(start -0.12065 -0.3048)
			(end -0.67945 -0.3048)
			(stroke
				(width 0.1)
				(type default)
			)
			(layer "B.Fab")
		)
		(fp_line
			(start -0.67945 -0.3048)
			(end -0.67945 0.3048)
			(stroke
				(width 0.1)
				(type default)
			)
			(layer "B.Fab")
		)
		(fp_line
			(start 0.12065 -0.2794)
			(end -0.12065 -0.2794)
			(stroke
				(width 0.1)
				(type default)
			)
			(layer "B.Fab")
		)
		(fp_line
			(start -0.12065 -0.2794)
			(end -0.12065 -0.3048)
			(stroke
				(width 0.1)
				(type default)
			)
			(layer "B.Fab")
		)
		(fp_line
			(start 0.12065 0.2794)
			(end 0.12065 0.3048)
			(stroke
				(width 0.1)
				(type default)
			)
			(layer "B.Fab")
		)
		(fp_line
			(start -0.120396 0.2794)
			(end 0.12065 0.2794)
			(stroke
				(width 0.1)
				(type default)
			)
			(layer "B.Fab")
		)
		(fp_line
			(start 0.67945 0.3048)
			(end 0.67945 -0.305054)
			(stroke
				(width 0.1)
				(type default)
			)
			(layer "B.Fab")
		)
		(fp_line
			(start 0.12065 0.3048)
			(end 0.67945 0.3048)
			(stroke
				(width 0.1)
				(type default)
			)
			(layer "B.Fab")
		)
		(fp_line
			(start -0.120396 0.3048)
			(end -0.120396 0.2794)
			(stroke
				(width 0.1)
				(type default)
			)
			(layer "B.Fab")
		)
		(fp_line
			(start -0.67945 0.3048)
			(end -0.120396 0.3048)
			(stroke
				(width 0.1)
				(type default)
			)
			(layer "B.Fab")
		)
		(pad "1" smd circle
			(at 0.40005 0 270)
			(size 0 0)
			(layers "B.Cu" "B.Mask" "B.Paste")
			(net "P3V3_AUX_USB_HUB_2")
		)
		(pad "2" smd circle
			(at -0.40005 0 270)
			(size 0 0)
			(layers "B.Cu" "B.Mask" "B.Paste")
			(net "GND")
		)
	)
	(footprint ""
		(layer "B.Cu")
		(at 114.734848 -210.194144 180)
		(property "Reference" "C459"
			(at 0 0 0)
			(layer "B.SilkS")
			(hide yes)
			(effects
				(font
					(size 1.27 1.27)
				)
				(justify mirror)
			)
		)
		(property "Value" ""
			(at 0 0 0)
			(layer "B.Fab")
			(effects
				(font
					(size 1.27 1.27)
				)
				(justify mirror)
			)
		)
		(duplicate_pad_numbers_are_jumpers no)
		(fp_line
			(start 1.524 0.762)
			(end 1.524 -0.762)
			(stroke
				(width 0.1524)
				(type default)
			)
			(layer "B.SilkS")
		)
		(fp_line
			(start 1.524 -0.762)
			(end -1.524 -0.762)
			(stroke
				(width 0.1524)
				(type default)
			)
			(layer "B.SilkS")
		)
		(fp_line
			(start -1.524 0.762)
			(end 1.524 0.762)
			(stroke
				(width 0.1524)
				(type default)
			)
			(layer "B.SilkS")
		)
		(fp_line
			(start -1.524 -0.762)
			(end -1.524 0.762)
			(stroke
				(width 0.1524)
				(type default)
			)
			(layer "B.SilkS")
		)
		(fp_line
			(start 1.1049 0.724916)
			(end -1.1049 0.724916)
			(stroke
				(width 0.1)
				(type default)
			)
			(layer "B.Fab")
		)
		(fp_line
			(start 1.1049 -0.724916)
			(end 1.1049 0.724916)
			(stroke
				(width 0.1)
				(type default)
			)
			(layer "B.Fab")
		)
		(fp_line
			(start -1.1049 0.724916)
			(end -1.1049 -0.724916)
			(stroke
				(width 0.1)
				(type default)
			)
			(layer "B.Fab")
		)
		(fp_line
			(start -1.1049 -0.724916)
			(end 1.1049 -0.724916)
			(stroke
				(width 0.1)
				(type default)
			)
			(layer "B.Fab")
		)
		(pad "1" smd rect
			(at 0.889 0 180)
			(size 1.016 1.27)
			(layers "B.Cu" "B.Mask" "B.Paste")
			(net "PVCCD_HV_CPU1")
		)
		(pad "2" smd rect
			(at -0.889 0 180)
			(size 1.016 1.27)
			(layers "B.Cu" "B.Mask" "B.Paste")
			(net "GND")
		)
	)
	(footprint ""
		(layer "B.Cu")
		(at 419.605968 -353.25939 -90)
		(property "Reference" "PC617_P0_1"
			(at 0 0 90)
			(layer "B.SilkS")
			(hide yes)
			(effects
				(font
					(size 1.27 1.27)
				)
				(justify mirror)
			)
		)
		(property "Value" ""
			(at 0 0 90)
			(layer "B.Fab")
			(effects
				(font
					(size 1.27 1.27)
				)
				(justify mirror)
			)
		)
		(duplicate_pad_numbers_are_jumpers no)
		(fp_line
			(start -1.524 0.762)
			(end 1.524 0.762)
			(stroke
				(width 0.1524)
				(type default)
			)
			(layer "B.SilkS")
		)
		(fp_line
			(start 1.524 0.762)
			(end 1.524 -0.762)
			(stroke
				(width 0.1524)
				(type default)
			)
			(layer "B.SilkS")
		)
		(fp_line
			(start -1.524 -0.762)
			(end -1.524 0.762)
			(stroke
				(width 0.1524)
				(type default)
			)
			(layer "B.SilkS")
		)
		(fp_line
			(start 1.524 -0.762)
			(end -1.524 -0.762)
			(stroke
				(width 0.1524)
				(type default)
			)
			(layer "B.SilkS")
		)
		(fp_line
			(start -1.1049 0.724916)
			(end -1.1049 -0.724916)
			(stroke
				(width 0.1)
				(type default)
			)
			(layer "B.Fab")
		)
		(fp_line
			(start 1.1049 0.724916)
			(end -1.1049 0.724916)
			(stroke
				(width 0.1)
				(type default)
			)
			(layer "B.Fab")
		)
		(fp_line
			(start -1.1049 -0.724916)
			(end 1.1049 -0.724916)
			(stroke
				(width 0.1)
				(type default)
			)
			(layer "B.Fab")
		)
		(fp_line
			(start 1.1049 -0.724916)
			(end 1.1049 0.724916)
			(stroke
				(width 0.1)
				(type default)
			)
			(layer "B.Fab")
		)
		(pad "1" smd rect
			(at 0.889 0 270)
			(size 1.016 1.27)
			(layers "B.Cu" "B.Mask" "B.Paste")
			(net "PVCCFA_EHV_FIVRA_CPU0")
		)
		(pad "2" smd rect
			(at -0.889 0 270)
			(size 1.016 1.27)
			(layers "B.Cu" "B.Mask" "B.Paste")
			(net "GND")
		)
	)
	(footprint ""
		(layer "B.Cu")
		(at 236.851698 -123.871482 90)
		(property "Reference" "C206"
			(at 0 0 90)
			(layer "B.SilkS")
			(hide yes)
			(effects
				(font
					(size 1.27 1.27)
				)
				(justify mirror)
			)
		)
		(property "Value" ""
			(at 0 0 90)
			(layer "B.Fab")
			(effects
				(font
					(size 1.27 1.27)
				)
				(justify mirror)
			)
		)
		(duplicate_pad_numbers_are_jumpers no)
		(fp_line
			(start 0.7874 -0.4064)
			(end -0.7874 -0.4064)
			(stroke
				(width 0.1524)
				(type default)
			)
			(layer "B.SilkS")
		)
		(fp_line
			(start -0.7874 -0.4064)
			(end -0.7874 0.4064)
			(stroke
				(width 0.1524)
				(type default)
			)
			(layer "B.SilkS")
		)
		(fp_line
			(start 0.7874 0.4064)
			(end 0.7874 -0.4064)
			(stroke
				(width 0.1524)
				(type default)
			)
			(layer "B.SilkS")
		)
		(fp_line
			(start -0.7874 0.4064)
			(end 0.7874 0.4064)
			(stroke
				(width 0.1524)
				(type default)
			)
			(layer "B.SilkS")
		)
		(fp_line
			(start 0.67945 -0.305054)
			(end 0.12065 -0.305054)
			(stroke
				(width 0.1)
				(type default)
			)
			(layer "B.Fab")
		)
		(fp_line
			(start 0.12065 -0.305054)
			(end 0.12065 -0.2794)
			(stroke
				(width 0.1)
				(type default)
			)
			(layer "B.Fab")
		)
		(fp_line
			(start -0.12065 -0.3048)
			(end -0.67945 -0.3048)
			(stroke
				(width 0.1)
				(type default)
			)
			(layer "B.Fab")
		)
		(fp_line
			(start -0.67945 -0.3048)
			(end -0.67945 0.3048)
			(stroke
				(width 0.1)
				(type default)
			)
			(layer "B.Fab")
		)
		(fp_line
			(start 0.12065 -0.2794)
			(end -0.12065 -0.2794)
			(stroke
				(width 0.1)
				(type default)
			)
			(layer "B.Fab")
		)
		(fp_line
			(start -0.12065 -0.2794)
			(end -0.12065 -0.3048)
			(stroke
				(width 0.1)
				(type default)
			)
			(layer "B.Fab")
		)
		(fp_line
			(start 0.12065 0.2794)
			(end 0.12065 0.3048)
			(stroke
				(width 0.1)
				(type default)
			)
			(layer "B.Fab")
		)
		(fp_line
			(start -0.120396 0.2794)
			(end 0.12065 0.2794)
			(stroke
				(width 0.1)
				(type default)
			)
			(layer "B.Fab")
		)
		(fp_line
			(start 0.67945 0.3048)
			(end 0.67945 -0.305054)
			(stroke
				(width 0.1)
				(type default)
			)
			(layer "B.Fab")
		)
		(fp_line
			(start 0.12065 0.3048)
			(end 0.67945 0.3048)
			(stroke
				(width 0.1)
				(type default)
			)
			(layer "B.Fab")
		)
		(fp_line
			(start -0.120396 0.3048)
			(end -0.120396 0.2794)
			(stroke
				(width 0.1)
				(type default)
			)
			(layer "B.Fab")
		)
		(fp_line
			(start -0.67945 0.3048)
			(end -0.120396 0.3048)
			(stroke
				(width 0.1)
				(type default)
			)
			(layer "B.Fab")
		)
		(pad "1" smd circle
			(at 0.40005 0 270)
			(size 0 0)
			(layers "B.Cu" "B.Mask" "B.Paste")
			(net "P3V3_DB2000_VDD")
		)
		(pad "2" smd circle
			(at -0.40005 0 270)
			(size 0 0)
			(layers "B.Cu" "B.Mask" "B.Paste")
			(net "GND")
		)
	)
	(footprint ""
		(layer "B.Cu")
		(at 449.5546 -10.594086 90)
		(property "Reference" "R423"
			(at 0 0 90)
			(layer "B.SilkS")
			(hide yes)
			(effects
				(font
					(size 1.27 1.27)
				)
				(justify mirror)
			)
		)
		(property "Value" ""
			(at 0 0 90)
			(layer "B.Fab")
			(effects
				(font
					(size 1.27 1.27)
				)
				(justify mirror)
			)
		)
		(duplicate_pad_numbers_are_jumpers no)
		(fp_line
			(start 0.7874 -0.4064)
			(end -0.7874 -0.4064)
			(stroke
				(width 0.1524)
				(type default)
			)
			(layer "B.SilkS")
		)
		(fp_line
			(start -0.7874 -0.4064)
			(end -0.7874 0.4064)
			(stroke
				(width 0.1524)
				(type default)
			)
			(layer "B.SilkS")
		)
		(fp_line
			(start 0.7874 0.4064)
			(end 0.7874 -0.4064)
			(stroke
				(width 0.1524)
				(type default)
			)
			(layer "B.SilkS")
		)
		(fp_line
			(start -0.7874 0.4064)
			(end 0.7874 0.4064)
			(stroke
				(width 0.1524)
				(type default)
			)
			(layer "B.SilkS")
		)
		(fp_line
			(start 0.67945 -0.305054)
			(end 0.12065 -0.305054)
			(stroke
				(width 0.1)
				(type default)
			)
			(layer "B.Fab")
		)
		(fp_line
			(start 0.12065 -0.305054)
			(end 0.12065 -0.2794)
			(stroke
				(width 0.1)
				(type default)
			)
			(layer "B.Fab")
		)
		(fp_line
			(start -0.12065 -0.3048)
			(end -0.67945 -0.3048)
			(stroke
				(width 0.1)
				(type default)
			)
			(layer "B.Fab")
		)
		(fp_line
			(start -0.67945 -0.3048)
			(end -0.67945 0.3048)
			(stroke
				(width 0.1)
				(type default)
			)
			(layer "B.Fab")
		)
		(fp_line
			(start 0.12065 -0.2794)
			(end -0.12065 -0.2794)
			(stroke
				(width 0.1)
				(type default)
			)
			(layer "B.Fab")
		)
		(fp_line
			(start -0.12065 -0.2794)
			(end -0.12065 -0.3048)
			(stroke
				(width 0.1)
				(type default)
			)
			(layer "B.Fab")
		)
		(fp_line
			(start 0.12065 0.2794)
			(end 0.12065 0.3048)
			(stroke
				(width 0.1)
				(type default)
			)
			(layer "B.Fab")
		)
		(fp_line
			(start -0.120396 0.2794)
			(end 0.12065 0.2794)
			(stroke
				(width 0.1)
				(type default)
			)
			(layer "B.Fab")
		)
		(fp_line
			(start 0.67945 0.3048)
			(end 0.67945 -0.305054)
			(stroke
				(width 0.1)
				(type default)
			)
			(layer "B.Fab")
		)
		(fp_line
			(start 0.12065 0.3048)
			(end 0.67945 0.3048)
			(stroke
				(width 0.1)
				(type default)
			)
			(layer "B.Fab")
		)
		(fp_line
			(start -0.120396 0.3048)
			(end -0.120396 0.2794)
			(stroke
				(width 0.1)
				(type default)
			)
			(layer "B.Fab")
		)
		(fp_line
			(start -0.67945 0.3048)
			(end -0.120396 0.3048)
			(stroke
				(width 0.1)
				(type default)
			)
			(layer "B.Fab")
		)
		(pad "1" smd circle
			(at 0.40005 0 270)
			(size 0 0)
			(layers "B.Cu" "B.Mask" "B.Paste")
			(net "SGPIO_OCP_SFF_CLK")
		)
		(pad "2" smd circle
			(at -0.40005 0 270)
			(size 0 0)
			(layers "B.Cu" "B.Mask" "B.Paste")
			(net "P3V3_OCP_SFF")
		)
	)
	(footprint ""
		(layer "B.Cu")
		(at 178.10988 -102.707948)
		(property "Reference" "C1942"
			(at 0 0 0)
			(layer "B.SilkS")
			(hide yes)
			(effects
				(font
					(size 1.27 1.27)
				)
				(justify mirror)
			)
		)
		(property "Value" ""
			(at 0 0 0)
			(layer "B.Fab")
			(effects
				(font
					(size 1.27 1.27)
				)
				(justify mirror)
			)
		)
		(duplicate_pad_numbers_are_jumpers no)
		(fp_line
			(start -0.7874 -0.4064)
			(end -0.7874 0.4064)
			(stroke
				(width 0.1524)
				(type default)
			)
			(layer "B.SilkS")
		)
		(fp_line
			(start -0.7874 0.4064)
			(end 0.7874 0.4064)
			(stroke
				(width 0.1524)
				(type default)
			)
			(layer "B.SilkS")
		)
		(fp_line
			(start 0.7874 -0.4064)
			(end -0.7874 -0.4064)
			(stroke
				(width 0.1524)
				(type default)
			)
			(layer "B.SilkS")
		)
		(fp_line
			(start 0.7874 0.4064)
			(end 0.7874 -0.4064)
			(stroke
				(width 0.1524)
				(type default)
			)
			(layer "B.SilkS")
		)
		(fp_line
			(start -0.67945 -0.3048)
			(end -0.67945 0.3048)
			(stroke
				(width 0.1)
				(type default)
			)
			(layer "B.Fab")
		)
		(fp_line
			(start -0.67945 0.3048)
			(end -0.120396 0.3048)
			(stroke
				(width 0.1)
				(type default)
			)
			(layer "B.Fab")
		)
		(fp_line
			(start -0.12065 -0.3048)
			(end -0.67945 -0.3048)
			(stroke
				(width 0.1)
				(type default)
			)
			(layer "B.Fab")
		)
		(fp_line
			(start -0.12065 -0.2794)
			(end -0.12065 -0.3048)
			(stroke
				(width 0.1)
				(type default)
			)
			(layer "B.Fab")
		)
		(fp_line
			(start -0.120396 0.2794)
			(end 0.12065 0.2794)
			(stroke
				(width 0.1)
				(type default)
			)
			(layer "B.Fab")
		)
		(fp_line
			(start -0.120396 0.3048)
			(end -0.120396 0.2794)
			(stroke
				(width 0.1)
				(type default)
			)
			(layer "B.Fab")
		)
		(fp_line
			(start 0.12065 -0.305054)
			(end 0.12065 -0.2794)
			(stroke
				(width 0.1)
				(type default)
			)
			(layer "B.Fab")
		)
		(fp_line
			(start 0.12065 -0.2794)
			(end -0.12065 -0.2794)
			(stroke
				(width 0.1)
				(type default)
			)
			(layer "B.Fab")
		)
		(fp_line
			(start 0.12065 0.2794)
			(end 0.12065 0.3048)
			(stroke
				(width 0.1)
				(type default)
			)
			(layer "B.Fab")
		)
		(fp_line
			(start 0.12065 0.3048)
			(end 0.67945 0.3048)
			(stroke
				(width 0.1)
				(type default)
			)
			(layer "B.Fab")
		)
		(fp_line
			(start 0.67945 -0.305054)
			(end 0.12065 -0.305054)
			(stroke
				(width 0.1)
				(type default)
			)
			(layer "B.Fab")
		)
		(fp_line
			(start 0.67945 0.3048)
			(end 0.67945 -0.305054)
			(stroke
				(width 0.1)
				(type default)
			)
			(layer "B.Fab")
		)
		(pad "1" smd circle
			(at 0.40005 0 180)
			(size 0 0)
			(layers "B.Cu" "B.Mask" "B.Paste")
			(net "P3V3_AUX_FPGA_VCCIO4")
		)
		(pad "2" smd circle
			(at -0.40005 0 180)
			(size 0 0)
			(layers "B.Cu" "B.Mask" "B.Paste")
			(net "GND")
		)
	)
	(footprint ""
		(layer "B.Cu")
		(at 53.095652 -177.349404 180)
		(property "Reference" "PC433"
			(at 0 0 0)
			(layer "B.SilkS")
			(hide yes)
			(effects
				(font
					(size 1.27 1.27)
				)
				(justify mirror)
			)
		)
		(property "Value" ""
			(at 0 0 0)
			(layer "B.Fab")
			(effects
				(font
					(size 1.27 1.27)
				)
				(justify mirror)
			)
		)
		(duplicate_pad_numbers_are_jumpers no)
		(fp_line
			(start 1.524 0.762)
			(end 1.524 -0.762)
			(stroke
				(width 0.1524)
				(type default)
			)
			(layer "B.SilkS")
		)
		(fp_line
			(start 1.524 -0.762)
			(end -1.524 -0.762)
			(stroke
				(width 0.1524)
				(type default)
			)
			(layer "B.SilkS")
		)
		(fp_line
			(start -1.524 0.762)
			(end 1.524 0.762)
			(stroke
				(width 0.1524)
				(type default)
			)
			(layer "B.SilkS")
		)
		(fp_line
			(start -1.524 -0.762)
			(end -1.524 0.762)
			(stroke
				(width 0.1524)
				(type default)
			)
			(layer "B.SilkS")
		)
		(fp_line
			(start 1.1049 0.724916)
			(end -1.1049 0.724916)
			(stroke
				(width 0.1)
				(type default)
			)
			(layer "B.Fab")
		)
		(fp_line
			(start 1.1049 -0.724916)
			(end 1.1049 0.724916)
			(stroke
				(width 0.1)
				(type default)
			)
			(layer "B.Fab")
		)
		(fp_line
			(start -1.1049 0.724916)
			(end -1.1049 -0.724916)
			(stroke
				(width 0.1)
				(type default)
			)
			(layer "B.Fab")
		)
		(fp_line
			(start -1.1049 -0.724916)
			(end 1.1049 -0.724916)
			(stroke
				(width 0.1)
				(type default)
			)
			(layer "B.Fab")
		)
		(pad "1" smd rect
			(at 0.889 0 180)
			(size 1.016 1.27)
			(layers "B.Cu" "B.Mask" "B.Paste")
			(net "SW_P12V_PVCCINFAON_CPU1_FLT")
		)
		(pad "2" smd rect
			(at -0.889 0 180)
			(size 1.016 1.27)
			(layers "B.Cu" "B.Mask" "B.Paste")
			(net "GND")
		)
	)
	(footprint ""
		(layer "B.Cu")
		(at 113.91773 -415.671254)
		(property "Reference" "C2332"
			(at 0 0 0)
			(layer "B.SilkS")
			(hide yes)
			(effects
				(font
					(size 1.27 1.27)
				)
				(justify mirror)
			)
		)
		(property "Value" ""
			(at 0 0 0)
			(layer "B.Fab")
			(effects
				(font
					(size 1.27 1.27)
				)
				(justify mirror)
			)
		)
		(duplicate_pad_numbers_are_jumpers no)
		(fp_line
			(start -1.2954 -0.5842)
			(end -1.2954 0.5842)
			(stroke
				(width 0.1524)
				(type default)
			)
			(layer "B.SilkS")
		)
		(fp_line
			(start -1.2954 0.5842)
			(end 1.2954 0.5842)
			(stroke
				(width 0.1524)
				(type default)
			)
			(layer "B.SilkS")
		)
		(fp_line
			(start 0 -0.5842)
			(end 0 0.5842)
			(stroke
				(width 0.1524)
				(type default)
			)
			(layer "B.SilkS")
		)
		(fp_line
			(start 1.2954 -0.5842)
			(end -1.2954 -0.5842)
			(stroke
				(width 0.1524)
				(type default)
			)
			(layer "B.SilkS")
		)
		(fp_line
			(start 1.2954 0.5842)
			(end 1.2954 -0.5842)
			(stroke
				(width 0.1524)
				(type default)
			)
			(layer "B.SilkS")
		)
		(fp_line
			(start -1.1938 -0.4064)
			(end -1.1938 0.4064)
			(stroke
				(width 0.1)
				(type default)
			)
			(layer "B.Fab")
		)
		(fp_line
			(start -1.1938 0.4064)
			(end -0.8636 0.4064)
			(stroke
				(width 0.1)
				(type default)
			)
			(layer "B.Fab")
		)
		(fp_line
			(start -0.8636 -0.4572)
			(end -0.8636 -0.4064)
			(stroke
				(width 0.1)
				(type default)
			)
			(layer "B.Fab")
		)
		(fp_line
			(start -0.8636 -0.4064)
			(end -1.1938 -0.4064)
			(stroke
				(width 0.1)
				(type default)
			)
			(layer "B.Fab")
		)
		(fp_line
			(start -0.8636 0.4064)
			(end -0.8636 0.4572)
			(stroke
				(width 0.1)
				(type default)
			)
			(layer "B.Fab")
		)
		(fp_line
			(start -0.8636 0.4572)
			(end 0.8636 0.4572)
			(stroke
				(width 0.1)
				(type default)
			)
			(layer "B.Fab")
		)
		(fp_line
			(start 0.8636 -0.4572)
			(end -0.8636 -0.4572)
			(stroke
				(width 0.1)
				(type default)
			)
			(layer "B.Fab")
		)
		(fp_line
			(start 0.8636 -0.4064)
			(end 0.8636 -0.4572)
			(stroke
				(width 0.1)
				(type default)
			)
			(layer "B.Fab")
		)
		(fp_line
			(start 0.8636 0.4064)
			(end 1.1938 0.4064)
			(stroke
				(width 0.1)
				(type default)
			)
			(layer "B.Fab")
		)
		(fp_line
			(start 0.8636 0.4572)
			(end 0.8636 0.4064)
			(stroke
				(width 0.1)
				(type default)
			)
			(layer "B.Fab")
		)
		(fp_line
			(start 1.1938 -0.4064)
			(end 0.8636 -0.4064)
			(stroke
				(width 0.1)
				(type default)
			)
			(layer "B.Fab")
		)
		(fp_line
			(start 1.1938 0.4064)
			(end 1.1938 -0.4064)
			(stroke
				(width 0.1)
				(type default)
			)
			(layer "B.Fab")
		)
		(pad "1" smd rect
			(at 0.7366 0 270)
			(size 0.7112 0.8128)
			(layers "B.Cu" "B.Mask" "B.Paste")
			(net "P3V3_9ZXL045_VDDR")
		)
		(pad "2" smd rect
			(at -0.7366 0 270)
			(size 0.7112 0.8128)
			(layers "B.Cu" "B.Mask" "B.Paste")
			(net "GND")
		)
	)
	(footprint ""
		(layer "B.Cu")
		(at 456.543918 -314.80506 90)
		(property "Reference" "R2501"
			(at 0 0 90)
			(layer "B.SilkS")
			(hide yes)
			(effects
				(font
					(size 1.27 1.27)
				)
				(justify mirror)
			)
		)
		(property "Value" ""
			(at 0 0 90)
			(layer "B.Fab")
			(effects
				(font
					(size 1.27 1.27)
				)
				(justify mirror)
			)
		)
		(duplicate_pad_numbers_are_jumpers no)
		(fp_line
			(start 0.7874 -0.4064)
			(end -0.7874 -0.4064)
			(stroke
				(width 0.1524)
				(type default)
			)
			(layer "B.SilkS")
		)
		(fp_line
			(start -0.7874 -0.4064)
			(end -0.7874 0.4064)
			(stroke
				(width 0.1524)
				(type default)
			)
			(layer "B.SilkS")
		)
		(fp_line
			(start 0.7874 0.4064)
			(end 0.7874 -0.4064)
			(stroke
				(width 0.1524)
				(type default)
			)
			(layer "B.SilkS")
		)
		(fp_line
			(start -0.7874 0.4064)
			(end 0.7874 0.4064)
			(stroke
				(width 0.1524)
				(type default)
			)
			(layer "B.SilkS")
		)
		(fp_line
			(start 0.67945 -0.305054)
			(end 0.12065 -0.305054)
			(stroke
				(width 0.1)
				(type default)
			)
			(layer "B.Fab")
		)
		(fp_line
			(start 0.12065 -0.305054)
			(end 0.12065 -0.2794)
			(stroke
				(width 0.1)
				(type default)
			)
			(layer "B.Fab")
		)
		(fp_line
			(start -0.12065 -0.3048)
			(end -0.67945 -0.3048)
			(stroke
				(width 0.1)
				(type default)
			)
			(layer "B.Fab")
		)
		(fp_line
			(start -0.67945 -0.3048)
			(end -0.67945 0.3048)
			(stroke
				(width 0.1)
				(type default)
			)
			(layer "B.Fab")
		)
		(fp_line
			(start 0.12065 -0.2794)
			(end -0.12065 -0.2794)
			(stroke
				(width 0.1)
				(type default)
			)
			(layer "B.Fab")
		)
		(fp_line
			(start -0.12065 -0.2794)
			(end -0.12065 -0.3048)
			(stroke
				(width 0.1)
				(type default)
			)
			(layer "B.Fab")
		)
		(fp_line
			(start 0.12065 0.2794)
			(end 0.12065 0.3048)
			(stroke
				(width 0.1)
				(type default)
			)
			(layer "B.Fab")
		)
		(fp_line
			(start -0.120396 0.2794)
			(end 0.12065 0.2794)
			(stroke
				(width 0.1)
				(type default)
			)
			(layer "B.Fab")
		)
		(fp_line
			(start 0.67945 0.3048)
			(end 0.67945 -0.305054)
			(stroke
				(width 0.1)
				(type default)
			)
			(layer "B.Fab")
		)
		(fp_line
			(start 0.12065 0.3048)
			(end 0.67945 0.3048)
			(stroke
				(width 0.1)
				(type default)
			)
			(layer "B.Fab")
		)
		(fp_line
			(start -0.120396 0.3048)
			(end -0.120396 0.2794)
			(stroke
				(width 0.1)
				(type default)
			)
			(layer "B.Fab")
		)
		(fp_line
			(start -0.67945 0.3048)
			(end -0.120396 0.3048)
			(stroke
				(width 0.1)
				(type default)
			)
			(layer "B.Fab")
		)
		(pad "1" smd circle
			(at 0.40005 0 270)
			(size 0 0)
			(layers "B.Cu" "B.Mask" "B.Paste")
			(net "PWRGD_FAIL_CPU0_GH_R1")
		)
		(pad "2" smd circle
			(at -0.40005 0 270)
			(size 0 0)
			(layers "B.Cu" "B.Mask" "B.Paste")
			(net "PWRGD_FAIL_CPU0_GH_R")
		)
	)
	(footprint ""
		(layer "B.Cu")
		(at 339.298534 8.003794 180)
		(property "Reference" "J114"
			(at 4.172204 -1.648206 270)
			(unlocked yes)
			(layer "B.SilkS")
			(effects
				(font
					(size 0.7874 0.5842)
					(thickness 0.1524)
				)
				(justify left mirror)
			)
		)
		(property "Value" ""
			(at 0 0 0)
			(layer "B.Fab")
			(effects
				(font
					(size 1.27 1.27)
				)
				(justify mirror)
			)
		)
		(duplicate_pad_numbers_are_jumpers no)
		(fp_line
			(start 1.2192 2.1082)
			(end 1.2192 -2.1082)
			(stroke
				(width 0.1524)
				(type default)
			)
			(layer "B.SilkS")
		)
		(fp_line
			(start 1.2192 -2.1082)
			(end -1.2192 -2.1082)
			(stroke
				(width 0.1524)
				(type default)
			)
			(layer "B.SilkS")
		)
		(fp_line
			(start -1.2192 2.1082)
			(end 1.2192 2.1082)
			(stroke
				(width 0.1524)
				(type default)
			)
			(layer "B.SilkS")
		)
		(fp_line
			(start -1.2192 -2.1082)
			(end -1.2192 2.1082)
			(stroke
				(width 0.1524)
				(type default)
			)
			(layer "B.SilkS")
		)
		(pad "" np_thru_hole circle
			(at -3.4671 -1.27 90)
			(size 1.0414 1.0414)
			(drill 1.0414)
			(layers "*.Cu" "*.Mask")
			(clearance 0.381)
			(thermal_gap 0.381)
		)
		(pad "" np_thru_hole circle
			(at -3.4671 1.27 90)
			(size 1.0414 1.0414)
			(drill 1.0414)
			(layers "*.Cu" "*.Mask")
			(clearance 0.381)
			(thermal_gap 0.381)
		)
		(pad "" np_thru_hole circle
			(at 2.8829 -1.27 90)
			(size 1.0414 1.0414)
			(drill 1.0414)
			(layers "*.Cu" "*.Mask")
			(clearance 0.381)
			(thermal_gap 0.381)
		)
		(pad "" np_thru_hole circle
			(at 2.8829 1.27 90)
			(size 1.0414 1.0414)
			(drill 1.0414)
			(layers "*.Cu" "*.Mask")
			(clearance 0.381)
			(thermal_gap 0.381)
		)
		(pad "1" smd rect
			(at -0.8255 -0.249936 90)
			(size 0.3048 0.508)
			(layers "B.Cu" "B.Mask" "B.Paste")
			(net "DELTA_L_85_5INCH_IN5_DP")
		)
		(pad "2" smd rect
			(at -0.8255 0.249936 90)
			(size 0.3048 0.508)
			(layers "B.Cu" "B.Mask" "B.Paste")
			(net "DELTA_L_85_5INCH_IN5_DN")
		)
		(pad "3" smd circle
			(at 0 0)
			(size 0 0)
			(layers "B.Cu" "B.Mask" "B.Paste")
			(net "DELTA_L_GND_1")
		)
		(zone
			(layers "F.Cu" "B.Cu" "In1.Cu" "In2.Cu" "In3.Cu" "In4.Cu" "In5.Cu" "In6.Cu"
				"In7.Cu" "In8.Cu" "In9.Cu" "In10.Cu" "In11.Cu" "In12.Cu" "In13.Cu" "In14.Cu"
				"In15.Cu" "In16.Cu"
			)
			(hatch none 0.5)
			(connect_pads
				(clearance 0)
			)
			(min_thickness 0.25)
			(keepout
				(tracks not_allowed)
				(vias allowed)
				(pads allowed)
				(copperpour not_allowed)
				(footprints allowed)
			)
			(placement
				(enabled no)
				(sheetname "")
			)
			(fill
				(thermal_gap 0.5)
				(thermal_bridge_width 0.5)
				(island_removal_mode 0)
			)
			(polygon
				(pts
					(arc
						(start 337.342734 6.733794)
						(mid 335.488534 6.733794)
						(end 337.342734 6.733794)
					)
				)
			)
		)
		(zone
			(layers "F.Cu" "B.Cu" "In1.Cu" "In2.Cu" "In3.Cu" "In4.Cu" "In5.Cu" "In6.Cu"
				"In7.Cu" "In8.Cu" "In9.Cu" "In10.Cu" "In11.Cu" "In12.Cu" "In13.Cu" "In14.Cu"
				"In15.Cu" "In16.Cu"
			)
			(hatch none 0.5)
			(connect_pads
				(clearance 0)
			)
			(min_thickness 0.25)
			(keepout
				(tracks not_allowed)
				(vias allowed)
				(pads allowed)
				(copperpour not_allowed)
				(footprints allowed)
			)
			(placement
				(enabled no)
				(sheetname "")
			)
			(fill
				(thermal_gap 0.5)
				(thermal_bridge_width 0.5)
				(island_removal_mode 0)
			)
			(polygon
				(pts
					(arc
						(start 337.342734 9.273794)
						(mid 335.488534 9.273794)
						(end 337.342734 9.273794)
					)
				)
			)
		)
		(zone
			(layers "F.Cu" "B.Cu" "In1.Cu" "In2.Cu" "In3.Cu" "In4.Cu" "In5.Cu" "In6.Cu"
				"In7.Cu" "In8.Cu" "In9.Cu" "In10.Cu" "In11.Cu" "In12.Cu" "In13.Cu" "In14.Cu"
				"In15.Cu" "In16.Cu"
			)
			(hatch none 0.5)
			(connect_pads
				(clearance 0)
			)
			(min_thickness 0.25)
			(keepout
				(tracks not_allowed)
				(vias allowed)
				(pads allowed)
				(copperpour not_allowed)
				(footprints allowed)
			)
			(placement
				(enabled no)
				(sheetname "")
			)
			(fill
				(thermal_gap 0.5)
				(thermal_bridge_width 0.5)
				(island_removal_mode 0)
			)
			(polygon
				(pts
					(arc
						(start 343.692734 6.733794)
						(mid 341.838534 6.733794)
						(end 343.692734 6.733794)
					)
				)
			)
		)
		(zone
			(layers "F.Cu" "B.Cu" "In1.Cu" "In2.Cu" "In3.Cu" "In4.Cu" "In5.Cu" "In6.Cu"
				"In7.Cu" "In8.Cu" "In9.Cu" "In10.Cu" "In11.Cu" "In12.Cu" "In13.Cu" "In14.Cu"
				"In15.Cu" "In16.Cu"
			)
			(hatch none 0.5)
			(connect_pads
				(clearance 0)
			)
			(min_thickness 0.25)
			(keepout
				(tracks not_allowed)
				(vias allowed)
				(pads allowed)
				(copperpour not_allowed)
				(footprints allowed)
			)
			(placement
				(enabled no)
				(sheetname "")
			)
			(fill
				(thermal_gap 0.5)
				(thermal_bridge_width 0.5)
				(island_removal_mode 0)
			)
			(polygon
				(pts
					(arc
						(start 343.692734 9.273794)
						(mid 341.838534 9.273794)
						(end 343.692734 9.273794)
					)
				)
			)
		)
		(zone
			(layer "B.Cu")
			(hatch none 0.5)
			(connect_pads
				(clearance 0)
			)
			(min_thickness 0.25)
			(keepout
				(tracks not_allowed)
				(vias allowed)
				(pads allowed)
				(copperpour not_allowed)
				(footprints allowed)
			)
			(placement
				(enabled no)
				(sheetname "")
			)
			(fill
				(thermal_gap 0.5)
				(thermal_bridge_width 0.5)
				(island_removal_mode 0)
			)
			(polygon
				(pts
					(xy 340.416134 8.552434) (xy 340.416134 8.45693) (xy 339.819234 8.45693) (xy 339.819234 8.05053)
					(xy 340.416134 8.05053) (xy 340.416134 7.957058) (xy 339.819234 7.957058) (xy 339.819234 7.550658)
					(xy 340.416134 7.550658) (xy 340.416134 7.455154) (xy 339.717634 7.455154) (xy 339.717634 8.552434)
				)
			)
		)
	)
	(footprint ""
		(layer "B.Cu")
		(at 30.155896 -127.416052 180)
		(property "Reference" "PR276"
			(at 0 0 0)
			(layer "B.SilkS")
			(hide yes)
			(effects
				(font
					(size 1.27 1.27)
				)
				(justify mirror)
			)
		)
		(property "Value" ""
			(at 0 0 0)
			(layer "B.Fab")
			(effects
				(font
					(size 1.27 1.27)
				)
				(justify mirror)
			)
		)
		(duplicate_pad_numbers_are_jumpers no)
		(fp_line
			(start 0.7874 0.4064)
			(end 0.7874 -0.4064)
			(stroke
				(width 0.1524)
				(type default)
			)
			(layer "B.SilkS")
		)
		(fp_line
			(start 0.7874 -0.4064)
			(end -0.7874 -0.4064)
			(stroke
				(width 0.1524)
				(type default)
			)
			(layer "B.SilkS")
		)
		(fp_line
			(start -0.7874 0.4064)
			(end 0.7874 0.4064)
			(stroke
				(width 0.1524)
				(type default)
			)
			(layer "B.SilkS")
		)
		(fp_line
			(start -0.7874 -0.4064)
			(end -0.7874 0.4064)
			(stroke
				(width 0.1524)
				(type default)
			)
			(layer "B.SilkS")
		)
		(fp_line
			(start 0.67945 0.3048)
			(end 0.67945 -0.305054)
			(stroke
				(width 0.1)
				(type default)
			)
			(layer "B.Fab")
		)
		(fp_line
			(start 0.67945 -0.305054)
			(end 0.12065 -0.305054)
			(stroke
				(width 0.1)
				(type default)
			)
			(layer "B.Fab")
		)
		(fp_line
			(start 0.12065 0.3048)
			(end 0.67945 0.3048)
			(stroke
				(width 0.1)
				(type default)
			)
			(layer "B.Fab")
		)
		(fp_line
			(start 0.12065 0.2794)
			(end 0.12065 0.3048)
			(stroke
				(width 0.1)
				(type default)
			)
			(layer "B.Fab")
		)
		(fp_line
			(start 0.12065 -0.2794)
			(end -0.12065 -0.2794)
			(stroke
				(width 0.1)
				(type default)
			)
			(layer "B.Fab")
		)
		(fp_line
			(start 0.12065 -0.305054)
			(end 0.12065 -0.2794)
			(stroke
				(width 0.1)
				(type default)
			)
			(layer "B.Fab")
		)
		(fp_line
			(start -0.120396 0.3048)
			(end -0.120396 0.2794)
			(stroke
				(width 0.1)
				(type default)
			)
			(layer "B.Fab")
		)
		(fp_line
			(start -0.120396 0.2794)
			(end 0.12065 0.2794)
			(stroke
				(width 0.1)
				(type default)
			)
			(layer "B.Fab")
		)
		(fp_line
			(start -0.12065 -0.2794)
			(end -0.12065 -0.3048)
			(stroke
				(width 0.1)
				(type default)
			)
			(layer "B.Fab")
		)
		(fp_line
			(start -0.12065 -0.3048)
			(end -0.67945 -0.3048)
			(stroke
				(width 0.1)
				(type default)
			)
			(layer "B.Fab")
		)
		(fp_line
			(start -0.67945 0.3048)
			(end -0.120396 0.3048)
			(stroke
				(width 0.1)
				(type default)
			)
			(layer "B.Fab")
		)
		(fp_line
			(start -0.67945 -0.3048)
			(end -0.67945 0.3048)
			(stroke
				(width 0.1)
				(type default)
			)
			(layer "B.Fab")
		)
		(pad "1" smd circle
			(at 0.40005 0)
			(size 0 0)
			(layers "B.Cu" "B.Mask" "B.Paste")
			(net "PVCCINFAON_CPU1_VIN_CSNIN")
		)
		(pad "2" smd circle
			(at -0.40005 0)
			(size 0 0)
			(layers "B.Cu" "B.Mask" "B.Paste")
			(net "GND")
		)
	)
	(footprint ""
		(layer "B.Cu")
		(at 105.679494 -248.49836 -90)
		(property "Reference" "C336"
			(at 0 0 90)
			(layer "B.SilkS")
			(hide yes)
			(effects
				(font
					(size 1.27 1.27)
				)
				(justify mirror)
			)
		)
		(property "Value" ""
			(at 0 0 90)
			(layer "B.Fab")
			(effects
				(font
					(size 1.27 1.27)
				)
				(justify mirror)
			)
		)
		(duplicate_pad_numbers_are_jumpers no)
		(fp_line
			(start -1.524 0.762)
			(end 1.524 0.762)
			(stroke
				(width 0.1524)
				(type default)
			)
			(layer "B.SilkS")
		)
		(fp_line
			(start 1.524 0.762)
			(end 1.524 -0.762)
			(stroke
				(width 0.1524)
				(type default)
			)
			(layer "B.SilkS")
		)
		(fp_line
			(start -1.524 -0.762)
			(end -1.524 0.762)
			(stroke
				(width 0.1524)
				(type default)
			)
			(layer "B.SilkS")
		)
		(fp_line
			(start 1.524 -0.762)
			(end -1.524 -0.762)
			(stroke
				(width 0.1524)
				(type default)
			)
			(layer "B.SilkS")
		)
		(fp_line
			(start -1.1049 0.724916)
			(end -1.1049 -0.724916)
			(stroke
				(width 0.1)
				(type default)
			)
			(layer "B.Fab")
		)
		(fp_line
			(start 1.1049 0.724916)
			(end -1.1049 0.724916)
			(stroke
				(width 0.1)
				(type default)
			)
			(layer "B.Fab")
		)
		(fp_line
			(start -1.1049 -0.724916)
			(end 1.1049 -0.724916)
			(stroke
				(width 0.1)
				(type default)
			)
			(layer "B.Fab")
		)
		(fp_line
			(start 1.1049 -0.724916)
			(end 1.1049 0.724916)
			(stroke
				(width 0.1)
				(type default)
			)
			(layer "B.Fab")
		)
		(pad "1" smd rect
			(at 0.889 0 270)
			(size 1.016 1.27)
			(layers "B.Cu" "B.Mask" "B.Paste")
			(net "PVCCIN_CPU1")
		)
		(pad "2" smd rect
			(at -0.889 0 270)
			(size 1.016 1.27)
			(layers "B.Cu" "B.Mask" "B.Paste")
			(net "GND")
		)
	)
	(footprint ""
		(layer "B.Cu")
		(at 161.29 -15.712948 -90)
		(property "Reference" "R1385"
			(at 0 0 90)
			(layer "B.SilkS")
			(hide yes)
			(effects
				(font
					(size 1.27 1.27)
				)
				(justify mirror)
			)
		)
		(property "Value" ""
			(at 0 0 90)
			(layer "B.Fab")
			(effects
				(font
					(size 1.27 1.27)
				)
				(justify mirror)
			)
		)
		(duplicate_pad_numbers_are_jumpers no)
		(fp_line
			(start -0.7874 0.4064)
			(end 0.7874 0.4064)
			(stroke
				(width 0.1524)
				(type default)
			)
			(layer "B.SilkS")
		)
		(fp_line
			(start 0.7874 0.4064)
			(end 0.7874 -0.4064)
			(stroke
				(width 0.1524)
				(type default)
			)
			(layer "B.SilkS")
		)
		(fp_line
			(start -0.7874 -0.4064)
			(end -0.7874 0.4064)
			(stroke
				(width 0.1524)
				(type default)
			)
			(layer "B.SilkS")
		)
		(fp_line
			(start 0.7874 -0.4064)
			(end -0.7874 -0.4064)
			(stroke
				(width 0.1524)
				(type default)
			)
			(layer "B.SilkS")
		)
		(fp_line
			(start -0.67945 0.3048)
			(end -0.120396 0.3048)
			(stroke
				(width 0.1)
				(type default)
			)
			(layer "B.Fab")
		)
		(fp_line
			(start -0.120396 0.3048)
			(end -0.120396 0.2794)
			(stroke
				(width 0.1)
				(type default)
			)
			(layer "B.Fab")
		)
		(fp_line
			(start 0.12065 0.3048)
			(end 0.67945 0.3048)
			(stroke
				(width 0.1)
				(type default)
			)
			(layer "B.Fab")
		)
		(fp_line
			(start 0.67945 0.3048)
			(end 0.67945 -0.305054)
			(stroke
				(width 0.1)
				(type default)
			)
			(layer "B.Fab")
		)
		(fp_line
			(start -0.120396 0.2794)
			(end 0.12065 0.2794)
			(stroke
				(width 0.1)
				(type default)
			)
			(layer "B.Fab")
		)
		(fp_line
			(start 0.12065 0.2794)
			(end 0.12065 0.3048)
			(stroke
				(width 0.1)
				(type default)
			)
			(layer "B.Fab")
		)
		(fp_line
			(start -0.12065 -0.2794)
			(end -0.12065 -0.3048)
			(stroke
				(width 0.1)
				(type default)
			)
			(layer "B.Fab")
		)
		(fp_line
			(start 0.12065 -0.2794)
			(end -0.12065 -0.2794)
			(stroke
				(width 0.1)
				(type default)
			)
			(layer "B.Fab")
		)
		(fp_line
			(start -0.67945 -0.3048)
			(end -0.67945 0.3048)
			(stroke
				(width 0.1)
				(type default)
			)
			(layer "B.Fab")
		)
		(fp_line
			(start -0.12065 -0.3048)
			(end -0.67945 -0.3048)
			(stroke
				(width 0.1)
				(type default)
			)
			(layer "B.Fab")
		)
		(fp_line
			(start 0.12065 -0.305054)
			(end 0.12065 -0.2794)
			(stroke
				(width 0.1)
				(type default)
			)
			(layer "B.Fab")
		)
		(fp_line
			(start 0.67945 -0.305054)
			(end 0.12065 -0.305054)
			(stroke
				(width 0.1)
				(type default)
			)
			(layer "B.Fab")
		)
		(pad "1" smd circle
			(at 0.40005 0 90)
			(size 0 0)
			(layers "B.Cu" "B.Mask" "B.Paste")
			(net "SMB_SML0_3V3AUX_SDA")
		)
		(pad "2" smd circle
			(at -0.40005 0 90)
			(size 0 0)
			(layers "B.Cu" "B.Mask" "B.Paste")
			(net "P3V3_AUX")
		)
	)
	(footprint ""
		(layer "B.Cu")
		(at 353.619308 -244.820186 -90)
		(property "Reference" "C391"
			(at 0 0 90)
			(layer "B.SilkS")
			(hide yes)
			(effects
				(font
					(size 1.27 1.27)
				)
				(justify mirror)
			)
		)
		(property "Value" ""
			(at 0 0 90)
			(layer "B.Fab")
			(effects
				(font
					(size 1.27 1.27)
				)
				(justify mirror)
			)
		)
		(duplicate_pad_numbers_are_jumpers no)
		(fp_line
			(start -1.524 0.762)
			(end 1.524 0.762)
			(stroke
				(width 0.1524)
				(type default)
			)
			(layer "B.SilkS")
		)
		(fp_line
			(start 1.524 0.762)
			(end 1.524 -0.762)
			(stroke
				(width 0.1524)
				(type default)
			)
			(layer "B.SilkS")
		)
		(fp_line
			(start -1.524 -0.762)
			(end -1.524 0.762)
			(stroke
				(width 0.1524)
				(type default)
			)
			(layer "B.SilkS")
		)
		(fp_line
			(start 1.524 -0.762)
			(end -1.524 -0.762)
			(stroke
				(width 0.1524)
				(type default)
			)
			(layer "B.SilkS")
		)
		(fp_line
			(start -1.1049 0.724916)
			(end -1.1049 -0.724916)
			(stroke
				(width 0.1)
				(type default)
			)
			(layer "B.Fab")
		)
		(fp_line
			(start 1.1049 0.724916)
			(end -1.1049 0.724916)
			(stroke
				(width 0.1)
				(type default)
			)
			(layer "B.Fab")
		)
		(fp_line
			(start -1.1049 -0.724916)
			(end 1.1049 -0.724916)
			(stroke
				(width 0.1)
				(type default)
			)
			(layer "B.Fab")
		)
		(fp_line
			(start 1.1049 -0.724916)
			(end 1.1049 0.724916)
			(stroke
				(width 0.1)
				(type default)
			)
			(layer "B.Fab")
		)
		(pad "1" smd rect
			(at 0.889 0 270)
			(size 1.016 1.27)
			(layers "B.Cu" "B.Mask" "B.Paste")
			(net "PVCCIN_CPU0")
		)
		(pad "2" smd rect
			(at -0.889 0 270)
			(size 1.016 1.27)
			(layers "B.Cu" "B.Mask" "B.Paste")
			(net "GND")
		)
	)
	(footprint ""
		(layer "B.Cu")
		(at 362.31449 -360.418126 -90)
		(property "Reference" "PR157"
			(at 0 0 90)
			(layer "B.SilkS")
			(hide yes)
			(effects
				(font
					(size 1.27 1.27)
				)
				(justify mirror)
			)
		)
		(property "Value" ""
			(at 0 0 90)
			(layer "B.Fab")
			(effects
				(font
					(size 1.27 1.27)
				)
				(justify mirror)
			)
		)
		(duplicate_pad_numbers_are_jumpers no)
		(fp_line
			(start -0.7874 0.4064)
			(end 0.7874 0.4064)
			(stroke
				(width 0.1524)
				(type default)
			)
			(layer "B.SilkS")
		)
		(fp_line
			(start 0.7874 0.4064)
			(end 0.7874 -0.4064)
			(stroke
				(width 0.1524)
				(type default)
			)
			(layer "B.SilkS")
		)
		(fp_line
			(start -0.7874 -0.4064)
			(end -0.7874 0.4064)
			(stroke
				(width 0.1524)
				(type default)
			)
			(layer "B.SilkS")
		)
		(fp_line
			(start 0.7874 -0.4064)
			(end -0.7874 -0.4064)
			(stroke
				(width 0.1524)
				(type default)
			)
			(layer "B.SilkS")
		)
		(fp_line
			(start -0.67945 0.3048)
			(end -0.120396 0.3048)
			(stroke
				(width 0.1)
				(type default)
			)
			(layer "B.Fab")
		)
		(fp_line
			(start -0.120396 0.3048)
			(end -0.120396 0.2794)
			(stroke
				(width 0.1)
				(type default)
			)
			(layer "B.Fab")
		)
		(fp_line
			(start 0.12065 0.3048)
			(end 0.67945 0.3048)
			(stroke
				(width 0.1)
				(type default)
			)
			(layer "B.Fab")
		)
		(fp_line
			(start 0.67945 0.3048)
			(end 0.67945 -0.305054)
			(stroke
				(width 0.1)
				(type default)
			)
			(layer "B.Fab")
		)
		(fp_line
			(start -0.120396 0.2794)
			(end 0.12065 0.2794)
			(stroke
				(width 0.1)
				(type default)
			)
			(layer "B.Fab")
		)
		(fp_line
			(start 0.12065 0.2794)
			(end 0.12065 0.3048)
			(stroke
				(width 0.1)
				(type default)
			)
			(layer "B.Fab")
		)
		(fp_line
			(start -0.12065 -0.2794)
			(end -0.12065 -0.3048)
			(stroke
				(width 0.1)
				(type default)
			)
			(layer "B.Fab")
		)
		(fp_line
			(start 0.12065 -0.2794)
			(end -0.12065 -0.2794)
			(stroke
				(width 0.1)
				(type default)
			)
			(layer "B.Fab")
		)
		(fp_line
			(start -0.67945 -0.3048)
			(end -0.67945 0.3048)
			(stroke
				(width 0.1)
				(type default)
			)
			(layer "B.Fab")
		)
		(fp_line
			(start -0.12065 -0.3048)
			(end -0.67945 -0.3048)
			(stroke
				(width 0.1)
				(type default)
			)
			(layer "B.Fab")
		)
		(fp_line
			(start 0.12065 -0.305054)
			(end 0.12065 -0.2794)
			(stroke
				(width 0.1)
				(type default)
			)
			(layer "B.Fab")
		)
		(fp_line
			(start 0.67945 -0.305054)
			(end 0.12065 -0.305054)
			(stroke
				(width 0.1)
				(type default)
			)
			(layer "B.Fab")
		)
		(pad "1" smd circle
			(at 0.40005 0 90)
			(size 0 0)
			(layers "B.Cu" "B.Mask" "B.Paste")
			(net "P12V_AUX")
		)
		(pad "2" smd circle
			(at -0.40005 0 90)
			(size 0 0)
			(layers "B.Cu" "B.Mask" "B.Paste")
			(net "PVCCIN_CPU0_CSPIN")
		)
	)
	(footprint ""
		(layer "B.Cu")
		(at 183.885078 -18.710148 90)
		(property "Reference" "R3238"
			(at 0 0 90)
			(layer "B.SilkS")
			(hide yes)
			(effects
				(font
					(size 1.27 1.27)
				)
				(justify mirror)
			)
		)
		(property "Value" ""
			(at 0 0 90)
			(layer "B.Fab")
			(effects
				(font
					(size 1.27 1.27)
				)
				(justify mirror)
			)
		)
		(duplicate_pad_numbers_are_jumpers no)
		(fp_line
			(start 0.7874 -0.4064)
			(end -0.7874 -0.4064)
			(stroke
				(width 0.1524)
				(type default)
			)
			(layer "B.SilkS")
		)
		(fp_line
			(start -0.7874 -0.4064)
			(end -0.7874 0.4064)
			(stroke
				(width 0.1524)
				(type default)
			)
			(layer "B.SilkS")
		)
		(fp_line
			(start 0.7874 0.4064)
			(end 0.7874 -0.4064)
			(stroke
				(width 0.1524)
				(type default)
			)
			(layer "B.SilkS")
		)
		(fp_line
			(start -0.7874 0.4064)
			(end 0.7874 0.4064)
			(stroke
				(width 0.1524)
				(type default)
			)
			(layer "B.SilkS")
		)
		(fp_line
			(start 0.67945 -0.305054)
			(end 0.12065 -0.305054)
			(stroke
				(width 0.1)
				(type default)
			)
			(layer "B.Fab")
		)
		(fp_line
			(start 0.12065 -0.305054)
			(end 0.12065 -0.2794)
			(stroke
				(width 0.1)
				(type default)
			)
			(layer "B.Fab")
		)
		(fp_line
			(start -0.12065 -0.3048)
			(end -0.67945 -0.3048)
			(stroke
				(width 0.1)
				(type default)
			)
			(layer "B.Fab")
		)
		(fp_line
			(start -0.67945 -0.3048)
			(end -0.67945 0.3048)
			(stroke
				(width 0.1)
				(type default)
			)
			(layer "B.Fab")
		)
		(fp_line
			(start 0.12065 -0.2794)
			(end -0.12065 -0.2794)
			(stroke
				(width 0.1)
				(type default)
			)
			(layer "B.Fab")
		)
		(fp_line
			(start -0.12065 -0.2794)
			(end -0.12065 -0.3048)
			(stroke
				(width 0.1)
				(type default)
			)
			(layer "B.Fab")
		)
		(fp_line
			(start 0.12065 0.2794)
			(end 0.12065 0.3048)
			(stroke
				(width 0.1)
				(type default)
			)
			(layer "B.Fab")
		)
		(fp_line
			(start -0.120396 0.2794)
			(end 0.12065 0.2794)
			(stroke
				(width 0.1)
				(type default)
			)
			(layer "B.Fab")
		)
		(fp_line
			(start 0.67945 0.3048)
			(end 0.67945 -0.305054)
			(stroke
				(width 0.1)
				(type default)
			)
			(layer "B.Fab")
		)
		(fp_line
			(start 0.12065 0.3048)
			(end 0.67945 0.3048)
			(stroke
				(width 0.1)
				(type default)
			)
			(layer "B.Fab")
		)
		(fp_line
			(start -0.120396 0.3048)
			(end -0.120396 0.2794)
			(stroke
				(width 0.1)
				(type default)
			)
			(layer "B.Fab")
		)
		(fp_line
			(start -0.67945 0.3048)
			(end -0.120396 0.3048)
			(stroke
				(width 0.1)
				(type default)
			)
			(layer "B.Fab")
		)
		(pad "1" smd circle
			(at 0.40005 0 270)
			(size 0 0)
			(layers "B.Cu" "B.Mask" "B.Paste")
			(net "SMB_OCP_SFF_3V3AUX_SCL")
		)
		(pad "2" smd circle
			(at -0.40005 0 270)
			(size 0 0)
			(layers "B.Cu" "B.Mask" "B.Paste")
			(net "SMB_OCP_SFF_3V3AUX_SCL_R0")
		)
	)
	(footprint ""
		(layer "B.Cu")
		(at 174.155608 -121.375424 -90)
		(property "Reference" "C1896"
			(at 0 0 90)
			(layer "B.SilkS")
			(hide yes)
			(effects
				(font
					(size 1.27 1.27)
				)
				(justify mirror)
			)
		)
		(property "Value" ""
			(at 0 0 90)
			(layer "B.Fab")
			(effects
				(font
					(size 1.27 1.27)
				)
				(justify mirror)
			)
		)
		(duplicate_pad_numbers_are_jumpers no)
		(fp_line
			(start -0.69215 0.2921)
			(end 0.69215 0.2921)
			(stroke
				(width 0.1524)
				(type default)
			)
			(layer "B.SilkS")
		)
		(fp_line
			(start 0.69215 0.2921)
			(end 0.69215 -0.2921)
			(stroke
				(width 0.1524)
				(type default)
			)
			(layer "B.SilkS")
		)
		(fp_line
			(start -0.69215 -0.2921)
			(end -0.69215 0.2921)
			(stroke
				(width 0.1524)
				(type default)
			)
			(layer "B.SilkS")
		)
		(fp_line
			(start 0.69215 -0.2921)
			(end -0.69215 -0.2921)
			(stroke
				(width 0.1524)
				(type default)
			)
			(layer "B.SilkS")
		)
		(fp_line
			(start -0.51435 0.2794)
			(end 0.51435 0.2794)
			(stroke
				(width 0.1)
				(type default)
			)
			(layer "B.Fab")
		)
		(fp_line
			(start 0.51435 0.2794)
			(end 0.51435 -0.2794)
			(stroke
				(width 0.1)
				(type default)
			)
			(layer "B.Fab")
		)
		(fp_line
			(start -0.51435 -0.2794)
			(end -0.51435 0.2794)
			(stroke
				(width 0.1)
				(type default)
			)
			(layer "B.Fab")
		)
		(fp_line
			(start 0.51435 -0.2794)
			(end -0.51435 -0.2794)
			(stroke
				(width 0.1)
				(type default)
			)
			(layer "B.Fab")
		)
		(pad "1" smd circle
			(at 0.40005 0 90)
			(size 0 0)
			(layers "B.Cu" "B.Mask" "B.Paste")
			(net "P3V3_AUX_FPGA_VCCIO1")
		)
		(pad "2" smd circle
			(at -0.40005 0 90)
			(size 0 0)
			(layers "B.Cu" "B.Mask" "B.Paste")
			(net "GND")
		)
		(zone
			(layer "B.Cu")
			(hatch none 0.5)
			(connect_pads
				(clearance 0)
			)
			(min_thickness 0.25)
			(keepout
				(tracks not_allowed)
				(vias allowed)
				(pads allowed)
				(copperpour not_allowed)
				(footprints allowed)
			)
			(placement
				(enabled no)
				(sheetname "")
			)
			(fill
				(thermal_gap 0.5)
				(thermal_bridge_width 0.5)
				(island_removal_mode 0)
			)
			(polygon
				(pts
					(xy 174.067978 -121.184924) (xy 174.009812 -121.276364) (xy 174.009812 -121.475754) (xy 174.067978 -121.565924)
					(xy 174.243238 -121.565924) (xy 174.301658 -121.475754) (xy 174.301658 -121.276364) (xy 174.243492 -121.184924)
				)
			)
		)
	)
	(footprint ""
		(layer "B.Cu")
		(at 36.956492 -132.783834 180)
		(property "Reference" "C2453"
			(at 0 0 0)
			(layer "B.SilkS")
			(hide yes)
			(effects
				(font
					(size 1.27 1.27)
				)
				(justify mirror)
			)
		)
		(property "Value" ""
			(at 0 0 0)
			(layer "B.Fab")
			(effects
				(font
					(size 1.27 1.27)
				)
				(justify mirror)
			)
		)
		(duplicate_pad_numbers_are_jumpers no)
		(fp_line
			(start 0.7874 0.4064)
			(end 0.7874 -0.4064)
			(stroke
				(width 0.1524)
				(type default)
			)
			(layer "B.SilkS")
		)
		(fp_line
			(start 0.7874 -0.4064)
			(end -0.7874 -0.4064)
			(stroke
				(width 0.1524)
				(type default)
			)
			(layer "B.SilkS")
		)
		(fp_line
			(start -0.7874 0.4064)
			(end 0.7874 0.4064)
			(stroke
				(width 0.1524)
				(type default)
			)
			(layer "B.SilkS")
		)
		(fp_line
			(start -0.7874 -0.4064)
			(end -0.7874 0.4064)
			(stroke
				(width 0.1524)
				(type default)
			)
			(layer "B.SilkS")
		)
		(fp_line
			(start 0.67945 0.3048)
			(end 0.67945 -0.305054)
			(stroke
				(width 0.1)
				(type default)
			)
			(layer "B.Fab")
		)
		(fp_line
			(start 0.67945 -0.305054)
			(end 0.12065 -0.305054)
			(stroke
				(width 0.1)
				(type default)
			)
			(layer "B.Fab")
		)
		(fp_line
			(start 0.12065 0.3048)
			(end 0.67945 0.3048)
			(stroke
				(width 0.1)
				(type default)
			)
			(layer "B.Fab")
		)
		(fp_line
			(start 0.12065 0.2794)
			(end 0.12065 0.3048)
			(stroke
				(width 0.1)
				(type default)
			)
			(layer "B.Fab")
		)
		(fp_line
			(start 0.12065 -0.2794)
			(end -0.12065 -0.2794)
			(stroke
				(width 0.1)
				(type default)
			)
			(layer "B.Fab")
		)
		(fp_line
			(start 0.12065 -0.305054)
			(end 0.12065 -0.2794)
			(stroke
				(width 0.1)
				(type default)
			)
			(layer "B.Fab")
		)
		(fp_line
			(start -0.120396 0.3048)
			(end -0.120396 0.2794)
			(stroke
				(width 0.1)
				(type default)
			)
			(layer "B.Fab")
		)
		(fp_line
			(start -0.120396 0.2794)
			(end 0.12065 0.2794)
			(stroke
				(width 0.1)
				(type default)
			)
			(layer "B.Fab")
		)
		(fp_line
			(start -0.12065 -0.2794)
			(end -0.12065 -0.3048)
			(stroke
				(width 0.1)
				(type default)
			)
			(layer "B.Fab")
		)
		(fp_line
			(start -0.12065 -0.3048)
			(end -0.67945 -0.3048)
			(stroke
				(width 0.1)
				(type default)
			)
			(layer "B.Fab")
		)
		(fp_line
			(start -0.67945 0.3048)
			(end -0.120396 0.3048)
			(stroke
				(width 0.1)
				(type default)
			)
			(layer "B.Fab")
		)
		(fp_line
			(start -0.67945 -0.3048)
			(end -0.67945 0.3048)
			(stroke
				(width 0.1)
				(type default)
			)
			(layer "B.Fab")
		)
		(pad "1" smd circle
			(at 0.40005 0)
			(size 0 0)
			(layers "B.Cu" "B.Mask" "B.Paste")
			(net "PWRGD_PVCCFA_EHV_CPU1_R")
		)
		(pad "2" smd circle
			(at -0.40005 0)
			(size 0 0)
			(layers "B.Cu" "B.Mask" "B.Paste")
			(net "GND")
		)
	)
	(footprint ""
		(layer "B.Cu")
		(at 208.127854 -318.641476 90)
		(property "Reference" "R908"
			(at 0 0 90)
			(layer "B.SilkS")
			(hide yes)
			(effects
				(font
					(size 1.27 1.27)
				)
				(justify mirror)
			)
		)
		(property "Value" ""
			(at 0 0 90)
			(layer "B.Fab")
			(effects
				(font
					(size 1.27 1.27)
				)
				(justify mirror)
			)
		)
		(duplicate_pad_numbers_are_jumpers no)
		(fp_line
			(start 0.7874 -0.4064)
			(end -0.7874 -0.4064)
			(stroke
				(width 0.1524)
				(type default)
			)
			(layer "B.SilkS")
		)
		(fp_line
			(start -0.7874 -0.4064)
			(end -0.7874 0.4064)
			(stroke
				(width 0.1524)
				(type default)
			)
			(layer "B.SilkS")
		)
		(fp_line
			(start 0.7874 0.4064)
			(end 0.7874 -0.4064)
			(stroke
				(width 0.1524)
				(type default)
			)
			(layer "B.SilkS")
		)
		(fp_line
			(start -0.7874 0.4064)
			(end 0.7874 0.4064)
			(stroke
				(width 0.1524)
				(type default)
			)
			(layer "B.SilkS")
		)
		(fp_line
			(start 0.67945 -0.305054)
			(end 0.12065 -0.305054)
			(stroke
				(width 0.1)
				(type default)
			)
			(layer "B.Fab")
		)
		(fp_line
			(start 0.12065 -0.305054)
			(end 0.12065 -0.2794)
			(stroke
				(width 0.1)
				(type default)
			)
			(layer "B.Fab")
		)
		(fp_line
			(start -0.12065 -0.3048)
			(end -0.67945 -0.3048)
			(stroke
				(width 0.1)
				(type default)
			)
			(layer "B.Fab")
		)
		(fp_line
			(start -0.67945 -0.3048)
			(end -0.67945 0.3048)
			(stroke
				(width 0.1)
				(type default)
			)
			(layer "B.Fab")
		)
		(fp_line
			(start 0.12065 -0.2794)
			(end -0.12065 -0.2794)
			(stroke
				(width 0.1)
				(type default)
			)
			(layer "B.Fab")
		)
		(fp_line
			(start -0.12065 -0.2794)
			(end -0.12065 -0.3048)
			(stroke
				(width 0.1)
				(type default)
			)
			(layer "B.Fab")
		)
		(fp_line
			(start 0.12065 0.2794)
			(end 0.12065 0.3048)
			(stroke
				(width 0.1)
				(type default)
			)
			(layer "B.Fab")
		)
		(fp_line
			(start -0.120396 0.2794)
			(end 0.12065 0.2794)
			(stroke
				(width 0.1)
				(type default)
			)
			(layer "B.Fab")
		)
		(fp_line
			(start 0.67945 0.3048)
			(end 0.67945 -0.305054)
			(stroke
				(width 0.1)
				(type default)
			)
			(layer "B.Fab")
		)
		(fp_line
			(start 0.12065 0.3048)
			(end 0.67945 0.3048)
			(stroke
				(width 0.1)
				(type default)
			)
			(layer "B.Fab")
		)
		(fp_line
			(start -0.120396 0.3048)
			(end -0.120396 0.2794)
			(stroke
				(width 0.1)
				(type default)
			)
			(layer "B.Fab")
		)
		(fp_line
			(start -0.67945 0.3048)
			(end -0.120396 0.3048)
			(stroke
				(width 0.1)
				(type default)
			)
			(layer "B.Fab")
		)
		(pad "1" smd circle
			(at 0.40005 0 270)
			(size 0 0)
			(layers "B.Cu" "B.Mask" "B.Paste")
			(net "PWRGD_CHH_CPU1_DIMM2")
		)
		(pad "2" smd circle
			(at -0.40005 0 270)
			(size 0 0)
			(layers "B.Cu" "B.Mask" "B.Paste")
			(net "PWRGD_FAIL_CPU1_GH")
		)
	)
	(footprint ""
		(layer "B.Cu")
		(at 209.295746 -77.263752)
		(property "Reference" "U222"
			(at 2.032 -3.27533 0)
			(unlocked yes)
			(layer "B.SilkS")
			(effects
				(font
					(size 0.7874 0.5842)
					(thickness 0.1524)
				)
				(justify left mirror)
			)
		)
		(property "Value" ""
			(at 0 0 0)
			(layer "B.Fab")
			(effects
				(font
					(size 1.27 1.27)
				)
				(justify mirror)
			)
		)
		(duplicate_pad_numbers_are_jumpers no)
		(fp_line
			(start -2.0066 -2.5527)
			(end -2.0066 2.5527)
			(stroke
				(width 0.1524)
				(type default)
			)
			(layer "B.SilkS")
		)
		(fp_line
			(start -2.0066 2.5527)
			(end 2.0066 2.5527)
			(stroke
				(width 0.1524)
				(type default)
			)
			(layer "B.SilkS")
		)
		(fp_line
			(start -0.5715 -2.5527)
			(end -2.0066 -2.5527)
			(stroke
				(width 0.1524)
				(type default)
			)
			(layer "B.SilkS")
		)
		(fp_line
			(start 0 -1.9812)
			(end -0.5715 -2.5527)
			(stroke
				(width 0.1524)
				(type default)
			)
			(layer "B.SilkS")
		)
		(fp_line
			(start 0.5715 -2.5527)
			(end 0 -1.9812)
			(stroke
				(width 0.1524)
				(type default)
			)
			(layer "B.SilkS")
		)
		(fp_line
			(start 2.0066 -2.5527)
			(end 0.5715 -2.5527)
			(stroke
				(width 0.1524)
				(type default)
			)
			(layer "B.SilkS")
		)
		(fp_line
			(start 2.0066 2.5527)
			(end 2.0066 -2.5527)
			(stroke
				(width 0.1524)
				(type default)
			)
			(layer "B.SilkS")
		)
		(fp_poly
			(pts
				(xy 4.36372 -1.608328) (xy 3.81 -1.905) (xy 4.36372 -2.233168)
			)
			(stroke
				(width 0)
				(type default)
			)
			(fill yes)
			(layer "B.SilkS")
		)
		(fp_line
			(start -2.249932 -2.549906)
			(end -2.249932 2.549906)
			(stroke
				(width 0.1)
				(type default)
			)
			(layer "B.Fab")
		)
		(fp_line
			(start -2.249932 2.549906)
			(end 2.249932 2.549906)
			(stroke
				(width 0.1)
				(type default)
			)
			(layer "B.Fab")
		)
		(fp_line
			(start 2.249932 -2.549906)
			(end -2.249932 -2.549906)
			(stroke
				(width 0.1)
				(type default)
			)
			(layer "B.Fab")
		)
		(fp_line
			(start 2.249932 2.549906)
			(end 2.249932 -2.549906)
			(stroke
				(width 0.1)
				(type default)
			)
			(layer "B.Fab")
		)
		(fp_poly
			(pts
				(xy 4.36372 -1.608328) (xy 4.36372 -2.233168) (xy 3.81 -1.905)
			)
			(stroke
				(width 0)
				(type default)
			)
			(fill yes)
			(layer "B.Fab")
		)
		(pad "1" smd rect
			(at 2.921 -1.949958 270)
			(size 0.3556 1.4986)
			(layers "B.Cu" "B.Mask" "B.Paste")
			(net "FB_BMC_ISOLATE1")
		)
		(pad "2" smd rect
			(at 2.921 -1.299972 270)
			(size 0.3556 1.4986)
			(layers "B.Cu" "B.Mask" "B.Paste")
			(net "NCSI_BMC_RXD1_R1")
		)
		(pad "3" smd rect
			(at 2.921 -0.649986 270)
			(size 0.3556 1.4986)
			(layers "B.Cu" "B.Mask" "B.Paste")
			(net "NCSI_OCP_V3_2_RXD1")
		)
		(pad "4" smd rect
			(at 2.921 0 270)
			(size 0.3556 1.4986)
			(layers "B.Cu" "B.Mask" "B.Paste")
			(net "FB_BMC_ISOLATE1")
		)
		(pad "5" smd rect
			(at 2.921 0.649986 270)
			(size 0.3556 1.4986)
			(layers "B.Cu" "B.Mask" "B.Paste")
			(net "NCSI_BMC_RXD0_R1")
		)
		(pad "6" smd rect
			(at 2.921 1.299972 270)
			(size 0.3556 1.4986)
			(layers "B.Cu" "B.Mask" "B.Paste")
			(net "NCSI_OCP_V3_2_RXD0")
		)
		(pad "7" smd rect
			(at 2.921 1.949958 270)
			(size 0.3556 1.4986)
			(layers "B.Cu" "B.Mask" "B.Paste")
			(net "GND")
		)
		(pad "8" smd rect
			(at -2.921 1.949958 270)
			(size 0.3556 1.4986)
			(layers "B.Cu" "B.Mask" "B.Paste")
			(net "NCSI_OCP_V3_2_CRS_DV")
		)
		(pad "9" smd rect
			(at -2.921 1.299972 270)
			(size 0.3556 1.4986)
			(layers "B.Cu" "B.Mask" "B.Paste")
			(net "NCSI_BMC_CRS_DV_R1")
		)
		(pad "10" smd rect
			(at -2.921 0.649986 270)
			(size 0.3556 1.4986)
			(layers "B.Cu" "B.Mask" "B.Paste")
			(net "FB_BMC_ISOLATE1")
		)
		(pad "11" smd rect
			(at -2.921 0 270)
			(size 0.3556 1.4986)
			(layers "B.Cu" "B.Mask" "B.Paste")
			(net "OCP_V3_2_ISO1_RBT_ARB_IN")
		)
		(pad "12" smd rect
			(at -2.921 -0.649986 270)
			(size 0.3556 1.4986)
			(layers "B.Cu" "B.Mask" "B.Paste")
			(net "OCP_V3_2_RBT_ARB_IN_R")
		)
		(pad "13" smd rect
			(at -2.921 -1.299972 270)
			(size 0.3556 1.4986)
			(layers "B.Cu" "B.Mask" "B.Paste")
			(net "FB_BMC_ISOLATE1")
		)
		(pad "14" smd rect
			(at -2.921 -1.949958 270)
			(size 0.3556 1.4986)
			(layers "B.Cu" "B.Mask" "B.Paste")
			(net "P3V3_AUX")
		)
	)
	(footprint ""
		(layer "B.Cu")
		(at 306.968398 -190.45047 90)
		(property "Reference" "R555"
			(at 0 0 90)
			(layer "B.SilkS")
			(hide yes)
			(effects
				(font
					(size 1.27 1.27)
				)
				(justify mirror)
			)
		)
		(property "Value" ""
			(at 0 0 90)
			(layer "B.Fab")
			(effects
				(font
					(size 1.27 1.27)
				)
				(justify mirror)
			)
		)
		(duplicate_pad_numbers_are_jumpers no)
		(fp_line
			(start 0.7874 -0.4064)
			(end -0.7874 -0.4064)
			(stroke
				(width 0.1524)
				(type default)
			)
			(layer "B.SilkS")
		)
		(fp_line
			(start -0.7874 -0.4064)
			(end -0.7874 0.4064)
			(stroke
				(width 0.1524)
				(type default)
			)
			(layer "B.SilkS")
		)
		(fp_line
			(start 0.7874 0.4064)
			(end 0.7874 -0.4064)
			(stroke
				(width 0.1524)
				(type default)
			)
			(layer "B.SilkS")
		)
		(fp_line
			(start -0.7874 0.4064)
			(end 0.7874 0.4064)
			(stroke
				(width 0.1524)
				(type default)
			)
			(layer "B.SilkS")
		)
		(fp_line
			(start 0.67945 -0.305054)
			(end 0.12065 -0.305054)
			(stroke
				(width 0.1)
				(type default)
			)
			(layer "B.Fab")
		)
		(fp_line
			(start 0.12065 -0.305054)
			(end 0.12065 -0.2794)
			(stroke
				(width 0.1)
				(type default)
			)
			(layer "B.Fab")
		)
		(fp_line
			(start -0.12065 -0.3048)
			(end -0.67945 -0.3048)
			(stroke
				(width 0.1)
				(type default)
			)
			(layer "B.Fab")
		)
		(fp_line
			(start -0.67945 -0.3048)
			(end -0.67945 0.3048)
			(stroke
				(width 0.1)
				(type default)
			)
			(layer "B.Fab")
		)
		(fp_line
			(start 0.12065 -0.2794)
			(end -0.12065 -0.2794)
			(stroke
				(width 0.1)
				(type default)
			)
			(layer "B.Fab")
		)
		(fp_line
			(start -0.12065 -0.2794)
			(end -0.12065 -0.3048)
			(stroke
				(width 0.1)
				(type default)
			)
			(layer "B.Fab")
		)
		(fp_line
			(start 0.12065 0.2794)
			(end 0.12065 0.3048)
			(stroke
				(width 0.1)
				(type default)
			)
			(layer "B.Fab")
		)
		(fp_line
			(start -0.120396 0.2794)
			(end 0.12065 0.2794)
			(stroke
				(width 0.1)
				(type default)
			)
			(layer "B.Fab")
		)
		(fp_line
			(start 0.67945 0.3048)
			(end 0.67945 -0.305054)
			(stroke
				(width 0.1)
				(type default)
			)
			(layer "B.Fab")
		)
		(fp_line
			(start 0.12065 0.3048)
			(end 0.67945 0.3048)
			(stroke
				(width 0.1)
				(type default)
			)
			(layer "B.Fab")
		)
		(fp_line
			(start -0.120396 0.3048)
			(end -0.120396 0.2794)
			(stroke
				(width 0.1)
				(type default)
			)
			(layer "B.Fab")
		)
		(fp_line
			(start -0.67945 0.3048)
			(end -0.120396 0.3048)
			(stroke
				(width 0.1)
				(type default)
			)
			(layer "B.Fab")
		)
		(pad "1" smd circle
			(at 0.40005 0 270)
			(size 0 0)
			(layers "B.Cu" "B.Mask" "B.Paste")
			(net "SVID_DIO1_CPU0_R")
		)
		(pad "2" smd circle
			(at -0.40005 0 270)
			(size 0 0)
			(layers "B.Cu" "B.Mask" "B.Paste")
			(net "PVNN_TERM_CPU0")
		)
	)
	(footprint ""
		(layer "B.Cu")
		(at 178.1556 -110.975394 -90)
		(property "Reference" "C1908"
			(at 0 0 90)
			(layer "B.SilkS")
			(hide yes)
			(effects
				(font
					(size 1.27 1.27)
				)
				(justify mirror)
			)
		)
		(property "Value" ""
			(at 0 0 90)
			(layer "B.Fab")
			(effects
				(font
					(size 1.27 1.27)
				)
				(justify mirror)
			)
		)
		(duplicate_pad_numbers_are_jumpers no)
		(fp_line
			(start -0.69215 0.2921)
			(end 0.69215 0.2921)
			(stroke
				(width 0.1524)
				(type default)
			)
			(layer "B.SilkS")
		)
		(fp_line
			(start 0.69215 0.2921)
			(end 0.69215 -0.2921)
			(stroke
				(width 0.1524)
				(type default)
			)
			(layer "B.SilkS")
		)
		(fp_line
			(start -0.69215 -0.2921)
			(end -0.69215 0.2921)
			(stroke
				(width 0.1524)
				(type default)
			)
			(layer "B.SilkS")
		)
		(fp_line
			(start 0.69215 -0.2921)
			(end -0.69215 -0.2921)
			(stroke
				(width 0.1524)
				(type default)
			)
			(layer "B.SilkS")
		)
		(fp_line
			(start -0.51435 0.2794)
			(end 0.51435 0.2794)
			(stroke
				(width 0.1)
				(type default)
			)
			(layer "B.Fab")
		)
		(fp_line
			(start 0.51435 0.2794)
			(end 0.51435 -0.2794)
			(stroke
				(width 0.1)
				(type default)
			)
			(layer "B.Fab")
		)
		(fp_line
			(start -0.51435 -0.2794)
			(end -0.51435 0.2794)
			(stroke
				(width 0.1)
				(type default)
			)
			(layer "B.Fab")
		)
		(fp_line
			(start 0.51435 -0.2794)
			(end -0.51435 -0.2794)
			(stroke
				(width 0.1)
				(type default)
			)
			(layer "B.Fab")
		)
		(pad "1" smd circle
			(at 0.40005 0 90)
			(size 0 0)
			(layers "B.Cu" "B.Mask" "B.Paste")
			(net "P3V3_AUX_FPGA_VCCIO4")
		)
		(pad "2" smd circle
			(at -0.40005 0 90)
			(size 0 0)
			(layers "B.Cu" "B.Mask" "B.Paste")
			(net "GND")
		)
		(zone
			(layer "B.Cu")
			(hatch none 0.5)
			(connect_pads
				(clearance 0)
			)
			(min_thickness 0.25)
			(keepout
				(tracks not_allowed)
				(vias allowed)
				(pads allowed)
				(copperpour not_allowed)
				(footprints allowed)
			)
			(placement
				(enabled no)
				(sheetname "")
			)
			(fill
				(thermal_gap 0.5)
				(thermal_bridge_width 0.5)
				(island_removal_mode 0)
			)
			(polygon
				(pts
					(xy 178.06797 -110.784894) (xy 178.009804 -110.876334) (xy 178.009804 -111.075724) (xy 178.06797 -111.165894)
					(xy 178.24323 -111.165894) (xy 178.30165 -111.075724) (xy 178.30165 -110.876334) (xy 178.243484 -110.784894)
				)
			)
		)
	)
	(footprint ""
		(layer "B.Cu")
		(at 193.384678 -126.405132 180)
		(property "Reference" "R4518"
			(at 0 0 0)
			(layer "B.SilkS")
			(hide yes)
			(effects
				(font
					(size 1.27 1.27)
				)
				(justify mirror)
			)
		)
		(property "Value" ""
			(at 0 0 0)
			(layer "B.Fab")
			(effects
				(font
					(size 1.27 1.27)
				)
				(justify mirror)
			)
		)
		(duplicate_pad_numbers_are_jumpers no)
		(fp_line
			(start 0.7874 0.4064)
			(end 0.7874 -0.4064)
			(stroke
				(width 0.1524)
				(type default)
			)
			(layer "B.SilkS")
		)
		(fp_line
			(start 0.7874 -0.4064)
			(end -0.7874 -0.4064)
			(stroke
				(width 0.1524)
				(type default)
			)
			(layer "B.SilkS")
		)
		(fp_line
			(start -0.7874 0.4064)
			(end 0.7874 0.4064)
			(stroke
				(width 0.1524)
				(type default)
			)
			(layer "B.SilkS")
		)
		(fp_line
			(start -0.7874 -0.4064)
			(end -0.7874 0.4064)
			(stroke
				(width 0.1524)
				(type default)
			)
			(layer "B.SilkS")
		)
		(fp_line
			(start 0.67945 0.3048)
			(end 0.67945 -0.305054)
			(stroke
				(width 0.1)
				(type default)
			)
			(layer "B.Fab")
		)
		(fp_line
			(start 0.67945 -0.305054)
			(end 0.12065 -0.305054)
			(stroke
				(width 0.1)
				(type default)
			)
			(layer "B.Fab")
		)
		(fp_line
			(start 0.12065 0.3048)
			(end 0.67945 0.3048)
			(stroke
				(width 0.1)
				(type default)
			)
			(layer "B.Fab")
		)
		(fp_line
			(start 0.12065 0.2794)
			(end 0.12065 0.3048)
			(stroke
				(width 0.1)
				(type default)
			)
			(layer "B.Fab")
		)
		(fp_line
			(start 0.12065 -0.2794)
			(end -0.12065 -0.2794)
			(stroke
				(width 0.1)
				(type default)
			)
			(layer "B.Fab")
		)
		(fp_line
			(start 0.12065 -0.305054)
			(end 0.12065 -0.2794)
			(stroke
				(width 0.1)
				(type default)
			)
			(layer "B.Fab")
		)
		(fp_line
			(start -0.120396 0.3048)
			(end -0.120396 0.2794)
			(stroke
				(width 0.1)
				(type default)
			)
			(layer "B.Fab")
		)
		(fp_line
			(start -0.120396 0.2794)
			(end 0.12065 0.2794)
			(stroke
				(width 0.1)
				(type default)
			)
			(layer "B.Fab")
		)
		(fp_line
			(start -0.12065 -0.2794)
			(end -0.12065 -0.3048)
			(stroke
				(width 0.1)
				(type default)
			)
			(layer "B.Fab")
		)
		(fp_line
			(start -0.12065 -0.3048)
			(end -0.67945 -0.3048)
			(stroke
				(width 0.1)
				(type default)
			)
			(layer "B.Fab")
		)
		(fp_line
			(start -0.67945 0.3048)
			(end -0.120396 0.3048)
			(stroke
				(width 0.1)
				(type default)
			)
			(layer "B.Fab")
		)
		(fp_line
			(start -0.67945 -0.3048)
			(end -0.67945 0.3048)
			(stroke
				(width 0.1)
				(type default)
			)
			(layer "B.Fab")
		)
		(pad "1" smd circle
			(at 0.40005 0)
			(size 0 0)
			(layers "B.Cu" "B.Mask" "B.Paste")
			(net "P3V3")
		)
		(pad "2" smd circle
			(at -0.40005 0)
			(size 0 0)
			(layers "B.Cu" "B.Mask" "B.Paste")
			(net "CLK_GPU_2_OE_N")
		)
	)
	(footprint ""
		(layer "B.Cu")
		(at 121.1326 -357.675688 180)
		(property "Reference" "PC2282"
			(at 0 0 0)
			(layer "B.SilkS")
			(hide yes)
			(effects
				(font
					(size 1.27 1.27)
				)
				(justify mirror)
			)
		)
		(property "Value" ""
			(at 0 0 0)
			(layer "B.Fab")
			(effects
				(font
					(size 1.27 1.27)
				)
				(justify mirror)
			)
		)
		(duplicate_pad_numbers_are_jumpers no)
		(fp_line
			(start 0.7874 0.4064)
			(end 0.7874 -0.4064)
			(stroke
				(width 0.1524)
				(type default)
			)
			(layer "B.SilkS")
		)
		(fp_line
			(start 0.7874 -0.4064)
			(end -0.7874 -0.4064)
			(stroke
				(width 0.1524)
				(type default)
			)
			(layer "B.SilkS")
		)
		(fp_line
			(start -0.7874 0.4064)
			(end 0.7874 0.4064)
			(stroke
				(width 0.1524)
				(type default)
			)
			(layer "B.SilkS")
		)
		(fp_line
			(start -0.7874 -0.4064)
			(end -0.7874 0.4064)
			(stroke
				(width 0.1524)
				(type default)
			)
			(layer "B.SilkS")
		)
		(fp_line
			(start 0.67945 0.3048)
			(end 0.67945 -0.305054)
			(stroke
				(width 0.1)
				(type default)
			)
			(layer "B.Fab")
		)
		(fp_line
			(start 0.67945 -0.305054)
			(end 0.12065 -0.305054)
			(stroke
				(width 0.1)
				(type default)
			)
			(layer "B.Fab")
		)
		(fp_line
			(start 0.12065 0.3048)
			(end 0.67945 0.3048)
			(stroke
				(width 0.1)
				(type default)
			)
			(layer "B.Fab")
		)
		(fp_line
			(start 0.12065 0.2794)
			(end 0.12065 0.3048)
			(stroke
				(width 0.1)
				(type default)
			)
			(layer "B.Fab")
		)
		(fp_line
			(start 0.12065 -0.2794)
			(end -0.12065 -0.2794)
			(stroke
				(width 0.1)
				(type default)
			)
			(layer "B.Fab")
		)
		(fp_line
			(start 0.12065 -0.305054)
			(end 0.12065 -0.2794)
			(stroke
				(width 0.1)
				(type default)
			)
			(layer "B.Fab")
		)
		(fp_line
			(start -0.120396 0.3048)
			(end -0.120396 0.2794)
			(stroke
				(width 0.1)
				(type default)
			)
			(layer "B.Fab")
		)
		(fp_line
			(start -0.120396 0.2794)
			(end 0.12065 0.2794)
			(stroke
				(width 0.1)
				(type default)
			)
			(layer "B.Fab")
		)
		(fp_line
			(start -0.12065 -0.2794)
			(end -0.12065 -0.3048)
			(stroke
				(width 0.1)
				(type default)
			)
			(layer "B.Fab")
		)
		(fp_line
			(start -0.12065 -0.3048)
			(end -0.67945 -0.3048)
			(stroke
				(width 0.1)
				(type default)
			)
			(layer "B.Fab")
		)
		(fp_line
			(start -0.67945 0.3048)
			(end -0.120396 0.3048)
			(stroke
				(width 0.1)
				(type default)
			)
			(layer "B.Fab")
		)
		(fp_line
			(start -0.67945 -0.3048)
			(end -0.67945 0.3048)
			(stroke
				(width 0.1)
				(type default)
			)
			(layer "B.Fab")
		)
		(pad "1" smd circle
			(at 0.40005 0)
			(size 0 0)
			(layers "B.Cu" "B.Mask" "B.Paste")
			(net "SH_PVPP_HBM_CPU1_P")
		)
		(pad "2" smd circle
			(at -0.40005 0)
			(size 0 0)
			(layers "B.Cu" "B.Mask" "B.Paste")
			(net "SH_PVPP_HBM_CPU1_N")
		)
	)
	(footprint ""
		(layer "B.Cu")
		(at 173.04893 -102.707948)
		(property "Reference" "C1947"
			(at 0 0 0)
			(layer "B.SilkS")
			(hide yes)
			(effects
				(font
					(size 1.27 1.27)
				)
				(justify mirror)
			)
		)
		(property "Value" ""
			(at 0 0 0)
			(layer "B.Fab")
			(effects
				(font
					(size 1.27 1.27)
				)
				(justify mirror)
			)
		)
		(duplicate_pad_numbers_are_jumpers no)
		(fp_line
			(start -0.7874 -0.4064)
			(end -0.7874 0.4064)
			(stroke
				(width 0.1524)
				(type default)
			)
			(layer "B.SilkS")
		)
		(fp_line
			(start -0.7874 0.4064)
			(end 0.7874 0.4064)
			(stroke
				(width 0.1524)
				(type default)
			)
			(layer "B.SilkS")
		)
		(fp_line
			(start 0.7874 -0.4064)
			(end -0.7874 -0.4064)
			(stroke
				(width 0.1524)
				(type default)
			)
			(layer "B.SilkS")
		)
		(fp_line
			(start 0.7874 0.4064)
			(end 0.7874 -0.4064)
			(stroke
				(width 0.1524)
				(type default)
			)
			(layer "B.SilkS")
		)
		(fp_line
			(start -0.67945 -0.3048)
			(end -0.67945 0.3048)
			(stroke
				(width 0.1)
				(type default)
			)
			(layer "B.Fab")
		)
		(fp_line
			(start -0.67945 0.3048)
			(end -0.120396 0.3048)
			(stroke
				(width 0.1)
				(type default)
			)
			(layer "B.Fab")
		)
		(fp_line
			(start -0.12065 -0.3048)
			(end -0.67945 -0.3048)
			(stroke
				(width 0.1)
				(type default)
			)
			(layer "B.Fab")
		)
		(fp_line
			(start -0.12065 -0.2794)
			(end -0.12065 -0.3048)
			(stroke
				(width 0.1)
				(type default)
			)
			(layer "B.Fab")
		)
		(fp_line
			(start -0.120396 0.2794)
			(end 0.12065 0.2794)
			(stroke
				(width 0.1)
				(type default)
			)
			(layer "B.Fab")
		)
		(fp_line
			(start -0.120396 0.3048)
			(end -0.120396 0.2794)
			(stroke
				(width 0.1)
				(type default)
			)
			(layer "B.Fab")
		)
		(fp_line
			(start 0.12065 -0.305054)
			(end 0.12065 -0.2794)
			(stroke
				(width 0.1)
				(type default)
			)
			(layer "B.Fab")
		)
		(fp_line
			(start 0.12065 -0.2794)
			(end -0.12065 -0.2794)
			(stroke
				(width 0.1)
				(type default)
			)
			(layer "B.Fab")
		)
		(fp_line
			(start 0.12065 0.2794)
			(end 0.12065 0.3048)
			(stroke
				(width 0.1)
				(type default)
			)
			(layer "B.Fab")
		)
		(fp_line
			(start 0.12065 0.3048)
			(end 0.67945 0.3048)
			(stroke
				(width 0.1)
				(type default)
			)
			(layer "B.Fab")
		)
		(fp_line
			(start 0.67945 -0.305054)
			(end 0.12065 -0.305054)
			(stroke
				(width 0.1)
				(type default)
			)
			(layer "B.Fab")
		)
		(fp_line
			(start 0.67945 0.3048)
			(end 0.67945 -0.305054)
			(stroke
				(width 0.1)
				(type default)
			)
			(layer "B.Fab")
		)
		(pad "1" smd circle
			(at 0.40005 0 180)
			(size 0 0)
			(layers "B.Cu" "B.Mask" "B.Paste")
			(net "P3V3_AUX_FPGA_VCCIO5")
		)
		(pad "2" smd circle
			(at -0.40005 0 180)
			(size 0 0)
			(layers "B.Cu" "B.Mask" "B.Paste")
			(net "GND")
		)
	)
	(footprint ""
		(layer "B.Cu")
		(at 80.430624 -184.096152 -90)
		(property "Reference" "R240"
			(at 0 0 90)
			(layer "B.SilkS")
			(hide yes)
			(effects
				(font
					(size 1.27 1.27)
				)
				(justify mirror)
			)
		)
		(property "Value" ""
			(at 0 0 90)
			(layer "B.Fab")
			(effects
				(font
					(size 1.27 1.27)
				)
				(justify mirror)
			)
		)
		(duplicate_pad_numbers_are_jumpers no)
		(fp_line
			(start -0.7874 0.4064)
			(end 0.7874 0.4064)
			(stroke
				(width 0.1524)
				(type default)
			)
			(layer "B.SilkS")
		)
		(fp_line
			(start 0.7874 0.4064)
			(end 0.7874 -0.4064)
			(stroke
				(width 0.1524)
				(type default)
			)
			(layer "B.SilkS")
		)
		(fp_line
			(start -0.7874 -0.4064)
			(end -0.7874 0.4064)
			(stroke
				(width 0.1524)
				(type default)
			)
			(layer "B.SilkS")
		)
		(fp_line
			(start 0.7874 -0.4064)
			(end -0.7874 -0.4064)
			(stroke
				(width 0.1524)
				(type default)
			)
			(layer "B.SilkS")
		)
		(fp_line
			(start -0.67945 0.3048)
			(end -0.120396 0.3048)
			(stroke
				(width 0.1)
				(type default)
			)
			(layer "B.Fab")
		)
		(fp_line
			(start -0.120396 0.3048)
			(end -0.120396 0.2794)
			(stroke
				(width 0.1)
				(type default)
			)
			(layer "B.Fab")
		)
		(fp_line
			(start 0.12065 0.3048)
			(end 0.67945 0.3048)
			(stroke
				(width 0.1)
				(type default)
			)
			(layer "B.Fab")
		)
		(fp_line
			(start 0.67945 0.3048)
			(end 0.67945 -0.305054)
			(stroke
				(width 0.1)
				(type default)
			)
			(layer "B.Fab")
		)
		(fp_line
			(start -0.120396 0.2794)
			(end 0.12065 0.2794)
			(stroke
				(width 0.1)
				(type default)
			)
			(layer "B.Fab")
		)
		(fp_line
			(start 0.12065 0.2794)
			(end 0.12065 0.3048)
			(stroke
				(width 0.1)
				(type default)
			)
			(layer "B.Fab")
		)
		(fp_line
			(start -0.12065 -0.2794)
			(end -0.12065 -0.3048)
			(stroke
				(width 0.1)
				(type default)
			)
			(layer "B.Fab")
		)
		(fp_line
			(start 0.12065 -0.2794)
			(end -0.12065 -0.2794)
			(stroke
				(width 0.1)
				(type default)
			)
			(layer "B.Fab")
		)
		(fp_line
			(start -0.67945 -0.3048)
			(end -0.67945 0.3048)
			(stroke
				(width 0.1)
				(type default)
			)
			(layer "B.Fab")
		)
		(fp_line
			(start -0.12065 -0.3048)
			(end -0.67945 -0.3048)
			(stroke
				(width 0.1)
				(type default)
			)
			(layer "B.Fab")
		)
		(fp_line
			(start 0.12065 -0.305054)
			(end 0.12065 -0.2794)
			(stroke
				(width 0.1)
				(type default)
			)
			(layer "B.Fab")
		)
		(fp_line
			(start 0.67945 -0.305054)
			(end 0.12065 -0.305054)
			(stroke
				(width 0.1)
				(type default)
			)
			(layer "B.Fab")
		)
		(pad "1" smd circle
			(at 0.40005 0 90)
			(size 0 0)
			(layers "B.Cu" "B.Mask" "B.Paste")
			(net "H_CPU1_PROCHOT_LVC1_R_N")
		)
		(pad "2" smd circle
			(at -0.40005 0 90)
			(size 0 0)
			(layers "B.Cu" "B.Mask" "B.Paste")
			(net "H_CPU1_PROCHOT_LVC1_N")
		)
	)
	(footprint ""
		(layer "B.Cu")
		(at 162.306 -15.712948 -90)
		(property "Reference" "R1384"
			(at 0 0 90)
			(layer "B.SilkS")
			(hide yes)
			(effects
				(font
					(size 1.27 1.27)
				)
				(justify mirror)
			)
		)
		(property "Value" ""
			(at 0 0 90)
			(layer "B.Fab")
			(effects
				(font
					(size 1.27 1.27)
				)
				(justify mirror)
			)
		)
		(duplicate_pad_numbers_are_jumpers no)
		(fp_line
			(start -0.7874 0.4064)
			(end 0.7874 0.4064)
			(stroke
				(width 0.1524)
				(type default)
			)
			(layer "B.SilkS")
		)
		(fp_line
			(start 0.7874 0.4064)
			(end 0.7874 -0.4064)
			(stroke
				(width 0.1524)
				(type default)
			)
			(layer "B.SilkS")
		)
		(fp_line
			(start -0.7874 -0.4064)
			(end -0.7874 0.4064)
			(stroke
				(width 0.1524)
				(type default)
			)
			(layer "B.SilkS")
		)
		(fp_line
			(start 0.7874 -0.4064)
			(end -0.7874 -0.4064)
			(stroke
				(width 0.1524)
				(type default)
			)
			(layer "B.SilkS")
		)
		(fp_line
			(start -0.67945 0.3048)
			(end -0.120396 0.3048)
			(stroke
				(width 0.1)
				(type default)
			)
			(layer "B.Fab")
		)
		(fp_line
			(start -0.120396 0.3048)
			(end -0.120396 0.2794)
			(stroke
				(width 0.1)
				(type default)
			)
			(layer "B.Fab")
		)
		(fp_line
			(start 0.12065 0.3048)
			(end 0.67945 0.3048)
			(stroke
				(width 0.1)
				(type default)
			)
			(layer "B.Fab")
		)
		(fp_line
			(start 0.67945 0.3048)
			(end 0.67945 -0.305054)
			(stroke
				(width 0.1)
				(type default)
			)
			(layer "B.Fab")
		)
		(fp_line
			(start -0.120396 0.2794)
			(end 0.12065 0.2794)
			(stroke
				(width 0.1)
				(type default)
			)
			(layer "B.Fab")
		)
		(fp_line
			(start 0.12065 0.2794)
			(end 0.12065 0.3048)
			(stroke
				(width 0.1)
				(type default)
			)
			(layer "B.Fab")
		)
		(fp_line
			(start -0.12065 -0.2794)
			(end -0.12065 -0.3048)
			(stroke
				(width 0.1)
				(type default)
			)
			(layer "B.Fab")
		)
		(fp_line
			(start 0.12065 -0.2794)
			(end -0.12065 -0.2794)
			(stroke
				(width 0.1)
				(type default)
			)
			(layer "B.Fab")
		)
		(fp_line
			(start -0.67945 -0.3048)
			(end -0.67945 0.3048)
			(stroke
				(width 0.1)
				(type default)
			)
			(layer "B.Fab")
		)
		(fp_line
			(start -0.12065 -0.3048)
			(end -0.67945 -0.3048)
			(stroke
				(width 0.1)
				(type default)
			)
			(layer "B.Fab")
		)
		(fp_line
			(start 0.12065 -0.305054)
			(end 0.12065 -0.2794)
			(stroke
				(width 0.1)
				(type default)
			)
			(layer "B.Fab")
		)
		(fp_line
			(start 0.67945 -0.305054)
			(end 0.12065 -0.305054)
			(stroke
				(width 0.1)
				(type default)
			)
			(layer "B.Fab")
		)
		(pad "1" smd circle
			(at 0.40005 0 90)
			(size 0 0)
			(layers "B.Cu" "B.Mask" "B.Paste")
			(net "SMB_SML0_3V3AUX_SCL")
		)
		(pad "2" smd circle
			(at -0.40005 0 90)
			(size 0 0)
			(layers "B.Cu" "B.Mask" "B.Paste")
			(net "P3V3_AUX")
		)
	)
	(footprint ""
		(layer "B.Cu")
		(at 369.49888 -37.937948 180)
		(property "Reference" "R4117"
			(at 0 0 0)
			(layer "B.SilkS")
			(hide yes)
			(effects
				(font
					(size 1.27 1.27)
				)
				(justify mirror)
			)
		)
		(property "Value" ""
			(at 0 0 0)
			(layer "B.Fab")
			(effects
				(font
					(size 1.27 1.27)
				)
				(justify mirror)
			)
		)
		(duplicate_pad_numbers_are_jumpers no)
		(fp_line
			(start 0.7874 0.4064)
			(end 0.7874 -0.4064)
			(stroke
				(width 0.1524)
				(type default)
			)
			(layer "B.SilkS")
		)
		(fp_line
			(start 0.7874 -0.4064)
			(end -0.7874 -0.4064)
			(stroke
				(width 0.1524)
				(type default)
			)
			(layer "B.SilkS")
		)
		(fp_line
			(start -0.7874 0.4064)
			(end 0.7874 0.4064)
			(stroke
				(width 0.1524)
				(type default)
			)
			(layer "B.SilkS")
		)
		(fp_line
			(start -0.7874 -0.4064)
			(end -0.7874 0.4064)
			(stroke
				(width 0.1524)
				(type default)
			)
			(layer "B.SilkS")
		)
		(fp_line
			(start 0.67945 0.3048)
			(end 0.67945 -0.305054)
			(stroke
				(width 0.1)
				(type default)
			)
			(layer "B.Fab")
		)
		(fp_line
			(start 0.67945 -0.305054)
			(end 0.12065 -0.305054)
			(stroke
				(width 0.1)
				(type default)
			)
			(layer "B.Fab")
		)
		(fp_line
			(start 0.12065 0.3048)
			(end 0.67945 0.3048)
			(stroke
				(width 0.1)
				(type default)
			)
			(layer "B.Fab")
		)
		(fp_line
			(start 0.12065 0.2794)
			(end 0.12065 0.3048)
			(stroke
				(width 0.1)
				(type default)
			)
			(layer "B.Fab")
		)
		(fp_line
			(start 0.12065 -0.2794)
			(end -0.12065 -0.2794)
			(stroke
				(width 0.1)
				(type default)
			)
			(layer "B.Fab")
		)
		(fp_line
			(start 0.12065 -0.305054)
			(end 0.12065 -0.2794)
			(stroke
				(width 0.1)
				(type default)
			)
			(layer "B.Fab")
		)
		(fp_line
			(start -0.120396 0.3048)
			(end -0.120396 0.2794)
			(stroke
				(width 0.1)
				(type default)
			)
			(layer "B.Fab")
		)
		(fp_line
			(start -0.120396 0.2794)
			(end 0.12065 0.2794)
			(stroke
				(width 0.1)
				(type default)
			)
			(layer "B.Fab")
		)
		(fp_line
			(start -0.12065 -0.2794)
			(end -0.12065 -0.3048)
			(stroke
				(width 0.1)
				(type default)
			)
			(layer "B.Fab")
		)
		(fp_line
			(start -0.12065 -0.3048)
			(end -0.67945 -0.3048)
			(stroke
				(width 0.1)
				(type default)
			)
			(layer "B.Fab")
		)
		(fp_line
			(start -0.67945 0.3048)
			(end -0.120396 0.3048)
			(stroke
				(width 0.1)
				(type default)
			)
			(layer "B.Fab")
		)
		(fp_line
			(start -0.67945 -0.3048)
			(end -0.67945 0.3048)
			(stroke
				(width 0.1)
				(type default)
			)
			(layer "B.Fab")
		)
		(pad "1" smd circle
			(at 0.40005 0)
			(size 0 0)
			(layers "B.Cu" "B.Mask" "B.Paste")
			(net "PD_PCH_GPP_E_3")
		)
		(pad "2" smd circle
			(at -0.40005 0)
			(size 0 0)
			(layers "B.Cu" "B.Mask" "B.Paste")
			(net "GND")
		)
	)
	(footprint ""
		(layer "B.Cu")
		(at 36.765992 -178.63058 180)
		(property "Reference" "C1365"
			(at 0 0 0)
			(layer "B.SilkS")
			(hide yes)
			(effects
				(font
					(size 1.27 1.27)
				)
				(justify mirror)
			)
		)
		(property "Value" ""
			(at 0 0 0)
			(layer "B.Fab")
			(effects
				(font
					(size 1.27 1.27)
				)
				(justify mirror)
			)
		)
		(duplicate_pad_numbers_are_jumpers no)
		(fp_line
			(start 0.7874 0.4064)
			(end 0.7874 -0.4064)
			(stroke
				(width 0.1524)
				(type default)
			)
			(layer "B.SilkS")
		)
		(fp_line
			(start 0.7874 -0.4064)
			(end -0.7874 -0.4064)
			(stroke
				(width 0.1524)
				(type default)
			)
			(layer "B.SilkS")
		)
		(fp_line
			(start -0.7874 0.4064)
			(end 0.7874 0.4064)
			(stroke
				(width 0.1524)
				(type default)
			)
			(layer "B.SilkS")
		)
		(fp_line
			(start -0.7874 -0.4064)
			(end -0.7874 0.4064)
			(stroke
				(width 0.1524)
				(type default)
			)
			(layer "B.SilkS")
		)
		(fp_line
			(start 0.67945 0.3048)
			(end 0.67945 -0.305054)
			(stroke
				(width 0.1)
				(type default)
			)
			(layer "B.Fab")
		)
		(fp_line
			(start 0.67945 -0.305054)
			(end 0.12065 -0.305054)
			(stroke
				(width 0.1)
				(type default)
			)
			(layer "B.Fab")
		)
		(fp_line
			(start 0.12065 0.3048)
			(end 0.67945 0.3048)
			(stroke
				(width 0.1)
				(type default)
			)
			(layer "B.Fab")
		)
		(fp_line
			(start 0.12065 0.2794)
			(end 0.12065 0.3048)
			(stroke
				(width 0.1)
				(type default)
			)
			(layer "B.Fab")
		)
		(fp_line
			(start 0.12065 -0.2794)
			(end -0.12065 -0.2794)
			(stroke
				(width 0.1)
				(type default)
			)
			(layer "B.Fab")
		)
		(fp_line
			(start 0.12065 -0.305054)
			(end 0.12065 -0.2794)
			(stroke
				(width 0.1)
				(type default)
			)
			(layer "B.Fab")
		)
		(fp_line
			(start -0.120396 0.3048)
			(end -0.120396 0.2794)
			(stroke
				(width 0.1)
				(type default)
			)
			(layer "B.Fab")
		)
		(fp_line
			(start -0.120396 0.2794)
			(end 0.12065 0.2794)
			(stroke
				(width 0.1)
				(type default)
			)
			(layer "B.Fab")
		)
		(fp_line
			(start -0.12065 -0.2794)
			(end -0.12065 -0.3048)
			(stroke
				(width 0.1)
				(type default)
			)
			(layer "B.Fab")
		)
		(fp_line
			(start -0.12065 -0.3048)
			(end -0.67945 -0.3048)
			(stroke
				(width 0.1)
				(type default)
			)
			(layer "B.Fab")
		)
		(fp_line
			(start -0.67945 0.3048)
			(end -0.120396 0.3048)
			(stroke
				(width 0.1)
				(type default)
			)
			(layer "B.Fab")
		)
		(fp_line
			(start -0.67945 -0.3048)
			(end -0.67945 0.3048)
			(stroke
				(width 0.1)
				(type default)
			)
			(layer "B.Fab")
		)
		(pad "1" smd circle
			(at 0.40005 0)
			(size 0 0)
			(layers "B.Cu" "B.Mask" "B.Paste")
			(net "PVNN_MAIN_CPU1")
		)
		(pad "2" smd circle
			(at -0.40005 0)
			(size 0 0)
			(layers "B.Cu" "B.Mask" "B.Paste")
			(net "GND")
		)
	)
	(footprint ""
		(layer "B.Cu")
		(at 51.14544 -170.495468 90)
		(property "Reference" "PR250"
			(at 0 0 90)
			(layer "B.SilkS")
			(hide yes)
			(effects
				(font
					(size 1.27 1.27)
				)
				(justify mirror)
			)
		)
		(property "Value" ""
			(at 0 0 90)
			(layer "B.Fab")
			(effects
				(font
					(size 1.27 1.27)
				)
				(justify mirror)
			)
		)
		(duplicate_pad_numbers_are_jumpers no)
		(fp_line
			(start 0.7874 -0.4064)
			(end -0.7874 -0.4064)
			(stroke
				(width 0.1524)
				(type default)
			)
			(layer "B.SilkS")
		)
		(fp_line
			(start -0.7874 -0.4064)
			(end -0.7874 0.4064)
			(stroke
				(width 0.1524)
				(type default)
			)
			(layer "B.SilkS")
		)
		(fp_line
			(start 0.7874 0.4064)
			(end 0.7874 -0.4064)
			(stroke
				(width 0.1524)
				(type default)
			)
			(layer "B.SilkS")
		)
		(fp_line
			(start -0.7874 0.4064)
			(end 0.7874 0.4064)
			(stroke
				(width 0.1524)
				(type default)
			)
			(layer "B.SilkS")
		)
		(fp_line
			(start 0.67945 -0.305054)
			(end 0.12065 -0.305054)
			(stroke
				(width 0.1)
				(type default)
			)
			(layer "B.Fab")
		)
		(fp_line
			(start 0.12065 -0.305054)
			(end 0.12065 -0.2794)
			(stroke
				(width 0.1)
				(type default)
			)
			(layer "B.Fab")
		)
		(fp_line
			(start -0.12065 -0.3048)
			(end -0.67945 -0.3048)
			(stroke
				(width 0.1)
				(type default)
			)
			(layer "B.Fab")
		)
		(fp_line
			(start -0.67945 -0.3048)
			(end -0.67945 0.3048)
			(stroke
				(width 0.1)
				(type default)
			)
			(layer "B.Fab")
		)
		(fp_line
			(start 0.12065 -0.2794)
			(end -0.12065 -0.2794)
			(stroke
				(width 0.1)
				(type default)
			)
			(layer "B.Fab")
		)
		(fp_line
			(start -0.12065 -0.2794)
			(end -0.12065 -0.3048)
			(stroke
				(width 0.1)
				(type default)
			)
			(layer "B.Fab")
		)
		(fp_line
			(start 0.12065 0.2794)
			(end 0.12065 0.3048)
			(stroke
				(width 0.1)
				(type default)
			)
			(layer "B.Fab")
		)
		(fp_line
			(start -0.120396 0.2794)
			(end 0.12065 0.2794)
			(stroke
				(width 0.1)
				(type default)
			)
			(layer "B.Fab")
		)
		(fp_line
			(start 0.67945 0.3048)
			(end 0.67945 -0.305054)
			(stroke
				(width 0.1)
				(type default)
			)
			(layer "B.Fab")
		)
		(fp_line
			(start 0.12065 0.3048)
			(end 0.67945 0.3048)
			(stroke
				(width 0.1)
				(type default)
			)
			(layer "B.Fab")
		)
		(fp_line
			(start -0.120396 0.3048)
			(end -0.120396 0.2794)
			(stroke
				(width 0.1)
				(type default)
			)
			(layer "B.Fab")
		)
		(fp_line
			(start -0.67945 0.3048)
			(end -0.120396 0.3048)
			(stroke
				(width 0.1)
				(type default)
			)
			(layer "B.Fab")
		)
		(pad "1" smd circle
			(at 0.40005 0 270)
			(size 0 0)
			(layers "B.Cu" "B.Mask" "B.Paste")
			(net "PVCCFA_EHV_CPU1_PVCC")
		)
		(pad "2" smd circle
			(at -0.40005 0 270)
			(size 0 0)
			(layers "B.Cu" "B.Mask" "B.Paste")
			(net "PVCCFA_EHV_CPU1_VDD1")
		)
	)
	(footprint ""
		(layer "B.Cu")
		(at 308.823614 -258.379976 -90)
		(property "Reference" "C517"
			(at 0 0 90)
			(layer "B.SilkS")
			(hide yes)
			(effects
				(font
					(size 1.27 1.27)
				)
				(justify mirror)
			)
		)
		(property "Value" ""
			(at 0 0 90)
			(layer "B.Fab")
			(effects
				(font
					(size 1.27 1.27)
				)
				(justify mirror)
			)
		)
		(duplicate_pad_numbers_are_jumpers no)
		(fp_line
			(start -1.524 0.762)
			(end 1.524 0.762)
			(stroke
				(width 0.1524)
				(type default)
			)
			(layer "B.SilkS")
		)
		(fp_line
			(start 1.524 0.762)
			(end 1.524 -0.762)
			(stroke
				(width 0.1524)
				(type default)
			)
			(layer "B.SilkS")
		)
		(fp_line
			(start -1.524 -0.762)
			(end -1.524 0.762)
			(stroke
				(width 0.1524)
				(type default)
			)
			(layer "B.SilkS")
		)
		(fp_line
			(start 1.524 -0.762)
			(end -1.524 -0.762)
			(stroke
				(width 0.1524)
				(type default)
			)
			(layer "B.SilkS")
		)
		(fp_line
			(start -1.1049 0.724916)
			(end -1.1049 -0.724916)
			(stroke
				(width 0.1)
				(type default)
			)
			(layer "B.Fab")
		)
		(fp_line
			(start 1.1049 0.724916)
			(end -1.1049 0.724916)
			(stroke
				(width 0.1)
				(type default)
			)
			(layer "B.Fab")
		)
		(fp_line
			(start -1.1049 -0.724916)
			(end 1.1049 -0.724916)
			(stroke
				(width 0.1)
				(type default)
			)
			(layer "B.Fab")
		)
		(fp_line
			(start 1.1049 -0.724916)
			(end 1.1049 0.724916)
			(stroke
				(width 0.1)
				(type default)
			)
			(layer "B.Fab")
		)
		(pad "1" smd rect
			(at 0.889 0 270)
			(size 1.016 1.27)
			(layers "B.Cu" "B.Mask" "B.Paste")
			(net "PVCCFA_EHV_FIVRA_CPU0")
		)
		(pad "2" smd rect
			(at -0.889 0 270)
			(size 1.016 1.27)
			(layers "B.Cu" "B.Mask" "B.Paste")
			(net "GND")
		)
	)
	(footprint ""
		(layer "B.Cu")
		(at 50.698908 -193.25971 -90)
		(property "Reference" "R1393"
			(at 0 0 90)
			(layer "B.SilkS")
			(hide yes)
			(effects
				(font
					(size 1.27 1.27)
				)
				(justify mirror)
			)
		)
		(property "Value" ""
			(at 0 0 90)
			(layer "B.Fab")
			(effects
				(font
					(size 1.27 1.27)
				)
				(justify mirror)
			)
		)
		(duplicate_pad_numbers_are_jumpers no)
		(fp_line
			(start -0.7874 0.4064)
			(end 0.7874 0.4064)
			(stroke
				(width 0.1524)
				(type default)
			)
			(layer "B.SilkS")
		)
		(fp_line
			(start 0.7874 0.4064)
			(end 0.7874 -0.4064)
			(stroke
				(width 0.1524)
				(type default)
			)
			(layer "B.SilkS")
		)
		(fp_line
			(start -0.7874 -0.4064)
			(end -0.7874 0.4064)
			(stroke
				(width 0.1524)
				(type default)
			)
			(layer "B.SilkS")
		)
		(fp_line
			(start 0.7874 -0.4064)
			(end -0.7874 -0.4064)
			(stroke
				(width 0.1524)
				(type default)
			)
			(layer "B.SilkS")
		)
		(fp_line
			(start -0.67945 0.3048)
			(end -0.120396 0.3048)
			(stroke
				(width 0.1)
				(type default)
			)
			(layer "B.Fab")
		)
		(fp_line
			(start -0.120396 0.3048)
			(end -0.120396 0.2794)
			(stroke
				(width 0.1)
				(type default)
			)
			(layer "B.Fab")
		)
		(fp_line
			(start 0.12065 0.3048)
			(end 0.67945 0.3048)
			(stroke
				(width 0.1)
				(type default)
			)
			(layer "B.Fab")
		)
		(fp_line
			(start 0.67945 0.3048)
			(end 0.67945 -0.305054)
			(stroke
				(width 0.1)
				(type default)
			)
			(layer "B.Fab")
		)
		(fp_line
			(start -0.120396 0.2794)
			(end 0.12065 0.2794)
			(stroke
				(width 0.1)
				(type default)
			)
			(layer "B.Fab")
		)
		(fp_line
			(start 0.12065 0.2794)
			(end 0.12065 0.3048)
			(stroke
				(width 0.1)
				(type default)
			)
			(layer "B.Fab")
		)
		(fp_line
			(start -0.12065 -0.2794)
			(end -0.12065 -0.3048)
			(stroke
				(width 0.1)
				(type default)
			)
			(layer "B.Fab")
		)
		(fp_line
			(start 0.12065 -0.2794)
			(end -0.12065 -0.2794)
			(stroke
				(width 0.1)
				(type default)
			)
			(layer "B.Fab")
		)
		(fp_line
			(start -0.67945 -0.3048)
			(end -0.67945 0.3048)
			(stroke
				(width 0.1)
				(type default)
			)
			(layer "B.Fab")
		)
		(fp_line
			(start -0.12065 -0.3048)
			(end -0.67945 -0.3048)
			(stroke
				(width 0.1)
				(type default)
			)
			(layer "B.Fab")
		)
		(fp_line
			(start 0.12065 -0.305054)
			(end 0.12065 -0.2794)
			(stroke
				(width 0.1)
				(type default)
			)
			(layer "B.Fab")
		)
		(fp_line
			(start 0.67945 -0.305054)
			(end 0.12065 -0.305054)
			(stroke
				(width 0.1)
				(type default)
			)
			(layer "B.Fab")
		)
		(pad "1" smd circle
			(at 0.40005 0 90)
			(size 0 0)
			(layers "B.Cu" "B.Mask" "B.Paste")
			(net "GND")
		)
		(pad "2" smd circle
			(at -0.40005 0 90)
			(size 0 0)
			(layers "B.Cu" "B.Mask" "B.Paste")
			(net "FM_S3M_CPU1_LVC1_GPIO_2")
		)
	)
	(footprint ""
		(layer "B.Cu")
		(at 369.49888 -41.112948 180)
		(property "Reference" "R4111"
			(at 0 0 0)
			(layer "B.SilkS")
			(hide yes)
			(effects
				(font
					(size 1.27 1.27)
				)
				(justify mirror)
			)
		)
		(property "Value" ""
			(at 0 0 0)
			(layer "B.Fab")
			(effects
				(font
					(size 1.27 1.27)
				)
				(justify mirror)
			)
		)
		(duplicate_pad_numbers_are_jumpers no)
		(fp_line
			(start 0.7874 0.4064)
			(end 0.7874 -0.4064)
			(stroke
				(width 0.1524)
				(type default)
			)
			(layer "B.SilkS")
		)
		(fp_line
			(start 0.7874 -0.4064)
			(end -0.7874 -0.4064)
			(stroke
				(width 0.1524)
				(type default)
			)
			(layer "B.SilkS")
		)
		(fp_line
			(start -0.7874 0.4064)
			(end 0.7874 0.4064)
			(stroke
				(width 0.1524)
				(type default)
			)
			(layer "B.SilkS")
		)
		(fp_line
			(start -0.7874 -0.4064)
			(end -0.7874 0.4064)
			(stroke
				(width 0.1524)
				(type default)
			)
			(layer "B.SilkS")
		)
		(fp_line
			(start 0.67945 0.3048)
			(end 0.67945 -0.305054)
			(stroke
				(width 0.1)
				(type default)
			)
			(layer "B.Fab")
		)
		(fp_line
			(start 0.67945 -0.305054)
			(end 0.12065 -0.305054)
			(stroke
				(width 0.1)
				(type default)
			)
			(layer "B.Fab")
		)
		(fp_line
			(start 0.12065 0.3048)
			(end 0.67945 0.3048)
			(stroke
				(width 0.1)
				(type default)
			)
			(layer "B.Fab")
		)
		(fp_line
			(start 0.12065 0.2794)
			(end 0.12065 0.3048)
			(stroke
				(width 0.1)
				(type default)
			)
			(layer "B.Fab")
		)
		(fp_line
			(start 0.12065 -0.2794)
			(end -0.12065 -0.2794)
			(stroke
				(width 0.1)
				(type default)
			)
			(layer "B.Fab")
		)
		(fp_line
			(start 0.12065 -0.305054)
			(end 0.12065 -0.2794)
			(stroke
				(width 0.1)
				(type default)
			)
			(layer "B.Fab")
		)
		(fp_line
			(start -0.120396 0.3048)
			(end -0.120396 0.2794)
			(stroke
				(width 0.1)
				(type default)
			)
			(layer "B.Fab")
		)
		(fp_line
			(start -0.120396 0.2794)
			(end 0.12065 0.2794)
			(stroke
				(width 0.1)
				(type default)
			)
			(layer "B.Fab")
		)
		(fp_line
			(start -0.12065 -0.2794)
			(end -0.12065 -0.3048)
			(stroke
				(width 0.1)
				(type default)
			)
			(layer "B.Fab")
		)
		(fp_line
			(start -0.12065 -0.3048)
			(end -0.67945 -0.3048)
			(stroke
				(width 0.1)
				(type default)
			)
			(layer "B.Fab")
		)
		(fp_line
			(start -0.67945 0.3048)
			(end -0.120396 0.3048)
			(stroke
				(width 0.1)
				(type default)
			)
			(layer "B.Fab")
		)
		(fp_line
			(start -0.67945 -0.3048)
			(end -0.67945 0.3048)
			(stroke
				(width 0.1)
				(type default)
			)
			(layer "B.Fab")
		)
		(pad "1" smd circle
			(at 0.40005 0)
			(size 0 0)
			(layers "B.Cu" "B.Mask" "B.Paste")
			(net "PD_PCH_GPP_E_13")
		)
		(pad "2" smd circle
			(at -0.40005 0)
			(size 0 0)
			(layers "B.Cu" "B.Mask" "B.Paste")
			(net "GND")
		)
	)
	(footprint ""
		(layer "B.Cu")
		(at 350.435418 -294.009826 180)
		(property "Reference" "C366"
			(at 0 0 0)
			(layer "B.SilkS")
			(hide yes)
			(effects
				(font
					(size 1.27 1.27)
				)
				(justify mirror)
			)
		)
		(property "Value" ""
			(at 0 0 0)
			(layer "B.Fab")
			(effects
				(font
					(size 1.27 1.27)
				)
				(justify mirror)
			)
		)
		(duplicate_pad_numbers_are_jumpers no)
		(fp_line
			(start 1.524 0.762)
			(end 1.524 -0.762)
			(stroke
				(width 0.1524)
				(type default)
			)
			(layer "B.SilkS")
		)
		(fp_line
			(start 1.524 -0.762)
			(end -1.524 -0.762)
			(stroke
				(width 0.1524)
				(type default)
			)
			(layer "B.SilkS")
		)
		(fp_line
			(start -1.524 0.762)
			(end 1.524 0.762)
			(stroke
				(width 0.1524)
				(type default)
			)
			(layer "B.SilkS")
		)
		(fp_line
			(start -1.524 -0.762)
			(end -1.524 0.762)
			(stroke
				(width 0.1524)
				(type default)
			)
			(layer "B.SilkS")
		)
		(fp_line
			(start 1.1049 0.724916)
			(end -1.1049 0.724916)
			(stroke
				(width 0.1)
				(type default)
			)
			(layer "B.Fab")
		)
		(fp_line
			(start 1.1049 -0.724916)
			(end 1.1049 0.724916)
			(stroke
				(width 0.1)
				(type default)
			)
			(layer "B.Fab")
		)
		(fp_line
			(start -1.1049 0.724916)
			(end -1.1049 -0.724916)
			(stroke
				(width 0.1)
				(type default)
			)
			(layer "B.Fab")
		)
		(fp_line
			(start -1.1049 -0.724916)
			(end 1.1049 -0.724916)
			(stroke
				(width 0.1)
				(type default)
			)
			(layer "B.Fab")
		)
		(pad "1" smd rect
			(at 0.889 0 180)
			(size 1.016 1.27)
			(layers "B.Cu" "B.Mask" "B.Paste")
			(net "PVCCIN_CPU0")
		)
		(pad "2" smd rect
			(at -0.889 0 180)
			(size 1.016 1.27)
			(layers "B.Cu" "B.Mask" "B.Paste")
			(net "GND")
		)
	)
	(footprint ""
		(layer "B.Cu")
		(at 362.56341 -357.690166)
		(property "Reference" "PR159"
			(at 0 0 0)
			(layer "B.SilkS")
			(hide yes)
			(effects
				(font
					(size 1.27 1.27)
				)
				(justify mirror)
			)
		)
		(property "Value" ""
			(at 0 0 0)
			(layer "B.Fab")
			(effects
				(font
					(size 1.27 1.27)
				)
				(justify mirror)
			)
		)
		(duplicate_pad_numbers_are_jumpers no)
		(fp_line
			(start -0.7874 -0.4064)
			(end -0.7874 0.4064)
			(stroke
				(width 0.1524)
				(type default)
			)
			(layer "B.SilkS")
		)
		(fp_line
			(start -0.7874 0.4064)
			(end 0.7874 0.4064)
			(stroke
				(width 0.1524)
				(type default)
			)
			(layer "B.SilkS")
		)
		(fp_line
			(start 0.7874 -0.4064)
			(end -0.7874 -0.4064)
			(stroke
				(width 0.1524)
				(type default)
			)
			(layer "B.SilkS")
		)
		(fp_line
			(start 0.7874 0.4064)
			(end 0.7874 -0.4064)
			(stroke
				(width 0.1524)
				(type default)
			)
			(layer "B.SilkS")
		)
		(fp_line
			(start -0.67945 -0.3048)
			(end -0.67945 0.3048)
			(stroke
				(width 0.1)
				(type default)
			)
			(layer "B.Fab")
		)
		(fp_line
			(start -0.67945 0.3048)
			(end -0.120396 0.3048)
			(stroke
				(width 0.1)
				(type default)
			)
			(layer "B.Fab")
		)
		(fp_line
			(start -0.12065 -0.3048)
			(end -0.67945 -0.3048)
			(stroke
				(width 0.1)
				(type default)
			)
			(layer "B.Fab")
		)
		(fp_line
			(start -0.12065 -0.2794)
			(end -0.12065 -0.3048)
			(stroke
				(width 0.1)
				(type default)
			)
			(layer "B.Fab")
		)
		(fp_line
			(start -0.120396 0.2794)
			(end 0.12065 0.2794)
			(stroke
				(width 0.1)
				(type default)
			)
			(layer "B.Fab")
		)
		(fp_line
			(start -0.120396 0.3048)
			(end -0.120396 0.2794)
			(stroke
				(width 0.1)
				(type default)
			)
			(layer "B.Fab")
		)
		(fp_line
			(start 0.12065 -0.305054)
			(end 0.12065 -0.2794)
			(stroke
				(width 0.1)
				(type default)
			)
			(layer "B.Fab")
		)
		(fp_line
			(start 0.12065 -0.2794)
			(end -0.12065 -0.2794)
			(stroke
				(width 0.1)
				(type default)
			)
			(layer "B.Fab")
		)
		(fp_line
			(start 0.12065 0.2794)
			(end 0.12065 0.3048)
			(stroke
				(width 0.1)
				(type default)
			)
			(layer "B.Fab")
		)
		(fp_line
			(start 0.12065 0.3048)
			(end 0.67945 0.3048)
			(stroke
				(width 0.1)
				(type default)
			)
			(layer "B.Fab")
		)
		(fp_line
			(start 0.67945 -0.305054)
			(end 0.12065 -0.305054)
			(stroke
				(width 0.1)
				(type default)
			)
			(layer "B.Fab")
		)
		(fp_line
			(start 0.67945 0.3048)
			(end 0.67945 -0.305054)
			(stroke
				(width 0.1)
				(type default)
			)
			(layer "B.Fab")
		)
		(pad "1" smd circle
			(at 0.40005 0 180)
			(size 0 0)
			(layers "B.Cu" "B.Mask" "B.Paste")
			(net "PVCCIN_CPU0_VREF")
		)
		(pad "2" smd circle
			(at -0.40005 0 180)
			(size 0 0)
			(layers "B.Cu" "B.Mask" "B.Paste")
			(net "PVCCIN_CPU0_ADDR")
		)
	)
	(footprint ""
		(layer "B.Cu")
		(at 416.287712 -193.08953 -90)
		(property "Reference" "R321"
			(at 0 0 90)
			(layer "B.SilkS")
			(hide yes)
			(effects
				(font
					(size 1.27 1.27)
				)
				(justify mirror)
			)
		)
		(property "Value" ""
			(at 0 0 90)
			(layer "B.Fab")
			(effects
				(font
					(size 1.27 1.27)
				)
				(justify mirror)
			)
		)
		(duplicate_pad_numbers_are_jumpers no)
		(fp_line
			(start -0.7874 0.4064)
			(end 0.7874 0.4064)
			(stroke
				(width 0.1524)
				(type default)
			)
			(layer "B.SilkS")
		)
		(fp_line
			(start 0.7874 0.4064)
			(end 0.7874 -0.4064)
			(stroke
				(width 0.1524)
				(type default)
			)
			(layer "B.SilkS")
		)
		(fp_line
			(start -0.7874 -0.4064)
			(end -0.7874 0.4064)
			(stroke
				(width 0.1524)
				(type default)
			)
			(layer "B.SilkS")
		)
		(fp_line
			(start 0.7874 -0.4064)
			(end -0.7874 -0.4064)
			(stroke
				(width 0.1524)
				(type default)
			)
			(layer "B.SilkS")
		)
		(fp_line
			(start -0.67945 0.3048)
			(end -0.120396 0.3048)
			(stroke
				(width 0.1)
				(type default)
			)
			(layer "B.Fab")
		)
		(fp_line
			(start -0.120396 0.3048)
			(end -0.120396 0.2794)
			(stroke
				(width 0.1)
				(type default)
			)
			(layer "B.Fab")
		)
		(fp_line
			(start 0.12065 0.3048)
			(end 0.67945 0.3048)
			(stroke
				(width 0.1)
				(type default)
			)
			(layer "B.Fab")
		)
		(fp_line
			(start 0.67945 0.3048)
			(end 0.67945 -0.305054)
			(stroke
				(width 0.1)
				(type default)
			)
			(layer "B.Fab")
		)
		(fp_line
			(start -0.120396 0.2794)
			(end 0.12065 0.2794)
			(stroke
				(width 0.1)
				(type default)
			)
			(layer "B.Fab")
		)
		(fp_line
			(start 0.12065 0.2794)
			(end 0.12065 0.3048)
			(stroke
				(width 0.1)
				(type default)
			)
			(layer "B.Fab")
		)
		(fp_line
			(start -0.12065 -0.2794)
			(end -0.12065 -0.3048)
			(stroke
				(width 0.1)
				(type default)
			)
			(layer "B.Fab")
		)
		(fp_line
			(start 0.12065 -0.2794)
			(end -0.12065 -0.2794)
			(stroke
				(width 0.1)
				(type default)
			)
			(layer "B.Fab")
		)
		(fp_line
			(start -0.67945 -0.3048)
			(end -0.67945 0.3048)
			(stroke
				(width 0.1)
				(type default)
			)
			(layer "B.Fab")
		)
		(fp_line
			(start -0.12065 -0.3048)
			(end -0.67945 -0.3048)
			(stroke
				(width 0.1)
				(type default)
			)
			(layer "B.Fab")
		)
		(fp_line
			(start 0.12065 -0.305054)
			(end 0.12065 -0.2794)
			(stroke
				(width 0.1)
				(type default)
			)
			(layer "B.Fab")
		)
		(fp_line
			(start 0.67945 -0.305054)
			(end 0.12065 -0.305054)
			(stroke
				(width 0.1)
				(type default)
			)
			(layer "B.Fab")
		)
		(pad "1" smd circle
			(at 0.40005 0 90)
			(size 0 0)
			(layers "B.Cu" "B.Mask" "B.Paste")
			(net "P3V3_AUX")
		)
		(pad "2" smd circle
			(at -0.40005 0 90)
			(size 0 0)
			(layers "B.Cu" "B.Mask" "B.Paste")
			(net "FM_S3M_CPU0_CPLD_CONFIG_N")
		)
	)
	(footprint ""
		(layer "B.Cu")
		(at 154.00782 -13.762228 90)
		(property "Reference" "R2415"
			(at 0 0 90)
			(layer "B.SilkS")
			(hide yes)
			(effects
				(font
					(size 1.27 1.27)
				)
				(justify mirror)
			)
		)
		(property "Value" ""
			(at 0 0 90)
			(layer "B.Fab")
			(effects
				(font
					(size 1.27 1.27)
				)
				(justify mirror)
			)
		)
		(duplicate_pad_numbers_are_jumpers no)
		(fp_line
			(start 0.7874 -0.4064)
			(end -0.7874 -0.4064)
			(stroke
				(width 0.1524)
				(type default)
			)
			(layer "B.SilkS")
		)
		(fp_line
			(start -0.7874 -0.4064)
			(end -0.7874 0.4064)
			(stroke
				(width 0.1524)
				(type default)
			)
			(layer "B.SilkS")
		)
		(fp_line
			(start 0.7874 0.4064)
			(end 0.7874 -0.4064)
			(stroke
				(width 0.1524)
				(type default)
			)
			(layer "B.SilkS")
		)
		(fp_line
			(start -0.7874 0.4064)
			(end 0.7874 0.4064)
			(stroke
				(width 0.1524)
				(type default)
			)
			(layer "B.SilkS")
		)
		(fp_line
			(start 0.67945 -0.305054)
			(end 0.12065 -0.305054)
			(stroke
				(width 0.1)
				(type default)
			)
			(layer "B.Fab")
		)
		(fp_line
			(start 0.12065 -0.305054)
			(end 0.12065 -0.2794)
			(stroke
				(width 0.1)
				(type default)
			)
			(layer "B.Fab")
		)
		(fp_line
			(start -0.12065 -0.3048)
			(end -0.67945 -0.3048)
			(stroke
				(width 0.1)
				(type default)
			)
			(layer "B.Fab")
		)
		(fp_line
			(start -0.67945 -0.3048)
			(end -0.67945 0.3048)
			(stroke
				(width 0.1)
				(type default)
			)
			(layer "B.Fab")
		)
		(fp_line
			(start 0.12065 -0.2794)
			(end -0.12065 -0.2794)
			(stroke
				(width 0.1)
				(type default)
			)
			(layer "B.Fab")
		)
		(fp_line
			(start -0.12065 -0.2794)
			(end -0.12065 -0.3048)
			(stroke
				(width 0.1)
				(type default)
			)
			(layer "B.Fab")
		)
		(fp_line
			(start 0.12065 0.2794)
			(end 0.12065 0.3048)
			(stroke
				(width 0.1)
				(type default)
			)
			(layer "B.Fab")
		)
		(fp_line
			(start -0.120396 0.2794)
			(end 0.12065 0.2794)
			(stroke
				(width 0.1)
				(type default)
			)
			(layer "B.Fab")
		)
		(fp_line
			(start 0.67945 0.3048)
			(end 0.67945 -0.305054)
			(stroke
				(width 0.1)
				(type default)
			)
			(layer "B.Fab")
		)
		(fp_line
			(start 0.12065 0.3048)
			(end 0.67945 0.3048)
			(stroke
				(width 0.1)
				(type default)
			)
			(layer "B.Fab")
		)
		(fp_line
			(start -0.120396 0.3048)
			(end -0.120396 0.2794)
			(stroke
				(width 0.1)
				(type default)
			)
			(layer "B.Fab")
		)
		(fp_line
			(start -0.67945 0.3048)
			(end -0.120396 0.3048)
			(stroke
				(width 0.1)
				(type default)
			)
			(layer "B.Fab")
		)
		(pad "1" smd circle
			(at 0.40005 0 270)
			(size 0 0)
			(layers "B.Cu" "B.Mask" "B.Paste")
			(net "SMB_1_BMC_GPU_SCL")
		)
		(pad "2" smd circle
			(at -0.40005 0 270)
			(size 0 0)
			(layers "B.Cu" "B.Mask" "B.Paste")
			(net "SMB_PCIE3_3V3AUX_SCL_R")
		)
	)
	(footprint ""
		(layer "B.Cu")
		(at 382.009904 -188.29401)
		(property "Reference" "R1216"
			(at 0 0 0)
			(layer "B.SilkS")
			(hide yes)
			(effects
				(font
					(size 1.27 1.27)
				)
				(justify mirror)
			)
		)
		(property "Value" ""
			(at 0 0 0)
			(layer "B.Fab")
			(effects
				(font
					(size 1.27 1.27)
				)
				(justify mirror)
			)
		)
		(duplicate_pad_numbers_are_jumpers no)
		(fp_line
			(start -0.7874 -0.4064)
			(end -0.7874 0.4064)
			(stroke
				(width 0.1524)
				(type default)
			)
			(layer "B.SilkS")
		)
		(fp_line
			(start -0.7874 0.4064)
			(end 0.7874 0.4064)
			(stroke
				(width 0.1524)
				(type default)
			)
			(layer "B.SilkS")
		)
		(fp_line
			(start 0.7874 -0.4064)
			(end -0.7874 -0.4064)
			(stroke
				(width 0.1524)
				(type default)
			)
			(layer "B.SilkS")
		)
		(fp_line
			(start 0.7874 0.4064)
			(end 0.7874 -0.4064)
			(stroke
				(width 0.1524)
				(type default)
			)
			(layer "B.SilkS")
		)
		(fp_line
			(start -0.67945 -0.3048)
			(end -0.67945 0.3048)
			(stroke
				(width 0.1)
				(type default)
			)
			(layer "B.Fab")
		)
		(fp_line
			(start -0.67945 0.3048)
			(end -0.120396 0.3048)
			(stroke
				(width 0.1)
				(type default)
			)
			(layer "B.Fab")
		)
		(fp_line
			(start -0.12065 -0.3048)
			(end -0.67945 -0.3048)
			(stroke
				(width 0.1)
				(type default)
			)
			(layer "B.Fab")
		)
		(fp_line
			(start -0.12065 -0.2794)
			(end -0.12065 -0.3048)
			(stroke
				(width 0.1)
				(type default)
			)
			(layer "B.Fab")
		)
		(fp_line
			(start -0.120396 0.2794)
			(end 0.12065 0.2794)
			(stroke
				(width 0.1)
				(type default)
			)
			(layer "B.Fab")
		)
		(fp_line
			(start -0.120396 0.3048)
			(end -0.120396 0.2794)
			(stroke
				(width 0.1)
				(type default)
			)
			(layer "B.Fab")
		)
		(fp_line
			(start 0.12065 -0.305054)
			(end 0.12065 -0.2794)
			(stroke
				(width 0.1)
				(type default)
			)
			(layer "B.Fab")
		)
		(fp_line
			(start 0.12065 -0.2794)
			(end -0.12065 -0.2794)
			(stroke
				(width 0.1)
				(type default)
			)
			(layer "B.Fab")
		)
		(fp_line
			(start 0.12065 0.2794)
			(end 0.12065 0.3048)
			(stroke
				(width 0.1)
				(type default)
			)
			(layer "B.Fab")
		)
		(fp_line
			(start 0.12065 0.3048)
			(end 0.67945 0.3048)
			(stroke
				(width 0.1)
				(type default)
			)
			(layer "B.Fab")
		)
		(fp_line
			(start 0.67945 -0.305054)
			(end 0.12065 -0.305054)
			(stroke
				(width 0.1)
				(type default)
			)
			(layer "B.Fab")
		)
		(fp_line
			(start 0.67945 0.3048)
			(end 0.67945 -0.305054)
			(stroke
				(width 0.1)
				(type default)
			)
			(layer "B.Fab")
		)
		(pad "1" smd circle
			(at 0.40005 0 180)
			(size 0 0)
			(layers "B.Cu" "B.Mask" "B.Paste")
			(net "P3V3_AUX")
		)
		(pad "2" smd circle
			(at -0.40005 0 180)
			(size 0 0)
			(layers "B.Cu" "B.Mask" "B.Paste")
			(net "FM_S3M_CPU0_CPLD_CRC_ERROR")
		)
	)
	(footprint ""
		(layer "B.Cu")
		(at 354.601526 -337.564984 -90)
		(property "Reference" "PC302_P0_2"
			(at 0 0 90)
			(layer "B.SilkS")
			(hide yes)
			(effects
				(font
					(size 1.27 1.27)
				)
				(justify mirror)
			)
		)
		(property "Value" ""
			(at 0 0 90)
			(layer "B.Fab")
			(effects
				(font
					(size 1.27 1.27)
				)
				(justify mirror)
			)
		)
		(duplicate_pad_numbers_are_jumpers no)
		(fp_line
			(start -1.524 0.762)
			(end 1.524 0.762)
			(stroke
				(width 0.1524)
				(type default)
			)
			(layer "B.SilkS")
		)
		(fp_line
			(start 1.524 0.762)
			(end 1.524 -0.762)
			(stroke
				(width 0.1524)
				(type default)
			)
			(layer "B.SilkS")
		)
		(fp_line
			(start -1.524 -0.762)
			(end -1.524 0.762)
			(stroke
				(width 0.1524)
				(type default)
			)
			(layer "B.SilkS")
		)
		(fp_line
			(start 1.524 -0.762)
			(end -1.524 -0.762)
			(stroke
				(width 0.1524)
				(type default)
			)
			(layer "B.SilkS")
		)
		(fp_line
			(start -1.1049 0.724916)
			(end -1.1049 -0.724916)
			(stroke
				(width 0.1)
				(type default)
			)
			(layer "B.Fab")
		)
		(fp_line
			(start 1.1049 0.724916)
			(end -1.1049 0.724916)
			(stroke
				(width 0.1)
				(type default)
			)
			(layer "B.Fab")
		)
		(fp_line
			(start -1.1049 -0.724916)
			(end 1.1049 -0.724916)
			(stroke
				(width 0.1)
				(type default)
			)
			(layer "B.Fab")
		)
		(fp_line
			(start 1.1049 -0.724916)
			(end 1.1049 0.724916)
			(stroke
				(width 0.1)
				(type default)
			)
			(layer "B.Fab")
		)
		(pad "1" smd rect
			(at 0.889 0 270)
			(size 1.016 1.27)
			(layers "B.Cu" "B.Mask" "B.Paste")
			(net "SW_P12V_PVCCIN_CPU0_FLT")
		)
		(pad "2" smd rect
			(at -0.889 0 270)
			(size 1.016 1.27)
			(layers "B.Cu" "B.Mask" "B.Paste")
			(net "GND")
		)
	)
	(footprint ""
		(layer "B.Cu")
		(at 18.613374 -176.431194 90)
		(property "Reference" "R2384"
			(at 0 0 90)
			(layer "B.SilkS")
			(hide yes)
			(effects
				(font
					(size 1.27 1.27)
				)
				(justify mirror)
			)
		)
		(property "Value" ""
			(at 0 0 90)
			(layer "B.Fab")
			(effects
				(font
					(size 1.27 1.27)
				)
				(justify mirror)
			)
		)
		(duplicate_pad_numbers_are_jumpers no)
		(fp_line
			(start 0.7874 -0.4064)
			(end -0.7874 -0.4064)
			(stroke
				(width 0.1524)
				(type default)
			)
			(layer "B.SilkS")
		)
		(fp_line
			(start -0.7874 -0.4064)
			(end -0.7874 0.4064)
			(stroke
				(width 0.1524)
				(type default)
			)
			(layer "B.SilkS")
		)
		(fp_line
			(start 0.7874 0.4064)
			(end 0.7874 -0.4064)
			(stroke
				(width 0.1524)
				(type default)
			)
			(layer "B.SilkS")
		)
		(fp_line
			(start -0.7874 0.4064)
			(end 0.7874 0.4064)
			(stroke
				(width 0.1524)
				(type default)
			)
			(layer "B.SilkS")
		)
		(fp_line
			(start 0.67945 -0.305054)
			(end 0.12065 -0.305054)
			(stroke
				(width 0.1)
				(type default)
			)
			(layer "B.Fab")
		)
		(fp_line
			(start 0.12065 -0.305054)
			(end 0.12065 -0.2794)
			(stroke
				(width 0.1)
				(type default)
			)
			(layer "B.Fab")
		)
		(fp_line
			(start -0.12065 -0.3048)
			(end -0.67945 -0.3048)
			(stroke
				(width 0.1)
				(type default)
			)
			(layer "B.Fab")
		)
		(fp_line
			(start -0.67945 -0.3048)
			(end -0.67945 0.3048)
			(stroke
				(width 0.1)
				(type default)
			)
			(layer "B.Fab")
		)
		(fp_line
			(start 0.12065 -0.2794)
			(end -0.12065 -0.2794)
			(stroke
				(width 0.1)
				(type default)
			)
			(layer "B.Fab")
		)
		(fp_line
			(start -0.12065 -0.2794)
			(end -0.12065 -0.3048)
			(stroke
				(width 0.1)
				(type default)
			)
			(layer "B.Fab")
		)
		(fp_line
			(start 0.12065 0.2794)
			(end 0.12065 0.3048)
			(stroke
				(width 0.1)
				(type default)
			)
			(layer "B.Fab")
		)
		(fp_line
			(start -0.120396 0.2794)
			(end 0.12065 0.2794)
			(stroke
				(width 0.1)
				(type default)
			)
			(layer "B.Fab")
		)
		(fp_line
			(start 0.67945 0.3048)
			(end 0.67945 -0.305054)
			(stroke
				(width 0.1)
				(type default)
			)
			(layer "B.Fab")
		)
		(fp_line
			(start 0.12065 0.3048)
			(end 0.67945 0.3048)
			(stroke
				(width 0.1)
				(type default)
			)
			(layer "B.Fab")
		)
		(fp_line
			(start -0.120396 0.3048)
			(end -0.120396 0.2794)
			(stroke
				(width 0.1)
				(type default)
			)
			(layer "B.Fab")
		)
		(fp_line
			(start -0.67945 0.3048)
			(end -0.120396 0.3048)
			(stroke
				(width 0.1)
				(type default)
			)
			(layer "B.Fab")
		)
		(pad "1" smd circle
			(at 0.40005 0 270)
			(size 0 0)
			(layers "B.Cu" "B.Mask" "B.Paste")
			(net "P3V3_AUX")
		)
		(pad "2" smd circle
			(at -0.40005 0 270)
			(size 0 0)
			(layers "B.Cu" "B.Mask" "B.Paste")
			(net "FM_PVNN_MAIN_CPU1_EN")
		)
	)
	(footprint ""
		(layer "B.Cu")
		(at 240.3094 -422.9862 90)
		(property "Reference" "C2296"
			(at 0 0 90)
			(layer "B.SilkS")
			(hide yes)
			(effects
				(font
					(size 1.27 1.27)
				)
				(justify mirror)
			)
		)
		(property "Value" ""
			(at 0 0 90)
			(layer "B.Fab")
			(effects
				(font
					(size 1.27 1.27)
				)
				(justify mirror)
			)
		)
		(duplicate_pad_numbers_are_jumpers no)
		(fp_line
			(start 0.7874 -0.4064)
			(end -0.7874 -0.4064)
			(stroke
				(width 0.1524)
				(type default)
			)
			(layer "B.SilkS")
		)
		(fp_line
			(start -0.7874 -0.4064)
			(end -0.7874 0.4064)
			(stroke
				(width 0.1524)
				(type default)
			)
			(layer "B.SilkS")
		)
		(fp_line
			(start 0.7874 0.4064)
			(end 0.7874 -0.4064)
			(stroke
				(width 0.1524)
				(type default)
			)
			(layer "B.SilkS")
		)
		(fp_line
			(start -0.7874 0.4064)
			(end 0.7874 0.4064)
			(stroke
				(width 0.1524)
				(type default)
			)
			(layer "B.SilkS")
		)
		(fp_line
			(start 0.67945 -0.305054)
			(end 0.12065 -0.305054)
			(stroke
				(width 0.1)
				(type default)
			)
			(layer "B.Fab")
		)
		(fp_line
			(start 0.12065 -0.305054)
			(end 0.12065 -0.2794)
			(stroke
				(width 0.1)
				(type default)
			)
			(layer "B.Fab")
		)
		(fp_line
			(start -0.12065 -0.3048)
			(end -0.67945 -0.3048)
			(stroke
				(width 0.1)
				(type default)
			)
			(layer "B.Fab")
		)
		(fp_line
			(start -0.67945 -0.3048)
			(end -0.67945 0.3048)
			(stroke
				(width 0.1)
				(type default)
			)
			(layer "B.Fab")
		)
		(fp_line
			(start 0.12065 -0.2794)
			(end -0.12065 -0.2794)
			(stroke
				(width 0.1)
				(type default)
			)
			(layer "B.Fab")
		)
		(fp_line
			(start -0.12065 -0.2794)
			(end -0.12065 -0.3048)
			(stroke
				(width 0.1)
				(type default)
			)
			(layer "B.Fab")
		)
		(fp_line
			(start 0.12065 0.2794)
			(end 0.12065 0.3048)
			(stroke
				(width 0.1)
				(type default)
			)
			(layer "B.Fab")
		)
		(fp_line
			(start -0.120396 0.2794)
			(end 0.12065 0.2794)
			(stroke
				(width 0.1)
				(type default)
			)
			(layer "B.Fab")
		)
		(fp_line
			(start 0.67945 0.3048)
			(end 0.67945 -0.305054)
			(stroke
				(width 0.1)
				(type default)
			)
			(layer "B.Fab")
		)
		(fp_line
			(start 0.12065 0.3048)
			(end 0.67945 0.3048)
			(stroke
				(width 0.1)
				(type default)
			)
			(layer "B.Fab")
		)
		(fp_line
			(start -0.120396 0.3048)
			(end -0.120396 0.2794)
			(stroke
				(width 0.1)
				(type default)
			)
			(layer "B.Fab")
		)
		(fp_line
			(start -0.67945 0.3048)
			(end -0.120396 0.3048)
			(stroke
				(width 0.1)
				(type default)
			)
			(layer "B.Fab")
		)
		(pad "1" smd circle
			(at 0.40005 0 270)
			(size 0 0)
			(layers "B.Cu" "B.Mask" "B.Paste")
			(net "FM_FAN_PWR_EN_R")
		)
		(pad "2" smd circle
			(at -0.40005 0 270)
			(size 0 0)
			(layers "B.Cu" "B.Mask" "B.Paste")
			(net "GND")
		)
	)
	(footprint ""
		(layer "B.Cu")
		(at 114.440462 -333.73568 90)
		(property "Reference" "PC536_P1_3"
			(at 0 0 90)
			(layer "B.SilkS")
			(hide yes)
			(effects
				(font
					(size 1.27 1.27)
				)
				(justify mirror)
			)
		)
		(property "Value" ""
			(at 0 0 90)
			(layer "B.Fab")
			(effects
				(font
					(size 1.27 1.27)
				)
				(justify mirror)
			)
		)
		(duplicate_pad_numbers_are_jumpers no)
		(fp_line
			(start 1.524 -0.762)
			(end -1.524 -0.762)
			(stroke
				(width 0.1524)
				(type default)
			)
			(layer "B.SilkS")
		)
		(fp_line
			(start -1.524 -0.762)
			(end -1.524 0.762)
			(stroke
				(width 0.1524)
				(type default)
			)
			(layer "B.SilkS")
		)
		(fp_line
			(start 1.524 0.762)
			(end 1.524 -0.762)
			(stroke
				(width 0.1524)
				(type default)
			)
			(layer "B.SilkS")
		)
		(fp_line
			(start -1.524 0.762)
			(end 1.524 0.762)
			(stroke
				(width 0.1524)
				(type default)
			)
			(layer "B.SilkS")
		)
		(fp_line
			(start 1.1049 -0.724916)
			(end 1.1049 0.724916)
			(stroke
				(width 0.1)
				(type default)
			)
			(layer "B.Fab")
		)
		(fp_line
			(start -1.1049 -0.724916)
			(end 1.1049 -0.724916)
			(stroke
				(width 0.1)
				(type default)
			)
			(layer "B.Fab")
		)
		(fp_line
			(start 1.1049 0.724916)
			(end -1.1049 0.724916)
			(stroke
				(width 0.1)
				(type default)
			)
			(layer "B.Fab")
		)
		(fp_line
			(start -1.1049 0.724916)
			(end -1.1049 -0.724916)
			(stroke
				(width 0.1)
				(type default)
			)
			(layer "B.Fab")
		)
		(pad "1" smd rect
			(at 0.889 0 90)
			(size 1.016 1.27)
			(layers "B.Cu" "B.Mask" "B.Paste")
			(net "SW_P12V_PVCCIN_CPU1_FLT")
		)
		(pad "2" smd rect
			(at -0.889 0 90)
			(size 1.016 1.27)
			(layers "B.Cu" "B.Mask" "B.Paste")
			(net "GND")
		)
	)
	(footprint ""
		(layer "B.Cu")
		(at 24.352504 -175.819562 90)
		(property "Reference" "R2387"
			(at 0 0 90)
			(layer "B.SilkS")
			(hide yes)
			(effects
				(font
					(size 1.27 1.27)
				)
				(justify mirror)
			)
		)
		(property "Value" ""
			(at 0 0 90)
			(layer "B.Fab")
			(effects
				(font
					(size 1.27 1.27)
				)
				(justify mirror)
			)
		)
		(duplicate_pad_numbers_are_jumpers no)
		(fp_line
			(start 0.7874 -0.4064)
			(end -0.7874 -0.4064)
			(stroke
				(width 0.1524)
				(type default)
			)
			(layer "B.SilkS")
		)
		(fp_line
			(start -0.7874 -0.4064)
			(end -0.7874 0.4064)
			(stroke
				(width 0.1524)
				(type default)
			)
			(layer "B.SilkS")
		)
		(fp_line
			(start 0.7874 0.4064)
			(end 0.7874 -0.4064)
			(stroke
				(width 0.1524)
				(type default)
			)
			(layer "B.SilkS")
		)
		(fp_line
			(start -0.7874 0.4064)
			(end 0.7874 0.4064)
			(stroke
				(width 0.1524)
				(type default)
			)
			(layer "B.SilkS")
		)
		(fp_line
			(start 0.67945 -0.305054)
			(end 0.12065 -0.305054)
			(stroke
				(width 0.1)
				(type default)
			)
			(layer "B.Fab")
		)
		(fp_line
			(start 0.12065 -0.305054)
			(end 0.12065 -0.2794)
			(stroke
				(width 0.1)
				(type default)
			)
			(layer "B.Fab")
		)
		(fp_line
			(start -0.12065 -0.3048)
			(end -0.67945 -0.3048)
			(stroke
				(width 0.1)
				(type default)
			)
			(layer "B.Fab")
		)
		(fp_line
			(start -0.67945 -0.3048)
			(end -0.67945 0.3048)
			(stroke
				(width 0.1)
				(type default)
			)
			(layer "B.Fab")
		)
		(fp_line
			(start 0.12065 -0.2794)
			(end -0.12065 -0.2794)
			(stroke
				(width 0.1)
				(type default)
			)
			(layer "B.Fab")
		)
		(fp_line
			(start -0.12065 -0.2794)
			(end -0.12065 -0.3048)
			(stroke
				(width 0.1)
				(type default)
			)
			(layer "B.Fab")
		)
		(fp_line
			(start 0.12065 0.2794)
			(end 0.12065 0.3048)
			(stroke
				(width 0.1)
				(type default)
			)
			(layer "B.Fab")
		)
		(fp_line
			(start -0.120396 0.2794)
			(end 0.12065 0.2794)
			(stroke
				(width 0.1)
				(type default)
			)
			(layer "B.Fab")
		)
		(fp_line
			(start 0.67945 0.3048)
			(end 0.67945 -0.305054)
			(stroke
				(width 0.1)
				(type default)
			)
			(layer "B.Fab")
		)
		(fp_line
			(start 0.12065 0.3048)
			(end 0.67945 0.3048)
			(stroke
				(width 0.1)
				(type default)
			)
			(layer "B.Fab")
		)
		(fp_line
			(start -0.120396 0.3048)
			(end -0.120396 0.2794)
			(stroke
				(width 0.1)
				(type default)
			)
			(layer "B.Fab")
		)
		(fp_line
			(start -0.67945 0.3048)
			(end -0.120396 0.3048)
			(stroke
				(width 0.1)
				(type default)
			)
			(layer "B.Fab")
		)
		(pad "1" smd circle
			(at 0.40005 0 270)
			(size 0 0)
			(layers "B.Cu" "B.Mask" "B.Paste")
			(net "PWRGD_PVNN_MAIN_CPU1_R")
		)
		(pad "2" smd circle
			(at -0.40005 0 270)
			(size 0 0)
			(layers "B.Cu" "B.Mask" "B.Paste")
			(net "PWRGD_PVNN_MAIN_CPU1")
		)
	)
	(footprint ""
		(layer "B.Cu")
		(at 260.157214 -321.549776 -90)
		(property "Reference" "C21"
			(at 0 0 90)
			(layer "B.SilkS")
			(hide yes)
			(effects
				(font
					(size 1.27 1.27)
				)
				(justify mirror)
			)
		)
		(property "Value" ""
			(at 0 0 90)
			(layer "B.Fab")
			(effects
				(font
					(size 1.27 1.27)
				)
				(justify mirror)
			)
		)
		(duplicate_pad_numbers_are_jumpers no)
		(fp_line
			(start -1.524 0.762)
			(end 1.524 0.762)
			(stroke
				(width 0.1524)
				(type default)
			)
			(layer "B.SilkS")
		)
		(fp_line
			(start 1.524 0.762)
			(end 1.524 -0.762)
			(stroke
				(width 0.1524)
				(type default)
			)
			(layer "B.SilkS")
		)
		(fp_line
			(start -1.524 -0.762)
			(end -1.524 0.762)
			(stroke
				(width 0.1524)
				(type default)
			)
			(layer "B.SilkS")
		)
		(fp_line
			(start 1.524 -0.762)
			(end -1.524 -0.762)
			(stroke
				(width 0.1524)
				(type default)
			)
			(layer "B.SilkS")
		)
		(fp_line
			(start -1.1049 0.724916)
			(end -1.1049 -0.724916)
			(stroke
				(width 0.1)
				(type default)
			)
			(layer "B.Fab")
		)
		(fp_line
			(start 1.1049 0.724916)
			(end -1.1049 0.724916)
			(stroke
				(width 0.1)
				(type default)
			)
			(layer "B.Fab")
		)
		(fp_line
			(start -1.1049 -0.724916)
			(end 1.1049 -0.724916)
			(stroke
				(width 0.1)
				(type default)
			)
			(layer "B.Fab")
		)
		(fp_line
			(start 1.1049 -0.724916)
			(end 1.1049 0.724916)
			(stroke
				(width 0.1)
				(type default)
			)
			(layer "B.Fab")
		)
		(pad "1" smd rect
			(at 0.889 0 270)
			(size 1.016 1.27)
			(layers "B.Cu" "B.Mask" "B.Paste")
			(net "P12V_S3_AUX_CPU0_NVDIMM")
		)
		(pad "2" smd rect
			(at -0.889 0 270)
			(size 1.016 1.27)
			(layers "B.Cu" "B.Mask" "B.Paste")
			(net "GND")
		)
	)
	(footprint ""
		(layer "B.Cu")
		(at 269.179294 -64.432434)
		(property "Reference" "PC1229"
			(at 0 0 0)
			(layer "B.SilkS")
			(hide yes)
			(effects
				(font
					(size 1.27 1.27)
				)
				(justify mirror)
			)
		)
		(property "Value" ""
			(at 0 0 0)
			(layer "B.Fab")
			(effects
				(font
					(size 1.27 1.27)
				)
				(justify mirror)
			)
		)
		(duplicate_pad_numbers_are_jumpers no)
		(fp_line
			(start -4.53898 -2.15011)
			(end -4.53898 2.15011)
			(stroke
				(width 0.1524)
				(type default)
			)
			(layer "B.SilkS")
		)
		(fp_line
			(start -4.53898 2.15011)
			(end 4.53898 2.15011)
			(stroke
				(width 0.1524)
				(type default)
			)
			(layer "B.SilkS")
		)
		(fp_line
			(start 4.53898 -2.150618)
			(end 4.539742 2.152142)
			(stroke
				(width 0.1524)
				(type default)
			)
			(layer "B.SilkS")
		)
		(fp_line
			(start 4.53898 -2.15011)
			(end -4.53898 -2.15011)
			(stroke
				(width 0.1524)
				(type default)
			)
			(layer "B.SilkS")
		)
		(fp_line
			(start 4.53898 2.15011)
			(end 4.53898 -2.15011)
			(stroke
				(width 0.1524)
				(type default)
			)
			(layer "B.SilkS")
		)
		(fp_line
			(start 4.69138 -2.150618)
			(end 4.692396 2.161032)
			(stroke
				(width 0.1524)
				(type default)
			)
			(layer "B.SilkS")
		)
		(fp_line
			(start 4.83108 2.150364)
			(end 4.447794 2.149348)
			(stroke
				(width 0.1524)
				(type default)
			)
			(layer "B.SilkS")
		)
		(fp_line
			(start 4.84378 -2.150618)
			(end 4.53898 -2.150618)
			(stroke
				(width 0.1524)
				(type default)
			)
			(layer "B.SilkS")
		)
		(fp_line
			(start 4.84378 -2.150618)
			(end 4.842256 2.163064)
			(stroke
				(width 0.1524)
				(type default)
			)
			(layer "B.SilkS")
		)
		(fp_line
			(start -3.64998 -2.15011)
			(end -3.64998 2.15011)
			(stroke
				(width 0.1)
				(type default)
			)
			(layer "B.Fab")
		)
		(fp_line
			(start -3.64998 2.15011)
			(end 3.64998 2.15011)
			(stroke
				(width 0.1)
				(type default)
			)
			(layer "B.Fab")
		)
		(fp_line
			(start 3.64998 -2.15011)
			(end -3.64998 -2.15011)
			(stroke
				(width 0.1)
				(type default)
			)
			(layer "B.Fab")
		)
		(fp_line
			(start 3.64998 2.15011)
			(end 3.64998 -2.15011)
			(stroke
				(width 0.1)
				(type default)
			)
			(layer "B.Fab")
		)
		(fp_text user "-"
			(at -4.658614 2.955036 0)
			(unlocked yes)
			(layer "B.SilkS")
			(effects
				(font
					(size 1.905 1.4224)
					(thickness 0.1524)
				)
				(justify left mirror)
			)
		)
		(fp_text user "+"
			(at 6.214872 -0.337058 0)
			(unlocked yes)
			(layer "B.SilkS")
			(effects
				(font
					(size 1.905 1.4224)
					(thickness 0.1524)
				)
				(justify left mirror)
			)
		)
		(fp_text user "-"
			(at -4.313174 -0.094488 0)
			(unlocked yes)
			(layer "B.Fab")
			(effects
				(font
					(size 1.905 1.4224)
					(thickness 0.1524)
				)
				(justify left mirror)
			)
		)
		(fp_text user "+"
			(at 6.214872 -0.337058 0)
			(unlocked yes)
			(layer "B.Fab")
			(effects
				(font
					(size 1.905 1.4224)
					(thickness 0.1524)
				)
				(justify left mirror)
			)
		)
		(pad "1" smd rect
			(at 3.199892 0 180)
			(size 2.413 2.8194)
			(layers "B.Cu" "B.Mask" "B.Paste")
			(net "P1V05_PCH_AUX")
		)
		(pad "2" smd rect
			(at -3.199892 0 180)
			(size 2.413 2.8194)
			(layers "B.Cu" "B.Mask" "B.Paste")
			(net "GND")
		)
	)
	(footprint ""
		(layer "B.Cu")
		(at 115.66652 -355.925628)
		(property "Reference" "R2524"
			(at 0 0 0)
			(layer "B.SilkS")
			(hide yes)
			(effects
				(font
					(size 1.27 1.27)
				)
				(justify mirror)
			)
		)
		(property "Value" ""
			(at 0 0 0)
			(layer "B.Fab")
			(effects
				(font
					(size 1.27 1.27)
				)
				(justify mirror)
			)
		)
		(duplicate_pad_numbers_are_jumpers no)
		(fp_line
			(start -0.7874 -0.4064)
			(end -0.7874 0.4064)
			(stroke
				(width 0.1524)
				(type default)
			)
			(layer "B.SilkS")
		)
		(fp_line
			(start -0.7874 0.4064)
			(end 0.7874 0.4064)
			(stroke
				(width 0.1524)
				(type default)
			)
			(layer "B.SilkS")
		)
		(fp_line
			(start 0.7874 -0.4064)
			(end -0.7874 -0.4064)
			(stroke
				(width 0.1524)
				(type default)
			)
			(layer "B.SilkS")
		)
		(fp_line
			(start 0.7874 0.4064)
			(end 0.7874 -0.4064)
			(stroke
				(width 0.1524)
				(type default)
			)
			(layer "B.SilkS")
		)
		(fp_line
			(start -0.67945 -0.3048)
			(end -0.67945 0.3048)
			(stroke
				(width 0.1)
				(type default)
			)
			(layer "B.Fab")
		)
		(fp_line
			(start -0.67945 0.3048)
			(end -0.120396 0.3048)
			(stroke
				(width 0.1)
				(type default)
			)
			(layer "B.Fab")
		)
		(fp_line
			(start -0.12065 -0.3048)
			(end -0.67945 -0.3048)
			(stroke
				(width 0.1)
				(type default)
			)
			(layer "B.Fab")
		)
		(fp_line
			(start -0.12065 -0.2794)
			(end -0.12065 -0.3048)
			(stroke
				(width 0.1)
				(type default)
			)
			(layer "B.Fab")
		)
		(fp_line
			(start -0.120396 0.2794)
			(end 0.12065 0.2794)
			(stroke
				(width 0.1)
				(type default)
			)
			(layer "B.Fab")
		)
		(fp_line
			(start -0.120396 0.3048)
			(end -0.120396 0.2794)
			(stroke
				(width 0.1)
				(type default)
			)
			(layer "B.Fab")
		)
		(fp_line
			(start 0.12065 -0.305054)
			(end 0.12065 -0.2794)
			(stroke
				(width 0.1)
				(type default)
			)
			(layer "B.Fab")
		)
		(fp_line
			(start 0.12065 -0.2794)
			(end -0.12065 -0.2794)
			(stroke
				(width 0.1)
				(type default)
			)
			(layer "B.Fab")
		)
		(fp_line
			(start 0.12065 0.2794)
			(end 0.12065 0.3048)
			(stroke
				(width 0.1)
				(type default)
			)
			(layer "B.Fab")
		)
		(fp_line
			(start 0.12065 0.3048)
			(end 0.67945 0.3048)
			(stroke
				(width 0.1)
				(type default)
			)
			(layer "B.Fab")
		)
		(fp_line
			(start 0.67945 -0.305054)
			(end 0.12065 -0.305054)
			(stroke
				(width 0.1)
				(type default)
			)
			(layer "B.Fab")
		)
		(fp_line
			(start 0.67945 0.3048)
			(end 0.67945 -0.305054)
			(stroke
				(width 0.1)
				(type default)
			)
			(layer "B.Fab")
		)
		(pad "1" smd circle
			(at 0.40005 0 180)
			(size 0 0)
			(layers "B.Cu" "B.Mask" "B.Paste")
			(net "P3V3_AUX")
		)
		(pad "2" smd circle
			(at -0.40005 0 180)
			(size 0 0)
			(layers "B.Cu" "B.Mask" "B.Paste")
			(net "PVCCIN_CPU1_VR_FAULT")
		)
	)
	(footprint ""
		(layer "B.Cu")
		(at 252.222 -99.405948 180)
		(property "Reference" "C120"
			(at 0 0 0)
			(layer "B.SilkS")
			(hide yes)
			(effects
				(font
					(size 1.27 1.27)
				)
				(justify mirror)
			)
		)
		(property "Value" ""
			(at 0 0 0)
			(layer "B.Fab")
			(effects
				(font
					(size 1.27 1.27)
				)
				(justify mirror)
			)
		)
		(duplicate_pad_numbers_are_jumpers no)
		(fp_line
			(start 0.7874 0.4064)
			(end 0.7874 -0.4064)
			(stroke
				(width 0.1524)
				(type default)
			)
			(layer "B.SilkS")
		)
		(fp_line
			(start 0.7874 -0.4064)
			(end -0.7874 -0.4064)
			(stroke
				(width 0.1524)
				(type default)
			)
			(layer "B.SilkS")
		)
		(fp_line
			(start -0.7874 0.4064)
			(end 0.7874 0.4064)
			(stroke
				(width 0.1524)
				(type default)
			)
			(layer "B.SilkS")
		)
		(fp_line
			(start -0.7874 -0.4064)
			(end -0.7874 0.4064)
			(stroke
				(width 0.1524)
				(type default)
			)
			(layer "B.SilkS")
		)
		(fp_line
			(start 0.67945 0.3048)
			(end 0.67945 -0.305054)
			(stroke
				(width 0.1)
				(type default)
			)
			(layer "B.Fab")
		)
		(fp_line
			(start 0.67945 -0.305054)
			(end 0.12065 -0.305054)
			(stroke
				(width 0.1)
				(type default)
			)
			(layer "B.Fab")
		)
		(fp_line
			(start 0.12065 0.3048)
			(end 0.67945 0.3048)
			(stroke
				(width 0.1)
				(type default)
			)
			(layer "B.Fab")
		)
		(fp_line
			(start 0.12065 0.2794)
			(end 0.12065 0.3048)
			(stroke
				(width 0.1)
				(type default)
			)
			(layer "B.Fab")
		)
		(fp_line
			(start 0.12065 -0.2794)
			(end -0.12065 -0.2794)
			(stroke
				(width 0.1)
				(type default)
			)
			(layer "B.Fab")
		)
		(fp_line
			(start 0.12065 -0.305054)
			(end 0.12065 -0.2794)
			(stroke
				(width 0.1)
				(type default)
			)
			(layer "B.Fab")
		)
		(fp_line
			(start -0.120396 0.3048)
			(end -0.120396 0.2794)
			(stroke
				(width 0.1)
				(type default)
			)
			(layer "B.Fab")
		)
		(fp_line
			(start -0.120396 0.2794)
			(end 0.12065 0.2794)
			(stroke
				(width 0.1)
				(type default)
			)
			(layer "B.Fab")
		)
		(fp_line
			(start -0.12065 -0.2794)
			(end -0.12065 -0.3048)
			(stroke
				(width 0.1)
				(type default)
			)
			(layer "B.Fab")
		)
		(fp_line
			(start -0.12065 -0.3048)
			(end -0.67945 -0.3048)
			(stroke
				(width 0.1)
				(type default)
			)
			(layer "B.Fab")
		)
		(fp_line
			(start -0.67945 0.3048)
			(end -0.120396 0.3048)
			(stroke
				(width 0.1)
				(type default)
			)
			(layer "B.Fab")
		)
		(fp_line
			(start -0.67945 -0.3048)
			(end -0.67945 0.3048)
			(stroke
				(width 0.1)
				(type default)
			)
			(layer "B.Fab")
		)
		(pad "1" smd circle
			(at 0.40005 0)
			(size 0 0)
			(layers "B.Cu" "B.Mask" "B.Paste")
			(net "P3V3_AUX_CLK_GEN_VDDPT_CK440")
		)
		(pad "2" smd circle
			(at -0.40005 0)
			(size 0 0)
			(layers "B.Cu" "B.Mask" "B.Paste")
			(net "GND")
		)
	)
	(footprint ""
		(layer "B.Cu")
		(at 100.969572 -324.753986 -90)
		(property "Reference" "PC577_P1_2"
			(at 0 0 90)
			(layer "B.SilkS")
			(hide yes)
			(effects
				(font
					(size 1.27 1.27)
				)
				(justify mirror)
			)
		)
		(property "Value" ""
			(at 0 0 90)
			(layer "B.Fab")
			(effects
				(font
					(size 1.27 1.27)
				)
				(justify mirror)
			)
		)
		(duplicate_pad_numbers_are_jumpers no)
		(fp_line
			(start -1.524 0.762)
			(end 1.524 0.762)
			(stroke
				(width 0.1524)
				(type default)
			)
			(layer "B.SilkS")
		)
		(fp_line
			(start 1.524 0.762)
			(end 1.524 -0.762)
			(stroke
				(width 0.1524)
				(type default)
			)
			(layer "B.SilkS")
		)
		(fp_line
			(start -1.524 -0.762)
			(end -1.524 0.762)
			(stroke
				(width 0.1524)
				(type default)
			)
			(layer "B.SilkS")
		)
		(fp_line
			(start 1.524 -0.762)
			(end -1.524 -0.762)
			(stroke
				(width 0.1524)
				(type default)
			)
			(layer "B.SilkS")
		)
		(fp_line
			(start -1.1049 0.724916)
			(end -1.1049 -0.724916)
			(stroke
				(width 0.1)
				(type default)
			)
			(layer "B.Fab")
		)
		(fp_line
			(start 1.1049 0.724916)
			(end -1.1049 0.724916)
			(stroke
				(width 0.1)
				(type default)
			)
			(layer "B.Fab")
		)
		(fp_line
			(start -1.1049 -0.724916)
			(end 1.1049 -0.724916)
			(stroke
				(width 0.1)
				(type default)
			)
			(layer "B.Fab")
		)
		(fp_line
			(start 1.1049 -0.724916)
			(end 1.1049 0.724916)
			(stroke
				(width 0.1)
				(type default)
			)
			(layer "B.Fab")
		)
		(pad "1" smd rect
			(at 0.889 0 270)
			(size 1.016 1.27)
			(layers "B.Cu" "B.Mask" "B.Paste")
			(net "PVCCIN_CPU1")
		)
		(pad "2" smd rect
			(at -0.889 0 270)
			(size 1.016 1.27)
			(layers "B.Cu" "B.Mask" "B.Paste")
			(net "GND")
		)
	)
	(footprint ""
		(layer "B.Cu")
		(at 103.901494 -255.8542 90)
		(property "Reference" "C452"
			(at 0 0 90)
			(layer "B.SilkS")
			(hide yes)
			(effects
				(font
					(size 1.27 1.27)
				)
				(justify mirror)
			)
		)
		(property "Value" ""
			(at 0 0 90)
			(layer "B.Fab")
			(effects
				(font
					(size 1.27 1.27)
				)
				(justify mirror)
			)
		)
		(duplicate_pad_numbers_are_jumpers no)
		(fp_line
			(start 1.524 -0.762)
			(end -1.524 -0.762)
			(stroke
				(width 0.1524)
				(type default)
			)
			(layer "B.SilkS")
		)
		(fp_line
			(start -1.524 -0.762)
			(end -1.524 0.762)
			(stroke
				(width 0.1524)
				(type default)
			)
			(layer "B.SilkS")
		)
		(fp_line
			(start 1.524 0.762)
			(end 1.524 -0.762)
			(stroke
				(width 0.1524)
				(type default)
			)
			(layer "B.SilkS")
		)
		(fp_line
			(start -1.524 0.762)
			(end 1.524 0.762)
			(stroke
				(width 0.1524)
				(type default)
			)
			(layer "B.SilkS")
		)
		(fp_line
			(start 1.1049 -0.724916)
			(end 1.1049 0.724916)
			(stroke
				(width 0.1)
				(type default)
			)
			(layer "B.Fab")
		)
		(fp_line
			(start -1.1049 -0.724916)
			(end 1.1049 -0.724916)
			(stroke
				(width 0.1)
				(type default)
			)
			(layer "B.Fab")
		)
		(fp_line
			(start 1.1049 0.724916)
			(end -1.1049 0.724916)
			(stroke
				(width 0.1)
				(type default)
			)
			(layer "B.Fab")
		)
		(fp_line
			(start -1.1049 0.724916)
			(end -1.1049 -0.724916)
			(stroke
				(width 0.1)
				(type default)
			)
			(layer "B.Fab")
		)
		(pad "1" smd rect
			(at 0.889 0 90)
			(size 1.016 1.27)
			(layers "B.Cu" "B.Mask" "B.Paste")
			(net "PVCCFA_EHV_CPU1")
		)
		(pad "2" smd rect
			(at -0.889 0 90)
			(size 1.016 1.27)
			(layers "B.Cu" "B.Mask" "B.Paste")
			(net "GND")
		)
	)
	(footprint ""
		(layer "B.Cu")
		(at 418.570664 -183.327294 180)
		(property "Reference" "PR1777"
			(at 0 0 0)
			(layer "B.SilkS")
			(hide yes)
			(effects
				(font
					(size 1.27 1.27)
				)
				(justify mirror)
			)
		)
		(property "Value" ""
			(at 0 0 0)
			(layer "B.Fab")
			(effects
				(font
					(size 1.27 1.27)
				)
				(justify mirror)
			)
		)
		(duplicate_pad_numbers_are_jumpers no)
		(fp_line
			(start 0.7874 0.4064)
			(end 0.7874 -0.4064)
			(stroke
				(width 0.1524)
				(type default)
			)
			(layer "B.SilkS")
		)
		(fp_line
			(start 0.7874 -0.4064)
			(end -0.7874 -0.4064)
			(stroke
				(width 0.1524)
				(type default)
			)
			(layer "B.SilkS")
		)
		(fp_line
			(start -0.7874 0.4064)
			(end 0.7874 0.4064)
			(stroke
				(width 0.1524)
				(type default)
			)
			(layer "B.SilkS")
		)
		(fp_line
			(start -0.7874 -0.4064)
			(end -0.7874 0.4064)
			(stroke
				(width 0.1524)
				(type default)
			)
			(layer "B.SilkS")
		)
		(fp_line
			(start 0.67945 0.3048)
			(end 0.67945 -0.305054)
			(stroke
				(width 0.1)
				(type default)
			)
			(layer "B.Fab")
		)
		(fp_line
			(start 0.67945 -0.305054)
			(end 0.12065 -0.305054)
			(stroke
				(width 0.1)
				(type default)
			)
			(layer "B.Fab")
		)
		(fp_line
			(start 0.12065 0.3048)
			(end 0.67945 0.3048)
			(stroke
				(width 0.1)
				(type default)
			)
			(layer "B.Fab")
		)
		(fp_line
			(start 0.12065 0.2794)
			(end 0.12065 0.3048)
			(stroke
				(width 0.1)
				(type default)
			)
			(layer "B.Fab")
		)
		(fp_line
			(start 0.12065 -0.2794)
			(end -0.12065 -0.2794)
			(stroke
				(width 0.1)
				(type default)
			)
			(layer "B.Fab")
		)
		(fp_line
			(start 0.12065 -0.305054)
			(end 0.12065 -0.2794)
			(stroke
				(width 0.1)
				(type default)
			)
			(layer "B.Fab")
		)
		(fp_line
			(start -0.120396 0.3048)
			(end -0.120396 0.2794)
			(stroke
				(width 0.1)
				(type default)
			)
			(layer "B.Fab")
		)
		(fp_line
			(start -0.120396 0.2794)
			(end 0.12065 0.2794)
			(stroke
				(width 0.1)
				(type default)
			)
			(layer "B.Fab")
		)
		(fp_line
			(start -0.12065 -0.2794)
			(end -0.12065 -0.3048)
			(stroke
				(width 0.1)
				(type default)
			)
			(layer "B.Fab")
		)
		(fp_line
			(start -0.12065 -0.3048)
			(end -0.67945 -0.3048)
			(stroke
				(width 0.1)
				(type default)
			)
			(layer "B.Fab")
		)
		(fp_line
			(start -0.67945 0.3048)
			(end -0.120396 0.3048)
			(stroke
				(width 0.1)
				(type default)
			)
			(layer "B.Fab")
		)
		(fp_line
			(start -0.67945 -0.3048)
			(end -0.67945 0.3048)
			(stroke
				(width 0.1)
				(type default)
			)
			(layer "B.Fab")
		)
		(pad "1" smd circle
			(at 0.40005 0)
			(size 0 0)
			(layers "B.Cu" "B.Mask" "B.Paste")
			(net "PVCCINFAON_CPU0_VOS2")
		)
		(pad "2" smd circle
			(at -0.40005 0)
			(size 0 0)
			(layers "B.Cu" "B.Mask" "B.Paste")
			(net "PVCCINFAON_CPU0")
		)
	)
	(footprint ""
		(layer "B.Cu")
		(at 446.780158 -177.78476 180)
		(property "Reference" "C1400"
			(at 0 0 0)
			(layer "B.SilkS")
			(hide yes)
			(effects
				(font
					(size 1.27 1.27)
				)
				(justify mirror)
			)
		)
		(property "Value" ""
			(at 0 0 0)
			(layer "B.Fab")
			(effects
				(font
					(size 1.27 1.27)
				)
				(justify mirror)
			)
		)
		(duplicate_pad_numbers_are_jumpers no)
		(fp_line
			(start 1.524 0.762)
			(end 1.524 -0.762)
			(stroke
				(width 0.1524)
				(type default)
			)
			(layer "B.SilkS")
		)
		(fp_line
			(start 1.524 -0.762)
			(end -1.524 -0.762)
			(stroke
				(width 0.1524)
				(type default)
			)
			(layer "B.SilkS")
		)
		(fp_line
			(start -1.524 0.762)
			(end 1.524 0.762)
			(stroke
				(width 0.1524)
				(type default)
			)
			(layer "B.SilkS")
		)
		(fp_line
			(start -1.524 -0.762)
			(end -1.524 0.762)
			(stroke
				(width 0.1524)
				(type default)
			)
			(layer "B.SilkS")
		)
		(fp_line
			(start 1.1049 0.724916)
			(end -1.1049 0.724916)
			(stroke
				(width 0.1)
				(type default)
			)
			(layer "B.Fab")
		)
		(fp_line
			(start 1.1049 -0.724916)
			(end 1.1049 0.724916)
			(stroke
				(width 0.1)
				(type default)
			)
			(layer "B.Fab")
		)
		(fp_line
			(start -1.1049 0.724916)
			(end -1.1049 -0.724916)
			(stroke
				(width 0.1)
				(type default)
			)
			(layer "B.Fab")
		)
		(fp_line
			(start -1.1049 -0.724916)
			(end 1.1049 -0.724916)
			(stroke
				(width 0.1)
				(type default)
			)
			(layer "B.Fab")
		)
		(pad "1" smd rect
			(at 0.889 0 180)
			(size 1.016 1.27)
			(layers "B.Cu" "B.Mask" "B.Paste")
			(net "PVNN_MAIN_CPU0")
		)
		(pad "2" smd rect
			(at -0.889 0 180)
			(size 1.016 1.27)
			(layers "B.Cu" "B.Mask" "B.Paste")
			(net "GND")
		)
	)
	(footprint ""
		(layer "B.Cu")
		(at 416.996626 -173.218602 180)
		(property "Reference" "PR101"
			(at 0 0 0)
			(layer "B.SilkS")
			(hide yes)
			(effects
				(font
					(size 1.27 1.27)
				)
				(justify mirror)
			)
		)
		(property "Value" ""
			(at 0 0 0)
			(layer "B.Fab")
			(effects
				(font
					(size 1.27 1.27)
				)
				(justify mirror)
			)
		)
		(duplicate_pad_numbers_are_jumpers no)
		(fp_line
			(start 0.7874 0.4064)
			(end 0.7874 -0.4064)
			(stroke
				(width 0.1524)
				(type default)
			)
			(layer "B.SilkS")
		)
		(fp_line
			(start 0.7874 -0.4064)
			(end -0.7874 -0.4064)
			(stroke
				(width 0.1524)
				(type default)
			)
			(layer "B.SilkS")
		)
		(fp_line
			(start -0.7874 0.4064)
			(end 0.7874 0.4064)
			(stroke
				(width 0.1524)
				(type default)
			)
			(layer "B.SilkS")
		)
		(fp_line
			(start -0.7874 -0.4064)
			(end -0.7874 0.4064)
			(stroke
				(width 0.1524)
				(type default)
			)
			(layer "B.SilkS")
		)
		(fp_line
			(start 0.67945 0.3048)
			(end 0.67945 -0.305054)
			(stroke
				(width 0.1)
				(type default)
			)
			(layer "B.Fab")
		)
		(fp_line
			(start 0.67945 -0.305054)
			(end 0.12065 -0.305054)
			(stroke
				(width 0.1)
				(type default)
			)
			(layer "B.Fab")
		)
		(fp_line
			(start 0.12065 0.3048)
			(end 0.67945 0.3048)
			(stroke
				(width 0.1)
				(type default)
			)
			(layer "B.Fab")
		)
		(fp_line
			(start 0.12065 0.2794)
			(end 0.12065 0.3048)
			(stroke
				(width 0.1)
				(type default)
			)
			(layer "B.Fab")
		)
		(fp_line
			(start 0.12065 -0.2794)
			(end -0.12065 -0.2794)
			(stroke
				(width 0.1)
				(type default)
			)
			(layer "B.Fab")
		)
		(fp_line
			(start 0.12065 -0.305054)
			(end 0.12065 -0.2794)
			(stroke
				(width 0.1)
				(type default)
			)
			(layer "B.Fab")
		)
		(fp_line
			(start -0.120396 0.3048)
			(end -0.120396 0.2794)
			(stroke
				(width 0.1)
				(type default)
			)
			(layer "B.Fab")
		)
		(fp_line
			(start -0.120396 0.2794)
			(end 0.12065 0.2794)
			(stroke
				(width 0.1)
				(type default)
			)
			(layer "B.Fab")
		)
		(fp_line
			(start -0.12065 -0.2794)
			(end -0.12065 -0.3048)
			(stroke
				(width 0.1)
				(type default)
			)
			(layer "B.Fab")
		)
		(fp_line
			(start -0.12065 -0.3048)
			(end -0.67945 -0.3048)
			(stroke
				(width 0.1)
				(type default)
			)
			(layer "B.Fab")
		)
		(fp_line
			(start -0.67945 0.3048)
			(end -0.120396 0.3048)
			(stroke
				(width 0.1)
				(type default)
			)
			(layer "B.Fab")
		)
		(fp_line
			(start -0.67945 -0.3048)
			(end -0.67945 0.3048)
			(stroke
				(width 0.1)
				(type default)
			)
			(layer "B.Fab")
		)
		(pad "1" smd circle
			(at 0.40005 0)
			(size 0 0)
			(layers "B.Cu" "B.Mask" "B.Paste")
			(net "PVCCFA_EHV_CPU0_PVCC")
		)
		(pad "2" smd circle
			(at -0.40005 0)
			(size 0 0)
			(layers "B.Cu" "B.Mask" "B.Paste")
			(net "PVCCINFAON_CPU0_VDD1")
		)
	)
	(footprint ""
		(layer "B.Cu")
		(at 317.632588 -35.856672 -135)
		(property "Reference" "R4674"
			(at 0 0 45)
			(layer "B.SilkS")
			(hide yes)
			(effects
				(font
					(size 1.27 1.27)
				)
				(justify mirror)
			)
		)
		(property "Value" ""
			(at 0 0 45)
			(layer "B.Fab")
			(effects
				(font
					(size 1.27 1.27)
				)
				(justify mirror)
			)
		)
		(duplicate_pad_numbers_are_jumpers no)
		(fp_line
			(start 0.787389 0.406267)
			(end 0.787389 -0.406267)
			(stroke
				(width 0.1524)
				(type default)
			)
			(layer "B.SilkS")
		)
		(fp_line
			(start 0.787389 -0.406267)
			(end -0.787389 -0.406267)
			(stroke
				(width 0.1524)
				(type default)
			)
			(layer "B.SilkS")
		)
		(fp_line
			(start -0.787389 0.406267)
			(end 0.787389 0.406267)
			(stroke
				(width 0.1524)
				(type default)
			)
			(layer "B.SilkS")
		)
		(fp_line
			(start -0.787389 -0.406267)
			(end -0.787389 0.406267)
			(stroke
				(width 0.1524)
				(type default)
			)
			(layer "B.SilkS")
		)
		(fp_line
			(start 0.679446 0.30479)
			(end 0.679446 -0.305149)
			(stroke
				(width 0.1)
				(type default)
			)
			(layer "B.Fab")
		)
		(fp_line
			(start 0.120515 0.30479)
			(end 0.679446 0.30479)
			(stroke
				(width 0.1)
				(type default)
			)
			(layer "B.Fab")
		)
		(fp_line
			(start 0.120695 0.279466)
			(end 0.120515 0.30479)
			(stroke
				(width 0.1)
				(type default)
			)
			(layer "B.Fab")
		)
		(fp_line
			(start 0.679446 -0.305149)
			(end 0.120695 -0.304969)
			(stroke
				(width 0.1)
				(type default)
			)
			(layer "B.Fab")
		)
		(fp_line
			(start -0.120515 0.30479)
			(end -0.120335 0.279466)
			(stroke
				(width 0.1)
				(type default)
			)
			(layer "B.Fab")
		)
		(fp_line
			(start -0.120335 0.279466)
			(end 0.120695 0.279466)
			(stroke
				(width 0.1)
				(type default)
			)
			(layer "B.Fab")
		)
		(fp_line
			(start 0.120695 -0.279466)
			(end -0.120695 -0.279466)
			(stroke
				(width 0.1)
				(type default)
			)
			(layer "B.Fab")
		)
		(fp_line
			(start 0.120695 -0.304969)
			(end 0.120695 -0.279466)
			(stroke
				(width 0.1)
				(type default)
			)
			(layer "B.Fab")
		)
		(fp_line
			(start -0.679446 0.30479)
			(end -0.120515 0.30479)
			(stroke
				(width 0.1)
				(type default)
			)
			(layer "B.Fab")
		)
		(fp_line
			(start -0.120695 -0.279466)
			(end -0.120515 -0.30479)
			(stroke
				(width 0.1)
				(type default)
			)
			(layer "B.Fab")
		)
		(fp_line
			(start -0.120515 -0.30479)
			(end -0.679446 -0.30479)
			(stroke
				(width 0.1)
				(type default)
			)
			(layer "B.Fab")
		)
		(fp_line
			(start -0.679446 -0.30479)
			(end -0.679446 0.30479)
			(stroke
				(width 0.1)
				(type default)
			)
			(layer "B.Fab")
		)
		(pad "1" smd circle
			(at 0.40005 0 45)
			(size 0 0)
			(layers "B.Cu" "B.Mask" "B.Paste")
			(net "FM_SLP_SUS_RSM_RST_N")
		)
		(pad "2" smd circle
			(at -0.40005 0 45)
			(size 0 0)
			(layers "B.Cu" "B.Mask" "B.Paste")
			(net "GND")
		)
	)
	(footprint ""
		(layer "B.Cu")
		(at 44.821856 -353.567492 90)
		(property "Reference" "PC1200_P1_4"
			(at 0 0 90)
			(layer "B.SilkS")
			(hide yes)
			(effects
				(font
					(size 1.27 1.27)
				)
				(justify mirror)
			)
		)
		(property "Value" ""
			(at 0 0 90)
			(layer "B.Fab")
			(effects
				(font
					(size 1.27 1.27)
				)
				(justify mirror)
			)
		)
		(duplicate_pad_numbers_are_jumpers no)
		(fp_line
			(start 1.524 -0.762)
			(end -1.524 -0.762)
			(stroke
				(width 0.1524)
				(type default)
			)
			(layer "B.SilkS")
		)
		(fp_line
			(start -1.524 -0.762)
			(end -1.524 0.762)
			(stroke
				(width 0.1524)
				(type default)
			)
			(layer "B.SilkS")
		)
		(fp_line
			(start 1.524 0.762)
			(end 1.524 -0.762)
			(stroke
				(width 0.1524)
				(type default)
			)
			(layer "B.SilkS")
		)
		(fp_line
			(start -1.524 0.762)
			(end 1.524 0.762)
			(stroke
				(width 0.1524)
				(type default)
			)
			(layer "B.SilkS")
		)
		(fp_line
			(start 1.1049 -0.724916)
			(end 1.1049 0.724916)
			(stroke
				(width 0.1)
				(type default)
			)
			(layer "B.Fab")
		)
		(fp_line
			(start -1.1049 -0.724916)
			(end 1.1049 -0.724916)
			(stroke
				(width 0.1)
				(type default)
			)
			(layer "B.Fab")
		)
		(fp_line
			(start 1.1049 0.724916)
			(end -1.1049 0.724916)
			(stroke
				(width 0.1)
				(type default)
			)
			(layer "B.Fab")
		)
		(fp_line
			(start -1.1049 0.724916)
			(end -1.1049 -0.724916)
			(stroke
				(width 0.1)
				(type default)
			)
			(layer "B.Fab")
		)
		(pad "1" smd rect
			(at 0.889 0 90)
			(size 1.016 1.27)
			(layers "B.Cu" "B.Mask" "B.Paste")
			(net "SW_P12V_PVCCFA_EHV_FIVRA_CPU1_L")
		)
		(pad "2" smd rect
			(at -0.889 0 90)
			(size 1.016 1.27)
			(layers "B.Cu" "B.Mask" "B.Paste")
			(net "GND")
		)
	)
	(footprint ""
		(layer "B.Cu")
		(at 297.876468 -196.191378 -90)
		(property "Reference" "R4295"
			(at 0 0 90)
			(layer "B.SilkS")
			(hide yes)
			(effects
				(font
					(size 1.27 1.27)
				)
				(justify mirror)
			)
		)
		(property "Value" ""
			(at 0 0 90)
			(layer "B.Fab")
			(effects
				(font
					(size 1.27 1.27)
				)
				(justify mirror)
			)
		)
		(duplicate_pad_numbers_are_jumpers no)
		(fp_line
			(start -0.7874 0.4064)
			(end 0.7874 0.4064)
			(stroke
				(width 0.1524)
				(type default)
			)
			(layer "B.SilkS")
		)
		(fp_line
			(start 0.7874 0.4064)
			(end 0.7874 -0.4064)
			(stroke
				(width 0.1524)
				(type default)
			)
			(layer "B.SilkS")
		)
		(fp_line
			(start -0.7874 -0.4064)
			(end -0.7874 0.4064)
			(stroke
				(width 0.1524)
				(type default)
			)
			(layer "B.SilkS")
		)
		(fp_line
			(start 0.7874 -0.4064)
			(end -0.7874 -0.4064)
			(stroke
				(width 0.1524)
				(type default)
			)
			(layer "B.SilkS")
		)
		(fp_line
			(start -0.67945 0.3048)
			(end -0.120396 0.3048)
			(stroke
				(width 0.1)
				(type default)
			)
			(layer "B.Fab")
		)
		(fp_line
			(start -0.120396 0.3048)
			(end -0.120396 0.2794)
			(stroke
				(width 0.1)
				(type default)
			)
			(layer "B.Fab")
		)
		(fp_line
			(start 0.12065 0.3048)
			(end 0.67945 0.3048)
			(stroke
				(width 0.1)
				(type default)
			)
			(layer "B.Fab")
		)
		(fp_line
			(start 0.67945 0.3048)
			(end 0.67945 -0.305054)
			(stroke
				(width 0.1)
				(type default)
			)
			(layer "B.Fab")
		)
		(fp_line
			(start -0.120396 0.2794)
			(end 0.12065 0.2794)
			(stroke
				(width 0.1)
				(type default)
			)
			(layer "B.Fab")
		)
		(fp_line
			(start 0.12065 0.2794)
			(end 0.12065 0.3048)
			(stroke
				(width 0.1)
				(type default)
			)
			(layer "B.Fab")
		)
		(fp_line
			(start -0.12065 -0.2794)
			(end -0.12065 -0.3048)
			(stroke
				(width 0.1)
				(type default)
			)
			(layer "B.Fab")
		)
		(fp_line
			(start 0.12065 -0.2794)
			(end -0.12065 -0.2794)
			(stroke
				(width 0.1)
				(type default)
			)
			(layer "B.Fab")
		)
		(fp_line
			(start -0.67945 -0.3048)
			(end -0.67945 0.3048)
			(stroke
				(width 0.1)
				(type default)
			)
			(layer "B.Fab")
		)
		(fp_line
			(start -0.12065 -0.3048)
			(end -0.67945 -0.3048)
			(stroke
				(width 0.1)
				(type default)
			)
			(layer "B.Fab")
		)
		(fp_line
			(start 0.12065 -0.305054)
			(end 0.12065 -0.2794)
			(stroke
				(width 0.1)
				(type default)
			)
			(layer "B.Fab")
		)
		(fp_line
			(start 0.67945 -0.305054)
			(end 0.12065 -0.305054)
			(stroke
				(width 0.1)
				(type default)
			)
			(layer "B.Fab")
		)
		(pad "1" smd circle
			(at 0.40005 0 90)
			(size 0 0)
			(layers "B.Cu" "B.Mask" "B.Paste")
			(net "PWRGD_DRAMPWRGD_CPU0_AB_LVC1_R2")
		)
		(pad "2" smd circle
			(at -0.40005 0 90)
			(size 0 0)
			(layers "B.Cu" "B.Mask" "B.Paste")
			(net "PWRGD_DRAMPWRGD_CPU0_AB_LVC1_R")
		)
	)
	(footprint ""
		(layer "B.Cu")
		(at 312.189622 -29.708348 180)
		(property "Reference" "R1198"
			(at 0 0 0)
			(layer "B.SilkS")
			(hide yes)
			(effects
				(font
					(size 1.27 1.27)
				)
				(justify mirror)
			)
		)
		(property "Value" ""
			(at 0 0 0)
			(layer "B.Fab")
			(effects
				(font
					(size 1.27 1.27)
				)
				(justify mirror)
			)
		)
		(duplicate_pad_numbers_are_jumpers no)
		(fp_line
			(start 0.7874 0.4064)
			(end 0.7874 -0.4064)
			(stroke
				(width 0.1524)
				(type default)
			)
			(layer "B.SilkS")
		)
		(fp_line
			(start 0.7874 -0.4064)
			(end -0.7874 -0.4064)
			(stroke
				(width 0.1524)
				(type default)
			)
			(layer "B.SilkS")
		)
		(fp_line
			(start -0.7874 0.4064)
			(end 0.7874 0.4064)
			(stroke
				(width 0.1524)
				(type default)
			)
			(layer "B.SilkS")
		)
		(fp_line
			(start -0.7874 -0.4064)
			(end -0.7874 0.4064)
			(stroke
				(width 0.1524)
				(type default)
			)
			(layer "B.SilkS")
		)
		(fp_line
			(start 0.67945 0.3048)
			(end 0.67945 -0.305054)
			(stroke
				(width 0.1)
				(type default)
			)
			(layer "B.Fab")
		)
		(fp_line
			(start 0.67945 -0.305054)
			(end 0.12065 -0.305054)
			(stroke
				(width 0.1)
				(type default)
			)
			(layer "B.Fab")
		)
		(fp_line
			(start 0.12065 0.3048)
			(end 0.67945 0.3048)
			(stroke
				(width 0.1)
				(type default)
			)
			(layer "B.Fab")
		)
		(fp_line
			(start 0.12065 0.2794)
			(end 0.12065 0.3048)
			(stroke
				(width 0.1)
				(type default)
			)
			(layer "B.Fab")
		)
		(fp_line
			(start 0.12065 -0.2794)
			(end -0.12065 -0.2794)
			(stroke
				(width 0.1)
				(type default)
			)
			(layer "B.Fab")
		)
		(fp_line
			(start 0.12065 -0.305054)
			(end 0.12065 -0.2794)
			(stroke
				(width 0.1)
				(type default)
			)
			(layer "B.Fab")
		)
		(fp_line
			(start -0.120396 0.3048)
			(end -0.120396 0.2794)
			(stroke
				(width 0.1)
				(type default)
			)
			(layer "B.Fab")
		)
		(fp_line
			(start -0.120396 0.2794)
			(end 0.12065 0.2794)
			(stroke
				(width 0.1)
				(type default)
			)
			(layer "B.Fab")
		)
		(fp_line
			(start -0.12065 -0.2794)
			(end -0.12065 -0.3048)
			(stroke
				(width 0.1)
				(type default)
			)
			(layer "B.Fab")
		)
		(fp_line
			(start -0.12065 -0.3048)
			(end -0.67945 -0.3048)
			(stroke
				(width 0.1)
				(type default)
			)
			(layer "B.Fab")
		)
		(fp_line
			(start -0.67945 0.3048)
			(end -0.120396 0.3048)
			(stroke
				(width 0.1)
				(type default)
			)
			(layer "B.Fab")
		)
		(fp_line
			(start -0.67945 -0.3048)
			(end -0.67945 0.3048)
			(stroke
				(width 0.1)
				(type default)
			)
			(layer "B.Fab")
		)
		(pad "1" smd circle
			(at 0.40005 0)
			(size 0 0)
			(layers "B.Cu" "B.Mask" "B.Paste")
			(net "P3V3_AUX")
		)
		(pad "2" smd circle
			(at -0.40005 0)
			(size 0 0)
			(layers "B.Cu" "B.Mask" "B.Paste")
			(net "PU_ACPRESENT")
		)
	)
	(footprint ""
		(layer "B.Cu")
		(at 98.052382 -333.639922 90)
		(property "Reference" "PC571_P1_1"
			(at 0 0 90)
			(layer "B.SilkS")
			(hide yes)
			(effects
				(font
					(size 1.27 1.27)
				)
				(justify mirror)
			)
		)
		(property "Value" ""
			(at 0 0 90)
			(layer "B.Fab")
			(effects
				(font
					(size 1.27 1.27)
				)
				(justify mirror)
			)
		)
		(duplicate_pad_numbers_are_jumpers no)
		(fp_line
			(start 1.524 -0.762)
			(end -1.524 -0.762)
			(stroke
				(width 0.1524)
				(type default)
			)
			(layer "B.SilkS")
		)
		(fp_line
			(start -1.524 -0.762)
			(end -1.524 0.762)
			(stroke
				(width 0.1524)
				(type default)
			)
			(layer "B.SilkS")
		)
		(fp_line
			(start 1.524 0.762)
			(end 1.524 -0.762)
			(stroke
				(width 0.1524)
				(type default)
			)
			(layer "B.SilkS")
		)
		(fp_line
			(start -1.524 0.762)
			(end 1.524 0.762)
			(stroke
				(width 0.1524)
				(type default)
			)
			(layer "B.SilkS")
		)
		(fp_line
			(start 1.1049 -0.724916)
			(end 1.1049 0.724916)
			(stroke
				(width 0.1)
				(type default)
			)
			(layer "B.Fab")
		)
		(fp_line
			(start -1.1049 -0.724916)
			(end 1.1049 -0.724916)
			(stroke
				(width 0.1)
				(type default)
			)
			(layer "B.Fab")
		)
		(fp_line
			(start 1.1049 0.724916)
			(end -1.1049 0.724916)
			(stroke
				(width 0.1)
				(type default)
			)
			(layer "B.Fab")
		)
		(fp_line
			(start -1.1049 0.724916)
			(end -1.1049 -0.724916)
			(stroke
				(width 0.1)
				(type default)
			)
			(layer "B.Fab")
		)
		(pad "1" smd rect
			(at 0.889 0 90)
			(size 1.016 1.27)
			(layers "B.Cu" "B.Mask" "B.Paste")
			(net "SW_P12V_PVCCIN_CPU1_FLT")
		)
		(pad "2" smd rect
			(at -0.889 0 90)
			(size 1.016 1.27)
			(layers "B.Cu" "B.Mask" "B.Paste")
			(net "GND")
		)
	)
	(footprint ""
		(layer "B.Cu")
		(at 421.304466 -193.353436 -90)
		(property "Reference" "C624"
			(at 0 0 90)
			(layer "B.SilkS")
			(hide yes)
			(effects
				(font
					(size 1.27 1.27)
				)
				(justify mirror)
			)
		)
		(property "Value" ""
			(at 0 0 90)
			(layer "B.Fab")
			(effects
				(font
					(size 1.27 1.27)
				)
				(justify mirror)
			)
		)
		(duplicate_pad_numbers_are_jumpers no)
		(fp_line
			(start -0.7874 0.4064)
			(end 0.7874 0.4064)
			(stroke
				(width 0.1524)
				(type default)
			)
			(layer "B.SilkS")
		)
		(fp_line
			(start 0.7874 0.4064)
			(end 0.7874 -0.4064)
			(stroke
				(width 0.1524)
				(type default)
			)
			(layer "B.SilkS")
		)
		(fp_line
			(start -0.7874 -0.4064)
			(end -0.7874 0.4064)
			(stroke
				(width 0.1524)
				(type default)
			)
			(layer "B.SilkS")
		)
		(fp_line
			(start 0.7874 -0.4064)
			(end -0.7874 -0.4064)
			(stroke
				(width 0.1524)
				(type default)
			)
			(layer "B.SilkS")
		)
		(fp_line
			(start -0.67945 0.3048)
			(end -0.120396 0.3048)
			(stroke
				(width 0.1)
				(type default)
			)
			(layer "B.Fab")
		)
		(fp_line
			(start -0.120396 0.3048)
			(end -0.120396 0.2794)
			(stroke
				(width 0.1)
				(type default)
			)
			(layer "B.Fab")
		)
		(fp_line
			(start 0.12065 0.3048)
			(end 0.67945 0.3048)
			(stroke
				(width 0.1)
				(type default)
			)
			(layer "B.Fab")
		)
		(fp_line
			(start 0.67945 0.3048)
			(end 0.67945 -0.305054)
			(stroke
				(width 0.1)
				(type default)
			)
			(layer "B.Fab")
		)
		(fp_line
			(start -0.120396 0.2794)
			(end 0.12065 0.2794)
			(stroke
				(width 0.1)
				(type default)
			)
			(layer "B.Fab")
		)
		(fp_line
			(start 0.12065 0.2794)
			(end 0.12065 0.3048)
			(stroke
				(width 0.1)
				(type default)
			)
			(layer "B.Fab")
		)
		(fp_line
			(start -0.12065 -0.2794)
			(end -0.12065 -0.3048)
			(stroke
				(width 0.1)
				(type default)
			)
			(layer "B.Fab")
		)
		(fp_line
			(start 0.12065 -0.2794)
			(end -0.12065 -0.2794)
			(stroke
				(width 0.1)
				(type default)
			)
			(layer "B.Fab")
		)
		(fp_line
			(start -0.67945 -0.3048)
			(end -0.67945 0.3048)
			(stroke
				(width 0.1)
				(type default)
			)
			(layer "B.Fab")
		)
		(fp_line
			(start -0.12065 -0.3048)
			(end -0.67945 -0.3048)
			(stroke
				(width 0.1)
				(type default)
			)
			(layer "B.Fab")
		)
		(fp_line
			(start 0.12065 -0.305054)
			(end 0.12065 -0.2794)
			(stroke
				(width 0.1)
				(type default)
			)
			(layer "B.Fab")
		)
		(fp_line
			(start 0.67945 -0.305054)
			(end 0.12065 -0.305054)
			(stroke
				(width 0.1)
				(type default)
			)
			(layer "B.Fab")
		)
		(pad "1" smd circle
			(at 0.40005 0 90)
			(size 0 0)
			(layers "B.Cu" "B.Mask" "B.Paste")
			(net "RST_PLD_CPU0_DRAM_EF_N")
		)
		(pad "2" smd circle
			(at -0.40005 0 90)
			(size 0 0)
			(layers "B.Cu" "B.Mask" "B.Paste")
			(net "GND")
		)
	)
	(footprint ""
		(layer "B.Cu")
		(at 126.041912 -328.298048 -90)
		(property "Reference" "PC520_P1_5"
			(at 0 0 90)
			(layer "B.SilkS")
			(hide yes)
			(effects
				(font
					(size 1.27 1.27)
				)
				(justify mirror)
			)
		)
		(property "Value" ""
			(at 0 0 90)
			(layer "B.Fab")
			(effects
				(font
					(size 1.27 1.27)
				)
				(justify mirror)
			)
		)
		(duplicate_pad_numbers_are_jumpers no)
		(fp_line
			(start -1.524 0.762)
			(end 1.524 0.762)
			(stroke
				(width 0.1524)
				(type default)
			)
			(layer "B.SilkS")
		)
		(fp_line
			(start 1.524 0.762)
			(end 1.524 -0.762)
			(stroke
				(width 0.1524)
				(type default)
			)
			(layer "B.SilkS")
		)
		(fp_line
			(start -1.524 -0.762)
			(end -1.524 0.762)
			(stroke
				(width 0.1524)
				(type default)
			)
			(layer "B.SilkS")
		)
		(fp_line
			(start 1.524 -0.762)
			(end -1.524 -0.762)
			(stroke
				(width 0.1524)
				(type default)
			)
			(layer "B.SilkS")
		)
		(fp_line
			(start -1.1049 0.724916)
			(end -1.1049 -0.724916)
			(stroke
				(width 0.1)
				(type default)
			)
			(layer "B.Fab")
		)
		(fp_line
			(start 1.1049 0.724916)
			(end -1.1049 0.724916)
			(stroke
				(width 0.1)
				(type default)
			)
			(layer "B.Fab")
		)
		(fp_line
			(start -1.1049 -0.724916)
			(end 1.1049 -0.724916)
			(stroke
				(width 0.1)
				(type default)
			)
			(layer "B.Fab")
		)
		(fp_line
			(start 1.1049 -0.724916)
			(end 1.1049 0.724916)
			(stroke
				(width 0.1)
				(type default)
			)
			(layer "B.Fab")
		)
		(pad "1" smd rect
			(at 0.889 0 270)
			(size 1.016 1.27)
			(layers "B.Cu" "B.Mask" "B.Paste")
			(net "PVCCIN_CPU1")
		)
		(pad "2" smd rect
			(at -0.889 0 270)
			(size 1.016 1.27)
			(layers "B.Cu" "B.Mask" "B.Paste")
			(net "GND")
		)
	)
	(footprint ""
		(layer "B.Cu")
		(at 309.5498 -34.1884 180)
		(property "Reference" "R4768"
			(at 0 0 0)
			(layer "B.SilkS")
			(hide yes)
			(effects
				(font
					(size 1.27 1.27)
				)
				(justify mirror)
			)
		)
		(property "Value" ""
			(at 0 0 0)
			(layer "B.Fab")
			(effects
				(font
					(size 1.27 1.27)
				)
				(justify mirror)
			)
		)
		(duplicate_pad_numbers_are_jumpers no)
		(fp_line
			(start 0.7874 0.4064)
			(end 0.7874 -0.4064)
			(stroke
				(width 0.1524)
				(type default)
			)
			(layer "B.SilkS")
		)
		(fp_line
			(start 0.7874 -0.4064)
			(end -0.7874 -0.4064)
			(stroke
				(width 0.1524)
				(type default)
			)
			(layer "B.SilkS")
		)
		(fp_line
			(start -0.7874 0.4064)
			(end 0.7874 0.4064)
			(stroke
				(width 0.1524)
				(type default)
			)
			(layer "B.SilkS")
		)
		(fp_line
			(start -0.7874 -0.4064)
			(end -0.7874 0.4064)
			(stroke
				(width 0.1524)
				(type default)
			)
			(layer "B.SilkS")
		)
		(fp_line
			(start 0.67945 0.3048)
			(end 0.67945 -0.305054)
			(stroke
				(width 0.1)
				(type default)
			)
			(layer "B.Fab")
		)
		(fp_line
			(start 0.67945 -0.305054)
			(end 0.12065 -0.305054)
			(stroke
				(width 0.1)
				(type default)
			)
			(layer "B.Fab")
		)
		(fp_line
			(start 0.12065 0.3048)
			(end 0.67945 0.3048)
			(stroke
				(width 0.1)
				(type default)
			)
			(layer "B.Fab")
		)
		(fp_line
			(start 0.12065 0.2794)
			(end 0.12065 0.3048)
			(stroke
				(width 0.1)
				(type default)
			)
			(layer "B.Fab")
		)
		(fp_line
			(start 0.12065 -0.2794)
			(end -0.12065 -0.2794)
			(stroke
				(width 0.1)
				(type default)
			)
			(layer "B.Fab")
		)
		(fp_line
			(start 0.12065 -0.305054)
			(end 0.12065 -0.2794)
			(stroke
				(width 0.1)
				(type default)
			)
			(layer "B.Fab")
		)
		(fp_line
			(start -0.120396 0.3048)
			(end -0.120396 0.2794)
			(stroke
				(width 0.1)
				(type default)
			)
			(layer "B.Fab")
		)
		(fp_line
			(start -0.120396 0.2794)
			(end 0.12065 0.2794)
			(stroke
				(width 0.1)
				(type default)
			)
			(layer "B.Fab")
		)
		(fp_line
			(start -0.12065 -0.2794)
			(end -0.12065 -0.3048)
			(stroke
				(width 0.1)
				(type default)
			)
			(layer "B.Fab")
		)
		(fp_line
			(start -0.12065 -0.3048)
			(end -0.67945 -0.3048)
			(stroke
				(width 0.1)
				(type default)
			)
			(layer "B.Fab")
		)
		(fp_line
			(start -0.67945 0.3048)
			(end -0.120396 0.3048)
			(stroke
				(width 0.1)
				(type default)
			)
			(layer "B.Fab")
		)
		(fp_line
			(start -0.67945 -0.3048)
			(end -0.67945 0.3048)
			(stroke
				(width 0.1)
				(type default)
			)
			(layer "B.Fab")
		)
		(pad "1" smd circle
			(at 0.40005 0)
			(size 0 0)
			(layers "B.Cu" "B.Mask" "B.Paste")
			(net "E1S_0_CLK_OE_N")
		)
		(pad "2" smd circle
			(at -0.40005 0)
			(size 0 0)
			(layers "B.Cu" "B.Mask" "B.Paste")
			(net "P3V3_AUX")
		)
	)
	(footprint ""
		(layer "B.Cu")
		(at 171.755562 -113.37544 90)
		(property "Reference" "C1895"
			(at 0 0 90)
			(layer "B.SilkS")
			(hide yes)
			(effects
				(font
					(size 1.27 1.27)
				)
				(justify mirror)
			)
		)
		(property "Value" ""
			(at 0 0 90)
			(layer "B.Fab")
			(effects
				(font
					(size 1.27 1.27)
				)
				(justify mirror)
			)
		)
		(duplicate_pad_numbers_are_jumpers no)
		(fp_line
			(start 0.69215 -0.2921)
			(end -0.69215 -0.2921)
			(stroke
				(width 0.1524)
				(type default)
			)
			(layer "B.SilkS")
		)
		(fp_line
			(start -0.69215 -0.2921)
			(end -0.69215 0.2921)
			(stroke
				(width 0.1524)
				(type default)
			)
			(layer "B.SilkS")
		)
		(fp_line
			(start 0.69215 0.2921)
			(end 0.69215 -0.2921)
			(stroke
				(width 0.1524)
				(type default)
			)
			(layer "B.SilkS")
		)
		(fp_line
			(start -0.69215 0.2921)
			(end 0.69215 0.2921)
			(stroke
				(width 0.1524)
				(type default)
			)
			(layer "B.SilkS")
		)
		(fp_line
			(start 0.51435 -0.2794)
			(end -0.51435 -0.2794)
			(stroke
				(width 0.1)
				(type default)
			)
			(layer "B.Fab")
		)
		(fp_line
			(start -0.51435 -0.2794)
			(end -0.51435 0.2794)
			(stroke
				(width 0.1)
				(type default)
			)
			(layer "B.Fab")
		)
		(fp_line
			(start 0.51435 0.2794)
			(end 0.51435 -0.2794)
			(stroke
				(width 0.1)
				(type default)
			)
			(layer "B.Fab")
		)
		(fp_line
			(start -0.51435 0.2794)
			(end 0.51435 0.2794)
			(stroke
				(width 0.1)
				(type default)
			)
			(layer "B.Fab")
		)
		(pad "1" smd circle
			(at 0.40005 0 270)
			(size 0 0)
			(layers "B.Cu" "B.Mask" "B.Paste")
			(net "P3V3_AUX_FPGA_VCCIO0")
		)
		(pad "2" smd circle
			(at -0.40005 0 270)
			(size 0 0)
			(layers "B.Cu" "B.Mask" "B.Paste")
			(net "GND")
		)
		(zone
			(layer "B.Cu")
			(hatch none 0.5)
			(connect_pads
				(clearance 0)
			)
			(min_thickness 0.25)
			(keepout
				(tracks not_allowed)
				(vias allowed)
				(pads allowed)
				(copperpour not_allowed)
				(footprints allowed)
			)
			(placement
				(enabled no)
				(sheetname "")
			)
			(fill
				(thermal_gap 0.5)
				(thermal_bridge_width 0.5)
				(island_removal_mode 0)
			)
			(polygon
				(pts
					(xy 171.843192 -113.56594) (xy 171.901358 -113.4745) (xy 171.901358 -113.27511) (xy 171.843192 -113.18494)
					(xy 171.667932 -113.18494) (xy 171.609512 -113.27511) (xy 171.609512 -113.4745) (xy 171.667678 -113.56594)
				)
			)
		)
	)
	(footprint ""
		(layer "B.Cu")
		(at 178.61788 -329.479148)
		(property "Reference" "R1934"
			(at 0 0 0)
			(layer "B.SilkS")
			(hide yes)
			(effects
				(font
					(size 1.27 1.27)
				)
				(justify mirror)
			)
		)
		(property "Value" ""
			(at 0 0 0)
			(layer "B.Fab")
			(effects
				(font
					(size 1.27 1.27)
				)
				(justify mirror)
			)
		)
		(duplicate_pad_numbers_are_jumpers no)
		(fp_line
			(start -0.7874 -0.4064)
			(end -0.7874 0.4064)
			(stroke
				(width 0.1524)
				(type default)
			)
			(layer "B.SilkS")
		)
		(fp_line
			(start -0.7874 0.4064)
			(end 0.7874 0.4064)
			(stroke
				(width 0.1524)
				(type default)
			)
			(layer "B.SilkS")
		)
		(fp_line
			(start 0.7874 -0.4064)
			(end -0.7874 -0.4064)
			(stroke
				(width 0.1524)
				(type default)
			)
			(layer "B.SilkS")
		)
		(fp_line
			(start 0.7874 0.4064)
			(end 0.7874 -0.4064)
			(stroke
				(width 0.1524)
				(type default)
			)
			(layer "B.SilkS")
		)
		(fp_line
			(start -0.67945 -0.3048)
			(end -0.67945 0.3048)
			(stroke
				(width 0.1)
				(type default)
			)
			(layer "B.Fab")
		)
		(fp_line
			(start -0.67945 0.3048)
			(end -0.120396 0.3048)
			(stroke
				(width 0.1)
				(type default)
			)
			(layer "B.Fab")
		)
		(fp_line
			(start -0.12065 -0.3048)
			(end -0.67945 -0.3048)
			(stroke
				(width 0.1)
				(type default)
			)
			(layer "B.Fab")
		)
		(fp_line
			(start -0.12065 -0.2794)
			(end -0.12065 -0.3048)
			(stroke
				(width 0.1)
				(type default)
			)
			(layer "B.Fab")
		)
		(fp_line
			(start -0.120396 0.2794)
			(end 0.12065 0.2794)
			(stroke
				(width 0.1)
				(type default)
			)
			(layer "B.Fab")
		)
		(fp_line
			(start -0.120396 0.3048)
			(end -0.120396 0.2794)
			(stroke
				(width 0.1)
				(type default)
			)
			(layer "B.Fab")
		)
		(fp_line
			(start 0.12065 -0.305054)
			(end 0.12065 -0.2794)
			(stroke
				(width 0.1)
				(type default)
			)
			(layer "B.Fab")
		)
		(fp_line
			(start 0.12065 -0.2794)
			(end -0.12065 -0.2794)
			(stroke
				(width 0.1)
				(type default)
			)
			(layer "B.Fab")
		)
		(fp_line
			(start 0.12065 0.2794)
			(end 0.12065 0.3048)
			(stroke
				(width 0.1)
				(type default)
			)
			(layer "B.Fab")
		)
		(fp_line
			(start 0.12065 0.3048)
			(end 0.67945 0.3048)
			(stroke
				(width 0.1)
				(type default)
			)
			(layer "B.Fab")
		)
		(fp_line
			(start 0.67945 -0.305054)
			(end 0.12065 -0.305054)
			(stroke
				(width 0.1)
				(type default)
			)
			(layer "B.Fab")
		)
		(fp_line
			(start 0.67945 0.3048)
			(end 0.67945 -0.305054)
			(stroke
				(width 0.1)
				(type default)
			)
			(layer "B.Fab")
		)
		(pad "1" smd circle
			(at 0.40005 0 180)
			(size 0 0)
			(layers "B.Cu" "B.Mask" "B.Paste")
			(net "SMB_S3M_CPU1_PIROM_3V3AUX_SCL")
		)
		(pad "2" smd circle
			(at -0.40005 0 180)
			(size 0 0)
			(layers "B.Cu" "B.Mask" "B.Paste")
			(net "SMB_S3M_CPU1_PIROM_3V3AUX_SCL_1")
		)
	)
	(footprint ""
		(layer "B.Cu")
		(at 182.14594 5.461 180)
		(property "Reference" "J80"
			(at 4.24561 -1.143 270)
			(unlocked yes)
			(layer "B.SilkS")
			(effects
				(font
					(size 0.7874 0.5842)
					(thickness 0.1524)
				)
				(justify left mirror)
			)
		)
		(property "Value" ""
			(at 0 0 0)
			(layer "B.Fab")
			(effects
				(font
					(size 1.27 1.27)
				)
				(justify mirror)
			)
		)
		(duplicate_pad_numbers_are_jumpers no)
		(fp_line
			(start 1.2192 2.1082)
			(end 1.2192 -2.1082)
			(stroke
				(width 0.1524)
				(type default)
			)
			(layer "B.SilkS")
		)
		(fp_line
			(start 1.2192 -2.1082)
			(end -1.2192 -2.1082)
			(stroke
				(width 0.1524)
				(type default)
			)
			(layer "B.SilkS")
		)
		(fp_line
			(start -1.2192 2.1082)
			(end 1.2192 2.1082)
			(stroke
				(width 0.1524)
				(type default)
			)
			(layer "B.SilkS")
		)
		(fp_line
			(start -1.2192 -2.1082)
			(end -1.2192 2.1082)
			(stroke
				(width 0.1524)
				(type default)
			)
			(layer "B.SilkS")
		)
		(pad "" np_thru_hole circle
			(at -3.4671 -1.27 90)
			(size 1.0414 1.0414)
			(drill 1.0414)
			(layers "*.Cu" "*.Mask")
			(clearance 0.381)
			(thermal_gap 0.381)
		)
		(pad "" np_thru_hole circle
			(at -3.4671 1.27 90)
			(size 1.0414 1.0414)
			(drill 1.0414)
			(layers "*.Cu" "*.Mask")
			(clearance 0.381)
			(thermal_gap 0.381)
		)
		(pad "" np_thru_hole circle
			(at 2.8829 -1.27 90)
			(size 1.0414 1.0414)
			(drill 1.0414)
			(layers "*.Cu" "*.Mask")
			(clearance 0.381)
			(thermal_gap 0.381)
		)
		(pad "" np_thru_hole circle
			(at 2.8829 1.27 90)
			(size 1.0414 1.0414)
			(drill 1.0414)
			(layers "*.Cu" "*.Mask")
			(clearance 0.381)
			(thermal_gap 0.381)
		)
		(pad "1" smd rect
			(at -0.8255 -0.249936 90)
			(size 0.3048 0.508)
			(layers "B.Cu" "B.Mask" "B.Paste")
			(net "DELTA_L_85_10INCH_IN4_DP")
		)
		(pad "2" smd rect
			(at -0.8255 0.249936 90)
			(size 0.3048 0.508)
			(layers "B.Cu" "B.Mask" "B.Paste")
			(net "DELTA_L_85_10INCH_IN4_DN")
		)
		(pad "3" smd circle
			(at 0 0)
			(size 0 0)
			(layers "B.Cu" "B.Mask" "B.Paste")
			(net "DELTA_L_GND_1")
		)
		(zone
			(layers "F.Cu" "B.Cu" "In1.Cu" "In2.Cu" "In3.Cu" "In4.Cu" "In5.Cu" "In6.Cu"
				"In7.Cu" "In8.Cu" "In9.Cu" "In10.Cu" "In11.Cu" "In12.Cu" "In13.Cu" "In14.Cu"
				"In15.Cu" "In16.Cu"
			)
			(hatch none 0.5)
			(connect_pads
				(clearance 0)
			)
			(min_thickness 0.25)
			(keepout
				(tracks not_allowed)
				(vias allowed)
				(pads allowed)
				(copperpour not_allowed)
				(footprints allowed)
			)
			(placement
				(enabled no)
				(sheetname "")
			)
			(fill
				(thermal_gap 0.5)
				(thermal_bridge_width 0.5)
				(island_removal_mode 0)
			)
			(polygon
				(pts
					(arc
						(start 180.19014 4.191)
						(mid 178.33594 4.191)
						(end 180.19014 4.191)
					)
				)
			)
		)
		(zone
			(layers "F.Cu" "B.Cu" "In1.Cu" "In2.Cu" "In3.Cu" "In4.Cu" "In5.Cu" "In6.Cu"
				"In7.Cu" "In8.Cu" "In9.Cu" "In10.Cu" "In11.Cu" "In12.Cu" "In13.Cu" "In14.Cu"
				"In15.Cu" "In16.Cu"
			)
			(hatch none 0.5)
			(connect_pads
				(clearance 0)
			)
			(min_thickness 0.25)
			(keepout
				(tracks not_allowed)
				(vias allowed)
				(pads allowed)
				(copperpour not_allowed)
				(footprints allowed)
			)
			(placement
				(enabled no)
				(sheetname "")
			)
			(fill
				(thermal_gap 0.5)
				(thermal_bridge_width 0.5)
				(island_removal_mode 0)
			)
			(polygon
				(pts
					(arc
						(start 180.19014 6.731)
						(mid 178.33594 6.731)
						(end 180.19014 6.731)
					)
				)
			)
		)
		(zone
			(layers "F.Cu" "B.Cu" "In1.Cu" "In2.Cu" "In3.Cu" "In4.Cu" "In5.Cu" "In6.Cu"
				"In7.Cu" "In8.Cu" "In9.Cu" "In10.Cu" "In11.Cu" "In12.Cu" "In13.Cu" "In14.Cu"
				"In15.Cu" "In16.Cu"
			)
			(hatch none 0.5)
			(connect_pads
				(clearance 0)
			)
			(min_thickness 0.25)
			(keepout
				(tracks not_allowed)
				(vias allowed)
				(pads allowed)
				(copperpour not_allowed)
				(footprints allowed)
			)
			(placement
				(enabled no)
				(sheetname "")
			)
			(fill
				(thermal_gap 0.5)
				(thermal_bridge_width 0.5)
				(island_removal_mode 0)
			)
			(polygon
				(pts
					(arc
						(start 186.54014 4.191)
						(mid 184.68594 4.191)
						(end 186.54014 4.191)
					)
				)
			)
		)
		(zone
			(layers "F.Cu" "B.Cu" "In1.Cu" "In2.Cu" "In3.Cu" "In4.Cu" "In5.Cu" "In6.Cu"
				"In7.Cu" "In8.Cu" "In9.Cu" "In10.Cu" "In11.Cu" "In12.Cu" "In13.Cu" "In14.Cu"
				"In15.Cu" "In16.Cu"
			)
			(hatch none 0.5)
			(connect_pads
				(clearance 0)
			)
			(min_thickness 0.25)
			(keepout
				(tracks not_allowed)
				(vias allowed)
				(pads allowed)
				(copperpour not_allowed)
				(footprints allowed)
			)
			(placement
				(enabled no)
				(sheetname "")
			)
			(fill
				(thermal_gap 0.5)
				(thermal_bridge_width 0.5)
				(island_removal_mode 0)
			)
			(polygon
				(pts
					(arc
						(start 186.54014 6.731)
						(mid 184.68594 6.731)
						(end 186.54014 6.731)
					)
				)
			)
		)
		(zone
			(layer "B.Cu")
			(hatch none 0.5)
			(connect_pads
				(clearance 0)
			)
			(min_thickness 0.25)
			(keepout
				(tracks not_allowed)
				(vias allowed)
				(pads allowed)
				(copperpour not_allowed)
				(footprints allowed)
			)
			(placement
				(enabled no)
				(sheetname "")
			)
			(fill
				(thermal_gap 0.5)
				(thermal_bridge_width 0.5)
				(island_removal_mode 0)
			)
			(polygon
				(pts
					(xy 183.26354 6.00964) (xy 183.26354 5.914136) (xy 182.66664 5.914136) (xy 182.66664 5.507736)
					(xy 183.26354 5.507736) (xy 183.26354 5.414264) (xy 182.66664 5.414264) (xy 182.66664 5.007864)
					(xy 183.26354 5.007864) (xy 183.26354 4.91236) (xy 182.56504 4.91236) (xy 182.56504 6.00964)
				)
			)
		)
	)
	(footprint ""
		(layer "B.Cu")
		(at 24.887682 -164.086286 180)
		(property "Reference" "PR4252"
			(at 0 0 0)
			(layer "B.SilkS")
			(hide yes)
			(effects
				(font
					(size 1.27 1.27)
				)
				(justify mirror)
			)
		)
		(property "Value" ""
			(at 0 0 0)
			(layer "B.Fab")
			(effects
				(font
					(size 1.27 1.27)
				)
				(justify mirror)
			)
		)
		(duplicate_pad_numbers_are_jumpers no)
		(fp_line
			(start 0.7874 0.4064)
			(end 0.7874 -0.4064)
			(stroke
				(width 0.1524)
				(type default)
			)
			(layer "B.SilkS")
		)
		(fp_line
			(start 0.7874 -0.4064)
			(end -0.7874 -0.4064)
			(stroke
				(width 0.1524)
				(type default)
			)
			(layer "B.SilkS")
		)
		(fp_line
			(start -0.7874 0.4064)
			(end 0.7874 0.4064)
			(stroke
				(width 0.1524)
				(type default)
			)
			(layer "B.SilkS")
		)
		(fp_line
			(start -0.7874 -0.4064)
			(end -0.7874 0.4064)
			(stroke
				(width 0.1524)
				(type default)
			)
			(layer "B.SilkS")
		)
		(fp_line
			(start 0.67945 0.3048)
			(end 0.67945 -0.305054)
			(stroke
				(width 0.1)
				(type default)
			)
			(layer "B.Fab")
		)
		(fp_line
			(start 0.67945 -0.305054)
			(end 0.12065 -0.305054)
			(stroke
				(width 0.1)
				(type default)
			)
			(layer "B.Fab")
		)
		(fp_line
			(start 0.12065 0.3048)
			(end 0.67945 0.3048)
			(stroke
				(width 0.1)
				(type default)
			)
			(layer "B.Fab")
		)
		(fp_line
			(start 0.12065 0.2794)
			(end 0.12065 0.3048)
			(stroke
				(width 0.1)
				(type default)
			)
			(layer "B.Fab")
		)
		(fp_line
			(start 0.12065 -0.2794)
			(end -0.12065 -0.2794)
			(stroke
				(width 0.1)
				(type default)
			)
			(layer "B.Fab")
		)
		(fp_line
			(start 0.12065 -0.305054)
			(end 0.12065 -0.2794)
			(stroke
				(width 0.1)
				(type default)
			)
			(layer "B.Fab")
		)
		(fp_line
			(start -0.120396 0.3048)
			(end -0.120396 0.2794)
			(stroke
				(width 0.1)
				(type default)
			)
			(layer "B.Fab")
		)
		(fp_line
			(start -0.120396 0.2794)
			(end 0.12065 0.2794)
			(stroke
				(width 0.1)
				(type default)
			)
			(layer "B.Fab")
		)
		(fp_line
			(start -0.12065 -0.2794)
			(end -0.12065 -0.3048)
			(stroke
				(width 0.1)
				(type default)
			)
			(layer "B.Fab")
		)
		(fp_line
			(start -0.12065 -0.3048)
			(end -0.67945 -0.3048)
			(stroke
				(width 0.1)
				(type default)
			)
			(layer "B.Fab")
		)
		(fp_line
			(start -0.67945 0.3048)
			(end -0.120396 0.3048)
			(stroke
				(width 0.1)
				(type default)
			)
			(layer "B.Fab")
		)
		(fp_line
			(start -0.67945 -0.3048)
			(end -0.67945 0.3048)
			(stroke
				(width 0.1)
				(type default)
			)
			(layer "B.Fab")
		)
		(pad "1" smd circle
			(at 0.40005 0)
			(size 0 0)
			(layers "B.Cu" "B.Mask" "B.Paste")
			(net "NC_PVCCD_HV_CPU1_ACSP3")
		)
		(pad "2" smd circle
			(at -0.40005 0)
			(size 0 0)
			(layers "B.Cu" "B.Mask" "B.Paste")
			(net "GND")
		)
	)
	(footprint ""
		(layer "B.Cu")
		(at 349.028004 -357.239316 180)
		(property "Reference" "C3270"
			(at 0 0 0)
			(layer "B.SilkS")
			(hide yes)
			(effects
				(font
					(size 1.27 1.27)
				)
				(justify mirror)
			)
		)
		(property "Value" ""
			(at 0 0 0)
			(layer "B.Fab")
			(effects
				(font
					(size 1.27 1.27)
				)
				(justify mirror)
			)
		)
		(duplicate_pad_numbers_are_jumpers no)
		(fp_line
			(start 1.2954 0.5842)
			(end 1.2954 -0.5842)
			(stroke
				(width 0.1524)
				(type default)
			)
			(layer "B.SilkS")
		)
		(fp_line
			(start 1.2954 -0.5842)
			(end -1.2954 -0.5842)
			(stroke
				(width 0.1524)
				(type default)
			)
			(layer "B.SilkS")
		)
		(fp_line
			(start 0 -0.5842)
			(end 0 0.5842)
			(stroke
				(width 0.1524)
				(type default)
			)
			(layer "B.SilkS")
		)
		(fp_line
			(start -1.2954 0.5842)
			(end 1.2954 0.5842)
			(stroke
				(width 0.1524)
				(type default)
			)
			(layer "B.SilkS")
		)
		(fp_line
			(start -1.2954 -0.5842)
			(end -1.2954 0.5842)
			(stroke
				(width 0.1524)
				(type default)
			)
			(layer "B.SilkS")
		)
		(fp_line
			(start 1.1938 0.4064)
			(end 1.1938 -0.4064)
			(stroke
				(width 0.1)
				(type default)
			)
			(layer "B.Fab")
		)
		(fp_line
			(start 1.1938 -0.4064)
			(end 0.8636 -0.4064)
			(stroke
				(width 0.1)
				(type default)
			)
			(layer "B.Fab")
		)
		(fp_line
			(start 0.8636 0.4572)
			(end 0.8636 0.4064)
			(stroke
				(width 0.1)
				(type default)
			)
			(layer "B.Fab")
		)
		(fp_line
			(start 0.8636 0.4064)
			(end 1.1938 0.4064)
			(stroke
				(width 0.1)
				(type default)
			)
			(layer "B.Fab")
		)
		(fp_line
			(start 0.8636 -0.4064)
			(end 0.8636 -0.4572)
			(stroke
				(width 0.1)
				(type default)
			)
			(layer "B.Fab")
		)
		(fp_line
			(start 0.8636 -0.4572)
			(end -0.8636 -0.4572)
			(stroke
				(width 0.1)
				(type default)
			)
			(layer "B.Fab")
		)
		(fp_line
			(start -0.8636 0.4572)
			(end 0.8636 0.4572)
			(stroke
				(width 0.1)
				(type default)
			)
			(layer "B.Fab")
		)
		(fp_line
			(start -0.8636 0.4064)
			(end -0.8636 0.4572)
			(stroke
				(width 0.1)
				(type default)
			)
			(layer "B.Fab")
		)
		(fp_line
			(start -0.8636 -0.4064)
			(end -1.1938 -0.4064)
			(stroke
				(width 0.1)
				(type default)
			)
			(layer "B.Fab")
		)
		(fp_line
			(start -0.8636 -0.4572)
			(end -0.8636 -0.4064)
			(stroke
				(width 0.1)
				(type default)
			)
			(layer "B.Fab")
		)
		(fp_line
			(start -1.1938 0.4064)
			(end -0.8636 0.4064)
			(stroke
				(width 0.1)
				(type default)
			)
			(layer "B.Fab")
		)
		(fp_line
			(start -1.1938 -0.4064)
			(end -1.1938 0.4064)
			(stroke
				(width 0.1)
				(type default)
			)
			(layer "B.Fab")
		)
		(pad "1" smd rect
			(at 0.7366 0 90)
			(size 0.7112 0.8128)
			(layers "B.Cu" "B.Mask" "B.Paste")
			(net "PVNN_TERM_CPU0")
		)
		(pad "2" smd rect
			(at -0.7366 0 90)
			(size 0.7112 0.8128)
			(layers "B.Cu" "B.Mask" "B.Paste")
			(net "GND")
		)
	)
	(footprint ""
		(layer "B.Cu")
		(at 200.031858 -194.01917)
		(property "Reference" "R739"
			(at 0 0 0)
			(layer "B.SilkS")
			(hide yes)
			(effects
				(font
					(size 1.27 1.27)
				)
				(justify mirror)
			)
		)
		(property "Value" ""
			(at 0 0 0)
			(layer "B.Fab")
			(effects
				(font
					(size 1.27 1.27)
				)
				(justify mirror)
			)
		)
		(duplicate_pad_numbers_are_jumpers no)
		(fp_line
			(start -0.7874 -0.4064)
			(end -0.7874 0.4064)
			(stroke
				(width 0.1524)
				(type default)
			)
			(layer "B.SilkS")
		)
		(fp_line
			(start -0.7874 0.4064)
			(end 0.7874 0.4064)
			(stroke
				(width 0.1524)
				(type default)
			)
			(layer "B.SilkS")
		)
		(fp_line
			(start 0.7874 -0.4064)
			(end -0.7874 -0.4064)
			(stroke
				(width 0.1524)
				(type default)
			)
			(layer "B.SilkS")
		)
		(fp_line
			(start 0.7874 0.4064)
			(end 0.7874 -0.4064)
			(stroke
				(width 0.1524)
				(type default)
			)
			(layer "B.SilkS")
		)
		(fp_line
			(start -0.67945 -0.3048)
			(end -0.67945 0.3048)
			(stroke
				(width 0.1)
				(type default)
			)
			(layer "B.Fab")
		)
		(fp_line
			(start -0.67945 0.3048)
			(end -0.120396 0.3048)
			(stroke
				(width 0.1)
				(type default)
			)
			(layer "B.Fab")
		)
		(fp_line
			(start -0.12065 -0.3048)
			(end -0.67945 -0.3048)
			(stroke
				(width 0.1)
				(type default)
			)
			(layer "B.Fab")
		)
		(fp_line
			(start -0.12065 -0.2794)
			(end -0.12065 -0.3048)
			(stroke
				(width 0.1)
				(type default)
			)
			(layer "B.Fab")
		)
		(fp_line
			(start -0.120396 0.2794)
			(end 0.12065 0.2794)
			(stroke
				(width 0.1)
				(type default)
			)
			(layer "B.Fab")
		)
		(fp_line
			(start -0.120396 0.3048)
			(end -0.120396 0.2794)
			(stroke
				(width 0.1)
				(type default)
			)
			(layer "B.Fab")
		)
		(fp_line
			(start 0.12065 -0.305054)
			(end 0.12065 -0.2794)
			(stroke
				(width 0.1)
				(type default)
			)
			(layer "B.Fab")
		)
		(fp_line
			(start 0.12065 -0.2794)
			(end -0.12065 -0.2794)
			(stroke
				(width 0.1)
				(type default)
			)
			(layer "B.Fab")
		)
		(fp_line
			(start 0.12065 0.2794)
			(end 0.12065 0.3048)
			(stroke
				(width 0.1)
				(type default)
			)
			(layer "B.Fab")
		)
		(fp_line
			(start 0.12065 0.3048)
			(end 0.67945 0.3048)
			(stroke
				(width 0.1)
				(type default)
			)
			(layer "B.Fab")
		)
		(fp_line
			(start 0.67945 -0.305054)
			(end 0.12065 -0.305054)
			(stroke
				(width 0.1)
				(type default)
			)
			(layer "B.Fab")
		)
		(fp_line
			(start 0.67945 0.3048)
			(end 0.67945 -0.305054)
			(stroke
				(width 0.1)
				(type default)
			)
			(layer "B.Fab")
		)
		(pad "1" smd circle
			(at 0.40005 0 180)
			(size 0 0)
			(layers "B.Cu" "B.Mask" "B.Paste")
			(net "P3V3_AUX")
		)
		(pad "2" smd circle
			(at -0.40005 0 180)
			(size 0 0)
			(layers "B.Cu" "B.Mask" "B.Paste")
			(net "FM_CPU1_SKTOCC_N")
		)
	)
	(footprint ""
		(layer "B.Cu")
		(at 237.842806 -125.400054)
		(property "Reference" "R573"
			(at 0 0 0)
			(layer "B.SilkS")
			(hide yes)
			(effects
				(font
					(size 1.27 1.27)
				)
				(justify mirror)
			)
		)
		(property "Value" ""
			(at 0 0 0)
			(layer "B.Fab")
			(effects
				(font
					(size 1.27 1.27)
				)
				(justify mirror)
			)
		)
		(duplicate_pad_numbers_are_jumpers no)
		(fp_line
			(start -0.7874 -0.4064)
			(end -0.7874 0.4064)
			(stroke
				(width 0.1524)
				(type default)
			)
			(layer "B.SilkS")
		)
		(fp_line
			(start -0.7874 0.4064)
			(end 0.7874 0.4064)
			(stroke
				(width 0.1524)
				(type default)
			)
			(layer "B.SilkS")
		)
		(fp_line
			(start 0.7874 -0.4064)
			(end -0.7874 -0.4064)
			(stroke
				(width 0.1524)
				(type default)
			)
			(layer "B.SilkS")
		)
		(fp_line
			(start 0.7874 0.4064)
			(end 0.7874 -0.4064)
			(stroke
				(width 0.1524)
				(type default)
			)
			(layer "B.SilkS")
		)
		(fp_line
			(start -0.67945 -0.3048)
			(end -0.67945 0.3048)
			(stroke
				(width 0.1)
				(type default)
			)
			(layer "B.Fab")
		)
		(fp_line
			(start -0.67945 0.3048)
			(end -0.120396 0.3048)
			(stroke
				(width 0.1)
				(type default)
			)
			(layer "B.Fab")
		)
		(fp_line
			(start -0.12065 -0.3048)
			(end -0.67945 -0.3048)
			(stroke
				(width 0.1)
				(type default)
			)
			(layer "B.Fab")
		)
		(fp_line
			(start -0.12065 -0.2794)
			(end -0.12065 -0.3048)
			(stroke
				(width 0.1)
				(type default)
			)
			(layer "B.Fab")
		)
		(fp_line
			(start -0.120396 0.2794)
			(end 0.12065 0.2794)
			(stroke
				(width 0.1)
				(type default)
			)
			(layer "B.Fab")
		)
		(fp_line
			(start -0.120396 0.3048)
			(end -0.120396 0.2794)
			(stroke
				(width 0.1)
				(type default)
			)
			(layer "B.Fab")
		)
		(fp_line
			(start 0.12065 -0.305054)
			(end 0.12065 -0.2794)
			(stroke
				(width 0.1)
				(type default)
			)
			(layer "B.Fab")
		)
		(fp_line
			(start 0.12065 -0.2794)
			(end -0.12065 -0.2794)
			(stroke
				(width 0.1)
				(type default)
			)
			(layer "B.Fab")
		)
		(fp_line
			(start 0.12065 0.2794)
			(end 0.12065 0.3048)
			(stroke
				(width 0.1)
				(type default)
			)
			(layer "B.Fab")
		)
		(fp_line
			(start 0.12065 0.3048)
			(end 0.67945 0.3048)
			(stroke
				(width 0.1)
				(type default)
			)
			(layer "B.Fab")
		)
		(fp_line
			(start 0.67945 -0.305054)
			(end 0.12065 -0.305054)
			(stroke
				(width 0.1)
				(type default)
			)
			(layer "B.Fab")
		)
		(fp_line
			(start 0.67945 0.3048)
			(end 0.67945 -0.305054)
			(stroke
				(width 0.1)
				(type default)
			)
			(layer "B.Fab")
		)
		(pad "1" smd circle
			(at 0.40005 0 180)
			(size 0 0)
			(layers "B.Cu" "B.Mask" "B.Paste")
			(net "P3V3")
		)
		(pad "2" smd circle
			(at -0.40005 0 180)
			(size 0 0)
			(layers "B.Cu" "B.Mask" "B.Paste")
			(net "FM_DB2000_VSBEN")
		)
	)
	(footprint ""
		(layer "B.Cu")
		(at 164.64788 -118.836948)
		(property "Reference" "R1410"
			(at 0 0 0)
			(layer "B.SilkS")
			(hide yes)
			(effects
				(font
					(size 1.27 1.27)
				)
				(justify mirror)
			)
		)
		(property "Value" ""
			(at 0 0 0)
			(layer "B.Fab")
			(effects
				(font
					(size 1.27 1.27)
				)
				(justify mirror)
			)
		)
		(duplicate_pad_numbers_are_jumpers no)
		(fp_line
			(start -0.7874 -0.4064)
			(end -0.7874 0.4064)
			(stroke
				(width 0.1524)
				(type default)
			)
			(layer "B.SilkS")
		)
		(fp_line
			(start -0.7874 0.4064)
			(end 0.7874 0.4064)
			(stroke
				(width 0.1524)
				(type default)
			)
			(layer "B.SilkS")
		)
		(fp_line
			(start 0.7874 -0.4064)
			(end -0.7874 -0.4064)
			(stroke
				(width 0.1524)
				(type default)
			)
			(layer "B.SilkS")
		)
		(fp_line
			(start 0.7874 0.4064)
			(end 0.7874 -0.4064)
			(stroke
				(width 0.1524)
				(type default)
			)
			(layer "B.SilkS")
		)
		(fp_line
			(start -0.67945 -0.3048)
			(end -0.67945 0.3048)
			(stroke
				(width 0.1)
				(type default)
			)
			(layer "B.Fab")
		)
		(fp_line
			(start -0.67945 0.3048)
			(end -0.120396 0.3048)
			(stroke
				(width 0.1)
				(type default)
			)
			(layer "B.Fab")
		)
		(fp_line
			(start -0.12065 -0.3048)
			(end -0.67945 -0.3048)
			(stroke
				(width 0.1)
				(type default)
			)
			(layer "B.Fab")
		)
		(fp_line
			(start -0.12065 -0.2794)
			(end -0.12065 -0.3048)
			(stroke
				(width 0.1)
				(type default)
			)
			(layer "B.Fab")
		)
		(fp_line
			(start -0.120396 0.2794)
			(end 0.12065 0.2794)
			(stroke
				(width 0.1)
				(type default)
			)
			(layer "B.Fab")
		)
		(fp_line
			(start -0.120396 0.3048)
			(end -0.120396 0.2794)
			(stroke
				(width 0.1)
				(type default)
			)
			(layer "B.Fab")
		)
		(fp_line
			(start 0.12065 -0.305054)
			(end 0.12065 -0.2794)
			(stroke
				(width 0.1)
				(type default)
			)
			(layer "B.Fab")
		)
		(fp_line
			(start 0.12065 -0.2794)
			(end -0.12065 -0.2794)
			(stroke
				(width 0.1)
				(type default)
			)
			(layer "B.Fab")
		)
		(fp_line
			(start 0.12065 0.2794)
			(end 0.12065 0.3048)
			(stroke
				(width 0.1)
				(type default)
			)
			(layer "B.Fab")
		)
		(fp_line
			(start 0.12065 0.3048)
			(end 0.67945 0.3048)
			(stroke
				(width 0.1)
				(type default)
			)
			(layer "B.Fab")
		)
		(fp_line
			(start 0.67945 -0.305054)
			(end 0.12065 -0.305054)
			(stroke
				(width 0.1)
				(type default)
			)
			(layer "B.Fab")
		)
		(fp_line
			(start 0.67945 0.3048)
			(end 0.67945 -0.305054)
			(stroke
				(width 0.1)
				(type default)
			)
			(layer "B.Fab")
		)
		(pad "1" smd circle
			(at 0.40005 0 180)
			(size 0 0)
			(layers "B.Cu" "B.Mask" "B.Paste")
			(net "FM_PVCCFA_EHV_CPU1_R_EN")
		)
		(pad "2" smd circle
			(at -0.40005 0 180)
			(size 0 0)
			(layers "B.Cu" "B.Mask" "B.Paste")
			(net "GND")
		)
	)
	(footprint ""
		(layer "B.Cu")
		(at 334.02016 -386.8928)
		(property "Reference" "ME11"
			(at 9.652 -9.540748 0)
			(unlocked yes)
			(layer "B.SilkS")
			(effects
				(font
					(size 0.7874 0.5842)
					(thickness 0.1524)
				)
				(justify left mirror)
			)
		)
		(property "Value" ""
			(at 0 0 0)
			(layer "B.Fab")
			(effects
				(font
					(size 1.27 1.27)
				)
				(justify mirror)
			)
		)
		(duplicate_pad_numbers_are_jumpers no)
		(zone
			(layer "B.Cu")
			(hatch none 0.5)
			(connect_pads
				(clearance 0)
			)
			(min_thickness 0.25)
			(keepout
				(tracks allowed)
				(vias allowed)
				(pads allowed)
				(copperpour allowed)
				(footprints not_allowed)
			)
			(placement
				(enabled no)
				(sheetname "")
			)
			(fill
				(thermal_gap 0.5)
				(thermal_bridge_width 0.5)
				(island_removal_mode 0)
			)
			(polygon
				(pts
					(arc
						(start 344.02014 -386.8928)
						(mid 324.02018 -386.8928)
						(end 344.02014 -386.8928)
					)
				)
			)
		)
	)
	(footprint ""
		(layer "B.Cu")
		(at 179.352448 -404.287482)
		(property "Reference" "PR2149"
			(at 0 0 0)
			(layer "B.SilkS")
			(hide yes)
			(effects
				(font
					(size 1.27 1.27)
				)
				(justify mirror)
			)
		)
		(property "Value" ""
			(at 0 0 0)
			(layer "B.Fab")
			(effects
				(font
					(size 1.27 1.27)
				)
				(justify mirror)
			)
		)
		(duplicate_pad_numbers_are_jumpers no)
		(fp_line
			(start -0.7874 -0.4064)
			(end -0.7874 0.4064)
			(stroke
				(width 0.1524)
				(type default)
			)
			(layer "B.SilkS")
		)
		(fp_line
			(start -0.7874 0.4064)
			(end 0.7874 0.4064)
			(stroke
				(width 0.1524)
				(type default)
			)
			(layer "B.SilkS")
		)
		(fp_line
			(start 0.7874 -0.4064)
			(end -0.7874 -0.4064)
			(stroke
				(width 0.1524)
				(type default)
			)
			(layer "B.SilkS")
		)
		(fp_line
			(start 0.7874 0.4064)
			(end 0.7874 -0.4064)
			(stroke
				(width 0.1524)
				(type default)
			)
			(layer "B.SilkS")
		)
		(fp_line
			(start -0.67945 -0.3048)
			(end -0.67945 0.3048)
			(stroke
				(width 0.1)
				(type default)
			)
			(layer "B.Fab")
		)
		(fp_line
			(start -0.67945 0.3048)
			(end -0.120396 0.3048)
			(stroke
				(width 0.1)
				(type default)
			)
			(layer "B.Fab")
		)
		(fp_line
			(start -0.12065 -0.3048)
			(end -0.67945 -0.3048)
			(stroke
				(width 0.1)
				(type default)
			)
			(layer "B.Fab")
		)
		(fp_line
			(start -0.12065 -0.2794)
			(end -0.12065 -0.3048)
			(stroke
				(width 0.1)
				(type default)
			)
			(layer "B.Fab")
		)
		(fp_line
			(start -0.120396 0.2794)
			(end 0.12065 0.2794)
			(stroke
				(width 0.1)
				(type default)
			)
			(layer "B.Fab")
		)
		(fp_line
			(start -0.120396 0.3048)
			(end -0.120396 0.2794)
			(stroke
				(width 0.1)
				(type default)
			)
			(layer "B.Fab")
		)
		(fp_line
			(start 0.12065 -0.305054)
			(end 0.12065 -0.2794)
			(stroke
				(width 0.1)
				(type default)
			)
			(layer "B.Fab")
		)
		(fp_line
			(start 0.12065 -0.2794)
			(end -0.12065 -0.2794)
			(stroke
				(width 0.1)
				(type default)
			)
			(layer "B.Fab")
		)
		(fp_line
			(start 0.12065 0.2794)
			(end 0.12065 0.3048)
			(stroke
				(width 0.1)
				(type default)
			)
			(layer "B.Fab")
		)
		(fp_line
			(start 0.12065 0.3048)
			(end 0.67945 0.3048)
			(stroke
				(width 0.1)
				(type default)
			)
			(layer "B.Fab")
		)
		(fp_line
			(start 0.67945 -0.305054)
			(end 0.12065 -0.305054)
			(stroke
				(width 0.1)
				(type default)
			)
			(layer "B.Fab")
		)
		(fp_line
			(start 0.67945 0.3048)
			(end 0.67945 -0.305054)
			(stroke
				(width 0.1)
				(type default)
			)
			(layer "B.Fab")
		)
		(pad "1" smd circle
			(at 0.40005 0 180)
			(size 0 0)
			(layers "B.Cu" "B.Mask" "B.Paste")
			(net "HSC_VDD_R")
		)
		(pad "2" smd circle
			(at -0.40005 0 180)
			(size 0 0)
			(layers "B.Cu" "B.Mask" "B.Paste")
			(net "HSC_VDD")
		)
	)
	(footprint ""
		(layer "B.Cu")
		(at 456.003406 -318.266826 180)
		(property "Reference" "R2493"
			(at 0 0 0)
			(layer "B.SilkS")
			(hide yes)
			(effects
				(font
					(size 1.27 1.27)
				)
				(justify mirror)
			)
		)
		(property "Value" ""
			(at 0 0 0)
			(layer "B.Fab")
			(effects
				(font
					(size 1.27 1.27)
				)
				(justify mirror)
			)
		)
		(duplicate_pad_numbers_are_jumpers no)
		(fp_line
			(start 0.7874 0.4064)
			(end 0.7874 -0.4064)
			(stroke
				(width 0.1524)
				(type default)
			)
			(layer "B.SilkS")
		)
		(fp_line
			(start 0.7874 -0.4064)
			(end -0.7874 -0.4064)
			(stroke
				(width 0.1524)
				(type default)
			)
			(layer "B.SilkS")
		)
		(fp_line
			(start -0.7874 0.4064)
			(end 0.7874 0.4064)
			(stroke
				(width 0.1524)
				(type default)
			)
			(layer "B.SilkS")
		)
		(fp_line
			(start -0.7874 -0.4064)
			(end -0.7874 0.4064)
			(stroke
				(width 0.1524)
				(type default)
			)
			(layer "B.SilkS")
		)
		(fp_line
			(start 0.67945 0.3048)
			(end 0.67945 -0.305054)
			(stroke
				(width 0.1)
				(type default)
			)
			(layer "B.Fab")
		)
		(fp_line
			(start 0.67945 -0.305054)
			(end 0.12065 -0.305054)
			(stroke
				(width 0.1)
				(type default)
			)
			(layer "B.Fab")
		)
		(fp_line
			(start 0.12065 0.3048)
			(end 0.67945 0.3048)
			(stroke
				(width 0.1)
				(type default)
			)
			(layer "B.Fab")
		)
		(fp_line
			(start 0.12065 0.2794)
			(end 0.12065 0.3048)
			(stroke
				(width 0.1)
				(type default)
			)
			(layer "B.Fab")
		)
		(fp_line
			(start 0.12065 -0.2794)
			(end -0.12065 -0.2794)
			(stroke
				(width 0.1)
				(type default)
			)
			(layer "B.Fab")
		)
		(fp_line
			(start 0.12065 -0.305054)
			(end 0.12065 -0.2794)
			(stroke
				(width 0.1)
				(type default)
			)
			(layer "B.Fab")
		)
		(fp_line
			(start -0.120396 0.3048)
			(end -0.120396 0.2794)
			(stroke
				(width 0.1)
				(type default)
			)
			(layer "B.Fab")
		)
		(fp_line
			(start -0.120396 0.2794)
			(end 0.12065 0.2794)
			(stroke
				(width 0.1)
				(type default)
			)
			(layer "B.Fab")
		)
		(fp_line
			(start -0.12065 -0.2794)
			(end -0.12065 -0.3048)
			(stroke
				(width 0.1)
				(type default)
			)
			(layer "B.Fab")
		)
		(fp_line
			(start -0.12065 -0.3048)
			(end -0.67945 -0.3048)
			(stroke
				(width 0.1)
				(type default)
			)
			(layer "B.Fab")
		)
		(fp_line
			(start -0.67945 0.3048)
			(end -0.120396 0.3048)
			(stroke
				(width 0.1)
				(type default)
			)
			(layer "B.Fab")
		)
		(fp_line
			(start -0.67945 -0.3048)
			(end -0.67945 0.3048)
			(stroke
				(width 0.1)
				(type default)
			)
			(layer "B.Fab")
		)
		(pad "1" smd circle
			(at 0.40005 0)
			(size 0 0)
			(layers "B.Cu" "B.Mask" "B.Paste")
			(net "PWRGD_FAIL_CPU0_GH")
		)
		(pad "2" smd circle
			(at -0.40005 0)
			(size 0 0)
			(layers "B.Cu" "B.Mask" "B.Paste")
			(net "PWRGD_FAIL_CPU0_GH_R1")
		)
	)
	(footprint ""
		(layer "B.Cu")
		(at 283.430726 -193.691256 -90)
		(property "Reference" "C622"
			(at 0 0 90)
			(layer "B.SilkS")
			(hide yes)
			(effects
				(font
					(size 1.27 1.27)
				)
				(justify mirror)
			)
		)
		(property "Value" ""
			(at 0 0 90)
			(layer "B.Fab")
			(effects
				(font
					(size 1.27 1.27)
				)
				(justify mirror)
			)
		)
		(duplicate_pad_numbers_are_jumpers no)
		(fp_line
			(start -0.7874 0.4064)
			(end 0.7874 0.4064)
			(stroke
				(width 0.1524)
				(type default)
			)
			(layer "B.SilkS")
		)
		(fp_line
			(start 0.7874 0.4064)
			(end 0.7874 -0.4064)
			(stroke
				(width 0.1524)
				(type default)
			)
			(layer "B.SilkS")
		)
		(fp_line
			(start -0.7874 -0.4064)
			(end -0.7874 0.4064)
			(stroke
				(width 0.1524)
				(type default)
			)
			(layer "B.SilkS")
		)
		(fp_line
			(start 0.7874 -0.4064)
			(end -0.7874 -0.4064)
			(stroke
				(width 0.1524)
				(type default)
			)
			(layer "B.SilkS")
		)
		(fp_line
			(start -0.67945 0.3048)
			(end -0.120396 0.3048)
			(stroke
				(width 0.1)
				(type default)
			)
			(layer "B.Fab")
		)
		(fp_line
			(start -0.120396 0.3048)
			(end -0.120396 0.2794)
			(stroke
				(width 0.1)
				(type default)
			)
			(layer "B.Fab")
		)
		(fp_line
			(start 0.12065 0.3048)
			(end 0.67945 0.3048)
			(stroke
				(width 0.1)
				(type default)
			)
			(layer "B.Fab")
		)
		(fp_line
			(start 0.67945 0.3048)
			(end 0.67945 -0.305054)
			(stroke
				(width 0.1)
				(type default)
			)
			(layer "B.Fab")
		)
		(fp_line
			(start -0.120396 0.2794)
			(end 0.12065 0.2794)
			(stroke
				(width 0.1)
				(type default)
			)
			(layer "B.Fab")
		)
		(fp_line
			(start 0.12065 0.2794)
			(end 0.12065 0.3048)
			(stroke
				(width 0.1)
				(type default)
			)
			(layer "B.Fab")
		)
		(fp_line
			(start -0.12065 -0.2794)
			(end -0.12065 -0.3048)
			(stroke
				(width 0.1)
				(type default)
			)
			(layer "B.Fab")
		)
		(fp_line
			(start 0.12065 -0.2794)
			(end -0.12065 -0.2794)
			(stroke
				(width 0.1)
				(type default)
			)
			(layer "B.Fab")
		)
		(fp_line
			(start -0.67945 -0.3048)
			(end -0.67945 0.3048)
			(stroke
				(width 0.1)
				(type default)
			)
			(layer "B.Fab")
		)
		(fp_line
			(start -0.12065 -0.3048)
			(end -0.67945 -0.3048)
			(stroke
				(width 0.1)
				(type default)
			)
			(layer "B.Fab")
		)
		(fp_line
			(start 0.12065 -0.305054)
			(end 0.12065 -0.2794)
			(stroke
				(width 0.1)
				(type default)
			)
			(layer "B.Fab")
		)
		(fp_line
			(start 0.67945 -0.305054)
			(end 0.12065 -0.305054)
			(stroke
				(width 0.1)
				(type default)
			)
			(layer "B.Fab")
		)
		(pad "1" smd circle
			(at 0.40005 0 90)
			(size 0 0)
			(layers "B.Cu" "B.Mask" "B.Paste")
			(net "RST_PLD_CPU0_DRAM_AB_N")
		)
		(pad "2" smd circle
			(at -0.40005 0 90)
			(size 0 0)
			(layers "B.Cu" "B.Mask" "B.Paste")
			(net "GND")
		)
	)
	(footprint ""
		(layer "B.Cu")
		(at 446.966848 -184.060592 180)
		(property "Reference" "C1363"
			(at 0 0 0)
			(layer "B.SilkS")
			(hide yes)
			(effects
				(font
					(size 1.27 1.27)
				)
				(justify mirror)
			)
		)
		(property "Value" ""
			(at 0 0 0)
			(layer "B.Fab")
			(effects
				(font
					(size 1.27 1.27)
				)
				(justify mirror)
			)
		)
		(duplicate_pad_numbers_are_jumpers no)
		(fp_line
			(start 0.7874 0.4064)
			(end 0.7874 -0.4064)
			(stroke
				(width 0.1524)
				(type default)
			)
			(layer "B.SilkS")
		)
		(fp_line
			(start 0.7874 -0.4064)
			(end -0.7874 -0.4064)
			(stroke
				(width 0.1524)
				(type default)
			)
			(layer "B.SilkS")
		)
		(fp_line
			(start -0.7874 0.4064)
			(end 0.7874 0.4064)
			(stroke
				(width 0.1524)
				(type default)
			)
			(layer "B.SilkS")
		)
		(fp_line
			(start -0.7874 -0.4064)
			(end -0.7874 0.4064)
			(stroke
				(width 0.1524)
				(type default)
			)
			(layer "B.SilkS")
		)
		(fp_line
			(start 0.67945 0.3048)
			(end 0.67945 -0.305054)
			(stroke
				(width 0.1)
				(type default)
			)
			(layer "B.Fab")
		)
		(fp_line
			(start 0.67945 -0.305054)
			(end 0.12065 -0.305054)
			(stroke
				(width 0.1)
				(type default)
			)
			(layer "B.Fab")
		)
		(fp_line
			(start 0.12065 0.3048)
			(end 0.67945 0.3048)
			(stroke
				(width 0.1)
				(type default)
			)
			(layer "B.Fab")
		)
		(fp_line
			(start 0.12065 0.2794)
			(end 0.12065 0.3048)
			(stroke
				(width 0.1)
				(type default)
			)
			(layer "B.Fab")
		)
		(fp_line
			(start 0.12065 -0.2794)
			(end -0.12065 -0.2794)
			(stroke
				(width 0.1)
				(type default)
			)
			(layer "B.Fab")
		)
		(fp_line
			(start 0.12065 -0.305054)
			(end 0.12065 -0.2794)
			(stroke
				(width 0.1)
				(type default)
			)
			(layer "B.Fab")
		)
		(fp_line
			(start -0.120396 0.3048)
			(end -0.120396 0.2794)
			(stroke
				(width 0.1)
				(type default)
			)
			(layer "B.Fab")
		)
		(fp_line
			(start -0.120396 0.2794)
			(end 0.12065 0.2794)
			(stroke
				(width 0.1)
				(type default)
			)
			(layer "B.Fab")
		)
		(fp_line
			(start -0.12065 -0.2794)
			(end -0.12065 -0.3048)
			(stroke
				(width 0.1)
				(type default)
			)
			(layer "B.Fab")
		)
		(fp_line
			(start -0.12065 -0.3048)
			(end -0.67945 -0.3048)
			(stroke
				(width 0.1)
				(type default)
			)
			(layer "B.Fab")
		)
		(fp_line
			(start -0.67945 0.3048)
			(end -0.120396 0.3048)
			(stroke
				(width 0.1)
				(type default)
			)
			(layer "B.Fab")
		)
		(fp_line
			(start -0.67945 -0.3048)
			(end -0.67945 0.3048)
			(stroke
				(width 0.1)
				(type default)
			)
			(layer "B.Fab")
		)
		(pad "1" smd circle
			(at 0.40005 0)
			(size 0 0)
			(layers "B.Cu" "B.Mask" "B.Paste")
			(net "PVNN_MAIN_CPU0")
		)
		(pad "2" smd circle
			(at -0.40005 0)
			(size 0 0)
			(layers "B.Cu" "B.Mask" "B.Paste")
			(net "GND")
		)
	)
	(footprint ""
		(layer "B.Cu")
		(at 414.41243 -316.621922 90)
		(property "Reference" "R3883"
			(at 0 0 90)
			(layer "B.SilkS")
			(hide yes)
			(effects
				(font
					(size 1.27 1.27)
				)
				(justify mirror)
			)
		)
		(property "Value" ""
			(at 0 0 90)
			(layer "B.Fab")
			(effects
				(font
					(size 1.27 1.27)
				)
				(justify mirror)
			)
		)
		(duplicate_pad_numbers_are_jumpers no)
		(fp_line
			(start 0.7874 -0.4064)
			(end -0.7874 -0.4064)
			(stroke
				(width 0.1524)
				(type default)
			)
			(layer "B.SilkS")
		)
		(fp_line
			(start -0.7874 -0.4064)
			(end -0.7874 0.4064)
			(stroke
				(width 0.1524)
				(type default)
			)
			(layer "B.SilkS")
		)
		(fp_line
			(start 0.7874 0.4064)
			(end 0.7874 -0.4064)
			(stroke
				(width 0.1524)
				(type default)
			)
			(layer "B.SilkS")
		)
		(fp_line
			(start -0.7874 0.4064)
			(end 0.7874 0.4064)
			(stroke
				(width 0.1524)
				(type default)
			)
			(layer "B.SilkS")
		)
		(fp_line
			(start 0.67945 -0.305054)
			(end 0.12065 -0.305054)
			(stroke
				(width 0.1)
				(type default)
			)
			(layer "B.Fab")
		)
		(fp_line
			(start 0.12065 -0.305054)
			(end 0.12065 -0.2794)
			(stroke
				(width 0.1)
				(type default)
			)
			(layer "B.Fab")
		)
		(fp_line
			(start -0.12065 -0.3048)
			(end -0.67945 -0.3048)
			(stroke
				(width 0.1)
				(type default)
			)
			(layer "B.Fab")
		)
		(fp_line
			(start -0.67945 -0.3048)
			(end -0.67945 0.3048)
			(stroke
				(width 0.1)
				(type default)
			)
			(layer "B.Fab")
		)
		(fp_line
			(start 0.12065 -0.2794)
			(end -0.12065 -0.2794)
			(stroke
				(width 0.1)
				(type default)
			)
			(layer "B.Fab")
		)
		(fp_line
			(start -0.12065 -0.2794)
			(end -0.12065 -0.3048)
			(stroke
				(width 0.1)
				(type default)
			)
			(layer "B.Fab")
		)
		(fp_line
			(start 0.12065 0.2794)
			(end 0.12065 0.3048)
			(stroke
				(width 0.1)
				(type default)
			)
			(layer "B.Fab")
		)
		(fp_line
			(start -0.120396 0.2794)
			(end 0.12065 0.2794)
			(stroke
				(width 0.1)
				(type default)
			)
			(layer "B.Fab")
		)
		(fp_line
			(start 0.67945 0.3048)
			(end 0.67945 -0.305054)
			(stroke
				(width 0.1)
				(type default)
			)
			(layer "B.Fab")
		)
		(fp_line
			(start 0.12065 0.3048)
			(end 0.67945 0.3048)
			(stroke
				(width 0.1)
				(type default)
			)
			(layer "B.Fab")
		)
		(fp_line
			(start -0.120396 0.3048)
			(end -0.120396 0.2794)
			(stroke
				(width 0.1)
				(type default)
			)
			(layer "B.Fab")
		)
		(fp_line
			(start -0.67945 0.3048)
			(end -0.120396 0.3048)
			(stroke
				(width 0.1)
				(type default)
			)
			(layer "B.Fab")
		)
		(pad "1" smd circle
			(at 0.40005 0 270)
			(size 0 0)
			(layers "B.Cu" "B.Mask" "B.Paste")
			(net "I3C_SPD_DDREFGH_CPU0_LVC1_SCL_R")
		)
		(pad "2" smd circle
			(at -0.40005 0 270)
			(size 0 0)
			(layers "B.Cu" "B.Mask" "B.Paste")
			(net "I3C_SPD_DDREFGH_CPU0_LVC1_SCL")
		)
	)
	(footprint ""
		(layer "B.Cu")
		(at 334.59674 -49.022508)
		(property "Reference" "C1189"
			(at 0 0 0)
			(layer "B.SilkS")
			(hide yes)
			(effects
				(font
					(size 1.27 1.27)
				)
				(justify mirror)
			)
		)
		(property "Value" ""
			(at 0 0 0)
			(layer "B.Fab")
			(effects
				(font
					(size 1.27 1.27)
				)
				(justify mirror)
			)
		)
		(duplicate_pad_numbers_are_jumpers no)
		(fp_line
			(start -0.7874 -0.4064)
			(end -0.7874 0.4064)
			(stroke
				(width 0.1524)
				(type default)
			)
			(layer "B.SilkS")
		)
		(fp_line
			(start -0.7874 0.4064)
			(end 0.7874 0.4064)
			(stroke
				(width 0.1524)
				(type default)
			)
			(layer "B.SilkS")
		)
		(fp_line
			(start 0.7874 -0.4064)
			(end -0.7874 -0.4064)
			(stroke
				(width 0.1524)
				(type default)
			)
			(layer "B.SilkS")
		)
		(fp_line
			(start 0.7874 0.4064)
			(end 0.7874 -0.4064)
			(stroke
				(width 0.1524)
				(type default)
			)
			(layer "B.SilkS")
		)
		(fp_line
			(start -0.67945 -0.3048)
			(end -0.67945 0.3048)
			(stroke
				(width 0.1)
				(type default)
			)
			(layer "B.Fab")
		)
		(fp_line
			(start -0.67945 0.3048)
			(end -0.120396 0.3048)
			(stroke
				(width 0.1)
				(type default)
			)
			(layer "B.Fab")
		)
		(fp_line
			(start -0.12065 -0.3048)
			(end -0.67945 -0.3048)
			(stroke
				(width 0.1)
				(type default)
			)
			(layer "B.Fab")
		)
		(fp_line
			(start -0.12065 -0.2794)
			(end -0.12065 -0.3048)
			(stroke
				(width 0.1)
				(type default)
			)
			(layer "B.Fab")
		)
		(fp_line
			(start -0.120396 0.2794)
			(end 0.12065 0.2794)
			(stroke
				(width 0.1)
				(type default)
			)
			(layer "B.Fab")
		)
		(fp_line
			(start -0.120396 0.3048)
			(end -0.120396 0.2794)
			(stroke
				(width 0.1)
				(type default)
			)
			(layer "B.Fab")
		)
		(fp_line
			(start 0.12065 -0.305054)
			(end 0.12065 -0.2794)
			(stroke
				(width 0.1)
				(type default)
			)
			(layer "B.Fab")
		)
		(fp_line
			(start 0.12065 -0.2794)
			(end -0.12065 -0.2794)
			(stroke
				(width 0.1)
				(type default)
			)
			(layer "B.Fab")
		)
		(fp_line
			(start 0.12065 0.2794)
			(end 0.12065 0.3048)
			(stroke
				(width 0.1)
				(type default)
			)
			(layer "B.Fab")
		)
		(fp_line
			(start 0.12065 0.3048)
			(end 0.67945 0.3048)
			(stroke
				(width 0.1)
				(type default)
			)
			(layer "B.Fab")
		)
		(fp_line
			(start 0.67945 -0.305054)
			(end 0.12065 -0.305054)
			(stroke
				(width 0.1)
				(type default)
			)
			(layer "B.Fab")
		)
		(fp_line
			(start 0.67945 0.3048)
			(end 0.67945 -0.305054)
			(stroke
				(width 0.1)
				(type default)
			)
			(layer "B.Fab")
		)
		(pad "1" smd circle
			(at 0.40005 0 180)
			(size 0 0)
			(layers "B.Cu" "B.Mask" "B.Paste")
			(net "P1V05_PCH_AUX")
		)
		(pad "2" smd circle
			(at -0.40005 0 180)
			(size 0 0)
			(layers "B.Cu" "B.Mask" "B.Paste")
			(net "GND")
		)
	)
	(footprint ""
		(layer "B.Cu")
		(at 192.280286 -193.615056 -90)
		(property "Reference" "R702"
			(at 0 0 90)
			(layer "B.SilkS")
			(hide yes)
			(effects
				(font
					(size 1.27 1.27)
				)
				(justify mirror)
			)
		)
		(property "Value" ""
			(at 0 0 90)
			(layer "B.Fab")
			(effects
				(font
					(size 1.27 1.27)
				)
				(justify mirror)
			)
		)
		(duplicate_pad_numbers_are_jumpers no)
		(fp_line
			(start -0.7874 0.4064)
			(end 0.7874 0.4064)
			(stroke
				(width 0.1524)
				(type default)
			)
			(layer "B.SilkS")
		)
		(fp_line
			(start 0.7874 0.4064)
			(end 0.7874 -0.4064)
			(stroke
				(width 0.1524)
				(type default)
			)
			(layer "B.SilkS")
		)
		(fp_line
			(start -0.7874 -0.4064)
			(end -0.7874 0.4064)
			(stroke
				(width 0.1524)
				(type default)
			)
			(layer "B.SilkS")
		)
		(fp_line
			(start 0.7874 -0.4064)
			(end -0.7874 -0.4064)
			(stroke
				(width 0.1524)
				(type default)
			)
			(layer "B.SilkS")
		)
		(fp_line
			(start -0.67945 0.3048)
			(end -0.120396 0.3048)
			(stroke
				(width 0.1)
				(type default)
			)
			(layer "B.Fab")
		)
		(fp_line
			(start -0.120396 0.3048)
			(end -0.120396 0.2794)
			(stroke
				(width 0.1)
				(type default)
			)
			(layer "B.Fab")
		)
		(fp_line
			(start 0.12065 0.3048)
			(end 0.67945 0.3048)
			(stroke
				(width 0.1)
				(type default)
			)
			(layer "B.Fab")
		)
		(fp_line
			(start 0.67945 0.3048)
			(end 0.67945 -0.305054)
			(stroke
				(width 0.1)
				(type default)
			)
			(layer "B.Fab")
		)
		(fp_line
			(start -0.120396 0.2794)
			(end 0.12065 0.2794)
			(stroke
				(width 0.1)
				(type default)
			)
			(layer "B.Fab")
		)
		(fp_line
			(start 0.12065 0.2794)
			(end 0.12065 0.3048)
			(stroke
				(width 0.1)
				(type default)
			)
			(layer "B.Fab")
		)
		(fp_line
			(start -0.12065 -0.2794)
			(end -0.12065 -0.3048)
			(stroke
				(width 0.1)
				(type default)
			)
			(layer "B.Fab")
		)
		(fp_line
			(start 0.12065 -0.2794)
			(end -0.12065 -0.2794)
			(stroke
				(width 0.1)
				(type default)
			)
			(layer "B.Fab")
		)
		(fp_line
			(start -0.67945 -0.3048)
			(end -0.67945 0.3048)
			(stroke
				(width 0.1)
				(type default)
			)
			(layer "B.Fab")
		)
		(fp_line
			(start -0.12065 -0.3048)
			(end -0.67945 -0.3048)
			(stroke
				(width 0.1)
				(type default)
			)
			(layer "B.Fab")
		)
		(fp_line
			(start 0.12065 -0.305054)
			(end 0.12065 -0.2794)
			(stroke
				(width 0.1)
				(type default)
			)
			(layer "B.Fab")
		)
		(fp_line
			(start 0.67945 -0.305054)
			(end 0.12065 -0.305054)
			(stroke
				(width 0.1)
				(type default)
			)
			(layer "B.Fab")
		)
		(pad "1" smd circle
			(at 0.40005 0 90)
			(size 0 0)
			(layers "B.Cu" "B.Mask" "B.Paste")
			(net "RST_PLD_CPU1_DRAM_GH_N")
		)
		(pad "2" smd circle
			(at -0.40005 0 90)
			(size 0 0)
			(layers "B.Cu" "B.Mask" "B.Paste")
			(net "GND")
		)
	)
	(footprint ""
		(layer "B.Cu")
		(at 282.788614 -321.549776 -90)
		(property "Reference" "C18"
			(at 0 0 90)
			(layer "B.SilkS")
			(hide yes)
			(effects
				(font
					(size 1.27 1.27)
				)
				(justify mirror)
			)
		)
		(property "Value" ""
			(at 0 0 90)
			(layer "B.Fab")
			(effects
				(font
					(size 1.27 1.27)
				)
				(justify mirror)
			)
		)
		(duplicate_pad_numbers_are_jumpers no)
		(fp_line
			(start -1.524 0.762)
			(end 1.524 0.762)
			(stroke
				(width 0.1524)
				(type default)
			)
			(layer "B.SilkS")
		)
		(fp_line
			(start 1.524 0.762)
			(end 1.524 -0.762)
			(stroke
				(width 0.1524)
				(type default)
			)
			(layer "B.SilkS")
		)
		(fp_line
			(start -1.524 -0.762)
			(end -1.524 0.762)
			(stroke
				(width 0.1524)
				(type default)
			)
			(layer "B.SilkS")
		)
		(fp_line
			(start 1.524 -0.762)
			(end -1.524 -0.762)
			(stroke
				(width 0.1524)
				(type default)
			)
			(layer "B.SilkS")
		)
		(fp_line
			(start -1.1049 0.724916)
			(end -1.1049 -0.724916)
			(stroke
				(width 0.1)
				(type default)
			)
			(layer "B.Fab")
		)
		(fp_line
			(start 1.1049 0.724916)
			(end -1.1049 0.724916)
			(stroke
				(width 0.1)
				(type default)
			)
			(layer "B.Fab")
		)
		(fp_line
			(start -1.1049 -0.724916)
			(end 1.1049 -0.724916)
			(stroke
				(width 0.1)
				(type default)
			)
			(layer "B.Fab")
		)
		(fp_line
			(start 1.1049 -0.724916)
			(end 1.1049 0.724916)
			(stroke
				(width 0.1)
				(type default)
			)
			(layer "B.Fab")
		)
		(pad "1" smd rect
			(at 0.889 0 270)
			(size 1.016 1.27)
			(layers "B.Cu" "B.Mask" "B.Paste")
			(net "P12V_S3_AUX_CPU0_NVDIMM")
		)
		(pad "2" smd rect
			(at -0.889 0 270)
			(size 1.016 1.27)
			(layers "B.Cu" "B.Mask" "B.Paste")
			(net "GND")
		)
	)
	(footprint ""
		(layer "B.Cu")
		(at 334.62849 -50.314352)
		(property "Reference" "C1253"
			(at 0 0 0)
			(layer "B.SilkS")
			(hide yes)
			(effects
				(font
					(size 1.27 1.27)
				)
				(justify mirror)
			)
		)
		(property "Value" ""
			(at 0 0 0)
			(layer "B.Fab")
			(effects
				(font
					(size 1.27 1.27)
				)
				(justify mirror)
			)
		)
		(duplicate_pad_numbers_are_jumpers no)
		(fp_line
			(start -0.7874 -0.4064)
			(end -0.7874 0.4064)
			(stroke
				(width 0.1524)
				(type default)
			)
			(layer "B.SilkS")
		)
		(fp_line
			(start -0.7874 0.4064)
			(end 0.7874 0.4064)
			(stroke
				(width 0.1524)
				(type default)
			)
			(layer "B.SilkS")
		)
		(fp_line
			(start 0.7874 -0.4064)
			(end -0.7874 -0.4064)
			(stroke
				(width 0.1524)
				(type default)
			)
			(layer "B.SilkS")
		)
		(fp_line
			(start 0.7874 0.4064)
			(end 0.7874 -0.4064)
			(stroke
				(width 0.1524)
				(type default)
			)
			(layer "B.SilkS")
		)
		(fp_line
			(start -0.67945 -0.3048)
			(end -0.67945 0.3048)
			(stroke
				(width 0.1)
				(type default)
			)
			(layer "B.Fab")
		)
		(fp_line
			(start -0.67945 0.3048)
			(end -0.120396 0.3048)
			(stroke
				(width 0.1)
				(type default)
			)
			(layer "B.Fab")
		)
		(fp_line
			(start -0.12065 -0.3048)
			(end -0.67945 -0.3048)
			(stroke
				(width 0.1)
				(type default)
			)
			(layer "B.Fab")
		)
		(fp_line
			(start -0.12065 -0.2794)
			(end -0.12065 -0.3048)
			(stroke
				(width 0.1)
				(type default)
			)
			(layer "B.Fab")
		)
		(fp_line
			(start -0.120396 0.2794)
			(end 0.12065 0.2794)
			(stroke
				(width 0.1)
				(type default)
			)
			(layer "B.Fab")
		)
		(fp_line
			(start -0.120396 0.3048)
			(end -0.120396 0.2794)
			(stroke
				(width 0.1)
				(type default)
			)
			(layer "B.Fab")
		)
		(fp_line
			(start 0.12065 -0.305054)
			(end 0.12065 -0.2794)
			(stroke
				(width 0.1)
				(type default)
			)
			(layer "B.Fab")
		)
		(fp_line
			(start 0.12065 -0.2794)
			(end -0.12065 -0.2794)
			(stroke
				(width 0.1)
				(type default)
			)
			(layer "B.Fab")
		)
		(fp_line
			(start 0.12065 0.2794)
			(end 0.12065 0.3048)
			(stroke
				(width 0.1)
				(type default)
			)
			(layer "B.Fab")
		)
		(fp_line
			(start 0.12065 0.3048)
			(end 0.67945 0.3048)
			(stroke
				(width 0.1)
				(type default)
			)
			(layer "B.Fab")
		)
		(fp_line
			(start 0.67945 -0.305054)
			(end 0.12065 -0.305054)
			(stroke
				(width 0.1)
				(type default)
			)
			(layer "B.Fab")
		)
		(fp_line
			(start 0.67945 0.3048)
			(end 0.67945 -0.305054)
			(stroke
				(width 0.1)
				(type default)
			)
			(layer "B.Fab")
		)
		(pad "1" smd circle
			(at 0.40005 0 180)
			(size 0 0)
			(layers "B.Cu" "B.Mask" "B.Paste")
			(net "P1V8_PCH_AUX")
		)
		(pad "2" smd circle
			(at -0.40005 0 180)
			(size 0 0)
			(layers "B.Cu" "B.Mask" "B.Paste")
			(net "GND")
		)
	)
	(footprint ""
		(layer "B.Cu")
		(at 430.8221 -51.42738 180)
		(property "Reference" "C2359"
			(at 0 0 0)
			(layer "B.SilkS")
			(hide yes)
			(effects
				(font
					(size 1.27 1.27)
				)
				(justify mirror)
			)
		)
		(property "Value" ""
			(at 0 0 0)
			(layer "B.Fab")
			(effects
				(font
					(size 1.27 1.27)
				)
				(justify mirror)
			)
		)
		(duplicate_pad_numbers_are_jumpers no)
		(fp_line
			(start 0.7874 0.4064)
			(end 0.7874 -0.4064)
			(stroke
				(width 0.1524)
				(type default)
			)
			(layer "B.SilkS")
		)
		(fp_line
			(start 0.7874 -0.4064)
			(end -0.7874 -0.4064)
			(stroke
				(width 0.1524)
				(type default)
			)
			(layer "B.SilkS")
		)
		(fp_line
			(start -0.7874 0.4064)
			(end 0.7874 0.4064)
			(stroke
				(width 0.1524)
				(type default)
			)
			(layer "B.SilkS")
		)
		(fp_line
			(start -0.7874 -0.4064)
			(end -0.7874 0.4064)
			(stroke
				(width 0.1524)
				(type default)
			)
			(layer "B.SilkS")
		)
		(fp_line
			(start 0.67945 0.3048)
			(end 0.67945 -0.305054)
			(stroke
				(width 0.1)
				(type default)
			)
			(layer "B.Fab")
		)
		(fp_line
			(start 0.67945 -0.305054)
			(end 0.12065 -0.305054)
			(stroke
				(width 0.1)
				(type default)
			)
			(layer "B.Fab")
		)
		(fp_line
			(start 0.12065 0.3048)
			(end 0.67945 0.3048)
			(stroke
				(width 0.1)
				(type default)
			)
			(layer "B.Fab")
		)
		(fp_line
			(start 0.12065 0.2794)
			(end 0.12065 0.3048)
			(stroke
				(width 0.1)
				(type default)
			)
			(layer "B.Fab")
		)
		(fp_line
			(start 0.12065 -0.2794)
			(end -0.12065 -0.2794)
			(stroke
				(width 0.1)
				(type default)
			)
			(layer "B.Fab")
		)
		(fp_line
			(start 0.12065 -0.305054)
			(end 0.12065 -0.2794)
			(stroke
				(width 0.1)
				(type default)
			)
			(layer "B.Fab")
		)
		(fp_line
			(start -0.120396 0.3048)
			(end -0.120396 0.2794)
			(stroke
				(width 0.1)
				(type default)
			)
			(layer "B.Fab")
		)
		(fp_line
			(start -0.120396 0.2794)
			(end 0.12065 0.2794)
			(stroke
				(width 0.1)
				(type default)
			)
			(layer "B.Fab")
		)
		(fp_line
			(start -0.12065 -0.2794)
			(end -0.12065 -0.3048)
			(stroke
				(width 0.1)
				(type default)
			)
			(layer "B.Fab")
		)
		(fp_line
			(start -0.12065 -0.3048)
			(end -0.67945 -0.3048)
			(stroke
				(width 0.1)
				(type default)
			)
			(layer "B.Fab")
		)
		(fp_line
			(start -0.67945 0.3048)
			(end -0.120396 0.3048)
			(stroke
				(width 0.1)
				(type default)
			)
			(layer "B.Fab")
		)
		(fp_line
			(start -0.67945 -0.3048)
			(end -0.67945 0.3048)
			(stroke
				(width 0.1)
				(type default)
			)
			(layer "B.Fab")
		)
		(pad "1" smd circle
			(at 0.40005 0)
			(size 0 0)
			(layers "B.Cu" "B.Mask" "B.Paste")
			(net "PWRGD_P5V_ISO_R")
		)
		(pad "2" smd circle
			(at -0.40005 0)
			(size 0 0)
			(layers "B.Cu" "B.Mask" "B.Paste")
			(net "GND")
		)
	)
	(footprint ""
		(layer "B.Cu")
		(at 34.551366 -192.924176 -90)
		(property "Reference" "C614"
			(at 0 0 90)
			(layer "B.SilkS")
			(hide yes)
			(effects
				(font
					(size 1.27 1.27)
				)
				(justify mirror)
			)
		)
		(property "Value" ""
			(at 0 0 90)
			(layer "B.Fab")
			(effects
				(font
					(size 1.27 1.27)
				)
				(justify mirror)
			)
		)
		(duplicate_pad_numbers_are_jumpers no)
		(fp_line
			(start -0.7874 0.4064)
			(end 0.7874 0.4064)
			(stroke
				(width 0.1524)
				(type default)
			)
			(layer "B.SilkS")
		)
		(fp_line
			(start 0.7874 0.4064)
			(end 0.7874 -0.4064)
			(stroke
				(width 0.1524)
				(type default)
			)
			(layer "B.SilkS")
		)
		(fp_line
			(start -0.7874 -0.4064)
			(end -0.7874 0.4064)
			(stroke
				(width 0.1524)
				(type default)
			)
			(layer "B.SilkS")
		)
		(fp_line
			(start 0.7874 -0.4064)
			(end -0.7874 -0.4064)
			(stroke
				(width 0.1524)
				(type default)
			)
			(layer "B.SilkS")
		)
		(fp_line
			(start -0.67945 0.3048)
			(end -0.120396 0.3048)
			(stroke
				(width 0.1)
				(type default)
			)
			(layer "B.Fab")
		)
		(fp_line
			(start -0.120396 0.3048)
			(end -0.120396 0.2794)
			(stroke
				(width 0.1)
				(type default)
			)
			(layer "B.Fab")
		)
		(fp_line
			(start 0.12065 0.3048)
			(end 0.67945 0.3048)
			(stroke
				(width 0.1)
				(type default)
			)
			(layer "B.Fab")
		)
		(fp_line
			(start 0.67945 0.3048)
			(end 0.67945 -0.305054)
			(stroke
				(width 0.1)
				(type default)
			)
			(layer "B.Fab")
		)
		(fp_line
			(start -0.120396 0.2794)
			(end 0.12065 0.2794)
			(stroke
				(width 0.1)
				(type default)
			)
			(layer "B.Fab")
		)
		(fp_line
			(start 0.12065 0.2794)
			(end 0.12065 0.3048)
			(stroke
				(width 0.1)
				(type default)
			)
			(layer "B.Fab")
		)
		(fp_line
			(start -0.12065 -0.2794)
			(end -0.12065 -0.3048)
			(stroke
				(width 0.1)
				(type default)
			)
			(layer "B.Fab")
		)
		(fp_line
			(start 0.12065 -0.2794)
			(end -0.12065 -0.2794)
			(stroke
				(width 0.1)
				(type default)
			)
			(layer "B.Fab")
		)
		(fp_line
			(start -0.67945 -0.3048)
			(end -0.67945 0.3048)
			(stroke
				(width 0.1)
				(type default)
			)
			(layer "B.Fab")
		)
		(fp_line
			(start -0.12065 -0.3048)
			(end -0.67945 -0.3048)
			(stroke
				(width 0.1)
				(type default)
			)
			(layer "B.Fab")
		)
		(fp_line
			(start 0.12065 -0.305054)
			(end 0.12065 -0.2794)
			(stroke
				(width 0.1)
				(type default)
			)
			(layer "B.Fab")
		)
		(fp_line
			(start 0.67945 -0.305054)
			(end 0.12065 -0.305054)
			(stroke
				(width 0.1)
				(type default)
			)
			(layer "B.Fab")
		)
		(pad "1" smd circle
			(at 0.40005 0 90)
			(size 0 0)
			(layers "B.Cu" "B.Mask" "B.Paste")
			(net "RST_PLD_CPU1_DRAM_AB_N")
		)
		(pad "2" smd circle
			(at -0.40005 0 90)
			(size 0 0)
			(layers "B.Cu" "B.Mask" "B.Paste")
			(net "GND")
		)
	)
	(footprint ""
		(layer "B.Cu")
		(at 193.60388 -107.495848 180)
		(property "Reference" "R1437"
			(at 0 0 0)
			(layer "B.SilkS")
			(hide yes)
			(effects
				(font
					(size 1.27 1.27)
				)
				(justify mirror)
			)
		)
		(property "Value" ""
			(at 0 0 0)
			(layer "B.Fab")
			(effects
				(font
					(size 1.27 1.27)
				)
				(justify mirror)
			)
		)
		(duplicate_pad_numbers_are_jumpers no)
		(fp_line
			(start 0.7874 0.4064)
			(end 0.7874 -0.4064)
			(stroke
				(width 0.1524)
				(type default)
			)
			(layer "B.SilkS")
		)
		(fp_line
			(start 0.7874 -0.4064)
			(end -0.7874 -0.4064)
			(stroke
				(width 0.1524)
				(type default)
			)
			(layer "B.SilkS")
		)
		(fp_line
			(start -0.7874 0.4064)
			(end 0.7874 0.4064)
			(stroke
				(width 0.1524)
				(type default)
			)
			(layer "B.SilkS")
		)
		(fp_line
			(start -0.7874 -0.4064)
			(end -0.7874 0.4064)
			(stroke
				(width 0.1524)
				(type default)
			)
			(layer "B.SilkS")
		)
		(fp_line
			(start 0.67945 0.3048)
			(end 0.67945 -0.305054)
			(stroke
				(width 0.1)
				(type default)
			)
			(layer "B.Fab")
		)
		(fp_line
			(start 0.67945 -0.305054)
			(end 0.12065 -0.305054)
			(stroke
				(width 0.1)
				(type default)
			)
			(layer "B.Fab")
		)
		(fp_line
			(start 0.12065 0.3048)
			(end 0.67945 0.3048)
			(stroke
				(width 0.1)
				(type default)
			)
			(layer "B.Fab")
		)
		(fp_line
			(start 0.12065 0.2794)
			(end 0.12065 0.3048)
			(stroke
				(width 0.1)
				(type default)
			)
			(layer "B.Fab")
		)
		(fp_line
			(start 0.12065 -0.2794)
			(end -0.12065 -0.2794)
			(stroke
				(width 0.1)
				(type default)
			)
			(layer "B.Fab")
		)
		(fp_line
			(start 0.12065 -0.305054)
			(end 0.12065 -0.2794)
			(stroke
				(width 0.1)
				(type default)
			)
			(layer "B.Fab")
		)
		(fp_line
			(start -0.120396 0.3048)
			(end -0.120396 0.2794)
			(stroke
				(width 0.1)
				(type default)
			)
			(layer "B.Fab")
		)
		(fp_line
			(start -0.120396 0.2794)
			(end 0.12065 0.2794)
			(stroke
				(width 0.1)
				(type default)
			)
			(layer "B.Fab")
		)
		(fp_line
			(start -0.12065 -0.2794)
			(end -0.12065 -0.3048)
			(stroke
				(width 0.1)
				(type default)
			)
			(layer "B.Fab")
		)
		(fp_line
			(start -0.12065 -0.3048)
			(end -0.67945 -0.3048)
			(stroke
				(width 0.1)
				(type default)
			)
			(layer "B.Fab")
		)
		(fp_line
			(start -0.67945 0.3048)
			(end -0.120396 0.3048)
			(stroke
				(width 0.1)
				(type default)
			)
			(layer "B.Fab")
		)
		(fp_line
			(start -0.67945 -0.3048)
			(end -0.67945 0.3048)
			(stroke
				(width 0.1)
				(type default)
			)
			(layer "B.Fab")
		)
		(pad "1" smd circle
			(at 0.40005 0)
			(size 0 0)
			(layers "B.Cu" "B.Mask" "B.Paste")
			(net "FM_PLD_HEARTBEAT_LVC3")
		)
		(pad "2" smd circle
			(at -0.40005 0)
			(size 0 0)
			(layers "B.Cu" "B.Mask" "B.Paste")
			(net "P3V3_AUX")
		)
	)
	(footprint ""
		(layer "B.Cu")
		(at 69.404484 -190.795656 90)
		(property "Reference" "R558"
			(at 0 0 90)
			(layer "B.SilkS")
			(hide yes)
			(effects
				(font
					(size 1.27 1.27)
				)
				(justify mirror)
			)
		)
		(property "Value" ""
			(at 0 0 90)
			(layer "B.Fab")
			(effects
				(font
					(size 1.27 1.27)
				)
				(justify mirror)
			)
		)
		(duplicate_pad_numbers_are_jumpers no)
		(fp_line
			(start 0.7874 -0.4064)
			(end -0.7874 -0.4064)
			(stroke
				(width 0.1524)
				(type default)
			)
			(layer "B.SilkS")
		)
		(fp_line
			(start -0.7874 -0.4064)
			(end -0.7874 0.4064)
			(stroke
				(width 0.1524)
				(type default)
			)
			(layer "B.SilkS")
		)
		(fp_line
			(start 0.7874 0.4064)
			(end 0.7874 -0.4064)
			(stroke
				(width 0.1524)
				(type default)
			)
			(layer "B.SilkS")
		)
		(fp_line
			(start -0.7874 0.4064)
			(end 0.7874 0.4064)
			(stroke
				(width 0.1524)
				(type default)
			)
			(layer "B.SilkS")
		)
		(fp_line
			(start 0.67945 -0.305054)
			(end 0.12065 -0.305054)
			(stroke
				(width 0.1)
				(type default)
			)
			(layer "B.Fab")
		)
		(fp_line
			(start 0.12065 -0.305054)
			(end 0.12065 -0.2794)
			(stroke
				(width 0.1)
				(type default)
			)
			(layer "B.Fab")
		)
		(fp_line
			(start -0.12065 -0.3048)
			(end -0.67945 -0.3048)
			(stroke
				(width 0.1)
				(type default)
			)
			(layer "B.Fab")
		)
		(fp_line
			(start -0.67945 -0.3048)
			(end -0.67945 0.3048)
			(stroke
				(width 0.1)
				(type default)
			)
			(layer "B.Fab")
		)
		(fp_line
			(start 0.12065 -0.2794)
			(end -0.12065 -0.2794)
			(stroke
				(width 0.1)
				(type default)
			)
			(layer "B.Fab")
		)
		(fp_line
			(start -0.12065 -0.2794)
			(end -0.12065 -0.3048)
			(stroke
				(width 0.1)
				(type default)
			)
			(layer "B.Fab")
		)
		(fp_line
			(start 0.12065 0.2794)
			(end 0.12065 0.3048)
			(stroke
				(width 0.1)
				(type default)
			)
			(layer "B.Fab")
		)
		(fp_line
			(start -0.120396 0.2794)
			(end 0.12065 0.2794)
			(stroke
				(width 0.1)
				(type default)
			)
			(layer "B.Fab")
		)
		(fp_line
			(start 0.67945 0.3048)
			(end 0.67945 -0.305054)
			(stroke
				(width 0.1)
				(type default)
			)
			(layer "B.Fab")
		)
		(fp_line
			(start 0.12065 0.3048)
			(end 0.67945 0.3048)
			(stroke
				(width 0.1)
				(type default)
			)
			(layer "B.Fab")
		)
		(fp_line
			(start -0.120396 0.3048)
			(end -0.120396 0.2794)
			(stroke
				(width 0.1)
				(type default)
			)
			(layer "B.Fab")
		)
		(fp_line
			(start -0.67945 0.3048)
			(end -0.120396 0.3048)
			(stroke
				(width 0.1)
				(type default)
			)
			(layer "B.Fab")
		)
		(pad "1" smd circle
			(at 0.40005 0 270)
			(size 0 0)
			(layers "B.Cu" "B.Mask" "B.Paste")
			(net "SVID_ALERT0_CPU1_R_N")
		)
		(pad "2" smd circle
			(at -0.40005 0 270)
			(size 0 0)
			(layers "B.Cu" "B.Mask" "B.Paste")
			(net "PVNN_TERM_CPU1")
		)
	)
	(footprint ""
		(layer "B.Cu")
		(at 178.10988 -103.723948)
		(property "Reference" "C1935"
			(at 0 0 0)
			(layer "B.SilkS")
			(hide yes)
			(effects
				(font
					(size 1.27 1.27)
				)
				(justify mirror)
			)
		)
		(property "Value" ""
			(at 0 0 0)
			(layer "B.Fab")
			(effects
				(font
					(size 1.27 1.27)
				)
				(justify mirror)
			)
		)
		(duplicate_pad_numbers_are_jumpers no)
		(fp_line
			(start -0.7874 -0.4064)
			(end -0.7874 0.4064)
			(stroke
				(width 0.1524)
				(type default)
			)
			(layer "B.SilkS")
		)
		(fp_line
			(start -0.7874 0.4064)
			(end 0.7874 0.4064)
			(stroke
				(width 0.1524)
				(type default)
			)
			(layer "B.SilkS")
		)
		(fp_line
			(start 0.7874 -0.4064)
			(end -0.7874 -0.4064)
			(stroke
				(width 0.1524)
				(type default)
			)
			(layer "B.SilkS")
		)
		(fp_line
			(start 0.7874 0.4064)
			(end 0.7874 -0.4064)
			(stroke
				(width 0.1524)
				(type default)
			)
			(layer "B.SilkS")
		)
		(fp_line
			(start -0.67945 -0.3048)
			(end -0.67945 0.3048)
			(stroke
				(width 0.1)
				(type default)
			)
			(layer "B.Fab")
		)
		(fp_line
			(start -0.67945 0.3048)
			(end -0.120396 0.3048)
			(stroke
				(width 0.1)
				(type default)
			)
			(layer "B.Fab")
		)
		(fp_line
			(start -0.12065 -0.3048)
			(end -0.67945 -0.3048)
			(stroke
				(width 0.1)
				(type default)
			)
			(layer "B.Fab")
		)
		(fp_line
			(start -0.12065 -0.2794)
			(end -0.12065 -0.3048)
			(stroke
				(width 0.1)
				(type default)
			)
			(layer "B.Fab")
		)
		(fp_line
			(start -0.120396 0.2794)
			(end 0.12065 0.2794)
			(stroke
				(width 0.1)
				(type default)
			)
			(layer "B.Fab")
		)
		(fp_line
			(start -0.120396 0.3048)
			(end -0.120396 0.2794)
			(stroke
				(width 0.1)
				(type default)
			)
			(layer "B.Fab")
		)
		(fp_line
			(start 0.12065 -0.305054)
			(end 0.12065 -0.2794)
			(stroke
				(width 0.1)
				(type default)
			)
			(layer "B.Fab")
		)
		(fp_line
			(start 0.12065 -0.2794)
			(end -0.12065 -0.2794)
			(stroke
				(width 0.1)
				(type default)
			)
			(layer "B.Fab")
		)
		(fp_line
			(start 0.12065 0.2794)
			(end 0.12065 0.3048)
			(stroke
				(width 0.1)
				(type default)
			)
			(layer "B.Fab")
		)
		(fp_line
			(start 0.12065 0.3048)
			(end 0.67945 0.3048)
			(stroke
				(width 0.1)
				(type default)
			)
			(layer "B.Fab")
		)
		(fp_line
			(start 0.67945 -0.305054)
			(end 0.12065 -0.305054)
			(stroke
				(width 0.1)
				(type default)
			)
			(layer "B.Fab")
		)
		(fp_line
			(start 0.67945 0.3048)
			(end 0.67945 -0.305054)
			(stroke
				(width 0.1)
				(type default)
			)
			(layer "B.Fab")
		)
		(pad "1" smd circle
			(at 0.40005 0 180)
			(size 0 0)
			(layers "B.Cu" "B.Mask" "B.Paste")
			(net "P3V3_AUX_FPGA_VCCIO4")
		)
		(pad "2" smd circle
			(at -0.40005 0 180)
			(size 0 0)
			(layers "B.Cu" "B.Mask" "B.Paste")
			(net "GND")
		)
	)
	(footprint ""
		(layer "B.Cu")
		(at 261.73557 -317.881762 180)
		(property "Reference" "R3882"
			(at 0 0 0)
			(layer "B.SilkS")
			(hide yes)
			(effects
				(font
					(size 1.27 1.27)
				)
				(justify mirror)
			)
		)
		(property "Value" ""
			(at 0 0 0)
			(layer "B.Fab")
			(effects
				(font
					(size 1.27 1.27)
				)
				(justify mirror)
			)
		)
		(duplicate_pad_numbers_are_jumpers no)
		(fp_line
			(start 0.7874 0.4064)
			(end 0.7874 -0.4064)
			(stroke
				(width 0.1524)
				(type default)
			)
			(layer "B.SilkS")
		)
		(fp_line
			(start 0.7874 -0.4064)
			(end -0.7874 -0.4064)
			(stroke
				(width 0.1524)
				(type default)
			)
			(layer "B.SilkS")
		)
		(fp_line
			(start -0.7874 0.4064)
			(end 0.7874 0.4064)
			(stroke
				(width 0.1524)
				(type default)
			)
			(layer "B.SilkS")
		)
		(fp_line
			(start -0.7874 -0.4064)
			(end -0.7874 0.4064)
			(stroke
				(width 0.1524)
				(type default)
			)
			(layer "B.SilkS")
		)
		(fp_line
			(start 0.67945 0.3048)
			(end 0.67945 -0.305054)
			(stroke
				(width 0.1)
				(type default)
			)
			(layer "B.Fab")
		)
		(fp_line
			(start 0.67945 -0.305054)
			(end 0.12065 -0.305054)
			(stroke
				(width 0.1)
				(type default)
			)
			(layer "B.Fab")
		)
		(fp_line
			(start 0.12065 0.3048)
			(end 0.67945 0.3048)
			(stroke
				(width 0.1)
				(type default)
			)
			(layer "B.Fab")
		)
		(fp_line
			(start 0.12065 0.2794)
			(end 0.12065 0.3048)
			(stroke
				(width 0.1)
				(type default)
			)
			(layer "B.Fab")
		)
		(fp_line
			(start 0.12065 -0.2794)
			(end -0.12065 -0.2794)
			(stroke
				(width 0.1)
				(type default)
			)
			(layer "B.Fab")
		)
		(fp_line
			(start 0.12065 -0.305054)
			(end 0.12065 -0.2794)
			(stroke
				(width 0.1)
				(type default)
			)
			(layer "B.Fab")
		)
		(fp_line
			(start -0.120396 0.3048)
			(end -0.120396 0.2794)
			(stroke
				(width 0.1)
				(type default)
			)
			(layer "B.Fab")
		)
		(fp_line
			(start -0.120396 0.2794)
			(end 0.12065 0.2794)
			(stroke
				(width 0.1)
				(type default)
			)
			(layer "B.Fab")
		)
		(fp_line
			(start -0.12065 -0.2794)
			(end -0.12065 -0.3048)
			(stroke
				(width 0.1)
				(type default)
			)
			(layer "B.Fab")
		)
		(fp_line
			(start -0.12065 -0.3048)
			(end -0.67945 -0.3048)
			(stroke
				(width 0.1)
				(type default)
			)
			(layer "B.Fab")
		)
		(fp_line
			(start -0.67945 0.3048)
			(end -0.120396 0.3048)
			(stroke
				(width 0.1)
				(type default)
			)
			(layer "B.Fab")
		)
		(fp_line
			(start -0.67945 -0.3048)
			(end -0.67945 0.3048)
			(stroke
				(width 0.1)
				(type default)
			)
			(layer "B.Fab")
		)
		(pad "1" smd circle
			(at 0.40005 0)
			(size 0 0)
			(layers "B.Cu" "B.Mask" "B.Paste")
			(net "I3C_SPD_DDRABCD_CPU0_LVC1_SCL_7")
		)
		(pad "2" smd circle
			(at -0.40005 0)
			(size 0 0)
			(layers "B.Cu" "B.Mask" "B.Paste")
			(net "I3C_SPD_DDRABCD_CPU0_LVC1_SCL")
		)
	)
	(footprint ""
		(layer "B.Cu")
		(at 154.4955 -190.87211 -90)
		(property "Reference" "R1244"
			(at 0 0 90)
			(layer "B.SilkS")
			(hide yes)
			(effects
				(font
					(size 1.27 1.27)
				)
				(justify mirror)
			)
		)
		(property "Value" ""
			(at 0 0 90)
			(layer "B.Fab")
			(effects
				(font
					(size 1.27 1.27)
				)
				(justify mirror)
			)
		)
		(duplicate_pad_numbers_are_jumpers no)
		(fp_line
			(start -0.7874 0.4064)
			(end 0.7874 0.4064)
			(stroke
				(width 0.1524)
				(type default)
			)
			(layer "B.SilkS")
		)
		(fp_line
			(start 0.7874 0.4064)
			(end 0.7874 -0.4064)
			(stroke
				(width 0.1524)
				(type default)
			)
			(layer "B.SilkS")
		)
		(fp_line
			(start -0.7874 -0.4064)
			(end -0.7874 0.4064)
			(stroke
				(width 0.1524)
				(type default)
			)
			(layer "B.SilkS")
		)
		(fp_line
			(start 0.7874 -0.4064)
			(end -0.7874 -0.4064)
			(stroke
				(width 0.1524)
				(type default)
			)
			(layer "B.SilkS")
		)
		(fp_line
			(start -0.67945 0.3048)
			(end -0.120396 0.3048)
			(stroke
				(width 0.1)
				(type default)
			)
			(layer "B.Fab")
		)
		(fp_line
			(start -0.120396 0.3048)
			(end -0.120396 0.2794)
			(stroke
				(width 0.1)
				(type default)
			)
			(layer "B.Fab")
		)
		(fp_line
			(start 0.12065 0.3048)
			(end 0.67945 0.3048)
			(stroke
				(width 0.1)
				(type default)
			)
			(layer "B.Fab")
		)
		(fp_line
			(start 0.67945 0.3048)
			(end 0.67945 -0.305054)
			(stroke
				(width 0.1)
				(type default)
			)
			(layer "B.Fab")
		)
		(fp_line
			(start -0.120396 0.2794)
			(end 0.12065 0.2794)
			(stroke
				(width 0.1)
				(type default)
			)
			(layer "B.Fab")
		)
		(fp_line
			(start 0.12065 0.2794)
			(end 0.12065 0.3048)
			(stroke
				(width 0.1)
				(type default)
			)
			(layer "B.Fab")
		)
		(fp_line
			(start -0.12065 -0.2794)
			(end -0.12065 -0.3048)
			(stroke
				(width 0.1)
				(type default)
			)
			(layer "B.Fab")
		)
		(fp_line
			(start 0.12065 -0.2794)
			(end -0.12065 -0.2794)
			(stroke
				(width 0.1)
				(type default)
			)
			(layer "B.Fab")
		)
		(fp_line
			(start -0.67945 -0.3048)
			(end -0.67945 0.3048)
			(stroke
				(width 0.1)
				(type default)
			)
			(layer "B.Fab")
		)
		(fp_line
			(start -0.12065 -0.3048)
			(end -0.67945 -0.3048)
			(stroke
				(width 0.1)
				(type default)
			)
			(layer "B.Fab")
		)
		(fp_line
			(start 0.12065 -0.305054)
			(end 0.12065 -0.2794)
			(stroke
				(width 0.1)
				(type default)
			)
			(layer "B.Fab")
		)
		(fp_line
			(start 0.67945 -0.305054)
			(end 0.12065 -0.305054)
			(stroke
				(width 0.1)
				(type default)
			)
			(layer "B.Fab")
		)
		(pad "1" smd circle
			(at 0.40005 0 90)
			(size 0 0)
			(layers "B.Cu" "B.Mask" "B.Paste")
			(net "PVNN_TERM_CPU1")
		)
		(pad "2" smd circle
			(at -0.40005 0 90)
			(size 0 0)
			(layers "B.Cu" "B.Mask" "B.Paste")
			(net "H_CPU_PM_FAST_WAKE_N")
		)
	)
	(footprint ""
		(layer "B.Cu")
		(at 404.09241 -194.87007 90)
		(property "Reference" "R1239"
			(at 0 0 90)
			(layer "B.SilkS")
			(hide yes)
			(effects
				(font
					(size 1.27 1.27)
				)
				(justify mirror)
			)
		)
		(property "Value" ""
			(at 0 0 90)
			(layer "B.Fab")
			(effects
				(font
					(size 1.27 1.27)
				)
				(justify mirror)
			)
		)
		(duplicate_pad_numbers_are_jumpers no)
		(fp_line
			(start 0.7874 -0.4064)
			(end -0.7874 -0.4064)
			(stroke
				(width 0.1524)
				(type default)
			)
			(layer "B.SilkS")
		)
		(fp_line
			(start -0.7874 -0.4064)
			(end -0.7874 0.4064)
			(stroke
				(width 0.1524)
				(type default)
			)
			(layer "B.SilkS")
		)
		(fp_line
			(start 0.7874 0.4064)
			(end 0.7874 -0.4064)
			(stroke
				(width 0.1524)
				(type default)
			)
			(layer "B.SilkS")
		)
		(fp_line
			(start -0.7874 0.4064)
			(end 0.7874 0.4064)
			(stroke
				(width 0.1524)
				(type default)
			)
			(layer "B.SilkS")
		)
		(fp_line
			(start 0.67945 -0.305054)
			(end 0.12065 -0.305054)
			(stroke
				(width 0.1)
				(type default)
			)
			(layer "B.Fab")
		)
		(fp_line
			(start 0.12065 -0.305054)
			(end 0.12065 -0.2794)
			(stroke
				(width 0.1)
				(type default)
			)
			(layer "B.Fab")
		)
		(fp_line
			(start -0.12065 -0.3048)
			(end -0.67945 -0.3048)
			(stroke
				(width 0.1)
				(type default)
			)
			(layer "B.Fab")
		)
		(fp_line
			(start -0.67945 -0.3048)
			(end -0.67945 0.3048)
			(stroke
				(width 0.1)
				(type default)
			)
			(layer "B.Fab")
		)
		(fp_line
			(start 0.12065 -0.2794)
			(end -0.12065 -0.2794)
			(stroke
				(width 0.1)
				(type default)
			)
			(layer "B.Fab")
		)
		(fp_line
			(start -0.12065 -0.2794)
			(end -0.12065 -0.3048)
			(stroke
				(width 0.1)
				(type default)
			)
			(layer "B.Fab")
		)
		(fp_line
			(start 0.12065 0.2794)
			(end 0.12065 0.3048)
			(stroke
				(width 0.1)
				(type default)
			)
			(layer "B.Fab")
		)
		(fp_line
			(start -0.120396 0.2794)
			(end 0.12065 0.2794)
			(stroke
				(width 0.1)
				(type default)
			)
			(layer "B.Fab")
		)
		(fp_line
			(start 0.67945 0.3048)
			(end 0.67945 -0.305054)
			(stroke
				(width 0.1)
				(type default)
			)
			(layer "B.Fab")
		)
		(fp_line
			(start 0.12065 0.3048)
			(end 0.67945 0.3048)
			(stroke
				(width 0.1)
				(type default)
			)
			(layer "B.Fab")
		)
		(fp_line
			(start -0.120396 0.3048)
			(end -0.120396 0.2794)
			(stroke
				(width 0.1)
				(type default)
			)
			(layer "B.Fab")
		)
		(fp_line
			(start -0.67945 0.3048)
			(end -0.120396 0.3048)
			(stroke
				(width 0.1)
				(type default)
			)
			(layer "B.Fab")
		)
		(pad "1" smd circle
			(at 0.40005 0 270)
			(size 0 0)
			(layers "B.Cu" "B.Mask" "B.Paste")
			(net "GND")
		)
		(pad "2" smd circle
			(at -0.40005 0 270)
			(size 0 0)
			(layers "B.Cu" "B.Mask" "B.Paste")
			(net "PUD_XTAL_CPU0_MODE1")
		)
	)
	(footprint ""
		(layer "B.Cu")
		(at 183.7436 -21.351748 -90)
		(property "Reference" "R1319"
			(at 0 0 90)
			(layer "B.SilkS")
			(hide yes)
			(effects
				(font
					(size 1.27 1.27)
				)
				(justify mirror)
			)
		)
		(property "Value" ""
			(at 0 0 90)
			(layer "B.Fab")
			(effects
				(font
					(size 1.27 1.27)
				)
				(justify mirror)
			)
		)
		(duplicate_pad_numbers_are_jumpers no)
		(fp_line
			(start -0.7874 0.4064)
			(end 0.7874 0.4064)
			(stroke
				(width 0.1524)
				(type default)
			)
			(layer "B.SilkS")
		)
		(fp_line
			(start 0.7874 0.4064)
			(end 0.7874 -0.4064)
			(stroke
				(width 0.1524)
				(type default)
			)
			(layer "B.SilkS")
		)
		(fp_line
			(start -0.7874 -0.4064)
			(end -0.7874 0.4064)
			(stroke
				(width 0.1524)
				(type default)
			)
			(layer "B.SilkS")
		)
		(fp_line
			(start 0.7874 -0.4064)
			(end -0.7874 -0.4064)
			(stroke
				(width 0.1524)
				(type default)
			)
			(layer "B.SilkS")
		)
		(fp_line
			(start -0.67945 0.3048)
			(end -0.120396 0.3048)
			(stroke
				(width 0.1)
				(type default)
			)
			(layer "B.Fab")
		)
		(fp_line
			(start -0.120396 0.3048)
			(end -0.120396 0.2794)
			(stroke
				(width 0.1)
				(type default)
			)
			(layer "B.Fab")
		)
		(fp_line
			(start 0.12065 0.3048)
			(end 0.67945 0.3048)
			(stroke
				(width 0.1)
				(type default)
			)
			(layer "B.Fab")
		)
		(fp_line
			(start 0.67945 0.3048)
			(end 0.67945 -0.305054)
			(stroke
				(width 0.1)
				(type default)
			)
			(layer "B.Fab")
		)
		(fp_line
			(start -0.120396 0.2794)
			(end 0.12065 0.2794)
			(stroke
				(width 0.1)
				(type default)
			)
			(layer "B.Fab")
		)
		(fp_line
			(start 0.12065 0.2794)
			(end 0.12065 0.3048)
			(stroke
				(width 0.1)
				(type default)
			)
			(layer "B.Fab")
		)
		(fp_line
			(start -0.12065 -0.2794)
			(end -0.12065 -0.3048)
			(stroke
				(width 0.1)
				(type default)
			)
			(layer "B.Fab")
		)
		(fp_line
			(start 0.12065 -0.2794)
			(end -0.12065 -0.2794)
			(stroke
				(width 0.1)
				(type default)
			)
			(layer "B.Fab")
		)
		(fp_line
			(start -0.67945 -0.3048)
			(end -0.67945 0.3048)
			(stroke
				(width 0.1)
				(type default)
			)
			(layer "B.Fab")
		)
		(fp_line
			(start -0.12065 -0.3048)
			(end -0.67945 -0.3048)
			(stroke
				(width 0.1)
				(type default)
			)
			(layer "B.Fab")
		)
		(fp_line
			(start 0.12065 -0.305054)
			(end 0.12065 -0.2794)
			(stroke
				(width 0.1)
				(type default)
			)
			(layer "B.Fab")
		)
		(fp_line
			(start 0.67945 -0.305054)
			(end 0.12065 -0.305054)
			(stroke
				(width 0.1)
				(type default)
			)
			(layer "B.Fab")
		)
		(pad "1" smd circle
			(at 0.40005 0 90)
			(size 0 0)
			(layers "B.Cu" "B.Mask" "B.Paste")
			(net "SMB_HOST_3V3AUX_SCL")
		)
		(pad "2" smd circle
			(at -0.40005 0 90)
			(size 0 0)
			(layers "B.Cu" "B.Mask" "B.Paste")
			(net "P3V3_AUX")
		)
	)
	(footprint ""
		(layer "B.Cu")
		(at 371.273578 -189.56147 180)
		(property "Reference" "C559"
			(at 0 0 0)
			(layer "B.SilkS")
			(hide yes)
			(effects
				(font
					(size 1.27 1.27)
				)
				(justify mirror)
			)
		)
		(property "Value" ""
			(at 0 0 0)
			(layer "B.Fab")
			(effects
				(font
					(size 1.27 1.27)
				)
				(justify mirror)
			)
		)
		(duplicate_pad_numbers_are_jumpers no)
		(fp_line
			(start 0.7874 0.4064)
			(end 0.7874 -0.4064)
			(stroke
				(width 0.1524)
				(type default)
			)
			(layer "B.SilkS")
		)
		(fp_line
			(start 0.7874 -0.4064)
			(end -0.7874 -0.4064)
			(stroke
				(width 0.1524)
				(type default)
			)
			(layer "B.SilkS")
		)
		(fp_line
			(start -0.7874 0.4064)
			(end 0.7874 0.4064)
			(stroke
				(width 0.1524)
				(type default)
			)
			(layer "B.SilkS")
		)
		(fp_line
			(start -0.7874 -0.4064)
			(end -0.7874 0.4064)
			(stroke
				(width 0.1524)
				(type default)
			)
			(layer "B.SilkS")
		)
		(fp_line
			(start 0.67945 0.3048)
			(end 0.67945 -0.305054)
			(stroke
				(width 0.1)
				(type default)
			)
			(layer "B.Fab")
		)
		(fp_line
			(start 0.67945 -0.305054)
			(end 0.12065 -0.305054)
			(stroke
				(width 0.1)
				(type default)
			)
			(layer "B.Fab")
		)
		(fp_line
			(start 0.12065 0.3048)
			(end 0.67945 0.3048)
			(stroke
				(width 0.1)
				(type default)
			)
			(layer "B.Fab")
		)
		(fp_line
			(start 0.12065 0.2794)
			(end 0.12065 0.3048)
			(stroke
				(width 0.1)
				(type default)
			)
			(layer "B.Fab")
		)
		(fp_line
			(start 0.12065 -0.2794)
			(end -0.12065 -0.2794)
			(stroke
				(width 0.1)
				(type default)
			)
			(layer "B.Fab")
		)
		(fp_line
			(start 0.12065 -0.305054)
			(end 0.12065 -0.2794)
			(stroke
				(width 0.1)
				(type default)
			)
			(layer "B.Fab")
		)
		(fp_line
			(start -0.120396 0.3048)
			(end -0.120396 0.2794)
			(stroke
				(width 0.1)
				(type default)
			)
			(layer "B.Fab")
		)
		(fp_line
			(start -0.120396 0.2794)
			(end 0.12065 0.2794)
			(stroke
				(width 0.1)
				(type default)
			)
			(layer "B.Fab")
		)
		(fp_line
			(start -0.12065 -0.2794)
			(end -0.12065 -0.3048)
			(stroke
				(width 0.1)
				(type default)
			)
			(layer "B.Fab")
		)
		(fp_line
			(start -0.12065 -0.3048)
			(end -0.67945 -0.3048)
			(stroke
				(width 0.1)
				(type default)
			)
			(layer "B.Fab")
		)
		(fp_line
			(start -0.67945 0.3048)
			(end -0.120396 0.3048)
			(stroke
				(width 0.1)
				(type default)
			)
			(layer "B.Fab")
		)
		(fp_line
			(start -0.67945 -0.3048)
			(end -0.67945 0.3048)
			(stroke
				(width 0.1)
				(type default)
			)
			(layer "B.Fab")
		)
		(pad "1" smd circle
			(at 0.40005 0)
			(size 0 0)
			(layers "B.Cu" "B.Mask" "B.Paste")
			(net "PVNN_TERM_CPU0")
		)
		(pad "2" smd circle
			(at -0.40005 0)
			(size 0 0)
			(layers "B.Cu" "B.Mask" "B.Paste")
			(net "GND")
		)
	)
	(footprint ""
		(layer "B.Cu")
		(at 30.784546 -317.626746 180)
		(property "Reference" "R3896"
			(at 0 0 0)
			(layer "B.SilkS")
			(hide yes)
			(effects
				(font
					(size 1.27 1.27)
				)
				(justify mirror)
			)
		)
		(property "Value" ""
			(at 0 0 0)
			(layer "B.Fab")
			(effects
				(font
					(size 1.27 1.27)
				)
				(justify mirror)
			)
		)
		(duplicate_pad_numbers_are_jumpers no)
		(fp_line
			(start 0.7874 0.4064)
			(end 0.7874 -0.4064)
			(stroke
				(width 0.1524)
				(type default)
			)
			(layer "B.SilkS")
		)
		(fp_line
			(start 0.7874 -0.4064)
			(end -0.7874 -0.4064)
			(stroke
				(width 0.1524)
				(type default)
			)
			(layer "B.SilkS")
		)
		(fp_line
			(start -0.7874 0.4064)
			(end 0.7874 0.4064)
			(stroke
				(width 0.1524)
				(type default)
			)
			(layer "B.SilkS")
		)
		(fp_line
			(start -0.7874 -0.4064)
			(end -0.7874 0.4064)
			(stroke
				(width 0.1524)
				(type default)
			)
			(layer "B.SilkS")
		)
		(fp_line
			(start 0.67945 0.3048)
			(end 0.67945 -0.305054)
			(stroke
				(width 0.1)
				(type default)
			)
			(layer "B.Fab")
		)
		(fp_line
			(start 0.67945 -0.305054)
			(end 0.12065 -0.305054)
			(stroke
				(width 0.1)
				(type default)
			)
			(layer "B.Fab")
		)
		(fp_line
			(start 0.12065 0.3048)
			(end 0.67945 0.3048)
			(stroke
				(width 0.1)
				(type default)
			)
			(layer "B.Fab")
		)
		(fp_line
			(start 0.12065 0.2794)
			(end 0.12065 0.3048)
			(stroke
				(width 0.1)
				(type default)
			)
			(layer "B.Fab")
		)
		(fp_line
			(start 0.12065 -0.2794)
			(end -0.12065 -0.2794)
			(stroke
				(width 0.1)
				(type default)
			)
			(layer "B.Fab")
		)
		(fp_line
			(start 0.12065 -0.305054)
			(end 0.12065 -0.2794)
			(stroke
				(width 0.1)
				(type default)
			)
			(layer "B.Fab")
		)
		(fp_line
			(start -0.120396 0.3048)
			(end -0.120396 0.2794)
			(stroke
				(width 0.1)
				(type default)
			)
			(layer "B.Fab")
		)
		(fp_line
			(start -0.120396 0.2794)
			(end 0.12065 0.2794)
			(stroke
				(width 0.1)
				(type default)
			)
			(layer "B.Fab")
		)
		(fp_line
			(start -0.12065 -0.2794)
			(end -0.12065 -0.3048)
			(stroke
				(width 0.1)
				(type default)
			)
			(layer "B.Fab")
		)
		(fp_line
			(start -0.12065 -0.3048)
			(end -0.67945 -0.3048)
			(stroke
				(width 0.1)
				(type default)
			)
			(layer "B.Fab")
		)
		(fp_line
			(start -0.67945 0.3048)
			(end -0.120396 0.3048)
			(stroke
				(width 0.1)
				(type default)
			)
			(layer "B.Fab")
		)
		(fp_line
			(start -0.67945 -0.3048)
			(end -0.67945 0.3048)
			(stroke
				(width 0.1)
				(type default)
			)
			(layer "B.Fab")
		)
		(pad "1" smd circle
			(at 0.40005 0)
			(size 0 0)
			(layers "B.Cu" "B.Mask" "B.Paste")
			(net "I3C_SPD_DDRABCD_CPU1_LVC1_SCL_5")
		)
		(pad "2" smd circle
			(at -0.40005 0)
			(size 0 0)
			(layers "B.Cu" "B.Mask" "B.Paste")
			(net "I3C_SPD_DDRABCD_CPU1_LVC1_SCL")
		)
	)
	(footprint ""
		(layer "B.Cu")
		(at 355.397308 -252.176026 -90)
		(property "Reference" "C371"
			(at 0 0 90)
			(layer "B.SilkS")
			(hide yes)
			(effects
				(font
					(size 1.27 1.27)
				)
				(justify mirror)
			)
		)
		(property "Value" ""
			(at 0 0 90)
			(layer "B.Fab")
			(effects
				(font
					(size 1.27 1.27)
				)
				(justify mirror)
			)
		)
		(duplicate_pad_numbers_are_jumpers no)
		(fp_line
			(start -1.524 0.762)
			(end 1.524 0.762)
			(stroke
				(width 0.1524)
				(type default)
			)
			(layer "B.SilkS")
		)
		(fp_line
			(start 1.524 0.762)
			(end 1.524 -0.762)
			(stroke
				(width 0.1524)
				(type default)
			)
			(layer "B.SilkS")
		)
		(fp_line
			(start -1.524 -0.762)
			(end -1.524 0.762)
			(stroke
				(width 0.1524)
				(type default)
			)
			(layer "B.SilkS")
		)
		(fp_line
			(start 1.524 -0.762)
			(end -1.524 -0.762)
			(stroke
				(width 0.1524)
				(type default)
			)
			(layer "B.SilkS")
		)
		(fp_line
			(start -1.1049 0.724916)
			(end -1.1049 -0.724916)
			(stroke
				(width 0.1)
				(type default)
			)
			(layer "B.Fab")
		)
		(fp_line
			(start 1.1049 0.724916)
			(end -1.1049 0.724916)
			(stroke
				(width 0.1)
				(type default)
			)
			(layer "B.Fab")
		)
		(fp_line
			(start -1.1049 -0.724916)
			(end 1.1049 -0.724916)
			(stroke
				(width 0.1)
				(type default)
			)
			(layer "B.Fab")
		)
		(fp_line
			(start 1.1049 -0.724916)
			(end 1.1049 0.724916)
			(stroke
				(width 0.1)
				(type default)
			)
			(layer "B.Fab")
		)
		(pad "1" smd rect
			(at 0.889 0 270)
			(size 1.016 1.27)
			(layers "B.Cu" "B.Mask" "B.Paste")
			(net "PVCCIN_CPU0")
		)
		(pad "2" smd rect
			(at -0.889 0 270)
			(size 1.016 1.27)
			(layers "B.Cu" "B.Mask" "B.Paste")
			(net "GND")
		)
	)
	(footprint ""
		(layer "B.Cu")
		(at 122.157744 -354.189538)
		(property "Reference" "R2374"
			(at 0 0 0)
			(layer "B.SilkS")
			(hide yes)
			(effects
				(font
					(size 1.27 1.27)
				)
				(justify mirror)
			)
		)
		(property "Value" ""
			(at 0 0 0)
			(layer "B.Fab")
			(effects
				(font
					(size 1.27 1.27)
				)
				(justify mirror)
			)
		)
		(duplicate_pad_numbers_are_jumpers no)
		(fp_line
			(start -0.7874 -0.4064)
			(end -0.7874 0.4064)
			(stroke
				(width 0.1524)
				(type default)
			)
			(layer "B.SilkS")
		)
		(fp_line
			(start -0.7874 0.4064)
			(end 0.7874 0.4064)
			(stroke
				(width 0.1524)
				(type default)
			)
			(layer "B.SilkS")
		)
		(fp_line
			(start 0.7874 -0.4064)
			(end -0.7874 -0.4064)
			(stroke
				(width 0.1524)
				(type default)
			)
			(layer "B.SilkS")
		)
		(fp_line
			(start 0.7874 0.4064)
			(end 0.7874 -0.4064)
			(stroke
				(width 0.1524)
				(type default)
			)
			(layer "B.SilkS")
		)
		(fp_line
			(start -0.67945 -0.3048)
			(end -0.67945 0.3048)
			(stroke
				(width 0.1)
				(type default)
			)
			(layer "B.Fab")
		)
		(fp_line
			(start -0.67945 0.3048)
			(end -0.120396 0.3048)
			(stroke
				(width 0.1)
				(type default)
			)
			(layer "B.Fab")
		)
		(fp_line
			(start -0.12065 -0.3048)
			(end -0.67945 -0.3048)
			(stroke
				(width 0.1)
				(type default)
			)
			(layer "B.Fab")
		)
		(fp_line
			(start -0.12065 -0.2794)
			(end -0.12065 -0.3048)
			(stroke
				(width 0.1)
				(type default)
			)
			(layer "B.Fab")
		)
		(fp_line
			(start -0.120396 0.2794)
			(end 0.12065 0.2794)
			(stroke
				(width 0.1)
				(type default)
			)
			(layer "B.Fab")
		)
		(fp_line
			(start -0.120396 0.3048)
			(end -0.120396 0.2794)
			(stroke
				(width 0.1)
				(type default)
			)
			(layer "B.Fab")
		)
		(fp_line
			(start 0.12065 -0.305054)
			(end 0.12065 -0.2794)
			(stroke
				(width 0.1)
				(type default)
			)
			(layer "B.Fab")
		)
		(fp_line
			(start 0.12065 -0.2794)
			(end -0.12065 -0.2794)
			(stroke
				(width 0.1)
				(type default)
			)
			(layer "B.Fab")
		)
		(fp_line
			(start 0.12065 0.2794)
			(end 0.12065 0.3048)
			(stroke
				(width 0.1)
				(type default)
			)
			(layer "B.Fab")
		)
		(fp_line
			(start 0.12065 0.3048)
			(end 0.67945 0.3048)
			(stroke
				(width 0.1)
				(type default)
			)
			(layer "B.Fab")
		)
		(fp_line
			(start 0.67945 -0.305054)
			(end 0.12065 -0.305054)
			(stroke
				(width 0.1)
				(type default)
			)
			(layer "B.Fab")
		)
		(fp_line
			(start 0.67945 0.3048)
			(end 0.67945 -0.305054)
			(stroke
				(width 0.1)
				(type default)
			)
			(layer "B.Fab")
		)
		(pad "1" smd circle
			(at 0.40005 0 180)
			(size 0 0)
			(layers "B.Cu" "B.Mask" "B.Paste")
			(net "FM_PVPP_HBM_CPU1_EN")
		)
		(pad "2" smd circle
			(at -0.40005 0 180)
			(size 0 0)
			(layers "B.Cu" "B.Mask" "B.Paste")
			(net "GND")
		)
	)
	(footprint ""
		(layer "B.Cu")
		(at 258.953 -100.167948)
		(property "Reference" "C115"
			(at 0 0 0)
			(layer "B.SilkS")
			(hide yes)
			(effects
				(font
					(size 1.27 1.27)
				)
				(justify mirror)
			)
		)
		(property "Value" ""
			(at 0 0 0)
			(layer "B.Fab")
			(effects
				(font
					(size 1.27 1.27)
				)
				(justify mirror)
			)
		)
		(duplicate_pad_numbers_are_jumpers no)
		(fp_line
			(start -0.7874 -0.4064)
			(end -0.7874 0.4064)
			(stroke
				(width 0.1524)
				(type default)
			)
			(layer "B.SilkS")
		)
		(fp_line
			(start -0.7874 0.4064)
			(end 0.7874 0.4064)
			(stroke
				(width 0.1524)
				(type default)
			)
			(layer "B.SilkS")
		)
		(fp_line
			(start 0.7874 -0.4064)
			(end -0.7874 -0.4064)
			(stroke
				(width 0.1524)
				(type default)
			)
			(layer "B.SilkS")
		)
		(fp_line
			(start 0.7874 0.4064)
			(end 0.7874 -0.4064)
			(stroke
				(width 0.1524)
				(type default)
			)
			(layer "B.SilkS")
		)
		(fp_line
			(start -0.67945 -0.3048)
			(end -0.67945 0.3048)
			(stroke
				(width 0.1)
				(type default)
			)
			(layer "B.Fab")
		)
		(fp_line
			(start -0.67945 0.3048)
			(end -0.120396 0.3048)
			(stroke
				(width 0.1)
				(type default)
			)
			(layer "B.Fab")
		)
		(fp_line
			(start -0.12065 -0.3048)
			(end -0.67945 -0.3048)
			(stroke
				(width 0.1)
				(type default)
			)
			(layer "B.Fab")
		)
		(fp_line
			(start -0.12065 -0.2794)
			(end -0.12065 -0.3048)
			(stroke
				(width 0.1)
				(type default)
			)
			(layer "B.Fab")
		)
		(fp_line
			(start -0.120396 0.2794)
			(end 0.12065 0.2794)
			(stroke
				(width 0.1)
				(type default)
			)
			(layer "B.Fab")
		)
		(fp_line
			(start -0.120396 0.3048)
			(end -0.120396 0.2794)
			(stroke
				(width 0.1)
				(type default)
			)
			(layer "B.Fab")
		)
		(fp_line
			(start 0.12065 -0.305054)
			(end 0.12065 -0.2794)
			(stroke
				(width 0.1)
				(type default)
			)
			(layer "B.Fab")
		)
		(fp_line
			(start 0.12065 -0.2794)
			(end -0.12065 -0.2794)
			(stroke
				(width 0.1)
				(type default)
			)
			(layer "B.Fab")
		)
		(fp_line
			(start 0.12065 0.2794)
			(end 0.12065 0.3048)
			(stroke
				(width 0.1)
				(type default)
			)
			(layer "B.Fab")
		)
		(fp_line
			(start 0.12065 0.3048)
			(end 0.67945 0.3048)
			(stroke
				(width 0.1)
				(type default)
			)
			(layer "B.Fab")
		)
		(fp_line
			(start 0.67945 -0.305054)
			(end 0.12065 -0.305054)
			(stroke
				(width 0.1)
				(type default)
			)
			(layer "B.Fab")
		)
		(fp_line
			(start 0.67945 0.3048)
			(end 0.67945 -0.305054)
			(stroke
				(width 0.1)
				(type default)
			)
			(layer "B.Fab")
		)
		(pad "1" smd circle
			(at 0.40005 0 180)
			(size 0 0)
			(layers "B.Cu" "B.Mask" "B.Paste")
			(net "P3V3_AUX_CLK_GEN_VDDMXCK_CK440")
		)
		(pad "2" smd circle
			(at -0.40005 0 180)
			(size 0 0)
			(layers "B.Cu" "B.Mask" "B.Paste")
			(net "GND")
		)
	)
	(footprint ""
		(layer "B.Cu")
		(at 150.900638 -13.762228 90)
		(property "Reference" "R2418"
			(at 0 0 90)
			(layer "B.SilkS")
			(hide yes)
			(effects
				(font
					(size 1.27 1.27)
				)
				(justify mirror)
			)
		)
		(property "Value" ""
			(at 0 0 90)
			(layer "B.Fab")
			(effects
				(font
					(size 1.27 1.27)
				)
				(justify mirror)
			)
		)
		(duplicate_pad_numbers_are_jumpers no)
		(fp_line
			(start 0.7874 -0.4064)
			(end -0.7874 -0.4064)
			(stroke
				(width 0.1524)
				(type default)
			)
			(layer "B.SilkS")
		)
		(fp_line
			(start -0.7874 -0.4064)
			(end -0.7874 0.4064)
			(stroke
				(width 0.1524)
				(type default)
			)
			(layer "B.SilkS")
		)
		(fp_line
			(start 0.7874 0.4064)
			(end 0.7874 -0.4064)
			(stroke
				(width 0.1524)
				(type default)
			)
			(layer "B.SilkS")
		)
		(fp_line
			(start -0.7874 0.4064)
			(end 0.7874 0.4064)
			(stroke
				(width 0.1524)
				(type default)
			)
			(layer "B.SilkS")
		)
		(fp_line
			(start 0.67945 -0.305054)
			(end 0.12065 -0.305054)
			(stroke
				(width 0.1)
				(type default)
			)
			(layer "B.Fab")
		)
		(fp_line
			(start 0.12065 -0.305054)
			(end 0.12065 -0.2794)
			(stroke
				(width 0.1)
				(type default)
			)
			(layer "B.Fab")
		)
		(fp_line
			(start -0.12065 -0.3048)
			(end -0.67945 -0.3048)
			(stroke
				(width 0.1)
				(type default)
			)
			(layer "B.Fab")
		)
		(fp_line
			(start -0.67945 -0.3048)
			(end -0.67945 0.3048)
			(stroke
				(width 0.1)
				(type default)
			)
			(layer "B.Fab")
		)
		(fp_line
			(start 0.12065 -0.2794)
			(end -0.12065 -0.2794)
			(stroke
				(width 0.1)
				(type default)
			)
			(layer "B.Fab")
		)
		(fp_line
			(start -0.12065 -0.2794)
			(end -0.12065 -0.3048)
			(stroke
				(width 0.1)
				(type default)
			)
			(layer "B.Fab")
		)
		(fp_line
			(start 0.12065 0.2794)
			(end 0.12065 0.3048)
			(stroke
				(width 0.1)
				(type default)
			)
			(layer "B.Fab")
		)
		(fp_line
			(start -0.120396 0.2794)
			(end 0.12065 0.2794)
			(stroke
				(width 0.1)
				(type default)
			)
			(layer "B.Fab")
		)
		(fp_line
			(start 0.67945 0.3048)
			(end 0.67945 -0.305054)
			(stroke
				(width 0.1)
				(type default)
			)
			(layer "B.Fab")
		)
		(fp_line
			(start 0.12065 0.3048)
			(end 0.67945 0.3048)
			(stroke
				(width 0.1)
				(type default)
			)
			(layer "B.Fab")
		)
		(fp_line
			(start -0.120396 0.3048)
			(end -0.120396 0.2794)
			(stroke
				(width 0.1)
				(type default)
			)
			(layer "B.Fab")
		)
		(fp_line
			(start -0.67945 0.3048)
			(end -0.120396 0.3048)
			(stroke
				(width 0.1)
				(type default)
			)
			(layer "B.Fab")
		)
		(pad "1" smd circle
			(at 0.40005 0 270)
			(size 0 0)
			(layers "B.Cu" "B.Mask" "B.Paste")
			(net "SMB_S3M_CPU_3V3AUX_SDA")
		)
		(pad "2" smd circle
			(at -0.40005 0 270)
			(size 0 0)
			(layers "B.Cu" "B.Mask" "B.Paste")
			(net "SMB_S3M_CPU_3V3AUX_SDA_R0")
		)
	)
	(footprint ""
		(layer "B.Cu")
		(at 404.011892 -54.754272 180)
		(property "Reference" "C548"
			(at 0 0 0)
			(layer "B.SilkS")
			(hide yes)
			(effects
				(font
					(size 1.27 1.27)
				)
				(justify mirror)
			)
		)
		(property "Value" ""
			(at 0 0 0)
			(layer "B.Fab")
			(effects
				(font
					(size 1.27 1.27)
				)
				(justify mirror)
			)
		)
		(duplicate_pad_numbers_are_jumpers no)
		(fp_line
			(start 0.7874 0.4064)
			(end 0.7874 -0.4064)
			(stroke
				(width 0.1524)
				(type default)
			)
			(layer "B.SilkS")
		)
		(fp_line
			(start 0.7874 -0.4064)
			(end -0.7874 -0.4064)
			(stroke
				(width 0.1524)
				(type default)
			)
			(layer "B.SilkS")
		)
		(fp_line
			(start -0.7874 0.4064)
			(end 0.7874 0.4064)
			(stroke
				(width 0.1524)
				(type default)
			)
			(layer "B.SilkS")
		)
		(fp_line
			(start -0.7874 -0.4064)
			(end -0.7874 0.4064)
			(stroke
				(width 0.1524)
				(type default)
			)
			(layer "B.SilkS")
		)
		(fp_line
			(start 0.67945 0.3048)
			(end 0.67945 -0.305054)
			(stroke
				(width 0.1)
				(type default)
			)
			(layer "B.Fab")
		)
		(fp_line
			(start 0.67945 -0.305054)
			(end 0.12065 -0.305054)
			(stroke
				(width 0.1)
				(type default)
			)
			(layer "B.Fab")
		)
		(fp_line
			(start 0.12065 0.3048)
			(end 0.67945 0.3048)
			(stroke
				(width 0.1)
				(type default)
			)
			(layer "B.Fab")
		)
		(fp_line
			(start 0.12065 0.2794)
			(end 0.12065 0.3048)
			(stroke
				(width 0.1)
				(type default)
			)
			(layer "B.Fab")
		)
		(fp_line
			(start 0.12065 -0.2794)
			(end -0.12065 -0.2794)
			(stroke
				(width 0.1)
				(type default)
			)
			(layer "B.Fab")
		)
		(fp_line
			(start 0.12065 -0.305054)
			(end 0.12065 -0.2794)
			(stroke
				(width 0.1)
				(type default)
			)
			(layer "B.Fab")
		)
		(fp_line
			(start -0.120396 0.3048)
			(end -0.120396 0.2794)
			(stroke
				(width 0.1)
				(type default)
			)
			(layer "B.Fab")
		)
		(fp_line
			(start -0.120396 0.2794)
			(end 0.12065 0.2794)
			(stroke
				(width 0.1)
				(type default)
			)
			(layer "B.Fab")
		)
		(fp_line
			(start -0.12065 -0.2794)
			(end -0.12065 -0.3048)
			(stroke
				(width 0.1)
				(type default)
			)
			(layer "B.Fab")
		)
		(fp_line
			(start -0.12065 -0.3048)
			(end -0.67945 -0.3048)
			(stroke
				(width 0.1)
				(type default)
			)
			(layer "B.Fab")
		)
		(fp_line
			(start -0.67945 0.3048)
			(end -0.120396 0.3048)
			(stroke
				(width 0.1)
				(type default)
			)
			(layer "B.Fab")
		)
		(fp_line
			(start -0.67945 -0.3048)
			(end -0.67945 0.3048)
			(stroke
				(width 0.1)
				(type default)
			)
			(layer "B.Fab")
		)
		(pad "1" smd circle
			(at 0.40005 0)
			(size 0 0)
			(layers "B.Cu" "B.Mask" "B.Paste")
			(net "JTAG_DBP_POWER_BTN_N")
		)
		(pad "2" smd circle
			(at -0.40005 0)
			(size 0 0)
			(layers "B.Cu" "B.Mask" "B.Paste")
			(net "GND")
		)
	)
	(footprint ""
		(layer "B.Cu")
		(at 116.40312 -259.53212 90)
		(property "Reference" "C450"
			(at 0 0 90)
			(layer "B.SilkS")
			(hide yes)
			(effects
				(font
					(size 1.27 1.27)
				)
				(justify mirror)
			)
		)
		(property "Value" ""
			(at 0 0 90)
			(layer "B.Fab")
			(effects
				(font
					(size 1.27 1.27)
				)
				(justify mirror)
			)
		)
		(duplicate_pad_numbers_are_jumpers no)
		(fp_line
			(start 1.524 -0.762)
			(end -1.524 -0.762)
			(stroke
				(width 0.1524)
				(type default)
			)
			(layer "B.SilkS")
		)
		(fp_line
			(start -1.524 -0.762)
			(end -1.524 0.762)
			(stroke
				(width 0.1524)
				(type default)
			)
			(layer "B.SilkS")
		)
		(fp_line
			(start 1.524 0.762)
			(end 1.524 -0.762)
			(stroke
				(width 0.1524)
				(type default)
			)
			(layer "B.SilkS")
		)
		(fp_line
			(start -1.524 0.762)
			(end 1.524 0.762)
			(stroke
				(width 0.1524)
				(type default)
			)
			(layer "B.SilkS")
		)
		(fp_line
			(start 1.1049 -0.724916)
			(end 1.1049 0.724916)
			(stroke
				(width 0.1)
				(type default)
			)
			(layer "B.Fab")
		)
		(fp_line
			(start -1.1049 -0.724916)
			(end 1.1049 -0.724916)
			(stroke
				(width 0.1)
				(type default)
			)
			(layer "B.Fab")
		)
		(fp_line
			(start 1.1049 0.724916)
			(end -1.1049 0.724916)
			(stroke
				(width 0.1)
				(type default)
			)
			(layer "B.Fab")
		)
		(fp_line
			(start -1.1049 0.724916)
			(end -1.1049 -0.724916)
			(stroke
				(width 0.1)
				(type default)
			)
			(layer "B.Fab")
		)
		(pad "1" smd rect
			(at 0.889 0 90)
			(size 1.016 1.27)
			(layers "B.Cu" "B.Mask" "B.Paste")
			(net "PVCCFA_EHV_FIVRA_CPU1")
		)
		(pad "2" smd rect
			(at -0.889 0 90)
			(size 1.016 1.27)
			(layers "B.Cu" "B.Mask" "B.Paste")
			(net "GND")
		)
	)
	(footprint ""
		(layer "B.Cu")
		(at 48.344328 -354.558854 -90)
		(property "Reference" "PR227"
			(at 0 0 90)
			(layer "B.SilkS")
			(hide yes)
			(effects
				(font
					(size 1.27 1.27)
				)
				(justify mirror)
			)
		)
		(property "Value" ""
			(at 0 0 90)
			(layer "B.Fab")
			(effects
				(font
					(size 1.27 1.27)
				)
				(justify mirror)
			)
		)
		(duplicate_pad_numbers_are_jumpers no)
		(fp_line
			(start -0.7874 0.4064)
			(end 0.7874 0.4064)
			(stroke
				(width 0.1524)
				(type default)
			)
			(layer "B.SilkS")
		)
		(fp_line
			(start 0.7874 0.4064)
			(end 0.7874 -0.4064)
			(stroke
				(width 0.1524)
				(type default)
			)
			(layer "B.SilkS")
		)
		(fp_line
			(start -0.7874 -0.4064)
			(end -0.7874 0.4064)
			(stroke
				(width 0.1524)
				(type default)
			)
			(layer "B.SilkS")
		)
		(fp_line
			(start 0.7874 -0.4064)
			(end -0.7874 -0.4064)
			(stroke
				(width 0.1524)
				(type default)
			)
			(layer "B.SilkS")
		)
		(fp_line
			(start -0.67945 0.3048)
			(end -0.120396 0.3048)
			(stroke
				(width 0.1)
				(type default)
			)
			(layer "B.Fab")
		)
		(fp_line
			(start -0.120396 0.3048)
			(end -0.120396 0.2794)
			(stroke
				(width 0.1)
				(type default)
			)
			(layer "B.Fab")
		)
		(fp_line
			(start 0.12065 0.3048)
			(end 0.67945 0.3048)
			(stroke
				(width 0.1)
				(type default)
			)
			(layer "B.Fab")
		)
		(fp_line
			(start 0.67945 0.3048)
			(end 0.67945 -0.305054)
			(stroke
				(width 0.1)
				(type default)
			)
			(layer "B.Fab")
		)
		(fp_line
			(start -0.120396 0.2794)
			(end 0.12065 0.2794)
			(stroke
				(width 0.1)
				(type default)
			)
			(layer "B.Fab")
		)
		(fp_line
			(start 0.12065 0.2794)
			(end 0.12065 0.3048)
			(stroke
				(width 0.1)
				(type default)
			)
			(layer "B.Fab")
		)
		(fp_line
			(start -0.12065 -0.2794)
			(end -0.12065 -0.3048)
			(stroke
				(width 0.1)
				(type default)
			)
			(layer "B.Fab")
		)
		(fp_line
			(start 0.12065 -0.2794)
			(end -0.12065 -0.2794)
			(stroke
				(width 0.1)
				(type default)
			)
			(layer "B.Fab")
		)
		(fp_line
			(start -0.67945 -0.3048)
			(end -0.67945 0.3048)
			(stroke
				(width 0.1)
				(type default)
			)
			(layer "B.Fab")
		)
		(fp_line
			(start -0.12065 -0.3048)
			(end -0.67945 -0.3048)
			(stroke
				(width 0.1)
				(type default)
			)
			(layer "B.Fab")
		)
		(fp_line
			(start 0.12065 -0.305054)
			(end 0.12065 -0.2794)
			(stroke
				(width 0.1)
				(type default)
			)
			(layer "B.Fab")
		)
		(fp_line
			(start 0.67945 -0.305054)
			(end 0.12065 -0.305054)
			(stroke
				(width 0.1)
				(type default)
			)
			(layer "B.Fab")
		)
		(pad "1" smd circle
			(at 0.40005 0 90)
			(size 0 0)
			(layers "B.Cu" "B.Mask" "B.Paste")
			(net "PVCCFA_EHV_FIVRA_CPU1_PVCC2")
		)
		(pad "2" smd circle
			(at -0.40005 0 90)
			(size 0 0)
			(layers "B.Cu" "B.Mask" "B.Paste")
			(net "PVCCFA_EHV_FIVRA_CPU1_VDD2")
		)
	)
	(footprint ""
		(layer "B.Cu")
		(at 206.176372 -72.214994 180)
		(property "Reference" "R3215"
			(at 0 0 0)
			(layer "B.SilkS")
			(hide yes)
			(effects
				(font
					(size 1.27 1.27)
				)
				(justify mirror)
			)
		)
		(property "Value" ""
			(at 0 0 0)
			(layer "B.Fab")
			(effects
				(font
					(size 1.27 1.27)
				)
				(justify mirror)
			)
		)
		(duplicate_pad_numbers_are_jumpers no)
		(fp_line
			(start 0.7874 0.4064)
			(end 0.7874 -0.4064)
			(stroke
				(width 0.1524)
				(type default)
			)
			(layer "B.SilkS")
		)
		(fp_line
			(start 0.7874 -0.4064)
			(end -0.7874 -0.4064)
			(stroke
				(width 0.1524)
				(type default)
			)
			(layer "B.SilkS")
		)
		(fp_line
			(start -0.7874 0.4064)
			(end 0.7874 0.4064)
			(stroke
				(width 0.1524)
				(type default)
			)
			(layer "B.SilkS")
		)
		(fp_line
			(start -0.7874 -0.4064)
			(end -0.7874 0.4064)
			(stroke
				(width 0.1524)
				(type default)
			)
			(layer "B.SilkS")
		)
		(fp_line
			(start 0.67945 0.3048)
			(end 0.67945 -0.305054)
			(stroke
				(width 0.1)
				(type default)
			)
			(layer "B.Fab")
		)
		(fp_line
			(start 0.67945 -0.305054)
			(end 0.12065 -0.305054)
			(stroke
				(width 0.1)
				(type default)
			)
			(layer "B.Fab")
		)
		(fp_line
			(start 0.12065 0.3048)
			(end 0.67945 0.3048)
			(stroke
				(width 0.1)
				(type default)
			)
			(layer "B.Fab")
		)
		(fp_line
			(start 0.12065 0.2794)
			(end 0.12065 0.3048)
			(stroke
				(width 0.1)
				(type default)
			)
			(layer "B.Fab")
		)
		(fp_line
			(start 0.12065 -0.2794)
			(end -0.12065 -0.2794)
			(stroke
				(width 0.1)
				(type default)
			)
			(layer "B.Fab")
		)
		(fp_line
			(start 0.12065 -0.305054)
			(end 0.12065 -0.2794)
			(stroke
				(width 0.1)
				(type default)
			)
			(layer "B.Fab")
		)
		(fp_line
			(start -0.120396 0.3048)
			(end -0.120396 0.2794)
			(stroke
				(width 0.1)
				(type default)
			)
			(layer "B.Fab")
		)
		(fp_line
			(start -0.120396 0.2794)
			(end 0.12065 0.2794)
			(stroke
				(width 0.1)
				(type default)
			)
			(layer "B.Fab")
		)
		(fp_line
			(start -0.12065 -0.2794)
			(end -0.12065 -0.3048)
			(stroke
				(width 0.1)
				(type default)
			)
			(layer "B.Fab")
		)
		(fp_line
			(start -0.12065 -0.3048)
			(end -0.67945 -0.3048)
			(stroke
				(width 0.1)
				(type default)
			)
			(layer "B.Fab")
		)
		(fp_line
			(start -0.67945 0.3048)
			(end -0.120396 0.3048)
			(stroke
				(width 0.1)
				(type default)
			)
			(layer "B.Fab")
		)
		(fp_line
			(start -0.67945 -0.3048)
			(end -0.67945 0.3048)
			(stroke
				(width 0.1)
				(type default)
			)
			(layer "B.Fab")
		)
		(pad "1" smd circle
			(at 0.40005 0)
			(size 0 0)
			(layers "B.Cu" "B.Mask" "B.Paste")
			(net "NCSI_BMC_TXD1_R1")
		)
		(pad "2" smd circle
			(at -0.40005 0)
			(size 0 0)
			(layers "B.Cu" "B.Mask" "B.Paste")
			(net "RMII_BMC_OCP_TXD_1")
		)
	)
	(footprint ""
		(layer "B.Cu")
		(at 36.791392 -176.52238 180)
		(property "Reference" "C1366"
			(at 0 0 0)
			(layer "B.SilkS")
			(hide yes)
			(effects
				(font
					(size 1.27 1.27)
				)
				(justify mirror)
			)
		)
		(property "Value" ""
			(at 0 0 0)
			(layer "B.Fab")
			(effects
				(font
					(size 1.27 1.27)
				)
				(justify mirror)
			)
		)
		(duplicate_pad_numbers_are_jumpers no)
		(fp_line
			(start 0.7874 0.4064)
			(end 0.7874 -0.4064)
			(stroke
				(width 0.1524)
				(type default)
			)
			(layer "B.SilkS")
		)
		(fp_line
			(start 0.7874 -0.4064)
			(end -0.7874 -0.4064)
			(stroke
				(width 0.1524)
				(type default)
			)
			(layer "B.SilkS")
		)
		(fp_line
			(start -0.7874 0.4064)
			(end 0.7874 0.4064)
			(stroke
				(width 0.1524)
				(type default)
			)
			(layer "B.SilkS")
		)
		(fp_line
			(start -0.7874 -0.4064)
			(end -0.7874 0.4064)
			(stroke
				(width 0.1524)
				(type default)
			)
			(layer "B.SilkS")
		)
		(fp_line
			(start 0.67945 0.3048)
			(end 0.67945 -0.305054)
			(stroke
				(width 0.1)
				(type default)
			)
			(layer "B.Fab")
		)
		(fp_line
			(start 0.67945 -0.305054)
			(end 0.12065 -0.305054)
			(stroke
				(width 0.1)
				(type default)
			)
			(layer "B.Fab")
		)
		(fp_line
			(start 0.12065 0.3048)
			(end 0.67945 0.3048)
			(stroke
				(width 0.1)
				(type default)
			)
			(layer "B.Fab")
		)
		(fp_line
			(start 0.12065 0.2794)
			(end 0.12065 0.3048)
			(stroke
				(width 0.1)
				(type default)
			)
			(layer "B.Fab")
		)
		(fp_line
			(start 0.12065 -0.2794)
			(end -0.12065 -0.2794)
			(stroke
				(width 0.1)
				(type default)
			)
			(layer "B.Fab")
		)
		(fp_line
			(start 0.12065 -0.305054)
			(end 0.12065 -0.2794)
			(stroke
				(width 0.1)
				(type default)
			)
			(layer "B.Fab")
		)
		(fp_line
			(start -0.120396 0.3048)
			(end -0.120396 0.2794)
			(stroke
				(width 0.1)
				(type default)
			)
			(layer "B.Fab")
		)
		(fp_line
			(start -0.120396 0.2794)
			(end 0.12065 0.2794)
			(stroke
				(width 0.1)
				(type default)
			)
			(layer "B.Fab")
		)
		(fp_line
			(start -0.12065 -0.2794)
			(end -0.12065 -0.3048)
			(stroke
				(width 0.1)
				(type default)
			)
			(layer "B.Fab")
		)
		(fp_line
			(start -0.12065 -0.3048)
			(end -0.67945 -0.3048)
			(stroke
				(width 0.1)
				(type default)
			)
			(layer "B.Fab")
		)
		(fp_line
			(start -0.67945 0.3048)
			(end -0.120396 0.3048)
			(stroke
				(width 0.1)
				(type default)
			)
			(layer "B.Fab")
		)
		(fp_line
			(start -0.67945 -0.3048)
			(end -0.67945 0.3048)
			(stroke
				(width 0.1)
				(type default)
			)
			(layer "B.Fab")
		)
		(pad "1" smd circle
			(at 0.40005 0)
			(size 0 0)
			(layers "B.Cu" "B.Mask" "B.Paste")
			(net "PVNN_MAIN_CPU1")
		)
		(pad "2" smd circle
			(at -0.40005 0)
			(size 0 0)
			(layers "B.Cu" "B.Mask" "B.Paste")
			(net "GND")
		)
	)
	(footprint ""
		(layer "B.Cu")
		(at 245.835424 -101.127052 180)
		(property "Reference" "R2481"
			(at 0 0 0)
			(layer "B.SilkS")
			(hide yes)
			(effects
				(font
					(size 1.27 1.27)
				)
				(justify mirror)
			)
		)
		(property "Value" ""
			(at 0 0 0)
			(layer "B.Fab")
			(effects
				(font
					(size 1.27 1.27)
				)
				(justify mirror)
			)
		)
		(duplicate_pad_numbers_are_jumpers no)
		(fp_line
			(start 0.7874 0.4064)
			(end 0.7874 -0.4064)
			(stroke
				(width 0.1524)
				(type default)
			)
			(layer "B.SilkS")
		)
		(fp_line
			(start 0.7874 -0.4064)
			(end -0.7874 -0.4064)
			(stroke
				(width 0.1524)
				(type default)
			)
			(layer "B.SilkS")
		)
		(fp_line
			(start -0.7874 0.4064)
			(end 0.7874 0.4064)
			(stroke
				(width 0.1524)
				(type default)
			)
			(layer "B.SilkS")
		)
		(fp_line
			(start -0.7874 -0.4064)
			(end -0.7874 0.4064)
			(stroke
				(width 0.1524)
				(type default)
			)
			(layer "B.SilkS")
		)
		(fp_line
			(start 0.67945 0.3048)
			(end 0.67945 -0.305054)
			(stroke
				(width 0.1)
				(type default)
			)
			(layer "B.Fab")
		)
		(fp_line
			(start 0.67945 -0.305054)
			(end 0.12065 -0.305054)
			(stroke
				(width 0.1)
				(type default)
			)
			(layer "B.Fab")
		)
		(fp_line
			(start 0.12065 0.3048)
			(end 0.67945 0.3048)
			(stroke
				(width 0.1)
				(type default)
			)
			(layer "B.Fab")
		)
		(fp_line
			(start 0.12065 0.2794)
			(end 0.12065 0.3048)
			(stroke
				(width 0.1)
				(type default)
			)
			(layer "B.Fab")
		)
		(fp_line
			(start 0.12065 -0.2794)
			(end -0.12065 -0.2794)
			(stroke
				(width 0.1)
				(type default)
			)
			(layer "B.Fab")
		)
		(fp_line
			(start 0.12065 -0.305054)
			(end 0.12065 -0.2794)
			(stroke
				(width 0.1)
				(type default)
			)
			(layer "B.Fab")
		)
		(fp_line
			(start -0.120396 0.3048)
			(end -0.120396 0.2794)
			(stroke
				(width 0.1)
				(type default)
			)
			(layer "B.Fab")
		)
		(fp_line
			(start -0.120396 0.2794)
			(end 0.12065 0.2794)
			(stroke
				(width 0.1)
				(type default)
			)
			(layer "B.Fab")
		)
		(fp_line
			(start -0.12065 -0.2794)
			(end -0.12065 -0.3048)
			(stroke
				(width 0.1)
				(type default)
			)
			(layer "B.Fab")
		)
		(fp_line
			(start -0.12065 -0.3048)
			(end -0.67945 -0.3048)
			(stroke
				(width 0.1)
				(type default)
			)
			(layer "B.Fab")
		)
		(fp_line
			(start -0.67945 0.3048)
			(end -0.120396 0.3048)
			(stroke
				(width 0.1)
				(type default)
			)
			(layer "B.Fab")
		)
		(fp_line
			(start -0.67945 -0.3048)
			(end -0.67945 0.3048)
			(stroke
				(width 0.1)
				(type default)
			)
			(layer "B.Fab")
		)
		(pad "1" smd circle
			(at 0.40005 0)
			(size 0 0)
			(layers "B.Cu" "B.Mask" "B.Paste")
			(net "P3V3_AUX")
		)
		(pad "2" smd circle
			(at -0.40005 0)
			(size 0 0)
			(layers "B.Cu" "B.Mask" "B.Paste")
			(net "CLK_CK440_SMB_ADDR1")
		)
	)
	(footprint ""
		(layer "B.Cu")
		(at 244.944138 -128.343914 90)
		(property "Reference" "R567"
			(at 0 0 90)
			(layer "B.SilkS")
			(hide yes)
			(effects
				(font
					(size 1.27 1.27)
				)
				(justify mirror)
			)
		)
		(property "Value" ""
			(at 0 0 90)
			(layer "B.Fab")
			(effects
				(font
					(size 1.27 1.27)
				)
				(justify mirror)
			)
		)
		(duplicate_pad_numbers_are_jumpers no)
		(fp_line
			(start 0.7874 -0.4064)
			(end -0.7874 -0.4064)
			(stroke
				(width 0.1524)
				(type default)
			)
			(layer "B.SilkS")
		)
		(fp_line
			(start -0.7874 -0.4064)
			(end -0.7874 0.4064)
			(stroke
				(width 0.1524)
				(type default)
			)
			(layer "B.SilkS")
		)
		(fp_line
			(start 0.7874 0.4064)
			(end 0.7874 -0.4064)
			(stroke
				(width 0.1524)
				(type default)
			)
			(layer "B.SilkS")
		)
		(fp_line
			(start -0.7874 0.4064)
			(end 0.7874 0.4064)
			(stroke
				(width 0.1524)
				(type default)
			)
			(layer "B.SilkS")
		)
		(fp_line
			(start 0.67945 -0.305054)
			(end 0.12065 -0.305054)
			(stroke
				(width 0.1)
				(type default)
			)
			(layer "B.Fab")
		)
		(fp_line
			(start 0.12065 -0.305054)
			(end 0.12065 -0.2794)
			(stroke
				(width 0.1)
				(type default)
			)
			(layer "B.Fab")
		)
		(fp_line
			(start -0.12065 -0.3048)
			(end -0.67945 -0.3048)
			(stroke
				(width 0.1)
				(type default)
			)
			(layer "B.Fab")
		)
		(fp_line
			(start -0.67945 -0.3048)
			(end -0.67945 0.3048)
			(stroke
				(width 0.1)
				(type default)
			)
			(layer "B.Fab")
		)
		(fp_line
			(start 0.12065 -0.2794)
			(end -0.12065 -0.2794)
			(stroke
				(width 0.1)
				(type default)
			)
			(layer "B.Fab")
		)
		(fp_line
			(start -0.12065 -0.2794)
			(end -0.12065 -0.3048)
			(stroke
				(width 0.1)
				(type default)
			)
			(layer "B.Fab")
		)
		(fp_line
			(start 0.12065 0.2794)
			(end 0.12065 0.3048)
			(stroke
				(width 0.1)
				(type default)
			)
			(layer "B.Fab")
		)
		(fp_line
			(start -0.120396 0.2794)
			(end 0.12065 0.2794)
			(stroke
				(width 0.1)
				(type default)
			)
			(layer "B.Fab")
		)
		(fp_line
			(start 0.67945 0.3048)
			(end 0.67945 -0.305054)
			(stroke
				(width 0.1)
				(type default)
			)
			(layer "B.Fab")
		)
		(fp_line
			(start 0.12065 0.3048)
			(end 0.67945 0.3048)
			(stroke
				(width 0.1)
				(type default)
			)
			(layer "B.Fab")
		)
		(fp_line
			(start -0.120396 0.3048)
			(end -0.120396 0.2794)
			(stroke
				(width 0.1)
				(type default)
			)
			(layer "B.Fab")
		)
		(fp_line
			(start -0.67945 0.3048)
			(end -0.120396 0.3048)
			(stroke
				(width 0.1)
				(type default)
			)
			(layer "B.Fab")
		)
		(pad "1" smd circle
			(at 0.40005 0 270)
			(size 0 0)
			(layers "B.Cu" "B.Mask" "B.Paste")
			(net "P3V3")
		)
		(pad "2" smd circle
			(at -0.40005 0 270)
			(size 0 0)
			(layers "B.Cu" "B.Mask" "B.Paste")
			(net "PD_DB2000_SMB_SA1")
		)
	)
	(footprint ""
		(layer "B.Cu")
		(at 452.62546 -10.60577 90)
		(property "Reference" "R420"
			(at 0 0 90)
			(layer "B.SilkS")
			(hide yes)
			(effects
				(font
					(size 1.27 1.27)
				)
				(justify mirror)
			)
		)
		(property "Value" ""
			(at 0 0 90)
			(layer "B.Fab")
			(effects
				(font
					(size 1.27 1.27)
				)
				(justify mirror)
			)
		)
		(duplicate_pad_numbers_are_jumpers no)
		(fp_line
			(start 0.7874 -0.4064)
			(end -0.7874 -0.4064)
			(stroke
				(width 0.1524)
				(type default)
			)
			(layer "B.SilkS")
		)
		(fp_line
			(start -0.7874 -0.4064)
			(end -0.7874 0.4064)
			(stroke
				(width 0.1524)
				(type default)
			)
			(layer "B.SilkS")
		)
		(fp_line
			(start 0.7874 0.4064)
			(end 0.7874 -0.4064)
			(stroke
				(width 0.1524)
				(type default)
			)
			(layer "B.SilkS")
		)
		(fp_line
			(start -0.7874 0.4064)
			(end 0.7874 0.4064)
			(stroke
				(width 0.1524)
				(type default)
			)
			(layer "B.SilkS")
		)
		(fp_line
			(start 0.67945 -0.305054)
			(end 0.12065 -0.305054)
			(stroke
				(width 0.1)
				(type default)
			)
			(layer "B.Fab")
		)
		(fp_line
			(start 0.12065 -0.305054)
			(end 0.12065 -0.2794)
			(stroke
				(width 0.1)
				(type default)
			)
			(layer "B.Fab")
		)
		(fp_line
			(start -0.12065 -0.3048)
			(end -0.67945 -0.3048)
			(stroke
				(width 0.1)
				(type default)
			)
			(layer "B.Fab")
		)
		(fp_line
			(start -0.67945 -0.3048)
			(end -0.67945 0.3048)
			(stroke
				(width 0.1)
				(type default)
			)
			(layer "B.Fab")
		)
		(fp_line
			(start 0.12065 -0.2794)
			(end -0.12065 -0.2794)
			(stroke
				(width 0.1)
				(type default)
			)
			(layer "B.Fab")
		)
		(fp_line
			(start -0.12065 -0.2794)
			(end -0.12065 -0.3048)
			(stroke
				(width 0.1)
				(type default)
			)
			(layer "B.Fab")
		)
		(fp_line
			(start 0.12065 0.2794)
			(end 0.12065 0.3048)
			(stroke
				(width 0.1)
				(type default)
			)
			(layer "B.Fab")
		)
		(fp_line
			(start -0.120396 0.2794)
			(end 0.12065 0.2794)
			(stroke
				(width 0.1)
				(type default)
			)
			(layer "B.Fab")
		)
		(fp_line
			(start 0.67945 0.3048)
			(end 0.67945 -0.305054)
			(stroke
				(width 0.1)
				(type default)
			)
			(layer "B.Fab")
		)
		(fp_line
			(start 0.12065 0.3048)
			(end 0.67945 0.3048)
			(stroke
				(width 0.1)
				(type default)
			)
			(layer "B.Fab")
		)
		(fp_line
			(start -0.120396 0.3048)
			(end -0.120396 0.2794)
			(stroke
				(width 0.1)
				(type default)
			)
			(layer "B.Fab")
		)
		(fp_line
			(start -0.67945 0.3048)
			(end -0.120396 0.3048)
			(stroke
				(width 0.1)
				(type default)
			)
			(layer "B.Fab")
		)
		(pad "1" smd circle
			(at 0.40005 0 270)
			(size 0 0)
			(layers "B.Cu" "B.Mask" "B.Paste")
			(net "SGPIO_OCP_SFF_LD_N")
		)
		(pad "2" smd circle
			(at -0.40005 0 270)
			(size 0 0)
			(layers "B.Cu" "B.Mask" "B.Paste")
			(net "P3V3_OCP_SFF")
		)
	)
	(footprint ""
		(layer "B.Cu")
		(at 441.005214 -321.549776 -90)
		(property "Reference" "C43"
			(at 0 0 90)
			(layer "B.SilkS")
			(hide yes)
			(effects
				(font
					(size 1.27 1.27)
				)
				(justify mirror)
			)
		)
		(property "Value" ""
			(at 0 0 90)
			(layer "B.Fab")
			(effects
				(font
					(size 1.27 1.27)
				)
				(justify mirror)
			)
		)
		(duplicate_pad_numbers_are_jumpers no)
		(fp_line
			(start -1.524 0.762)
			(end 1.524 0.762)
			(stroke
				(width 0.1524)
				(type default)
			)
			(layer "B.SilkS")
		)
		(fp_line
			(start 1.524 0.762)
			(end 1.524 -0.762)
			(stroke
				(width 0.1524)
				(type default)
			)
			(layer "B.SilkS")
		)
		(fp_line
			(start -1.524 -0.762)
			(end -1.524 0.762)
			(stroke
				(width 0.1524)
				(type default)
			)
			(layer "B.SilkS")
		)
		(fp_line
			(start 1.524 -0.762)
			(end -1.524 -0.762)
			(stroke
				(width 0.1524)
				(type default)
			)
			(layer "B.SilkS")
		)
		(fp_line
			(start -1.1049 0.724916)
			(end -1.1049 -0.724916)
			(stroke
				(width 0.1)
				(type default)
			)
			(layer "B.Fab")
		)
		(fp_line
			(start 1.1049 0.724916)
			(end -1.1049 0.724916)
			(stroke
				(width 0.1)
				(type default)
			)
			(layer "B.Fab")
		)
		(fp_line
			(start -1.1049 -0.724916)
			(end 1.1049 -0.724916)
			(stroke
				(width 0.1)
				(type default)
			)
			(layer "B.Fab")
		)
		(fp_line
			(start 1.1049 -0.724916)
			(end 1.1049 0.724916)
			(stroke
				(width 0.1)
				(type default)
			)
			(layer "B.Fab")
		)
		(pad "1" smd rect
			(at 0.889 0 270)
			(size 1.016 1.27)
			(layers "B.Cu" "B.Mask" "B.Paste")
			(net "P12V_S3_AUX_CPU0_NVDIMM")
		)
		(pad "2" smd rect
			(at -0.889 0 270)
			(size 1.016 1.27)
			(layers "B.Cu" "B.Mask" "B.Paste")
			(net "GND")
		)
	)
	(footprint ""
		(layer "B.Cu")
		(at 430.600104 -138.558778)
		(property "Reference" "R2397"
			(at 0 0 0)
			(layer "B.SilkS")
			(hide yes)
			(effects
				(font
					(size 1.27 1.27)
				)
				(justify mirror)
			)
		)
		(property "Value" ""
			(at 0 0 0)
			(layer "B.Fab")
			(effects
				(font
					(size 1.27 1.27)
				)
				(justify mirror)
			)
		)
		(duplicate_pad_numbers_are_jumpers no)
		(fp_line
			(start -0.7874 -0.4064)
			(end -0.7874 0.4064)
			(stroke
				(width 0.1524)
				(type default)
			)
			(layer "B.SilkS")
		)
		(fp_line
			(start -0.7874 0.4064)
			(end 0.7874 0.4064)
			(stroke
				(width 0.1524)
				(type default)
			)
			(layer "B.SilkS")
		)
		(fp_line
			(start 0.7874 -0.4064)
			(end -0.7874 -0.4064)
			(stroke
				(width 0.1524)
				(type default)
			)
			(layer "B.SilkS")
		)
		(fp_line
			(start 0.7874 0.4064)
			(end 0.7874 -0.4064)
			(stroke
				(width 0.1524)
				(type default)
			)
			(layer "B.SilkS")
		)
		(fp_line
			(start -0.67945 -0.3048)
			(end -0.67945 0.3048)
			(stroke
				(width 0.1)
				(type default)
			)
			(layer "B.Fab")
		)
		(fp_line
			(start -0.67945 0.3048)
			(end -0.120396 0.3048)
			(stroke
				(width 0.1)
				(type default)
			)
			(layer "B.Fab")
		)
		(fp_line
			(start -0.12065 -0.3048)
			(end -0.67945 -0.3048)
			(stroke
				(width 0.1)
				(type default)
			)
			(layer "B.Fab")
		)
		(fp_line
			(start -0.12065 -0.2794)
			(end -0.12065 -0.3048)
			(stroke
				(width 0.1)
				(type default)
			)
			(layer "B.Fab")
		)
		(fp_line
			(start -0.120396 0.2794)
			(end 0.12065 0.2794)
			(stroke
				(width 0.1)
				(type default)
			)
			(layer "B.Fab")
		)
		(fp_line
			(start -0.120396 0.3048)
			(end -0.120396 0.2794)
			(stroke
				(width 0.1)
				(type default)
			)
			(layer "B.Fab")
		)
		(fp_line
			(start 0.12065 -0.305054)
			(end 0.12065 -0.2794)
			(stroke
				(width 0.1)
				(type default)
			)
			(layer "B.Fab")
		)
		(fp_line
			(start 0.12065 -0.2794)
			(end -0.12065 -0.2794)
			(stroke
				(width 0.1)
				(type default)
			)
			(layer "B.Fab")
		)
		(fp_line
			(start 0.12065 0.2794)
			(end 0.12065 0.3048)
			(stroke
				(width 0.1)
				(type default)
			)
			(layer "B.Fab")
		)
		(fp_line
			(start 0.12065 0.3048)
			(end 0.67945 0.3048)
			(stroke
				(width 0.1)
				(type default)
			)
			(layer "B.Fab")
		)
		(fp_line
			(start 0.67945 -0.305054)
			(end 0.12065 -0.305054)
			(stroke
				(width 0.1)
				(type default)
			)
			(layer "B.Fab")
		)
		(fp_line
			(start 0.67945 0.3048)
			(end 0.67945 -0.305054)
			(stroke
				(width 0.1)
				(type default)
			)
			(layer "B.Fab")
		)
		(pad "1" smd circle
			(at 0.40005 0 180)
			(size 0 0)
			(layers "B.Cu" "B.Mask" "B.Paste")
			(net "PWRGD_PVCCFA_EHV_CPU0")
		)
		(pad "2" smd circle
			(at -0.40005 0 180)
			(size 0 0)
			(layers "B.Cu" "B.Mask" "B.Paste")
			(net "PWRGD_PVCCFA_EHV_CPU0_R")
		)
	)
	(footprint ""
		(layer "B.Cu")
		(at 64.546988 -8.98398 90)
		(property "Reference" "C1835"
			(at 0 0 90)
			(layer "B.SilkS")
			(hide yes)
			(effects
				(font
					(size 1.27 1.27)
				)
				(justify mirror)
			)
		)
		(property "Value" ""
			(at 0 0 90)
			(layer "B.Fab")
			(effects
				(font
					(size 1.27 1.27)
				)
				(justify mirror)
			)
		)
		(duplicate_pad_numbers_are_jumpers no)
		(fp_line
			(start 0.7874 -0.4064)
			(end -0.7874 -0.4064)
			(stroke
				(width 0.1524)
				(type default)
			)
			(layer "B.SilkS")
		)
		(fp_line
			(start -0.7874 -0.4064)
			(end -0.7874 0.4064)
			(stroke
				(width 0.1524)
				(type default)
			)
			(layer "B.SilkS")
		)
		(fp_line
			(start 0.7874 0.4064)
			(end 0.7874 -0.4064)
			(stroke
				(width 0.1524)
				(type default)
			)
			(layer "B.SilkS")
		)
		(fp_line
			(start -0.7874 0.4064)
			(end 0.7874 0.4064)
			(stroke
				(width 0.1524)
				(type default)
			)
			(layer "B.SilkS")
		)
		(fp_line
			(start 0.67945 -0.305054)
			(end 0.12065 -0.305054)
			(stroke
				(width 0.1)
				(type default)
			)
			(layer "B.Fab")
		)
		(fp_line
			(start 0.12065 -0.305054)
			(end 0.12065 -0.2794)
			(stroke
				(width 0.1)
				(type default)
			)
			(layer "B.Fab")
		)
		(fp_line
			(start -0.12065 -0.3048)
			(end -0.67945 -0.3048)
			(stroke
				(width 0.1)
				(type default)
			)
			(layer "B.Fab")
		)
		(fp_line
			(start -0.67945 -0.3048)
			(end -0.67945 0.3048)
			(stroke
				(width 0.1)
				(type default)
			)
			(layer "B.Fab")
		)
		(fp_line
			(start 0.12065 -0.2794)
			(end -0.12065 -0.2794)
			(stroke
				(width 0.1)
				(type default)
			)
			(layer "B.Fab")
		)
		(fp_line
			(start -0.12065 -0.2794)
			(end -0.12065 -0.3048)
			(stroke
				(width 0.1)
				(type default)
			)
			(layer "B.Fab")
		)
		(fp_line
			(start 0.12065 0.2794)
			(end 0.12065 0.3048)
			(stroke
				(width 0.1)
				(type default)
			)
			(layer "B.Fab")
		)
		(fp_line
			(start -0.120396 0.2794)
			(end 0.12065 0.2794)
			(stroke
				(width 0.1)
				(type default)
			)
			(layer "B.Fab")
		)
		(fp_line
			(start 0.67945 0.3048)
			(end 0.67945 -0.305054)
			(stroke
				(width 0.1)
				(type default)
			)
			(layer "B.Fab")
		)
		(fp_line
			(start 0.12065 0.3048)
			(end 0.67945 0.3048)
			(stroke
				(width 0.1)
				(type default)
			)
			(layer "B.Fab")
		)
		(fp_line
			(start -0.120396 0.3048)
			(end -0.120396 0.2794)
			(stroke
				(width 0.1)
				(type default)
			)
			(layer "B.Fab")
		)
		(fp_line
			(start -0.67945 0.3048)
			(end -0.120396 0.3048)
			(stroke
				(width 0.1)
				(type default)
			)
			(layer "B.Fab")
		)
		(pad "1" smd circle
			(at 0.40005 0 270)
			(size 0 0)
			(layers "B.Cu" "B.Mask" "B.Paste")
			(net "P3V3_OCP_V3_2")
		)
		(pad "2" smd circle
			(at -0.40005 0 270)
			(size 0 0)
			(layers "B.Cu" "B.Mask" "B.Paste")
			(net "GND")
		)
	)
	(footprint ""
		(layer "B.Cu")
		(at 8.153146 -321.554856 -90)
		(property "Reference" "C70"
			(at 0 0 90)
			(layer "B.SilkS")
			(hide yes)
			(effects
				(font
					(size 1.27 1.27)
				)
				(justify mirror)
			)
		)
		(property "Value" ""
			(at 0 0 90)
			(layer "B.Fab")
			(effects
				(font
					(size 1.27 1.27)
				)
				(justify mirror)
			)
		)
		(duplicate_pad_numbers_are_jumpers no)
		(fp_line
			(start -1.524 0.762)
			(end 1.524 0.762)
			(stroke
				(width 0.1524)
				(type default)
			)
			(layer "B.SilkS")
		)
		(fp_line
			(start 1.524 0.762)
			(end 1.524 -0.762)
			(stroke
				(width 0.1524)
				(type default)
			)
			(layer "B.SilkS")
		)
		(fp_line
			(start -1.524 -0.762)
			(end -1.524 0.762)
			(stroke
				(width 0.1524)
				(type default)
			)
			(layer "B.SilkS")
		)
		(fp_line
			(start 1.524 -0.762)
			(end -1.524 -0.762)
			(stroke
				(width 0.1524)
				(type default)
			)
			(layer "B.SilkS")
		)
		(fp_line
			(start -1.1049 0.724916)
			(end -1.1049 -0.724916)
			(stroke
				(width 0.1)
				(type default)
			)
			(layer "B.Fab")
		)
		(fp_line
			(start 1.1049 0.724916)
			(end -1.1049 0.724916)
			(stroke
				(width 0.1)
				(type default)
			)
			(layer "B.Fab")
		)
		(fp_line
			(start -1.1049 -0.724916)
			(end 1.1049 -0.724916)
			(stroke
				(width 0.1)
				(type default)
			)
			(layer "B.Fab")
		)
		(fp_line
			(start 1.1049 -0.724916)
			(end 1.1049 0.724916)
			(stroke
				(width 0.1)
				(type default)
			)
			(layer "B.Fab")
		)
		(pad "1" smd rect
			(at 0.889 0 270)
			(size 1.016 1.27)
			(layers "B.Cu" "B.Mask" "B.Paste")
			(net "P12V_S3_AUX_CPU1_NVDIMM")
		)
		(pad "2" smd rect
			(at -0.889 0 270)
			(size 1.016 1.27)
			(layers "B.Cu" "B.Mask" "B.Paste")
			(net "GND")
		)
	)
	(footprint ""
		(layer "B.Cu")
		(at 39.3954 -436.646828 -90)
		(property "Reference" "R4603"
			(at 0 0 90)
			(layer "B.SilkS")
			(hide yes)
			(effects
				(font
					(size 1.27 1.27)
				)
				(justify mirror)
			)
		)
		(property "Value" ""
			(at 0 0 90)
			(layer "B.Fab")
			(effects
				(font
					(size 1.27 1.27)
				)
				(justify mirror)
			)
		)
		(duplicate_pad_numbers_are_jumpers no)
		(fp_line
			(start -0.7874 0.4064)
			(end 0.7874 0.4064)
			(stroke
				(width 0.1524)
				(type default)
			)
			(layer "B.SilkS")
		)
		(fp_line
			(start 0.7874 0.4064)
			(end 0.7874 -0.4064)
			(stroke
				(width 0.1524)
				(type default)
			)
			(layer "B.SilkS")
		)
		(fp_line
			(start -0.7874 -0.4064)
			(end -0.7874 0.4064)
			(stroke
				(width 0.1524)
				(type default)
			)
			(layer "B.SilkS")
		)
		(fp_line
			(start 0.7874 -0.4064)
			(end -0.7874 -0.4064)
			(stroke
				(width 0.1524)
				(type default)
			)
			(layer "B.SilkS")
		)
		(fp_line
			(start -0.67945 0.3048)
			(end -0.120396 0.3048)
			(stroke
				(width 0.1)
				(type default)
			)
			(layer "B.Fab")
		)
		(fp_line
			(start -0.120396 0.3048)
			(end -0.120396 0.2794)
			(stroke
				(width 0.1)
				(type default)
			)
			(layer "B.Fab")
		)
		(fp_line
			(start 0.12065 0.3048)
			(end 0.67945 0.3048)
			(stroke
				(width 0.1)
				(type default)
			)
			(layer "B.Fab")
		)
		(fp_line
			(start 0.67945 0.3048)
			(end 0.67945 -0.305054)
			(stroke
				(width 0.1)
				(type default)
			)
			(layer "B.Fab")
		)
		(fp_line
			(start -0.120396 0.2794)
			(end 0.12065 0.2794)
			(stroke
				(width 0.1)
				(type default)
			)
			(layer "B.Fab")
		)
		(fp_line
			(start 0.12065 0.2794)
			(end 0.12065 0.3048)
			(stroke
				(width 0.1)
				(type default)
			)
			(layer "B.Fab")
		)
		(fp_line
			(start -0.12065 -0.2794)
			(end -0.12065 -0.3048)
			(stroke
				(width 0.1)
				(type default)
			)
			(layer "B.Fab")
		)
		(fp_line
			(start 0.12065 -0.2794)
			(end -0.12065 -0.2794)
			(stroke
				(width 0.1)
				(type default)
			)
			(layer "B.Fab")
		)
		(fp_line
			(start -0.67945 -0.3048)
			(end -0.67945 0.3048)
			(stroke
				(width 0.1)
				(type default)
			)
			(layer "B.Fab")
		)
		(fp_line
			(start -0.12065 -0.3048)
			(end -0.67945 -0.3048)
			(stroke
				(width 0.1)
				(type default)
			)
			(layer "B.Fab")
		)
		(fp_line
			(start 0.12065 -0.305054)
			(end 0.12065 -0.2794)
			(stroke
				(width 0.1)
				(type default)
			)
			(layer "B.Fab")
		)
		(fp_line
			(start 0.67945 -0.305054)
			(end 0.12065 -0.305054)
			(stroke
				(width 0.1)
				(type default)
			)
			(layer "B.Fab")
		)
		(pad "1" smd circle
			(at 0.40005 0 90)
			(size 0 0)
			(layers "B.Cu" "B.Mask" "B.Paste")
			(net "SMB_BMC_GPU_EN")
		)
		(pad "2" smd circle
			(at -0.40005 0 90)
			(size 0 0)
			(layers "B.Cu" "B.Mask" "B.Paste")
			(net "GND")
		)
	)
	(footprint ""
		(layer "B.Cu")
		(at 42.814748 -100.584762 -90)
		(property "Reference" "C2195"
			(at 0 0 90)
			(layer "B.SilkS")
			(hide yes)
			(effects
				(font
					(size 1.27 1.27)
				)
				(justify mirror)
			)
		)
		(property "Value" ""
			(at 0 0 90)
			(layer "B.Fab")
			(effects
				(font
					(size 1.27 1.27)
				)
				(justify mirror)
			)
		)
		(duplicate_pad_numbers_are_jumpers no)
		(fp_line
			(start -0.7874 0.4064)
			(end 0.7874 0.4064)
			(stroke
				(width 0.1524)
				(type default)
			)
			(layer "B.SilkS")
		)
		(fp_line
			(start 0.7874 0.4064)
			(end 0.7874 -0.4064)
			(stroke
				(width 0.1524)
				(type default)
			)
			(layer "B.SilkS")
		)
		(fp_line
			(start -0.7874 -0.4064)
			(end -0.7874 0.4064)
			(stroke
				(width 0.1524)
				(type default)
			)
			(layer "B.SilkS")
		)
		(fp_line
			(start 0.7874 -0.4064)
			(end -0.7874 -0.4064)
			(stroke
				(width 0.1524)
				(type default)
			)
			(layer "B.SilkS")
		)
		(fp_line
			(start -0.67945 0.3048)
			(end -0.120396 0.3048)
			(stroke
				(width 0.1)
				(type default)
			)
			(layer "B.Fab")
		)
		(fp_line
			(start -0.120396 0.3048)
			(end -0.120396 0.2794)
			(stroke
				(width 0.1)
				(type default)
			)
			(layer "B.Fab")
		)
		(fp_line
			(start 0.12065 0.3048)
			(end 0.67945 0.3048)
			(stroke
				(width 0.1)
				(type default)
			)
			(layer "B.Fab")
		)
		(fp_line
			(start 0.67945 0.3048)
			(end 0.67945 -0.305054)
			(stroke
				(width 0.1)
				(type default)
			)
			(layer "B.Fab")
		)
		(fp_line
			(start -0.120396 0.2794)
			(end 0.12065 0.2794)
			(stroke
				(width 0.1)
				(type default)
			)
			(layer "B.Fab")
		)
		(fp_line
			(start 0.12065 0.2794)
			(end 0.12065 0.3048)
			(stroke
				(width 0.1)
				(type default)
			)
			(layer "B.Fab")
		)
		(fp_line
			(start -0.12065 -0.2794)
			(end -0.12065 -0.3048)
			(stroke
				(width 0.1)
				(type default)
			)
			(layer "B.Fab")
		)
		(fp_line
			(start 0.12065 -0.2794)
			(end -0.12065 -0.2794)
			(stroke
				(width 0.1)
				(type default)
			)
			(layer "B.Fab")
		)
		(fp_line
			(start -0.67945 -0.3048)
			(end -0.67945 0.3048)
			(stroke
				(width 0.1)
				(type default)
			)
			(layer "B.Fab")
		)
		(fp_line
			(start -0.12065 -0.3048)
			(end -0.67945 -0.3048)
			(stroke
				(width 0.1)
				(type default)
			)
			(layer "B.Fab")
		)
		(fp_line
			(start 0.12065 -0.305054)
			(end 0.12065 -0.2794)
			(stroke
				(width 0.1)
				(type default)
			)
			(layer "B.Fab")
		)
		(fp_line
			(start 0.67945 -0.305054)
			(end 0.12065 -0.305054)
			(stroke
				(width 0.1)
				(type default)
			)
			(layer "B.Fab")
		)
		(pad "1" smd circle
			(at 0.40005 0 90)
			(size 0 0)
			(layers "B.Cu" "B.Mask" "B.Paste")
			(net "P12V_E1S_0_ISENSE_MAM")
		)
		(pad "2" smd circle
			(at -0.40005 0 90)
			(size 0 0)
			(layers "B.Cu" "B.Mask" "B.Paste")
			(net "GND")
		)
	)
	(footprint ""
		(layer "B.Cu")
		(at 238.064294 -247.691148 180)
		(property "Reference" "C1883"
			(at 0 0 0)
			(layer "B.SilkS")
			(hide yes)
			(effects
				(font
					(size 1.27 1.27)
				)
				(justify mirror)
			)
		)
		(property "Value" ""
			(at 0 0 0)
			(layer "B.Fab")
			(effects
				(font
					(size 1.27 1.27)
				)
				(justify mirror)
			)
		)
		(duplicate_pad_numbers_are_jumpers no)
		(fp_line
			(start 1.524 0.762)
			(end 1.524 -0.762)
			(stroke
				(width 0.1524)
				(type default)
			)
			(layer "B.SilkS")
		)
		(fp_line
			(start 1.524 -0.762)
			(end -1.524 -0.762)
			(stroke
				(width 0.1524)
				(type default)
			)
			(layer "B.SilkS")
		)
		(fp_line
			(start -1.524 0.762)
			(end 1.524 0.762)
			(stroke
				(width 0.1524)
				(type default)
			)
			(layer "B.SilkS")
		)
		(fp_line
			(start -1.524 -0.762)
			(end -1.524 0.762)
			(stroke
				(width 0.1524)
				(type default)
			)
			(layer "B.SilkS")
		)
		(fp_line
			(start 1.1049 0.724916)
			(end -1.1049 0.724916)
			(stroke
				(width 0.1)
				(type default)
			)
			(layer "B.Fab")
		)
		(fp_line
			(start 1.1049 -0.724916)
			(end 1.1049 0.724916)
			(stroke
				(width 0.1)
				(type default)
			)
			(layer "B.Fab")
		)
		(fp_line
			(start -1.1049 0.724916)
			(end -1.1049 -0.724916)
			(stroke
				(width 0.1)
				(type default)
			)
			(layer "B.Fab")
		)
		(fp_line
			(start -1.1049 -0.724916)
			(end 1.1049 -0.724916)
			(stroke
				(width 0.1)
				(type default)
			)
			(layer "B.Fab")
		)
		(pad "1" smd rect
			(at 0.889 0 180)
			(size 1.016 1.27)
			(layers "B.Cu" "B.Mask" "B.Paste")
			(net "VFG3P3_CLK_GEN")
		)
		(pad "2" smd rect
			(at -0.889 0 180)
			(size 1.016 1.27)
			(layers "B.Cu" "B.Mask" "B.Paste")
			(net "GND")
		)
	)
	(footprint ""
		(layer "B.Cu")
		(at 435.549802 -10.072116 180)
		(property "Reference" "C1240"
			(at 0 0 0)
			(layer "B.SilkS")
			(hide yes)
			(effects
				(font
					(size 1.27 1.27)
				)
				(justify mirror)
			)
		)
		(property "Value" ""
			(at 0 0 0)
			(layer "B.Fab")
			(effects
				(font
					(size 1.27 1.27)
				)
				(justify mirror)
			)
		)
		(duplicate_pad_numbers_are_jumpers no)
		(fp_line
			(start 0.7874 0.4064)
			(end 0.7874 -0.4064)
			(stroke
				(width 0.1524)
				(type default)
			)
			(layer "B.SilkS")
		)
		(fp_line
			(start 0.7874 -0.4064)
			(end -0.7874 -0.4064)
			(stroke
				(width 0.1524)
				(type default)
			)
			(layer "B.SilkS")
		)
		(fp_line
			(start -0.7874 0.4064)
			(end 0.7874 0.4064)
			(stroke
				(width 0.1524)
				(type default)
			)
			(layer "B.SilkS")
		)
		(fp_line
			(start -0.7874 -0.4064)
			(end -0.7874 0.4064)
			(stroke
				(width 0.1524)
				(type default)
			)
			(layer "B.SilkS")
		)
		(fp_line
			(start 0.67945 0.3048)
			(end 0.67945 -0.305054)
			(stroke
				(width 0.1)
				(type default)
			)
			(layer "B.Fab")
		)
		(fp_line
			(start 0.67945 -0.305054)
			(end 0.12065 -0.305054)
			(stroke
				(width 0.1)
				(type default)
			)
			(layer "B.Fab")
		)
		(fp_line
			(start 0.12065 0.3048)
			(end 0.67945 0.3048)
			(stroke
				(width 0.1)
				(type default)
			)
			(layer "B.Fab")
		)
		(fp_line
			(start 0.12065 0.2794)
			(end 0.12065 0.3048)
			(stroke
				(width 0.1)
				(type default)
			)
			(layer "B.Fab")
		)
		(fp_line
			(start 0.12065 -0.2794)
			(end -0.12065 -0.2794)
			(stroke
				(width 0.1)
				(type default)
			)
			(layer "B.Fab")
		)
		(fp_line
			(start 0.12065 -0.305054)
			(end 0.12065 -0.2794)
			(stroke
				(width 0.1)
				(type default)
			)
			(layer "B.Fab")
		)
		(fp_line
			(start -0.120396 0.3048)
			(end -0.120396 0.2794)
			(stroke
				(width 0.1)
				(type default)
			)
			(layer "B.Fab")
		)
		(fp_line
			(start -0.120396 0.2794)
			(end 0.12065 0.2794)
			(stroke
				(width 0.1)
				(type default)
			)
			(layer "B.Fab")
		)
		(fp_line
			(start -0.12065 -0.2794)
			(end -0.12065 -0.3048)
			(stroke
				(width 0.1)
				(type default)
			)
			(layer "B.Fab")
		)
		(fp_line
			(start -0.12065 -0.3048)
			(end -0.67945 -0.3048)
			(stroke
				(width 0.1)
				(type default)
			)
			(layer "B.Fab")
		)
		(fp_line
			(start -0.67945 0.3048)
			(end -0.120396 0.3048)
			(stroke
				(width 0.1)
				(type default)
			)
			(layer "B.Fab")
		)
		(fp_line
			(start -0.67945 -0.3048)
			(end -0.67945 0.3048)
			(stroke
				(width 0.1)
				(type default)
			)
			(layer "B.Fab")
		)
		(pad "1" smd circle
			(at 0.40005 0)
			(size 0 0)
			(layers "B.Cu" "B.Mask" "B.Paste")
			(net "P3V3_OCP_SFF")
		)
		(pad "2" smd circle
			(at -0.40005 0)
			(size 0 0)
			(layers "B.Cu" "B.Mask" "B.Paste")
			(net "GND")
		)
	)
	(footprint ""
		(layer "B.Cu")
		(at 317.276988 -191.619378 -90)
		(property "Reference" "R4389"
			(at 0 0 90)
			(layer "B.SilkS")
			(hide yes)
			(effects
				(font
					(size 1.27 1.27)
				)
				(justify mirror)
			)
		)
		(property "Value" ""
			(at 0 0 90)
			(layer "B.Fab")
			(effects
				(font
					(size 1.27 1.27)
				)
				(justify mirror)
			)
		)
		(duplicate_pad_numbers_are_jumpers no)
		(fp_line
			(start -0.7874 0.4064)
			(end 0.7874 0.4064)
			(stroke
				(width 0.1524)
				(type default)
			)
			(layer "B.SilkS")
		)
		(fp_line
			(start 0.7874 0.4064)
			(end 0.7874 -0.4064)
			(stroke
				(width 0.1524)
				(type default)
			)
			(layer "B.SilkS")
		)
		(fp_line
			(start -0.7874 -0.4064)
			(end -0.7874 0.4064)
			(stroke
				(width 0.1524)
				(type default)
			)
			(layer "B.SilkS")
		)
		(fp_line
			(start 0.7874 -0.4064)
			(end -0.7874 -0.4064)
			(stroke
				(width 0.1524)
				(type default)
			)
			(layer "B.SilkS")
		)
		(fp_line
			(start -0.67945 0.3048)
			(end -0.120396 0.3048)
			(stroke
				(width 0.1)
				(type default)
			)
			(layer "B.Fab")
		)
		(fp_line
			(start -0.120396 0.3048)
			(end -0.120396 0.2794)
			(stroke
				(width 0.1)
				(type default)
			)
			(layer "B.Fab")
		)
		(fp_line
			(start 0.12065 0.3048)
			(end 0.67945 0.3048)
			(stroke
				(width 0.1)
				(type default)
			)
			(layer "B.Fab")
		)
		(fp_line
			(start 0.67945 0.3048)
			(end 0.67945 -0.305054)
			(stroke
				(width 0.1)
				(type default)
			)
			(layer "B.Fab")
		)
		(fp_line
			(start -0.120396 0.2794)
			(end 0.12065 0.2794)
			(stroke
				(width 0.1)
				(type default)
			)
			(layer "B.Fab")
		)
		(fp_line
			(start 0.12065 0.2794)
			(end 0.12065 0.3048)
			(stroke
				(width 0.1)
				(type default)
			)
			(layer "B.Fab")
		)
		(fp_line
			(start -0.12065 -0.2794)
			(end -0.12065 -0.3048)
			(stroke
				(width 0.1)
				(type default)
			)
			(layer "B.Fab")
		)
		(fp_line
			(start 0.12065 -0.2794)
			(end -0.12065 -0.2794)
			(stroke
				(width 0.1)
				(type default)
			)
			(layer "B.Fab")
		)
		(fp_line
			(start -0.67945 -0.3048)
			(end -0.67945 0.3048)
			(stroke
				(width 0.1)
				(type default)
			)
			(layer "B.Fab")
		)
		(fp_line
			(start -0.12065 -0.3048)
			(end -0.67945 -0.3048)
			(stroke
				(width 0.1)
				(type default)
			)
			(layer "B.Fab")
		)
		(fp_line
			(start 0.12065 -0.305054)
			(end 0.12065 -0.2794)
			(stroke
				(width 0.1)
				(type default)
			)
			(layer "B.Fab")
		)
		(fp_line
			(start 0.67945 -0.305054)
			(end 0.12065 -0.305054)
			(stroke
				(width 0.1)
				(type default)
			)
			(layer "B.Fab")
		)
		(pad "1" smd circle
			(at 0.40005 0 90)
			(size 0 0)
			(layers "B.Cu" "B.Mask" "B.Paste")
			(net "PVNN_TERM_CPU0")
		)
		(pad "2" smd circle
			(at -0.40005 0 90)
			(size 0 0)
			(layers "B.Cu" "B.Mask" "B.Paste")
			(net "H_CPU_ERR2_LVC1_R_N")
		)
	)
	(footprint ""
		(layer "B.Cu")
		(at 229.89032 -127.029718 180)
		(property "Reference" "R2562"
			(at 0 0 0)
			(layer "B.SilkS")
			(hide yes)
			(effects
				(font
					(size 1.27 1.27)
				)
				(justify mirror)
			)
		)
		(property "Value" ""
			(at 0 0 0)
			(layer "B.Fab")
			(effects
				(font
					(size 1.27 1.27)
				)
				(justify mirror)
			)
		)
		(duplicate_pad_numbers_are_jumpers no)
		(fp_line
			(start 0.7874 0.4064)
			(end 0.7874 -0.4064)
			(stroke
				(width 0.1524)
				(type default)
			)
			(layer "B.SilkS")
		)
		(fp_line
			(start 0.7874 -0.4064)
			(end -0.7874 -0.4064)
			(stroke
				(width 0.1524)
				(type default)
			)
			(layer "B.SilkS")
		)
		(fp_line
			(start -0.7874 0.4064)
			(end 0.7874 0.4064)
			(stroke
				(width 0.1524)
				(type default)
			)
			(layer "B.SilkS")
		)
		(fp_line
			(start -0.7874 -0.4064)
			(end -0.7874 0.4064)
			(stroke
				(width 0.1524)
				(type default)
			)
			(layer "B.SilkS")
		)
		(fp_line
			(start 0.67945 0.3048)
			(end 0.67945 -0.305054)
			(stroke
				(width 0.1)
				(type default)
			)
			(layer "B.Fab")
		)
		(fp_line
			(start 0.67945 -0.305054)
			(end 0.12065 -0.305054)
			(stroke
				(width 0.1)
				(type default)
			)
			(layer "B.Fab")
		)
		(fp_line
			(start 0.12065 0.3048)
			(end 0.67945 0.3048)
			(stroke
				(width 0.1)
				(type default)
			)
			(layer "B.Fab")
		)
		(fp_line
			(start 0.12065 0.2794)
			(end 0.12065 0.3048)
			(stroke
				(width 0.1)
				(type default)
			)
			(layer "B.Fab")
		)
		(fp_line
			(start 0.12065 -0.2794)
			(end -0.12065 -0.2794)
			(stroke
				(width 0.1)
				(type default)
			)
			(layer "B.Fab")
		)
		(fp_line
			(start 0.12065 -0.305054)
			(end 0.12065 -0.2794)
			(stroke
				(width 0.1)
				(type default)
			)
			(layer "B.Fab")
		)
		(fp_line
			(start -0.120396 0.3048)
			(end -0.120396 0.2794)
			(stroke
				(width 0.1)
				(type default)
			)
			(layer "B.Fab")
		)
		(fp_line
			(start -0.120396 0.2794)
			(end 0.12065 0.2794)
			(stroke
				(width 0.1)
				(type default)
			)
			(layer "B.Fab")
		)
		(fp_line
			(start -0.12065 -0.2794)
			(end -0.12065 -0.3048)
			(stroke
				(width 0.1)
				(type default)
			)
			(layer "B.Fab")
		)
		(fp_line
			(start -0.12065 -0.3048)
			(end -0.67945 -0.3048)
			(stroke
				(width 0.1)
				(type default)
			)
			(layer "B.Fab")
		)
		(fp_line
			(start -0.67945 0.3048)
			(end -0.120396 0.3048)
			(stroke
				(width 0.1)
				(type default)
			)
			(layer "B.Fab")
		)
		(fp_line
			(start -0.67945 -0.3048)
			(end -0.67945 0.3048)
			(stroke
				(width 0.1)
				(type default)
			)
			(layer "B.Fab")
		)
		(pad "1" smd circle
			(at 0.40005 0)
			(size 0 0)
			(layers "B.Cu" "B.Mask" "B.Paste")
			(net "OCP_SFF_CLK_OE_N")
		)
		(pad "2" smd circle
			(at -0.40005 0)
			(size 0 0)
			(layers "B.Cu" "B.Mask" "B.Paste")
			(net "FM_DB2000_10_OE_N")
		)
	)
	(footprint ""
		(layer "B.Cu")
		(at 193.60388 -104.955848 180)
		(property "Reference" "R1474"
			(at 0 0 0)
			(layer "B.SilkS")
			(hide yes)
			(effects
				(font
					(size 1.27 1.27)
				)
				(justify mirror)
			)
		)
		(property "Value" ""
			(at 0 0 0)
			(layer "B.Fab")
			(effects
				(font
					(size 1.27 1.27)
				)
				(justify mirror)
			)
		)
		(duplicate_pad_numbers_are_jumpers no)
		(fp_line
			(start 0.7874 0.4064)
			(end 0.7874 -0.4064)
			(stroke
				(width 0.1524)
				(type default)
			)
			(layer "B.SilkS")
		)
		(fp_line
			(start 0.7874 -0.4064)
			(end -0.7874 -0.4064)
			(stroke
				(width 0.1524)
				(type default)
			)
			(layer "B.SilkS")
		)
		(fp_line
			(start -0.7874 0.4064)
			(end 0.7874 0.4064)
			(stroke
				(width 0.1524)
				(type default)
			)
			(layer "B.SilkS")
		)
		(fp_line
			(start -0.7874 -0.4064)
			(end -0.7874 0.4064)
			(stroke
				(width 0.1524)
				(type default)
			)
			(layer "B.SilkS")
		)
		(fp_line
			(start 0.67945 0.3048)
			(end 0.67945 -0.305054)
			(stroke
				(width 0.1)
				(type default)
			)
			(layer "B.Fab")
		)
		(fp_line
			(start 0.67945 -0.305054)
			(end 0.12065 -0.305054)
			(stroke
				(width 0.1)
				(type default)
			)
			(layer "B.Fab")
		)
		(fp_line
			(start 0.12065 0.3048)
			(end 0.67945 0.3048)
			(stroke
				(width 0.1)
				(type default)
			)
			(layer "B.Fab")
		)
		(fp_line
			(start 0.12065 0.2794)
			(end 0.12065 0.3048)
			(stroke
				(width 0.1)
				(type default)
			)
			(layer "B.Fab")
		)
		(fp_line
			(start 0.12065 -0.2794)
			(end -0.12065 -0.2794)
			(stroke
				(width 0.1)
				(type default)
			)
			(layer "B.Fab")
		)
		(fp_line
			(start 0.12065 -0.305054)
			(end 0.12065 -0.2794)
			(stroke
				(width 0.1)
				(type default)
			)
			(layer "B.Fab")
		)
		(fp_line
			(start -0.120396 0.3048)
			(end -0.120396 0.2794)
			(stroke
				(width 0.1)
				(type default)
			)
			(layer "B.Fab")
		)
		(fp_line
			(start -0.120396 0.2794)
			(end 0.12065 0.2794)
			(stroke
				(width 0.1)
				(type default)
			)
			(layer "B.Fab")
		)
		(fp_line
			(start -0.12065 -0.2794)
			(end -0.12065 -0.3048)
			(stroke
				(width 0.1)
				(type default)
			)
			(layer "B.Fab")
		)
		(fp_line
			(start -0.12065 -0.3048)
			(end -0.67945 -0.3048)
			(stroke
				(width 0.1)
				(type default)
			)
			(layer "B.Fab")
		)
		(fp_line
			(start -0.67945 0.3048)
			(end -0.120396 0.3048)
			(stroke
				(width 0.1)
				(type default)
			)
			(layer "B.Fab")
		)
		(fp_line
			(start -0.67945 -0.3048)
			(end -0.67945 0.3048)
			(stroke
				(width 0.1)
				(type default)
			)
			(layer "B.Fab")
		)
		(pad "1" smd circle
			(at 0.40005 0)
			(size 0 0)
			(layers "B.Cu" "B.Mask" "B.Paste")
			(net "FM_RST_PERST_BIT2")
		)
		(pad "2" smd circle
			(at -0.40005 0)
			(size 0 0)
			(layers "B.Cu" "B.Mask" "B.Paste")
			(net "P3V3_AUX")
		)
	)
	(footprint ""
		(layer "B.Cu")
		(at 367.898934 -244.820186 -90)
		(property "Reference" "C385"
			(at 0 0 90)
			(layer "B.SilkS")
			(hide yes)
			(effects
				(font
					(size 1.27 1.27)
				)
				(justify mirror)
			)
		)
		(property "Value" ""
			(at 0 0 90)
			(layer "B.Fab")
			(effects
				(font
					(size 1.27 1.27)
				)
				(justify mirror)
			)
		)
		(duplicate_pad_numbers_are_jumpers no)
		(fp_line
			(start -1.524 0.762)
			(end 1.524 0.762)
			(stroke
				(width 0.1524)
				(type default)
			)
			(layer "B.SilkS")
		)
		(fp_line
			(start 1.524 0.762)
			(end 1.524 -0.762)
			(stroke
				(width 0.1524)
				(type default)
			)
			(layer "B.SilkS")
		)
		(fp_line
			(start -1.524 -0.762)
			(end -1.524 0.762)
			(stroke
				(width 0.1524)
				(type default)
			)
			(layer "B.SilkS")
		)
		(fp_line
			(start 1.524 -0.762)
			(end -1.524 -0.762)
			(stroke
				(width 0.1524)
				(type default)
			)
			(layer "B.SilkS")
		)
		(fp_line
			(start -1.1049 0.724916)
			(end -1.1049 -0.724916)
			(stroke
				(width 0.1)
				(type default)
			)
			(layer "B.Fab")
		)
		(fp_line
			(start 1.1049 0.724916)
			(end -1.1049 0.724916)
			(stroke
				(width 0.1)
				(type default)
			)
			(layer "B.Fab")
		)
		(fp_line
			(start -1.1049 -0.724916)
			(end 1.1049 -0.724916)
			(stroke
				(width 0.1)
				(type default)
			)
			(layer "B.Fab")
		)
		(fp_line
			(start 1.1049 -0.724916)
			(end 1.1049 0.724916)
			(stroke
				(width 0.1)
				(type default)
			)
			(layer "B.Fab")
		)
		(pad "1" smd rect
			(at 0.889 0 270)
			(size 1.016 1.27)
			(layers "B.Cu" "B.Mask" "B.Paste")
			(net "PVCCIN_CPU0")
		)
		(pad "2" smd rect
			(at -0.889 0 270)
			(size 1.016 1.27)
			(layers "B.Cu" "B.Mask" "B.Paste")
			(net "GND")
		)
	)
	(footprint ""
		(layer "B.Cu")
		(at 293.053516 -367.168176 180)
		(property "Reference" "PC1671"
			(at 0 0 0)
			(layer "B.SilkS")
			(hide yes)
			(effects
				(font
					(size 1.27 1.27)
				)
				(justify mirror)
			)
		)
		(property "Value" ""
			(at 0 0 0)
			(layer "B.Fab")
			(effects
				(font
					(size 1.27 1.27)
				)
				(justify mirror)
			)
		)
		(duplicate_pad_numbers_are_jumpers no)
		(fp_line
			(start 1.524 0.762)
			(end 1.524 -0.762)
			(stroke
				(width 0.1524)
				(type default)
			)
			(layer "B.SilkS")
		)
		(fp_line
			(start 1.524 -0.762)
			(end -1.524 -0.762)
			(stroke
				(width 0.1524)
				(type default)
			)
			(layer "B.SilkS")
		)
		(fp_line
			(start -1.524 0.762)
			(end 1.524 0.762)
			(stroke
				(width 0.1524)
				(type default)
			)
			(layer "B.SilkS")
		)
		(fp_line
			(start -1.524 -0.762)
			(end -1.524 0.762)
			(stroke
				(width 0.1524)
				(type default)
			)
			(layer "B.SilkS")
		)
		(fp_line
			(start 1.1049 0.724916)
			(end -1.1049 0.724916)
			(stroke
				(width 0.1)
				(type default)
			)
			(layer "B.Fab")
		)
		(fp_line
			(start 1.1049 -0.724916)
			(end 1.1049 0.724916)
			(stroke
				(width 0.1)
				(type default)
			)
			(layer "B.Fab")
		)
		(fp_line
			(start -1.1049 0.724916)
			(end -1.1049 -0.724916)
			(stroke
				(width 0.1)
				(type default)
			)
			(layer "B.Fab")
		)
		(fp_line
			(start -1.1049 -0.724916)
			(end 1.1049 -0.724916)
			(stroke
				(width 0.1)
				(type default)
			)
			(layer "B.Fab")
		)
		(pad "1" smd rect
			(at 0.889 0 180)
			(size 1.016 1.27)
			(layers "B.Cu" "B.Mask" "B.Paste")
			(net "SW_P12V_PVCCFA_EHV_FIVRA_CPU0_L")
		)
		(pad "2" smd rect
			(at -0.889 0 180)
			(size 1.016 1.27)
			(layers "B.Cu" "B.Mask" "B.Paste")
			(net "GND")
		)
	)
	(footprint ""
		(layer "B.Cu")
		(at 172.346112 -8.907018)
		(property "Reference" "R3111"
			(at 0 0 0)
			(layer "B.SilkS")
			(hide yes)
			(effects
				(font
					(size 1.27 1.27)
				)
				(justify mirror)
			)
		)
		(property "Value" ""
			(at 0 0 0)
			(layer "B.Fab")
			(effects
				(font
					(size 1.27 1.27)
				)
				(justify mirror)
			)
		)
		(duplicate_pad_numbers_are_jumpers no)
		(fp_line
			(start -0.7874 -0.4064)
			(end -0.7874 0.4064)
			(stroke
				(width 0.1524)
				(type default)
			)
			(layer "B.SilkS")
		)
		(fp_line
			(start -0.7874 0.4064)
			(end 0.7874 0.4064)
			(stroke
				(width 0.1524)
				(type default)
			)
			(layer "B.SilkS")
		)
		(fp_line
			(start 0.7874 -0.4064)
			(end -0.7874 -0.4064)
			(stroke
				(width 0.1524)
				(type default)
			)
			(layer "B.SilkS")
		)
		(fp_line
			(start 0.7874 0.4064)
			(end 0.7874 -0.4064)
			(stroke
				(width 0.1524)
				(type default)
			)
			(layer "B.SilkS")
		)
		(fp_line
			(start -0.67945 -0.3048)
			(end -0.67945 0.3048)
			(stroke
				(width 0.1)
				(type default)
			)
			(layer "B.Fab")
		)
		(fp_line
			(start -0.67945 0.3048)
			(end -0.120396 0.3048)
			(stroke
				(width 0.1)
				(type default)
			)
			(layer "B.Fab")
		)
		(fp_line
			(start -0.12065 -0.3048)
			(end -0.67945 -0.3048)
			(stroke
				(width 0.1)
				(type default)
			)
			(layer "B.Fab")
		)
		(fp_line
			(start -0.12065 -0.2794)
			(end -0.12065 -0.3048)
			(stroke
				(width 0.1)
				(type default)
			)
			(layer "B.Fab")
		)
		(fp_line
			(start -0.120396 0.2794)
			(end 0.12065 0.2794)
			(stroke
				(width 0.1)
				(type default)
			)
			(layer "B.Fab")
		)
		(fp_line
			(start -0.120396 0.3048)
			(end -0.120396 0.2794)
			(stroke
				(width 0.1)
				(type default)
			)
			(layer "B.Fab")
		)
		(fp_line
			(start 0.12065 -0.305054)
			(end 0.12065 -0.2794)
			(stroke
				(width 0.1)
				(type default)
			)
			(layer "B.Fab")
		)
		(fp_line
			(start 0.12065 -0.2794)
			(end -0.12065 -0.2794)
			(stroke
				(width 0.1)
				(type default)
			)
			(layer "B.Fab")
		)
		(fp_line
			(start 0.12065 0.2794)
			(end 0.12065 0.3048)
			(stroke
				(width 0.1)
				(type default)
			)
			(layer "B.Fab")
		)
		(fp_line
			(start 0.12065 0.3048)
			(end 0.67945 0.3048)
			(stroke
				(width 0.1)
				(type default)
			)
			(layer "B.Fab")
		)
		(fp_line
			(start 0.67945 -0.305054)
			(end 0.12065 -0.305054)
			(stroke
				(width 0.1)
				(type default)
			)
			(layer "B.Fab")
		)
		(fp_line
			(start 0.67945 0.3048)
			(end 0.67945 -0.305054)
			(stroke
				(width 0.1)
				(type default)
			)
			(layer "B.Fab")
		)
		(pad "1" smd circle
			(at 0.40005 0 180)
			(size 0 0)
			(layers "B.Cu" "B.Mask" "B.Paste")
			(net "I3C_BMC_SWB_SDA")
		)
		(pad "2" smd circle
			(at -0.40005 0 180)
			(size 0 0)
			(layers "B.Cu" "B.Mask" "B.Paste")
			(net "I3C_BMC_SWB_R_SDA")
		)
	)
	(footprint ""
		(layer "B.Cu")
		(at 38.09746 -357.575612)
		(property "Reference" "PR1334"
			(at 0 0 0)
			(layer "B.SilkS")
			(hide yes)
			(effects
				(font
					(size 1.27 1.27)
				)
				(justify mirror)
			)
		)
		(property "Value" ""
			(at 0 0 0)
			(layer "B.Fab")
			(effects
				(font
					(size 1.27 1.27)
				)
				(justify mirror)
			)
		)
		(duplicate_pad_numbers_are_jumpers no)
		(fp_line
			(start -0.7874 -0.4064)
			(end -0.7874 0.4064)
			(stroke
				(width 0.1524)
				(type default)
			)
			(layer "B.SilkS")
		)
		(fp_line
			(start -0.7874 0.4064)
			(end 0.7874 0.4064)
			(stroke
				(width 0.1524)
				(type default)
			)
			(layer "B.SilkS")
		)
		(fp_line
			(start 0.7874 -0.4064)
			(end -0.7874 -0.4064)
			(stroke
				(width 0.1524)
				(type default)
			)
			(layer "B.SilkS")
		)
		(fp_line
			(start 0.7874 0.4064)
			(end 0.7874 -0.4064)
			(stroke
				(width 0.1524)
				(type default)
			)
			(layer "B.SilkS")
		)
		(fp_line
			(start -0.67945 -0.3048)
			(end -0.67945 0.3048)
			(stroke
				(width 0.1)
				(type default)
			)
			(layer "B.Fab")
		)
		(fp_line
			(start -0.67945 0.3048)
			(end -0.120396 0.3048)
			(stroke
				(width 0.1)
				(type default)
			)
			(layer "B.Fab")
		)
		(fp_line
			(start -0.12065 -0.3048)
			(end -0.67945 -0.3048)
			(stroke
				(width 0.1)
				(type default)
			)
			(layer "B.Fab")
		)
		(fp_line
			(start -0.12065 -0.2794)
			(end -0.12065 -0.3048)
			(stroke
				(width 0.1)
				(type default)
			)
			(layer "B.Fab")
		)
		(fp_line
			(start -0.120396 0.2794)
			(end 0.12065 0.2794)
			(stroke
				(width 0.1)
				(type default)
			)
			(layer "B.Fab")
		)
		(fp_line
			(start -0.120396 0.3048)
			(end -0.120396 0.2794)
			(stroke
				(width 0.1)
				(type default)
			)
			(layer "B.Fab")
		)
		(fp_line
			(start 0.12065 -0.305054)
			(end 0.12065 -0.2794)
			(stroke
				(width 0.1)
				(type default)
			)
			(layer "B.Fab")
		)
		(fp_line
			(start 0.12065 -0.2794)
			(end -0.12065 -0.2794)
			(stroke
				(width 0.1)
				(type default)
			)
			(layer "B.Fab")
		)
		(fp_line
			(start 0.12065 0.2794)
			(end 0.12065 0.3048)
			(stroke
				(width 0.1)
				(type default)
			)
			(layer "B.Fab")
		)
		(fp_line
			(start 0.12065 0.3048)
			(end 0.67945 0.3048)
			(stroke
				(width 0.1)
				(type default)
			)
			(layer "B.Fab")
		)
		(fp_line
			(start 0.67945 -0.305054)
			(end 0.12065 -0.305054)
			(stroke
				(width 0.1)
				(type default)
			)
			(layer "B.Fab")
		)
		(fp_line
			(start 0.67945 0.3048)
			(end 0.67945 -0.305054)
			(stroke
				(width 0.1)
				(type default)
			)
			(layer "B.Fab")
		)
		(pad "1" smd circle
			(at 0.40005 0 180)
			(size 0 0)
			(layers "B.Cu" "B.Mask" "B.Paste")
			(net "PVCCFA_EHV_FIVRA_CPU1_VOS4")
		)
		(pad "2" smd circle
			(at -0.40005 0 180)
			(size 0 0)
			(layers "B.Cu" "B.Mask" "B.Paste")
			(net "PVCCFA_EHV_FIVRA_CPU1")
		)
	)
	(footprint ""
		(layer "B.Cu")
		(at 99.26828 -325.084948 -90)
		(property "Reference" "PR4240"
			(at 0 0 90)
			(layer "B.SilkS")
			(hide yes)
			(effects
				(font
					(size 1.27 1.27)
				)
				(justify mirror)
			)
		)
		(property "Value" ""
			(at 0 0 90)
			(layer "B.Fab")
			(effects
				(font
					(size 1.27 1.27)
				)
				(justify mirror)
			)
		)
		(duplicate_pad_numbers_are_jumpers no)
		(fp_line
			(start -0.7874 0.4064)
			(end 0.7874 0.4064)
			(stroke
				(width 0.1524)
				(type default)
			)
			(layer "B.SilkS")
		)
		(fp_line
			(start 0.7874 0.4064)
			(end 0.7874 -0.4064)
			(stroke
				(width 0.1524)
				(type default)
			)
			(layer "B.SilkS")
		)
		(fp_line
			(start -0.7874 -0.4064)
			(end -0.7874 0.4064)
			(stroke
				(width 0.1524)
				(type default)
			)
			(layer "B.SilkS")
		)
		(fp_line
			(start 0.7874 -0.4064)
			(end -0.7874 -0.4064)
			(stroke
				(width 0.1524)
				(type default)
			)
			(layer "B.SilkS")
		)
		(fp_line
			(start -0.67945 0.3048)
			(end -0.120396 0.3048)
			(stroke
				(width 0.1)
				(type default)
			)
			(layer "B.Fab")
		)
		(fp_line
			(start -0.120396 0.3048)
			(end -0.120396 0.2794)
			(stroke
				(width 0.1)
				(type default)
			)
			(layer "B.Fab")
		)
		(fp_line
			(start 0.12065 0.3048)
			(end 0.67945 0.3048)
			(stroke
				(width 0.1)
				(type default)
			)
			(layer "B.Fab")
		)
		(fp_line
			(start 0.67945 0.3048)
			(end 0.67945 -0.305054)
			(stroke
				(width 0.1)
				(type default)
			)
			(layer "B.Fab")
		)
		(fp_line
			(start -0.120396 0.2794)
			(end 0.12065 0.2794)
			(stroke
				(width 0.1)
				(type default)
			)
			(layer "B.Fab")
		)
		(fp_line
			(start 0.12065 0.2794)
			(end 0.12065 0.3048)
			(stroke
				(width 0.1)
				(type default)
			)
			(layer "B.Fab")
		)
		(fp_line
			(start -0.12065 -0.2794)
			(end -0.12065 -0.3048)
			(stroke
				(width 0.1)
				(type default)
			)
			(layer "B.Fab")
		)
		(fp_line
			(start 0.12065 -0.2794)
			(end -0.12065 -0.2794)
			(stroke
				(width 0.1)
				(type default)
			)
			(layer "B.Fab")
		)
		(fp_line
			(start -0.67945 -0.3048)
			(end -0.67945 0.3048)
			(stroke
				(width 0.1)
				(type default)
			)
			(layer "B.Fab")
		)
		(fp_line
			(start -0.12065 -0.3048)
			(end -0.67945 -0.3048)
			(stroke
				(width 0.1)
				(type default)
			)
			(layer "B.Fab")
		)
		(fp_line
			(start 0.12065 -0.305054)
			(end 0.12065 -0.2794)
			(stroke
				(width 0.1)
				(type default)
			)
			(layer "B.Fab")
		)
		(fp_line
			(start 0.67945 -0.305054)
			(end 0.12065 -0.305054)
			(stroke
				(width 0.1)
				(type default)
			)
			(layer "B.Fab")
		)
		(pad "1" smd circle
			(at 0.40005 0 90)
			(size 0 0)
			(layers "B.Cu" "B.Mask" "B.Paste")
			(net "PVCCIN_CPU1")
		)
		(pad "2" smd circle
			(at -0.40005 0 90)
			(size 0 0)
			(layers "B.Cu" "B.Mask" "B.Paste")
			(net "GND")
		)
	)
	(footprint ""
		(layer "B.Cu")
		(at 374.562624 -190.703454 90)
		(property "Reference" "R909"
			(at 0 0 90)
			(layer "B.SilkS")
			(hide yes)
			(effects
				(font
					(size 1.27 1.27)
				)
				(justify mirror)
			)
		)
		(property "Value" ""
			(at 0 0 90)
			(layer "B.Fab")
			(effects
				(font
					(size 1.27 1.27)
				)
				(justify mirror)
			)
		)
		(duplicate_pad_numbers_are_jumpers no)
		(fp_line
			(start 0.7874 -0.4064)
			(end -0.7874 -0.4064)
			(stroke
				(width 0.1524)
				(type default)
			)
			(layer "B.SilkS")
		)
		(fp_line
			(start -0.7874 -0.4064)
			(end -0.7874 0.4064)
			(stroke
				(width 0.1524)
				(type default)
			)
			(layer "B.SilkS")
		)
		(fp_line
			(start 0.7874 0.4064)
			(end 0.7874 -0.4064)
			(stroke
				(width 0.1524)
				(type default)
			)
			(layer "B.SilkS")
		)
		(fp_line
			(start -0.7874 0.4064)
			(end 0.7874 0.4064)
			(stroke
				(width 0.1524)
				(type default)
			)
			(layer "B.SilkS")
		)
		(fp_line
			(start 0.67945 -0.305054)
			(end 0.12065 -0.305054)
			(stroke
				(width 0.1)
				(type default)
			)
			(layer "B.Fab")
		)
		(fp_line
			(start 0.12065 -0.305054)
			(end 0.12065 -0.2794)
			(stroke
				(width 0.1)
				(type default)
			)
			(layer "B.Fab")
		)
		(fp_line
			(start -0.12065 -0.3048)
			(end -0.67945 -0.3048)
			(stroke
				(width 0.1)
				(type default)
			)
			(layer "B.Fab")
		)
		(fp_line
			(start -0.67945 -0.3048)
			(end -0.67945 0.3048)
			(stroke
				(width 0.1)
				(type default)
			)
			(layer "B.Fab")
		)
		(fp_line
			(start 0.12065 -0.2794)
			(end -0.12065 -0.2794)
			(stroke
				(width 0.1)
				(type default)
			)
			(layer "B.Fab")
		)
		(fp_line
			(start -0.12065 -0.2794)
			(end -0.12065 -0.3048)
			(stroke
				(width 0.1)
				(type default)
			)
			(layer "B.Fab")
		)
		(fp_line
			(start 0.12065 0.2794)
			(end 0.12065 0.3048)
			(stroke
				(width 0.1)
				(type default)
			)
			(layer "B.Fab")
		)
		(fp_line
			(start -0.120396 0.2794)
			(end 0.12065 0.2794)
			(stroke
				(width 0.1)
				(type default)
			)
			(layer "B.Fab")
		)
		(fp_line
			(start 0.67945 0.3048)
			(end 0.67945 -0.305054)
			(stroke
				(width 0.1)
				(type default)
			)
			(layer "B.Fab")
		)
		(fp_line
			(start 0.12065 0.3048)
			(end 0.67945 0.3048)
			(stroke
				(width 0.1)
				(type default)
			)
			(layer "B.Fab")
		)
		(fp_line
			(start -0.120396 0.3048)
			(end -0.120396 0.2794)
			(stroke
				(width 0.1)
				(type default)
			)
			(layer "B.Fab")
		)
		(fp_line
			(start -0.67945 0.3048)
			(end -0.120396 0.3048)
			(stroke
				(width 0.1)
				(type default)
			)
			(layer "B.Fab")
		)
		(pad "1" smd circle
			(at 0.40005 0 270)
			(size 0 0)
			(layers "B.Cu" "B.Mask" "B.Paste")
			(net "SMB_PEHPCPU0_GTL_SDA")
		)
		(pad "2" smd circle
			(at -0.40005 0 270)
			(size 0 0)
			(layers "B.Cu" "B.Mask" "B.Paste")
			(net "SMB_PEHPCPU0_GTL_R_SDA")
		)
	)
	(footprint ""
		(layer "B.Cu")
		(at 303.554638 -192.457578 90)
		(property "Reference" "R548"
			(at 0 0 90)
			(layer "B.SilkS")
			(hide yes)
			(effects
				(font
					(size 1.27 1.27)
				)
				(justify mirror)
			)
		)
		(property "Value" ""
			(at 0 0 90)
			(layer "B.Fab")
			(effects
				(font
					(size 1.27 1.27)
				)
				(justify mirror)
			)
		)
		(duplicate_pad_numbers_are_jumpers no)
		(fp_line
			(start 0.7874 -0.4064)
			(end -0.7874 -0.4064)
			(stroke
				(width 0.1524)
				(type default)
			)
			(layer "B.SilkS")
		)
		(fp_line
			(start -0.7874 -0.4064)
			(end -0.7874 0.4064)
			(stroke
				(width 0.1524)
				(type default)
			)
			(layer "B.SilkS")
		)
		(fp_line
			(start 0.7874 0.4064)
			(end 0.7874 -0.4064)
			(stroke
				(width 0.1524)
				(type default)
			)
			(layer "B.SilkS")
		)
		(fp_line
			(start -0.7874 0.4064)
			(end 0.7874 0.4064)
			(stroke
				(width 0.1524)
				(type default)
			)
			(layer "B.SilkS")
		)
		(fp_line
			(start 0.67945 -0.305054)
			(end 0.12065 -0.305054)
			(stroke
				(width 0.1)
				(type default)
			)
			(layer "B.Fab")
		)
		(fp_line
			(start 0.12065 -0.305054)
			(end 0.12065 -0.2794)
			(stroke
				(width 0.1)
				(type default)
			)
			(layer "B.Fab")
		)
		(fp_line
			(start -0.12065 -0.3048)
			(end -0.67945 -0.3048)
			(stroke
				(width 0.1)
				(type default)
			)
			(layer "B.Fab")
		)
		(fp_line
			(start -0.67945 -0.3048)
			(end -0.67945 0.3048)
			(stroke
				(width 0.1)
				(type default)
			)
			(layer "B.Fab")
		)
		(fp_line
			(start 0.12065 -0.2794)
			(end -0.12065 -0.2794)
			(stroke
				(width 0.1)
				(type default)
			)
			(layer "B.Fab")
		)
		(fp_line
			(start -0.12065 -0.2794)
			(end -0.12065 -0.3048)
			(stroke
				(width 0.1)
				(type default)
			)
			(layer "B.Fab")
		)
		(fp_line
			(start 0.12065 0.2794)
			(end 0.12065 0.3048)
			(stroke
				(width 0.1)
				(type default)
			)
			(layer "B.Fab")
		)
		(fp_line
			(start -0.120396 0.2794)
			(end 0.12065 0.2794)
			(stroke
				(width 0.1)
				(type default)
			)
			(layer "B.Fab")
		)
		(fp_line
			(start 0.67945 0.3048)
			(end 0.67945 -0.305054)
			(stroke
				(width 0.1)
				(type default)
			)
			(layer "B.Fab")
		)
		(fp_line
			(start 0.12065 0.3048)
			(end 0.67945 0.3048)
			(stroke
				(width 0.1)
				(type default)
			)
			(layer "B.Fab")
		)
		(fp_line
			(start -0.120396 0.3048)
			(end -0.120396 0.2794)
			(stroke
				(width 0.1)
				(type default)
			)
			(layer "B.Fab")
		)
		(fp_line
			(start -0.67945 0.3048)
			(end -0.120396 0.3048)
			(stroke
				(width 0.1)
				(type default)
			)
			(layer "B.Fab")
		)
		(pad "1" smd circle
			(at 0.40005 0 270)
			(size 0 0)
			(layers "B.Cu" "B.Mask" "B.Paste")
			(net "SVID_ALERT0_CPU0_R_N")
		)
		(pad "2" smd circle
			(at -0.40005 0 270)
			(size 0 0)
			(layers "B.Cu" "B.Mask" "B.Paste")
			(net "PVNN_TERM_CPU0")
		)
	)
	(footprint ""
		(layer "B.Cu")
		(at 49.15408 -172.989748)
		(property "Reference" "PR4248"
			(at 0 0 0)
			(layer "B.SilkS")
			(hide yes)
			(effects
				(font
					(size 1.27 1.27)
				)
				(justify mirror)
			)
		)
		(property "Value" ""
			(at 0 0 0)
			(layer "B.Fab")
			(effects
				(font
					(size 1.27 1.27)
				)
				(justify mirror)
			)
		)
		(duplicate_pad_numbers_are_jumpers no)
		(fp_line
			(start -0.7874 -0.4064)
			(end -0.7874 0.4064)
			(stroke
				(width 0.1524)
				(type default)
			)
			(layer "B.SilkS")
		)
		(fp_line
			(start -0.7874 0.4064)
			(end 0.7874 0.4064)
			(stroke
				(width 0.1524)
				(type default)
			)
			(layer "B.SilkS")
		)
		(fp_line
			(start 0.7874 -0.4064)
			(end -0.7874 -0.4064)
			(stroke
				(width 0.1524)
				(type default)
			)
			(layer "B.SilkS")
		)
		(fp_line
			(start 0.7874 0.4064)
			(end 0.7874 -0.4064)
			(stroke
				(width 0.1524)
				(type default)
			)
			(layer "B.SilkS")
		)
		(fp_line
			(start -0.67945 -0.3048)
			(end -0.67945 0.3048)
			(stroke
				(width 0.1)
				(type default)
			)
			(layer "B.Fab")
		)
		(fp_line
			(start -0.67945 0.3048)
			(end -0.120396 0.3048)
			(stroke
				(width 0.1)
				(type default)
			)
			(layer "B.Fab")
		)
		(fp_line
			(start -0.12065 -0.3048)
			(end -0.67945 -0.3048)
			(stroke
				(width 0.1)
				(type default)
			)
			(layer "B.Fab")
		)
		(fp_line
			(start -0.12065 -0.2794)
			(end -0.12065 -0.3048)
			(stroke
				(width 0.1)
				(type default)
			)
			(layer "B.Fab")
		)
		(fp_line
			(start -0.120396 0.2794)
			(end 0.12065 0.2794)
			(stroke
				(width 0.1)
				(type default)
			)
			(layer "B.Fab")
		)
		(fp_line
			(start -0.120396 0.3048)
			(end -0.120396 0.2794)
			(stroke
				(width 0.1)
				(type default)
			)
			(layer "B.Fab")
		)
		(fp_line
			(start 0.12065 -0.305054)
			(end 0.12065 -0.2794)
			(stroke
				(width 0.1)
				(type default)
			)
			(layer "B.Fab")
		)
		(fp_line
			(start 0.12065 -0.2794)
			(end -0.12065 -0.2794)
			(stroke
				(width 0.1)
				(type default)
			)
			(layer "B.Fab")
		)
		(fp_line
			(start 0.12065 0.2794)
			(end 0.12065 0.3048)
			(stroke
				(width 0.1)
				(type default)
			)
			(layer "B.Fab")
		)
		(fp_line
			(start 0.12065 0.3048)
			(end 0.67945 0.3048)
			(stroke
				(width 0.1)
				(type default)
			)
			(layer "B.Fab")
		)
		(fp_line
			(start 0.67945 -0.305054)
			(end 0.12065 -0.305054)
			(stroke
				(width 0.1)
				(type default)
			)
			(layer "B.Fab")
		)
		(fp_line
			(start 0.67945 0.3048)
			(end 0.67945 -0.305054)
			(stroke
				(width 0.1)
				(type default)
			)
			(layer "B.Fab")
		)
		(pad "1" smd circle
			(at 0.40005 0 180)
			(size 0 0)
			(layers "B.Cu" "B.Mask" "B.Paste")
			(net "PVCCFA_EHV_CPU1_NC2")
		)
		(pad "2" smd circle
			(at -0.40005 0 180)
			(size 0 0)
			(layers "B.Cu" "B.Mask" "B.Paste")
			(net "PVCCFA_EHV_CPU1_VDD1")
		)
	)
	(footprint ""
		(layer "B.Cu")
		(at 430.600104 -137.542778)
		(property "Reference" "R2396"
			(at 0 0 0)
			(layer "B.SilkS")
			(hide yes)
			(effects
				(font
					(size 1.27 1.27)
				)
				(justify mirror)
			)
		)
		(property "Value" ""
			(at 0 0 0)
			(layer "B.Fab")
			(effects
				(font
					(size 1.27 1.27)
				)
				(justify mirror)
			)
		)
		(duplicate_pad_numbers_are_jumpers no)
		(fp_line
			(start -0.7874 -0.4064)
			(end -0.7874 0.4064)
			(stroke
				(width 0.1524)
				(type default)
			)
			(layer "B.SilkS")
		)
		(fp_line
			(start -0.7874 0.4064)
			(end 0.7874 0.4064)
			(stroke
				(width 0.1524)
				(type default)
			)
			(layer "B.SilkS")
		)
		(fp_line
			(start 0.7874 -0.4064)
			(end -0.7874 -0.4064)
			(stroke
				(width 0.1524)
				(type default)
			)
			(layer "B.SilkS")
		)
		(fp_line
			(start 0.7874 0.4064)
			(end 0.7874 -0.4064)
			(stroke
				(width 0.1524)
				(type default)
			)
			(layer "B.SilkS")
		)
		(fp_line
			(start -0.67945 -0.3048)
			(end -0.67945 0.3048)
			(stroke
				(width 0.1)
				(type default)
			)
			(layer "B.Fab")
		)
		(fp_line
			(start -0.67945 0.3048)
			(end -0.120396 0.3048)
			(stroke
				(width 0.1)
				(type default)
			)
			(layer "B.Fab")
		)
		(fp_line
			(start -0.12065 -0.3048)
			(end -0.67945 -0.3048)
			(stroke
				(width 0.1)
				(type default)
			)
			(layer "B.Fab")
		)
		(fp_line
			(start -0.12065 -0.2794)
			(end -0.12065 -0.3048)
			(stroke
				(width 0.1)
				(type default)
			)
			(layer "B.Fab")
		)
		(fp_line
			(start -0.120396 0.2794)
			(end 0.12065 0.2794)
			(stroke
				(width 0.1)
				(type default)
			)
			(layer "B.Fab")
		)
		(fp_line
			(start -0.120396 0.3048)
			(end -0.120396 0.2794)
			(stroke
				(width 0.1)
				(type default)
			)
			(layer "B.Fab")
		)
		(fp_line
			(start 0.12065 -0.305054)
			(end 0.12065 -0.2794)
			(stroke
				(width 0.1)
				(type default)
			)
			(layer "B.Fab")
		)
		(fp_line
			(start 0.12065 -0.2794)
			(end -0.12065 -0.2794)
			(stroke
				(width 0.1)
				(type default)
			)
			(layer "B.Fab")
		)
		(fp_line
			(start 0.12065 0.2794)
			(end 0.12065 0.3048)
			(stroke
				(width 0.1)
				(type default)
			)
			(layer "B.Fab")
		)
		(fp_line
			(start 0.12065 0.3048)
			(end 0.67945 0.3048)
			(stroke
				(width 0.1)
				(type default)
			)
			(layer "B.Fab")
		)
		(fp_line
			(start 0.67945 -0.305054)
			(end 0.12065 -0.305054)
			(stroke
				(width 0.1)
				(type default)
			)
			(layer "B.Fab")
		)
		(fp_line
			(start 0.67945 0.3048)
			(end 0.67945 -0.305054)
			(stroke
				(width 0.1)
				(type default)
			)
			(layer "B.Fab")
		)
		(pad "1" smd circle
			(at 0.40005 0 180)
			(size 0 0)
			(layers "B.Cu" "B.Mask" "B.Paste")
			(net "P3V3_AUX")
		)
		(pad "2" smd circle
			(at -0.40005 0 180)
			(size 0 0)
			(layers "B.Cu" "B.Mask" "B.Paste")
			(net "PWRGD_PVCCFA_EHV_CPU0_R")
		)
	)
	(footprint ""
		(layer "B.Cu")
		(at 61.62421 -147.84197)
		(property "Reference" "PC1588"
			(at 0 0 0)
			(layer "B.SilkS")
			(hide yes)
			(effects
				(font
					(size 1.27 1.27)
				)
				(justify mirror)
			)
		)
		(property "Value" ""
			(at 0 0 0)
			(layer "B.Fab")
			(effects
				(font
					(size 1.27 1.27)
				)
				(justify mirror)
			)
		)
		(duplicate_pad_numbers_are_jumpers no)
		(fp_line
			(start -4.53898 -2.15011)
			(end -4.53898 2.15011)
			(stroke
				(width 0.1524)
				(type default)
			)
			(layer "B.SilkS")
		)
		(fp_line
			(start -4.53898 2.15011)
			(end 4.53898 2.15011)
			(stroke
				(width 0.1524)
				(type default)
			)
			(layer "B.SilkS")
		)
		(fp_line
			(start 4.53898 -2.150618)
			(end 4.539742 2.152142)
			(stroke
				(width 0.1524)
				(type default)
			)
			(layer "B.SilkS")
		)
		(fp_line
			(start 4.53898 -2.15011)
			(end -4.53898 -2.15011)
			(stroke
				(width 0.1524)
				(type default)
			)
			(layer "B.SilkS")
		)
		(fp_line
			(start 4.53898 2.15011)
			(end 4.53898 -2.15011)
			(stroke
				(width 0.1524)
				(type default)
			)
			(layer "B.SilkS")
		)
		(fp_line
			(start 4.69138 -2.150618)
			(end 4.692396 2.161032)
			(stroke
				(width 0.1524)
				(type default)
			)
			(layer "B.SilkS")
		)
		(fp_line
			(start 4.83108 2.150364)
			(end 4.447794 2.149348)
			(stroke
				(width 0.1524)
				(type default)
			)
			(layer "B.SilkS")
		)
		(fp_line
			(start 4.84378 -2.150618)
			(end 4.53898 -2.150618)
			(stroke
				(width 0.1524)
				(type default)
			)
			(layer "B.SilkS")
		)
		(fp_line
			(start 4.84378 -2.150618)
			(end 4.842256 2.163064)
			(stroke
				(width 0.1524)
				(type default)
			)
			(layer "B.SilkS")
		)
		(fp_line
			(start -3.64998 -2.15011)
			(end -3.64998 2.15011)
			(stroke
				(width 0.1)
				(type default)
			)
			(layer "B.Fab")
		)
		(fp_line
			(start -3.64998 2.15011)
			(end 3.64998 2.15011)
			(stroke
				(width 0.1)
				(type default)
			)
			(layer "B.Fab")
		)
		(fp_line
			(start 3.64998 -2.15011)
			(end -3.64998 -2.15011)
			(stroke
				(width 0.1)
				(type default)
			)
			(layer "B.Fab")
		)
		(fp_line
			(start 3.64998 2.15011)
			(end 3.64998 -2.15011)
			(stroke
				(width 0.1)
				(type default)
			)
			(layer "B.Fab")
		)
		(fp_text user "-"
			(at -4.66979 0.700532 0)
			(unlocked yes)
			(layer "B.SilkS")
			(effects
				(font
					(size 1.905 1.4224)
					(thickness 0.1524)
				)
				(justify left mirror)
			)
		)
		(fp_text user "+"
			(at 6.214872 -0.337058 0)
			(unlocked yes)
			(layer "B.SilkS")
			(effects
				(font
					(size 1.905 1.4224)
					(thickness 0.1524)
				)
				(justify left mirror)
			)
		)
		(fp_text user "-"
			(at -4.313174 -0.094488 0)
			(unlocked yes)
			(layer "B.Fab")
			(effects
				(font
					(size 1.905 1.4224)
					(thickness 0.1524)
				)
				(justify left mirror)
			)
		)
		(fp_text user "+"
			(at 6.214872 -0.337058 0)
			(unlocked yes)
			(layer "B.Fab")
			(effects
				(font
					(size 1.905 1.4224)
					(thickness 0.1524)
				)
				(justify left mirror)
			)
		)
		(pad "1" smd rect
			(at 3.199892 0 180)
			(size 2.413 2.8194)
			(layers "B.Cu" "B.Mask" "B.Paste")
			(net "PVCCINFAON_CPU1")
		)
		(pad "2" smd rect
			(at -3.199892 0 180)
			(size 2.413 2.8194)
			(layers "B.Cu" "B.Mask" "B.Paste")
			(net "GND")
		)
	)
	(footprint ""
		(layer "B.Cu")
		(at 55.695088 -193.39179 90)
		(property "Reference" "R157"
			(at 0 0 90)
			(layer "B.SilkS")
			(hide yes)
			(effects
				(font
					(size 1.27 1.27)
				)
				(justify mirror)
			)
		)
		(property "Value" ""
			(at 0 0 90)
			(layer "B.Fab")
			(effects
				(font
					(size 1.27 1.27)
				)
				(justify mirror)
			)
		)
		(duplicate_pad_numbers_are_jumpers no)
		(fp_line
			(start 0.7874 -0.4064)
			(end -0.7874 -0.4064)
			(stroke
				(width 0.1524)
				(type default)
			)
			(layer "B.SilkS")
		)
		(fp_line
			(start -0.7874 -0.4064)
			(end -0.7874 0.4064)
			(stroke
				(width 0.1524)
				(type default)
			)
			(layer "B.SilkS")
		)
		(fp_line
			(start 0.7874 0.4064)
			(end 0.7874 -0.4064)
			(stroke
				(width 0.1524)
				(type default)
			)
			(layer "B.SilkS")
		)
		(fp_line
			(start -0.7874 0.4064)
			(end 0.7874 0.4064)
			(stroke
				(width 0.1524)
				(type default)
			)
			(layer "B.SilkS")
		)
		(fp_line
			(start 0.67945 -0.305054)
			(end 0.12065 -0.305054)
			(stroke
				(width 0.1)
				(type default)
			)
			(layer "B.Fab")
		)
		(fp_line
			(start 0.12065 -0.305054)
			(end 0.12065 -0.2794)
			(stroke
				(width 0.1)
				(type default)
			)
			(layer "B.Fab")
		)
		(fp_line
			(start -0.12065 -0.3048)
			(end -0.67945 -0.3048)
			(stroke
				(width 0.1)
				(type default)
			)
			(layer "B.Fab")
		)
		(fp_line
			(start -0.67945 -0.3048)
			(end -0.67945 0.3048)
			(stroke
				(width 0.1)
				(type default)
			)
			(layer "B.Fab")
		)
		(fp_line
			(start 0.12065 -0.2794)
			(end -0.12065 -0.2794)
			(stroke
				(width 0.1)
				(type default)
			)
			(layer "B.Fab")
		)
		(fp_line
			(start -0.12065 -0.2794)
			(end -0.12065 -0.3048)
			(stroke
				(width 0.1)
				(type default)
			)
			(layer "B.Fab")
		)
		(fp_line
			(start 0.12065 0.2794)
			(end 0.12065 0.3048)
			(stroke
				(width 0.1)
				(type default)
			)
			(layer "B.Fab")
		)
		(fp_line
			(start -0.120396 0.2794)
			(end 0.12065 0.2794)
			(stroke
				(width 0.1)
				(type default)
			)
			(layer "B.Fab")
		)
		(fp_line
			(start 0.67945 0.3048)
			(end 0.67945 -0.305054)
			(stroke
				(width 0.1)
				(type default)
			)
			(layer "B.Fab")
		)
		(fp_line
			(start 0.12065 0.3048)
			(end 0.67945 0.3048)
			(stroke
				(width 0.1)
				(type default)
			)
			(layer "B.Fab")
		)
		(fp_line
			(start -0.120396 0.3048)
			(end -0.120396 0.2794)
			(stroke
				(width 0.1)
				(type default)
			)
			(layer "B.Fab")
		)
		(fp_line
			(start -0.67945 0.3048)
			(end -0.120396 0.3048)
			(stroke
				(width 0.1)
				(type default)
			)
			(layer "B.Fab")
		)
		(pad "1" smd circle
			(at 0.40005 0 270)
			(size 0 0)
			(layers "B.Cu" "B.Mask" "B.Paste")
			(net "RST_CPU1_BUF_R_N")
		)
		(pad "2" smd circle
			(at -0.40005 0 270)
			(size 0 0)
			(layers "B.Cu" "B.Mask" "B.Paste")
			(net "PVNN_TERM_CPU1")
		)
	)
	(footprint ""
		(layer "B.Cu")
		(at 440.383676 -15.656306)
		(property "Reference" "C1234"
			(at 0 0 0)
			(layer "B.SilkS")
			(hide yes)
			(effects
				(font
					(size 1.27 1.27)
				)
				(justify mirror)
			)
		)
		(property "Value" ""
			(at 0 0 0)
			(layer "B.Fab")
			(effects
				(font
					(size 1.27 1.27)
				)
				(justify mirror)
			)
		)
		(duplicate_pad_numbers_are_jumpers no)
		(fp_line
			(start -0.7874 -0.4064)
			(end -0.7874 0.4064)
			(stroke
				(width 0.1524)
				(type default)
			)
			(layer "B.SilkS")
		)
		(fp_line
			(start -0.7874 0.4064)
			(end 0.7874 0.4064)
			(stroke
				(width 0.1524)
				(type default)
			)
			(layer "B.SilkS")
		)
		(fp_line
			(start 0.7874 -0.4064)
			(end -0.7874 -0.4064)
			(stroke
				(width 0.1524)
				(type default)
			)
			(layer "B.SilkS")
		)
		(fp_line
			(start 0.7874 0.4064)
			(end 0.7874 -0.4064)
			(stroke
				(width 0.1524)
				(type default)
			)
			(layer "B.SilkS")
		)
		(fp_line
			(start -0.67945 -0.3048)
			(end -0.67945 0.3048)
			(stroke
				(width 0.1)
				(type default)
			)
			(layer "B.Fab")
		)
		(fp_line
			(start -0.67945 0.3048)
			(end -0.120396 0.3048)
			(stroke
				(width 0.1)
				(type default)
			)
			(layer "B.Fab")
		)
		(fp_line
			(start -0.12065 -0.3048)
			(end -0.67945 -0.3048)
			(stroke
				(width 0.1)
				(type default)
			)
			(layer "B.Fab")
		)
		(fp_line
			(start -0.12065 -0.2794)
			(end -0.12065 -0.3048)
			(stroke
				(width 0.1)
				(type default)
			)
			(layer "B.Fab")
		)
		(fp_line
			(start -0.120396 0.2794)
			(end 0.12065 0.2794)
			(stroke
				(width 0.1)
				(type default)
			)
			(layer "B.Fab")
		)
		(fp_line
			(start -0.120396 0.3048)
			(end -0.120396 0.2794)
			(stroke
				(width 0.1)
				(type default)
			)
			(layer "B.Fab")
		)
		(fp_line
			(start 0.12065 -0.305054)
			(end 0.12065 -0.2794)
			(stroke
				(width 0.1)
				(type default)
			)
			(layer "B.Fab")
		)
		(fp_line
			(start 0.12065 -0.2794)
			(end -0.12065 -0.2794)
			(stroke
				(width 0.1)
				(type default)
			)
			(layer "B.Fab")
		)
		(fp_line
			(start 0.12065 0.2794)
			(end 0.12065 0.3048)
			(stroke
				(width 0.1)
				(type default)
			)
			(layer "B.Fab")
		)
		(fp_line
			(start 0.12065 0.3048)
			(end 0.67945 0.3048)
			(stroke
				(width 0.1)
				(type default)
			)
			(layer "B.Fab")
		)
		(fp_line
			(start 0.67945 -0.305054)
			(end 0.12065 -0.305054)
			(stroke
				(width 0.1)
				(type default)
			)
			(layer "B.Fab")
		)
		(fp_line
			(start 0.67945 0.3048)
			(end 0.67945 -0.305054)
			(stroke
				(width 0.1)
				(type default)
			)
			(layer "B.Fab")
		)
		(pad "1" smd circle
			(at 0.40005 0 180)
			(size 0 0)
			(layers "B.Cu" "B.Mask" "B.Paste")
			(net "P12V_OCP_SFF")
		)
		(pad "2" smd circle
			(at -0.40005 0 180)
			(size 0 0)
			(layers "B.Cu" "B.Mask" "B.Paste")
			(net "GND")
		)
	)
	(footprint ""
		(layer "B.Cu")
		(at 213.58098 -318.107568)
		(property "Reference" "R73"
			(at 0 0 0)
			(layer "B.SilkS")
			(hide yes)
			(effects
				(font
					(size 1.27 1.27)
				)
				(justify mirror)
			)
		)
		(property "Value" ""
			(at 0 0 0)
			(layer "B.Fab")
			(effects
				(font
					(size 1.27 1.27)
				)
				(justify mirror)
			)
		)
		(duplicate_pad_numbers_are_jumpers no)
		(fp_line
			(start -0.7874 -0.4064)
			(end -0.7874 0.4064)
			(stroke
				(width 0.1524)
				(type default)
			)
			(layer "B.SilkS")
		)
		(fp_line
			(start -0.7874 0.4064)
			(end 0.7874 0.4064)
			(stroke
				(width 0.1524)
				(type default)
			)
			(layer "B.SilkS")
		)
		(fp_line
			(start 0.7874 -0.4064)
			(end -0.7874 -0.4064)
			(stroke
				(width 0.1524)
				(type default)
			)
			(layer "B.SilkS")
		)
		(fp_line
			(start 0.7874 0.4064)
			(end 0.7874 -0.4064)
			(stroke
				(width 0.1524)
				(type default)
			)
			(layer "B.SilkS")
		)
		(fp_line
			(start -0.67945 -0.3048)
			(end -0.67945 0.3048)
			(stroke
				(width 0.1)
				(type default)
			)
			(layer "B.Fab")
		)
		(fp_line
			(start -0.67945 0.3048)
			(end -0.120396 0.3048)
			(stroke
				(width 0.1)
				(type default)
			)
			(layer "B.Fab")
		)
		(fp_line
			(start -0.12065 -0.3048)
			(end -0.67945 -0.3048)
			(stroke
				(width 0.1)
				(type default)
			)
			(layer "B.Fab")
		)
		(fp_line
			(start -0.12065 -0.2794)
			(end -0.12065 -0.3048)
			(stroke
				(width 0.1)
				(type default)
			)
			(layer "B.Fab")
		)
		(fp_line
			(start -0.120396 0.2794)
			(end 0.12065 0.2794)
			(stroke
				(width 0.1)
				(type default)
			)
			(layer "B.Fab")
		)
		(fp_line
			(start -0.120396 0.3048)
			(end -0.120396 0.2794)
			(stroke
				(width 0.1)
				(type default)
			)
			(layer "B.Fab")
		)
		(fp_line
			(start 0.12065 -0.305054)
			(end 0.12065 -0.2794)
			(stroke
				(width 0.1)
				(type default)
			)
			(layer "B.Fab")
		)
		(fp_line
			(start 0.12065 -0.2794)
			(end -0.12065 -0.2794)
			(stroke
				(width 0.1)
				(type default)
			)
			(layer "B.Fab")
		)
		(fp_line
			(start 0.12065 0.2794)
			(end 0.12065 0.3048)
			(stroke
				(width 0.1)
				(type default)
			)
			(layer "B.Fab")
		)
		(fp_line
			(start 0.12065 0.3048)
			(end 0.67945 0.3048)
			(stroke
				(width 0.1)
				(type default)
			)
			(layer "B.Fab")
		)
		(fp_line
			(start 0.67945 -0.305054)
			(end 0.12065 -0.305054)
			(stroke
				(width 0.1)
				(type default)
			)
			(layer "B.Fab")
		)
		(fp_line
			(start 0.67945 0.3048)
			(end 0.67945 -0.305054)
			(stroke
				(width 0.1)
				(type default)
			)
			(layer "B.Fab")
		)
		(pad "1" smd circle
			(at 0.40005 0 180)
			(size 0 0)
			(layers "B.Cu" "B.Mask" "B.Paste")
			(net "PD_CHH_CPU1_DIMM1_SAA")
		)
		(pad "2" smd circle
			(at -0.40005 0 180)
			(size 0 0)
			(layers "B.Cu" "B.Mask" "B.Paste")
			(net "GND")
		)
	)
	(footprint ""
		(layer "B.Cu")
		(at 128.85674 -18.539968 -90)
		(property "Reference" "R4279"
			(at 0 0 90)
			(layer "B.SilkS")
			(hide yes)
			(effects
				(font
					(size 1.27 1.27)
				)
				(justify mirror)
			)
		)
		(property "Value" ""
			(at 0 0 90)
			(layer "B.Fab")
			(effects
				(font
					(size 1.27 1.27)
				)
				(justify mirror)
			)
		)
		(duplicate_pad_numbers_are_jumpers no)
		(fp_line
			(start -0.7874 0.4064)
			(end 0.7874 0.4064)
			(stroke
				(width 0.1524)
				(type default)
			)
			(layer "B.SilkS")
		)
		(fp_line
			(start 0.7874 0.4064)
			(end 0.7874 -0.4064)
			(stroke
				(width 0.1524)
				(type default)
			)
			(layer "B.SilkS")
		)
		(fp_line
			(start -0.7874 -0.4064)
			(end -0.7874 0.4064)
			(stroke
				(width 0.1524)
				(type default)
			)
			(layer "B.SilkS")
		)
		(fp_line
			(start 0.7874 -0.4064)
			(end -0.7874 -0.4064)
			(stroke
				(width 0.1524)
				(type default)
			)
			(layer "B.SilkS")
		)
		(fp_line
			(start -0.67945 0.3048)
			(end -0.120396 0.3048)
			(stroke
				(width 0.1)
				(type default)
			)
			(layer "B.Fab")
		)
		(fp_line
			(start -0.120396 0.3048)
			(end -0.120396 0.2794)
			(stroke
				(width 0.1)
				(type default)
			)
			(layer "B.Fab")
		)
		(fp_line
			(start 0.12065 0.3048)
			(end 0.67945 0.3048)
			(stroke
				(width 0.1)
				(type default)
			)
			(layer "B.Fab")
		)
		(fp_line
			(start 0.67945 0.3048)
			(end 0.67945 -0.305054)
			(stroke
				(width 0.1)
				(type default)
			)
			(layer "B.Fab")
		)
		(fp_line
			(start -0.120396 0.2794)
			(end 0.12065 0.2794)
			(stroke
				(width 0.1)
				(type default)
			)
			(layer "B.Fab")
		)
		(fp_line
			(start 0.12065 0.2794)
			(end 0.12065 0.3048)
			(stroke
				(width 0.1)
				(type default)
			)
			(layer "B.Fab")
		)
		(fp_line
			(start -0.12065 -0.2794)
			(end -0.12065 -0.3048)
			(stroke
				(width 0.1)
				(type default)
			)
			(layer "B.Fab")
		)
		(fp_line
			(start 0.12065 -0.2794)
			(end -0.12065 -0.2794)
			(stroke
				(width 0.1)
				(type default)
			)
			(layer "B.Fab")
		)
		(fp_line
			(start -0.67945 -0.3048)
			(end -0.67945 0.3048)
			(stroke
				(width 0.1)
				(type default)
			)
			(layer "B.Fab")
		)
		(fp_line
			(start -0.12065 -0.3048)
			(end -0.67945 -0.3048)
			(stroke
				(width 0.1)
				(type default)
			)
			(layer "B.Fab")
		)
		(fp_line
			(start 0.12065 -0.305054)
			(end 0.12065 -0.2794)
			(stroke
				(width 0.1)
				(type default)
			)
			(layer "B.Fab")
		)
		(fp_line
			(start 0.67945 -0.305054)
			(end 0.12065 -0.305054)
			(stroke
				(width 0.1)
				(type default)
			)
			(layer "B.Fab")
		)
		(pad "1" smd circle
			(at 0.40005 0 90)
			(size 0 0)
			(layers "B.Cu" "B.Mask" "B.Paste")
			(net "P3V3_AUX")
		)
		(pad "2" smd circle
			(at -0.40005 0 90)
			(size 0 0)
			(layers "B.Cu" "B.Mask" "B.Paste")
			(net "FM_USB3_1_FGA")
		)
	)
	(footprint ""
		(layer "B.Cu")
		(at 170.555666 -116.975382)
		(property "Reference" "C1910"
			(at 0 0 0)
			(layer "B.SilkS")
			(hide yes)
			(effects
				(font
					(size 1.27 1.27)
				)
				(justify mirror)
			)
		)
		(property "Value" ""
			(at 0 0 0)
			(layer "B.Fab")
			(effects
				(font
					(size 1.27 1.27)
				)
				(justify mirror)
			)
		)
		(duplicate_pad_numbers_are_jumpers no)
		(fp_line
			(start -0.69215 -0.2921)
			(end -0.69215 0.2921)
			(stroke
				(width 0.1524)
				(type default)
			)
			(layer "B.SilkS")
		)
		(fp_line
			(start -0.69215 0.2921)
			(end 0.69215 0.2921)
			(stroke
				(width 0.1524)
				(type default)
			)
			(layer "B.SilkS")
		)
		(fp_line
			(start 0.69215 -0.2921)
			(end -0.69215 -0.2921)
			(stroke
				(width 0.1524)
				(type default)
			)
			(layer "B.SilkS")
		)
		(fp_line
			(start 0.69215 0.2921)
			(end 0.69215 -0.2921)
			(stroke
				(width 0.1524)
				(type default)
			)
			(layer "B.SilkS")
		)
		(fp_line
			(start -0.51435 -0.2794)
			(end -0.51435 0.2794)
			(stroke
				(width 0.1)
				(type default)
			)
			(layer "B.Fab")
		)
		(fp_line
			(start -0.51435 0.2794)
			(end 0.51435 0.2794)
			(stroke
				(width 0.1)
				(type default)
			)
			(layer "B.Fab")
		)
		(fp_line
			(start 0.51435 -0.2794)
			(end -0.51435 -0.2794)
			(stroke
				(width 0.1)
				(type default)
			)
			(layer "B.Fab")
		)
		(fp_line
			(start 0.51435 0.2794)
			(end 0.51435 -0.2794)
			(stroke
				(width 0.1)
				(type default)
			)
			(layer "B.Fab")
		)
		(pad "1" smd circle
			(at 0.40005 0 180)
			(size 0 0)
			(layers "B.Cu" "B.Mask" "B.Paste")
			(net "P3V3_AUX_FPGA_VCCIO0")
		)
		(pad "2" smd circle
			(at -0.40005 0 180)
			(size 0 0)
			(layers "B.Cu" "B.Mask" "B.Paste")
			(net "GND")
		)
		(zone
			(layer "B.Cu")
			(hatch none 0.5)
			(connect_pads
				(clearance 0)
			)
			(min_thickness 0.25)
			(keepout
				(tracks not_allowed)
				(vias allowed)
				(pads allowed)
				(copperpour not_allowed)
				(footprints allowed)
			)
			(placement
				(enabled no)
				(sheetname "")
			)
			(fill
				(thermal_gap 0.5)
				(thermal_bridge_width 0.5)
				(island_removal_mode 0)
			)
			(polygon
				(pts
					(xy 170.746166 -116.887752) (xy 170.654726 -116.829586) (xy 170.455336 -116.829586) (xy 170.365166 -116.887752)
					(xy 170.365166 -117.063012) (xy 170.455336 -117.121432) (xy 170.654726 -117.121432) (xy 170.746166 -117.063266)
				)
			)
		)
	)
	(footprint ""
		(layer "B.Cu")
		(at 88.401398 -184.01665 90)
		(property "Reference" "R1001"
			(at 0 0 90)
			(layer "B.SilkS")
			(hide yes)
			(effects
				(font
					(size 1.27 1.27)
				)
				(justify mirror)
			)
		)
		(property "Value" ""
			(at 0 0 90)
			(layer "B.Fab")
			(effects
				(font
					(size 1.27 1.27)
				)
				(justify mirror)
			)
		)
		(duplicate_pad_numbers_are_jumpers no)
		(fp_line
			(start 0.7874 -0.4064)
			(end -0.7874 -0.4064)
			(stroke
				(width 0.1524)
				(type default)
			)
			(layer "B.SilkS")
		)
		(fp_line
			(start -0.7874 -0.4064)
			(end -0.7874 0.4064)
			(stroke
				(width 0.1524)
				(type default)
			)
			(layer "B.SilkS")
		)
		(fp_line
			(start 0.7874 0.4064)
			(end 0.7874 -0.4064)
			(stroke
				(width 0.1524)
				(type default)
			)
			(layer "B.SilkS")
		)
		(fp_line
			(start -0.7874 0.4064)
			(end 0.7874 0.4064)
			(stroke
				(width 0.1524)
				(type default)
			)
			(layer "B.SilkS")
		)
		(fp_line
			(start 0.67945 -0.305054)
			(end 0.12065 -0.305054)
			(stroke
				(width 0.1)
				(type default)
			)
			(layer "B.Fab")
		)
		(fp_line
			(start 0.12065 -0.305054)
			(end 0.12065 -0.2794)
			(stroke
				(width 0.1)
				(type default)
			)
			(layer "B.Fab")
		)
		(fp_line
			(start -0.12065 -0.3048)
			(end -0.67945 -0.3048)
			(stroke
				(width 0.1)
				(type default)
			)
			(layer "B.Fab")
		)
		(fp_line
			(start -0.67945 -0.3048)
			(end -0.67945 0.3048)
			(stroke
				(width 0.1)
				(type default)
			)
			(layer "B.Fab")
		)
		(fp_line
			(start 0.12065 -0.2794)
			(end -0.12065 -0.2794)
			(stroke
				(width 0.1)
				(type default)
			)
			(layer "B.Fab")
		)
		(fp_line
			(start -0.12065 -0.2794)
			(end -0.12065 -0.3048)
			(stroke
				(width 0.1)
				(type default)
			)
			(layer "B.Fab")
		)
		(fp_line
			(start 0.12065 0.2794)
			(end 0.12065 0.3048)
			(stroke
				(width 0.1)
				(type default)
			)
			(layer "B.Fab")
		)
		(fp_line
			(start -0.120396 0.2794)
			(end 0.12065 0.2794)
			(stroke
				(width 0.1)
				(type default)
			)
			(layer "B.Fab")
		)
		(fp_line
			(start 0.67945 0.3048)
			(end 0.67945 -0.305054)
			(stroke
				(width 0.1)
				(type default)
			)
			(layer "B.Fab")
		)
		(fp_line
			(start 0.12065 0.3048)
			(end 0.67945 0.3048)
			(stroke
				(width 0.1)
				(type default)
			)
			(layer "B.Fab")
		)
		(fp_line
			(start -0.120396 0.3048)
			(end -0.120396 0.2794)
			(stroke
				(width 0.1)
				(type default)
			)
			(layer "B.Fab")
		)
		(fp_line
			(start -0.67945 0.3048)
			(end -0.120396 0.3048)
			(stroke
				(width 0.1)
				(type default)
			)
			(layer "B.Fab")
		)
		(pad "1" smd circle
			(at 0.40005 0 270)
			(size 0 0)
			(layers "B.Cu" "B.Mask" "B.Paste")
			(net "P3V3")
		)
		(pad "2" smd circle
			(at -0.40005 0 270)
			(size 0 0)
			(layers "B.Cu" "B.Mask" "B.Paste")
			(net "FM_SMB_PEHPCPU1_PCIE_ALERT_R_N")
		)
	)
	(footprint ""
		(layer "B.Cu")
		(at 64.904112 -258.472686 -90)
		(property "Reference" "C470"
			(at 0 0 90)
			(layer "B.SilkS")
			(hide yes)
			(effects
				(font
					(size 1.27 1.27)
				)
				(justify mirror)
			)
		)
		(property "Value" ""
			(at 0 0 90)
			(layer "B.Fab")
			(effects
				(font
					(size 1.27 1.27)
				)
				(justify mirror)
			)
		)
		(duplicate_pad_numbers_are_jumpers no)
		(fp_line
			(start -1.524 0.762)
			(end 1.524 0.762)
			(stroke
				(width 0.1524)
				(type default)
			)
			(layer "B.SilkS")
		)
		(fp_line
			(start 1.524 0.762)
			(end 1.524 -0.762)
			(stroke
				(width 0.1524)
				(type default)
			)
			(layer "B.SilkS")
		)
		(fp_line
			(start -1.524 -0.762)
			(end -1.524 0.762)
			(stroke
				(width 0.1524)
				(type default)
			)
			(layer "B.SilkS")
		)
		(fp_line
			(start 1.524 -0.762)
			(end -1.524 -0.762)
			(stroke
				(width 0.1524)
				(type default)
			)
			(layer "B.SilkS")
		)
		(fp_line
			(start -1.1049 0.724916)
			(end -1.1049 -0.724916)
			(stroke
				(width 0.1)
				(type default)
			)
			(layer "B.Fab")
		)
		(fp_line
			(start 1.1049 0.724916)
			(end -1.1049 0.724916)
			(stroke
				(width 0.1)
				(type default)
			)
			(layer "B.Fab")
		)
		(fp_line
			(start -1.1049 -0.724916)
			(end 1.1049 -0.724916)
			(stroke
				(width 0.1)
				(type default)
			)
			(layer "B.Fab")
		)
		(fp_line
			(start 1.1049 -0.724916)
			(end 1.1049 0.724916)
			(stroke
				(width 0.1)
				(type default)
			)
			(layer "B.Fab")
		)
		(pad "1" smd rect
			(at 0.889 0 270)
			(size 1.016 1.27)
			(layers "B.Cu" "B.Mask" "B.Paste")
			(net "PVCCFA_EHV_FIVRA_CPU1")
		)
		(pad "2" smd rect
			(at -0.889 0 270)
			(size 1.016 1.27)
			(layers "B.Cu" "B.Mask" "B.Paste")
			(net "GND")
		)
	)
	(footprint ""
		(layer "B.Cu")
		(at 295.565322 -363.78642 -90)
		(property "Reference" "PR356"
			(at 0 0 90)
			(layer "B.SilkS")
			(hide yes)
			(effects
				(font
					(size 1.27 1.27)
				)
				(justify mirror)
			)
		)
		(property "Value" ""
			(at 0 0 90)
			(layer "B.Fab")
			(effects
				(font
					(size 1.27 1.27)
				)
				(justify mirror)
			)
		)
		(duplicate_pad_numbers_are_jumpers no)
		(fp_line
			(start -0.7874 0.4064)
			(end 0.7874 0.4064)
			(stroke
				(width 0.1524)
				(type default)
			)
			(layer "B.SilkS")
		)
		(fp_line
			(start 0.7874 0.4064)
			(end 0.7874 -0.4064)
			(stroke
				(width 0.1524)
				(type default)
			)
			(layer "B.SilkS")
		)
		(fp_line
			(start -0.7874 -0.4064)
			(end -0.7874 0.4064)
			(stroke
				(width 0.1524)
				(type default)
			)
			(layer "B.SilkS")
		)
		(fp_line
			(start 0.7874 -0.4064)
			(end -0.7874 -0.4064)
			(stroke
				(width 0.1524)
				(type default)
			)
			(layer "B.SilkS")
		)
		(fp_line
			(start -0.67945 0.3048)
			(end -0.120396 0.3048)
			(stroke
				(width 0.1)
				(type default)
			)
			(layer "B.Fab")
		)
		(fp_line
			(start -0.120396 0.3048)
			(end -0.120396 0.2794)
			(stroke
				(width 0.1)
				(type default)
			)
			(layer "B.Fab")
		)
		(fp_line
			(start 0.12065 0.3048)
			(end 0.67945 0.3048)
			(stroke
				(width 0.1)
				(type default)
			)
			(layer "B.Fab")
		)
		(fp_line
			(start 0.67945 0.3048)
			(end 0.67945 -0.305054)
			(stroke
				(width 0.1)
				(type default)
			)
			(layer "B.Fab")
		)
		(fp_line
			(start -0.120396 0.2794)
			(end 0.12065 0.2794)
			(stroke
				(width 0.1)
				(type default)
			)
			(layer "B.Fab")
		)
		(fp_line
			(start 0.12065 0.2794)
			(end 0.12065 0.3048)
			(stroke
				(width 0.1)
				(type default)
			)
			(layer "B.Fab")
		)
		(fp_line
			(start -0.12065 -0.2794)
			(end -0.12065 -0.3048)
			(stroke
				(width 0.1)
				(type default)
			)
			(layer "B.Fab")
		)
		(fp_line
			(start 0.12065 -0.2794)
			(end -0.12065 -0.2794)
			(stroke
				(width 0.1)
				(type default)
			)
			(layer "B.Fab")
		)
		(fp_line
			(start -0.67945 -0.3048)
			(end -0.67945 0.3048)
			(stroke
				(width 0.1)
				(type default)
			)
			(layer "B.Fab")
		)
		(fp_line
			(start -0.12065 -0.3048)
			(end -0.67945 -0.3048)
			(stroke
				(width 0.1)
				(type default)
			)
			(layer "B.Fab")
		)
		(fp_line
			(start 0.12065 -0.305054)
			(end 0.12065 -0.2794)
			(stroke
				(width 0.1)
				(type default)
			)
			(layer "B.Fab")
		)
		(fp_line
			(start 0.67945 -0.305054)
			(end 0.12065 -0.305054)
			(stroke
				(width 0.1)
				(type default)
			)
			(layer "B.Fab")
		)
		(pad "1" smd circle
			(at 0.40005 0 90)
			(size 0 0)
			(layers "B.Cu" "B.Mask" "B.Paste")
			(net "PVCCFA_EHV_FIVRA_CPU0_PVCC2")
		)
		(pad "2" smd circle
			(at -0.40005 0 90)
			(size 0 0)
			(layers "B.Cu" "B.Mask" "B.Paste")
			(net "PVCCFA_EHV_FIVRA_CPU0_VDD2")
		)
	)
	(footprint ""
		(layer "B.Cu")
		(at 215.840818 -315.334904 -90)
		(property "Reference" "R947"
			(at 0 0 90)
			(layer "B.SilkS")
			(hide yes)
			(effects
				(font
					(size 1.27 1.27)
				)
				(justify mirror)
			)
		)
		(property "Value" ""
			(at 0 0 90)
			(layer "B.Fab")
			(effects
				(font
					(size 1.27 1.27)
				)
				(justify mirror)
			)
		)
		(duplicate_pad_numbers_are_jumpers no)
		(fp_line
			(start -0.7874 0.4064)
			(end 0.7874 0.4064)
			(stroke
				(width 0.1524)
				(type default)
			)
			(layer "B.SilkS")
		)
		(fp_line
			(start 0.7874 0.4064)
			(end 0.7874 -0.4064)
			(stroke
				(width 0.1524)
				(type default)
			)
			(layer "B.SilkS")
		)
		(fp_line
			(start -0.7874 -0.4064)
			(end -0.7874 0.4064)
			(stroke
				(width 0.1524)
				(type default)
			)
			(layer "B.SilkS")
		)
		(fp_line
			(start 0.7874 -0.4064)
			(end -0.7874 -0.4064)
			(stroke
				(width 0.1524)
				(type default)
			)
			(layer "B.SilkS")
		)
		(fp_line
			(start -0.67945 0.3048)
			(end -0.120396 0.3048)
			(stroke
				(width 0.1)
				(type default)
			)
			(layer "B.Fab")
		)
		(fp_line
			(start -0.120396 0.3048)
			(end -0.120396 0.2794)
			(stroke
				(width 0.1)
				(type default)
			)
			(layer "B.Fab")
		)
		(fp_line
			(start 0.12065 0.3048)
			(end 0.67945 0.3048)
			(stroke
				(width 0.1)
				(type default)
			)
			(layer "B.Fab")
		)
		(fp_line
			(start 0.67945 0.3048)
			(end 0.67945 -0.305054)
			(stroke
				(width 0.1)
				(type default)
			)
			(layer "B.Fab")
		)
		(fp_line
			(start -0.120396 0.2794)
			(end 0.12065 0.2794)
			(stroke
				(width 0.1)
				(type default)
			)
			(layer "B.Fab")
		)
		(fp_line
			(start 0.12065 0.2794)
			(end 0.12065 0.3048)
			(stroke
				(width 0.1)
				(type default)
			)
			(layer "B.Fab")
		)
		(fp_line
			(start -0.12065 -0.2794)
			(end -0.12065 -0.3048)
			(stroke
				(width 0.1)
				(type default)
			)
			(layer "B.Fab")
		)
		(fp_line
			(start 0.12065 -0.2794)
			(end -0.12065 -0.2794)
			(stroke
				(width 0.1)
				(type default)
			)
			(layer "B.Fab")
		)
		(fp_line
			(start -0.67945 -0.3048)
			(end -0.67945 0.3048)
			(stroke
				(width 0.1)
				(type default)
			)
			(layer "B.Fab")
		)
		(fp_line
			(start -0.12065 -0.3048)
			(end -0.67945 -0.3048)
			(stroke
				(width 0.1)
				(type default)
			)
			(layer "B.Fab")
		)
		(fp_line
			(start 0.12065 -0.305054)
			(end 0.12065 -0.2794)
			(stroke
				(width 0.1)
				(type default)
			)
			(layer "B.Fab")
		)
		(fp_line
			(start 0.67945 -0.305054)
			(end 0.12065 -0.305054)
			(stroke
				(width 0.1)
				(type default)
			)
			(layer "B.Fab")
		)
		(pad "1" smd circle
			(at 0.40005 0 90)
			(size 0 0)
			(layers "B.Cu" "B.Mask" "B.Paste")
			(net "P3V3_AUX")
		)
		(pad "2" smd circle
			(at -0.40005 0 90)
			(size 0 0)
			(layers "B.Cu" "B.Mask" "B.Paste")
			(net "PWRGD_FAIL_CPU1_GH_R1")
		)
	)
	(footprint ""
		(layer "B.Cu")
		(at 105.726738 -241.19459 90)
		(property "Reference" "C483"
			(at 0 0 90)
			(layer "B.SilkS")
			(hide yes)
			(effects
				(font
					(size 1.27 1.27)
				)
				(justify mirror)
			)
		)
		(property "Value" ""
			(at 0 0 90)
			(layer "B.Fab")
			(effects
				(font
					(size 1.27 1.27)
				)
				(justify mirror)
			)
		)
		(duplicate_pad_numbers_are_jumpers no)
		(fp_line
			(start 1.524 -0.762)
			(end -1.524 -0.762)
			(stroke
				(width 0.1524)
				(type default)
			)
			(layer "B.SilkS")
		)
		(fp_line
			(start -1.524 -0.762)
			(end -1.524 0.762)
			(stroke
				(width 0.1524)
				(type default)
			)
			(layer "B.SilkS")
		)
		(fp_line
			(start 1.524 0.762)
			(end 1.524 -0.762)
			(stroke
				(width 0.1524)
				(type default)
			)
			(layer "B.SilkS")
		)
		(fp_line
			(start -1.524 0.762)
			(end 1.524 0.762)
			(stroke
				(width 0.1524)
				(type default)
			)
			(layer "B.SilkS")
		)
		(fp_line
			(start 1.1049 -0.724916)
			(end 1.1049 0.724916)
			(stroke
				(width 0.1)
				(type default)
			)
			(layer "B.Fab")
		)
		(fp_line
			(start -1.1049 -0.724916)
			(end 1.1049 -0.724916)
			(stroke
				(width 0.1)
				(type default)
			)
			(layer "B.Fab")
		)
		(fp_line
			(start 1.1049 0.724916)
			(end -1.1049 0.724916)
			(stroke
				(width 0.1)
				(type default)
			)
			(layer "B.Fab")
		)
		(fp_line
			(start -1.1049 0.724916)
			(end -1.1049 -0.724916)
			(stroke
				(width 0.1)
				(type default)
			)
			(layer "B.Fab")
		)
		(pad "1" smd rect
			(at 0.889 0 90)
			(size 1.016 1.27)
			(layers "B.Cu" "B.Mask" "B.Paste")
			(net "PVCCIN_CPU1")
		)
		(pad "2" smd rect
			(at -0.889 0 90)
			(size 1.016 1.27)
			(layers "B.Cu" "B.Mask" "B.Paste")
			(net "GND")
		)
	)
	(footprint ""
		(layer "B.Cu")
		(at 111.82858 -411.676088 -90)
		(property "Reference" "C2339"
			(at 0 0 90)
			(layer "B.SilkS")
			(hide yes)
			(effects
				(font
					(size 1.27 1.27)
				)
				(justify mirror)
			)
		)
		(property "Value" ""
			(at 0 0 90)
			(layer "B.Fab")
			(effects
				(font
					(size 1.27 1.27)
				)
				(justify mirror)
			)
		)
		(duplicate_pad_numbers_are_jumpers no)
		(fp_line
			(start -0.7874 0.4064)
			(end 0.7874 0.4064)
			(stroke
				(width 0.1524)
				(type default)
			)
			(layer "B.SilkS")
		)
		(fp_line
			(start 0.7874 0.4064)
			(end 0.7874 -0.4064)
			(stroke
				(width 0.1524)
				(type default)
			)
			(layer "B.SilkS")
		)
		(fp_line
			(start -0.7874 -0.4064)
			(end -0.7874 0.4064)
			(stroke
				(width 0.1524)
				(type default)
			)
			(layer "B.SilkS")
		)
		(fp_line
			(start 0.7874 -0.4064)
			(end -0.7874 -0.4064)
			(stroke
				(width 0.1524)
				(type default)
			)
			(layer "B.SilkS")
		)
		(fp_line
			(start -0.67945 0.3048)
			(end -0.120396 0.3048)
			(stroke
				(width 0.1)
				(type default)
			)
			(layer "B.Fab")
		)
		(fp_line
			(start -0.120396 0.3048)
			(end -0.120396 0.2794)
			(stroke
				(width 0.1)
				(type default)
			)
			(layer "B.Fab")
		)
		(fp_line
			(start 0.12065 0.3048)
			(end 0.67945 0.3048)
			(stroke
				(width 0.1)
				(type default)
			)
			(layer "B.Fab")
		)
		(fp_line
			(start 0.67945 0.3048)
			(end 0.67945 -0.305054)
			(stroke
				(width 0.1)
				(type default)
			)
			(layer "B.Fab")
		)
		(fp_line
			(start -0.120396 0.2794)
			(end 0.12065 0.2794)
			(stroke
				(width 0.1)
				(type default)
			)
			(layer "B.Fab")
		)
		(fp_line
			(start 0.12065 0.2794)
			(end 0.12065 0.3048)
			(stroke
				(width 0.1)
				(type default)
			)
			(layer "B.Fab")
		)
		(fp_line
			(start -0.12065 -0.2794)
			(end -0.12065 -0.3048)
			(stroke
				(width 0.1)
				(type default)
			)
			(layer "B.Fab")
		)
		(fp_line
			(start 0.12065 -0.2794)
			(end -0.12065 -0.2794)
			(stroke
				(width 0.1)
				(type default)
			)
			(layer "B.Fab")
		)
		(fp_line
			(start -0.67945 -0.3048)
			(end -0.67945 0.3048)
			(stroke
				(width 0.1)
				(type default)
			)
			(layer "B.Fab")
		)
		(fp_line
			(start -0.12065 -0.3048)
			(end -0.67945 -0.3048)
			(stroke
				(width 0.1)
				(type default)
			)
			(layer "B.Fab")
		)
		(fp_line
			(start 0.12065 -0.305054)
			(end 0.12065 -0.2794)
			(stroke
				(width 0.1)
				(type default)
			)
			(layer "B.Fab")
		)
		(fp_line
			(start 0.67945 -0.305054)
			(end 0.12065 -0.305054)
			(stroke
				(width 0.1)
				(type default)
			)
			(layer "B.Fab")
		)
		(pad "1" smd circle
			(at 0.40005 0 90)
			(size 0 0)
			(layers "B.Cu" "B.Mask" "B.Paste")
			(net "P3V3_9ZXL045_VDD")
		)
		(pad "2" smd circle
			(at -0.40005 0 90)
			(size 0 0)
			(layers "B.Cu" "B.Mask" "B.Paste")
			(net "GND")
		)
	)
	(footprint ""
		(layer "B.Cu")
		(at 179.352448 -403.271482)
		(property "Reference" "PC2191"
			(at 0 0 0)
			(layer "B.SilkS")
			(hide yes)
			(effects
				(font
					(size 1.27 1.27)
				)
				(justify mirror)
			)
		)
		(property "Value" ""
			(at 0 0 0)
			(layer "B.Fab")
			(effects
				(font
					(size 1.27 1.27)
				)
				(justify mirror)
			)
		)
		(duplicate_pad_numbers_are_jumpers no)
		(fp_line
			(start -0.7874 -0.4064)
			(end -0.7874 0.4064)
			(stroke
				(width 0.1524)
				(type default)
			)
			(layer "B.SilkS")
		)
		(fp_line
			(start -0.7874 0.4064)
			(end 0.7874 0.4064)
			(stroke
				(width 0.1524)
				(type default)
			)
			(layer "B.SilkS")
		)
		(fp_line
			(start 0.7874 -0.4064)
			(end -0.7874 -0.4064)
			(stroke
				(width 0.1524)
				(type default)
			)
			(layer "B.SilkS")
		)
		(fp_line
			(start 0.7874 0.4064)
			(end 0.7874 -0.4064)
			(stroke
				(width 0.1524)
				(type default)
			)
			(layer "B.SilkS")
		)
		(fp_line
			(start -0.67945 -0.3048)
			(end -0.67945 0.3048)
			(stroke
				(width 0.1)
				(type default)
			)
			(layer "B.Fab")
		)
		(fp_line
			(start -0.67945 0.3048)
			(end -0.120396 0.3048)
			(stroke
				(width 0.1)
				(type default)
			)
			(layer "B.Fab")
		)
		(fp_line
			(start -0.12065 -0.3048)
			(end -0.67945 -0.3048)
			(stroke
				(width 0.1)
				(type default)
			)
			(layer "B.Fab")
		)
		(fp_line
			(start -0.12065 -0.2794)
			(end -0.12065 -0.3048)
			(stroke
				(width 0.1)
				(type default)
			)
			(layer "B.Fab")
		)
		(fp_line
			(start -0.120396 0.2794)
			(end 0.12065 0.2794)
			(stroke
				(width 0.1)
				(type default)
			)
			(layer "B.Fab")
		)
		(fp_line
			(start -0.120396 0.3048)
			(end -0.120396 0.2794)
			(stroke
				(width 0.1)
				(type default)
			)
			(layer "B.Fab")
		)
		(fp_line
			(start 0.12065 -0.305054)
			(end 0.12065 -0.2794)
			(stroke
				(width 0.1)
				(type default)
			)
			(layer "B.Fab")
		)
		(fp_line
			(start 0.12065 -0.2794)
			(end -0.12065 -0.2794)
			(stroke
				(width 0.1)
				(type default)
			)
			(layer "B.Fab")
		)
		(fp_line
			(start 0.12065 0.2794)
			(end 0.12065 0.3048)
			(stroke
				(width 0.1)
				(type default)
			)
			(layer "B.Fab")
		)
		(fp_line
			(start 0.12065 0.3048)
			(end 0.67945 0.3048)
			(stroke
				(width 0.1)
				(type default)
			)
			(layer "B.Fab")
		)
		(fp_line
			(start 0.67945 -0.305054)
			(end 0.12065 -0.305054)
			(stroke
				(width 0.1)
				(type default)
			)
			(layer "B.Fab")
		)
		(fp_line
			(start 0.67945 0.3048)
			(end 0.67945 -0.305054)
			(stroke
				(width 0.1)
				(type default)
			)
			(layer "B.Fab")
		)
		(pad "1" smd circle
			(at 0.40005 0 180)
			(size 0 0)
			(layers "B.Cu" "B.Mask" "B.Paste")
			(net "HSC_SS")
		)
		(pad "2" smd circle
			(at -0.40005 0 180)
			(size 0 0)
			(layers "B.Cu" "B.Mask" "B.Paste")
			(net "AGND_HSC")
		)
	)
	(footprint ""
		(layer "B.Cu")
		(at 400.686778 -190.77559 90)
		(property "Reference" "R181"
			(at 0 0 90)
			(layer "B.SilkS")
			(hide yes)
			(effects
				(font
					(size 1.27 1.27)
				)
				(justify mirror)
			)
		)
		(property "Value" ""
			(at 0 0 90)
			(layer "B.Fab")
			(effects
				(font
					(size 1.27 1.27)
				)
				(justify mirror)
			)
		)
		(duplicate_pad_numbers_are_jumpers no)
		(fp_line
			(start 0.7874 -0.4064)
			(end -0.7874 -0.4064)
			(stroke
				(width 0.1524)
				(type default)
			)
			(layer "B.SilkS")
		)
		(fp_line
			(start -0.7874 -0.4064)
			(end -0.7874 0.4064)
			(stroke
				(width 0.1524)
				(type default)
			)
			(layer "B.SilkS")
		)
		(fp_line
			(start 0.7874 0.4064)
			(end 0.7874 -0.4064)
			(stroke
				(width 0.1524)
				(type default)
			)
			(layer "B.SilkS")
		)
		(fp_line
			(start -0.7874 0.4064)
			(end 0.7874 0.4064)
			(stroke
				(width 0.1524)
				(type default)
			)
			(layer "B.SilkS")
		)
		(fp_line
			(start 0.67945 -0.305054)
			(end 0.12065 -0.305054)
			(stroke
				(width 0.1)
				(type default)
			)
			(layer "B.Fab")
		)
		(fp_line
			(start 0.12065 -0.305054)
			(end 0.12065 -0.2794)
			(stroke
				(width 0.1)
				(type default)
			)
			(layer "B.Fab")
		)
		(fp_line
			(start -0.12065 -0.3048)
			(end -0.67945 -0.3048)
			(stroke
				(width 0.1)
				(type default)
			)
			(layer "B.Fab")
		)
		(fp_line
			(start -0.67945 -0.3048)
			(end -0.67945 0.3048)
			(stroke
				(width 0.1)
				(type default)
			)
			(layer "B.Fab")
		)
		(fp_line
			(start 0.12065 -0.2794)
			(end -0.12065 -0.2794)
			(stroke
				(width 0.1)
				(type default)
			)
			(layer "B.Fab")
		)
		(fp_line
			(start -0.12065 -0.2794)
			(end -0.12065 -0.3048)
			(stroke
				(width 0.1)
				(type default)
			)
			(layer "B.Fab")
		)
		(fp_line
			(start 0.12065 0.2794)
			(end 0.12065 0.3048)
			(stroke
				(width 0.1)
				(type default)
			)
			(layer "B.Fab")
		)
		(fp_line
			(start -0.120396 0.2794)
			(end 0.12065 0.2794)
			(stroke
				(width 0.1)
				(type default)
			)
			(layer "B.Fab")
		)
		(fp_line
			(start 0.67945 0.3048)
			(end 0.67945 -0.305054)
			(stroke
				(width 0.1)
				(type default)
			)
			(layer "B.Fab")
		)
		(fp_line
			(start 0.12065 0.3048)
			(end 0.67945 0.3048)
			(stroke
				(width 0.1)
				(type default)
			)
			(layer "B.Fab")
		)
		(fp_line
			(start -0.120396 0.3048)
			(end -0.120396 0.2794)
			(stroke
				(width 0.1)
				(type default)
			)
			(layer "B.Fab")
		)
		(fp_line
			(start -0.67945 0.3048)
			(end -0.120396 0.3048)
			(stroke
				(width 0.1)
				(type default)
			)
			(layer "B.Fab")
		)
		(pad "1" smd circle
			(at 0.40005 0 270)
			(size 0 0)
			(layers "B.Cu" "B.Mask" "B.Paste")
			(net "PWRGD_DRAMPWRGD_CPU0_GH_LVC1_R2")
		)
		(pad "2" smd circle
			(at -0.40005 0 270)
			(size 0 0)
			(layers "B.Cu" "B.Mask" "B.Paste")
			(net "PVCCD_HV_CPU0")
		)
	)
	(footprint ""
		(layer "B.Cu")
		(at 327.15708 -68.339208 90)
		(property "Reference" "L2"
			(at 0 0 90)
			(layer "B.SilkS")
			(hide yes)
			(effects
				(font
					(size 1.27 1.27)
				)
				(justify mirror)
			)
		)
		(property "Value" ""
			(at 0 0 90)
			(layer "B.Fab")
			(effects
				(font
					(size 1.27 1.27)
				)
				(justify mirror)
			)
		)
		(duplicate_pad_numbers_are_jumpers no)
		(fp_line
			(start 0.762 -0.381)
			(end -0.762 -0.381)
			(stroke
				(width 0.1524)
				(type default)
			)
			(layer "B.SilkS")
		)
		(fp_line
			(start -0.762 -0.381)
			(end -0.762 0.381)
			(stroke
				(width 0.1524)
				(type default)
			)
			(layer "B.SilkS")
		)
		(fp_line
			(start 0.762 0.381)
			(end 0.762 -0.381)
			(stroke
				(width 0.1524)
				(type default)
			)
			(layer "B.SilkS")
		)
		(fp_line
			(start -0.762 0.381)
			(end 0.762 0.381)
			(stroke
				(width 0.1524)
				(type default)
			)
			(layer "B.SilkS")
		)
		(fp_line
			(start 0.681736 -0.307086)
			(end 0.118364 -0.307086)
			(stroke
				(width 0.1)
				(type default)
			)
			(layer "B.Fab")
		)
		(fp_line
			(start 0.118364 -0.307086)
			(end 0.118364 -0.2794)
			(stroke
				(width 0.1)
				(type default)
			)
			(layer "B.Fab")
		)
		(fp_line
			(start -0.118872 -0.306324)
			(end -0.680466 -0.306324)
			(stroke
				(width 0.1)
				(type default)
			)
			(layer "B.Fab")
		)
		(fp_line
			(start -0.680466 -0.306324)
			(end -0.680466 0.306324)
			(stroke
				(width 0.1)
				(type default)
			)
			(layer "B.Fab")
		)
		(fp_line
			(start 0.118364 -0.2794)
			(end -0.118872 -0.2794)
			(stroke
				(width 0.1)
				(type default)
			)
			(layer "B.Fab")
		)
		(fp_line
			(start -0.118872 -0.2794)
			(end -0.118872 -0.306324)
			(stroke
				(width 0.1)
				(type default)
			)
			(layer "B.Fab")
		)
		(fp_line
			(start 0.119634 0.2794)
			(end 0.119634 0.30607)
			(stroke
				(width 0.1)
				(type default)
			)
			(layer "B.Fab")
		)
		(fp_line
			(start -0.118364 0.2794)
			(end 0.119634 0.2794)
			(stroke
				(width 0.1)
				(type default)
			)
			(layer "B.Fab")
		)
		(fp_line
			(start 0.681736 0.30607)
			(end 0.681736 -0.307086)
			(stroke
				(width 0.1)
				(type default)
			)
			(layer "B.Fab")
		)
		(fp_line
			(start 0.119634 0.30607)
			(end 0.681736 0.30607)
			(stroke
				(width 0.1)
				(type default)
			)
			(layer "B.Fab")
		)
		(fp_line
			(start -0.118364 0.306324)
			(end -0.118364 0.2794)
			(stroke
				(width 0.1)
				(type default)
			)
			(layer "B.Fab")
		)
		(fp_line
			(start -0.680466 0.306324)
			(end -0.118364 0.306324)
			(stroke
				(width 0.1)
				(type default)
			)
			(layer "B.Fab")
		)
		(pad "1" smd rect
			(at 0.40005 0 90)
			(size 0.4572 0.508)
			(layers "B.Cu" "B.Mask" "B.Paste")
			(net "P1V05_PCH_AUX")
		)
		(pad "2" smd rect
			(at -0.40005 0 90)
			(size 0.4572 0.508)
			(layers "B.Cu" "B.Mask" "B.Paste")
			(net "P1V05_PCH_PLL_AUX")
		)
	)
	(footprint ""
		(layer "B.Cu")
		(at 369.49888 -44.160948 180)
		(property "Reference" "R4116"
			(at 0 0 0)
			(layer "B.SilkS")
			(hide yes)
			(effects
				(font
					(size 1.27 1.27)
				)
				(justify mirror)
			)
		)
		(property "Value" ""
			(at 0 0 0)
			(layer "B.Fab")
			(effects
				(font
					(size 1.27 1.27)
				)
				(justify mirror)
			)
		)
		(duplicate_pad_numbers_are_jumpers no)
		(fp_line
			(start 0.7874 0.4064)
			(end 0.7874 -0.4064)
			(stroke
				(width 0.1524)
				(type default)
			)
			(layer "B.SilkS")
		)
		(fp_line
			(start 0.7874 -0.4064)
			(end -0.7874 -0.4064)
			(stroke
				(width 0.1524)
				(type default)
			)
			(layer "B.SilkS")
		)
		(fp_line
			(start -0.7874 0.4064)
			(end 0.7874 0.4064)
			(stroke
				(width 0.1524)
				(type default)
			)
			(layer "B.SilkS")
		)
		(fp_line
			(start -0.7874 -0.4064)
			(end -0.7874 0.4064)
			(stroke
				(width 0.1524)
				(type default)
			)
			(layer "B.SilkS")
		)
		(fp_line
			(start 0.67945 0.3048)
			(end 0.67945 -0.305054)
			(stroke
				(width 0.1)
				(type default)
			)
			(layer "B.Fab")
		)
		(fp_line
			(start 0.67945 -0.305054)
			(end 0.12065 -0.305054)
			(stroke
				(width 0.1)
				(type default)
			)
			(layer "B.Fab")
		)
		(fp_line
			(start 0.12065 0.3048)
			(end 0.67945 0.3048)
			(stroke
				(width 0.1)
				(type default)
			)
			(layer "B.Fab")
		)
		(fp_line
			(start 0.12065 0.2794)
			(end 0.12065 0.3048)
			(stroke
				(width 0.1)
				(type default)
			)
			(layer "B.Fab")
		)
		(fp_line
			(start 0.12065 -0.2794)
			(end -0.12065 -0.2794)
			(stroke
				(width 0.1)
				(type default)
			)
			(layer "B.Fab")
		)
		(fp_line
			(start 0.12065 -0.305054)
			(end 0.12065 -0.2794)
			(stroke
				(width 0.1)
				(type default)
			)
			(layer "B.Fab")
		)
		(fp_line
			(start -0.120396 0.3048)
			(end -0.120396 0.2794)
			(stroke
				(width 0.1)
				(type default)
			)
			(layer "B.Fab")
		)
		(fp_line
			(start -0.120396 0.2794)
			(end 0.12065 0.2794)
			(stroke
				(width 0.1)
				(type default)
			)
			(layer "B.Fab")
		)
		(fp_line
			(start -0.12065 -0.2794)
			(end -0.12065 -0.3048)
			(stroke
				(width 0.1)
				(type default)
			)
			(layer "B.Fab")
		)
		(fp_line
			(start -0.12065 -0.3048)
			(end -0.67945 -0.3048)
			(stroke
				(width 0.1)
				(type default)
			)
			(layer "B.Fab")
		)
		(fp_line
			(start -0.67945 0.3048)
			(end -0.120396 0.3048)
			(stroke
				(width 0.1)
				(type default)
			)
			(layer "B.Fab")
		)
		(fp_line
			(start -0.67945 -0.3048)
			(end -0.67945 0.3048)
			(stroke
				(width 0.1)
				(type default)
			)
			(layer "B.Fab")
		)
		(pad "1" smd circle
			(at 0.40005 0)
			(size 0 0)
			(layers "B.Cu" "B.Mask" "B.Paste")
			(net "PD_PCH_GPP_E_8")
		)
		(pad "2" smd circle
			(at -0.40005 0)
			(size 0 0)
			(layers "B.Cu" "B.Mask" "B.Paste")
			(net "GND")
		)
	)
	(footprint ""
		(layer "B.Cu")
		(at 286.268414 -319.263776 180)
		(property "Reference" "C8"
			(at 0 0 0)
			(layer "B.SilkS")
			(hide yes)
			(effects
				(font
					(size 1.27 1.27)
				)
				(justify mirror)
			)
		)
		(property "Value" ""
			(at 0 0 0)
			(layer "B.Fab")
			(effects
				(font
					(size 1.27 1.27)
				)
				(justify mirror)
			)
		)
		(duplicate_pad_numbers_are_jumpers no)
		(fp_line
			(start 0.7874 0.4064)
			(end 0.7874 -0.4064)
			(stroke
				(width 0.1524)
				(type default)
			)
			(layer "B.SilkS")
		)
		(fp_line
			(start 0.7874 -0.4064)
			(end -0.7874 -0.4064)
			(stroke
				(width 0.1524)
				(type default)
			)
			(layer "B.SilkS")
		)
		(fp_line
			(start -0.7874 0.4064)
			(end 0.7874 0.4064)
			(stroke
				(width 0.1524)
				(type default)
			)
			(layer "B.SilkS")
		)
		(fp_line
			(start -0.7874 -0.4064)
			(end -0.7874 0.4064)
			(stroke
				(width 0.1524)
				(type default)
			)
			(layer "B.SilkS")
		)
		(fp_line
			(start 0.67945 0.3048)
			(end 0.67945 -0.305054)
			(stroke
				(width 0.1)
				(type default)
			)
			(layer "B.Fab")
		)
		(fp_line
			(start 0.67945 -0.305054)
			(end 0.12065 -0.305054)
			(stroke
				(width 0.1)
				(type default)
			)
			(layer "B.Fab")
		)
		(fp_line
			(start 0.12065 0.3048)
			(end 0.67945 0.3048)
			(stroke
				(width 0.1)
				(type default)
			)
			(layer "B.Fab")
		)
		(fp_line
			(start 0.12065 0.2794)
			(end 0.12065 0.3048)
			(stroke
				(width 0.1)
				(type default)
			)
			(layer "B.Fab")
		)
		(fp_line
			(start 0.12065 -0.2794)
			(end -0.12065 -0.2794)
			(stroke
				(width 0.1)
				(type default)
			)
			(layer "B.Fab")
		)
		(fp_line
			(start 0.12065 -0.305054)
			(end 0.12065 -0.2794)
			(stroke
				(width 0.1)
				(type default)
			)
			(layer "B.Fab")
		)
		(fp_line
			(start -0.120396 0.3048)
			(end -0.120396 0.2794)
			(stroke
				(width 0.1)
				(type default)
			)
			(layer "B.Fab")
		)
		(fp_line
			(start -0.120396 0.2794)
			(end 0.12065 0.2794)
			(stroke
				(width 0.1)
				(type default)
			)
			(layer "B.Fab")
		)
		(fp_line
			(start -0.12065 -0.2794)
			(end -0.12065 -0.3048)
			(stroke
				(width 0.1)
				(type default)
			)
			(layer "B.Fab")
		)
		(fp_line
			(start -0.12065 -0.3048)
			(end -0.67945 -0.3048)
			(stroke
				(width 0.1)
				(type default)
			)
			(layer "B.Fab")
		)
		(fp_line
			(start -0.67945 0.3048)
			(end -0.120396 0.3048)
			(stroke
				(width 0.1)
				(type default)
			)
			(layer "B.Fab")
		)
		(fp_line
			(start -0.67945 -0.3048)
			(end -0.67945 0.3048)
			(stroke
				(width 0.1)
				(type default)
			)
			(layer "B.Fab")
		)
		(pad "1" smd circle
			(at 0.40005 0)
			(size 0 0)
			(layers "B.Cu" "B.Mask" "B.Paste")
			(net "P3V3_AUX")
		)
		(pad "2" smd circle
			(at -0.40005 0)
			(size 0 0)
			(layers "B.Cu" "B.Mask" "B.Paste")
			(net "GND")
		)
	)
	(footprint ""
		(layer "B.Cu")
		(at 193.38036 -120.614948)
		(property "Reference" "R1205"
			(at 0 0 0)
			(layer "B.SilkS")
			(hide yes)
			(effects
				(font
					(size 1.27 1.27)
				)
				(justify mirror)
			)
		)
		(property "Value" ""
			(at 0 0 0)
			(layer "B.Fab")
			(effects
				(font
					(size 1.27 1.27)
				)
				(justify mirror)
			)
		)
		(duplicate_pad_numbers_are_jumpers no)
		(fp_line
			(start -0.7874 -0.4064)
			(end -0.7874 0.4064)
			(stroke
				(width 0.1524)
				(type default)
			)
			(layer "B.SilkS")
		)
		(fp_line
			(start -0.7874 0.4064)
			(end 0.7874 0.4064)
			(stroke
				(width 0.1524)
				(type default)
			)
			(layer "B.SilkS")
		)
		(fp_line
			(start 0.7874 -0.4064)
			(end -0.7874 -0.4064)
			(stroke
				(width 0.1524)
				(type default)
			)
			(layer "B.SilkS")
		)
		(fp_line
			(start 0.7874 0.4064)
			(end 0.7874 -0.4064)
			(stroke
				(width 0.1524)
				(type default)
			)
			(layer "B.SilkS")
		)
		(fp_line
			(start -0.67945 -0.3048)
			(end -0.67945 0.3048)
			(stroke
				(width 0.1)
				(type default)
			)
			(layer "B.Fab")
		)
		(fp_line
			(start -0.67945 0.3048)
			(end -0.120396 0.3048)
			(stroke
				(width 0.1)
				(type default)
			)
			(layer "B.Fab")
		)
		(fp_line
			(start -0.12065 -0.3048)
			(end -0.67945 -0.3048)
			(stroke
				(width 0.1)
				(type default)
			)
			(layer "B.Fab")
		)
		(fp_line
			(start -0.12065 -0.2794)
			(end -0.12065 -0.3048)
			(stroke
				(width 0.1)
				(type default)
			)
			(layer "B.Fab")
		)
		(fp_line
			(start -0.120396 0.2794)
			(end 0.12065 0.2794)
			(stroke
				(width 0.1)
				(type default)
			)
			(layer "B.Fab")
		)
		(fp_line
			(start -0.120396 0.3048)
			(end -0.120396 0.2794)
			(stroke
				(width 0.1)
				(type default)
			)
			(layer "B.Fab")
		)
		(fp_line
			(start 0.12065 -0.305054)
			(end 0.12065 -0.2794)
			(stroke
				(width 0.1)
				(type default)
			)
			(layer "B.Fab")
		)
		(fp_line
			(start 0.12065 -0.2794)
			(end -0.12065 -0.2794)
			(stroke
				(width 0.1)
				(type default)
			)
			(layer "B.Fab")
		)
		(fp_line
			(start 0.12065 0.2794)
			(end 0.12065 0.3048)
			(stroke
				(width 0.1)
				(type default)
			)
			(layer "B.Fab")
		)
		(fp_line
			(start 0.12065 0.3048)
			(end 0.67945 0.3048)
			(stroke
				(width 0.1)
				(type default)
			)
			(layer "B.Fab")
		)
		(fp_line
			(start 0.67945 -0.305054)
			(end 0.12065 -0.305054)
			(stroke
				(width 0.1)
				(type default)
			)
			(layer "B.Fab")
		)
		(fp_line
			(start 0.67945 0.3048)
			(end 0.67945 -0.305054)
			(stroke
				(width 0.1)
				(type default)
			)
			(layer "B.Fab")
		)
		(pad "1" smd circle
			(at 0.40005 0 180)
			(size 0 0)
			(layers "B.Cu" "B.Mask" "B.Paste")
			(net "RST_PLTRST_N")
		)
		(pad "2" smd circle
			(at -0.40005 0 180)
			(size 0 0)
			(layers "B.Cu" "B.Mask" "B.Paste")
			(net "RST_PLTRST_PLD_N")
		)
	)
	(footprint ""
		(layer "B.Cu")
		(at 353.924108 -237.709202 -90)
		(property "Reference" "C1405"
			(at 0 0 90)
			(layer "B.SilkS")
			(hide yes)
			(effects
				(font
					(size 1.27 1.27)
				)
				(justify mirror)
			)
		)
		(property "Value" ""
			(at 0 0 90)
			(layer "B.Fab")
			(effects
				(font
					(size 1.27 1.27)
				)
				(justify mirror)
			)
		)
		(duplicate_pad_numbers_are_jumpers no)
		(fp_line
			(start -1.2954 0.5842)
			(end 1.2954 0.5842)
			(stroke
				(width 0.1524)
				(type default)
			)
			(layer "B.SilkS")
		)
		(fp_line
			(start 1.2954 0.5842)
			(end 1.2954 -0.5842)
			(stroke
				(width 0.1524)
				(type default)
			)
			(layer "B.SilkS")
		)
		(fp_line
			(start -1.2954 -0.5842)
			(end -1.2954 0.5842)
			(stroke
				(width 0.1524)
				(type default)
			)
			(layer "B.SilkS")
		)
		(fp_line
			(start 0 -0.5842)
			(end 0 0.5842)
			(stroke
				(width 0.1524)
				(type default)
			)
			(layer "B.SilkS")
		)
		(fp_line
			(start 1.2954 -0.5842)
			(end -1.2954 -0.5842)
			(stroke
				(width 0.1524)
				(type default)
			)
			(layer "B.SilkS")
		)
		(fp_line
			(start -0.8636 0.4572)
			(end 0.8636 0.4572)
			(stroke
				(width 0.1)
				(type default)
			)
			(layer "B.Fab")
		)
		(fp_line
			(start 0.8636 0.4572)
			(end 0.8636 0.4064)
			(stroke
				(width 0.1)
				(type default)
			)
			(layer "B.Fab")
		)
		(fp_line
			(start -1.1938 0.4064)
			(end -0.8636 0.4064)
			(stroke
				(width 0.1)
				(type default)
			)
			(layer "B.Fab")
		)
		(fp_line
			(start -0.8636 0.4064)
			(end -0.8636 0.4572)
			(stroke
				(width 0.1)
				(type default)
			)
			(layer "B.Fab")
		)
		(fp_line
			(start 0.8636 0.4064)
			(end 1.1938 0.4064)
			(stroke
				(width 0.1)
				(type default)
			)
			(layer "B.Fab")
		)
		(fp_line
			(start 1.1938 0.4064)
			(end 1.1938 -0.4064)
			(stroke
				(width 0.1)
				(type default)
			)
			(layer "B.Fab")
		)
		(fp_line
			(start -1.1938 -0.4064)
			(end -1.1938 0.4064)
			(stroke
				(width 0.1)
				(type default)
			)
			(layer "B.Fab")
		)
		(fp_line
			(start -0.8636 -0.4064)
			(end -1.1938 -0.4064)
			(stroke
				(width 0.1)
				(type default)
			)
			(layer "B.Fab")
		)
		(fp_line
			(start 0.8636 -0.4064)
			(end 0.8636 -0.4572)
			(stroke
				(width 0.1)
				(type default)
			)
			(layer "B.Fab")
		)
		(fp_line
			(start 1.1938 -0.4064)
			(end 0.8636 -0.4064)
			(stroke
				(width 0.1)
				(type default)
			)
			(layer "B.Fab")
		)
		(fp_line
			(start -0.8636 -0.4572)
			(end -0.8636 -0.4064)
			(stroke
				(width 0.1)
				(type default)
			)
			(layer "B.Fab")
		)
		(fp_line
			(start 0.8636 -0.4572)
			(end -0.8636 -0.4572)
			(stroke
				(width 0.1)
				(type default)
			)
			(layer "B.Fab")
		)
		(pad "1" smd rect
			(at 0.7366 0 180)
			(size 0.7112 0.8128)
			(layers "B.Cu" "B.Mask" "B.Paste")
			(net "PVNN_MAIN_CPU0")
		)
		(pad "2" smd rect
			(at -0.7366 0 180)
			(size 0.7112 0.8128)
			(layers "B.Cu" "B.Mask" "B.Paste")
			(net "GND")
		)
	)
	(footprint ""
		(layer "B.Cu")
		(at 160.83788 -116.296948)
		(property "Reference" "R4267"
			(at 0 0 0)
			(layer "B.SilkS")
			(hide yes)
			(effects
				(font
					(size 1.27 1.27)
				)
				(justify mirror)
			)
		)
		(property "Value" ""
			(at 0 0 0)
			(layer "B.Fab")
			(effects
				(font
					(size 1.27 1.27)
				)
				(justify mirror)
			)
		)
		(duplicate_pad_numbers_are_jumpers no)
		(fp_line
			(start -0.7874 -0.4064)
			(end -0.7874 0.4064)
			(stroke
				(width 0.1524)
				(type default)
			)
			(layer "B.SilkS")
		)
		(fp_line
			(start -0.7874 0.4064)
			(end 0.7874 0.4064)
			(stroke
				(width 0.1524)
				(type default)
			)
			(layer "B.SilkS")
		)
		(fp_line
			(start 0.7874 -0.4064)
			(end -0.7874 -0.4064)
			(stroke
				(width 0.1524)
				(type default)
			)
			(layer "B.SilkS")
		)
		(fp_line
			(start 0.7874 0.4064)
			(end 0.7874 -0.4064)
			(stroke
				(width 0.1524)
				(type default)
			)
			(layer "B.SilkS")
		)
		(fp_line
			(start -0.67945 -0.3048)
			(end -0.67945 0.3048)
			(stroke
				(width 0.1)
				(type default)
			)
			(layer "B.Fab")
		)
		(fp_line
			(start -0.67945 0.3048)
			(end -0.120396 0.3048)
			(stroke
				(width 0.1)
				(type default)
			)
			(layer "B.Fab")
		)
		(fp_line
			(start -0.12065 -0.3048)
			(end -0.67945 -0.3048)
			(stroke
				(width 0.1)
				(type default)
			)
			(layer "B.Fab")
		)
		(fp_line
			(start -0.12065 -0.2794)
			(end -0.12065 -0.3048)
			(stroke
				(width 0.1)
				(type default)
			)
			(layer "B.Fab")
		)
		(fp_line
			(start -0.120396 0.2794)
			(end 0.12065 0.2794)
			(stroke
				(width 0.1)
				(type default)
			)
			(layer "B.Fab")
		)
		(fp_line
			(start -0.120396 0.3048)
			(end -0.120396 0.2794)
			(stroke
				(width 0.1)
				(type default)
			)
			(layer "B.Fab")
		)
		(fp_line
			(start 0.12065 -0.305054)
			(end 0.12065 -0.2794)
			(stroke
				(width 0.1)
				(type default)
			)
			(layer "B.Fab")
		)
		(fp_line
			(start 0.12065 -0.2794)
			(end -0.12065 -0.2794)
			(stroke
				(width 0.1)
				(type default)
			)
			(layer "B.Fab")
		)
		(fp_line
			(start 0.12065 0.2794)
			(end 0.12065 0.3048)
			(stroke
				(width 0.1)
				(type default)
			)
			(layer "B.Fab")
		)
		(fp_line
			(start 0.12065 0.3048)
			(end 0.67945 0.3048)
			(stroke
				(width 0.1)
				(type default)
			)
			(layer "B.Fab")
		)
		(fp_line
			(start 0.67945 -0.305054)
			(end 0.12065 -0.305054)
			(stroke
				(width 0.1)
				(type default)
			)
			(layer "B.Fab")
		)
		(fp_line
			(start 0.67945 0.3048)
			(end 0.67945 -0.305054)
			(stroke
				(width 0.1)
				(type default)
			)
			(layer "B.Fab")
		)
		(pad "1" smd circle
			(at 0.40005 0 180)
			(size 0 0)
			(layers "B.Cu" "B.Mask" "B.Paste")
			(net "PWRGD_P3V3_AUX")
		)
		(pad "2" smd circle
			(at -0.40005 0 180)
			(size 0 0)
			(layers "B.Cu" "B.Mask" "B.Paste")
			(net "PWRGD_P3V3_AUX_PDB")
		)
	)
	(footprint ""
		(layer "B.Cu")
		(at 180.367686 -423.631614)
		(property "Reference" "R2800"
			(at 0 0 0)
			(layer "B.SilkS")
			(hide yes)
			(effects
				(font
					(size 1.27 1.27)
				)
				(justify mirror)
			)
		)
		(property "Value" ""
			(at 0 0 0)
			(layer "B.Fab")
			(effects
				(font
					(size 1.27 1.27)
				)
				(justify mirror)
			)
		)
		(duplicate_pad_numbers_are_jumpers no)
		(fp_line
			(start -0.7874 -0.4064)
			(end -0.7874 0.4064)
			(stroke
				(width 0.1524)
				(type default)
			)
			(layer "B.SilkS")
		)
		(fp_line
			(start -0.7874 0.4064)
			(end 0.7874 0.4064)
			(stroke
				(width 0.1524)
				(type default)
			)
			(layer "B.SilkS")
		)
		(fp_line
			(start 0.7874 -0.4064)
			(end -0.7874 -0.4064)
			(stroke
				(width 0.1524)
				(type default)
			)
			(layer "B.SilkS")
		)
		(fp_line
			(start 0.7874 0.4064)
			(end 0.7874 -0.4064)
			(stroke
				(width 0.1524)
				(type default)
			)
			(layer "B.SilkS")
		)
		(fp_line
			(start -0.67945 -0.3048)
			(end -0.67945 0.3048)
			(stroke
				(width 0.1)
				(type default)
			)
			(layer "B.Fab")
		)
		(fp_line
			(start -0.67945 0.3048)
			(end -0.120396 0.3048)
			(stroke
				(width 0.1)
				(type default)
			)
			(layer "B.Fab")
		)
		(fp_line
			(start -0.12065 -0.3048)
			(end -0.67945 -0.3048)
			(stroke
				(width 0.1)
				(type default)
			)
			(layer "B.Fab")
		)
		(fp_line
			(start -0.12065 -0.2794)
			(end -0.12065 -0.3048)
			(stroke
				(width 0.1)
				(type default)
			)
			(layer "B.Fab")
		)
		(fp_line
			(start -0.120396 0.2794)
			(end 0.12065 0.2794)
			(stroke
				(width 0.1)
				(type default)
			)
			(layer "B.Fab")
		)
		(fp_line
			(start -0.120396 0.3048)
			(end -0.120396 0.2794)
			(stroke
				(width 0.1)
				(type default)
			)
			(layer "B.Fab")
		)
		(fp_line
			(start 0.12065 -0.305054)
			(end 0.12065 -0.2794)
			(stroke
				(width 0.1)
				(type default)
			)
			(layer "B.Fab")
		)
		(fp_line
			(start 0.12065 -0.2794)
			(end -0.12065 -0.2794)
			(stroke
				(width 0.1)
				(type default)
			)
			(layer "B.Fab")
		)
		(fp_line
			(start 0.12065 0.2794)
			(end 0.12065 0.3048)
			(stroke
				(width 0.1)
				(type default)
			)
			(layer "B.Fab")
		)
		(fp_line
			(start 0.12065 0.3048)
			(end 0.67945 0.3048)
			(stroke
				(width 0.1)
				(type default)
			)
			(layer "B.Fab")
		)
		(fp_line
			(start 0.67945 -0.305054)
			(end 0.12065 -0.305054)
			(stroke
				(width 0.1)
				(type default)
			)
			(layer "B.Fab")
		)
		(fp_line
			(start 0.67945 0.3048)
			(end 0.67945 -0.305054)
			(stroke
				(width 0.1)
				(type default)
			)
			(layer "B.Fab")
		)
		(pad "1" smd circle
			(at 0.40005 0 180)
			(size 0 0)
			(layers "B.Cu" "B.Mask" "B.Paste")
			(net "SMB_FAN_3V3AUX_R_SCL")
		)
		(pad "2" smd circle
			(at -0.40005 0 180)
			(size 0 0)
			(layers "B.Cu" "B.Mask" "B.Paste")
			(net "SMB_FAN_3V3AUX_BUF_SCL")
		)
	)
	(footprint ""
		(layer "B.Cu")
		(at 305.942238 -194.72021 90)
		(property "Reference" "R13"
			(at 0 0 90)
			(layer "B.SilkS")
			(hide yes)
			(effects
				(font
					(size 1.27 1.27)
				)
				(justify mirror)
			)
		)
		(property "Value" ""
			(at 0 0 90)
			(layer "B.Fab")
			(effects
				(font
					(size 1.27 1.27)
				)
				(justify mirror)
			)
		)
		(duplicate_pad_numbers_are_jumpers no)
		(fp_line
			(start 0.7874 -0.4064)
			(end -0.7874 -0.4064)
			(stroke
				(width 0.1524)
				(type default)
			)
			(layer "B.SilkS")
		)
		(fp_line
			(start -0.7874 -0.4064)
			(end -0.7874 0.4064)
			(stroke
				(width 0.1524)
				(type default)
			)
			(layer "B.SilkS")
		)
		(fp_line
			(start 0.7874 0.4064)
			(end 0.7874 -0.4064)
			(stroke
				(width 0.1524)
				(type default)
			)
			(layer "B.SilkS")
		)
		(fp_line
			(start -0.7874 0.4064)
			(end 0.7874 0.4064)
			(stroke
				(width 0.1524)
				(type default)
			)
			(layer "B.SilkS")
		)
		(fp_line
			(start 0.67945 -0.305054)
			(end 0.12065 -0.305054)
			(stroke
				(width 0.1)
				(type default)
			)
			(layer "B.Fab")
		)
		(fp_line
			(start 0.12065 -0.305054)
			(end 0.12065 -0.2794)
			(stroke
				(width 0.1)
				(type default)
			)
			(layer "B.Fab")
		)
		(fp_line
			(start -0.12065 -0.3048)
			(end -0.67945 -0.3048)
			(stroke
				(width 0.1)
				(type default)
			)
			(layer "B.Fab")
		)
		(fp_line
			(start -0.67945 -0.3048)
			(end -0.67945 0.3048)
			(stroke
				(width 0.1)
				(type default)
			)
			(layer "B.Fab")
		)
		(fp_line
			(start 0.12065 -0.2794)
			(end -0.12065 -0.2794)
			(stroke
				(width 0.1)
				(type default)
			)
			(layer "B.Fab")
		)
		(fp_line
			(start -0.12065 -0.2794)
			(end -0.12065 -0.3048)
			(stroke
				(width 0.1)
				(type default)
			)
			(layer "B.Fab")
		)
		(fp_line
			(start 0.12065 0.2794)
			(end 0.12065 0.3048)
			(stroke
				(width 0.1)
				(type default)
			)
			(layer "B.Fab")
		)
		(fp_line
			(start -0.120396 0.2794)
			(end 0.12065 0.2794)
			(stroke
				(width 0.1)
				(type default)
			)
			(layer "B.Fab")
		)
		(fp_line
			(start 0.67945 0.3048)
			(end 0.67945 -0.305054)
			(stroke
				(width 0.1)
				(type default)
			)
			(layer "B.Fab")
		)
		(fp_line
			(start 0.12065 0.3048)
			(end 0.67945 0.3048)
			(stroke
				(width 0.1)
				(type default)
			)
			(layer "B.Fab")
		)
		(fp_line
			(start -0.120396 0.3048)
			(end -0.120396 0.2794)
			(stroke
				(width 0.1)
				(type default)
			)
			(layer "B.Fab")
		)
		(fp_line
			(start -0.67945 0.3048)
			(end -0.120396 0.3048)
			(stroke
				(width 0.1)
				(type default)
			)
			(layer "B.Fab")
		)
		(pad "1" smd circle
			(at 0.40005 0 270)
			(size 0 0)
			(layers "B.Cu" "B.Mask" "B.Paste")
			(net "SVID_CLK0_CPU0")
		)
		(pad "2" smd circle
			(at -0.40005 0 270)
			(size 0 0)
			(layers "B.Cu" "B.Mask" "B.Paste")
			(net "SVID_CLK0_CPU0_R")
		)
	)
	(footprint ""
		(layer "B.Cu")
		(at 69.353684 -183.303926 90)
		(property "Reference" "R760"
			(at 0 0 90)
			(layer "B.SilkS")
			(hide yes)
			(effects
				(font
					(size 1.27 1.27)
				)
				(justify mirror)
			)
		)
		(property "Value" ""
			(at 0 0 90)
			(layer "B.Fab")
			(effects
				(font
					(size 1.27 1.27)
				)
				(justify mirror)
			)
		)
		(duplicate_pad_numbers_are_jumpers no)
		(fp_line
			(start 0.7874 -0.4064)
			(end -0.7874 -0.4064)
			(stroke
				(width 0.1524)
				(type default)
			)
			(layer "B.SilkS")
		)
		(fp_line
			(start -0.7874 -0.4064)
			(end -0.7874 0.4064)
			(stroke
				(width 0.1524)
				(type default)
			)
			(layer "B.SilkS")
		)
		(fp_line
			(start 0.7874 0.4064)
			(end 0.7874 -0.4064)
			(stroke
				(width 0.1524)
				(type default)
			)
			(layer "B.SilkS")
		)
		(fp_line
			(start -0.7874 0.4064)
			(end 0.7874 0.4064)
			(stroke
				(width 0.1524)
				(type default)
			)
			(layer "B.SilkS")
		)
		(fp_line
			(start 0.67945 -0.305054)
			(end 0.12065 -0.305054)
			(stroke
				(width 0.1)
				(type default)
			)
			(layer "B.Fab")
		)
		(fp_line
			(start 0.12065 -0.305054)
			(end 0.12065 -0.2794)
			(stroke
				(width 0.1)
				(type default)
			)
			(layer "B.Fab")
		)
		(fp_line
			(start -0.12065 -0.3048)
			(end -0.67945 -0.3048)
			(stroke
				(width 0.1)
				(type default)
			)
			(layer "B.Fab")
		)
		(fp_line
			(start -0.67945 -0.3048)
			(end -0.67945 0.3048)
			(stroke
				(width 0.1)
				(type default)
			)
			(layer "B.Fab")
		)
		(fp_line
			(start 0.12065 -0.2794)
			(end -0.12065 -0.2794)
			(stroke
				(width 0.1)
				(type default)
			)
			(layer "B.Fab")
		)
		(fp_line
			(start -0.12065 -0.2794)
			(end -0.12065 -0.3048)
			(stroke
				(width 0.1)
				(type default)
			)
			(layer "B.Fab")
		)
		(fp_line
			(start 0.12065 0.2794)
			(end 0.12065 0.3048)
			(stroke
				(width 0.1)
				(type default)
			)
			(layer "B.Fab")
		)
		(fp_line
			(start -0.120396 0.2794)
			(end 0.12065 0.2794)
			(stroke
				(width 0.1)
				(type default)
			)
			(layer "B.Fab")
		)
		(fp_line
			(start 0.67945 0.3048)
			(end 0.67945 -0.305054)
			(stroke
				(width 0.1)
				(type default)
			)
			(layer "B.Fab")
		)
		(fp_line
			(start 0.12065 0.3048)
			(end 0.67945 0.3048)
			(stroke
				(width 0.1)
				(type default)
			)
			(layer "B.Fab")
		)
		(fp_line
			(start -0.120396 0.3048)
			(end -0.120396 0.2794)
			(stroke
				(width 0.1)
				(type default)
			)
			(layer "B.Fab")
		)
		(fp_line
			(start -0.67945 0.3048)
			(end -0.120396 0.3048)
			(stroke
				(width 0.1)
				(type default)
			)
			(layer "B.Fab")
		)
		(pad "1" smd circle
			(at 0.40005 0 270)
			(size 0 0)
			(layers "B.Cu" "B.Mask" "B.Paste")
			(net "PVNN_TERM_CPU0")
		)
		(pad "2" smd circle
			(at -0.40005 0 270)
			(size 0 0)
			(layers "B.Cu" "B.Mask" "B.Paste")
			(net "DBP_CPU_HOOK8_MBP2_GTL_QS_N")
		)
	)
	(footprint ""
		(layer "B.Cu")
		(at 42.392346 -321.554856 -90)
		(property "Reference" "C57"
			(at 0 0 90)
			(layer "B.SilkS")
			(hide yes)
			(effects
				(font
					(size 1.27 1.27)
				)
				(justify mirror)
			)
		)
		(property "Value" ""
			(at 0 0 90)
			(layer "B.Fab")
			(effects
				(font
					(size 1.27 1.27)
				)
				(justify mirror)
			)
		)
		(duplicate_pad_numbers_are_jumpers no)
		(fp_line
			(start -1.524 0.762)
			(end 1.524 0.762)
			(stroke
				(width 0.1524)
				(type default)
			)
			(layer "B.SilkS")
		)
		(fp_line
			(start 1.524 0.762)
			(end 1.524 -0.762)
			(stroke
				(width 0.1524)
				(type default)
			)
			(layer "B.SilkS")
		)
		(fp_line
			(start -1.524 -0.762)
			(end -1.524 0.762)
			(stroke
				(width 0.1524)
				(type default)
			)
			(layer "B.SilkS")
		)
		(fp_line
			(start 1.524 -0.762)
			(end -1.524 -0.762)
			(stroke
				(width 0.1524)
				(type default)
			)
			(layer "B.SilkS")
		)
		(fp_line
			(start -1.1049 0.724916)
			(end -1.1049 -0.724916)
			(stroke
				(width 0.1)
				(type default)
			)
			(layer "B.Fab")
		)
		(fp_line
			(start 1.1049 0.724916)
			(end -1.1049 0.724916)
			(stroke
				(width 0.1)
				(type default)
			)
			(layer "B.Fab")
		)
		(fp_line
			(start -1.1049 -0.724916)
			(end 1.1049 -0.724916)
			(stroke
				(width 0.1)
				(type default)
			)
			(layer "B.Fab")
		)
		(fp_line
			(start 1.1049 -0.724916)
			(end 1.1049 0.724916)
			(stroke
				(width 0.1)
				(type default)
			)
			(layer "B.Fab")
		)
		(pad "1" smd rect
			(at 0.889 0 270)
			(size 1.016 1.27)
			(layers "B.Cu" "B.Mask" "B.Paste")
			(net "P12V_S3_AUX_CPU1_NVDIMM")
		)
		(pad "2" smd rect
			(at -0.889 0 270)
			(size 1.016 1.27)
			(layers "B.Cu" "B.Mask" "B.Paste")
			(net "GND")
		)
	)
	(footprint ""
		(layer "B.Cu")
		(at 359.250742 -210.19389)
		(property "Reference" "C507"
			(at 0 0 0)
			(layer "B.SilkS")
			(hide yes)
			(effects
				(font
					(size 1.27 1.27)
				)
				(justify mirror)
			)
		)
		(property "Value" ""
			(at 0 0 0)
			(layer "B.Fab")
			(effects
				(font
					(size 1.27 1.27)
				)
				(justify mirror)
			)
		)
		(duplicate_pad_numbers_are_jumpers no)
		(fp_line
			(start -1.524 -0.762)
			(end -1.524 0.762)
			(stroke
				(width 0.1524)
				(type default)
			)
			(layer "B.SilkS")
		)
		(fp_line
			(start -1.524 0.762)
			(end 1.524 0.762)
			(stroke
				(width 0.1524)
				(type default)
			)
			(layer "B.SilkS")
		)
		(fp_line
			(start 1.524 -0.762)
			(end -1.524 -0.762)
			(stroke
				(width 0.1524)
				(type default)
			)
			(layer "B.SilkS")
		)
		(fp_line
			(start 1.524 0.762)
			(end 1.524 -0.762)
			(stroke
				(width 0.1524)
				(type default)
			)
			(layer "B.SilkS")
		)
		(fp_line
			(start -1.1049 -0.724916)
			(end 1.1049 -0.724916)
			(stroke
				(width 0.1)
				(type default)
			)
			(layer "B.Fab")
		)
		(fp_line
			(start -1.1049 0.724916)
			(end -1.1049 -0.724916)
			(stroke
				(width 0.1)
				(type default)
			)
			(layer "B.Fab")
		)
		(fp_line
			(start 1.1049 -0.724916)
			(end 1.1049 0.724916)
			(stroke
				(width 0.1)
				(type default)
			)
			(layer "B.Fab")
		)
		(fp_line
			(start 1.1049 0.724916)
			(end -1.1049 0.724916)
			(stroke
				(width 0.1)
				(type default)
			)
			(layer "B.Fab")
		)
		(pad "1" smd rect
			(at 0.889 0)
			(size 1.016 1.27)
			(layers "B.Cu" "B.Mask" "B.Paste")
			(net "PVCCD_HV_CPU0")
		)
		(pad "2" smd rect
			(at -0.889 0)
			(size 1.016 1.27)
			(layers "B.Cu" "B.Mask" "B.Paste")
			(net "GND")
		)
	)
	(footprint ""
		(layer "B.Cu")
		(at 446.179956 -318.603376)
		(property "Reference" "R38"
			(at 0 0 0)
			(layer "B.SilkS")
			(hide yes)
			(effects
				(font
					(size 1.27 1.27)
				)
				(justify mirror)
			)
		)
		(property "Value" ""
			(at 0 0 0)
			(layer "B.Fab")
			(effects
				(font
					(size 1.27 1.27)
				)
				(justify mirror)
			)
		)
		(duplicate_pad_numbers_are_jumpers no)
		(fp_line
			(start -0.7874 -0.4064)
			(end -0.7874 0.4064)
			(stroke
				(width 0.1524)
				(type default)
			)
			(layer "B.SilkS")
		)
		(fp_line
			(start -0.7874 0.4064)
			(end 0.7874 0.4064)
			(stroke
				(width 0.1524)
				(type default)
			)
			(layer "B.SilkS")
		)
		(fp_line
			(start 0.7874 -0.4064)
			(end -0.7874 -0.4064)
			(stroke
				(width 0.1524)
				(type default)
			)
			(layer "B.SilkS")
		)
		(fp_line
			(start 0.7874 0.4064)
			(end 0.7874 -0.4064)
			(stroke
				(width 0.1524)
				(type default)
			)
			(layer "B.SilkS")
		)
		(fp_line
			(start -0.67945 -0.3048)
			(end -0.67945 0.3048)
			(stroke
				(width 0.1)
				(type default)
			)
			(layer "B.Fab")
		)
		(fp_line
			(start -0.67945 0.3048)
			(end -0.120396 0.3048)
			(stroke
				(width 0.1)
				(type default)
			)
			(layer "B.Fab")
		)
		(fp_line
			(start -0.12065 -0.3048)
			(end -0.67945 -0.3048)
			(stroke
				(width 0.1)
				(type default)
			)
			(layer "B.Fab")
		)
		(fp_line
			(start -0.12065 -0.2794)
			(end -0.12065 -0.3048)
			(stroke
				(width 0.1)
				(type default)
			)
			(layer "B.Fab")
		)
		(fp_line
			(start -0.120396 0.2794)
			(end 0.12065 0.2794)
			(stroke
				(width 0.1)
				(type default)
			)
			(layer "B.Fab")
		)
		(fp_line
			(start -0.120396 0.3048)
			(end -0.120396 0.2794)
			(stroke
				(width 0.1)
				(type default)
			)
			(layer "B.Fab")
		)
		(fp_line
			(start 0.12065 -0.305054)
			(end 0.12065 -0.2794)
			(stroke
				(width 0.1)
				(type default)
			)
			(layer "B.Fab")
		)
		(fp_line
			(start 0.12065 -0.2794)
			(end -0.12065 -0.2794)
			(stroke
				(width 0.1)
				(type default)
			)
			(layer "B.Fab")
		)
		(fp_line
			(start 0.12065 0.2794)
			(end 0.12065 0.3048)
			(stroke
				(width 0.1)
				(type default)
			)
			(layer "B.Fab")
		)
		(fp_line
			(start 0.12065 0.3048)
			(end 0.67945 0.3048)
			(stroke
				(width 0.1)
				(type default)
			)
			(layer "B.Fab")
		)
		(fp_line
			(start 0.67945 -0.305054)
			(end 0.12065 -0.305054)
			(stroke
				(width 0.1)
				(type default)
			)
			(layer "B.Fab")
		)
		(fp_line
			(start 0.67945 0.3048)
			(end 0.67945 -0.305054)
			(stroke
				(width 0.1)
				(type default)
			)
			(layer "B.Fab")
		)
		(pad "1" smd circle
			(at 0.40005 0 180)
			(size 0 0)
			(layers "B.Cu" "B.Mask" "B.Paste")
			(net "PD_CHG_CPU0_DIMM1_SAA")
		)
		(pad "2" smd circle
			(at -0.40005 0 180)
			(size 0 0)
			(layers "B.Cu" "B.Mask" "B.Paste")
			(net "GND")
		)
	)
	(footprint ""
		(layer "B.Cu")
		(at 323.646292 -190.269114 -90)
		(property "Reference" "R1"
			(at 0 0 90)
			(layer "B.SilkS")
			(hide yes)
			(effects
				(font
					(size 1.27 1.27)
				)
				(justify mirror)
			)
		)
		(property "Value" ""
			(at 0 0 90)
			(layer "B.Fab")
			(effects
				(font
					(size 1.27 1.27)
				)
				(justify mirror)
			)
		)
		(duplicate_pad_numbers_are_jumpers no)
		(fp_line
			(start -0.7874 0.4064)
			(end 0.7874 0.4064)
			(stroke
				(width 0.1524)
				(type default)
			)
			(layer "B.SilkS")
		)
		(fp_line
			(start 0.7874 0.4064)
			(end 0.7874 -0.4064)
			(stroke
				(width 0.1524)
				(type default)
			)
			(layer "B.SilkS")
		)
		(fp_line
			(start -0.7874 -0.4064)
			(end -0.7874 0.4064)
			(stroke
				(width 0.1524)
				(type default)
			)
			(layer "B.SilkS")
		)
		(fp_line
			(start 0.7874 -0.4064)
			(end -0.7874 -0.4064)
			(stroke
				(width 0.1524)
				(type default)
			)
			(layer "B.SilkS")
		)
		(fp_line
			(start -0.67945 0.3048)
			(end -0.120396 0.3048)
			(stroke
				(width 0.1)
				(type default)
			)
			(layer "B.Fab")
		)
		(fp_line
			(start -0.120396 0.3048)
			(end -0.120396 0.2794)
			(stroke
				(width 0.1)
				(type default)
			)
			(layer "B.Fab")
		)
		(fp_line
			(start 0.12065 0.3048)
			(end 0.67945 0.3048)
			(stroke
				(width 0.1)
				(type default)
			)
			(layer "B.Fab")
		)
		(fp_line
			(start 0.67945 0.3048)
			(end 0.67945 -0.305054)
			(stroke
				(width 0.1)
				(type default)
			)
			(layer "B.Fab")
		)
		(fp_line
			(start -0.120396 0.2794)
			(end 0.12065 0.2794)
			(stroke
				(width 0.1)
				(type default)
			)
			(layer "B.Fab")
		)
		(fp_line
			(start 0.12065 0.2794)
			(end 0.12065 0.3048)
			(stroke
				(width 0.1)
				(type default)
			)
			(layer "B.Fab")
		)
		(fp_line
			(start -0.12065 -0.2794)
			(end -0.12065 -0.3048)
			(stroke
				(width 0.1)
				(type default)
			)
			(layer "B.Fab")
		)
		(fp_line
			(start 0.12065 -0.2794)
			(end -0.12065 -0.2794)
			(stroke
				(width 0.1)
				(type default)
			)
			(layer "B.Fab")
		)
		(fp_line
			(start -0.67945 -0.3048)
			(end -0.67945 0.3048)
			(stroke
				(width 0.1)
				(type default)
			)
			(layer "B.Fab")
		)
		(fp_line
			(start -0.12065 -0.3048)
			(end -0.67945 -0.3048)
			(stroke
				(width 0.1)
				(type default)
			)
			(layer "B.Fab")
		)
		(fp_line
			(start 0.12065 -0.305054)
			(end 0.12065 -0.2794)
			(stroke
				(width 0.1)
				(type default)
			)
			(layer "B.Fab")
		)
		(fp_line
			(start 0.67945 -0.305054)
			(end 0.12065 -0.305054)
			(stroke
				(width 0.1)
				(type default)
			)
			(layer "B.Fab")
		)
		(pad "1" smd circle
			(at 0.40005 0 90)
			(size 0 0)
			(layers "B.Cu" "B.Mask" "B.Paste")
			(net "H_CPU_PRDY_QS_GTL_N")
		)
		(pad "2" smd circle
			(at -0.40005 0 90)
			(size 0 0)
			(layers "B.Cu" "B.Mask" "B.Paste")
			(net "H_CPU0_PRDY_QS_GTL_R_N")
		)
	)
	(footprint ""
		(layer "B.Cu")
		(at 51.289458 -346.579952 -90)
		(property "Reference" "PC2171"
			(at 0 0 90)
			(layer "B.SilkS")
			(hide yes)
			(effects
				(font
					(size 1.27 1.27)
				)
				(justify mirror)
			)
		)
		(property "Value" ""
			(at 0 0 90)
			(layer "B.Fab")
			(effects
				(font
					(size 1.27 1.27)
				)
				(justify mirror)
			)
		)
		(duplicate_pad_numbers_are_jumpers no)
		(fp_line
			(start -4.533392 2.249932)
			(end 4.533392 2.249932)
			(stroke
				(width 0.1524)
				(type default)
			)
			(layer "B.SilkS")
		)
		(fp_line
			(start 4.533392 2.249932)
			(end 4.533392 -2.249932)
			(stroke
				(width 0.1524)
				(type default)
			)
			(layer "B.SilkS")
		)
		(fp_line
			(start -4.533392 -2.249932)
			(end -4.533392 2.249932)
			(stroke
				(width 0.1524)
				(type default)
			)
			(layer "B.SilkS")
		)
		(fp_line
			(start 4.533392 -2.249932)
			(end -4.533392 -2.249932)
			(stroke
				(width 0.1524)
				(type default)
			)
			(layer "B.SilkS")
		)
		(fp_poly
			(pts
				(xy 4.533392 -2.326132) (xy 5.39242 -2.326132) (xy 5.39242 2.326132) (xy 4.533392 2.326132)
			)
			(stroke
				(width 0)
				(type default)
			)
			(fill yes)
			(layer "B.SilkS")
		)
		(fp_line
			(start -3.750056 2.249932)
			(end 3.750056 2.249932)
			(stroke
				(width 0.1)
				(type default)
			)
			(layer "B.Fab")
		)
		(fp_line
			(start 3.750056 2.249932)
			(end 3.750056 -2.249932)
			(stroke
				(width 0.1)
				(type default)
			)
			(layer "B.Fab")
		)
		(fp_line
			(start -3.750056 -2.249932)
			(end -3.750056 2.249932)
			(stroke
				(width 0.1)
				(type default)
			)
			(layer "B.Fab")
		)
		(fp_line
			(start 3.750056 -2.249932)
			(end -3.750056 -2.249932)
			(stroke
				(width 0.1)
				(type default)
			)
			(layer "B.Fab")
		)
		(fp_text user "+"
			(at 6.322314 0.786384 180)
			(unlocked yes)
			(layer "B.SilkS")
			(effects
				(font
					(size 1.905 1.4224)
					(thickness 0.1524)
				)
				(justify left mirror)
			)
		)
		(fp_text user "-"
			(at -4.8514 -0.14605 270)
			(unlocked yes)
			(layer "B.SilkS")
			(effects
				(font
					(size 1.905 1.4224)
					(thickness 0.1524)
				)
				(justify left mirror)
			)
		)
		(fp_text user "+"
			(at 6.322314 0.786384 180)
			(unlocked yes)
			(layer "B.Fab")
			(effects
				(font
					(size 1.905 1.4224)
					(thickness 0.1524)
				)
				(justify left mirror)
			)
		)
		(fp_text user "-"
			(at -4.8514 -0.14605 270)
			(unlocked yes)
			(layer "B.Fab")
			(effects
				(font
					(size 1.905 1.4224)
					(thickness 0.1524)
				)
				(justify left mirror)
			)
		)
		(pad "1" smd rect
			(at 3.199892 0 90)
			(size 2.413 2.8194)
			(layers "B.Cu" "B.Mask" "B.Paste")
			(net "PVCCFA_EHV_FIVRA_CPU1")
		)
		(pad "2" smd rect
			(at -3.199892 0 90)
			(size 2.413 2.8194)
			(layers "B.Cu" "B.Mask" "B.Paste")
			(net "GND")
		)
	)
	(footprint ""
		(layer "B.Cu")
		(at 116.40312 -255.8542 -90)
		(property "Reference" "C329"
			(at 0 0 90)
			(layer "B.SilkS")
			(hide yes)
			(effects
				(font
					(size 1.27 1.27)
				)
				(justify mirror)
			)
		)
		(property "Value" ""
			(at 0 0 90)
			(layer "B.Fab")
			(effects
				(font
					(size 1.27 1.27)
				)
				(justify mirror)
			)
		)
		(duplicate_pad_numbers_are_jumpers no)
		(fp_line
			(start -1.524 0.762)
			(end 1.524 0.762)
			(stroke
				(width 0.1524)
				(type default)
			)
			(layer "B.SilkS")
		)
		(fp_line
			(start 1.524 0.762)
			(end 1.524 -0.762)
			(stroke
				(width 0.1524)
				(type default)
			)
			(layer "B.SilkS")
		)
		(fp_line
			(start -1.524 -0.762)
			(end -1.524 0.762)
			(stroke
				(width 0.1524)
				(type default)
			)
			(layer "B.SilkS")
		)
		(fp_line
			(start 1.524 -0.762)
			(end -1.524 -0.762)
			(stroke
				(width 0.1524)
				(type default)
			)
			(layer "B.SilkS")
		)
		(fp_line
			(start -1.1049 0.724916)
			(end -1.1049 -0.724916)
			(stroke
				(width 0.1)
				(type default)
			)
			(layer "B.Fab")
		)
		(fp_line
			(start 1.1049 0.724916)
			(end -1.1049 0.724916)
			(stroke
				(width 0.1)
				(type default)
			)
			(layer "B.Fab")
		)
		(fp_line
			(start -1.1049 -0.724916)
			(end 1.1049 -0.724916)
			(stroke
				(width 0.1)
				(type default)
			)
			(layer "B.Fab")
		)
		(fp_line
			(start 1.1049 -0.724916)
			(end 1.1049 0.724916)
			(stroke
				(width 0.1)
				(type default)
			)
			(layer "B.Fab")
		)
		(pad "1" smd rect
			(at 0.889 0 270)
			(size 1.016 1.27)
			(layers "B.Cu" "B.Mask" "B.Paste")
			(net "PVCCIN_CPU1")
		)
		(pad "2" smd rect
			(at -0.889 0 270)
			(size 1.016 1.27)
			(layers "B.Cu" "B.Mask" "B.Paste")
			(net "GND")
		)
	)
	(footprint ""
		(layer "B.Cu")
		(at 323.175884 -343.927938 90)
		(property "Reference" "PR402"
			(at 0 0 90)
			(layer "B.SilkS")
			(hide yes)
			(effects
				(font
					(size 1.27 1.27)
				)
				(justify mirror)
			)
		)
		(property "Value" ""
			(at 0 0 90)
			(layer "B.Fab")
			(effects
				(font
					(size 1.27 1.27)
				)
				(justify mirror)
			)
		)
		(duplicate_pad_numbers_are_jumpers no)
		(fp_line
			(start 0.7874 -0.4064)
			(end -0.7874 -0.4064)
			(stroke
				(width 0.1524)
				(type default)
			)
			(layer "B.SilkS")
		)
		(fp_line
			(start -0.7874 -0.4064)
			(end -0.7874 0.4064)
			(stroke
				(width 0.1524)
				(type default)
			)
			(layer "B.SilkS")
		)
		(fp_line
			(start 0.7874 0.4064)
			(end 0.7874 -0.4064)
			(stroke
				(width 0.1524)
				(type default)
			)
			(layer "B.SilkS")
		)
		(fp_line
			(start -0.7874 0.4064)
			(end 0.7874 0.4064)
			(stroke
				(width 0.1524)
				(type default)
			)
			(layer "B.SilkS")
		)
		(fp_line
			(start 0.67945 -0.305054)
			(end 0.12065 -0.305054)
			(stroke
				(width 0.1)
				(type default)
			)
			(layer "B.Fab")
		)
		(fp_line
			(start 0.12065 -0.305054)
			(end 0.12065 -0.2794)
			(stroke
				(width 0.1)
				(type default)
			)
			(layer "B.Fab")
		)
		(fp_line
			(start -0.12065 -0.3048)
			(end -0.67945 -0.3048)
			(stroke
				(width 0.1)
				(type default)
			)
			(layer "B.Fab")
		)
		(fp_line
			(start -0.67945 -0.3048)
			(end -0.67945 0.3048)
			(stroke
				(width 0.1)
				(type default)
			)
			(layer "B.Fab")
		)
		(fp_line
			(start 0.12065 -0.2794)
			(end -0.12065 -0.2794)
			(stroke
				(width 0.1)
				(type default)
			)
			(layer "B.Fab")
		)
		(fp_line
			(start -0.12065 -0.2794)
			(end -0.12065 -0.3048)
			(stroke
				(width 0.1)
				(type default)
			)
			(layer "B.Fab")
		)
		(fp_line
			(start 0.12065 0.2794)
			(end 0.12065 0.3048)
			(stroke
				(width 0.1)
				(type default)
			)
			(layer "B.Fab")
		)
		(fp_line
			(start -0.120396 0.2794)
			(end 0.12065 0.2794)
			(stroke
				(width 0.1)
				(type default)
			)
			(layer "B.Fab")
		)
		(fp_line
			(start 0.67945 0.3048)
			(end 0.67945 -0.305054)
			(stroke
				(width 0.1)
				(type default)
			)
			(layer "B.Fab")
		)
		(fp_line
			(start 0.12065 0.3048)
			(end 0.67945 0.3048)
			(stroke
				(width 0.1)
				(type default)
			)
			(layer "B.Fab")
		)
		(fp_line
			(start -0.120396 0.3048)
			(end -0.120396 0.2794)
			(stroke
				(width 0.1)
				(type default)
			)
			(layer "B.Fab")
		)
		(fp_line
			(start -0.67945 0.3048)
			(end -0.120396 0.3048)
			(stroke
				(width 0.1)
				(type default)
			)
			(layer "B.Fab")
		)
		(pad "1" smd circle
			(at 0.40005 0 270)
			(size 0 0)
			(layers "B.Cu" "B.Mask" "B.Paste")
			(net "P5V")
		)
		(pad "2" smd circle
			(at -0.40005 0 270)
			(size 0 0)
			(layers "B.Cu" "B.Mask" "B.Paste")
			(net "PVCCIN_CPU0_PVCC")
		)
	)
	(footprint ""
		(layer "B.Cu")
		(at 368.203734 -237.709202 90)
		(property "Reference" "C509"
			(at 0 0 90)
			(layer "B.SilkS")
			(hide yes)
			(effects
				(font
					(size 1.27 1.27)
				)
				(justify mirror)
			)
		)
		(property "Value" ""
			(at 0 0 90)
			(layer "B.Fab")
			(effects
				(font
					(size 1.27 1.27)
				)
				(justify mirror)
			)
		)
		(duplicate_pad_numbers_are_jumpers no)
		(fp_line
			(start 1.2954 -0.5842)
			(end -1.2954 -0.5842)
			(stroke
				(width 0.1524)
				(type default)
			)
			(layer "B.SilkS")
		)
		(fp_line
			(start 0 -0.5842)
			(end 0 0.5842)
			(stroke
				(width 0.1524)
				(type default)
			)
			(layer "B.SilkS")
		)
		(fp_line
			(start -1.2954 -0.5842)
			(end -1.2954 0.5842)
			(stroke
				(width 0.1524)
				(type default)
			)
			(layer "B.SilkS")
		)
		(fp_line
			(start 1.2954 0.5842)
			(end 1.2954 -0.5842)
			(stroke
				(width 0.1524)
				(type default)
			)
			(layer "B.SilkS")
		)
		(fp_line
			(start -1.2954 0.5842)
			(end 1.2954 0.5842)
			(stroke
				(width 0.1524)
				(type default)
			)
			(layer "B.SilkS")
		)
		(fp_line
			(start 0.8636 -0.4572)
			(end -0.8636 -0.4572)
			(stroke
				(width 0.1)
				(type default)
			)
			(layer "B.Fab")
		)
		(fp_line
			(start -0.8636 -0.4572)
			(end -0.8636 -0.4064)
			(stroke
				(width 0.1)
				(type default)
			)
			(layer "B.Fab")
		)
		(fp_line
			(start 1.1938 -0.4064)
			(end 0.8636 -0.4064)
			(stroke
				(width 0.1)
				(type default)
			)
			(layer "B.Fab")
		)
		(fp_line
			(start 0.8636 -0.4064)
			(end 0.8636 -0.4572)
			(stroke
				(width 0.1)
				(type default)
			)
			(layer "B.Fab")
		)
		(fp_line
			(start -0.8636 -0.4064)
			(end -1.1938 -0.4064)
			(stroke
				(width 0.1)
				(type default)
			)
			(layer "B.Fab")
		)
		(fp_line
			(start -1.1938 -0.4064)
			(end -1.1938 0.4064)
			(stroke
				(width 0.1)
				(type default)
			)
			(layer "B.Fab")
		)
		(fp_line
			(start 1.1938 0.4064)
			(end 1.1938 -0.4064)
			(stroke
				(width 0.1)
				(type default)
			)
			(layer "B.Fab")
		)
		(fp_line
			(start 0.8636 0.4064)
			(end 1.1938 0.4064)
			(stroke
				(width 0.1)
				(type default)
			)
			(layer "B.Fab")
		)
		(fp_line
			(start -0.8636 0.4064)
			(end -0.8636 0.4572)
			(stroke
				(width 0.1)
				(type default)
			)
			(layer "B.Fab")
		)
		(fp_line
			(start -1.1938 0.4064)
			(end -0.8636 0.4064)
			(stroke
				(width 0.1)
				(type default)
			)
			(layer "B.Fab")
		)
		(fp_line
			(start 0.8636 0.4572)
			(end 0.8636 0.4064)
			(stroke
				(width 0.1)
				(type default)
			)
			(layer "B.Fab")
		)
		(fp_line
			(start -0.8636 0.4572)
			(end 0.8636 0.4572)
			(stroke
				(width 0.1)
				(type default)
			)
			(layer "B.Fab")
		)
		(pad "1" smd rect
			(at 0.7366 0)
			(size 0.7112 0.8128)
			(layers "B.Cu" "B.Mask" "B.Paste")
			(net "PVCCFA_EHV_FIVRA_CPU0")
		)
		(pad "2" smd rect
			(at -0.7366 0)
			(size 0.7112 0.8128)
			(layers "B.Cu" "B.Mask" "B.Paste")
			(net "GND")
		)
	)
	(footprint ""
		(layer "B.Cu")
		(at 377.632214 -190.703708 -90)
		(property "Reference" "R681"
			(at 0 0 90)
			(layer "B.SilkS")
			(hide yes)
			(effects
				(font
					(size 1.27 1.27)
				)
				(justify mirror)
			)
		)
		(property "Value" ""
			(at 0 0 90)
			(layer "B.Fab")
			(effects
				(font
					(size 1.27 1.27)
				)
				(justify mirror)
			)
		)
		(duplicate_pad_numbers_are_jumpers no)
		(fp_line
			(start -0.7874 0.4064)
			(end 0.7874 0.4064)
			(stroke
				(width 0.1524)
				(type default)
			)
			(layer "B.SilkS")
		)
		(fp_line
			(start 0.7874 0.4064)
			(end 0.7874 -0.4064)
			(stroke
				(width 0.1524)
				(type default)
			)
			(layer "B.SilkS")
		)
		(fp_line
			(start -0.7874 -0.4064)
			(end -0.7874 0.4064)
			(stroke
				(width 0.1524)
				(type default)
			)
			(layer "B.SilkS")
		)
		(fp_line
			(start 0.7874 -0.4064)
			(end -0.7874 -0.4064)
			(stroke
				(width 0.1524)
				(type default)
			)
			(layer "B.SilkS")
		)
		(fp_line
			(start -0.67945 0.3048)
			(end -0.120396 0.3048)
			(stroke
				(width 0.1)
				(type default)
			)
			(layer "B.Fab")
		)
		(fp_line
			(start -0.120396 0.3048)
			(end -0.120396 0.2794)
			(stroke
				(width 0.1)
				(type default)
			)
			(layer "B.Fab")
		)
		(fp_line
			(start 0.12065 0.3048)
			(end 0.67945 0.3048)
			(stroke
				(width 0.1)
				(type default)
			)
			(layer "B.Fab")
		)
		(fp_line
			(start 0.67945 0.3048)
			(end 0.67945 -0.305054)
			(stroke
				(width 0.1)
				(type default)
			)
			(layer "B.Fab")
		)
		(fp_line
			(start -0.120396 0.2794)
			(end 0.12065 0.2794)
			(stroke
				(width 0.1)
				(type default)
			)
			(layer "B.Fab")
		)
		(fp_line
			(start 0.12065 0.2794)
			(end 0.12065 0.3048)
			(stroke
				(width 0.1)
				(type default)
			)
			(layer "B.Fab")
		)
		(fp_line
			(start -0.12065 -0.2794)
			(end -0.12065 -0.3048)
			(stroke
				(width 0.1)
				(type default)
			)
			(layer "B.Fab")
		)
		(fp_line
			(start 0.12065 -0.2794)
			(end -0.12065 -0.2794)
			(stroke
				(width 0.1)
				(type default)
			)
			(layer "B.Fab")
		)
		(fp_line
			(start -0.67945 -0.3048)
			(end -0.67945 0.3048)
			(stroke
				(width 0.1)
				(type default)
			)
			(layer "B.Fab")
		)
		(fp_line
			(start -0.12065 -0.3048)
			(end -0.67945 -0.3048)
			(stroke
				(width 0.1)
				(type default)
			)
			(layer "B.Fab")
		)
		(fp_line
			(start 0.12065 -0.305054)
			(end 0.12065 -0.2794)
			(stroke
				(width 0.1)
				(type default)
			)
			(layer "B.Fab")
		)
		(fp_line
			(start 0.67945 -0.305054)
			(end 0.12065 -0.305054)
			(stroke
				(width 0.1)
				(type default)
			)
			(layer "B.Fab")
		)
		(pad "1" smd circle
			(at 0.40005 0 90)
			(size 0 0)
			(layers "B.Cu" "B.Mask" "B.Paste")
			(net "PVNN_TERM_CPU0")
		)
		(pad "2" smd circle
			(at -0.40005 0 90)
			(size 0 0)
			(layers "B.Cu" "B.Mask" "B.Paste")
			(net "I3C_SPD_DDREFGH_CPU0_SCL")
		)
	)
	(footprint ""
		(layer "B.Cu")
		(at 479.84537 -179.526692 -90)
		(property "Reference" "X46"
			(at -0.305308 4.89204 270)
			(unlocked yes)
			(layer "B.SilkS")
			(effects
				(font
					(size 0.7874 0.5842)
					(thickness 0.1524)
				)
				(justify left mirror)
			)
		)
		(property "Value" ""
			(at 0 0 90)
			(layer "B.Fab")
			(effects
				(font
					(size 1.27 1.27)
				)
				(justify mirror)
			)
		)
		(property "Device Type" "TP_TDR_4P_FTS_TH-TP_TDR_4P_DIPA"
			(at -1.30175 1.27 180)
			(unlocked yes)
			(layer "B.Fab")
			(hide yes)
			(effects
				(font
					(size 0.635 0.4064)
					(thickness 0.1524)
				)
				(justify mirror)
			)
		)
		(property "User Part Number" "N_A"
			(at -1.30175 1.27 180)
			(unlocked yes)
			(layer "Cmts.User")
			(hide yes)
			(effects
				(font
					(size 0.635 0.4064)
					(thickness 0.1524)
				)
				(justify mirror)
			)
		)
		(duplicate_pad_numbers_are_jumpers no)
		(fp_line
			(start -2.54 3.81)
			(end -2.54 3.6703)
			(stroke
				(width 0.1524)
				(type default)
			)
			(layer "B.SilkS")
		)
		(fp_line
			(start 0 3.81)
			(end -2.54 3.81)
			(stroke
				(width 0.1524)
				(type default)
			)
			(layer "B.SilkS")
		)
		(fp_line
			(start 0 3.175)
			(end 0 3.81)
			(stroke
				(width 0.1524)
				(type default)
			)
			(layer "B.SilkS")
		)
		(fp_line
			(start -2.54 1.4097)
			(end -2.54 1.1303)
			(stroke
				(width 0.1524)
				(type default)
			)
			(layer "B.SilkS")
		)
		(fp_line
			(start 0 0.635)
			(end 0 1.905)
			(stroke
				(width 0.1524)
				(type default)
			)
			(layer "B.SilkS")
		)
		(fp_line
			(start -2.54 -1.1303)
			(end -2.54 -1.27)
			(stroke
				(width 0.1524)
				(type default)
			)
			(layer "B.SilkS")
		)
		(fp_line
			(start -2.54 -1.27)
			(end 0 -1.27)
			(stroke
				(width 0.1524)
				(type default)
			)
			(layer "B.SilkS")
		)
		(fp_line
			(start 0 -1.27)
			(end 0 -0.635)
			(stroke
				(width 0.1524)
				(type default)
			)
			(layer "B.SilkS")
		)
		(fp_poly
			(pts
				(xy 0.761746 0) (xy 2.285746 -0.762) (xy 2.285746 0.762)
			)
			(stroke
				(width 0)
				(type default)
			)
			(fill yes)
			(layer "B.SilkS")
		)
		(fp_line
			(start -2.54 3.81)
			(end -2.54 -1.27)
			(stroke
				(width 0.1)
				(type default)
			)
			(layer "B.Fab")
		)
		(fp_line
			(start 0 3.81)
			(end -2.54 3.81)
			(stroke
				(width 0.1)
				(type default)
			)
			(layer "B.Fab")
		)
		(fp_line
			(start -2.54 -1.27)
			(end 0 -1.27)
			(stroke
				(width 0.1)
				(type default)
			)
			(layer "B.Fab")
		)
		(fp_line
			(start 0 -1.27)
			(end 0 3.81)
			(stroke
				(width 0.1)
				(type default)
			)
			(layer "B.Fab")
		)
		(fp_poly
			(pts
				(xy 0.761746 0) (xy 2.285746 -0.762) (xy 2.285746 0.762)
			)
			(stroke
				(width 0)
				(type default)
			)
			(fill yes)
			(layer "B.Fab")
		)
		(pad "1" thru_hole circle
			(at 0 0 90)
			(size 1.0033 1.0033)
			(drill 0.249936)
			(layers "*.Cu" "*.Mask")
			(remove_unused_layers no)
			(net "TDR_DIFF_85_NECK_IN5_DN")
			(clearance 0.10795)
			(padstack
				(mode front_inner_back)
				(layer "Inner"
					(shape circle)
					(size 0.8001 0.8001)
					(clearance 0.1524)
				)
				(layer "B.Cu"
					(shape circle)
					(size 1.0033 1.0033)
					(thermal_gap 0.10795)
					(clearance 0.10795)
				)
			)
		)
		(pad "2" thru_hole circle
			(at -2.54 0 90)
			(size 1.9939 1.9939)
			(drill 0.249936)
			(layers "*.Cu" "*.Mask")
			(remove_unused_layers no)
			(net "T1_GND")
			(clearance 0.10795)
			(padstack
				(mode front_inner_back)
				(layer "Inner"
					(shape circle)
					(size 0.8001 0.8001)
					(clearance 0.1524)
				)
				(layer "B.Cu"
					(shape circle)
					(size 1.9939 1.9939)
					(thermal_gap 0.10795)
					(clearance 0.10795)
				)
			)
		)
		(pad "3" thru_hole circle
			(at -2.54 2.54 90)
			(size 1.9939 1.9939)
			(drill 0.249936)
			(layers "*.Cu" "*.Mask")
			(remove_unused_layers no)
			(net "T1_GND")
			(clearance 0.10795)
			(padstack
				(mode front_inner_back)
				(layer "Inner"
					(shape circle)
					(size 0.8001 0.8001)
					(clearance 0.1524)
				)
				(layer "B.Cu"
					(shape circle)
					(size 1.9939 1.9939)
					(thermal_gap 0.10795)
					(clearance 0.10795)
				)
			)
		)
		(pad "4" thru_hole circle
			(at 0 2.54 90)
			(size 1.0033 1.0033)
			(drill 0.249936)
			(layers "*.Cu" "*.Mask")
			(remove_unused_layers no)
			(net "TDR_DIFF_85_NECK_IN5_DP")
			(clearance 0.10795)
			(padstack
				(mode front_inner_back)
				(layer "Inner"
					(shape circle)
					(size 0.8001 0.8001)
					(clearance 0.1524)
				)
				(layer "B.Cu"
					(shape circle)
					(size 1.0033 1.0033)
					(thermal_gap 0.10795)
					(clearance 0.10795)
				)
			)
		)
	)
	(footprint ""
		(layer "B.Cu")
		(at 282.423616 -318.94653 90)
		(property "Reference" "R2730"
			(at 0 0 90)
			(layer "B.SilkS")
			(hide yes)
			(effects
				(font
					(size 1.27 1.27)
				)
				(justify mirror)
			)
		)
		(property "Value" ""
			(at 0 0 90)
			(layer "B.Fab")
			(effects
				(font
					(size 1.27 1.27)
				)
				(justify mirror)
			)
		)
		(duplicate_pad_numbers_are_jumpers no)
		(fp_line
			(start 0.7874 -0.4064)
			(end -0.7874 -0.4064)
			(stroke
				(width 0.1524)
				(type default)
			)
			(layer "B.SilkS")
		)
		(fp_line
			(start -0.7874 -0.4064)
			(end -0.7874 0.4064)
			(stroke
				(width 0.1524)
				(type default)
			)
			(layer "B.SilkS")
		)
		(fp_line
			(start 0.7874 0.4064)
			(end 0.7874 -0.4064)
			(stroke
				(width 0.1524)
				(type default)
			)
			(layer "B.SilkS")
		)
		(fp_line
			(start -0.7874 0.4064)
			(end 0.7874 0.4064)
			(stroke
				(width 0.1524)
				(type default)
			)
			(layer "B.SilkS")
		)
		(fp_line
			(start 0.67945 -0.305054)
			(end 0.12065 -0.305054)
			(stroke
				(width 0.1)
				(type default)
			)
			(layer "B.Fab")
		)
		(fp_line
			(start 0.12065 -0.305054)
			(end 0.12065 -0.2794)
			(stroke
				(width 0.1)
				(type default)
			)
			(layer "B.Fab")
		)
		(fp_line
			(start -0.12065 -0.3048)
			(end -0.67945 -0.3048)
			(stroke
				(width 0.1)
				(type default)
			)
			(layer "B.Fab")
		)
		(fp_line
			(start -0.67945 -0.3048)
			(end -0.67945 0.3048)
			(stroke
				(width 0.1)
				(type default)
			)
			(layer "B.Fab")
		)
		(fp_line
			(start 0.12065 -0.2794)
			(end -0.12065 -0.2794)
			(stroke
				(width 0.1)
				(type default)
			)
			(layer "B.Fab")
		)
		(fp_line
			(start -0.12065 -0.2794)
			(end -0.12065 -0.3048)
			(stroke
				(width 0.1)
				(type default)
			)
			(layer "B.Fab")
		)
		(fp_line
			(start 0.12065 0.2794)
			(end 0.12065 0.3048)
			(stroke
				(width 0.1)
				(type default)
			)
			(layer "B.Fab")
		)
		(fp_line
			(start -0.120396 0.2794)
			(end 0.12065 0.2794)
			(stroke
				(width 0.1)
				(type default)
			)
			(layer "B.Fab")
		)
		(fp_line
			(start 0.67945 0.3048)
			(end 0.67945 -0.305054)
			(stroke
				(width 0.1)
				(type default)
			)
			(layer "B.Fab")
		)
		(fp_line
			(start 0.12065 0.3048)
			(end 0.67945 0.3048)
			(stroke
				(width 0.1)
				(type default)
			)
			(layer "B.Fab")
		)
		(fp_line
			(start -0.120396 0.3048)
			(end -0.120396 0.2794)
			(stroke
				(width 0.1)
				(type default)
			)
			(layer "B.Fab")
		)
		(fp_line
			(start -0.67945 0.3048)
			(end -0.120396 0.3048)
			(stroke
				(width 0.1)
				(type default)
			)
			(layer "B.Fab")
		)
		(pad "1" smd circle
			(at 0.40005 0 270)
			(size 0 0)
			(layers "B.Cu" "B.Mask" "B.Paste")
			(net "PWRGD_CHC_CPU0_DIMM2")
		)
		(pad "2" smd circle
			(at -0.40005 0 270)
			(size 0 0)
			(layers "B.Cu" "B.Mask" "B.Paste")
			(net "PWRGD_FAIL_CPU0_CD")
		)
	)
	(footprint ""
		(layer "B.Cu")
		(at 304.718466 -319.061846 90)
		(property "Reference" "R2726"
			(at 0 0 90)
			(layer "B.SilkS")
			(hide yes)
			(effects
				(font
					(size 1.27 1.27)
				)
				(justify mirror)
			)
		)
		(property "Value" ""
			(at 0 0 90)
			(layer "B.Fab")
			(effects
				(font
					(size 1.27 1.27)
				)
				(justify mirror)
			)
		)
		(duplicate_pad_numbers_are_jumpers no)
		(fp_line
			(start 0.7874 -0.4064)
			(end -0.7874 -0.4064)
			(stroke
				(width 0.1524)
				(type default)
			)
			(layer "B.SilkS")
		)
		(fp_line
			(start -0.7874 -0.4064)
			(end -0.7874 0.4064)
			(stroke
				(width 0.1524)
				(type default)
			)
			(layer "B.SilkS")
		)
		(fp_line
			(start 0.7874 0.4064)
			(end 0.7874 -0.4064)
			(stroke
				(width 0.1524)
				(type default)
			)
			(layer "B.SilkS")
		)
		(fp_line
			(start -0.7874 0.4064)
			(end 0.7874 0.4064)
			(stroke
				(width 0.1524)
				(type default)
			)
			(layer "B.SilkS")
		)
		(fp_line
			(start 0.67945 -0.305054)
			(end 0.12065 -0.305054)
			(stroke
				(width 0.1)
				(type default)
			)
			(layer "B.Fab")
		)
		(fp_line
			(start 0.12065 -0.305054)
			(end 0.12065 -0.2794)
			(stroke
				(width 0.1)
				(type default)
			)
			(layer "B.Fab")
		)
		(fp_line
			(start -0.12065 -0.3048)
			(end -0.67945 -0.3048)
			(stroke
				(width 0.1)
				(type default)
			)
			(layer "B.Fab")
		)
		(fp_line
			(start -0.67945 -0.3048)
			(end -0.67945 0.3048)
			(stroke
				(width 0.1)
				(type default)
			)
			(layer "B.Fab")
		)
		(fp_line
			(start 0.12065 -0.2794)
			(end -0.12065 -0.2794)
			(stroke
				(width 0.1)
				(type default)
			)
			(layer "B.Fab")
		)
		(fp_line
			(start -0.12065 -0.2794)
			(end -0.12065 -0.3048)
			(stroke
				(width 0.1)
				(type default)
			)
			(layer "B.Fab")
		)
		(fp_line
			(start 0.12065 0.2794)
			(end 0.12065 0.3048)
			(stroke
				(width 0.1)
				(type default)
			)
			(layer "B.Fab")
		)
		(fp_line
			(start -0.120396 0.2794)
			(end 0.12065 0.2794)
			(stroke
				(width 0.1)
				(type default)
			)
			(layer "B.Fab")
		)
		(fp_line
			(start 0.67945 0.3048)
			(end 0.67945 -0.305054)
			(stroke
				(width 0.1)
				(type default)
			)
			(layer "B.Fab")
		)
		(fp_line
			(start 0.12065 0.3048)
			(end 0.67945 0.3048)
			(stroke
				(width 0.1)
				(type default)
			)
			(layer "B.Fab")
		)
		(fp_line
			(start -0.120396 0.3048)
			(end -0.120396 0.2794)
			(stroke
				(width 0.1)
				(type default)
			)
			(layer "B.Fab")
		)
		(fp_line
			(start -0.67945 0.3048)
			(end -0.120396 0.3048)
			(stroke
				(width 0.1)
				(type default)
			)
			(layer "B.Fab")
		)
		(pad "1" smd circle
			(at 0.40005 0 270)
			(size 0 0)
			(layers "B.Cu" "B.Mask" "B.Paste")
			(net "PWRGD_CHA_CPU0_DIMM1")
		)
		(pad "2" smd circle
			(at -0.40005 0 270)
			(size 0 0)
			(layers "B.Cu" "B.Mask" "B.Paste")
			(net "PWRGD_FAIL_CPU0_AB")
		)
	)
	(footprint ""
		(layer "B.Cu")
		(at 367.898934 -252.176026 -90)
		(property "Reference" "C370"
			(at 0 0 90)
			(layer "B.SilkS")
			(hide yes)
			(effects
				(font
					(size 1.27 1.27)
				)
				(justify mirror)
			)
		)
		(property "Value" ""
			(at 0 0 90)
			(layer "B.Fab")
			(effects
				(font
					(size 1.27 1.27)
				)
				(justify mirror)
			)
		)
		(duplicate_pad_numbers_are_jumpers no)
		(fp_line
			(start -1.524 0.762)
			(end 1.524 0.762)
			(stroke
				(width 0.1524)
				(type default)
			)
			(layer "B.SilkS")
		)
		(fp_line
			(start 1.524 0.762)
			(end 1.524 -0.762)
			(stroke
				(width 0.1524)
				(type default)
			)
			(layer "B.SilkS")
		)
		(fp_line
			(start -1.524 -0.762)
			(end -1.524 0.762)
			(stroke
				(width 0.1524)
				(type default)
			)
			(layer "B.SilkS")
		)
		(fp_line
			(start 1.524 -0.762)
			(end -1.524 -0.762)
			(stroke
				(width 0.1524)
				(type default)
			)
			(layer "B.SilkS")
		)
		(fp_line
			(start -1.1049 0.724916)
			(end -1.1049 -0.724916)
			(stroke
				(width 0.1)
				(type default)
			)
			(layer "B.Fab")
		)
		(fp_line
			(start 1.1049 0.724916)
			(end -1.1049 0.724916)
			(stroke
				(width 0.1)
				(type default)
			)
			(layer "B.Fab")
		)
		(fp_line
			(start -1.1049 -0.724916)
			(end 1.1049 -0.724916)
			(stroke
				(width 0.1)
				(type default)
			)
			(layer "B.Fab")
		)
		(fp_line
			(start 1.1049 -0.724916)
			(end 1.1049 0.724916)
			(stroke
				(width 0.1)
				(type default)
			)
			(layer "B.Fab")
		)
		(pad "1" smd rect
			(at 0.889 0 270)
			(size 1.016 1.27)
			(layers "B.Cu" "B.Mask" "B.Paste")
			(net "PVCCIN_CPU0")
		)
		(pad "2" smd rect
			(at -0.889 0 270)
			(size 1.016 1.27)
			(layers "B.Cu" "B.Mask" "B.Paste")
			(net "GND")
		)
	)
	(footprint ""
		(layer "B.Cu")
		(at 366.037368 -262.348726 180)
		(property "Reference" "C1396"
			(at 0 0 0)
			(layer "B.SilkS")
			(hide yes)
			(effects
				(font
					(size 1.27 1.27)
				)
				(justify mirror)
			)
		)
		(property "Value" ""
			(at 0 0 0)
			(layer "B.Fab")
			(effects
				(font
					(size 1.27 1.27)
				)
				(justify mirror)
			)
		)
		(duplicate_pad_numbers_are_jumpers no)
		(fp_line
			(start 1.524 0.762)
			(end 1.524 -0.762)
			(stroke
				(width 0.1524)
				(type default)
			)
			(layer "B.SilkS")
		)
		(fp_line
			(start 1.524 -0.762)
			(end -1.524 -0.762)
			(stroke
				(width 0.1524)
				(type default)
			)
			(layer "B.SilkS")
		)
		(fp_line
			(start -1.524 0.762)
			(end 1.524 0.762)
			(stroke
				(width 0.1524)
				(type default)
			)
			(layer "B.SilkS")
		)
		(fp_line
			(start -1.524 -0.762)
			(end -1.524 0.762)
			(stroke
				(width 0.1524)
				(type default)
			)
			(layer "B.SilkS")
		)
		(fp_line
			(start 1.1049 0.724916)
			(end -1.1049 0.724916)
			(stroke
				(width 0.1)
				(type default)
			)
			(layer "B.Fab")
		)
		(fp_line
			(start 1.1049 -0.724916)
			(end 1.1049 0.724916)
			(stroke
				(width 0.1)
				(type default)
			)
			(layer "B.Fab")
		)
		(fp_line
			(start -1.1049 0.724916)
			(end -1.1049 -0.724916)
			(stroke
				(width 0.1)
				(type default)
			)
			(layer "B.Fab")
		)
		(fp_line
			(start -1.1049 -0.724916)
			(end 1.1049 -0.724916)
			(stroke
				(width 0.1)
				(type default)
			)
			(layer "B.Fab")
		)
		(pad "1" smd rect
			(at 0.889 0 180)
			(size 1.016 1.27)
			(layers "B.Cu" "B.Mask" "B.Paste")
			(net "PVPP_HBM_CPU0")
		)
		(pad "2" smd rect
			(at -0.889 0 180)
			(size 1.016 1.27)
			(layers "B.Cu" "B.Mask" "B.Paste")
			(net "GND")
		)
	)
	(footprint ""
		(layer "B.Cu")
		(at 364.04804 -185.981848 180)
		(property "Reference" "R1006"
			(at 0 0 0)
			(layer "B.SilkS")
			(hide yes)
			(effects
				(font
					(size 1.27 1.27)
				)
				(justify mirror)
			)
		)
		(property "Value" ""
			(at 0 0 0)
			(layer "B.Fab")
			(effects
				(font
					(size 1.27 1.27)
				)
				(justify mirror)
			)
		)
		(duplicate_pad_numbers_are_jumpers no)
		(fp_line
			(start 0.7874 0.4064)
			(end 0.7874 -0.4064)
			(stroke
				(width 0.1524)
				(type default)
			)
			(layer "B.SilkS")
		)
		(fp_line
			(start 0.7874 -0.4064)
			(end -0.7874 -0.4064)
			(stroke
				(width 0.1524)
				(type default)
			)
			(layer "B.SilkS")
		)
		(fp_line
			(start -0.7874 0.4064)
			(end 0.7874 0.4064)
			(stroke
				(width 0.1524)
				(type default)
			)
			(layer "B.SilkS")
		)
		(fp_line
			(start -0.7874 -0.4064)
			(end -0.7874 0.4064)
			(stroke
				(width 0.1524)
				(type default)
			)
			(layer "B.SilkS")
		)
		(fp_line
			(start 0.67945 0.3048)
			(end 0.67945 -0.305054)
			(stroke
				(width 0.1)
				(type default)
			)
			(layer "B.Fab")
		)
		(fp_line
			(start 0.67945 -0.305054)
			(end 0.12065 -0.305054)
			(stroke
				(width 0.1)
				(type default)
			)
			(layer "B.Fab")
		)
		(fp_line
			(start 0.12065 0.3048)
			(end 0.67945 0.3048)
			(stroke
				(width 0.1)
				(type default)
			)
			(layer "B.Fab")
		)
		(fp_line
			(start 0.12065 0.2794)
			(end 0.12065 0.3048)
			(stroke
				(width 0.1)
				(type default)
			)
			(layer "B.Fab")
		)
		(fp_line
			(start 0.12065 -0.2794)
			(end -0.12065 -0.2794)
			(stroke
				(width 0.1)
				(type default)
			)
			(layer "B.Fab")
		)
		(fp_line
			(start 0.12065 -0.305054)
			(end 0.12065 -0.2794)
			(stroke
				(width 0.1)
				(type default)
			)
			(layer "B.Fab")
		)
		(fp_line
			(start -0.120396 0.3048)
			(end -0.120396 0.2794)
			(stroke
				(width 0.1)
				(type default)
			)
			(layer "B.Fab")
		)
		(fp_line
			(start -0.120396 0.2794)
			(end 0.12065 0.2794)
			(stroke
				(width 0.1)
				(type default)
			)
			(layer "B.Fab")
		)
		(fp_line
			(start -0.12065 -0.2794)
			(end -0.12065 -0.3048)
			(stroke
				(width 0.1)
				(type default)
			)
			(layer "B.Fab")
		)
		(fp_line
			(start -0.12065 -0.3048)
			(end -0.67945 -0.3048)
			(stroke
				(width 0.1)
				(type default)
			)
			(layer "B.Fab")
		)
		(fp_line
			(start -0.67945 0.3048)
			(end -0.120396 0.3048)
			(stroke
				(width 0.1)
				(type default)
			)
			(layer "B.Fab")
		)
		(fp_line
			(start -0.67945 -0.3048)
			(end -0.67945 0.3048)
			(stroke
				(width 0.1)
				(type default)
			)
			(layer "B.Fab")
		)
		(pad "1" smd circle
			(at 0.40005 0)
			(size 0 0)
			(layers "B.Cu" "B.Mask" "B.Paste")
			(net "PVNN_TERM_CPU0")
		)
		(pad "2" smd circle
			(at -0.40005 0)
			(size 0 0)
			(layers "B.Cu" "B.Mask" "B.Paste")
			(net "FM_PEHPCPU0_ALERT_N")
		)
	)
	(footprint ""
		(layer "B.Cu")
		(at 27.0383 -128.364996 180)
		(property "Reference" "PR261"
			(at 0 0 0)
			(layer "B.SilkS")
			(hide yes)
			(effects
				(font
					(size 1.27 1.27)
				)
				(justify mirror)
			)
		)
		(property "Value" ""
			(at 0 0 0)
			(layer "B.Fab")
			(effects
				(font
					(size 1.27 1.27)
				)
				(justify mirror)
			)
		)
		(duplicate_pad_numbers_are_jumpers no)
		(fp_line
			(start 0.7874 0.4064)
			(end 0.7874 -0.4064)
			(stroke
				(width 0.1524)
				(type default)
			)
			(layer "B.SilkS")
		)
		(fp_line
			(start 0.7874 -0.4064)
			(end -0.7874 -0.4064)
			(stroke
				(width 0.1524)
				(type default)
			)
			(layer "B.SilkS")
		)
		(fp_line
			(start -0.7874 0.4064)
			(end 0.7874 0.4064)
			(stroke
				(width 0.1524)
				(type default)
			)
			(layer "B.SilkS")
		)
		(fp_line
			(start -0.7874 -0.4064)
			(end -0.7874 0.4064)
			(stroke
				(width 0.1524)
				(type default)
			)
			(layer "B.SilkS")
		)
		(fp_line
			(start 0.67945 0.3048)
			(end 0.67945 -0.305054)
			(stroke
				(width 0.1)
				(type default)
			)
			(layer "B.Fab")
		)
		(fp_line
			(start 0.67945 -0.305054)
			(end 0.12065 -0.305054)
			(stroke
				(width 0.1)
				(type default)
			)
			(layer "B.Fab")
		)
		(fp_line
			(start 0.12065 0.3048)
			(end 0.67945 0.3048)
			(stroke
				(width 0.1)
				(type default)
			)
			(layer "B.Fab")
		)
		(fp_line
			(start 0.12065 0.2794)
			(end 0.12065 0.3048)
			(stroke
				(width 0.1)
				(type default)
			)
			(layer "B.Fab")
		)
		(fp_line
			(start 0.12065 -0.2794)
			(end -0.12065 -0.2794)
			(stroke
				(width 0.1)
				(type default)
			)
			(layer "B.Fab")
		)
		(fp_line
			(start 0.12065 -0.305054)
			(end 0.12065 -0.2794)
			(stroke
				(width 0.1)
				(type default)
			)
			(layer "B.Fab")
		)
		(fp_line
			(start -0.120396 0.3048)
			(end -0.120396 0.2794)
			(stroke
				(width 0.1)
				(type default)
			)
			(layer "B.Fab")
		)
		(fp_line
			(start -0.120396 0.2794)
			(end 0.12065 0.2794)
			(stroke
				(width 0.1)
				(type default)
			)
			(layer "B.Fab")
		)
		(fp_line
			(start -0.12065 -0.2794)
			(end -0.12065 -0.3048)
			(stroke
				(width 0.1)
				(type default)
			)
			(layer "B.Fab")
		)
		(fp_line
			(start -0.12065 -0.3048)
			(end -0.67945 -0.3048)
			(stroke
				(width 0.1)
				(type default)
			)
			(layer "B.Fab")
		)
		(fp_line
			(start -0.67945 0.3048)
			(end -0.120396 0.3048)
			(stroke
				(width 0.1)
				(type default)
			)
			(layer "B.Fab")
		)
		(fp_line
			(start -0.67945 -0.3048)
			(end -0.67945 0.3048)
			(stroke
				(width 0.1)
				(type default)
			)
			(layer "B.Fab")
		)
		(pad "1" smd circle
			(at 0.40005 0)
			(size 0 0)
			(layers "B.Cu" "B.Mask" "B.Paste")
			(net "P12V_AUX")
		)
		(pad "2" smd circle
			(at -0.40005 0)
			(size 0 0)
			(layers "B.Cu" "B.Mask" "B.Paste")
			(net "PVCCINFAON_CPU1_VIN_CSNIN")
		)
	)
	(footprint ""
		(layer "B.Cu")
		(at 181.755542 -114.575336)
		(property "Reference" "C1127"
			(at 0 0 0)
			(layer "B.SilkS")
			(hide yes)
			(effects
				(font
					(size 1.27 1.27)
				)
				(justify mirror)
			)
		)
		(property "Value" ""
			(at 0 0 0)
			(layer "B.Fab")
			(effects
				(font
					(size 1.27 1.27)
				)
				(justify mirror)
			)
		)
		(duplicate_pad_numbers_are_jumpers no)
		(fp_line
			(start -0.69215 -0.2921)
			(end -0.69215 0.2921)
			(stroke
				(width 0.1524)
				(type default)
			)
			(layer "B.SilkS")
		)
		(fp_line
			(start -0.69215 0.2921)
			(end 0.69215 0.2921)
			(stroke
				(width 0.1524)
				(type default)
			)
			(layer "B.SilkS")
		)
		(fp_line
			(start 0.69215 -0.2921)
			(end -0.69215 -0.2921)
			(stroke
				(width 0.1524)
				(type default)
			)
			(layer "B.SilkS")
		)
		(fp_line
			(start 0.69215 0.2921)
			(end 0.69215 -0.2921)
			(stroke
				(width 0.1524)
				(type default)
			)
			(layer "B.SilkS")
		)
		(fp_line
			(start -0.51435 -0.2794)
			(end -0.51435 0.2794)
			(stroke
				(width 0.1)
				(type default)
			)
			(layer "B.Fab")
		)
		(fp_line
			(start -0.51435 0.2794)
			(end 0.51435 0.2794)
			(stroke
				(width 0.1)
				(type default)
			)
			(layer "B.Fab")
		)
		(fp_line
			(start 0.51435 -0.2794)
			(end -0.51435 -0.2794)
			(stroke
				(width 0.1)
				(type default)
			)
			(layer "B.Fab")
		)
		(fp_line
			(start 0.51435 0.2794)
			(end 0.51435 -0.2794)
			(stroke
				(width 0.1)
				(type default)
			)
			(layer "B.Fab")
		)
		(pad "1" smd circle
			(at 0.40005 0 180)
			(size 0 0)
			(layers "B.Cu" "B.Mask" "B.Paste")
			(net "P3V3_AUX_FPGA_VCCIO2")
		)
		(pad "2" smd circle
			(at -0.40005 0 180)
			(size 0 0)
			(layers "B.Cu" "B.Mask" "B.Paste")
			(net "GND")
		)
		(zone
			(layer "B.Cu")
			(hatch none 0.5)
			(connect_pads
				(clearance 0)
			)
			(min_thickness 0.25)
			(keepout
				(tracks not_allowed)
				(vias allowed)
				(pads allowed)
				(copperpour not_allowed)
				(footprints allowed)
			)
			(placement
				(enabled no)
				(sheetname "")
			)
			(fill
				(thermal_gap 0.5)
				(thermal_bridge_width 0.5)
				(island_removal_mode 0)
			)
			(polygon
				(pts
					(xy 181.946042 -114.487706) (xy 181.854602 -114.42954) (xy 181.655212 -114.42954) (xy 181.565042 -114.487706)
					(xy 181.565042 -114.662966) (xy 181.655212 -114.721386) (xy 181.854602 -114.721386) (xy 181.946042 -114.66322)
				)
			)
		)
	)
	(footprint ""
		(layer "B.Cu")
		(at 450.43725 -44.171362)
		(property "Reference" "R425"
			(at 0 0 0)
			(layer "B.SilkS")
			(hide yes)
			(effects
				(font
					(size 1.27 1.27)
				)
				(justify mirror)
			)
		)
		(property "Value" ""
			(at 0 0 0)
			(layer "B.Fab")
			(effects
				(font
					(size 1.27 1.27)
				)
				(justify mirror)
			)
		)
		(duplicate_pad_numbers_are_jumpers no)
		(fp_line
			(start -0.7874 -0.4064)
			(end -0.7874 0.4064)
			(stroke
				(width 0.1524)
				(type default)
			)
			(layer "B.SilkS")
		)
		(fp_line
			(start -0.7874 0.4064)
			(end 0.7874 0.4064)
			(stroke
				(width 0.1524)
				(type default)
			)
			(layer "B.SilkS")
		)
		(fp_line
			(start 0.7874 -0.4064)
			(end -0.7874 -0.4064)
			(stroke
				(width 0.1524)
				(type default)
			)
			(layer "B.SilkS")
		)
		(fp_line
			(start 0.7874 0.4064)
			(end 0.7874 -0.4064)
			(stroke
				(width 0.1524)
				(type default)
			)
			(layer "B.SilkS")
		)
		(fp_line
			(start -0.67945 -0.3048)
			(end -0.67945 0.3048)
			(stroke
				(width 0.1)
				(type default)
			)
			(layer "B.Fab")
		)
		(fp_line
			(start -0.67945 0.3048)
			(end -0.120396 0.3048)
			(stroke
				(width 0.1)
				(type default)
			)
			(layer "B.Fab")
		)
		(fp_line
			(start -0.12065 -0.3048)
			(end -0.67945 -0.3048)
			(stroke
				(width 0.1)
				(type default)
			)
			(layer "B.Fab")
		)
		(fp_line
			(start -0.12065 -0.2794)
			(end -0.12065 -0.3048)
			(stroke
				(width 0.1)
				(type default)
			)
			(layer "B.Fab")
		)
		(fp_line
			(start -0.120396 0.2794)
			(end 0.12065 0.2794)
			(stroke
				(width 0.1)
				(type default)
			)
			(layer "B.Fab")
		)
		(fp_line
			(start -0.120396 0.3048)
			(end -0.120396 0.2794)
			(stroke
				(width 0.1)
				(type default)
			)
			(layer "B.Fab")
		)
		(fp_line
			(start 0.12065 -0.305054)
			(end 0.12065 -0.2794)
			(stroke
				(width 0.1)
				(type default)
			)
			(layer "B.Fab")
		)
		(fp_line
			(start 0.12065 -0.2794)
			(end -0.12065 -0.2794)
			(stroke
				(width 0.1)
				(type default)
			)
			(layer "B.Fab")
		)
		(fp_line
			(start 0.12065 0.2794)
			(end 0.12065 0.3048)
			(stroke
				(width 0.1)
				(type default)
			)
			(layer "B.Fab")
		)
		(fp_line
			(start 0.12065 0.3048)
			(end 0.67945 0.3048)
			(stroke
				(width 0.1)
				(type default)
			)
			(layer "B.Fab")
		)
		(fp_line
			(start 0.67945 -0.305054)
			(end 0.12065 -0.305054)
			(stroke
				(width 0.1)
				(type default)
			)
			(layer "B.Fab")
		)
		(fp_line
			(start 0.67945 0.3048)
			(end 0.67945 -0.305054)
			(stroke
				(width 0.1)
				(type default)
			)
			(layer "B.Fab")
		)
		(pad "1" smd circle
			(at 0.40005 0 180)
			(size 0 0)
			(layers "B.Cu" "B.Mask" "B.Paste")
			(net "SMB_OCP_SFF_3V3AUX_BUF_R_SDA")
		)
		(pad "2" smd circle
			(at -0.40005 0 180)
			(size 0 0)
			(layers "B.Cu" "B.Mask" "B.Paste")
			(net "SMB_OCP_SFF_3V3AUX_BUF_SDA")
		)
	)
	(footprint ""
		(layer "B.Cu")
		(at 246.8499 -96.761808)
		(property "Reference" "R3340"
			(at 0 0 0)
			(layer "B.SilkS")
			(hide yes)
			(effects
				(font
					(size 1.27 1.27)
				)
				(justify mirror)
			)
		)
		(property "Value" ""
			(at 0 0 0)
			(layer "B.Fab")
			(effects
				(font
					(size 1.27 1.27)
				)
				(justify mirror)
			)
		)
		(duplicate_pad_numbers_are_jumpers no)
		(fp_line
			(start -0.7874 -0.4064)
			(end -0.7874 0.4064)
			(stroke
				(width 0.1524)
				(type default)
			)
			(layer "B.SilkS")
		)
		(fp_line
			(start -0.7874 0.4064)
			(end 0.7874 0.4064)
			(stroke
				(width 0.1524)
				(type default)
			)
			(layer "B.SilkS")
		)
		(fp_line
			(start 0.7874 -0.4064)
			(end -0.7874 -0.4064)
			(stroke
				(width 0.1524)
				(type default)
			)
			(layer "B.SilkS")
		)
		(fp_line
			(start 0.7874 0.4064)
			(end 0.7874 -0.4064)
			(stroke
				(width 0.1524)
				(type default)
			)
			(layer "B.SilkS")
		)
		(fp_line
			(start -0.67945 -0.3048)
			(end -0.67945 0.3048)
			(stroke
				(width 0.1)
				(type default)
			)
			(layer "B.Fab")
		)
		(fp_line
			(start -0.67945 0.3048)
			(end -0.120396 0.3048)
			(stroke
				(width 0.1)
				(type default)
			)
			(layer "B.Fab")
		)
		(fp_line
			(start -0.12065 -0.3048)
			(end -0.67945 -0.3048)
			(stroke
				(width 0.1)
				(type default)
			)
			(layer "B.Fab")
		)
		(fp_line
			(start -0.12065 -0.2794)
			(end -0.12065 -0.3048)
			(stroke
				(width 0.1)
				(type default)
			)
			(layer "B.Fab")
		)
		(fp_line
			(start -0.120396 0.2794)
			(end 0.12065 0.2794)
			(stroke
				(width 0.1)
				(type default)
			)
			(layer "B.Fab")
		)
		(fp_line
			(start -0.120396 0.3048)
			(end -0.120396 0.2794)
			(stroke
				(width 0.1)
				(type default)
			)
			(layer "B.Fab")
		)
		(fp_line
			(start 0.12065 -0.305054)
			(end 0.12065 -0.2794)
			(stroke
				(width 0.1)
				(type default)
			)
			(layer "B.Fab")
		)
		(fp_line
			(start 0.12065 -0.2794)
			(end -0.12065 -0.2794)
			(stroke
				(width 0.1)
				(type default)
			)
			(layer "B.Fab")
		)
		(fp_line
			(start 0.12065 0.2794)
			(end 0.12065 0.3048)
			(stroke
				(width 0.1)
				(type default)
			)
			(layer "B.Fab")
		)
		(fp_line
			(start 0.12065 0.3048)
			(end 0.67945 0.3048)
			(stroke
				(width 0.1)
				(type default)
			)
			(layer "B.Fab")
		)
		(fp_line
			(start 0.67945 -0.305054)
			(end 0.12065 -0.305054)
			(stroke
				(width 0.1)
				(type default)
			)
			(layer "B.Fab")
		)
		(fp_line
			(start 0.67945 0.3048)
			(end 0.67945 -0.305054)
			(stroke
				(width 0.1)
				(type default)
			)
			(layer "B.Fab")
		)
		(pad "1" smd circle
			(at 0.40005 0 180)
			(size 0 0)
			(layers "B.Cu" "B.Mask" "B.Paste")
			(net "SMB_HOST_CLK_3V3AUX_SCL")
		)
		(pad "2" smd circle
			(at -0.40005 0 180)
			(size 0 0)
			(layers "B.Cu" "B.Mask" "B.Paste")
			(net "SMB_HOST_CLK_GEN2_3V3AUX_SCL")
		)
	)
	(footprint ""
		(layer "B.Cu")
		(at 116.40312 -252.17628 -90)
		(property "Reference" "C338"
			(at 0 0 90)
			(layer "B.SilkS")
			(hide yes)
			(effects
				(font
					(size 1.27 1.27)
				)
				(justify mirror)
			)
		)
		(property "Value" ""
			(at 0 0 90)
			(layer "B.Fab")
			(effects
				(font
					(size 1.27 1.27)
				)
				(justify mirror)
			)
		)
		(duplicate_pad_numbers_are_jumpers no)
		(fp_line
			(start -1.524 0.762)
			(end 1.524 0.762)
			(stroke
				(width 0.1524)
				(type default)
			)
			(layer "B.SilkS")
		)
		(fp_line
			(start 1.524 0.762)
			(end 1.524 -0.762)
			(stroke
				(width 0.1524)
				(type default)
			)
			(layer "B.SilkS")
		)
		(fp_line
			(start -1.524 -0.762)
			(end -1.524 0.762)
			(stroke
				(width 0.1524)
				(type default)
			)
			(layer "B.SilkS")
		)
		(fp_line
			(start 1.524 -0.762)
			(end -1.524 -0.762)
			(stroke
				(width 0.1524)
				(type default)
			)
			(layer "B.SilkS")
		)
		(fp_line
			(start -1.1049 0.724916)
			(end -1.1049 -0.724916)
			(stroke
				(width 0.1)
				(type default)
			)
			(layer "B.Fab")
		)
		(fp_line
			(start 1.1049 0.724916)
			(end -1.1049 0.724916)
			(stroke
				(width 0.1)
				(type default)
			)
			(layer "B.Fab")
		)
		(fp_line
			(start -1.1049 -0.724916)
			(end 1.1049 -0.724916)
			(stroke
				(width 0.1)
				(type default)
			)
			(layer "B.Fab")
		)
		(fp_line
			(start 1.1049 -0.724916)
			(end 1.1049 0.724916)
			(stroke
				(width 0.1)
				(type default)
			)
			(layer "B.Fab")
		)
		(pad "1" smd rect
			(at 0.889 0 270)
			(size 1.016 1.27)
			(layers "B.Cu" "B.Mask" "B.Paste")
			(net "PVCCIN_CPU1")
		)
		(pad "2" smd rect
			(at -0.889 0 270)
			(size 1.016 1.27)
			(layers "B.Cu" "B.Mask" "B.Paste")
			(net "GND")
		)
	)
	(footprint ""
		(layer "B.Cu")
		(at 63.616078 -192.93459 90)
		(property "Reference" "R135"
			(at 0 0 90)
			(layer "B.SilkS")
			(hide yes)
			(effects
				(font
					(size 1.27 1.27)
				)
				(justify mirror)
			)
		)
		(property "Value" ""
			(at 0 0 90)
			(layer "B.Fab")
			(effects
				(font
					(size 1.27 1.27)
				)
				(justify mirror)
			)
		)
		(duplicate_pad_numbers_are_jumpers no)
		(fp_line
			(start 0.7874 -0.4064)
			(end -0.7874 -0.4064)
			(stroke
				(width 0.1524)
				(type default)
			)
			(layer "B.SilkS")
		)
		(fp_line
			(start -0.7874 -0.4064)
			(end -0.7874 0.4064)
			(stroke
				(width 0.1524)
				(type default)
			)
			(layer "B.SilkS")
		)
		(fp_line
			(start 0.7874 0.4064)
			(end 0.7874 -0.4064)
			(stroke
				(width 0.1524)
				(type default)
			)
			(layer "B.SilkS")
		)
		(fp_line
			(start -0.7874 0.4064)
			(end 0.7874 0.4064)
			(stroke
				(width 0.1524)
				(type default)
			)
			(layer "B.SilkS")
		)
		(fp_line
			(start 0.67945 -0.305054)
			(end 0.12065 -0.305054)
			(stroke
				(width 0.1)
				(type default)
			)
			(layer "B.Fab")
		)
		(fp_line
			(start 0.12065 -0.305054)
			(end 0.12065 -0.2794)
			(stroke
				(width 0.1)
				(type default)
			)
			(layer "B.Fab")
		)
		(fp_line
			(start -0.12065 -0.3048)
			(end -0.67945 -0.3048)
			(stroke
				(width 0.1)
				(type default)
			)
			(layer "B.Fab")
		)
		(fp_line
			(start -0.67945 -0.3048)
			(end -0.67945 0.3048)
			(stroke
				(width 0.1)
				(type default)
			)
			(layer "B.Fab")
		)
		(fp_line
			(start 0.12065 -0.2794)
			(end -0.12065 -0.2794)
			(stroke
				(width 0.1)
				(type default)
			)
			(layer "B.Fab")
		)
		(fp_line
			(start -0.12065 -0.2794)
			(end -0.12065 -0.3048)
			(stroke
				(width 0.1)
				(type default)
			)
			(layer "B.Fab")
		)
		(fp_line
			(start 0.12065 0.2794)
			(end 0.12065 0.3048)
			(stroke
				(width 0.1)
				(type default)
			)
			(layer "B.Fab")
		)
		(fp_line
			(start -0.120396 0.2794)
			(end 0.12065 0.2794)
			(stroke
				(width 0.1)
				(type default)
			)
			(layer "B.Fab")
		)
		(fp_line
			(start 0.67945 0.3048)
			(end 0.67945 -0.305054)
			(stroke
				(width 0.1)
				(type default)
			)
			(layer "B.Fab")
		)
		(fp_line
			(start 0.12065 0.3048)
			(end 0.67945 0.3048)
			(stroke
				(width 0.1)
				(type default)
			)
			(layer "B.Fab")
		)
		(fp_line
			(start -0.120396 0.3048)
			(end -0.120396 0.2794)
			(stroke
				(width 0.1)
				(type default)
			)
			(layer "B.Fab")
		)
		(fp_line
			(start -0.67945 0.3048)
			(end -0.120396 0.3048)
			(stroke
				(width 0.1)
				(type default)
			)
			(layer "B.Fab")
		)
		(pad "1" smd circle
			(at 0.40005 0 270)
			(size 0 0)
			(layers "B.Cu" "B.Mask" "B.Paste")
			(net "PWRGD_DRAMPWRGD_CPU1_AB_LVC1_R2")
		)
		(pad "2" smd circle
			(at -0.40005 0 270)
			(size 0 0)
			(layers "B.Cu" "B.Mask" "B.Paste")
			(net "PVCCD_HV_CPU1")
		)
	)
	(footprint ""
		(layer "B.Cu")
		(at 54.880002 -159.734758 180)
		(property "Reference" "PC448_P1_1"
			(at 0 0 0)
			(layer "B.SilkS")
			(hide yes)
			(effects
				(font
					(size 1.27 1.27)
				)
				(justify mirror)
			)
		)
		(property "Value" ""
			(at 0 0 0)
			(layer "B.Fab")
			(effects
				(font
					(size 1.27 1.27)
				)
				(justify mirror)
			)
		)
		(duplicate_pad_numbers_are_jumpers no)
		(fp_line
			(start 1.524 0.762)
			(end 1.524 -0.762)
			(stroke
				(width 0.1524)
				(type default)
			)
			(layer "B.SilkS")
		)
		(fp_line
			(start 1.524 -0.762)
			(end -1.524 -0.762)
			(stroke
				(width 0.1524)
				(type default)
			)
			(layer "B.SilkS")
		)
		(fp_line
			(start -1.524 0.762)
			(end 1.524 0.762)
			(stroke
				(width 0.1524)
				(type default)
			)
			(layer "B.SilkS")
		)
		(fp_line
			(start -1.524 -0.762)
			(end -1.524 0.762)
			(stroke
				(width 0.1524)
				(type default)
			)
			(layer "B.SilkS")
		)
		(fp_line
			(start 1.1049 0.724916)
			(end -1.1049 0.724916)
			(stroke
				(width 0.1)
				(type default)
			)
			(layer "B.Fab")
		)
		(fp_line
			(start 1.1049 -0.724916)
			(end 1.1049 0.724916)
			(stroke
				(width 0.1)
				(type default)
			)
			(layer "B.Fab")
		)
		(fp_line
			(start -1.1049 0.724916)
			(end -1.1049 -0.724916)
			(stroke
				(width 0.1)
				(type default)
			)
			(layer "B.Fab")
		)
		(fp_line
			(start -1.1049 -0.724916)
			(end 1.1049 -0.724916)
			(stroke
				(width 0.1)
				(type default)
			)
			(layer "B.Fab")
		)
		(pad "1" smd rect
			(at 0.889 0 180)
			(size 1.016 1.27)
			(layers "B.Cu" "B.Mask" "B.Paste")
			(net "SW_P12V_PVCCINFAON_CPU1_FLT")
		)
		(pad "2" smd rect
			(at -0.889 0 180)
			(size 1.016 1.27)
			(layers "B.Cu" "B.Mask" "B.Paste")
			(net "GND")
		)
	)
	(footprint ""
		(layer "B.Cu")
		(at 312.592974 -319.069212 90)
		(property "Reference" "R2727"
			(at 0 0 90)
			(layer "B.SilkS")
			(hide yes)
			(effects
				(font
					(size 1.27 1.27)
				)
				(justify mirror)
			)
		)
		(property "Value" ""
			(at 0 0 90)
			(layer "B.Fab")
			(effects
				(font
					(size 1.27 1.27)
				)
				(justify mirror)
			)
		)
		(duplicate_pad_numbers_are_jumpers no)
		(fp_line
			(start 0.7874 -0.4064)
			(end -0.7874 -0.4064)
			(stroke
				(width 0.1524)
				(type default)
			)
			(layer "B.SilkS")
		)
		(fp_line
			(start -0.7874 -0.4064)
			(end -0.7874 0.4064)
			(stroke
				(width 0.1524)
				(type default)
			)
			(layer "B.SilkS")
		)
		(fp_line
			(start 0.7874 0.4064)
			(end 0.7874 -0.4064)
			(stroke
				(width 0.1524)
				(type default)
			)
			(layer "B.SilkS")
		)
		(fp_line
			(start -0.7874 0.4064)
			(end 0.7874 0.4064)
			(stroke
				(width 0.1524)
				(type default)
			)
			(layer "B.SilkS")
		)
		(fp_line
			(start 0.67945 -0.305054)
			(end 0.12065 -0.305054)
			(stroke
				(width 0.1)
				(type default)
			)
			(layer "B.Fab")
		)
		(fp_line
			(start 0.12065 -0.305054)
			(end 0.12065 -0.2794)
			(stroke
				(width 0.1)
				(type default)
			)
			(layer "B.Fab")
		)
		(fp_line
			(start -0.12065 -0.3048)
			(end -0.67945 -0.3048)
			(stroke
				(width 0.1)
				(type default)
			)
			(layer "B.Fab")
		)
		(fp_line
			(start -0.67945 -0.3048)
			(end -0.67945 0.3048)
			(stroke
				(width 0.1)
				(type default)
			)
			(layer "B.Fab")
		)
		(fp_line
			(start 0.12065 -0.2794)
			(end -0.12065 -0.2794)
			(stroke
				(width 0.1)
				(type default)
			)
			(layer "B.Fab")
		)
		(fp_line
			(start -0.12065 -0.2794)
			(end -0.12065 -0.3048)
			(stroke
				(width 0.1)
				(type default)
			)
			(layer "B.Fab")
		)
		(fp_line
			(start 0.12065 0.2794)
			(end 0.12065 0.3048)
			(stroke
				(width 0.1)
				(type default)
			)
			(layer "B.Fab")
		)
		(fp_line
			(start -0.120396 0.2794)
			(end 0.12065 0.2794)
			(stroke
				(width 0.1)
				(type default)
			)
			(layer "B.Fab")
		)
		(fp_line
			(start 0.67945 0.3048)
			(end 0.67945 -0.305054)
			(stroke
				(width 0.1)
				(type default)
			)
			(layer "B.Fab")
		)
		(fp_line
			(start 0.12065 0.3048)
			(end 0.67945 0.3048)
			(stroke
				(width 0.1)
				(type default)
			)
			(layer "B.Fab")
		)
		(fp_line
			(start -0.120396 0.3048)
			(end -0.120396 0.2794)
			(stroke
				(width 0.1)
				(type default)
			)
			(layer "B.Fab")
		)
		(fp_line
			(start -0.67945 0.3048)
			(end -0.120396 0.3048)
			(stroke
				(width 0.1)
				(type default)
			)
			(layer "B.Fab")
		)
		(pad "1" smd circle
			(at 0.40005 0 270)
			(size 0 0)
			(layers "B.Cu" "B.Mask" "B.Paste")
			(net "PWRGD_CHA_CPU0_DIMM2")
		)
		(pad "2" smd circle
			(at -0.40005 0 270)
			(size 0 0)
			(layers "B.Cu" "B.Mask" "B.Paste")
			(net "PWRGD_FAIL_CPU0_AB")
		)
	)
	(footprint ""
		(layer "B.Cu")
		(at 170.78579 -319.006728 180)
		(property "Reference" "R79"
			(at 0 0 0)
			(layer "B.SilkS")
			(hide yes)
			(effects
				(font
					(size 1.27 1.27)
				)
				(justify mirror)
			)
		)
		(property "Value" ""
			(at 0 0 0)
			(layer "B.Fab")
			(effects
				(font
					(size 1.27 1.27)
				)
				(justify mirror)
			)
		)
		(duplicate_pad_numbers_are_jumpers no)
		(fp_line
			(start 0.7874 0.4064)
			(end 0.7874 -0.4064)
			(stroke
				(width 0.1524)
				(type default)
			)
			(layer "B.SilkS")
		)
		(fp_line
			(start 0.7874 -0.4064)
			(end -0.7874 -0.4064)
			(stroke
				(width 0.1524)
				(type default)
			)
			(layer "B.SilkS")
		)
		(fp_line
			(start -0.7874 0.4064)
			(end 0.7874 0.4064)
			(stroke
				(width 0.1524)
				(type default)
			)
			(layer "B.SilkS")
		)
		(fp_line
			(start -0.7874 -0.4064)
			(end -0.7874 0.4064)
			(stroke
				(width 0.1524)
				(type default)
			)
			(layer "B.SilkS")
		)
		(fp_line
			(start 0.67945 0.3048)
			(end 0.67945 -0.305054)
			(stroke
				(width 0.1)
				(type default)
			)
			(layer "B.Fab")
		)
		(fp_line
			(start 0.67945 -0.305054)
			(end 0.12065 -0.305054)
			(stroke
				(width 0.1)
				(type default)
			)
			(layer "B.Fab")
		)
		(fp_line
			(start 0.12065 0.3048)
			(end 0.67945 0.3048)
			(stroke
				(width 0.1)
				(type default)
			)
			(layer "B.Fab")
		)
		(fp_line
			(start 0.12065 0.2794)
			(end 0.12065 0.3048)
			(stroke
				(width 0.1)
				(type default)
			)
			(layer "B.Fab")
		)
		(fp_line
			(start 0.12065 -0.2794)
			(end -0.12065 -0.2794)
			(stroke
				(width 0.1)
				(type default)
			)
			(layer "B.Fab")
		)
		(fp_line
			(start 0.12065 -0.305054)
			(end 0.12065 -0.2794)
			(stroke
				(width 0.1)
				(type default)
			)
			(layer "B.Fab")
		)
		(fp_line
			(start -0.120396 0.3048)
			(end -0.120396 0.2794)
			(stroke
				(width 0.1)
				(type default)
			)
			(layer "B.Fab")
		)
		(fp_line
			(start -0.120396 0.2794)
			(end 0.12065 0.2794)
			(stroke
				(width 0.1)
				(type default)
			)
			(layer "B.Fab")
		)
		(fp_line
			(start -0.12065 -0.2794)
			(end -0.12065 -0.3048)
			(stroke
				(width 0.1)
				(type default)
			)
			(layer "B.Fab")
		)
		(fp_line
			(start -0.12065 -0.3048)
			(end -0.67945 -0.3048)
			(stroke
				(width 0.1)
				(type default)
			)
			(layer "B.Fab")
		)
		(fp_line
			(start -0.67945 0.3048)
			(end -0.120396 0.3048)
			(stroke
				(width 0.1)
				(type default)
			)
			(layer "B.Fab")
		)
		(fp_line
			(start -0.67945 -0.3048)
			(end -0.67945 0.3048)
			(stroke
				(width 0.1)
				(type default)
			)
			(layer "B.Fab")
		)
		(pad "1" smd circle
			(at 0.40005 0)
			(size 0 0)
			(layers "B.Cu" "B.Mask" "B.Paste")
			(net "PD_CHE_CPU1_DIMM1_SAA")
		)
		(pad "2" smd circle
			(at -0.40005 0)
			(size 0 0)
			(layers "B.Cu" "B.Mask" "B.Paste")
			(net "GND")
		)
	)
	(footprint ""
		(layer "B.Cu")
		(at 231.52608 -118.760748 -90)
		(property "Reference" "R3637"
			(at 0 0 90)
			(layer "B.SilkS")
			(hide yes)
			(effects
				(font
					(size 1.27 1.27)
				)
				(justify mirror)
			)
		)
		(property "Value" ""
			(at 0 0 90)
			(layer "B.Fab")
			(effects
				(font
					(size 1.27 1.27)
				)
				(justify mirror)
			)
		)
		(duplicate_pad_numbers_are_jumpers no)
		(fp_line
			(start -0.7874 0.4064)
			(end 0.7874 0.4064)
			(stroke
				(width 0.1524)
				(type default)
			)
			(layer "B.SilkS")
		)
		(fp_line
			(start 0.7874 0.4064)
			(end 0.7874 -0.4064)
			(stroke
				(width 0.1524)
				(type default)
			)
			(layer "B.SilkS")
		)
		(fp_line
			(start -0.7874 -0.4064)
			(end -0.7874 0.4064)
			(stroke
				(width 0.1524)
				(type default)
			)
			(layer "B.SilkS")
		)
		(fp_line
			(start 0.7874 -0.4064)
			(end -0.7874 -0.4064)
			(stroke
				(width 0.1524)
				(type default)
			)
			(layer "B.SilkS")
		)
		(fp_line
			(start -0.67945 0.3048)
			(end -0.120396 0.3048)
			(stroke
				(width 0.1)
				(type default)
			)
			(layer "B.Fab")
		)
		(fp_line
			(start -0.120396 0.3048)
			(end -0.120396 0.2794)
			(stroke
				(width 0.1)
				(type default)
			)
			(layer "B.Fab")
		)
		(fp_line
			(start 0.12065 0.3048)
			(end 0.67945 0.3048)
			(stroke
				(width 0.1)
				(type default)
			)
			(layer "B.Fab")
		)
		(fp_line
			(start 0.67945 0.3048)
			(end 0.67945 -0.305054)
			(stroke
				(width 0.1)
				(type default)
			)
			(layer "B.Fab")
		)
		(fp_line
			(start -0.120396 0.2794)
			(end 0.12065 0.2794)
			(stroke
				(width 0.1)
				(type default)
			)
			(layer "B.Fab")
		)
		(fp_line
			(start 0.12065 0.2794)
			(end 0.12065 0.3048)
			(stroke
				(width 0.1)
				(type default)
			)
			(layer "B.Fab")
		)
		(fp_line
			(start -0.12065 -0.2794)
			(end -0.12065 -0.3048)
			(stroke
				(width 0.1)
				(type default)
			)
			(layer "B.Fab")
		)
		(fp_line
			(start 0.12065 -0.2794)
			(end -0.12065 -0.2794)
			(stroke
				(width 0.1)
				(type default)
			)
			(layer "B.Fab")
		)
		(fp_line
			(start -0.67945 -0.3048)
			(end -0.67945 0.3048)
			(stroke
				(width 0.1)
				(type default)
			)
			(layer "B.Fab")
		)
		(fp_line
			(start -0.12065 -0.3048)
			(end -0.67945 -0.3048)
			(stroke
				(width 0.1)
				(type default)
			)
			(layer "B.Fab")
		)
		(fp_line
			(start 0.12065 -0.305054)
			(end 0.12065 -0.2794)
			(stroke
				(width 0.1)
				(type default)
			)
			(layer "B.Fab")
		)
		(fp_line
			(start 0.67945 -0.305054)
			(end 0.12065 -0.305054)
			(stroke
				(width 0.1)
				(type default)
			)
			(layer "B.Fab")
		)
		(pad "1" smd circle
			(at 0.40005 0 90)
			(size 0 0)
			(layers "B.Cu" "B.Mask" "B.Paste")
			(net "OCP_SFF_CLK_OE_N")
		)
		(pad "2" smd circle
			(at -0.40005 0 90)
			(size 0 0)
			(layers "B.Cu" "B.Mask" "B.Paste")
			(net "FM_DB2000_12_OE_N")
		)
	)
	(footprint ""
		(layer "B.Cu")
		(at 178.871626 -415.633154 90)
		(property "Reference" "R2812"
			(at 0 0 90)
			(layer "B.SilkS")
			(hide yes)
			(effects
				(font
					(size 1.27 1.27)
				)
				(justify mirror)
			)
		)
		(property "Value" ""
			(at 0 0 90)
			(layer "B.Fab")
			(effects
				(font
					(size 1.27 1.27)
				)
				(justify mirror)
			)
		)
		(duplicate_pad_numbers_are_jumpers no)
		(fp_line
			(start 0.7874 -0.4064)
			(end -0.7874 -0.4064)
			(stroke
				(width 0.1524)
				(type default)
			)
			(layer "B.SilkS")
		)
		(fp_line
			(start -0.7874 -0.4064)
			(end -0.7874 0.4064)
			(stroke
				(width 0.1524)
				(type default)
			)
			(layer "B.SilkS")
		)
		(fp_line
			(start 0.7874 0.4064)
			(end 0.7874 -0.4064)
			(stroke
				(width 0.1524)
				(type default)
			)
			(layer "B.SilkS")
		)
		(fp_line
			(start -0.7874 0.4064)
			(end 0.7874 0.4064)
			(stroke
				(width 0.1524)
				(type default)
			)
			(layer "B.SilkS")
		)
		(fp_line
			(start 0.67945 -0.305054)
			(end 0.12065 -0.305054)
			(stroke
				(width 0.1)
				(type default)
			)
			(layer "B.Fab")
		)
		(fp_line
			(start 0.12065 -0.305054)
			(end 0.12065 -0.2794)
			(stroke
				(width 0.1)
				(type default)
			)
			(layer "B.Fab")
		)
		(fp_line
			(start -0.12065 -0.3048)
			(end -0.67945 -0.3048)
			(stroke
				(width 0.1)
				(type default)
			)
			(layer "B.Fab")
		)
		(fp_line
			(start -0.67945 -0.3048)
			(end -0.67945 0.3048)
			(stroke
				(width 0.1)
				(type default)
			)
			(layer "B.Fab")
		)
		(fp_line
			(start 0.12065 -0.2794)
			(end -0.12065 -0.2794)
			(stroke
				(width 0.1)
				(type default)
			)
			(layer "B.Fab")
		)
		(fp_line
			(start -0.12065 -0.2794)
			(end -0.12065 -0.3048)
			(stroke
				(width 0.1)
				(type default)
			)
			(layer "B.Fab")
		)
		(fp_line
			(start 0.12065 0.2794)
			(end 0.12065 0.3048)
			(stroke
				(width 0.1)
				(type default)
			)
			(layer "B.Fab")
		)
		(fp_line
			(start -0.120396 0.2794)
			(end 0.12065 0.2794)
			(stroke
				(width 0.1)
				(type default)
			)
			(layer "B.Fab")
		)
		(fp_line
			(start 0.67945 0.3048)
			(end 0.67945 -0.305054)
			(stroke
				(width 0.1)
				(type default)
			)
			(layer "B.Fab")
		)
		(fp_line
			(start 0.12065 0.3048)
			(end 0.67945 0.3048)
			(stroke
				(width 0.1)
				(type default)
			)
			(layer "B.Fab")
		)
		(fp_line
			(start -0.120396 0.3048)
			(end -0.120396 0.2794)
			(stroke
				(width 0.1)
				(type default)
			)
			(layer "B.Fab")
		)
		(fp_line
			(start -0.67945 0.3048)
			(end -0.120396 0.3048)
			(stroke
				(width 0.1)
				(type default)
			)
			(layer "B.Fab")
		)
		(pad "1" smd circle
			(at 0.40005 0 270)
			(size 0 0)
			(layers "B.Cu" "B.Mask" "B.Paste")
			(net "SMB_FAN_3V3AUX_BUF_SDA")
		)
		(pad "2" smd circle
			(at -0.40005 0 270)
			(size 0 0)
			(layers "B.Cu" "B.Mask" "B.Paste")
			(net "SMB_FAN_3V3AUX_BUF_R_SDA")
		)
	)
	(footprint ""
		(layer "B.Cu")
		(at 137.80262 -30.157928 -90)
		(property "Reference" "C2324"
			(at 0 0 90)
			(layer "B.SilkS")
			(hide yes)
			(effects
				(font
					(size 1.27 1.27)
				)
				(justify mirror)
			)
		)
		(property "Value" ""
			(at 0 0 90)
			(layer "B.Fab")
			(effects
				(font
					(size 1.27 1.27)
				)
				(justify mirror)
			)
		)
		(duplicate_pad_numbers_are_jumpers no)
		(fp_line
			(start -0.7874 0.4064)
			(end 0.7874 0.4064)
			(stroke
				(width 0.1524)
				(type default)
			)
			(layer "B.SilkS")
		)
		(fp_line
			(start 0.7874 0.4064)
			(end 0.7874 -0.4064)
			(stroke
				(width 0.1524)
				(type default)
			)
			(layer "B.SilkS")
		)
		(fp_line
			(start -0.7874 -0.4064)
			(end -0.7874 0.4064)
			(stroke
				(width 0.1524)
				(type default)
			)
			(layer "B.SilkS")
		)
		(fp_line
			(start 0.7874 -0.4064)
			(end -0.7874 -0.4064)
			(stroke
				(width 0.1524)
				(type default)
			)
			(layer "B.SilkS")
		)
		(fp_line
			(start -0.67945 0.3048)
			(end -0.120396 0.3048)
			(stroke
				(width 0.1)
				(type default)
			)
			(layer "B.Fab")
		)
		(fp_line
			(start -0.120396 0.3048)
			(end -0.120396 0.2794)
			(stroke
				(width 0.1)
				(type default)
			)
			(layer "B.Fab")
		)
		(fp_line
			(start 0.12065 0.3048)
			(end 0.67945 0.3048)
			(stroke
				(width 0.1)
				(type default)
			)
			(layer "B.Fab")
		)
		(fp_line
			(start 0.67945 0.3048)
			(end 0.67945 -0.305054)
			(stroke
				(width 0.1)
				(type default)
			)
			(layer "B.Fab")
		)
		(fp_line
			(start -0.120396 0.2794)
			(end 0.12065 0.2794)
			(stroke
				(width 0.1)
				(type default)
			)
			(layer "B.Fab")
		)
		(fp_line
			(start 0.12065 0.2794)
			(end 0.12065 0.3048)
			(stroke
				(width 0.1)
				(type default)
			)
			(layer "B.Fab")
		)
		(fp_line
			(start -0.12065 -0.2794)
			(end -0.12065 -0.3048)
			(stroke
				(width 0.1)
				(type default)
			)
			(layer "B.Fab")
		)
		(fp_line
			(start 0.12065 -0.2794)
			(end -0.12065 -0.2794)
			(stroke
				(width 0.1)
				(type default)
			)
			(layer "B.Fab")
		)
		(fp_line
			(start -0.67945 -0.3048)
			(end -0.67945 0.3048)
			(stroke
				(width 0.1)
				(type default)
			)
			(layer "B.Fab")
		)
		(fp_line
			(start -0.12065 -0.3048)
			(end -0.67945 -0.3048)
			(stroke
				(width 0.1)
				(type default)
			)
			(layer "B.Fab")
		)
		(fp_line
			(start 0.12065 -0.305054)
			(end 0.12065 -0.2794)
			(stroke
				(width 0.1)
				(type default)
			)
			(layer "B.Fab")
		)
		(fp_line
			(start 0.67945 -0.305054)
			(end 0.12065 -0.305054)
			(stroke
				(width 0.1)
				(type default)
			)
			(layer "B.Fab")
		)
		(pad "1" smd circle
			(at 0.40005 0 90)
			(size 0 0)
			(layers "B.Cu" "B.Mask" "B.Paste")
			(net "P3V3_AUX")
		)
		(pad "2" smd circle
			(at -0.40005 0 90)
			(size 0 0)
			(layers "B.Cu" "B.Mask" "B.Paste")
			(net "GND")
		)
	)
	(footprint ""
		(layer "B.Cu")
		(at 435.59857 -193.567304 -90)
		(property "Reference" "R839"
			(at 0 0 90)
			(layer "B.SilkS")
			(hide yes)
			(effects
				(font
					(size 1.27 1.27)
				)
				(justify mirror)
			)
		)
		(property "Value" ""
			(at 0 0 90)
			(layer "B.Fab")
			(effects
				(font
					(size 1.27 1.27)
				)
				(justify mirror)
			)
		)
		(duplicate_pad_numbers_are_jumpers no)
		(fp_line
			(start -0.7874 0.4064)
			(end 0.7874 0.4064)
			(stroke
				(width 0.1524)
				(type default)
			)
			(layer "B.SilkS")
		)
		(fp_line
			(start 0.7874 0.4064)
			(end 0.7874 -0.4064)
			(stroke
				(width 0.1524)
				(type default)
			)
			(layer "B.SilkS")
		)
		(fp_line
			(start -0.7874 -0.4064)
			(end -0.7874 0.4064)
			(stroke
				(width 0.1524)
				(type default)
			)
			(layer "B.SilkS")
		)
		(fp_line
			(start 0.7874 -0.4064)
			(end -0.7874 -0.4064)
			(stroke
				(width 0.1524)
				(type default)
			)
			(layer "B.SilkS")
		)
		(fp_line
			(start -0.67945 0.3048)
			(end -0.120396 0.3048)
			(stroke
				(width 0.1)
				(type default)
			)
			(layer "B.Fab")
		)
		(fp_line
			(start -0.120396 0.3048)
			(end -0.120396 0.2794)
			(stroke
				(width 0.1)
				(type default)
			)
			(layer "B.Fab")
		)
		(fp_line
			(start 0.12065 0.3048)
			(end 0.67945 0.3048)
			(stroke
				(width 0.1)
				(type default)
			)
			(layer "B.Fab")
		)
		(fp_line
			(start 0.67945 0.3048)
			(end 0.67945 -0.305054)
			(stroke
				(width 0.1)
				(type default)
			)
			(layer "B.Fab")
		)
		(fp_line
			(start -0.120396 0.2794)
			(end 0.12065 0.2794)
			(stroke
				(width 0.1)
				(type default)
			)
			(layer "B.Fab")
		)
		(fp_line
			(start 0.12065 0.2794)
			(end 0.12065 0.3048)
			(stroke
				(width 0.1)
				(type default)
			)
			(layer "B.Fab")
		)
		(fp_line
			(start -0.12065 -0.2794)
			(end -0.12065 -0.3048)
			(stroke
				(width 0.1)
				(type default)
			)
			(layer "B.Fab")
		)
		(fp_line
			(start 0.12065 -0.2794)
			(end -0.12065 -0.2794)
			(stroke
				(width 0.1)
				(type default)
			)
			(layer "B.Fab")
		)
		(fp_line
			(start -0.67945 -0.3048)
			(end -0.67945 0.3048)
			(stroke
				(width 0.1)
				(type default)
			)
			(layer "B.Fab")
		)
		(fp_line
			(start -0.12065 -0.3048)
			(end -0.67945 -0.3048)
			(stroke
				(width 0.1)
				(type default)
			)
			(layer "B.Fab")
		)
		(fp_line
			(start 0.12065 -0.305054)
			(end 0.12065 -0.2794)
			(stroke
				(width 0.1)
				(type default)
			)
			(layer "B.Fab")
		)
		(fp_line
			(start 0.67945 -0.305054)
			(end 0.12065 -0.305054)
			(stroke
				(width 0.1)
				(type default)
			)
			(layer "B.Fab")
		)
		(pad "1" smd circle
			(at 0.40005 0 90)
			(size 0 0)
			(layers "B.Cu" "B.Mask" "B.Paste")
			(net "PVCCD_HV_CPU0")
		)
		(pad "2" smd circle
			(at -0.40005 0 90)
			(size 0 0)
			(layers "B.Cu" "B.Mask" "B.Paste")
			(net "RST_M_GH_CPU0_FPGA_N")
		)
	)
	(footprint ""
		(layer "B.Cu")
		(at 297.876214 -321.549776 -90)
		(property "Reference" "C13"
			(at 0 0 90)
			(layer "B.SilkS")
			(hide yes)
			(effects
				(font
					(size 1.27 1.27)
				)
				(justify mirror)
			)
		)
		(property "Value" ""
			(at 0 0 90)
			(layer "B.Fab")
			(effects
				(font
					(size 1.27 1.27)
				)
				(justify mirror)
			)
		)
		(duplicate_pad_numbers_are_jumpers no)
		(fp_line
			(start -1.524 0.762)
			(end 1.524 0.762)
			(stroke
				(width 0.1524)
				(type default)
			)
			(layer "B.SilkS")
		)
		(fp_line
			(start 1.524 0.762)
			(end 1.524 -0.762)
			(stroke
				(width 0.1524)
				(type default)
			)
			(layer "B.SilkS")
		)
		(fp_line
			(start -1.524 -0.762)
			(end -1.524 0.762)
			(stroke
				(width 0.1524)
				(type default)
			)
			(layer "B.SilkS")
		)
		(fp_line
			(start 1.524 -0.762)
			(end -1.524 -0.762)
			(stroke
				(width 0.1524)
				(type default)
			)
			(layer "B.SilkS")
		)
		(fp_line
			(start -1.1049 0.724916)
			(end -1.1049 -0.724916)
			(stroke
				(width 0.1)
				(type default)
			)
			(layer "B.Fab")
		)
		(fp_line
			(start 1.1049 0.724916)
			(end -1.1049 0.724916)
			(stroke
				(width 0.1)
				(type default)
			)
			(layer "B.Fab")
		)
		(fp_line
			(start -1.1049 -0.724916)
			(end 1.1049 -0.724916)
			(stroke
				(width 0.1)
				(type default)
			)
			(layer "B.Fab")
		)
		(fp_line
			(start 1.1049 -0.724916)
			(end 1.1049 0.724916)
			(stroke
				(width 0.1)
				(type default)
			)
			(layer "B.Fab")
		)
		(pad "1" smd rect
			(at 0.889 0 270)
			(size 1.016 1.27)
			(layers "B.Cu" "B.Mask" "B.Paste")
			(net "P12V_S3_AUX_CPU0_NVDIMM")
		)
		(pad "2" smd rect
			(at -0.889 0 270)
			(size 1.016 1.27)
			(layers "B.Cu" "B.Mask" "B.Paste")
			(net "GND")
		)
	)
	(footprint ""
		(layer "B.Cu")
		(at 157.02788 -116.296948 180)
		(property "Reference" "R3480"
			(at 0 0 0)
			(layer "B.SilkS")
			(hide yes)
			(effects
				(font
					(size 1.27 1.27)
				)
				(justify mirror)
			)
		)
		(property "Value" ""
			(at 0 0 0)
			(layer "B.Fab")
			(effects
				(font
					(size 1.27 1.27)
				)
				(justify mirror)
			)
		)
		(duplicate_pad_numbers_are_jumpers no)
		(fp_line
			(start 0.7874 0.4064)
			(end 0.7874 -0.4064)
			(stroke
				(width 0.1524)
				(type default)
			)
			(layer "B.SilkS")
		)
		(fp_line
			(start 0.7874 -0.4064)
			(end -0.7874 -0.4064)
			(stroke
				(width 0.1524)
				(type default)
			)
			(layer "B.SilkS")
		)
		(fp_line
			(start -0.7874 0.4064)
			(end 0.7874 0.4064)
			(stroke
				(width 0.1524)
				(type default)
			)
			(layer "B.SilkS")
		)
		(fp_line
			(start -0.7874 -0.4064)
			(end -0.7874 0.4064)
			(stroke
				(width 0.1524)
				(type default)
			)
			(layer "B.SilkS")
		)
		(fp_line
			(start 0.67945 0.3048)
			(end 0.67945 -0.305054)
			(stroke
				(width 0.1)
				(type default)
			)
			(layer "B.Fab")
		)
		(fp_line
			(start 0.67945 -0.305054)
			(end 0.12065 -0.305054)
			(stroke
				(width 0.1)
				(type default)
			)
			(layer "B.Fab")
		)
		(fp_line
			(start 0.12065 0.3048)
			(end 0.67945 0.3048)
			(stroke
				(width 0.1)
				(type default)
			)
			(layer "B.Fab")
		)
		(fp_line
			(start 0.12065 0.2794)
			(end 0.12065 0.3048)
			(stroke
				(width 0.1)
				(type default)
			)
			(layer "B.Fab")
		)
		(fp_line
			(start 0.12065 -0.2794)
			(end -0.12065 -0.2794)
			(stroke
				(width 0.1)
				(type default)
			)
			(layer "B.Fab")
		)
		(fp_line
			(start 0.12065 -0.305054)
			(end 0.12065 -0.2794)
			(stroke
				(width 0.1)
				(type default)
			)
			(layer "B.Fab")
		)
		(fp_line
			(start -0.120396 0.3048)
			(end -0.120396 0.2794)
			(stroke
				(width 0.1)
				(type default)
			)
			(layer "B.Fab")
		)
		(fp_line
			(start -0.120396 0.2794)
			(end 0.12065 0.2794)
			(stroke
				(width 0.1)
				(type default)
			)
			(layer "B.Fab")
		)
		(fp_line
			(start -0.12065 -0.2794)
			(end -0.12065 -0.3048)
			(stroke
				(width 0.1)
				(type default)
			)
			(layer "B.Fab")
		)
		(fp_line
			(start -0.12065 -0.3048)
			(end -0.67945 -0.3048)
			(stroke
				(width 0.1)
				(type default)
			)
			(layer "B.Fab")
		)
		(fp_line
			(start -0.67945 0.3048)
			(end -0.120396 0.3048)
			(stroke
				(width 0.1)
				(type default)
			)
			(layer "B.Fab")
		)
		(fp_line
			(start -0.67945 -0.3048)
			(end -0.67945 0.3048)
			(stroke
				(width 0.1)
				(type default)
			)
			(layer "B.Fab")
		)
		(pad "1" smd circle
			(at 0.40005 0)
			(size 0 0)
			(layers "B.Cu" "B.Mask" "B.Paste")
			(net "GPU_BASE_HMC_READY_ISO")
		)
		(pad "2" smd circle
			(at -0.40005 0)
			(size 0 0)
			(layers "B.Cu" "B.Mask" "B.Paste")
			(net "GPU_BASE_HMC_READY_ISO_R")
		)
	)
	(footprint ""
		(layer "B.Cu")
		(at 110.874556 -416.030918 90)
		(property "Reference" "C2329"
			(at 0 0 90)
			(layer "B.SilkS")
			(hide yes)
			(effects
				(font
					(size 1.27 1.27)
				)
				(justify mirror)
			)
		)
		(property "Value" ""
			(at 0 0 90)
			(layer "B.Fab")
			(effects
				(font
					(size 1.27 1.27)
				)
				(justify mirror)
			)
		)
		(duplicate_pad_numbers_are_jumpers no)
		(fp_line
			(start 0.7874 -0.4064)
			(end -0.7874 -0.4064)
			(stroke
				(width 0.1524)
				(type default)
			)
			(layer "B.SilkS")
		)
		(fp_line
			(start -0.7874 -0.4064)
			(end -0.7874 0.4064)
			(stroke
				(width 0.1524)
				(type default)
			)
			(layer "B.SilkS")
		)
		(fp_line
			(start 0.7874 0.4064)
			(end 0.7874 -0.4064)
			(stroke
				(width 0.1524)
				(type default)
			)
			(layer "B.SilkS")
		)
		(fp_line
			(start -0.7874 0.4064)
			(end 0.7874 0.4064)
			(stroke
				(width 0.1524)
				(type default)
			)
			(layer "B.SilkS")
		)
		(fp_line
			(start 0.67945 -0.305054)
			(end 0.12065 -0.305054)
			(stroke
				(width 0.1)
				(type default)
			)
			(layer "B.Fab")
		)
		(fp_line
			(start 0.12065 -0.305054)
			(end 0.12065 -0.2794)
			(stroke
				(width 0.1)
				(type default)
			)
			(layer "B.Fab")
		)
		(fp_line
			(start -0.12065 -0.3048)
			(end -0.67945 -0.3048)
			(stroke
				(width 0.1)
				(type default)
			)
			(layer "B.Fab")
		)
		(fp_line
			(start -0.67945 -0.3048)
			(end -0.67945 0.3048)
			(stroke
				(width 0.1)
				(type default)
			)
			(layer "B.Fab")
		)
		(fp_line
			(start 0.12065 -0.2794)
			(end -0.12065 -0.2794)
			(stroke
				(width 0.1)
				(type default)
			)
			(layer "B.Fab")
		)
		(fp_line
			(start -0.12065 -0.2794)
			(end -0.12065 -0.3048)
			(stroke
				(width 0.1)
				(type default)
			)
			(layer "B.Fab")
		)
		(fp_line
			(start 0.12065 0.2794)
			(end 0.12065 0.3048)
			(stroke
				(width 0.1)
				(type default)
			)
			(layer "B.Fab")
		)
		(fp_line
			(start -0.120396 0.2794)
			(end 0.12065 0.2794)
			(stroke
				(width 0.1)
				(type default)
			)
			(layer "B.Fab")
		)
		(fp_line
			(start 0.67945 0.3048)
			(end 0.67945 -0.305054)
			(stroke
				(width 0.1)
				(type default)
			)
			(layer "B.Fab")
		)
		(fp_line
			(start 0.12065 0.3048)
			(end 0.67945 0.3048)
			(stroke
				(width 0.1)
				(type default)
			)
			(layer "B.Fab")
		)
		(fp_line
			(start -0.120396 0.3048)
			(end -0.120396 0.2794)
			(stroke
				(width 0.1)
				(type default)
			)
			(layer "B.Fab")
		)
		(fp_line
			(start -0.67945 0.3048)
			(end -0.120396 0.3048)
			(stroke
				(width 0.1)
				(type default)
			)
			(layer "B.Fab")
		)
		(pad "1" smd circle
			(at 0.40005 0 270)
			(size 0 0)
			(layers "B.Cu" "B.Mask" "B.Paste")
			(net "P3V3_9ZXL045_VDD")
		)
		(pad "2" smd circle
			(at -0.40005 0 270)
			(size 0 0)
			(layers "B.Cu" "B.Mask" "B.Paste")
			(net "GND")
		)
	)
	(footprint ""
		(layer "B.Cu")
		(at 94.596712 -334.752442 -90)
		(property "Reference" "PR328"
			(at 0 0 90)
			(layer "B.SilkS")
			(hide yes)
			(effects
				(font
					(size 1.27 1.27)
				)
				(justify mirror)
			)
		)
		(property "Value" ""
			(at 0 0 90)
			(layer "B.Fab")
			(effects
				(font
					(size 1.27 1.27)
				)
				(justify mirror)
			)
		)
		(duplicate_pad_numbers_are_jumpers no)
		(fp_line
			(start -0.7874 0.4064)
			(end 0.7874 0.4064)
			(stroke
				(width 0.1524)
				(type default)
			)
			(layer "B.SilkS")
		)
		(fp_line
			(start 0.7874 0.4064)
			(end 0.7874 -0.4064)
			(stroke
				(width 0.1524)
				(type default)
			)
			(layer "B.SilkS")
		)
		(fp_line
			(start -0.7874 -0.4064)
			(end -0.7874 0.4064)
			(stroke
				(width 0.1524)
				(type default)
			)
			(layer "B.SilkS")
		)
		(fp_line
			(start 0.7874 -0.4064)
			(end -0.7874 -0.4064)
			(stroke
				(width 0.1524)
				(type default)
			)
			(layer "B.SilkS")
		)
		(fp_line
			(start -0.67945 0.3048)
			(end -0.120396 0.3048)
			(stroke
				(width 0.1)
				(type default)
			)
			(layer "B.Fab")
		)
		(fp_line
			(start -0.120396 0.3048)
			(end -0.120396 0.2794)
			(stroke
				(width 0.1)
				(type default)
			)
			(layer "B.Fab")
		)
		(fp_line
			(start 0.12065 0.3048)
			(end 0.67945 0.3048)
			(stroke
				(width 0.1)
				(type default)
			)
			(layer "B.Fab")
		)
		(fp_line
			(start 0.67945 0.3048)
			(end 0.67945 -0.305054)
			(stroke
				(width 0.1)
				(type default)
			)
			(layer "B.Fab")
		)
		(fp_line
			(start -0.120396 0.2794)
			(end 0.12065 0.2794)
			(stroke
				(width 0.1)
				(type default)
			)
			(layer "B.Fab")
		)
		(fp_line
			(start 0.12065 0.2794)
			(end 0.12065 0.3048)
			(stroke
				(width 0.1)
				(type default)
			)
			(layer "B.Fab")
		)
		(fp_line
			(start -0.12065 -0.2794)
			(end -0.12065 -0.3048)
			(stroke
				(width 0.1)
				(type default)
			)
			(layer "B.Fab")
		)
		(fp_line
			(start 0.12065 -0.2794)
			(end -0.12065 -0.2794)
			(stroke
				(width 0.1)
				(type default)
			)
			(layer "B.Fab")
		)
		(fp_line
			(start -0.67945 -0.3048)
			(end -0.67945 0.3048)
			(stroke
				(width 0.1)
				(type default)
			)
			(layer "B.Fab")
		)
		(fp_line
			(start -0.12065 -0.3048)
			(end -0.67945 -0.3048)
			(stroke
				(width 0.1)
				(type default)
			)
			(layer "B.Fab")
		)
		(fp_line
			(start 0.12065 -0.305054)
			(end 0.12065 -0.2794)
			(stroke
				(width 0.1)
				(type default)
			)
			(layer "B.Fab")
		)
		(fp_line
			(start 0.67945 -0.305054)
			(end 0.12065 -0.305054)
			(stroke
				(width 0.1)
				(type default)
			)
			(layer "B.Fab")
		)
		(pad "1" smd circle
			(at 0.40005 0 90)
			(size 0 0)
			(layers "B.Cu" "B.Mask" "B.Paste")
			(net "PVCCIN_CPU1_PVCC")
		)
		(pad "2" smd circle
			(at -0.40005 0 90)
			(size 0 0)
			(layers "B.Cu" "B.Mask" "B.Paste")
			(net "PVCCIN_CPU1_VDD1")
		)
	)
	(footprint ""
		(layer "B.Cu")
		(at 291.588698 -152.176988)
		(property "Reference" "R691"
			(at 0 0 0)
			(layer "B.SilkS")
			(hide yes)
			(effects
				(font
					(size 1.27 1.27)
				)
				(justify mirror)
			)
		)
		(property "Value" ""
			(at 0 0 0)
			(layer "B.Fab")
			(effects
				(font
					(size 1.27 1.27)
				)
				(justify mirror)
			)
		)
		(duplicate_pad_numbers_are_jumpers no)
		(fp_line
			(start -0.7874 -0.4064)
			(end -0.7874 0.4064)
			(stroke
				(width 0.1524)
				(type default)
			)
			(layer "B.SilkS")
		)
		(fp_line
			(start -0.7874 0.4064)
			(end 0.7874 0.4064)
			(stroke
				(width 0.1524)
				(type default)
			)
			(layer "B.SilkS")
		)
		(fp_line
			(start 0.7874 -0.4064)
			(end -0.7874 -0.4064)
			(stroke
				(width 0.1524)
				(type default)
			)
			(layer "B.SilkS")
		)
		(fp_line
			(start 0.7874 0.4064)
			(end 0.7874 -0.4064)
			(stroke
				(width 0.1524)
				(type default)
			)
			(layer "B.SilkS")
		)
		(fp_line
			(start -0.67945 -0.3048)
			(end -0.67945 0.3048)
			(stroke
				(width 0.1)
				(type default)
			)
			(layer "B.Fab")
		)
		(fp_line
			(start -0.67945 0.3048)
			(end -0.120396 0.3048)
			(stroke
				(width 0.1)
				(type default)
			)
			(layer "B.Fab")
		)
		(fp_line
			(start -0.12065 -0.3048)
			(end -0.67945 -0.3048)
			(stroke
				(width 0.1)
				(type default)
			)
			(layer "B.Fab")
		)
		(fp_line
			(start -0.12065 -0.2794)
			(end -0.12065 -0.3048)
			(stroke
				(width 0.1)
				(type default)
			)
			(layer "B.Fab")
		)
		(fp_line
			(start -0.120396 0.2794)
			(end 0.12065 0.2794)
			(stroke
				(width 0.1)
				(type default)
			)
			(layer "B.Fab")
		)
		(fp_line
			(start -0.120396 0.3048)
			(end -0.120396 0.2794)
			(stroke
				(width 0.1)
				(type default)
			)
			(layer "B.Fab")
		)
		(fp_line
			(start 0.12065 -0.305054)
			(end 0.12065 -0.2794)
			(stroke
				(width 0.1)
				(type default)
			)
			(layer "B.Fab")
		)
		(fp_line
			(start 0.12065 -0.2794)
			(end -0.12065 -0.2794)
			(stroke
				(width 0.1)
				(type default)
			)
			(layer "B.Fab")
		)
		(fp_line
			(start 0.12065 0.2794)
			(end 0.12065 0.3048)
			(stroke
				(width 0.1)
				(type default)
			)
			(layer "B.Fab")
		)
		(fp_line
			(start 0.12065 0.3048)
			(end 0.67945 0.3048)
			(stroke
				(width 0.1)
				(type default)
			)
			(layer "B.Fab")
		)
		(fp_line
			(start 0.67945 -0.305054)
			(end 0.12065 -0.305054)
			(stroke
				(width 0.1)
				(type default)
			)
			(layer "B.Fab")
		)
		(fp_line
			(start 0.67945 0.3048)
			(end 0.67945 -0.305054)
			(stroke
				(width 0.1)
				(type default)
			)
			(layer "B.Fab")
		)
		(pad "1" smd circle
			(at 0.40005 0 180)
			(size 0 0)
			(layers "B.Cu" "B.Mask" "B.Paste")
			(net "I3C_SPD_DDRABCD_CPU0_LVC1_R_SCL")
		)
		(pad "2" smd circle
			(at -0.40005 0 180)
			(size 0 0)
			(layers "B.Cu" "B.Mask" "B.Paste")
			(net "I3C_SPD_DDRABCD_CPU0_LVC1_SCL")
		)
	)
	(footprint ""
		(layer "B.Cu")
		(at 315.284358 -230.50119)
		(property "Reference" "R1241"
			(at 0 0 0)
			(layer "B.SilkS")
			(hide yes)
			(effects
				(font
					(size 1.27 1.27)
				)
				(justify mirror)
			)
		)
		(property "Value" ""
			(at 0 0 0)
			(layer "B.Fab")
			(effects
				(font
					(size 1.27 1.27)
				)
				(justify mirror)
			)
		)
		(duplicate_pad_numbers_are_jumpers no)
		(fp_line
			(start -0.7874 -0.4064)
			(end -0.7874 0.4064)
			(stroke
				(width 0.1524)
				(type default)
			)
			(layer "B.SilkS")
		)
		(fp_line
			(start -0.7874 0.4064)
			(end 0.7874 0.4064)
			(stroke
				(width 0.1524)
				(type default)
			)
			(layer "B.SilkS")
		)
		(fp_line
			(start 0.7874 -0.4064)
			(end -0.7874 -0.4064)
			(stroke
				(width 0.1524)
				(type default)
			)
			(layer "B.SilkS")
		)
		(fp_line
			(start 0.7874 0.4064)
			(end 0.7874 -0.4064)
			(stroke
				(width 0.1524)
				(type default)
			)
			(layer "B.SilkS")
		)
		(fp_line
			(start -0.67945 -0.3048)
			(end -0.67945 0.3048)
			(stroke
				(width 0.1)
				(type default)
			)
			(layer "B.Fab")
		)
		(fp_line
			(start -0.67945 0.3048)
			(end -0.120396 0.3048)
			(stroke
				(width 0.1)
				(type default)
			)
			(layer "B.Fab")
		)
		(fp_line
			(start -0.12065 -0.3048)
			(end -0.67945 -0.3048)
			(stroke
				(width 0.1)
				(type default)
			)
			(layer "B.Fab")
		)
		(fp_line
			(start -0.12065 -0.2794)
			(end -0.12065 -0.3048)
			(stroke
				(width 0.1)
				(type default)
			)
			(layer "B.Fab")
		)
		(fp_line
			(start -0.120396 0.2794)
			(end 0.12065 0.2794)
			(stroke
				(width 0.1)
				(type default)
			)
			(layer "B.Fab")
		)
		(fp_line
			(start -0.120396 0.3048)
			(end -0.120396 0.2794)
			(stroke
				(width 0.1)
				(type default)
			)
			(layer "B.Fab")
		)
		(fp_line
			(start 0.12065 -0.305054)
			(end 0.12065 -0.2794)
			(stroke
				(width 0.1)
				(type default)
			)
			(layer "B.Fab")
		)
		(fp_line
			(start 0.12065 -0.2794)
			(end -0.12065 -0.2794)
			(stroke
				(width 0.1)
				(type default)
			)
			(layer "B.Fab")
		)
		(fp_line
			(start 0.12065 0.2794)
			(end 0.12065 0.3048)
			(stroke
				(width 0.1)
				(type default)
			)
			(layer "B.Fab")
		)
		(fp_line
			(start 0.12065 0.3048)
			(end 0.67945 0.3048)
			(stroke
				(width 0.1)
				(type default)
			)
			(layer "B.Fab")
		)
		(fp_line
			(start 0.67945 -0.305054)
			(end 0.12065 -0.305054)
			(stroke
				(width 0.1)
				(type default)
			)
			(layer "B.Fab")
		)
		(fp_line
			(start 0.67945 0.3048)
			(end 0.67945 -0.305054)
			(stroke
				(width 0.1)
				(type default)
			)
			(layer "B.Fab")
		)
		(pad "1" smd circle
			(at 0.40005 0 180)
			(size 0 0)
			(layers "B.Cu" "B.Mask" "B.Paste")
			(net "H_PMAX_TRIGGER_IO_CPU0")
		)
		(pad "2" smd circle
			(at -0.40005 0 180)
			(size 0 0)
			(layers "B.Cu" "B.Mask" "B.Paste")
			(net "GND")
		)
	)
	(footprint ""
		(layer "B.Cu")
		(at 62.996572 -159.87268)
		(property "Reference" "PC457_P1_1"
			(at 0 0 0)
			(layer "B.SilkS")
			(hide yes)
			(effects
				(font
					(size 1.27 1.27)
				)
				(justify mirror)
			)
		)
		(property "Value" ""
			(at 0 0 0)
			(layer "B.Fab")
			(effects
				(font
					(size 1.27 1.27)
				)
				(justify mirror)
			)
		)
		(duplicate_pad_numbers_are_jumpers no)
		(fp_line
			(start -1.524 -0.762)
			(end -1.524 0.762)
			(stroke
				(width 0.1524)
				(type default)
			)
			(layer "B.SilkS")
		)
		(fp_line
			(start -1.524 0.762)
			(end 1.524 0.762)
			(stroke
				(width 0.1524)
				(type default)
			)
			(layer "B.SilkS")
		)
		(fp_line
			(start 1.524 -0.762)
			(end -1.524 -0.762)
			(stroke
				(width 0.1524)
				(type default)
			)
			(layer "B.SilkS")
		)
		(fp_line
			(start 1.524 0.762)
			(end 1.524 -0.762)
			(stroke
				(width 0.1524)
				(type default)
			)
			(layer "B.SilkS")
		)
		(fp_line
			(start -1.1049 -0.724916)
			(end 1.1049 -0.724916)
			(stroke
				(width 0.1)
				(type default)
			)
			(layer "B.Fab")
		)
		(fp_line
			(start -1.1049 0.724916)
			(end -1.1049 -0.724916)
			(stroke
				(width 0.1)
				(type default)
			)
			(layer "B.Fab")
		)
		(fp_line
			(start 1.1049 -0.724916)
			(end 1.1049 0.724916)
			(stroke
				(width 0.1)
				(type default)
			)
			(layer "B.Fab")
		)
		(fp_line
			(start 1.1049 0.724916)
			(end -1.1049 0.724916)
			(stroke
				(width 0.1)
				(type default)
			)
			(layer "B.Fab")
		)
		(pad "1" smd rect
			(at 0.889 0)
			(size 1.016 1.27)
			(layers "B.Cu" "B.Mask" "B.Paste")
			(net "PVCCINFAON_CPU1")
		)
		(pad "2" smd rect
			(at -0.889 0)
			(size 1.016 1.27)
			(layers "B.Cu" "B.Mask" "B.Paste")
			(net "GND")
		)
	)
	(footprint ""
		(layer "B.Cu")
		(at 176.955704 -112.97539)
		(property "Reference" "C1934"
			(at 0 0 0)
			(layer "B.SilkS")
			(hide yes)
			(effects
				(font
					(size 1.27 1.27)
				)
				(justify mirror)
			)
		)
		(property "Value" ""
			(at 0 0 0)
			(layer "B.Fab")
			(effects
				(font
					(size 1.27 1.27)
				)
				(justify mirror)
			)
		)
		(duplicate_pad_numbers_are_jumpers no)
		(fp_line
			(start -0.69215 -0.2921)
			(end -0.69215 0.2921)
			(stroke
				(width 0.1524)
				(type default)
			)
			(layer "B.SilkS")
		)
		(fp_line
			(start -0.69215 0.2921)
			(end 0.69215 0.2921)
			(stroke
				(width 0.1524)
				(type default)
			)
			(layer "B.SilkS")
		)
		(fp_line
			(start 0.69215 -0.2921)
			(end -0.69215 -0.2921)
			(stroke
				(width 0.1524)
				(type default)
			)
			(layer "B.SilkS")
		)
		(fp_line
			(start 0.69215 0.2921)
			(end 0.69215 -0.2921)
			(stroke
				(width 0.1524)
				(type default)
			)
			(layer "B.SilkS")
		)
		(fp_line
			(start -0.51435 -0.2794)
			(end -0.51435 0.2794)
			(stroke
				(width 0.1)
				(type default)
			)
			(layer "B.Fab")
		)
		(fp_line
			(start -0.51435 0.2794)
			(end 0.51435 0.2794)
			(stroke
				(width 0.1)
				(type default)
			)
			(layer "B.Fab")
		)
		(fp_line
			(start 0.51435 -0.2794)
			(end -0.51435 -0.2794)
			(stroke
				(width 0.1)
				(type default)
			)
			(layer "B.Fab")
		)
		(fp_line
			(start 0.51435 0.2794)
			(end 0.51435 -0.2794)
			(stroke
				(width 0.1)
				(type default)
			)
			(layer "B.Fab")
		)
		(pad "1" smd circle
			(at 0.40005 0 180)
			(size 0 0)
			(layers "B.Cu" "B.Mask" "B.Paste")
			(net "VCC_PLD_CORE")
		)
		(pad "2" smd circle
			(at -0.40005 0 180)
			(size 0 0)
			(layers "B.Cu" "B.Mask" "B.Paste")
			(net "GND")
		)
		(zone
			(layer "B.Cu")
			(hatch none 0.5)
			(connect_pads
				(clearance 0)
			)
			(min_thickness 0.25)
			(keepout
				(tracks not_allowed)
				(vias allowed)
				(pads allowed)
				(copperpour not_allowed)
				(footprints allowed)
			)
			(placement
				(enabled no)
				(sheetname "")
			)
			(fill
				(thermal_gap 0.5)
				(thermal_bridge_width 0.5)
				(island_removal_mode 0)
			)
			(polygon
				(pts
					(xy 177.146204 -112.88776) (xy 177.054764 -112.829594) (xy 176.855374 -112.829594) (xy 176.765204 -112.88776)
					(xy 176.765204 -113.06302) (xy 176.855374 -113.12144) (xy 177.054764 -113.12144) (xy 177.146204 -113.063274)
				)
			)
		)
	)
	(footprint ""
		(layer "B.Cu")
		(at 321.039998 -188.96711 -90)
		(property "Reference" "R277"
			(at 0 0 90)
			(layer "B.SilkS")
			(hide yes)
			(effects
				(font
					(size 1.27 1.27)
				)
				(justify mirror)
			)
		)
		(property "Value" ""
			(at 0 0 90)
			(layer "B.Fab")
			(effects
				(font
					(size 1.27 1.27)
				)
				(justify mirror)
			)
		)
		(duplicate_pad_numbers_are_jumpers no)
		(fp_line
			(start -0.7874 0.4064)
			(end 0.7874 0.4064)
			(stroke
				(width 0.1524)
				(type default)
			)
			(layer "B.SilkS")
		)
		(fp_line
			(start 0.7874 0.4064)
			(end 0.7874 -0.4064)
			(stroke
				(width 0.1524)
				(type default)
			)
			(layer "B.SilkS")
		)
		(fp_line
			(start -0.7874 -0.4064)
			(end -0.7874 0.4064)
			(stroke
				(width 0.1524)
				(type default)
			)
			(layer "B.SilkS")
		)
		(fp_line
			(start 0.7874 -0.4064)
			(end -0.7874 -0.4064)
			(stroke
				(width 0.1524)
				(type default)
			)
			(layer "B.SilkS")
		)
		(fp_line
			(start -0.67945 0.3048)
			(end -0.120396 0.3048)
			(stroke
				(width 0.1)
				(type default)
			)
			(layer "B.Fab")
		)
		(fp_line
			(start -0.120396 0.3048)
			(end -0.120396 0.2794)
			(stroke
				(width 0.1)
				(type default)
			)
			(layer "B.Fab")
		)
		(fp_line
			(start 0.12065 0.3048)
			(end 0.67945 0.3048)
			(stroke
				(width 0.1)
				(type default)
			)
			(layer "B.Fab")
		)
		(fp_line
			(start 0.67945 0.3048)
			(end 0.67945 -0.305054)
			(stroke
				(width 0.1)
				(type default)
			)
			(layer "B.Fab")
		)
		(fp_line
			(start -0.120396 0.2794)
			(end 0.12065 0.2794)
			(stroke
				(width 0.1)
				(type default)
			)
			(layer "B.Fab")
		)
		(fp_line
			(start 0.12065 0.2794)
			(end 0.12065 0.3048)
			(stroke
				(width 0.1)
				(type default)
			)
			(layer "B.Fab")
		)
		(fp_line
			(start -0.12065 -0.2794)
			(end -0.12065 -0.3048)
			(stroke
				(width 0.1)
				(type default)
			)
			(layer "B.Fab")
		)
		(fp_line
			(start 0.12065 -0.2794)
			(end -0.12065 -0.2794)
			(stroke
				(width 0.1)
				(type default)
			)
			(layer "B.Fab")
		)
		(fp_line
			(start -0.67945 -0.3048)
			(end -0.67945 0.3048)
			(stroke
				(width 0.1)
				(type default)
			)
			(layer "B.Fab")
		)
		(fp_line
			(start -0.12065 -0.3048)
			(end -0.67945 -0.3048)
			(stroke
				(width 0.1)
				(type default)
			)
			(layer "B.Fab")
		)
		(fp_line
			(start 0.12065 -0.305054)
			(end 0.12065 -0.2794)
			(stroke
				(width 0.1)
				(type default)
			)
			(layer "B.Fab")
		)
		(fp_line
			(start 0.67945 -0.305054)
			(end 0.12065 -0.305054)
			(stroke
				(width 0.1)
				(type default)
			)
			(layer "B.Fab")
		)
		(pad "1" smd circle
			(at 0.40005 0 90)
			(size 0 0)
			(layers "B.Cu" "B.Mask" "B.Paste")
			(net "PVNN_TERM_CPU0")
		)
		(pad "2" smd circle
			(at -0.40005 0 90)
			(size 0 0)
			(layers "B.Cu" "B.Mask" "B.Paste")
			(net "PU_CPU0_FRMAGENT")
		)
	)
	(footprint ""
		(layer "B.Cu")
		(at 376.694446 -78.551278 180)
		(property "Reference" "PR1653"
			(at 0 0 0)
			(layer "B.SilkS")
			(hide yes)
			(effects
				(font
					(size 1.27 1.27)
				)
				(justify mirror)
			)
		)
		(property "Value" ""
			(at 0 0 0)
			(layer "B.Fab")
			(effects
				(font
					(size 1.27 1.27)
				)
				(justify mirror)
			)
		)
		(duplicate_pad_numbers_are_jumpers no)
		(fp_line
			(start 0.7874 0.4064)
			(end 0.7874 -0.4064)
			(stroke
				(width 0.1524)
				(type default)
			)
			(layer "B.SilkS")
		)
		(fp_line
			(start 0.7874 -0.4064)
			(end -0.7874 -0.4064)
			(stroke
				(width 0.1524)
				(type default)
			)
			(layer "B.SilkS")
		)
		(fp_line
			(start -0.7874 0.4064)
			(end 0.7874 0.4064)
			(stroke
				(width 0.1524)
				(type default)
			)
			(layer "B.SilkS")
		)
		(fp_line
			(start -0.7874 -0.4064)
			(end -0.7874 0.4064)
			(stroke
				(width 0.1524)
				(type default)
			)
			(layer "B.SilkS")
		)
		(fp_line
			(start 0.67945 0.3048)
			(end 0.67945 -0.305054)
			(stroke
				(width 0.1)
				(type default)
			)
			(layer "B.Fab")
		)
		(fp_line
			(start 0.67945 -0.305054)
			(end 0.12065 -0.305054)
			(stroke
				(width 0.1)
				(type default)
			)
			(layer "B.Fab")
		)
		(fp_line
			(start 0.12065 0.3048)
			(end 0.67945 0.3048)
			(stroke
				(width 0.1)
				(type default)
			)
			(layer "B.Fab")
		)
		(fp_line
			(start 0.12065 0.2794)
			(end 0.12065 0.3048)
			(stroke
				(width 0.1)
				(type default)
			)
			(layer "B.Fab")
		)
		(fp_line
			(start 0.12065 -0.2794)
			(end -0.12065 -0.2794)
			(stroke
				(width 0.1)
				(type default)
			)
			(layer "B.Fab")
		)
		(fp_line
			(start 0.12065 -0.305054)
			(end 0.12065 -0.2794)
			(stroke
				(width 0.1)
				(type default)
			)
			(layer "B.Fab")
		)
		(fp_line
			(start -0.120396 0.3048)
			(end -0.120396 0.2794)
			(stroke
				(width 0.1)
				(type default)
			)
			(layer "B.Fab")
		)
		(fp_line
			(start -0.120396 0.2794)
			(end 0.12065 0.2794)
			(stroke
				(width 0.1)
				(type default)
			)
			(layer "B.Fab")
		)
		(fp_line
			(start -0.12065 -0.2794)
			(end -0.12065 -0.3048)
			(stroke
				(width 0.1)
				(type default)
			)
			(layer "B.Fab")
		)
		(fp_line
			(start -0.12065 -0.3048)
			(end -0.67945 -0.3048)
			(stroke
				(width 0.1)
				(type default)
			)
			(layer "B.Fab")
		)
		(fp_line
			(start -0.67945 0.3048)
			(end -0.120396 0.3048)
			(stroke
				(width 0.1)
				(type default)
			)
			(layer "B.Fab")
		)
		(fp_line
			(start -0.67945 -0.3048)
			(end -0.67945 0.3048)
			(stroke
				(width 0.1)
				(type default)
			)
			(layer "B.Fab")
		)
		(pad "1" smd circle
			(at 0.40005 0)
			(size 0 0)
			(layers "B.Cu" "B.Mask" "B.Paste")
			(net "P1V8_PCH_AUX")
		)
		(pad "2" smd circle
			(at -0.40005 0)
			(size 0 0)
			(layers "B.Cu" "B.Mask" "B.Paste")
			(net "GND")
		)
	)
	(footprint ""
		(layer "B.Cu")
		(at 252.222 -98.389948 180)
		(property "Reference" "C1311"
			(at 0 0 0)
			(layer "B.SilkS")
			(hide yes)
			(effects
				(font
					(size 1.27 1.27)
				)
				(justify mirror)
			)
		)
		(property "Value" ""
			(at 0 0 0)
			(layer "B.Fab")
			(effects
				(font
					(size 1.27 1.27)
				)
				(justify mirror)
			)
		)
		(duplicate_pad_numbers_are_jumpers no)
		(fp_line
			(start 0.7874 0.4064)
			(end 0.7874 -0.4064)
			(stroke
				(width 0.1524)
				(type default)
			)
			(layer "B.SilkS")
		)
		(fp_line
			(start 0.7874 -0.4064)
			(end -0.7874 -0.4064)
			(stroke
				(width 0.1524)
				(type default)
			)
			(layer "B.SilkS")
		)
		(fp_line
			(start -0.7874 0.4064)
			(end 0.7874 0.4064)
			(stroke
				(width 0.1524)
				(type default)
			)
			(layer "B.SilkS")
		)
		(fp_line
			(start -0.7874 -0.4064)
			(end -0.7874 0.4064)
			(stroke
				(width 0.1524)
				(type default)
			)
			(layer "B.SilkS")
		)
		(fp_line
			(start 0.67945 0.3048)
			(end 0.67945 -0.305054)
			(stroke
				(width 0.1)
				(type default)
			)
			(layer "B.Fab")
		)
		(fp_line
			(start 0.67945 -0.305054)
			(end 0.12065 -0.305054)
			(stroke
				(width 0.1)
				(type default)
			)
			(layer "B.Fab")
		)
		(fp_line
			(start 0.12065 0.3048)
			(end 0.67945 0.3048)
			(stroke
				(width 0.1)
				(type default)
			)
			(layer "B.Fab")
		)
		(fp_line
			(start 0.12065 0.2794)
			(end 0.12065 0.3048)
			(stroke
				(width 0.1)
				(type default)
			)
			(layer "B.Fab")
		)
		(fp_line
			(start 0.12065 -0.2794)
			(end -0.12065 -0.2794)
			(stroke
				(width 0.1)
				(type default)
			)
			(layer "B.Fab")
		)
		(fp_line
			(start 0.12065 -0.305054)
			(end 0.12065 -0.2794)
			(stroke
				(width 0.1)
				(type default)
			)
			(layer "B.Fab")
		)
		(fp_line
			(start -0.120396 0.3048)
			(end -0.120396 0.2794)
			(stroke
				(width 0.1)
				(type default)
			)
			(layer "B.Fab")
		)
		(fp_line
			(start -0.120396 0.2794)
			(end 0.12065 0.2794)
			(stroke
				(width 0.1)
				(type default)
			)
			(layer "B.Fab")
		)
		(fp_line
			(start -0.12065 -0.2794)
			(end -0.12065 -0.3048)
			(stroke
				(width 0.1)
				(type default)
			)
			(layer "B.Fab")
		)
		(fp_line
			(start -0.12065 -0.3048)
			(end -0.67945 -0.3048)
			(stroke
				(width 0.1)
				(type default)
			)
			(layer "B.Fab")
		)
		(fp_line
			(start -0.67945 0.3048)
			(end -0.120396 0.3048)
			(stroke
				(width 0.1)
				(type default)
			)
			(layer "B.Fab")
		)
		(fp_line
			(start -0.67945 -0.3048)
			(end -0.67945 0.3048)
			(stroke
				(width 0.1)
				(type default)
			)
			(layer "B.Fab")
		)
		(pad "1" smd circle
			(at 0.40005 0)
			(size 0 0)
			(layers "B.Cu" "B.Mask" "B.Paste")
			(net "P3V3_AUX_CLK_GEN_VDDXTAL_CK440")
		)
		(pad "2" smd circle
			(at -0.40005 0)
			(size 0 0)
			(layers "B.Cu" "B.Mask" "B.Paste")
			(net "GND")
		)
	)
	(footprint ""
		(layer "B.Cu")
		(at 370.540788 -333.73568 90)
		(property "Reference" "PC284_P0_4"
			(at 0 0 90)
			(layer "B.SilkS")
			(hide yes)
			(effects
				(font
					(size 1.27 1.27)
				)
				(justify mirror)
			)
		)
		(property "Value" ""
			(at 0 0 90)
			(layer "B.Fab")
			(effects
				(font
					(size 1.27 1.27)
				)
				(justify mirror)
			)
		)
		(duplicate_pad_numbers_are_jumpers no)
		(fp_line
			(start 1.524 -0.762)
			(end -1.524 -0.762)
			(stroke
				(width 0.1524)
				(type default)
			)
			(layer "B.SilkS")
		)
		(fp_line
			(start -1.524 -0.762)
			(end -1.524 0.762)
			(stroke
				(width 0.1524)
				(type default)
			)
			(layer "B.SilkS")
		)
		(fp_line
			(start 1.524 0.762)
			(end 1.524 -0.762)
			(stroke
				(width 0.1524)
				(type default)
			)
			(layer "B.SilkS")
		)
		(fp_line
			(start -1.524 0.762)
			(end 1.524 0.762)
			(stroke
				(width 0.1524)
				(type default)
			)
			(layer "B.SilkS")
		)
		(fp_line
			(start 1.1049 -0.724916)
			(end 1.1049 0.724916)
			(stroke
				(width 0.1)
				(type default)
			)
			(layer "B.Fab")
		)
		(fp_line
			(start -1.1049 -0.724916)
			(end 1.1049 -0.724916)
			(stroke
				(width 0.1)
				(type default)
			)
			(layer "B.Fab")
		)
		(fp_line
			(start 1.1049 0.724916)
			(end -1.1049 0.724916)
			(stroke
				(width 0.1)
				(type default)
			)
			(layer "B.Fab")
		)
		(fp_line
			(start -1.1049 0.724916)
			(end -1.1049 -0.724916)
			(stroke
				(width 0.1)
				(type default)
			)
			(layer "B.Fab")
		)
		(pad "1" smd rect
			(at 0.889 0 90)
			(size 1.016 1.27)
			(layers "B.Cu" "B.Mask" "B.Paste")
			(net "SW_P12V_PVCCIN_CPU0_FLT")
		)
		(pad "2" smd rect
			(at -0.889 0 90)
			(size 1.016 1.27)
			(layers "B.Cu" "B.Mask" "B.Paste")
			(net "GND")
		)
	)
	(footprint ""
		(layer "B.Cu")
		(at 324.067424 -343.927938 90)
		(property "Reference" "PR403"
			(at 0 0 90)
			(layer "B.SilkS")
			(hide yes)
			(effects
				(font
					(size 1.27 1.27)
				)
				(justify mirror)
			)
		)
		(property "Value" ""
			(at 0 0 90)
			(layer "B.Fab")
			(effects
				(font
					(size 1.27 1.27)
				)
				(justify mirror)
			)
		)
		(duplicate_pad_numbers_are_jumpers no)
		(fp_line
			(start 0.7874 -0.4064)
			(end -0.7874 -0.4064)
			(stroke
				(width 0.1524)
				(type default)
			)
			(layer "B.SilkS")
		)
		(fp_line
			(start -0.7874 -0.4064)
			(end -0.7874 0.4064)
			(stroke
				(width 0.1524)
				(type default)
			)
			(layer "B.SilkS")
		)
		(fp_line
			(start 0.7874 0.4064)
			(end 0.7874 -0.4064)
			(stroke
				(width 0.1524)
				(type default)
			)
			(layer "B.SilkS")
		)
		(fp_line
			(start -0.7874 0.4064)
			(end 0.7874 0.4064)
			(stroke
				(width 0.1524)
				(type default)
			)
			(layer "B.SilkS")
		)
		(fp_line
			(start 0.67945 -0.305054)
			(end 0.12065 -0.305054)
			(stroke
				(width 0.1)
				(type default)
			)
			(layer "B.Fab")
		)
		(fp_line
			(start 0.12065 -0.305054)
			(end 0.12065 -0.2794)
			(stroke
				(width 0.1)
				(type default)
			)
			(layer "B.Fab")
		)
		(fp_line
			(start -0.12065 -0.3048)
			(end -0.67945 -0.3048)
			(stroke
				(width 0.1)
				(type default)
			)
			(layer "B.Fab")
		)
		(fp_line
			(start -0.67945 -0.3048)
			(end -0.67945 0.3048)
			(stroke
				(width 0.1)
				(type default)
			)
			(layer "B.Fab")
		)
		(fp_line
			(start 0.12065 -0.2794)
			(end -0.12065 -0.2794)
			(stroke
				(width 0.1)
				(type default)
			)
			(layer "B.Fab")
		)
		(fp_line
			(start -0.12065 -0.2794)
			(end -0.12065 -0.3048)
			(stroke
				(width 0.1)
				(type default)
			)
			(layer "B.Fab")
		)
		(fp_line
			(start 0.12065 0.2794)
			(end 0.12065 0.3048)
			(stroke
				(width 0.1)
				(type default)
			)
			(layer "B.Fab")
		)
		(fp_line
			(start -0.120396 0.2794)
			(end 0.12065 0.2794)
			(stroke
				(width 0.1)
				(type default)
			)
			(layer "B.Fab")
		)
		(fp_line
			(start 0.67945 0.3048)
			(end 0.67945 -0.305054)
			(stroke
				(width 0.1)
				(type default)
			)
			(layer "B.Fab")
		)
		(fp_line
			(start 0.12065 0.3048)
			(end 0.67945 0.3048)
			(stroke
				(width 0.1)
				(type default)
			)
			(layer "B.Fab")
		)
		(fp_line
			(start -0.120396 0.3048)
			(end -0.120396 0.2794)
			(stroke
				(width 0.1)
				(type default)
			)
			(layer "B.Fab")
		)
		(fp_line
			(start -0.67945 0.3048)
			(end -0.120396 0.3048)
			(stroke
				(width 0.1)
				(type default)
			)
			(layer "B.Fab")
		)
		(pad "1" smd circle
			(at 0.40005 0 270)
			(size 0 0)
			(layers "B.Cu" "B.Mask" "B.Paste")
			(net "P3V3")
		)
		(pad "2" smd circle
			(at -0.40005 0 270)
			(size 0 0)
			(layers "B.Cu" "B.Mask" "B.Paste")
			(net "PVCCIN_CPU0_PVCC")
		)
	)
	(footprint ""
		(layer "B.Cu")
		(at 45.857922 -357.91521 180)
		(property "Reference" "PC1679"
			(at 0 0 0)
			(layer "B.SilkS")
			(hide yes)
			(effects
				(font
					(size 1.27 1.27)
				)
				(justify mirror)
			)
		)
		(property "Value" ""
			(at 0 0 0)
			(layer "B.Fab")
			(effects
				(font
					(size 1.27 1.27)
				)
				(justify mirror)
			)
		)
		(duplicate_pad_numbers_are_jumpers no)
		(fp_line
			(start 1.524 0.762)
			(end 1.524 -0.762)
			(stroke
				(width 0.1524)
				(type default)
			)
			(layer "B.SilkS")
		)
		(fp_line
			(start 1.524 -0.762)
			(end -1.524 -0.762)
			(stroke
				(width 0.1524)
				(type default)
			)
			(layer "B.SilkS")
		)
		(fp_line
			(start -1.524 0.762)
			(end 1.524 0.762)
			(stroke
				(width 0.1524)
				(type default)
			)
			(layer "B.SilkS")
		)
		(fp_line
			(start -1.524 -0.762)
			(end -1.524 0.762)
			(stroke
				(width 0.1524)
				(type default)
			)
			(layer "B.SilkS")
		)
		(fp_line
			(start 1.1049 0.724916)
			(end -1.1049 0.724916)
			(stroke
				(width 0.1)
				(type default)
			)
			(layer "B.Fab")
		)
		(fp_line
			(start 1.1049 -0.724916)
			(end 1.1049 0.724916)
			(stroke
				(width 0.1)
				(type default)
			)
			(layer "B.Fab")
		)
		(fp_line
			(start -1.1049 0.724916)
			(end -1.1049 -0.724916)
			(stroke
				(width 0.1)
				(type default)
			)
			(layer "B.Fab")
		)
		(fp_line
			(start -1.1049 -0.724916)
			(end 1.1049 -0.724916)
			(stroke
				(width 0.1)
				(type default)
			)
			(layer "B.Fab")
		)
		(pad "1" smd rect
			(at 0.889 0 180)
			(size 1.016 1.27)
			(layers "B.Cu" "B.Mask" "B.Paste")
			(net "SW_P12V_PVCCFA_EHV_FIVRA_CPU1_L")
		)
		(pad "2" smd rect
			(at -0.889 0 180)
			(size 1.016 1.27)
			(layers "B.Cu" "B.Mask" "B.Paste")
			(net "GND")
		)
	)
	(footprint ""
		(layer "B.Cu")
		(at 432.325018 -177.15611 90)
		(property "Reference" "R1445"
			(at 0 0 90)
			(layer "B.SilkS")
			(hide yes)
			(effects
				(font
					(size 1.27 1.27)
				)
				(justify mirror)
			)
		)
		(property "Value" ""
			(at 0 0 90)
			(layer "B.Fab")
			(effects
				(font
					(size 1.27 1.27)
				)
				(justify mirror)
			)
		)
		(duplicate_pad_numbers_are_jumpers no)
		(fp_line
			(start 0.7874 -0.4064)
			(end -0.7874 -0.4064)
			(stroke
				(width 0.1524)
				(type default)
			)
			(layer "B.SilkS")
		)
		(fp_line
			(start -0.7874 -0.4064)
			(end -0.7874 0.4064)
			(stroke
				(width 0.1524)
				(type default)
			)
			(layer "B.SilkS")
		)
		(fp_line
			(start 0.7874 0.4064)
			(end 0.7874 -0.4064)
			(stroke
				(width 0.1524)
				(type default)
			)
			(layer "B.SilkS")
		)
		(fp_line
			(start -0.7874 0.4064)
			(end 0.7874 0.4064)
			(stroke
				(width 0.1524)
				(type default)
			)
			(layer "B.SilkS")
		)
		(fp_line
			(start 0.67945 -0.305054)
			(end 0.12065 -0.305054)
			(stroke
				(width 0.1)
				(type default)
			)
			(layer "B.Fab")
		)
		(fp_line
			(start 0.12065 -0.305054)
			(end 0.12065 -0.2794)
			(stroke
				(width 0.1)
				(type default)
			)
			(layer "B.Fab")
		)
		(fp_line
			(start -0.12065 -0.3048)
			(end -0.67945 -0.3048)
			(stroke
				(width 0.1)
				(type default)
			)
			(layer "B.Fab")
		)
		(fp_line
			(start -0.67945 -0.3048)
			(end -0.67945 0.3048)
			(stroke
				(width 0.1)
				(type default)
			)
			(layer "B.Fab")
		)
		(fp_line
			(start 0.12065 -0.2794)
			(end -0.12065 -0.2794)
			(stroke
				(width 0.1)
				(type default)
			)
			(layer "B.Fab")
		)
		(fp_line
			(start -0.12065 -0.2794)
			(end -0.12065 -0.3048)
			(stroke
				(width 0.1)
				(type default)
			)
			(layer "B.Fab")
		)
		(fp_line
			(start 0.12065 0.2794)
			(end 0.12065 0.3048)
			(stroke
				(width 0.1)
				(type default)
			)
			(layer "B.Fab")
		)
		(fp_line
			(start -0.120396 0.2794)
			(end 0.12065 0.2794)
			(stroke
				(width 0.1)
				(type default)
			)
			(layer "B.Fab")
		)
		(fp_line
			(start 0.67945 0.3048)
			(end 0.67945 -0.305054)
			(stroke
				(width 0.1)
				(type default)
			)
			(layer "B.Fab")
		)
		(fp_line
			(start 0.12065 0.3048)
			(end 0.67945 0.3048)
			(stroke
				(width 0.1)
				(type default)
			)
			(layer "B.Fab")
		)
		(fp_line
			(start -0.120396 0.3048)
			(end -0.120396 0.2794)
			(stroke
				(width 0.1)
				(type default)
			)
			(layer "B.Fab")
		)
		(fp_line
			(start -0.67945 0.3048)
			(end -0.120396 0.3048)
			(stroke
				(width 0.1)
				(type default)
			)
			(layer "B.Fab")
		)
		(pad "1" smd circle
			(at 0.40005 0 270)
			(size 0 0)
			(layers "B.Cu" "B.Mask" "B.Paste")
			(net "FM_PVNN_MAIN_CPU0_EN")
		)
		(pad "2" smd circle
			(at -0.40005 0 270)
			(size 0 0)
			(layers "B.Cu" "B.Mask" "B.Paste")
			(net "GND")
		)
	)
	(footprint ""
		(layer "B.Cu")
		(at 407.91257 -165.504368 180)
		(property "Reference" "PC642"
			(at 0 0 0)
			(layer "B.SilkS")
			(hide yes)
			(effects
				(font
					(size 1.27 1.27)
				)
				(justify mirror)
			)
		)
		(property "Value" ""
			(at 0 0 0)
			(layer "B.Fab")
			(effects
				(font
					(size 1.27 1.27)
				)
				(justify mirror)
			)
		)
		(duplicate_pad_numbers_are_jumpers no)
		(fp_line
			(start 1.524 0.762)
			(end 1.524 -0.762)
			(stroke
				(width 0.1524)
				(type default)
			)
			(layer "B.SilkS")
		)
		(fp_line
			(start 1.524 -0.762)
			(end -1.524 -0.762)
			(stroke
				(width 0.1524)
				(type default)
			)
			(layer "B.SilkS")
		)
		(fp_line
			(start -1.524 0.762)
			(end 1.524 0.762)
			(stroke
				(width 0.1524)
				(type default)
			)
			(layer "B.SilkS")
		)
		(fp_line
			(start -1.524 -0.762)
			(end -1.524 0.762)
			(stroke
				(width 0.1524)
				(type default)
			)
			(layer "B.SilkS")
		)
		(fp_line
			(start 1.1049 0.724916)
			(end -1.1049 0.724916)
			(stroke
				(width 0.1)
				(type default)
			)
			(layer "B.Fab")
		)
		(fp_line
			(start 1.1049 -0.724916)
			(end 1.1049 0.724916)
			(stroke
				(width 0.1)
				(type default)
			)
			(layer "B.Fab")
		)
		(fp_line
			(start -1.1049 0.724916)
			(end -1.1049 -0.724916)
			(stroke
				(width 0.1)
				(type default)
			)
			(layer "B.Fab")
		)
		(fp_line
			(start -1.1049 -0.724916)
			(end 1.1049 -0.724916)
			(stroke
				(width 0.1)
				(type default)
			)
			(layer "B.Fab")
		)
		(pad "1" smd rect
			(at 0.889 0 180)
			(size 1.016 1.27)
			(layers "B.Cu" "B.Mask" "B.Paste")
			(net "PVCCD_HV_CPU0")
		)
		(pad "2" smd rect
			(at -0.889 0 180)
			(size 1.016 1.27)
			(layers "B.Cu" "B.Mask" "B.Paste")
			(net "GND")
		)
	)
	(footprint ""
		(layer "B.Cu")
		(at 130.860546 -341.218012 -90)
		(property "Reference" "PC514_P1_5"
			(at 0 0 90)
			(layer "B.SilkS")
			(hide yes)
			(effects
				(font
					(size 1.27 1.27)
				)
				(justify mirror)
			)
		)
		(property "Value" ""
			(at 0 0 90)
			(layer "B.Fab")
			(effects
				(font
					(size 1.27 1.27)
				)
				(justify mirror)
			)
		)
		(duplicate_pad_numbers_are_jumpers no)
		(fp_line
			(start -1.524 0.762)
			(end 1.524 0.762)
			(stroke
				(width 0.1524)
				(type default)
			)
			(layer "B.SilkS")
		)
		(fp_line
			(start 1.524 0.762)
			(end 1.524 -0.762)
			(stroke
				(width 0.1524)
				(type default)
			)
			(layer "B.SilkS")
		)
		(fp_line
			(start -1.524 -0.762)
			(end -1.524 0.762)
			(stroke
				(width 0.1524)
				(type default)
			)
			(layer "B.SilkS")
		)
		(fp_line
			(start 1.524 -0.762)
			(end -1.524 -0.762)
			(stroke
				(width 0.1524)
				(type default)
			)
			(layer "B.SilkS")
		)
		(fp_line
			(start -1.1049 0.724916)
			(end -1.1049 -0.724916)
			(stroke
				(width 0.1)
				(type default)
			)
			(layer "B.Fab")
		)
		(fp_line
			(start 1.1049 0.724916)
			(end -1.1049 0.724916)
			(stroke
				(width 0.1)
				(type default)
			)
			(layer "B.Fab")
		)
		(fp_line
			(start -1.1049 -0.724916)
			(end 1.1049 -0.724916)
			(stroke
				(width 0.1)
				(type default)
			)
			(layer "B.Fab")
		)
		(fp_line
			(start 1.1049 -0.724916)
			(end 1.1049 0.724916)
			(stroke
				(width 0.1)
				(type default)
			)
			(layer "B.Fab")
		)
		(pad "1" smd rect
			(at 0.889 0 270)
			(size 1.016 1.27)
			(layers "B.Cu" "B.Mask" "B.Paste")
			(net "SW_P12V_PVCCIN_CPU1_FLT")
		)
		(pad "2" smd rect
			(at -0.889 0 270)
			(size 1.016 1.27)
			(layers "B.Cu" "B.Mask" "B.Paste")
			(net "GND")
		)
	)
	(footprint ""
		(layer "B.Cu")
		(at 42.686732 -353.567492 90)
		(property "Reference" "PC1202_P1_4"
			(at 0 0 90)
			(layer "B.SilkS")
			(hide yes)
			(effects
				(font
					(size 1.27 1.27)
				)
				(justify mirror)
			)
		)
		(property "Value" ""
			(at 0 0 90)
			(layer "B.Fab")
			(effects
				(font
					(size 1.27 1.27)
				)
				(justify mirror)
			)
		)
		(duplicate_pad_numbers_are_jumpers no)
		(fp_line
			(start 1.524 -0.762)
			(end -1.524 -0.762)
			(stroke
				(width 0.1524)
				(type default)
			)
			(layer "B.SilkS")
		)
		(fp_line
			(start -1.524 -0.762)
			(end -1.524 0.762)
			(stroke
				(width 0.1524)
				(type default)
			)
			(layer "B.SilkS")
		)
		(fp_line
			(start 1.524 0.762)
			(end 1.524 -0.762)
			(stroke
				(width 0.1524)
				(type default)
			)
			(layer "B.SilkS")
		)
		(fp_line
			(start -1.524 0.762)
			(end 1.524 0.762)
			(stroke
				(width 0.1524)
				(type default)
			)
			(layer "B.SilkS")
		)
		(fp_line
			(start 1.1049 -0.724916)
			(end 1.1049 0.724916)
			(stroke
				(width 0.1)
				(type default)
			)
			(layer "B.Fab")
		)
		(fp_line
			(start -1.1049 -0.724916)
			(end 1.1049 -0.724916)
			(stroke
				(width 0.1)
				(type default)
			)
			(layer "B.Fab")
		)
		(fp_line
			(start 1.1049 0.724916)
			(end -1.1049 0.724916)
			(stroke
				(width 0.1)
				(type default)
			)
			(layer "B.Fab")
		)
		(fp_line
			(start -1.1049 0.724916)
			(end -1.1049 -0.724916)
			(stroke
				(width 0.1)
				(type default)
			)
			(layer "B.Fab")
		)
		(pad "1" smd rect
			(at 0.889 0 90)
			(size 1.016 1.27)
			(layers "B.Cu" "B.Mask" "B.Paste")
			(net "SW_P12V_PVCCFA_EHV_FIVRA_CPU1_L")
		)
		(pad "2" smd rect
			(at -0.889 0 90)
			(size 1.016 1.27)
			(layers "B.Cu" "B.Mask" "B.Paste")
			(net "GND")
		)
	)
	(footprint ""
		(layer "B.Cu")
		(at 22.48916 -169.659808 180)
		(property "Reference" "R2575"
			(at 0 0 0)
			(layer "B.SilkS")
			(hide yes)
			(effects
				(font
					(size 1.27 1.27)
				)
				(justify mirror)
			)
		)
		(property "Value" ""
			(at 0 0 0)
			(layer "B.Fab")
			(effects
				(font
					(size 1.27 1.27)
				)
				(justify mirror)
			)
		)
		(duplicate_pad_numbers_are_jumpers no)
		(fp_line
			(start 0.7874 0.4064)
			(end 0.7874 -0.4064)
			(stroke
				(width 0.1524)
				(type default)
			)
			(layer "B.SilkS")
		)
		(fp_line
			(start 0.7874 -0.4064)
			(end -0.7874 -0.4064)
			(stroke
				(width 0.1524)
				(type default)
			)
			(layer "B.SilkS")
		)
		(fp_line
			(start -0.7874 0.4064)
			(end 0.7874 0.4064)
			(stroke
				(width 0.1524)
				(type default)
			)
			(layer "B.SilkS")
		)
		(fp_line
			(start -0.7874 -0.4064)
			(end -0.7874 0.4064)
			(stroke
				(width 0.1524)
				(type default)
			)
			(layer "B.SilkS")
		)
		(fp_line
			(start 0.67945 0.3048)
			(end 0.67945 -0.305054)
			(stroke
				(width 0.1)
				(type default)
			)
			(layer "B.Fab")
		)
		(fp_line
			(start 0.67945 -0.305054)
			(end 0.12065 -0.305054)
			(stroke
				(width 0.1)
				(type default)
			)
			(layer "B.Fab")
		)
		(fp_line
			(start 0.12065 0.3048)
			(end 0.67945 0.3048)
			(stroke
				(width 0.1)
				(type default)
			)
			(layer "B.Fab")
		)
		(fp_line
			(start 0.12065 0.2794)
			(end 0.12065 0.3048)
			(stroke
				(width 0.1)
				(type default)
			)
			(layer "B.Fab")
		)
		(fp_line
			(start 0.12065 -0.2794)
			(end -0.12065 -0.2794)
			(stroke
				(width 0.1)
				(type default)
			)
			(layer "B.Fab")
		)
		(fp_line
			(start 0.12065 -0.305054)
			(end 0.12065 -0.2794)
			(stroke
				(width 0.1)
				(type default)
			)
			(layer "B.Fab")
		)
		(fp_line
			(start -0.120396 0.3048)
			(end -0.120396 0.2794)
			(stroke
				(width 0.1)
				(type default)
			)
			(layer "B.Fab")
		)
		(fp_line
			(start -0.120396 0.2794)
			(end 0.12065 0.2794)
			(stroke
				(width 0.1)
				(type default)
			)
			(layer "B.Fab")
		)
		(fp_line
			(start -0.12065 -0.2794)
			(end -0.12065 -0.3048)
			(stroke
				(width 0.1)
				(type default)
			)
			(layer "B.Fab")
		)
		(fp_line
			(start -0.12065 -0.3048)
			(end -0.67945 -0.3048)
			(stroke
				(width 0.1)
				(type default)
			)
			(layer "B.Fab")
		)
		(fp_line
			(start -0.67945 0.3048)
			(end -0.120396 0.3048)
			(stroke
				(width 0.1)
				(type default)
			)
			(layer "B.Fab")
		)
		(fp_line
			(start -0.67945 -0.3048)
			(end -0.67945 0.3048)
			(stroke
				(width 0.1)
				(type default)
			)
			(layer "B.Fab")
		)
		(pad "1" smd circle
			(at 0.40005 0)
			(size 0 0)
			(layers "B.Cu" "B.Mask" "B.Paste")
			(net "P3V3_AUX")
		)
		(pad "2" smd circle
			(at -0.40005 0)
			(size 0 0)
			(layers "B.Cu" "B.Mask" "B.Paste")
			(net "PWRGD_PVCCD_HV_CPU1_R")
		)
	)
	(footprint ""
		(layer "B.Cu")
		(at 312.443622 -33.010348)
		(property "Reference" "R1298"
			(at 0 0 0)
			(layer "B.SilkS")
			(hide yes)
			(effects
				(font
					(size 1.27 1.27)
				)
				(justify mirror)
			)
		)
		(property "Value" ""
			(at 0 0 0)
			(layer "B.Fab")
			(effects
				(font
					(size 1.27 1.27)
				)
				(justify mirror)
			)
		)
		(duplicate_pad_numbers_are_jumpers no)
		(fp_line
			(start -0.7874 -0.4064)
			(end -0.7874 0.4064)
			(stroke
				(width 0.1524)
				(type default)
			)
			(layer "B.SilkS")
		)
		(fp_line
			(start -0.7874 0.4064)
			(end 0.7874 0.4064)
			(stroke
				(width 0.1524)
				(type default)
			)
			(layer "B.SilkS")
		)
		(fp_line
			(start 0.7874 -0.4064)
			(end -0.7874 -0.4064)
			(stroke
				(width 0.1524)
				(type default)
			)
			(layer "B.SilkS")
		)
		(fp_line
			(start 0.7874 0.4064)
			(end 0.7874 -0.4064)
			(stroke
				(width 0.1524)
				(type default)
			)
			(layer "B.SilkS")
		)
		(fp_line
			(start -0.67945 -0.3048)
			(end -0.67945 0.3048)
			(stroke
				(width 0.1)
				(type default)
			)
			(layer "B.Fab")
		)
		(fp_line
			(start -0.67945 0.3048)
			(end -0.120396 0.3048)
			(stroke
				(width 0.1)
				(type default)
			)
			(layer "B.Fab")
		)
		(fp_line
			(start -0.12065 -0.3048)
			(end -0.67945 -0.3048)
			(stroke
				(width 0.1)
				(type default)
			)
			(layer "B.Fab")
		)
		(fp_line
			(start -0.12065 -0.2794)
			(end -0.12065 -0.3048)
			(stroke
				(width 0.1)
				(type default)
			)
			(layer "B.Fab")
		)
		(fp_line
			(start -0.120396 0.2794)
			(end 0.12065 0.2794)
			(stroke
				(width 0.1)
				(type default)
			)
			(layer "B.Fab")
		)
		(fp_line
			(start -0.120396 0.3048)
			(end -0.120396 0.2794)
			(stroke
				(width 0.1)
				(type default)
			)
			(layer "B.Fab")
		)
		(fp_line
			(start 0.12065 -0.305054)
			(end 0.12065 -0.2794)
			(stroke
				(width 0.1)
				(type default)
			)
			(layer "B.Fab")
		)
		(fp_line
			(start 0.12065 -0.2794)
			(end -0.12065 -0.2794)
			(stroke
				(width 0.1)
				(type default)
			)
			(layer "B.Fab")
		)
		(fp_line
			(start 0.12065 0.2794)
			(end 0.12065 0.3048)
			(stroke
				(width 0.1)
				(type default)
			)
			(layer "B.Fab")
		)
		(fp_line
			(start 0.12065 0.3048)
			(end 0.67945 0.3048)
			(stroke
				(width 0.1)
				(type default)
			)
			(layer "B.Fab")
		)
		(fp_line
			(start 0.67945 -0.305054)
			(end 0.12065 -0.305054)
			(stroke
				(width 0.1)
				(type default)
			)
			(layer "B.Fab")
		)
		(fp_line
			(start 0.67945 0.3048)
			(end 0.67945 -0.305054)
			(stroke
				(width 0.1)
				(type default)
			)
			(layer "B.Fab")
		)
		(pad "1" smd circle
			(at 0.40005 0 180)
			(size 0 0)
			(layers "B.Cu" "B.Mask" "B.Paste")
			(net "P1V05_PCH_AUX")
		)
		(pad "2" smd circle
			(at -0.40005 0 180)
			(size 0 0)
			(layers "B.Cu" "B.Mask" "B.Paste")
			(net "FM_MFG_MODE")
		)
	)
	(footprint ""
		(layer "B.Cu")
		(at 175.355758 -111.375444 180)
		(property "Reference" "C1905"
			(at 0 0 0)
			(layer "B.SilkS")
			(hide yes)
			(effects
				(font
					(size 1.27 1.27)
				)
				(justify mirror)
			)
		)
		(property "Value" ""
			(at 0 0 0)
			(layer "B.Fab")
			(effects
				(font
					(size 1.27 1.27)
				)
				(justify mirror)
			)
		)
		(duplicate_pad_numbers_are_jumpers no)
		(fp_line
			(start 0.69215 0.2921)
			(end 0.69215 -0.2921)
			(stroke
				(width 0.1524)
				(type default)
			)
			(layer "B.SilkS")
		)
		(fp_line
			(start 0.69215 -0.2921)
			(end -0.69215 -0.2921)
			(stroke
				(width 0.1524)
				(type default)
			)
			(layer "B.SilkS")
		)
		(fp_line
			(start -0.69215 0.2921)
			(end 0.69215 0.2921)
			(stroke
				(width 0.1524)
				(type default)
			)
			(layer "B.SilkS")
		)
		(fp_line
			(start -0.69215 -0.2921)
			(end -0.69215 0.2921)
			(stroke
				(width 0.1524)
				(type default)
			)
			(layer "B.SilkS")
		)
		(fp_line
			(start 0.51435 0.2794)
			(end 0.51435 -0.2794)
			(stroke
				(width 0.1)
				(type default)
			)
			(layer "B.Fab")
		)
		(fp_line
			(start 0.51435 -0.2794)
			(end -0.51435 -0.2794)
			(stroke
				(width 0.1)
				(type default)
			)
			(layer "B.Fab")
		)
		(fp_line
			(start -0.51435 0.2794)
			(end 0.51435 0.2794)
			(stroke
				(width 0.1)
				(type default)
			)
			(layer "B.Fab")
		)
		(fp_line
			(start -0.51435 -0.2794)
			(end -0.51435 0.2794)
			(stroke
				(width 0.1)
				(type default)
			)
			(layer "B.Fab")
		)
		(pad "1" smd circle
			(at 0.40005 0)
			(size 0 0)
			(layers "B.Cu" "B.Mask" "B.Paste")
			(net "P3V3_AUX_FPGA_VCCIO0")
		)
		(pad "2" smd circle
			(at -0.40005 0)
			(size 0 0)
			(layers "B.Cu" "B.Mask" "B.Paste")
			(net "GND")
		)
		(zone
			(layer "B.Cu")
			(hatch none 0.5)
			(connect_pads
				(clearance 0)
			)
			(min_thickness 0.25)
			(keepout
				(tracks not_allowed)
				(vias allowed)
				(pads allowed)
				(copperpour not_allowed)
				(footprints allowed)
			)
			(placement
				(enabled no)
				(sheetname "")
			)
			(fill
				(thermal_gap 0.5)
				(thermal_bridge_width 0.5)
				(island_removal_mode 0)
			)
			(polygon
				(pts
					(xy 175.165258 -111.463074) (xy 175.256698 -111.52124) (xy 175.456088 -111.52124) (xy 175.546258 -111.463074)
					(xy 175.546258 -111.287814) (xy 175.456088 -111.229394) (xy 175.256698 -111.229394) (xy 175.165258 -111.28756)
				)
			)
		)
	)
	(footprint ""
		(layer "B.Cu")
		(at 459.982316 -318.608456 90)
		(property "Reference" "R2734"
			(at 0 0 90)
			(layer "B.SilkS")
			(hide yes)
			(effects
				(font
					(size 1.27 1.27)
				)
				(justify mirror)
			)
		)
		(property "Value" ""
			(at 0 0 90)
			(layer "B.Fab")
			(effects
				(font
					(size 1.27 1.27)
				)
				(justify mirror)
			)
		)
		(duplicate_pad_numbers_are_jumpers no)
		(fp_line
			(start 0.7874 -0.4064)
			(end -0.7874 -0.4064)
			(stroke
				(width 0.1524)
				(type default)
			)
			(layer "B.SilkS")
		)
		(fp_line
			(start -0.7874 -0.4064)
			(end -0.7874 0.4064)
			(stroke
				(width 0.1524)
				(type default)
			)
			(layer "B.SilkS")
		)
		(fp_line
			(start 0.7874 0.4064)
			(end 0.7874 -0.4064)
			(stroke
				(width 0.1524)
				(type default)
			)
			(layer "B.SilkS")
		)
		(fp_line
			(start -0.7874 0.4064)
			(end 0.7874 0.4064)
			(stroke
				(width 0.1524)
				(type default)
			)
			(layer "B.SilkS")
		)
		(fp_line
			(start 0.67945 -0.305054)
			(end 0.12065 -0.305054)
			(stroke
				(width 0.1)
				(type default)
			)
			(layer "B.Fab")
		)
		(fp_line
			(start 0.12065 -0.305054)
			(end 0.12065 -0.2794)
			(stroke
				(width 0.1)
				(type default)
			)
			(layer "B.Fab")
		)
		(fp_line
			(start -0.12065 -0.3048)
			(end -0.67945 -0.3048)
			(stroke
				(width 0.1)
				(type default)
			)
			(layer "B.Fab")
		)
		(fp_line
			(start -0.67945 -0.3048)
			(end -0.67945 0.3048)
			(stroke
				(width 0.1)
				(type default)
			)
			(layer "B.Fab")
		)
		(fp_line
			(start 0.12065 -0.2794)
			(end -0.12065 -0.2794)
			(stroke
				(width 0.1)
				(type default)
			)
			(layer "B.Fab")
		)
		(fp_line
			(start -0.12065 -0.2794)
			(end -0.12065 -0.3048)
			(stroke
				(width 0.1)
				(type default)
			)
			(layer "B.Fab")
		)
		(fp_line
			(start 0.12065 0.2794)
			(end 0.12065 0.3048)
			(stroke
				(width 0.1)
				(type default)
			)
			(layer "B.Fab")
		)
		(fp_line
			(start -0.120396 0.2794)
			(end 0.12065 0.2794)
			(stroke
				(width 0.1)
				(type default)
			)
			(layer "B.Fab")
		)
		(fp_line
			(start 0.67945 0.3048)
			(end 0.67945 -0.305054)
			(stroke
				(width 0.1)
				(type default)
			)
			(layer "B.Fab")
		)
		(fp_line
			(start 0.12065 0.3048)
			(end 0.67945 0.3048)
			(stroke
				(width 0.1)
				(type default)
			)
			(layer "B.Fab")
		)
		(fp_line
			(start -0.120396 0.3048)
			(end -0.120396 0.2794)
			(stroke
				(width 0.1)
				(type default)
			)
			(layer "B.Fab")
		)
		(fp_line
			(start -0.67945 0.3048)
			(end -0.120396 0.3048)
			(stroke
				(width 0.1)
				(type default)
			)
			(layer "B.Fab")
		)
		(pad "1" smd circle
			(at 0.40005 0 270)
			(size 0 0)
			(layers "B.Cu" "B.Mask" "B.Paste")
			(net "PWRGD_CHH_CPU0_DIMM1")
		)
		(pad "2" smd circle
			(at -0.40005 0 270)
			(size 0 0)
			(layers "B.Cu" "B.Mask" "B.Paste")
			(net "PWRGD_FAIL_CPU0_GH")
		)
	)
	(footprint ""
		(layer "B.Cu")
		(at 335.915254 -46.888146 -90)
		(property "Reference" "C1210"
			(at 0 0 90)
			(layer "B.SilkS")
			(hide yes)
			(effects
				(font
					(size 1.27 1.27)
				)
				(justify mirror)
			)
		)
		(property "Value" ""
			(at 0 0 90)
			(layer "B.Fab")
			(effects
				(font
					(size 1.27 1.27)
				)
				(justify mirror)
			)
		)
		(duplicate_pad_numbers_are_jumpers no)
		(fp_line
			(start -0.7874 0.4064)
			(end 0.7874 0.4064)
			(stroke
				(width 0.1524)
				(type default)
			)
			(layer "B.SilkS")
		)
		(fp_line
			(start 0.7874 0.4064)
			(end 0.7874 -0.4064)
			(stroke
				(width 0.1524)
				(type default)
			)
			(layer "B.SilkS")
		)
		(fp_line
			(start -0.7874 -0.4064)
			(end -0.7874 0.4064)
			(stroke
				(width 0.1524)
				(type default)
			)
			(layer "B.SilkS")
		)
		(fp_line
			(start 0.7874 -0.4064)
			(end -0.7874 -0.4064)
			(stroke
				(width 0.1524)
				(type default)
			)
			(layer "B.SilkS")
		)
		(fp_line
			(start -0.67945 0.3048)
			(end -0.120396 0.3048)
			(stroke
				(width 0.1)
				(type default)
			)
			(layer "B.Fab")
		)
		(fp_line
			(start -0.120396 0.3048)
			(end -0.120396 0.2794)
			(stroke
				(width 0.1)
				(type default)
			)
			(layer "B.Fab")
		)
		(fp_line
			(start 0.12065 0.3048)
			(end 0.67945 0.3048)
			(stroke
				(width 0.1)
				(type default)
			)
			(layer "B.Fab")
		)
		(fp_line
			(start 0.67945 0.3048)
			(end 0.67945 -0.305054)
			(stroke
				(width 0.1)
				(type default)
			)
			(layer "B.Fab")
		)
		(fp_line
			(start -0.120396 0.2794)
			(end 0.12065 0.2794)
			(stroke
				(width 0.1)
				(type default)
			)
			(layer "B.Fab")
		)
		(fp_line
			(start 0.12065 0.2794)
			(end 0.12065 0.3048)
			(stroke
				(width 0.1)
				(type default)
			)
			(layer "B.Fab")
		)
		(fp_line
			(start -0.12065 -0.2794)
			(end -0.12065 -0.3048)
			(stroke
				(width 0.1)
				(type default)
			)
			(layer "B.Fab")
		)
		(fp_line
			(start 0.12065 -0.2794)
			(end -0.12065 -0.2794)
			(stroke
				(width 0.1)
				(type default)
			)
			(layer "B.Fab")
		)
		(fp_line
			(start -0.67945 -0.3048)
			(end -0.67945 0.3048)
			(stroke
				(width 0.1)
				(type default)
			)
			(layer "B.Fab")
		)
		(fp_line
			(start -0.12065 -0.3048)
			(end -0.67945 -0.3048)
			(stroke
				(width 0.1)
				(type default)
			)
			(layer "B.Fab")
		)
		(fp_line
			(start 0.12065 -0.305054)
			(end 0.12065 -0.2794)
			(stroke
				(width 0.1)
				(type default)
			)
			(layer "B.Fab")
		)
		(fp_line
			(start 0.67945 -0.305054)
			(end 0.12065 -0.305054)
			(stroke
				(width 0.1)
				(type default)
			)
			(layer "B.Fab")
		)
		(pad "1" smd circle
			(at 0.40005 0 90)
			(size 0 0)
			(layers "B.Cu" "B.Mask" "B.Paste")
			(net "P1V05_PCH_AUX")
		)
		(pad "2" smd circle
			(at -0.40005 0 90)
			(size 0 0)
			(layers "B.Cu" "B.Mask" "B.Paste")
			(net "GND")
		)
	)
	(footprint ""
		(layer "B.Cu")
		(at 166.301166 -247.250712 180)
		(property "Reference" "R1270"
			(at 0 0 0)
			(layer "B.SilkS")
			(hide yes)
			(effects
				(font
					(size 1.27 1.27)
				)
				(justify mirror)
			)
		)
		(property "Value" ""
			(at 0 0 0)
			(layer "B.Fab")
			(effects
				(font
					(size 1.27 1.27)
				)
				(justify mirror)
			)
		)
		(duplicate_pad_numbers_are_jumpers no)
		(fp_line
			(start 0.7874 0.4064)
			(end 0.7874 -0.4064)
			(stroke
				(width 0.1524)
				(type default)
			)
			(layer "B.SilkS")
		)
		(fp_line
			(start 0.7874 -0.4064)
			(end -0.7874 -0.4064)
			(stroke
				(width 0.1524)
				(type default)
			)
			(layer "B.SilkS")
		)
		(fp_line
			(start -0.7874 0.4064)
			(end 0.7874 0.4064)
			(stroke
				(width 0.1524)
				(type default)
			)
			(layer "B.SilkS")
		)
		(fp_line
			(start -0.7874 -0.4064)
			(end -0.7874 0.4064)
			(stroke
				(width 0.1524)
				(type default)
			)
			(layer "B.SilkS")
		)
		(fp_line
			(start 0.67945 0.3048)
			(end 0.67945 -0.305054)
			(stroke
				(width 0.1)
				(type default)
			)
			(layer "B.Fab")
		)
		(fp_line
			(start 0.67945 -0.305054)
			(end 0.12065 -0.305054)
			(stroke
				(width 0.1)
				(type default)
			)
			(layer "B.Fab")
		)
		(fp_line
			(start 0.12065 0.3048)
			(end 0.67945 0.3048)
			(stroke
				(width 0.1)
				(type default)
			)
			(layer "B.Fab")
		)
		(fp_line
			(start 0.12065 0.2794)
			(end 0.12065 0.3048)
			(stroke
				(width 0.1)
				(type default)
			)
			(layer "B.Fab")
		)
		(fp_line
			(start 0.12065 -0.2794)
			(end -0.12065 -0.2794)
			(stroke
				(width 0.1)
				(type default)
			)
			(layer "B.Fab")
		)
		(fp_line
			(start 0.12065 -0.305054)
			(end 0.12065 -0.2794)
			(stroke
				(width 0.1)
				(type default)
			)
			(layer "B.Fab")
		)
		(fp_line
			(start -0.120396 0.3048)
			(end -0.120396 0.2794)
			(stroke
				(width 0.1)
				(type default)
			)
			(layer "B.Fab")
		)
		(fp_line
			(start -0.120396 0.2794)
			(end 0.12065 0.2794)
			(stroke
				(width 0.1)
				(type default)
			)
			(layer "B.Fab")
		)
		(fp_line
			(start -0.12065 -0.2794)
			(end -0.12065 -0.3048)
			(stroke
				(width 0.1)
				(type default)
			)
			(layer "B.Fab")
		)
		(fp_line
			(start -0.12065 -0.3048)
			(end -0.67945 -0.3048)
			(stroke
				(width 0.1)
				(type default)
			)
			(layer "B.Fab")
		)
		(fp_line
			(start -0.67945 0.3048)
			(end -0.120396 0.3048)
			(stroke
				(width 0.1)
				(type default)
			)
			(layer "B.Fab")
		)
		(fp_line
			(start -0.67945 -0.3048)
			(end -0.67945 0.3048)
			(stroke
				(width 0.1)
				(type default)
			)
			(layer "B.Fab")
		)
		(pad "1" smd circle
			(at 0.40005 0)
			(size 0 0)
			(layers "B.Cu" "B.Mask" "B.Paste")
			(net "PD_CPU1_PROCDIS_COD_GTL_N")
		)
		(pad "2" smd circle
			(at -0.40005 0)
			(size 0 0)
			(layers "B.Cu" "B.Mask" "B.Paste")
			(net "GND")
		)
	)
	(footprint ""
		(layer "B.Cu")
		(at 124.736098 -333.73568 90)
		(property "Reference" "PC535_P1_4"
			(at 0 0 90)
			(layer "B.SilkS")
			(hide yes)
			(effects
				(font
					(size 1.27 1.27)
				)
				(justify mirror)
			)
		)
		(property "Value" ""
			(at 0 0 90)
			(layer "B.Fab")
			(effects
				(font
					(size 1.27 1.27)
				)
				(justify mirror)
			)
		)
		(duplicate_pad_numbers_are_jumpers no)
		(fp_line
			(start 1.524 -0.762)
			(end -1.524 -0.762)
			(stroke
				(width 0.1524)
				(type default)
			)
			(layer "B.SilkS")
		)
		(fp_line
			(start -1.524 -0.762)
			(end -1.524 0.762)
			(stroke
				(width 0.1524)
				(type default)
			)
			(layer "B.SilkS")
		)
		(fp_line
			(start 1.524 0.762)
			(end 1.524 -0.762)
			(stroke
				(width 0.1524)
				(type default)
			)
			(layer "B.SilkS")
		)
		(fp_line
			(start -1.524 0.762)
			(end 1.524 0.762)
			(stroke
				(width 0.1524)
				(type default)
			)
			(layer "B.SilkS")
		)
		(fp_line
			(start 1.1049 -0.724916)
			(end 1.1049 0.724916)
			(stroke
				(width 0.1)
				(type default)
			)
			(layer "B.Fab")
		)
		(fp_line
			(start -1.1049 -0.724916)
			(end 1.1049 -0.724916)
			(stroke
				(width 0.1)
				(type default)
			)
			(layer "B.Fab")
		)
		(fp_line
			(start 1.1049 0.724916)
			(end -1.1049 0.724916)
			(stroke
				(width 0.1)
				(type default)
			)
			(layer "B.Fab")
		)
		(fp_line
			(start -1.1049 0.724916)
			(end -1.1049 -0.724916)
			(stroke
				(width 0.1)
				(type default)
			)
			(layer "B.Fab")
		)
		(pad "1" smd rect
			(at 0.889 0 90)
			(size 1.016 1.27)
			(layers "B.Cu" "B.Mask" "B.Paste")
			(net "SW_P12V_PVCCIN_CPU1_FLT")
		)
		(pad "2" smd rect
			(at -0.889 0 90)
			(size 1.016 1.27)
			(layers "B.Cu" "B.Mask" "B.Paste")
			(net "GND")
		)
	)
	(footprint ""
		(layer "B.Cu")
		(at 232.283 -423.0116 -90)
		(property "Reference" "R4721"
			(at 0 0 90)
			(layer "B.SilkS")
			(hide yes)
			(effects
				(font
					(size 1.27 1.27)
				)
				(justify mirror)
			)
		)
		(property "Value" ""
			(at 0 0 90)
			(layer "B.Fab")
			(effects
				(font
					(size 1.27 1.27)
				)
				(justify mirror)
			)
		)
		(duplicate_pad_numbers_are_jumpers no)
		(fp_line
			(start -0.7874 0.4064)
			(end 0.7874 0.4064)
			(stroke
				(width 0.1524)
				(type default)
			)
			(layer "B.SilkS")
		)
		(fp_line
			(start 0.7874 0.4064)
			(end 0.7874 -0.4064)
			(stroke
				(width 0.1524)
				(type default)
			)
			(layer "B.SilkS")
		)
		(fp_line
			(start -0.7874 -0.4064)
			(end -0.7874 0.4064)
			(stroke
				(width 0.1524)
				(type default)
			)
			(layer "B.SilkS")
		)
		(fp_line
			(start 0.7874 -0.4064)
			(end -0.7874 -0.4064)
			(stroke
				(width 0.1524)
				(type default)
			)
			(layer "B.SilkS")
		)
		(fp_line
			(start -0.67945 0.3048)
			(end -0.120396 0.3048)
			(stroke
				(width 0.1)
				(type default)
			)
			(layer "B.Fab")
		)
		(fp_line
			(start -0.120396 0.3048)
			(end -0.120396 0.2794)
			(stroke
				(width 0.1)
				(type default)
			)
			(layer "B.Fab")
		)
		(fp_line
			(start 0.12065 0.3048)
			(end 0.67945 0.3048)
			(stroke
				(width 0.1)
				(type default)
			)
			(layer "B.Fab")
		)
		(fp_line
			(start 0.67945 0.3048)
			(end 0.67945 -0.305054)
			(stroke
				(width 0.1)
				(type default)
			)
			(layer "B.Fab")
		)
		(fp_line
			(start -0.120396 0.2794)
			(end 0.12065 0.2794)
			(stroke
				(width 0.1)
				(type default)
			)
			(layer "B.Fab")
		)
		(fp_line
			(start 0.12065 0.2794)
			(end 0.12065 0.3048)
			(stroke
				(width 0.1)
				(type default)
			)
			(layer "B.Fab")
		)
		(fp_line
			(start -0.12065 -0.2794)
			(end -0.12065 -0.3048)
			(stroke
				(width 0.1)
				(type default)
			)
			(layer "B.Fab")
		)
		(fp_line
			(start 0.12065 -0.2794)
			(end -0.12065 -0.2794)
			(stroke
				(width 0.1)
				(type default)
			)
			(layer "B.Fab")
		)
		(fp_line
			(start -0.67945 -0.3048)
			(end -0.67945 0.3048)
			(stroke
				(width 0.1)
				(type default)
			)
			(layer "B.Fab")
		)
		(fp_line
			(start -0.12065 -0.3048)
			(end -0.67945 -0.3048)
			(stroke
				(width 0.1)
				(type default)
			)
			(layer "B.Fab")
		)
		(fp_line
			(start 0.12065 -0.305054)
			(end 0.12065 -0.2794)
			(stroke
				(width 0.1)
				(type default)
			)
			(layer "B.Fab")
		)
		(fp_line
			(start 0.67945 -0.305054)
			(end 0.12065 -0.305054)
			(stroke
				(width 0.1)
				(type default)
			)
			(layer "B.Fab")
		)
		(pad "1" smd circle
			(at 0.40005 0 90)
			(size 0 0)
			(layers "B.Cu" "B.Mask" "B.Paste")
			(net "FM_AC_PWR_BTN_R_N")
		)
		(pad "2" smd circle
			(at -0.40005 0 90)
			(size 0 0)
			(layers "B.Cu" "B.Mask" "B.Paste")
			(net "FM_AC_PWR_BTN_PDB_N")
		)
	)
	(footprint ""
		(layer "B.Cu")
		(at 236.67593 -49.120044)
		(property "Reference" "C1282"
			(at 0 0 0)
			(layer "B.SilkS")
			(hide yes)
			(effects
				(font
					(size 1.27 1.27)
				)
				(justify mirror)
			)
		)
		(property "Value" ""
			(at 0 0 0)
			(layer "B.Fab")
			(effects
				(font
					(size 1.27 1.27)
				)
				(justify mirror)
			)
		)
		(duplicate_pad_numbers_are_jumpers no)
		(fp_line
			(start -0.7874 -0.4064)
			(end -0.7874 0.4064)
			(stroke
				(width 0.1524)
				(type default)
			)
			(layer "B.SilkS")
		)
		(fp_line
			(start -0.7874 0.4064)
			(end 0.7874 0.4064)
			(stroke
				(width 0.1524)
				(type default)
			)
			(layer "B.SilkS")
		)
		(fp_line
			(start 0.7874 -0.4064)
			(end -0.7874 -0.4064)
			(stroke
				(width 0.1524)
				(type default)
			)
			(layer "B.SilkS")
		)
		(fp_line
			(start 0.7874 0.4064)
			(end 0.7874 -0.4064)
			(stroke
				(width 0.1524)
				(type default)
			)
			(layer "B.SilkS")
		)
		(fp_line
			(start -0.67945 -0.3048)
			(end -0.67945 0.3048)
			(stroke
				(width 0.1)
				(type default)
			)
			(layer "B.Fab")
		)
		(fp_line
			(start -0.67945 0.3048)
			(end -0.120396 0.3048)
			(stroke
				(width 0.1)
				(type default)
			)
			(layer "B.Fab")
		)
		(fp_line
			(start -0.12065 -0.3048)
			(end -0.67945 -0.3048)
			(stroke
				(width 0.1)
				(type default)
			)
			(layer "B.Fab")
		)
		(fp_line
			(start -0.12065 -0.2794)
			(end -0.12065 -0.3048)
			(stroke
				(width 0.1)
				(type default)
			)
			(layer "B.Fab")
		)
		(fp_line
			(start -0.120396 0.2794)
			(end 0.12065 0.2794)
			(stroke
				(width 0.1)
				(type default)
			)
			(layer "B.Fab")
		)
		(fp_line
			(start -0.120396 0.3048)
			(end -0.120396 0.2794)
			(stroke
				(width 0.1)
				(type default)
			)
			(layer "B.Fab")
		)
		(fp_line
			(start 0.12065 -0.305054)
			(end 0.12065 -0.2794)
			(stroke
				(width 0.1)
				(type default)
			)
			(layer "B.Fab")
		)
		(fp_line
			(start 0.12065 -0.2794)
			(end -0.12065 -0.2794)
			(stroke
				(width 0.1)
				(type default)
			)
			(layer "B.Fab")
		)
		(fp_line
			(start 0.12065 0.2794)
			(end 0.12065 0.3048)
			(stroke
				(width 0.1)
				(type default)
			)
			(layer "B.Fab")
		)
		(fp_line
			(start 0.12065 0.3048)
			(end 0.67945 0.3048)
			(stroke
				(width 0.1)
				(type default)
			)
			(layer "B.Fab")
		)
		(fp_line
			(start 0.67945 -0.305054)
			(end 0.12065 -0.305054)
			(stroke
				(width 0.1)
				(type default)
			)
			(layer "B.Fab")
		)
		(fp_line
			(start 0.67945 0.3048)
			(end 0.67945 -0.305054)
			(stroke
				(width 0.1)
				(type default)
			)
			(layer "B.Fab")
		)
		(pad "1" smd circle
			(at 0.40005 0 180)
			(size 0 0)
			(layers "B.Cu" "B.Mask" "B.Paste")
			(net "P3V3_E1S_0")
		)
		(pad "2" smd circle
			(at -0.40005 0 180)
			(size 0 0)
			(layers "B.Cu" "B.Mask" "B.Paste")
			(net "GND")
		)
	)
	(footprint ""
		(layer "B.Cu")
		(at 209.794856 -194.136264)
		(property "Reference" "C540"
			(at 0 0 0)
			(layer "B.SilkS")
			(hide yes)
			(effects
				(font
					(size 1.27 1.27)
				)
				(justify mirror)
			)
		)
		(property "Value" ""
			(at 0 0 0)
			(layer "B.Fab")
			(effects
				(font
					(size 1.27 1.27)
				)
				(justify mirror)
			)
		)
		(duplicate_pad_numbers_are_jumpers no)
		(fp_line
			(start -0.7874 -0.4064)
			(end -0.7874 0.4064)
			(stroke
				(width 0.1524)
				(type default)
			)
			(layer "B.SilkS")
		)
		(fp_line
			(start -0.7874 0.4064)
			(end 0.7874 0.4064)
			(stroke
				(width 0.1524)
				(type default)
			)
			(layer "B.SilkS")
		)
		(fp_line
			(start 0.7874 -0.4064)
			(end -0.7874 -0.4064)
			(stroke
				(width 0.1524)
				(type default)
			)
			(layer "B.SilkS")
		)
		(fp_line
			(start 0.7874 0.4064)
			(end 0.7874 -0.4064)
			(stroke
				(width 0.1524)
				(type default)
			)
			(layer "B.SilkS")
		)
		(fp_line
			(start -0.67945 -0.3048)
			(end -0.67945 0.3048)
			(stroke
				(width 0.1)
				(type default)
			)
			(layer "B.Fab")
		)
		(fp_line
			(start -0.67945 0.3048)
			(end -0.120396 0.3048)
			(stroke
				(width 0.1)
				(type default)
			)
			(layer "B.Fab")
		)
		(fp_line
			(start -0.12065 -0.3048)
			(end -0.67945 -0.3048)
			(stroke
				(width 0.1)
				(type default)
			)
			(layer "B.Fab")
		)
		(fp_line
			(start -0.12065 -0.2794)
			(end -0.12065 -0.3048)
			(stroke
				(width 0.1)
				(type default)
			)
			(layer "B.Fab")
		)
		(fp_line
			(start -0.120396 0.2794)
			(end 0.12065 0.2794)
			(stroke
				(width 0.1)
				(type default)
			)
			(layer "B.Fab")
		)
		(fp_line
			(start -0.120396 0.3048)
			(end -0.120396 0.2794)
			(stroke
				(width 0.1)
				(type default)
			)
			(layer "B.Fab")
		)
		(fp_line
			(start 0.12065 -0.305054)
			(end 0.12065 -0.2794)
			(stroke
				(width 0.1)
				(type default)
			)
			(layer "B.Fab")
		)
		(fp_line
			(start 0.12065 -0.2794)
			(end -0.12065 -0.2794)
			(stroke
				(width 0.1)
				(type default)
			)
			(layer "B.Fab")
		)
		(fp_line
			(start 0.12065 0.2794)
			(end 0.12065 0.3048)
			(stroke
				(width 0.1)
				(type default)
			)
			(layer "B.Fab")
		)
		(fp_line
			(start 0.12065 0.3048)
			(end 0.67945 0.3048)
			(stroke
				(width 0.1)
				(type default)
			)
			(layer "B.Fab")
		)
		(fp_line
			(start 0.67945 -0.305054)
			(end 0.12065 -0.305054)
			(stroke
				(width 0.1)
				(type default)
			)
			(layer "B.Fab")
		)
		(fp_line
			(start 0.67945 0.3048)
			(end 0.67945 -0.305054)
			(stroke
				(width 0.1)
				(type default)
			)
			(layer "B.Fab")
		)
		(pad "1" smd circle
			(at 0.40005 0 180)
			(size 0 0)
			(layers "B.Cu" "B.Mask" "B.Paste")
			(net "P3V3_AUX")
		)
		(pad "2" smd circle
			(at -0.40005 0 180)
			(size 0 0)
			(layers "B.Cu" "B.Mask" "B.Paste")
			(net "GND")
		)
	)
	(footprint ""
		(layer "B.Cu")
		(at 329.367388 -333.62138 -90)
		(property "Reference" "PC245_P0_7"
			(at 0 0 90)
			(layer "B.SilkS")
			(hide yes)
			(effects
				(font
					(size 1.27 1.27)
				)
				(justify mirror)
			)
		)
		(property "Value" ""
			(at 0 0 90)
			(layer "B.Fab")
			(effects
				(font
					(size 1.27 1.27)
				)
				(justify mirror)
			)
		)
		(duplicate_pad_numbers_are_jumpers no)
		(fp_line
			(start -1.524 0.762)
			(end 1.524 0.762)
			(stroke
				(width 0.1524)
				(type default)
			)
			(layer "B.SilkS")
		)
		(fp_line
			(start 1.524 0.762)
			(end 1.524 -0.762)
			(stroke
				(width 0.1524)
				(type default)
			)
			(layer "B.SilkS")
		)
		(fp_line
			(start -1.524 -0.762)
			(end -1.524 0.762)
			(stroke
				(width 0.1524)
				(type default)
			)
			(layer "B.SilkS")
		)
		(fp_line
			(start 1.524 -0.762)
			(end -1.524 -0.762)
			(stroke
				(width 0.1524)
				(type default)
			)
			(layer "B.SilkS")
		)
		(fp_line
			(start -1.1049 0.724916)
			(end -1.1049 -0.724916)
			(stroke
				(width 0.1)
				(type default)
			)
			(layer "B.Fab")
		)
		(fp_line
			(start 1.1049 0.724916)
			(end -1.1049 0.724916)
			(stroke
				(width 0.1)
				(type default)
			)
			(layer "B.Fab")
		)
		(fp_line
			(start -1.1049 -0.724916)
			(end 1.1049 -0.724916)
			(stroke
				(width 0.1)
				(type default)
			)
			(layer "B.Fab")
		)
		(fp_line
			(start 1.1049 -0.724916)
			(end 1.1049 0.724916)
			(stroke
				(width 0.1)
				(type default)
			)
			(layer "B.Fab")
		)
		(pad "1" smd rect
			(at 0.889 0 270)
			(size 1.016 1.27)
			(layers "B.Cu" "B.Mask" "B.Paste")
			(net "PVCCIN_CPU0")
		)
		(pad "2" smd rect
			(at -0.889 0 270)
			(size 1.016 1.27)
			(layers "B.Cu" "B.Mask" "B.Paste")
			(net "GND")
		)
	)
	(footprint ""
		(layer "B.Cu")
		(at 444.485014 -319.263776 180)
		(property "Reference" "C38"
			(at 0 0 0)
			(layer "B.SilkS")
			(hide yes)
			(effects
				(font
					(size 1.27 1.27)
				)
				(justify mirror)
			)
		)
		(property "Value" ""
			(at 0 0 0)
			(layer "B.Fab")
			(effects
				(font
					(size 1.27 1.27)
				)
				(justify mirror)
			)
		)
		(duplicate_pad_numbers_are_jumpers no)
		(fp_line
			(start 0.7874 0.4064)
			(end 0.7874 -0.4064)
			(stroke
				(width 0.1524)
				(type default)
			)
			(layer "B.SilkS")
		)
		(fp_line
			(start 0.7874 -0.4064)
			(end -0.7874 -0.4064)
			(stroke
				(width 0.1524)
				(type default)
			)
			(layer "B.SilkS")
		)
		(fp_line
			(start -0.7874 0.4064)
			(end 0.7874 0.4064)
			(stroke
				(width 0.1524)
				(type default)
			)
			(layer "B.SilkS")
		)
		(fp_line
			(start -0.7874 -0.4064)
			(end -0.7874 0.4064)
			(stroke
				(width 0.1524)
				(type default)
			)
			(layer "B.SilkS")
		)
		(fp_line
			(start 0.67945 0.3048)
			(end 0.67945 -0.305054)
			(stroke
				(width 0.1)
				(type default)
			)
			(layer "B.Fab")
		)
		(fp_line
			(start 0.67945 -0.305054)
			(end 0.12065 -0.305054)
			(stroke
				(width 0.1)
				(type default)
			)
			(layer "B.Fab")
		)
		(fp_line
			(start 0.12065 0.3048)
			(end 0.67945 0.3048)
			(stroke
				(width 0.1)
				(type default)
			)
			(layer "B.Fab")
		)
		(fp_line
			(start 0.12065 0.2794)
			(end 0.12065 0.3048)
			(stroke
				(width 0.1)
				(type default)
			)
			(layer "B.Fab")
		)
		(fp_line
			(start 0.12065 -0.2794)
			(end -0.12065 -0.2794)
			(stroke
				(width 0.1)
				(type default)
			)
			(layer "B.Fab")
		)
		(fp_line
			(start 0.12065 -0.305054)
			(end 0.12065 -0.2794)
			(stroke
				(width 0.1)
				(type default)
			)
			(layer "B.Fab")
		)
		(fp_line
			(start -0.120396 0.3048)
			(end -0.120396 0.2794)
			(stroke
				(width 0.1)
				(type default)
			)
			(layer "B.Fab")
		)
		(fp_line
			(start -0.120396 0.2794)
			(end 0.12065 0.2794)
			(stroke
				(width 0.1)
				(type default)
			)
			(layer "B.Fab")
		)
		(fp_line
			(start -0.12065 -0.2794)
			(end -0.12065 -0.3048)
			(stroke
				(width 0.1)
				(type default)
			)
			(layer "B.Fab")
		)
		(fp_line
			(start -0.12065 -0.3048)
			(end -0.67945 -0.3048)
			(stroke
				(width 0.1)
				(type default)
			)
			(layer "B.Fab")
		)
		(fp_line
			(start -0.67945 0.3048)
			(end -0.120396 0.3048)
			(stroke
				(width 0.1)
				(type default)
			)
			(layer "B.Fab")
		)
		(fp_line
			(start -0.67945 -0.3048)
			(end -0.67945 0.3048)
			(stroke
				(width 0.1)
				(type default)
			)
			(layer "B.Fab")
		)
		(pad "1" smd circle
			(at 0.40005 0)
			(size 0 0)
			(layers "B.Cu" "B.Mask" "B.Paste")
			(net "P3V3_AUX")
		)
		(pad "2" smd circle
			(at -0.40005 0)
			(size 0 0)
			(layers "B.Cu" "B.Mask" "B.Paste")
			(net "GND")
		)
	)
	(footprint ""
		(layer "B.Cu")
		(at 83.62315 -52.082446 180)
		(property "Reference" "R3833"
			(at 0 0 0)
			(layer "B.SilkS")
			(hide yes)
			(effects
				(font
					(size 1.27 1.27)
				)
				(justify mirror)
			)
		)
		(property "Value" ""
			(at 0 0 0)
			(layer "B.Fab")
			(effects
				(font
					(size 1.27 1.27)
				)
				(justify mirror)
			)
		)
		(duplicate_pad_numbers_are_jumpers no)
		(fp_line
			(start 0.7874 0.4064)
			(end 0.7874 -0.4064)
			(stroke
				(width 0.1524)
				(type default)
			)
			(layer "B.SilkS")
		)
		(fp_line
			(start 0.7874 -0.4064)
			(end -0.7874 -0.4064)
			(stroke
				(width 0.1524)
				(type default)
			)
			(layer "B.SilkS")
		)
		(fp_line
			(start -0.7874 0.4064)
			(end 0.7874 0.4064)
			(stroke
				(width 0.1524)
				(type default)
			)
			(layer "B.SilkS")
		)
		(fp_line
			(start -0.7874 -0.4064)
			(end -0.7874 0.4064)
			(stroke
				(width 0.1524)
				(type default)
			)
			(layer "B.SilkS")
		)
		(fp_line
			(start 0.67945 0.3048)
			(end 0.67945 -0.305054)
			(stroke
				(width 0.1)
				(type default)
			)
			(layer "B.Fab")
		)
		(fp_line
			(start 0.67945 -0.305054)
			(end 0.12065 -0.305054)
			(stroke
				(width 0.1)
				(type default)
			)
			(layer "B.Fab")
		)
		(fp_line
			(start 0.12065 0.3048)
			(end 0.67945 0.3048)
			(stroke
				(width 0.1)
				(type default)
			)
			(layer "B.Fab")
		)
		(fp_line
			(start 0.12065 0.2794)
			(end 0.12065 0.3048)
			(stroke
				(width 0.1)
				(type default)
			)
			(layer "B.Fab")
		)
		(fp_line
			(start 0.12065 -0.2794)
			(end -0.12065 -0.2794)
			(stroke
				(width 0.1)
				(type default)
			)
			(layer "B.Fab")
		)
		(fp_line
			(start 0.12065 -0.305054)
			(end 0.12065 -0.2794)
			(stroke
				(width 0.1)
				(type default)
			)
			(layer "B.Fab")
		)
		(fp_line
			(start -0.120396 0.3048)
			(end -0.120396 0.2794)
			(stroke
				(width 0.1)
				(type default)
			)
			(layer "B.Fab")
		)
		(fp_line
			(start -0.120396 0.2794)
			(end 0.12065 0.2794)
			(stroke
				(width 0.1)
				(type default)
			)
			(layer "B.Fab")
		)
		(fp_line
			(start -0.12065 -0.2794)
			(end -0.12065 -0.3048)
			(stroke
				(width 0.1)
				(type default)
			)
			(layer "B.Fab")
		)
		(fp_line
			(start -0.12065 -0.3048)
			(end -0.67945 -0.3048)
			(stroke
				(width 0.1)
				(type default)
			)
			(layer "B.Fab")
		)
		(fp_line
			(start -0.67945 0.3048)
			(end -0.120396 0.3048)
			(stroke
				(width 0.1)
				(type default)
			)
			(layer "B.Fab")
		)
		(fp_line
			(start -0.67945 -0.3048)
			(end -0.67945 0.3048)
			(stroke
				(width 0.1)
				(type default)
			)
			(layer "B.Fab")
		)
		(pad "1" smd circle
			(at 0.40005 0)
			(size 0 0)
			(layers "B.Cu" "B.Mask" "B.Paste")
			(net "P3V3_AUX")
		)
		(pad "2" smd circle
			(at -0.40005 0)
			(size 0 0)
			(layers "B.Cu" "B.Mask" "B.Paste")
			(net "P3V3_OCP_FAULT_2")
		)
	)
	(footprint ""
		(layer "B.Cu")
		(at 346.497148 -31.527242 180)
		(property "Reference" "R2348"
			(at 0 0 0)
			(layer "B.SilkS")
			(hide yes)
			(effects
				(font
					(size 1.27 1.27)
				)
				(justify mirror)
			)
		)
		(property "Value" ""
			(at 0 0 0)
			(layer "B.Fab")
			(effects
				(font
					(size 1.27 1.27)
				)
				(justify mirror)
			)
		)
		(duplicate_pad_numbers_are_jumpers no)
		(fp_line
			(start 0.7874 0.4064)
			(end 0.7874 -0.4064)
			(stroke
				(width 0.1524)
				(type default)
			)
			(layer "B.SilkS")
		)
		(fp_line
			(start 0.7874 -0.4064)
			(end -0.7874 -0.4064)
			(stroke
				(width 0.1524)
				(type default)
			)
			(layer "B.SilkS")
		)
		(fp_line
			(start -0.7874 0.4064)
			(end 0.7874 0.4064)
			(stroke
				(width 0.1524)
				(type default)
			)
			(layer "B.SilkS")
		)
		(fp_line
			(start -0.7874 -0.4064)
			(end -0.7874 0.4064)
			(stroke
				(width 0.1524)
				(type default)
			)
			(layer "B.SilkS")
		)
		(fp_line
			(start 0.67945 0.3048)
			(end 0.67945 -0.305054)
			(stroke
				(width 0.1)
				(type default)
			)
			(layer "B.Fab")
		)
		(fp_line
			(start 0.67945 -0.305054)
			(end 0.12065 -0.305054)
			(stroke
				(width 0.1)
				(type default)
			)
			(layer "B.Fab")
		)
		(fp_line
			(start 0.12065 0.3048)
			(end 0.67945 0.3048)
			(stroke
				(width 0.1)
				(type default)
			)
			(layer "B.Fab")
		)
		(fp_line
			(start 0.12065 0.2794)
			(end 0.12065 0.3048)
			(stroke
				(width 0.1)
				(type default)
			)
			(layer "B.Fab")
		)
		(fp_line
			(start 0.12065 -0.2794)
			(end -0.12065 -0.2794)
			(stroke
				(width 0.1)
				(type default)
			)
			(layer "B.Fab")
		)
		(fp_line
			(start 0.12065 -0.305054)
			(end 0.12065 -0.2794)
			(stroke
				(width 0.1)
				(type default)
			)
			(layer "B.Fab")
		)
		(fp_line
			(start -0.120396 0.3048)
			(end -0.120396 0.2794)
			(stroke
				(width 0.1)
				(type default)
			)
			(layer "B.Fab")
		)
		(fp_line
			(start -0.120396 0.2794)
			(end 0.12065 0.2794)
			(stroke
				(width 0.1)
				(type default)
			)
			(layer "B.Fab")
		)
		(fp_line
			(start -0.12065 -0.2794)
			(end -0.12065 -0.3048)
			(stroke
				(width 0.1)
				(type default)
			)
			(layer "B.Fab")
		)
		(fp_line
			(start -0.12065 -0.3048)
			(end -0.67945 -0.3048)
			(stroke
				(width 0.1)
				(type default)
			)
			(layer "B.Fab")
		)
		(fp_line
			(start -0.67945 0.3048)
			(end -0.120396 0.3048)
			(stroke
				(width 0.1)
				(type default)
			)
			(layer "B.Fab")
		)
		(fp_line
			(start -0.67945 -0.3048)
			(end -0.67945 0.3048)
			(stroke
				(width 0.1)
				(type default)
			)
			(layer "B.Fab")
		)
		(pad "1" smd circle
			(at 0.40005 0)
			(size 0 0)
			(layers "B.Cu" "B.Mask" "B.Paste")
			(net "FM_DEBUG_PORT_PRSNT_N")
		)
		(pad "2" smd circle
			(at -0.40005 0)
			(size 0 0)
			(layers "B.Cu" "B.Mask" "B.Paste")
			(net "FM_DEBUG_PORT_PRSNT_R_N")
		)
	)
	(footprint ""
		(layer "B.Cu")
		(at 192.724532 -423.657014 -90)
		(property "Reference" "R4703"
			(at 0 0 90)
			(layer "B.SilkS")
			(hide yes)
			(effects
				(font
					(size 1.27 1.27)
				)
				(justify mirror)
			)
		)
		(property "Value" ""
			(at 0 0 90)
			(layer "B.Fab")
			(effects
				(font
					(size 1.27 1.27)
				)
				(justify mirror)
			)
		)
		(duplicate_pad_numbers_are_jumpers no)
		(fp_line
			(start -0.7874 0.4064)
			(end 0.7874 0.4064)
			(stroke
				(width 0.1524)
				(type default)
			)
			(layer "B.SilkS")
		)
		(fp_line
			(start 0.7874 0.4064)
			(end 0.7874 -0.4064)
			(stroke
				(width 0.1524)
				(type default)
			)
			(layer "B.SilkS")
		)
		(fp_line
			(start -0.7874 -0.4064)
			(end -0.7874 0.4064)
			(stroke
				(width 0.1524)
				(type default)
			)
			(layer "B.SilkS")
		)
		(fp_line
			(start 0.7874 -0.4064)
			(end -0.7874 -0.4064)
			(stroke
				(width 0.1524)
				(type default)
			)
			(layer "B.SilkS")
		)
		(fp_line
			(start -0.67945 0.3048)
			(end -0.120396 0.3048)
			(stroke
				(width 0.1)
				(type default)
			)
			(layer "B.Fab")
		)
		(fp_line
			(start -0.120396 0.3048)
			(end -0.120396 0.2794)
			(stroke
				(width 0.1)
				(type default)
			)
			(layer "B.Fab")
		)
		(fp_line
			(start 0.12065 0.3048)
			(end 0.67945 0.3048)
			(stroke
				(width 0.1)
				(type default)
			)
			(layer "B.Fab")
		)
		(fp_line
			(start 0.67945 0.3048)
			(end 0.67945 -0.305054)
			(stroke
				(width 0.1)
				(type default)
			)
			(layer "B.Fab")
		)
		(fp_line
			(start -0.120396 0.2794)
			(end 0.12065 0.2794)
			(stroke
				(width 0.1)
				(type default)
			)
			(layer "B.Fab")
		)
		(fp_line
			(start 0.12065 0.2794)
			(end 0.12065 0.3048)
			(stroke
				(width 0.1)
				(type default)
			)
			(layer "B.Fab")
		)
		(fp_line
			(start -0.12065 -0.2794)
			(end -0.12065 -0.3048)
			(stroke
				(width 0.1)
				(type default)
			)
			(layer "B.Fab")
		)
		(fp_line
			(start 0.12065 -0.2794)
			(end -0.12065 -0.2794)
			(stroke
				(width 0.1)
				(type default)
			)
			(layer "B.Fab")
		)
		(fp_line
			(start -0.67945 -0.3048)
			(end -0.67945 0.3048)
			(stroke
				(width 0.1)
				(type default)
			)
			(layer "B.Fab")
		)
		(fp_line
			(start -0.12065 -0.3048)
			(end -0.67945 -0.3048)
			(stroke
				(width 0.1)
				(type default)
			)
			(layer "B.Fab")
		)
		(fp_line
			(start 0.12065 -0.305054)
			(end 0.12065 -0.2794)
			(stroke
				(width 0.1)
				(type default)
			)
			(layer "B.Fab")
		)
		(fp_line
			(start 0.67945 -0.305054)
			(end 0.12065 -0.305054)
			(stroke
				(width 0.1)
				(type default)
			)
			(layer "B.Fab")
		)
		(pad "1" smd circle
			(at 0.40005 0 90)
			(size 0 0)
			(layers "B.Cu" "B.Mask" "B.Paste")
			(net "LED_P12V_PSU_R1")
		)
		(pad "2" smd circle
			(at -0.40005 0 90)
			(size 0 0)
			(layers "B.Cu" "B.Mask" "B.Paste")
			(net "LED_P12V_PSU_R2")
		)
	)
	(footprint ""
		(layer "B.Cu")
		(at 386.861812 -342.936576 90)
		(property "Reference" "PC240_P0_8"
			(at 0 0 90)
			(layer "B.SilkS")
			(hide yes)
			(effects
				(font
					(size 1.27 1.27)
				)
				(justify mirror)
			)
		)
		(property "Value" ""
			(at 0 0 90)
			(layer "B.Fab")
			(effects
				(font
					(size 1.27 1.27)
				)
				(justify mirror)
			)
		)
		(duplicate_pad_numbers_are_jumpers no)
		(fp_line
			(start 1.524 -0.762)
			(end -1.524 -0.762)
			(stroke
				(width 0.1524)
				(type default)
			)
			(layer "B.SilkS")
		)
		(fp_line
			(start -1.524 -0.762)
			(end -1.524 0.762)
			(stroke
				(width 0.1524)
				(type default)
			)
			(layer "B.SilkS")
		)
		(fp_line
			(start 1.524 0.762)
			(end 1.524 -0.762)
			(stroke
				(width 0.1524)
				(type default)
			)
			(layer "B.SilkS")
		)
		(fp_line
			(start -1.524 0.762)
			(end 1.524 0.762)
			(stroke
				(width 0.1524)
				(type default)
			)
			(layer "B.SilkS")
		)
		(fp_line
			(start 1.1049 -0.724916)
			(end 1.1049 0.724916)
			(stroke
				(width 0.1)
				(type default)
			)
			(layer "B.Fab")
		)
		(fp_line
			(start -1.1049 -0.724916)
			(end 1.1049 -0.724916)
			(stroke
				(width 0.1)
				(type default)
			)
			(layer "B.Fab")
		)
		(fp_line
			(start 1.1049 0.724916)
			(end -1.1049 0.724916)
			(stroke
				(width 0.1)
				(type default)
			)
			(layer "B.Fab")
		)
		(fp_line
			(start -1.1049 0.724916)
			(end -1.1049 -0.724916)
			(stroke
				(width 0.1)
				(type default)
			)
			(layer "B.Fab")
		)
		(pad "1" smd rect
			(at 0.889 0 90)
			(size 1.016 1.27)
			(layers "B.Cu" "B.Mask" "B.Paste")
			(net "SW_P12V_PVCCIN_CPU0_FLT")
		)
		(pad "2" smd rect
			(at -0.889 0 90)
			(size 1.016 1.27)
			(layers "B.Cu" "B.Mask" "B.Paste")
			(net "GND")
		)
	)
	(footprint ""
		(layer "B.Cu")
		(at 313.014614 -258.379976 -90)
		(property "Reference" "C526"
			(at 0 0 90)
			(layer "B.SilkS")
			(hide yes)
			(effects
				(font
					(size 1.27 1.27)
				)
				(justify mirror)
			)
		)
		(property "Value" ""
			(at 0 0 90)
			(layer "B.Fab")
			(effects
				(font
					(size 1.27 1.27)
				)
				(justify mirror)
			)
		)
		(duplicate_pad_numbers_are_jumpers no)
		(fp_line
			(start -1.524 0.762)
			(end 1.524 0.762)
			(stroke
				(width 0.1524)
				(type default)
			)
			(layer "B.SilkS")
		)
		(fp_line
			(start 1.524 0.762)
			(end 1.524 -0.762)
			(stroke
				(width 0.1524)
				(type default)
			)
			(layer "B.SilkS")
		)
		(fp_line
			(start -1.524 -0.762)
			(end -1.524 0.762)
			(stroke
				(width 0.1524)
				(type default)
			)
			(layer "B.SilkS")
		)
		(fp_line
			(start 1.524 -0.762)
			(end -1.524 -0.762)
			(stroke
				(width 0.1524)
				(type default)
			)
			(layer "B.SilkS")
		)
		(fp_line
			(start -1.1049 0.724916)
			(end -1.1049 -0.724916)
			(stroke
				(width 0.1)
				(type default)
			)
			(layer "B.Fab")
		)
		(fp_line
			(start 1.1049 0.724916)
			(end -1.1049 0.724916)
			(stroke
				(width 0.1)
				(type default)
			)
			(layer "B.Fab")
		)
		(fp_line
			(start -1.1049 -0.724916)
			(end 1.1049 -0.724916)
			(stroke
				(width 0.1)
				(type default)
			)
			(layer "B.Fab")
		)
		(fp_line
			(start 1.1049 -0.724916)
			(end 1.1049 0.724916)
			(stroke
				(width 0.1)
				(type default)
			)
			(layer "B.Fab")
		)
		(pad "1" smd rect
			(at 0.889 0 270)
			(size 1.016 1.27)
			(layers "B.Cu" "B.Mask" "B.Paste")
			(net "PVCCFA_EHV_FIVRA_CPU0")
		)
		(pad "2" smd rect
			(at -0.889 0 270)
			(size 1.016 1.27)
			(layers "B.Cu" "B.Mask" "B.Paste")
			(net "GND")
		)
	)
	(footprint ""
		(layer "B.Cu")
		(at 105.679494 -252.17628 -90)
		(property "Reference" "C330"
			(at 0 0 90)
			(layer "B.SilkS")
			(hide yes)
			(effects
				(font
					(size 1.27 1.27)
				)
				(justify mirror)
			)
		)
		(property "Value" ""
			(at 0 0 90)
			(layer "B.Fab")
			(effects
				(font
					(size 1.27 1.27)
				)
				(justify mirror)
			)
		)
		(duplicate_pad_numbers_are_jumpers no)
		(fp_line
			(start -1.524 0.762)
			(end 1.524 0.762)
			(stroke
				(width 0.1524)
				(type default)
			)
			(layer "B.SilkS")
		)
		(fp_line
			(start 1.524 0.762)
			(end 1.524 -0.762)
			(stroke
				(width 0.1524)
				(type default)
			)
			(layer "B.SilkS")
		)
		(fp_line
			(start -1.524 -0.762)
			(end -1.524 0.762)
			(stroke
				(width 0.1524)
				(type default)
			)
			(layer "B.SilkS")
		)
		(fp_line
			(start 1.524 -0.762)
			(end -1.524 -0.762)
			(stroke
				(width 0.1524)
				(type default)
			)
			(layer "B.SilkS")
		)
		(fp_line
			(start -1.1049 0.724916)
			(end -1.1049 -0.724916)
			(stroke
				(width 0.1)
				(type default)
			)
			(layer "B.Fab")
		)
		(fp_line
			(start 1.1049 0.724916)
			(end -1.1049 0.724916)
			(stroke
				(width 0.1)
				(type default)
			)
			(layer "B.Fab")
		)
		(fp_line
			(start -1.1049 -0.724916)
			(end 1.1049 -0.724916)
			(stroke
				(width 0.1)
				(type default)
			)
			(layer "B.Fab")
		)
		(fp_line
			(start 1.1049 -0.724916)
			(end 1.1049 0.724916)
			(stroke
				(width 0.1)
				(type default)
			)
			(layer "B.Fab")
		)
		(pad "1" smd rect
			(at 0.889 0 270)
			(size 1.016 1.27)
			(layers "B.Cu" "B.Mask" "B.Paste")
			(net "PVCCIN_CPU1")
		)
		(pad "2" smd rect
			(at -0.889 0 270)
			(size 1.016 1.27)
			(layers "B.Cu" "B.Mask" "B.Paste")
			(net "GND")
		)
	)
	(footprint ""
		(layer "B.Cu")
		(at 105.679494 -259.53212 90)
		(property "Reference" "C461"
			(at 0 0 90)
			(layer "B.SilkS")
			(hide yes)
			(effects
				(font
					(size 1.27 1.27)
				)
				(justify mirror)
			)
		)
		(property "Value" ""
			(at 0 0 90)
			(layer "B.Fab")
			(effects
				(font
					(size 1.27 1.27)
				)
				(justify mirror)
			)
		)
		(duplicate_pad_numbers_are_jumpers no)
		(fp_line
			(start 1.524 -0.762)
			(end -1.524 -0.762)
			(stroke
				(width 0.1524)
				(type default)
			)
			(layer "B.SilkS")
		)
		(fp_line
			(start -1.524 -0.762)
			(end -1.524 0.762)
			(stroke
				(width 0.1524)
				(type default)
			)
			(layer "B.SilkS")
		)
		(fp_line
			(start 1.524 0.762)
			(end 1.524 -0.762)
			(stroke
				(width 0.1524)
				(type default)
			)
			(layer "B.SilkS")
		)
		(fp_line
			(start -1.524 0.762)
			(end 1.524 0.762)
			(stroke
				(width 0.1524)
				(type default)
			)
			(layer "B.SilkS")
		)
		(fp_line
			(start 1.1049 -0.724916)
			(end 1.1049 0.724916)
			(stroke
				(width 0.1)
				(type default)
			)
			(layer "B.Fab")
		)
		(fp_line
			(start -1.1049 -0.724916)
			(end 1.1049 -0.724916)
			(stroke
				(width 0.1)
				(type default)
			)
			(layer "B.Fab")
		)
		(fp_line
			(start 1.1049 0.724916)
			(end -1.1049 0.724916)
			(stroke
				(width 0.1)
				(type default)
			)
			(layer "B.Fab")
		)
		(fp_line
			(start -1.1049 0.724916)
			(end -1.1049 -0.724916)
			(stroke
				(width 0.1)
				(type default)
			)
			(layer "B.Fab")
		)
		(pad "1" smd rect
			(at 0.889 0 90)
			(size 1.016 1.27)
			(layers "B.Cu" "B.Mask" "B.Paste")
			(net "PVCCFA_EHV_FIVRA_CPU1")
		)
		(pad "2" smd rect
			(at -0.889 0 90)
			(size 1.016 1.27)
			(layers "B.Cu" "B.Mask" "B.Paste")
			(net "GND")
		)
	)
	(footprint ""
		(layer "B.Cu")
		(at 229.33025 -117.960648 -90)
		(property "Reference" "R4495"
			(at 0 0 90)
			(layer "B.SilkS")
			(hide yes)
			(effects
				(font
					(size 1.27 1.27)
				)
				(justify mirror)
			)
		)
		(property "Value" ""
			(at 0 0 90)
			(layer "B.Fab")
			(effects
				(font
					(size 1.27 1.27)
				)
				(justify mirror)
			)
		)
		(duplicate_pad_numbers_are_jumpers no)
		(fp_line
			(start -0.7874 0.4064)
			(end 0.7874 0.4064)
			(stroke
				(width 0.1524)
				(type default)
			)
			(layer "B.SilkS")
		)
		(fp_line
			(start 0.7874 0.4064)
			(end 0.7874 -0.4064)
			(stroke
				(width 0.1524)
				(type default)
			)
			(layer "B.SilkS")
		)
		(fp_line
			(start -0.7874 -0.4064)
			(end -0.7874 0.4064)
			(stroke
				(width 0.1524)
				(type default)
			)
			(layer "B.SilkS")
		)
		(fp_line
			(start 0.7874 -0.4064)
			(end -0.7874 -0.4064)
			(stroke
				(width 0.1524)
				(type default)
			)
			(layer "B.SilkS")
		)
		(fp_line
			(start -0.67945 0.3048)
			(end -0.120396 0.3048)
			(stroke
				(width 0.1)
				(type default)
			)
			(layer "B.Fab")
		)
		(fp_line
			(start -0.120396 0.3048)
			(end -0.120396 0.2794)
			(stroke
				(width 0.1)
				(type default)
			)
			(layer "B.Fab")
		)
		(fp_line
			(start 0.12065 0.3048)
			(end 0.67945 0.3048)
			(stroke
				(width 0.1)
				(type default)
			)
			(layer "B.Fab")
		)
		(fp_line
			(start 0.67945 0.3048)
			(end 0.67945 -0.305054)
			(stroke
				(width 0.1)
				(type default)
			)
			(layer "B.Fab")
		)
		(fp_line
			(start -0.120396 0.2794)
			(end 0.12065 0.2794)
			(stroke
				(width 0.1)
				(type default)
			)
			(layer "B.Fab")
		)
		(fp_line
			(start 0.12065 0.2794)
			(end 0.12065 0.3048)
			(stroke
				(width 0.1)
				(type default)
			)
			(layer "B.Fab")
		)
		(fp_line
			(start -0.12065 -0.2794)
			(end -0.12065 -0.3048)
			(stroke
				(width 0.1)
				(type default)
			)
			(layer "B.Fab")
		)
		(fp_line
			(start 0.12065 -0.2794)
			(end -0.12065 -0.2794)
			(stroke
				(width 0.1)
				(type default)
			)
			(layer "B.Fab")
		)
		(fp_line
			(start -0.67945 -0.3048)
			(end -0.67945 0.3048)
			(stroke
				(width 0.1)
				(type default)
			)
			(layer "B.Fab")
		)
		(fp_line
			(start -0.12065 -0.3048)
			(end -0.67945 -0.3048)
			(stroke
				(width 0.1)
				(type default)
			)
			(layer "B.Fab")
		)
		(fp_line
			(start 0.12065 -0.305054)
			(end 0.12065 -0.2794)
			(stroke
				(width 0.1)
				(type default)
			)
			(layer "B.Fab")
		)
		(fp_line
			(start 0.67945 -0.305054)
			(end 0.12065 -0.305054)
			(stroke
				(width 0.1)
				(type default)
			)
			(layer "B.Fab")
		)
		(pad "1" smd circle
			(at 0.40005 0 90)
			(size 0 0)
			(layers "B.Cu" "B.Mask" "B.Paste")
			(net "OCP_SFF_CLK_OE_R_N")
		)
		(pad "2" smd circle
			(at -0.40005 0 90)
			(size 0 0)
			(layers "B.Cu" "B.Mask" "B.Paste")
			(net "OCP_SFF_CLK_OE_N")
		)
	)
	(footprint ""
		(layer "B.Cu")
		(at 145.415 -9.362948 -90)
		(property "Reference" "R3057"
			(at 0 0 90)
			(layer "B.SilkS")
			(hide yes)
			(effects
				(font
					(size 1.27 1.27)
				)
				(justify mirror)
			)
		)
		(property "Value" ""
			(at 0 0 90)
			(layer "B.Fab")
			(effects
				(font
					(size 1.27 1.27)
				)
				(justify mirror)
			)
		)
		(duplicate_pad_numbers_are_jumpers no)
		(fp_line
			(start -0.7874 0.4064)
			(end 0.7874 0.4064)
			(stroke
				(width 0.1524)
				(type default)
			)
			(layer "B.SilkS")
		)
		(fp_line
			(start 0.7874 0.4064)
			(end 0.7874 -0.4064)
			(stroke
				(width 0.1524)
				(type default)
			)
			(layer "B.SilkS")
		)
		(fp_line
			(start -0.7874 -0.4064)
			(end -0.7874 0.4064)
			(stroke
				(width 0.1524)
				(type default)
			)
			(layer "B.SilkS")
		)
		(fp_line
			(start 0.7874 -0.4064)
			(end -0.7874 -0.4064)
			(stroke
				(width 0.1524)
				(type default)
			)
			(layer "B.SilkS")
		)
		(fp_line
			(start -0.67945 0.3048)
			(end -0.120396 0.3048)
			(stroke
				(width 0.1)
				(type default)
			)
			(layer "B.Fab")
		)
		(fp_line
			(start -0.120396 0.3048)
			(end -0.120396 0.2794)
			(stroke
				(width 0.1)
				(type default)
			)
			(layer "B.Fab")
		)
		(fp_line
			(start 0.12065 0.3048)
			(end 0.67945 0.3048)
			(stroke
				(width 0.1)
				(type default)
			)
			(layer "B.Fab")
		)
		(fp_line
			(start 0.67945 0.3048)
			(end 0.67945 -0.305054)
			(stroke
				(width 0.1)
				(type default)
			)
			(layer "B.Fab")
		)
		(fp_line
			(start -0.120396 0.2794)
			(end 0.12065 0.2794)
			(stroke
				(width 0.1)
				(type default)
			)
			(layer "B.Fab")
		)
		(fp_line
			(start 0.12065 0.2794)
			(end 0.12065 0.3048)
			(stroke
				(width 0.1)
				(type default)
			)
			(layer "B.Fab")
		)
		(fp_line
			(start -0.12065 -0.2794)
			(end -0.12065 -0.3048)
			(stroke
				(width 0.1)
				(type default)
			)
			(layer "B.Fab")
		)
		(fp_line
			(start 0.12065 -0.2794)
			(end -0.12065 -0.2794)
			(stroke
				(width 0.1)
				(type default)
			)
			(layer "B.Fab")
		)
		(fp_line
			(start -0.67945 -0.3048)
			(end -0.67945 0.3048)
			(stroke
				(width 0.1)
				(type default)
			)
			(layer "B.Fab")
		)
		(fp_line
			(start -0.12065 -0.3048)
			(end -0.67945 -0.3048)
			(stroke
				(width 0.1)
				(type default)
			)
			(layer "B.Fab")
		)
		(fp_line
			(start 0.12065 -0.305054)
			(end 0.12065 -0.2794)
			(stroke
				(width 0.1)
				(type default)
			)
			(layer "B.Fab")
		)
		(fp_line
			(start 0.67945 -0.305054)
			(end 0.12065 -0.305054)
			(stroke
				(width 0.1)
				(type default)
			)
			(layer "B.Fab")
		)
		(pad "1" smd circle
			(at 0.40005 0 90)
			(size 0 0)
			(layers "B.Cu" "B.Mask" "B.Paste")
			(net "JTAG_DBP_BMC_PREQ_R1_N")
		)
		(pad "2" smd circle
			(at -0.40005 0 90)
			(size 0 0)
			(layers "B.Cu" "B.Mask" "B.Paste")
			(net "JTAG_BMC_DBP_PREQ_N")
		)
	)
	(footprint ""
		(layer "B.Cu")
		(at 42.392346 -319.268856 180)
		(property "Reference" "R895"
			(at 0 0 0)
			(layer "B.SilkS")
			(hide yes)
			(effects
				(font
					(size 1.27 1.27)
				)
				(justify mirror)
			)
		)
		(property "Value" ""
			(at 0 0 0)
			(layer "B.Fab")
			(effects
				(font
					(size 1.27 1.27)
				)
				(justify mirror)
			)
		)
		(duplicate_pad_numbers_are_jumpers no)
		(fp_line
			(start 0.7874 0.4064)
			(end 0.7874 -0.4064)
			(stroke
				(width 0.1524)
				(type default)
			)
			(layer "B.SilkS")
		)
		(fp_line
			(start 0.7874 -0.4064)
			(end -0.7874 -0.4064)
			(stroke
				(width 0.1524)
				(type default)
			)
			(layer "B.SilkS")
		)
		(fp_line
			(start -0.7874 0.4064)
			(end 0.7874 0.4064)
			(stroke
				(width 0.1524)
				(type default)
			)
			(layer "B.SilkS")
		)
		(fp_line
			(start -0.7874 -0.4064)
			(end -0.7874 0.4064)
			(stroke
				(width 0.1524)
				(type default)
			)
			(layer "B.SilkS")
		)
		(fp_line
			(start 0.67945 0.3048)
			(end 0.67945 -0.305054)
			(stroke
				(width 0.1)
				(type default)
			)
			(layer "B.Fab")
		)
		(fp_line
			(start 0.67945 -0.305054)
			(end 0.12065 -0.305054)
			(stroke
				(width 0.1)
				(type default)
			)
			(layer "B.Fab")
		)
		(fp_line
			(start 0.12065 0.3048)
			(end 0.67945 0.3048)
			(stroke
				(width 0.1)
				(type default)
			)
			(layer "B.Fab")
		)
		(fp_line
			(start 0.12065 0.2794)
			(end 0.12065 0.3048)
			(stroke
				(width 0.1)
				(type default)
			)
			(layer "B.Fab")
		)
		(fp_line
			(start 0.12065 -0.2794)
			(end -0.12065 -0.2794)
			(stroke
				(width 0.1)
				(type default)
			)
			(layer "B.Fab")
		)
		(fp_line
			(start 0.12065 -0.305054)
			(end 0.12065 -0.2794)
			(stroke
				(width 0.1)
				(type default)
			)
			(layer "B.Fab")
		)
		(fp_line
			(start -0.120396 0.3048)
			(end -0.120396 0.2794)
			(stroke
				(width 0.1)
				(type default)
			)
			(layer "B.Fab")
		)
		(fp_line
			(start -0.120396 0.2794)
			(end 0.12065 0.2794)
			(stroke
				(width 0.1)
				(type default)
			)
			(layer "B.Fab")
		)
		(fp_line
			(start -0.12065 -0.2794)
			(end -0.12065 -0.3048)
			(stroke
				(width 0.1)
				(type default)
			)
			(layer "B.Fab")
		)
		(fp_line
			(start -0.12065 -0.3048)
			(end -0.67945 -0.3048)
			(stroke
				(width 0.1)
				(type default)
			)
			(layer "B.Fab")
		)
		(fp_line
			(start -0.67945 0.3048)
			(end -0.120396 0.3048)
			(stroke
				(width 0.1)
				(type default)
			)
			(layer "B.Fab")
		)
		(fp_line
			(start -0.67945 -0.3048)
			(end -0.67945 0.3048)
			(stroke
				(width 0.1)
				(type default)
			)
			(layer "B.Fab")
		)
		(pad "1" smd circle
			(at 0.40005 0)
			(size 0 0)
			(layers "B.Cu" "B.Mask" "B.Paste")
			(net "PWRGD_CHB_CPU1_DIMM1")
		)
		(pad "2" smd circle
			(at -0.40005 0)
			(size 0 0)
			(layers "B.Cu" "B.Mask" "B.Paste")
			(net "PWRGD_FAIL_CPU1_AB")
		)
	)
	(footprint ""
		(layer "B.Cu")
		(at 105.984294 -237.794292 -90)
		(property "Reference" "C1391"
			(at 0 0 90)
			(layer "B.SilkS")
			(hide yes)
			(effects
				(font
					(size 1.27 1.27)
				)
				(justify mirror)
			)
		)
		(property "Value" ""
			(at 0 0 90)
			(layer "B.Fab")
			(effects
				(font
					(size 1.27 1.27)
				)
				(justify mirror)
			)
		)
		(duplicate_pad_numbers_are_jumpers no)
		(fp_line
			(start -1.2954 0.5842)
			(end 1.2954 0.5842)
			(stroke
				(width 0.1524)
				(type default)
			)
			(layer "B.SilkS")
		)
		(fp_line
			(start 1.2954 0.5842)
			(end 1.2954 -0.5842)
			(stroke
				(width 0.1524)
				(type default)
			)
			(layer "B.SilkS")
		)
		(fp_line
			(start -1.2954 -0.5842)
			(end -1.2954 0.5842)
			(stroke
				(width 0.1524)
				(type default)
			)
			(layer "B.SilkS")
		)
		(fp_line
			(start 0 -0.5842)
			(end 0 0.5842)
			(stroke
				(width 0.1524)
				(type default)
			)
			(layer "B.SilkS")
		)
		(fp_line
			(start 1.2954 -0.5842)
			(end -1.2954 -0.5842)
			(stroke
				(width 0.1524)
				(type default)
			)
			(layer "B.SilkS")
		)
		(fp_line
			(start -0.8636 0.4572)
			(end 0.8636 0.4572)
			(stroke
				(width 0.1)
				(type default)
			)
			(layer "B.Fab")
		)
		(fp_line
			(start 0.8636 0.4572)
			(end 0.8636 0.4064)
			(stroke
				(width 0.1)
				(type default)
			)
			(layer "B.Fab")
		)
		(fp_line
			(start -1.1938 0.4064)
			(end -0.8636 0.4064)
			(stroke
				(width 0.1)
				(type default)
			)
			(layer "B.Fab")
		)
		(fp_line
			(start -0.8636 0.4064)
			(end -0.8636 0.4572)
			(stroke
				(width 0.1)
				(type default)
			)
			(layer "B.Fab")
		)
		(fp_line
			(start 0.8636 0.4064)
			(end 1.1938 0.4064)
			(stroke
				(width 0.1)
				(type default)
			)
			(layer "B.Fab")
		)
		(fp_line
			(start 1.1938 0.4064)
			(end 1.1938 -0.4064)
			(stroke
				(width 0.1)
				(type default)
			)
			(layer "B.Fab")
		)
		(fp_line
			(start -1.1938 -0.4064)
			(end -1.1938 0.4064)
			(stroke
				(width 0.1)
				(type default)
			)
			(layer "B.Fab")
		)
		(fp_line
			(start -0.8636 -0.4064)
			(end -1.1938 -0.4064)
			(stroke
				(width 0.1)
				(type default)
			)
			(layer "B.Fab")
		)
		(fp_line
			(start 0.8636 -0.4064)
			(end 0.8636 -0.4572)
			(stroke
				(width 0.1)
				(type default)
			)
			(layer "B.Fab")
		)
		(fp_line
			(start 1.1938 -0.4064)
			(end 0.8636 -0.4064)
			(stroke
				(width 0.1)
				(type default)
			)
			(layer "B.Fab")
		)
		(fp_line
			(start -0.8636 -0.4572)
			(end -0.8636 -0.4064)
			(stroke
				(width 0.1)
				(type default)
			)
			(layer "B.Fab")
		)
		(fp_line
			(start 0.8636 -0.4572)
			(end -0.8636 -0.4572)
			(stroke
				(width 0.1)
				(type default)
			)
			(layer "B.Fab")
		)
		(pad "1" smd rect
			(at 0.7366 0 180)
			(size 0.7112 0.8128)
			(layers "B.Cu" "B.Mask" "B.Paste")
			(net "PVNN_MAIN_CPU1")
		)
		(pad "2" smd rect
			(at -0.7366 0 180)
			(size 0.7112 0.8128)
			(layers "B.Cu" "B.Mask" "B.Paste")
			(net "GND")
		)
	)
	(footprint ""
		(layer "B.Cu")
		(at 243.99748 -128.336548 -90)
		(property "Reference" "R568"
			(at 0 0 90)
			(layer "B.SilkS")
			(hide yes)
			(effects
				(font
					(size 1.27 1.27)
				)
				(justify mirror)
			)
		)
		(property "Value" ""
			(at 0 0 90)
			(layer "B.Fab")
			(effects
				(font
					(size 1.27 1.27)
				)
				(justify mirror)
			)
		)
		(duplicate_pad_numbers_are_jumpers no)
		(fp_line
			(start -0.7874 0.4064)
			(end 0.7874 0.4064)
			(stroke
				(width 0.1524)
				(type default)
			)
			(layer "B.SilkS")
		)
		(fp_line
			(start 0.7874 0.4064)
			(end 0.7874 -0.4064)
			(stroke
				(width 0.1524)
				(type default)
			)
			(layer "B.SilkS")
		)
		(fp_line
			(start -0.7874 -0.4064)
			(end -0.7874 0.4064)
			(stroke
				(width 0.1524)
				(type default)
			)
			(layer "B.SilkS")
		)
		(fp_line
			(start 0.7874 -0.4064)
			(end -0.7874 -0.4064)
			(stroke
				(width 0.1524)
				(type default)
			)
			(layer "B.SilkS")
		)
		(fp_line
			(start -0.67945 0.3048)
			(end -0.120396 0.3048)
			(stroke
				(width 0.1)
				(type default)
			)
			(layer "B.Fab")
		)
		(fp_line
			(start -0.120396 0.3048)
			(end -0.120396 0.2794)
			(stroke
				(width 0.1)
				(type default)
			)
			(layer "B.Fab")
		)
		(fp_line
			(start 0.12065 0.3048)
			(end 0.67945 0.3048)
			(stroke
				(width 0.1)
				(type default)
			)
			(layer "B.Fab")
		)
		(fp_line
			(start 0.67945 0.3048)
			(end 0.67945 -0.305054)
			(stroke
				(width 0.1)
				(type default)
			)
			(layer "B.Fab")
		)
		(fp_line
			(start -0.120396 0.2794)
			(end 0.12065 0.2794)
			(stroke
				(width 0.1)
				(type default)
			)
			(layer "B.Fab")
		)
		(fp_line
			(start 0.12065 0.2794)
			(end 0.12065 0.3048)
			(stroke
				(width 0.1)
				(type default)
			)
			(layer "B.Fab")
		)
		(fp_line
			(start -0.12065 -0.2794)
			(end -0.12065 -0.3048)
			(stroke
				(width 0.1)
				(type default)
			)
			(layer "B.Fab")
		)
		(fp_line
			(start 0.12065 -0.2794)
			(end -0.12065 -0.2794)
			(stroke
				(width 0.1)
				(type default)
			)
			(layer "B.Fab")
		)
		(fp_line
			(start -0.67945 -0.3048)
			(end -0.67945 0.3048)
			(stroke
				(width 0.1)
				(type default)
			)
			(layer "B.Fab")
		)
		(fp_line
			(start -0.12065 -0.3048)
			(end -0.67945 -0.3048)
			(stroke
				(width 0.1)
				(type default)
			)
			(layer "B.Fab")
		)
		(fp_line
			(start 0.12065 -0.305054)
			(end 0.12065 -0.2794)
			(stroke
				(width 0.1)
				(type default)
			)
			(layer "B.Fab")
		)
		(fp_line
			(start 0.67945 -0.305054)
			(end 0.12065 -0.305054)
			(stroke
				(width 0.1)
				(type default)
			)
			(layer "B.Fab")
		)
		(pad "1" smd circle
			(at 0.40005 0 90)
			(size 0 0)
			(layers "B.Cu" "B.Mask" "B.Paste")
			(net "PD_DB2000_SMB_SA1")
		)
		(pad "2" smd circle
			(at -0.40005 0 90)
			(size 0 0)
			(layers "B.Cu" "B.Mask" "B.Paste")
			(net "GND")
		)
	)
	(footprint ""
		(layer "B.Cu")
		(at 193.501518 -319.423288 180)
		(property "Reference" "R906"
			(at 0 0 0)
			(layer "B.SilkS")
			(hide yes)
			(effects
				(font
					(size 1.27 1.27)
				)
				(justify mirror)
			)
		)
		(property "Value" ""
			(at 0 0 0)
			(layer "B.Fab")
			(effects
				(font
					(size 1.27 1.27)
				)
				(justify mirror)
			)
		)
		(duplicate_pad_numbers_are_jumpers no)
		(fp_line
			(start 0.7874 0.4064)
			(end 0.7874 -0.4064)
			(stroke
				(width 0.1524)
				(type default)
			)
			(layer "B.SilkS")
		)
		(fp_line
			(start 0.7874 -0.4064)
			(end -0.7874 -0.4064)
			(stroke
				(width 0.1524)
				(type default)
			)
			(layer "B.SilkS")
		)
		(fp_line
			(start -0.7874 0.4064)
			(end 0.7874 0.4064)
			(stroke
				(width 0.1524)
				(type default)
			)
			(layer "B.SilkS")
		)
		(fp_line
			(start -0.7874 -0.4064)
			(end -0.7874 0.4064)
			(stroke
				(width 0.1524)
				(type default)
			)
			(layer "B.SilkS")
		)
		(fp_line
			(start 0.67945 0.3048)
			(end 0.67945 -0.305054)
			(stroke
				(width 0.1)
				(type default)
			)
			(layer "B.Fab")
		)
		(fp_line
			(start 0.67945 -0.305054)
			(end 0.12065 -0.305054)
			(stroke
				(width 0.1)
				(type default)
			)
			(layer "B.Fab")
		)
		(fp_line
			(start 0.12065 0.3048)
			(end 0.67945 0.3048)
			(stroke
				(width 0.1)
				(type default)
			)
			(layer "B.Fab")
		)
		(fp_line
			(start 0.12065 0.2794)
			(end 0.12065 0.3048)
			(stroke
				(width 0.1)
				(type default)
			)
			(layer "B.Fab")
		)
		(fp_line
			(start 0.12065 -0.2794)
			(end -0.12065 -0.2794)
			(stroke
				(width 0.1)
				(type default)
			)
			(layer "B.Fab")
		)
		(fp_line
			(start 0.12065 -0.305054)
			(end 0.12065 -0.2794)
			(stroke
				(width 0.1)
				(type default)
			)
			(layer "B.Fab")
		)
		(fp_line
			(start -0.120396 0.3048)
			(end -0.120396 0.2794)
			(stroke
				(width 0.1)
				(type default)
			)
			(layer "B.Fab")
		)
		(fp_line
			(start -0.120396 0.2794)
			(end 0.12065 0.2794)
			(stroke
				(width 0.1)
				(type default)
			)
			(layer "B.Fab")
		)
		(fp_line
			(start -0.12065 -0.2794)
			(end -0.12065 -0.3048)
			(stroke
				(width 0.1)
				(type default)
			)
			(layer "B.Fab")
		)
		(fp_line
			(start -0.12065 -0.3048)
			(end -0.67945 -0.3048)
			(stroke
				(width 0.1)
				(type default)
			)
			(layer "B.Fab")
		)
		(fp_line
			(start -0.67945 0.3048)
			(end -0.120396 0.3048)
			(stroke
				(width 0.1)
				(type default)
			)
			(layer "B.Fab")
		)
		(fp_line
			(start -0.67945 -0.3048)
			(end -0.67945 0.3048)
			(stroke
				(width 0.1)
				(type default)
			)
			(layer "B.Fab")
		)
		(pad "1" smd circle
			(at 0.40005 0)
			(size 0 0)
			(layers "B.Cu" "B.Mask" "B.Paste")
			(net "PWRGD_CHG_CPU1_DIMM2")
		)
		(pad "2" smd circle
			(at -0.40005 0)
			(size 0 0)
			(layers "B.Cu" "B.Mask" "B.Paste")
			(net "PWRGD_FAIL_CPU1_GH")
		)
	)
	(footprint ""
		(layer "B.Cu")
		(at 342.536526 -334.752442 -90)
		(property "Reference" "PR153"
			(at 0 0 90)
			(layer "B.SilkS")
			(hide yes)
			(effects
				(font
					(size 1.27 1.27)
				)
				(justify mirror)
			)
		)
		(property "Value" ""
			(at 0 0 90)
			(layer "B.Fab")
			(effects
				(font
					(size 1.27 1.27)
				)
				(justify mirror)
			)
		)
		(duplicate_pad_numbers_are_jumpers no)
		(fp_line
			(start -0.7874 0.4064)
			(end 0.7874 0.4064)
			(stroke
				(width 0.1524)
				(type default)
			)
			(layer "B.SilkS")
		)
		(fp_line
			(start 0.7874 0.4064)
			(end 0.7874 -0.4064)
			(stroke
				(width 0.1524)
				(type default)
			)
			(layer "B.SilkS")
		)
		(fp_line
			(start -0.7874 -0.4064)
			(end -0.7874 0.4064)
			(stroke
				(width 0.1524)
				(type default)
			)
			(layer "B.SilkS")
		)
		(fp_line
			(start 0.7874 -0.4064)
			(end -0.7874 -0.4064)
			(stroke
				(width 0.1524)
				(type default)
			)
			(layer "B.SilkS")
		)
		(fp_line
			(start -0.67945 0.3048)
			(end -0.120396 0.3048)
			(stroke
				(width 0.1)
				(type default)
			)
			(layer "B.Fab")
		)
		(fp_line
			(start -0.120396 0.3048)
			(end -0.120396 0.2794)
			(stroke
				(width 0.1)
				(type default)
			)
			(layer "B.Fab")
		)
		(fp_line
			(start 0.12065 0.3048)
			(end 0.67945 0.3048)
			(stroke
				(width 0.1)
				(type default)
			)
			(layer "B.Fab")
		)
		(fp_line
			(start 0.67945 0.3048)
			(end 0.67945 -0.305054)
			(stroke
				(width 0.1)
				(type default)
			)
			(layer "B.Fab")
		)
		(fp_line
			(start -0.120396 0.2794)
			(end 0.12065 0.2794)
			(stroke
				(width 0.1)
				(type default)
			)
			(layer "B.Fab")
		)
		(fp_line
			(start 0.12065 0.2794)
			(end 0.12065 0.3048)
			(stroke
				(width 0.1)
				(type default)
			)
			(layer "B.Fab")
		)
		(fp_line
			(start -0.12065 -0.2794)
			(end -0.12065 -0.3048)
			(stroke
				(width 0.1)
				(type default)
			)
			(layer "B.Fab")
		)
		(fp_line
			(start 0.12065 -0.2794)
			(end -0.12065 -0.2794)
			(stroke
				(width 0.1)
				(type default)
			)
			(layer "B.Fab")
		)
		(fp_line
			(start -0.67945 -0.3048)
			(end -0.67945 0.3048)
			(stroke
				(width 0.1)
				(type default)
			)
			(layer "B.Fab")
		)
		(fp_line
			(start -0.12065 -0.3048)
			(end -0.67945 -0.3048)
			(stroke
				(width 0.1)
				(type default)
			)
			(layer "B.Fab")
		)
		(fp_line
			(start 0.12065 -0.305054)
			(end 0.12065 -0.2794)
			(stroke
				(width 0.1)
				(type default)
			)
			(layer "B.Fab")
		)
		(fp_line
			(start 0.67945 -0.305054)
			(end 0.12065 -0.305054)
			(stroke
				(width 0.1)
				(type default)
			)
			(layer "B.Fab")
		)
		(pad "1" smd circle
			(at 0.40005 0 90)
			(size 0 0)
			(layers "B.Cu" "B.Mask" "B.Paste")
			(net "PVCCIN_CPU0_PVCC")
		)
		(pad "2" smd circle
			(at -0.40005 0 90)
			(size 0 0)
			(layers "B.Cu" "B.Mask" "B.Paste")
			(net "PVCCIN_CPU0_VDD1")
		)
	)
	(footprint ""
		(layer "B.Cu")
		(at 353.619308 -255.853946 -90)
		(property "Reference" "C359"
			(at 0 0 90)
			(layer "B.SilkS")
			(hide yes)
			(effects
				(font
					(size 1.27 1.27)
				)
				(justify mirror)
			)
		)
		(property "Value" ""
			(at 0 0 90)
			(layer "B.Fab")
			(effects
				(font
					(size 1.27 1.27)
				)
				(justify mirror)
			)
		)
		(duplicate_pad_numbers_are_jumpers no)
		(fp_line
			(start -1.524 0.762)
			(end 1.524 0.762)
			(stroke
				(width 0.1524)
				(type default)
			)
			(layer "B.SilkS")
		)
		(fp_line
			(start 1.524 0.762)
			(end 1.524 -0.762)
			(stroke
				(width 0.1524)
				(type default)
			)
			(layer "B.SilkS")
		)
		(fp_line
			(start -1.524 -0.762)
			(end -1.524 0.762)
			(stroke
				(width 0.1524)
				(type default)
			)
			(layer "B.SilkS")
		)
		(fp_line
			(start 1.524 -0.762)
			(end -1.524 -0.762)
			(stroke
				(width 0.1524)
				(type default)
			)
			(layer "B.SilkS")
		)
		(fp_line
			(start -1.1049 0.724916)
			(end -1.1049 -0.724916)
			(stroke
				(width 0.1)
				(type default)
			)
			(layer "B.Fab")
		)
		(fp_line
			(start 1.1049 0.724916)
			(end -1.1049 0.724916)
			(stroke
				(width 0.1)
				(type default)
			)
			(layer "B.Fab")
		)
		(fp_line
			(start -1.1049 -0.724916)
			(end 1.1049 -0.724916)
			(stroke
				(width 0.1)
				(type default)
			)
			(layer "B.Fab")
		)
		(fp_line
			(start 1.1049 -0.724916)
			(end 1.1049 0.724916)
			(stroke
				(width 0.1)
				(type default)
			)
			(layer "B.Fab")
		)
		(pad "1" smd rect
			(at 0.889 0 270)
			(size 1.016 1.27)
			(layers "B.Cu" "B.Mask" "B.Paste")
			(net "PVCCIN_CPU0")
		)
		(pad "2" smd rect
			(at -0.889 0 270)
			(size 1.016 1.27)
			(layers "B.Cu" "B.Mask" "B.Paste")
			(net "GND")
		)
	)
	(footprint ""
		(layer "B.Cu")
		(at 233.971846 -132.475224 -90)
		(property "Reference" "R110"
			(at 0 0 90)
			(layer "B.SilkS")
			(hide yes)
			(effects
				(font
					(size 1.27 1.27)
				)
				(justify mirror)
			)
		)
		(property "Value" ""
			(at 0 0 90)
			(layer "B.Fab")
			(effects
				(font
					(size 1.27 1.27)
				)
				(justify mirror)
			)
		)
		(duplicate_pad_numbers_are_jumpers no)
		(fp_line
			(start -0.7874 0.4064)
			(end 0.7874 0.4064)
			(stroke
				(width 0.1524)
				(type default)
			)
			(layer "B.SilkS")
		)
		(fp_line
			(start 0.7874 0.4064)
			(end 0.7874 -0.4064)
			(stroke
				(width 0.1524)
				(type default)
			)
			(layer "B.SilkS")
		)
		(fp_line
			(start -0.7874 -0.4064)
			(end -0.7874 0.4064)
			(stroke
				(width 0.1524)
				(type default)
			)
			(layer "B.SilkS")
		)
		(fp_line
			(start 0.7874 -0.4064)
			(end -0.7874 -0.4064)
			(stroke
				(width 0.1524)
				(type default)
			)
			(layer "B.SilkS")
		)
		(fp_line
			(start -0.67945 0.3048)
			(end -0.120396 0.3048)
			(stroke
				(width 0.1)
				(type default)
			)
			(layer "B.Fab")
		)
		(fp_line
			(start -0.120396 0.3048)
			(end -0.120396 0.2794)
			(stroke
				(width 0.1)
				(type default)
			)
			(layer "B.Fab")
		)
		(fp_line
			(start 0.12065 0.3048)
			(end 0.67945 0.3048)
			(stroke
				(width 0.1)
				(type default)
			)
			(layer "B.Fab")
		)
		(fp_line
			(start 0.67945 0.3048)
			(end 0.67945 -0.305054)
			(stroke
				(width 0.1)
				(type default)
			)
			(layer "B.Fab")
		)
		(fp_line
			(start -0.120396 0.2794)
			(end 0.12065 0.2794)
			(stroke
				(width 0.1)
				(type default)
			)
			(layer "B.Fab")
		)
		(fp_line
			(start 0.12065 0.2794)
			(end 0.12065 0.3048)
			(stroke
				(width 0.1)
				(type default)
			)
			(layer "B.Fab")
		)
		(fp_line
			(start -0.12065 -0.2794)
			(end -0.12065 -0.3048)
			(stroke
				(width 0.1)
				(type default)
			)
			(layer "B.Fab")
		)
		(fp_line
			(start 0.12065 -0.2794)
			(end -0.12065 -0.2794)
			(stroke
				(width 0.1)
				(type default)
			)
			(layer "B.Fab")
		)
		(fp_line
			(start -0.67945 -0.3048)
			(end -0.67945 0.3048)
			(stroke
				(width 0.1)
				(type default)
			)
			(layer "B.Fab")
		)
		(fp_line
			(start -0.12065 -0.3048)
			(end -0.67945 -0.3048)
			(stroke
				(width 0.1)
				(type default)
			)
			(layer "B.Fab")
		)
		(fp_line
			(start 0.12065 -0.305054)
			(end 0.12065 -0.2794)
			(stroke
				(width 0.1)
				(type default)
			)
			(layer "B.Fab")
		)
		(fp_line
			(start 0.67945 -0.305054)
			(end 0.12065 -0.305054)
			(stroke
				(width 0.1)
				(type default)
			)
			(layer "B.Fab")
		)
		(pad "1" smd circle
			(at 0.40005 0 90)
			(size 0 0)
			(layers "B.Cu" "B.Mask" "B.Paste")
			(net "FM_PLD_CLKS_DEV_R_EN")
		)
		(pad "2" smd circle
			(at -0.40005 0 90)
			(size 0 0)
			(layers "B.Cu" "B.Mask" "B.Paste")
			(net "FM_PLD_CLKS_DEV_EN")
		)
	)
	(footprint ""
		(layer "B.Cu")
		(at 173.91507 -317.48984 90)
		(property "Reference" "R3902"
			(at 0 0 90)
			(layer "B.SilkS")
			(hide yes)
			(effects
				(font
					(size 1.27 1.27)
				)
				(justify mirror)
			)
		)
		(property "Value" ""
			(at 0 0 90)
			(layer "B.Fab")
			(effects
				(font
					(size 1.27 1.27)
				)
				(justify mirror)
			)
		)
		(duplicate_pad_numbers_are_jumpers no)
		(fp_line
			(start 0.7874 -0.4064)
			(end -0.7874 -0.4064)
			(stroke
				(width 0.1524)
				(type default)
			)
			(layer "B.SilkS")
		)
		(fp_line
			(start -0.7874 -0.4064)
			(end -0.7874 0.4064)
			(stroke
				(width 0.1524)
				(type default)
			)
			(layer "B.SilkS")
		)
		(fp_line
			(start 0.7874 0.4064)
			(end 0.7874 -0.4064)
			(stroke
				(width 0.1524)
				(type default)
			)
			(layer "B.SilkS")
		)
		(fp_line
			(start -0.7874 0.4064)
			(end 0.7874 0.4064)
			(stroke
				(width 0.1524)
				(type default)
			)
			(layer "B.SilkS")
		)
		(fp_line
			(start 0.67945 -0.305054)
			(end 0.12065 -0.305054)
			(stroke
				(width 0.1)
				(type default)
			)
			(layer "B.Fab")
		)
		(fp_line
			(start 0.12065 -0.305054)
			(end 0.12065 -0.2794)
			(stroke
				(width 0.1)
				(type default)
			)
			(layer "B.Fab")
		)
		(fp_line
			(start -0.12065 -0.3048)
			(end -0.67945 -0.3048)
			(stroke
				(width 0.1)
				(type default)
			)
			(layer "B.Fab")
		)
		(fp_line
			(start -0.67945 -0.3048)
			(end -0.67945 0.3048)
			(stroke
				(width 0.1)
				(type default)
			)
			(layer "B.Fab")
		)
		(fp_line
			(start 0.12065 -0.2794)
			(end -0.12065 -0.2794)
			(stroke
				(width 0.1)
				(type default)
			)
			(layer "B.Fab")
		)
		(fp_line
			(start -0.12065 -0.2794)
			(end -0.12065 -0.3048)
			(stroke
				(width 0.1)
				(type default)
			)
			(layer "B.Fab")
		)
		(fp_line
			(start 0.12065 0.2794)
			(end 0.12065 0.3048)
			(stroke
				(width 0.1)
				(type default)
			)
			(layer "B.Fab")
		)
		(fp_line
			(start -0.120396 0.2794)
			(end 0.12065 0.2794)
			(stroke
				(width 0.1)
				(type default)
			)
			(layer "B.Fab")
		)
		(fp_line
			(start 0.67945 0.3048)
			(end 0.67945 -0.305054)
			(stroke
				(width 0.1)
				(type default)
			)
			(layer "B.Fab")
		)
		(fp_line
			(start 0.12065 0.3048)
			(end 0.67945 0.3048)
			(stroke
				(width 0.1)
				(type default)
			)
			(layer "B.Fab")
		)
		(fp_line
			(start -0.120396 0.3048)
			(end -0.120396 0.2794)
			(stroke
				(width 0.1)
				(type default)
			)
			(layer "B.Fab")
		)
		(fp_line
			(start -0.67945 0.3048)
			(end -0.120396 0.3048)
			(stroke
				(width 0.1)
				(type default)
			)
			(layer "B.Fab")
		)
		(pad "1" smd circle
			(at 0.40005 0 270)
			(size 0 0)
			(layers "B.Cu" "B.Mask" "B.Paste")
			(net "I3C_SPD_DDREFGH_CPU1_LVC1_SCL_3")
		)
		(pad "2" smd circle
			(at -0.40005 0 270)
			(size 0 0)
			(layers "B.Cu" "B.Mask" "B.Paste")
			(net "I3C_SPD_DDREFGH_CPU1_LVC1_SCL")
		)
	)
	(footprint ""
		(layer "B.Cu")
		(at 24.895302 -163.105846 180)
		(property "Reference" "PR4251"
			(at 0 0 0)
			(layer "B.SilkS")
			(hide yes)
			(effects
				(font
					(size 1.27 1.27)
				)
				(justify mirror)
			)
		)
		(property "Value" ""
			(at 0 0 0)
			(layer "B.Fab")
			(effects
				(font
					(size 1.27 1.27)
				)
				(justify mirror)
			)
		)
		(duplicate_pad_numbers_are_jumpers no)
		(fp_line
			(start 0.7874 0.4064)
			(end 0.7874 -0.4064)
			(stroke
				(width 0.1524)
				(type default)
			)
			(layer "B.SilkS")
		)
		(fp_line
			(start 0.7874 -0.4064)
			(end -0.7874 -0.4064)
			(stroke
				(width 0.1524)
				(type default)
			)
			(layer "B.SilkS")
		)
		(fp_line
			(start -0.7874 0.4064)
			(end 0.7874 0.4064)
			(stroke
				(width 0.1524)
				(type default)
			)
			(layer "B.SilkS")
		)
		(fp_line
			(start -0.7874 -0.4064)
			(end -0.7874 0.4064)
			(stroke
				(width 0.1524)
				(type default)
			)
			(layer "B.SilkS")
		)
		(fp_line
			(start 0.67945 0.3048)
			(end 0.67945 -0.305054)
			(stroke
				(width 0.1)
				(type default)
			)
			(layer "B.Fab")
		)
		(fp_line
			(start 0.67945 -0.305054)
			(end 0.12065 -0.305054)
			(stroke
				(width 0.1)
				(type default)
			)
			(layer "B.Fab")
		)
		(fp_line
			(start 0.12065 0.3048)
			(end 0.67945 0.3048)
			(stroke
				(width 0.1)
				(type default)
			)
			(layer "B.Fab")
		)
		(fp_line
			(start 0.12065 0.2794)
			(end 0.12065 0.3048)
			(stroke
				(width 0.1)
				(type default)
			)
			(layer "B.Fab")
		)
		(fp_line
			(start 0.12065 -0.2794)
			(end -0.12065 -0.2794)
			(stroke
				(width 0.1)
				(type default)
			)
			(layer "B.Fab")
		)
		(fp_line
			(start 0.12065 -0.305054)
			(end 0.12065 -0.2794)
			(stroke
				(width 0.1)
				(type default)
			)
			(layer "B.Fab")
		)
		(fp_line
			(start -0.120396 0.3048)
			(end -0.120396 0.2794)
			(stroke
				(width 0.1)
				(type default)
			)
			(layer "B.Fab")
		)
		(fp_line
			(start -0.120396 0.2794)
			(end 0.12065 0.2794)
			(stroke
				(width 0.1)
				(type default)
			)
			(layer "B.Fab")
		)
		(fp_line
			(start -0.12065 -0.2794)
			(end -0.12065 -0.3048)
			(stroke
				(width 0.1)
				(type default)
			)
			(layer "B.Fab")
		)
		(fp_line
			(start -0.12065 -0.3048)
			(end -0.67945 -0.3048)
			(stroke
				(width 0.1)
				(type default)
			)
			(layer "B.Fab")
		)
		(fp_line
			(start -0.67945 0.3048)
			(end -0.120396 0.3048)
			(stroke
				(width 0.1)
				(type default)
			)
			(layer "B.Fab")
		)
		(fp_line
			(start -0.67945 -0.3048)
			(end -0.67945 0.3048)
			(stroke
				(width 0.1)
				(type default)
			)
			(layer "B.Fab")
		)
		(pad "1" smd circle
			(at 0.40005 0)
			(size 0 0)
			(layers "B.Cu" "B.Mask" "B.Paste")
			(net "NC_PVCCD_HV_CPU1_ACSP2")
		)
		(pad "2" smd circle
			(at -0.40005 0)
			(size 0 0)
			(layers "B.Cu" "B.Mask" "B.Paste")
			(net "GND")
		)
	)
	(footprint ""
		(layer "B.Cu")
		(at 126.65202 -36.761928 90)
		(property "Reference" "R4290"
			(at 0 0 90)
			(layer "B.SilkS")
			(hide yes)
			(effects
				(font
					(size 1.27 1.27)
				)
				(justify mirror)
			)
		)
		(property "Value" ""
			(at 0 0 90)
			(layer "B.Fab")
			(effects
				(font
					(size 1.27 1.27)
				)
				(justify mirror)
			)
		)
		(duplicate_pad_numbers_are_jumpers no)
		(fp_line
			(start 0.7874 -0.4064)
			(end -0.7874 -0.4064)
			(stroke
				(width 0.1524)
				(type default)
			)
			(layer "B.SilkS")
		)
		(fp_line
			(start -0.7874 -0.4064)
			(end -0.7874 0.4064)
			(stroke
				(width 0.1524)
				(type default)
			)
			(layer "B.SilkS")
		)
		(fp_line
			(start 0.7874 0.4064)
			(end 0.7874 -0.4064)
			(stroke
				(width 0.1524)
				(type default)
			)
			(layer "B.SilkS")
		)
		(fp_line
			(start -0.7874 0.4064)
			(end 0.7874 0.4064)
			(stroke
				(width 0.1524)
				(type default)
			)
			(layer "B.SilkS")
		)
		(fp_line
			(start 0.67945 -0.305054)
			(end 0.12065 -0.305054)
			(stroke
				(width 0.1)
				(type default)
			)
			(layer "B.Fab")
		)
		(fp_line
			(start 0.12065 -0.305054)
			(end 0.12065 -0.2794)
			(stroke
				(width 0.1)
				(type default)
			)
			(layer "B.Fab")
		)
		(fp_line
			(start -0.12065 -0.3048)
			(end -0.67945 -0.3048)
			(stroke
				(width 0.1)
				(type default)
			)
			(layer "B.Fab")
		)
		(fp_line
			(start -0.67945 -0.3048)
			(end -0.67945 0.3048)
			(stroke
				(width 0.1)
				(type default)
			)
			(layer "B.Fab")
		)
		(fp_line
			(start 0.12065 -0.2794)
			(end -0.12065 -0.2794)
			(stroke
				(width 0.1)
				(type default)
			)
			(layer "B.Fab")
		)
		(fp_line
			(start -0.12065 -0.2794)
			(end -0.12065 -0.3048)
			(stroke
				(width 0.1)
				(type default)
			)
			(layer "B.Fab")
		)
		(fp_line
			(start 0.12065 0.2794)
			(end 0.12065 0.3048)
			(stroke
				(width 0.1)
				(type default)
			)
			(layer "B.Fab")
		)
		(fp_line
			(start -0.120396 0.2794)
			(end 0.12065 0.2794)
			(stroke
				(width 0.1)
				(type default)
			)
			(layer "B.Fab")
		)
		(fp_line
			(start 0.67945 0.3048)
			(end 0.67945 -0.305054)
			(stroke
				(width 0.1)
				(type default)
			)
			(layer "B.Fab")
		)
		(fp_line
			(start 0.12065 0.3048)
			(end 0.67945 0.3048)
			(stroke
				(width 0.1)
				(type default)
			)
			(layer "B.Fab")
		)
		(fp_line
			(start -0.120396 0.3048)
			(end -0.120396 0.2794)
			(stroke
				(width 0.1)
				(type default)
			)
			(layer "B.Fab")
		)
		(fp_line
			(start -0.67945 0.3048)
			(end -0.120396 0.3048)
			(stroke
				(width 0.1)
				(type default)
			)
			(layer "B.Fab")
		)
		(pad "1" smd circle
			(at 0.40005 0 270)
			(size 0 0)
			(layers "B.Cu" "B.Mask" "B.Paste")
			(net "FM_USB3_1_RXDET_EN")
		)
		(pad "2" smd circle
			(at -0.40005 0 270)
			(size 0 0)
			(layers "B.Cu" "B.Mask" "B.Paste")
			(net "GND")
		)
	)
	(footprint ""
		(layer "B.Cu")
		(at 121.545604 -294.01008 180)
		(property "Reference" "C347"
			(at 0 0 0)
			(layer "B.SilkS")
			(hide yes)
			(effects
				(font
					(size 1.27 1.27)
				)
				(justify mirror)
			)
		)
		(property "Value" ""
			(at 0 0 0)
			(layer "B.Fab")
			(effects
				(font
					(size 1.27 1.27)
				)
				(justify mirror)
			)
		)
		(duplicate_pad_numbers_are_jumpers no)
		(fp_line
			(start 1.524 0.762)
			(end 1.524 -0.762)
			(stroke
				(width 0.1524)
				(type default)
			)
			(layer "B.SilkS")
		)
		(fp_line
			(start 1.524 -0.762)
			(end -1.524 -0.762)
			(stroke
				(width 0.1524)
				(type default)
			)
			(layer "B.SilkS")
		)
		(fp_line
			(start -1.524 0.762)
			(end 1.524 0.762)
			(stroke
				(width 0.1524)
				(type default)
			)
			(layer "B.SilkS")
		)
		(fp_line
			(start -1.524 -0.762)
			(end -1.524 0.762)
			(stroke
				(width 0.1524)
				(type default)
			)
			(layer "B.SilkS")
		)
		(fp_line
			(start 1.1049 0.724916)
			(end -1.1049 0.724916)
			(stroke
				(width 0.1)
				(type default)
			)
			(layer "B.Fab")
		)
		(fp_line
			(start 1.1049 -0.724916)
			(end 1.1049 0.724916)
			(stroke
				(width 0.1)
				(type default)
			)
			(layer "B.Fab")
		)
		(fp_line
			(start -1.1049 0.724916)
			(end -1.1049 -0.724916)
			(stroke
				(width 0.1)
				(type default)
			)
			(layer "B.Fab")
		)
		(fp_line
			(start -1.1049 -0.724916)
			(end 1.1049 -0.724916)
			(stroke
				(width 0.1)
				(type default)
			)
			(layer "B.Fab")
		)
		(pad "1" smd rect
			(at 0.889 0 180)
			(size 1.016 1.27)
			(layers "B.Cu" "B.Mask" "B.Paste")
			(net "PVCCIN_CPU1")
		)
		(pad "2" smd rect
			(at -0.889 0 180)
			(size 1.016 1.27)
			(layers "B.Cu" "B.Mask" "B.Paste")
			(net "GND")
		)
	)
	(footprint ""
		(layer "B.Cu")
		(at 367.898934 -255.853946 -90)
		(property "Reference" "C361"
			(at 0 0 90)
			(layer "B.SilkS")
			(hide yes)
			(effects
				(font
					(size 1.27 1.27)
				)
				(justify mirror)
			)
		)
		(property "Value" ""
			(at 0 0 90)
			(layer "B.Fab")
			(effects
				(font
					(size 1.27 1.27)
				)
				(justify mirror)
			)
		)
		(duplicate_pad_numbers_are_jumpers no)
		(fp_line
			(start -1.524 0.762)
			(end 1.524 0.762)
			(stroke
				(width 0.1524)
				(type default)
			)
			(layer "B.SilkS")
		)
		(fp_line
			(start 1.524 0.762)
			(end 1.524 -0.762)
			(stroke
				(width 0.1524)
				(type default)
			)
			(layer "B.SilkS")
		)
		(fp_line
			(start -1.524 -0.762)
			(end -1.524 0.762)
			(stroke
				(width 0.1524)
				(type default)
			)
			(layer "B.SilkS")
		)
		(fp_line
			(start 1.524 -0.762)
			(end -1.524 -0.762)
			(stroke
				(width 0.1524)
				(type default)
			)
			(layer "B.SilkS")
		)
		(fp_line
			(start -1.1049 0.724916)
			(end -1.1049 -0.724916)
			(stroke
				(width 0.1)
				(type default)
			)
			(layer "B.Fab")
		)
		(fp_line
			(start 1.1049 0.724916)
			(end -1.1049 0.724916)
			(stroke
				(width 0.1)
				(type default)
			)
			(layer "B.Fab")
		)
		(fp_line
			(start -1.1049 -0.724916)
			(end 1.1049 -0.724916)
			(stroke
				(width 0.1)
				(type default)
			)
			(layer "B.Fab")
		)
		(fp_line
			(start 1.1049 -0.724916)
			(end 1.1049 0.724916)
			(stroke
				(width 0.1)
				(type default)
			)
			(layer "B.Fab")
		)
		(pad "1" smd rect
			(at 0.889 0 270)
			(size 1.016 1.27)
			(layers "B.Cu" "B.Mask" "B.Paste")
			(net "PVCCIN_CPU0")
		)
		(pad "2" smd rect
			(at -0.889 0 270)
			(size 1.016 1.27)
			(layers "B.Cu" "B.Mask" "B.Paste")
			(net "GND")
		)
	)
	(footprint ""
		(layer "B.Cu")
		(at 110.31855 -413.110426 180)
		(property "Reference" "C2330"
			(at 0 0 0)
			(layer "B.SilkS")
			(hide yes)
			(effects
				(font
					(size 1.27 1.27)
				)
				(justify mirror)
			)
		)
		(property "Value" ""
			(at 0 0 0)
			(layer "B.Fab")
			(effects
				(font
					(size 1.27 1.27)
				)
				(justify mirror)
			)
		)
		(duplicate_pad_numbers_are_jumpers no)
		(fp_line
			(start 0.7874 0.4064)
			(end 0.7874 -0.4064)
			(stroke
				(width 0.1524)
				(type default)
			)
			(layer "B.SilkS")
		)
		(fp_line
			(start 0.7874 -0.4064)
			(end -0.7874 -0.4064)
			(stroke
				(width 0.1524)
				(type default)
			)
			(layer "B.SilkS")
		)
		(fp_line
			(start -0.7874 0.4064)
			(end 0.7874 0.4064)
			(stroke
				(width 0.1524)
				(type default)
			)
			(layer "B.SilkS")
		)
		(fp_line
			(start -0.7874 -0.4064)
			(end -0.7874 0.4064)
			(stroke
				(width 0.1524)
				(type default)
			)
			(layer "B.SilkS")
		)
		(fp_line
			(start 0.67945 0.3048)
			(end 0.67945 -0.305054)
			(stroke
				(width 0.1)
				(type default)
			)
			(layer "B.Fab")
		)
		(fp_line
			(start 0.67945 -0.305054)
			(end 0.12065 -0.305054)
			(stroke
				(width 0.1)
				(type default)
			)
			(layer "B.Fab")
		)
		(fp_line
			(start 0.12065 0.3048)
			(end 0.67945 0.3048)
			(stroke
				(width 0.1)
				(type default)
			)
			(layer "B.Fab")
		)
		(fp_line
			(start 0.12065 0.2794)
			(end 0.12065 0.3048)
			(stroke
				(width 0.1)
				(type default)
			)
			(layer "B.Fab")
		)
		(fp_line
			(start 0.12065 -0.2794)
			(end -0.12065 -0.2794)
			(stroke
				(width 0.1)
				(type default)
			)
			(layer "B.Fab")
		)
		(fp_line
			(start 0.12065 -0.305054)
			(end 0.12065 -0.2794)
			(stroke
				(width 0.1)
				(type default)
			)
			(layer "B.Fab")
		)
		(fp_line
			(start -0.120396 0.3048)
			(end -0.120396 0.2794)
			(stroke
				(width 0.1)
				(type default)
			)
			(layer "B.Fab")
		)
		(fp_line
			(start -0.120396 0.2794)
			(end 0.12065 0.2794)
			(stroke
				(width 0.1)
				(type default)
			)
			(layer "B.Fab")
		)
		(fp_line
			(start -0.12065 -0.2794)
			(end -0.12065 -0.3048)
			(stroke
				(width 0.1)
				(type default)
			)
			(layer "B.Fab")
		)
		(fp_line
			(start -0.12065 -0.3048)
			(end -0.67945 -0.3048)
			(stroke
				(width 0.1)
				(type default)
			)
			(layer "B.Fab")
		)
		(fp_line
			(start -0.67945 0.3048)
			(end -0.120396 0.3048)
			(stroke
				(width 0.1)
				(type default)
			)
			(layer "B.Fab")
		)
		(fp_line
			(start -0.67945 -0.3048)
			(end -0.67945 0.3048)
			(stroke
				(width 0.1)
				(type default)
			)
			(layer "B.Fab")
		)
		(pad "1" smd circle
			(at 0.40005 0)
			(size 0 0)
			(layers "B.Cu" "B.Mask" "B.Paste")
			(net "P3V3_9ZXL045_VDD")
		)
		(pad "2" smd circle
			(at -0.40005 0)
			(size 0 0)
			(layers "B.Cu" "B.Mask" "B.Paste")
			(net "GND")
		)
	)
	(footprint ""
		(layer "B.Cu")
		(at 138.921998 -342.936576 90)
		(property "Reference" "PC489_P1_8"
			(at 0 0 90)
			(layer "B.SilkS")
			(hide yes)
			(effects
				(font
					(size 1.27 1.27)
				)
				(justify mirror)
			)
		)
		(property "Value" ""
			(at 0 0 90)
			(layer "B.Fab")
			(effects
				(font
					(size 1.27 1.27)
				)
				(justify mirror)
			)
		)
		(duplicate_pad_numbers_are_jumpers no)
		(fp_line
			(start 1.524 -0.762)
			(end -1.524 -0.762)
			(stroke
				(width 0.1524)
				(type default)
			)
			(layer "B.SilkS")
		)
		(fp_line
			(start -1.524 -0.762)
			(end -1.524 0.762)
			(stroke
				(width 0.1524)
				(type default)
			)
			(layer "B.SilkS")
		)
		(fp_line
			(start 1.524 0.762)
			(end 1.524 -0.762)
			(stroke
				(width 0.1524)
				(type default)
			)
			(layer "B.SilkS")
		)
		(fp_line
			(start -1.524 0.762)
			(end 1.524 0.762)
			(stroke
				(width 0.1524)
				(type default)
			)
			(layer "B.SilkS")
		)
		(fp_line
			(start 1.1049 -0.724916)
			(end 1.1049 0.724916)
			(stroke
				(width 0.1)
				(type default)
			)
			(layer "B.Fab")
		)
		(fp_line
			(start -1.1049 -0.724916)
			(end 1.1049 -0.724916)
			(stroke
				(width 0.1)
				(type default)
			)
			(layer "B.Fab")
		)
		(fp_line
			(start 1.1049 0.724916)
			(end -1.1049 0.724916)
			(stroke
				(width 0.1)
				(type default)
			)
			(layer "B.Fab")
		)
		(fp_line
			(start -1.1049 0.724916)
			(end -1.1049 -0.724916)
			(stroke
				(width 0.1)
				(type default)
			)
			(layer "B.Fab")
		)
		(pad "1" smd rect
			(at 0.889 0 90)
			(size 1.016 1.27)
			(layers "B.Cu" "B.Mask" "B.Paste")
			(net "SW_P12V_PVCCIN_CPU1_FLT")
		)
		(pad "2" smd rect
			(at -0.889 0 90)
			(size 1.016 1.27)
			(layers "B.Cu" "B.Mask" "B.Paste")
			(net "GND")
		)
	)
	(footprint ""
		(layer "B.Cu")
		(at 416.02914 -178.336194)
		(property "Reference" "PC198_P0_2"
			(at 0 0 0)
			(layer "B.SilkS")
			(hide yes)
			(effects
				(font
					(size 1.27 1.27)
				)
				(justify mirror)
			)
		)
		(property "Value" ""
			(at 0 0 0)
			(layer "B.Fab")
			(effects
				(font
					(size 1.27 1.27)
				)
				(justify mirror)
			)
		)
		(duplicate_pad_numbers_are_jumpers no)
		(fp_line
			(start -1.524 -0.762)
			(end -1.524 0.762)
			(stroke
				(width 0.1524)
				(type default)
			)
			(layer "B.SilkS")
		)
		(fp_line
			(start -1.524 0.762)
			(end 1.524 0.762)
			(stroke
				(width 0.1524)
				(type default)
			)
			(layer "B.SilkS")
		)
		(fp_line
			(start 1.524 -0.762)
			(end -1.524 -0.762)
			(stroke
				(width 0.1524)
				(type default)
			)
			(layer "B.SilkS")
		)
		(fp_line
			(start 1.524 0.762)
			(end 1.524 -0.762)
			(stroke
				(width 0.1524)
				(type default)
			)
			(layer "B.SilkS")
		)
		(fp_line
			(start -1.1049 -0.724916)
			(end 1.1049 -0.724916)
			(stroke
				(width 0.1)
				(type default)
			)
			(layer "B.Fab")
		)
		(fp_line
			(start -1.1049 0.724916)
			(end -1.1049 -0.724916)
			(stroke
				(width 0.1)
				(type default)
			)
			(layer "B.Fab")
		)
		(fp_line
			(start 1.1049 -0.724916)
			(end 1.1049 0.724916)
			(stroke
				(width 0.1)
				(type default)
			)
			(layer "B.Fab")
		)
		(fp_line
			(start 1.1049 0.724916)
			(end -1.1049 0.724916)
			(stroke
				(width 0.1)
				(type default)
			)
			(layer "B.Fab")
		)
		(pad "1" smd rect
			(at 0.889 0)
			(size 1.016 1.27)
			(layers "B.Cu" "B.Mask" "B.Paste")
			(net "SW_P12V_PVCCINFAON_CPU0_FLT")
		)
		(pad "2" smd rect
			(at -0.889 0)
			(size 1.016 1.27)
			(layers "B.Cu" "B.Mask" "B.Paste")
			(net "GND")
		)
	)
	(footprint ""
		(layer "B.Cu")
		(at 104.463088 -210.194144)
		(property "Reference" "C456"
			(at 0 0 0)
			(layer "B.SilkS")
			(hide yes)
			(effects
				(font
					(size 1.27 1.27)
				)
				(justify mirror)
			)
		)
		(property "Value" ""
			(at 0 0 0)
			(layer "B.Fab")
			(effects
				(font
					(size 1.27 1.27)
				)
				(justify mirror)
			)
		)
		(duplicate_pad_numbers_are_jumpers no)
		(fp_line
			(start -1.524 -0.762)
			(end -1.524 0.762)
			(stroke
				(width 0.1524)
				(type default)
			)
			(layer "B.SilkS")
		)
		(fp_line
			(start -1.524 0.762)
			(end 1.524 0.762)
			(stroke
				(width 0.1524)
				(type default)
			)
			(layer "B.SilkS")
		)
		(fp_line
			(start 1.524 -0.762)
			(end -1.524 -0.762)
			(stroke
				(width 0.1524)
				(type default)
			)
			(layer "B.SilkS")
		)
		(fp_line
			(start 1.524 0.762)
			(end 1.524 -0.762)
			(stroke
				(width 0.1524)
				(type default)
			)
			(layer "B.SilkS")
		)
		(fp_line
			(start -1.1049 -0.724916)
			(end 1.1049 -0.724916)
			(stroke
				(width 0.1)
				(type default)
			)
			(layer "B.Fab")
		)
		(fp_line
			(start -1.1049 0.724916)
			(end -1.1049 -0.724916)
			(stroke
				(width 0.1)
				(type default)
			)
			(layer "B.Fab")
		)
		(fp_line
			(start 1.1049 -0.724916)
			(end 1.1049 0.724916)
			(stroke
				(width 0.1)
				(type default)
			)
			(layer "B.Fab")
		)
		(fp_line
			(start 1.1049 0.724916)
			(end -1.1049 0.724916)
			(stroke
				(width 0.1)
				(type default)
			)
			(layer "B.Fab")
		)
		(pad "1" smd rect
			(at 0.889 0)
			(size 1.016 1.27)
			(layers "B.Cu" "B.Mask" "B.Paste")
			(net "PVCCFA_EHV_CPU1")
		)
		(pad "2" smd rect
			(at -0.889 0)
			(size 1.016 1.27)
			(layers "B.Cu" "B.Mask" "B.Paste")
			(net "GND")
		)
	)
	(footprint ""
		(layer "B.Cu")
		(at 111.83112 -416.048698 90)
		(property "Reference" "C2333"
			(at 0 0 90)
			(layer "B.SilkS")
			(hide yes)
			(effects
				(font
					(size 1.27 1.27)
				)
				(justify mirror)
			)
		)
		(property "Value" ""
			(at 0 0 90)
			(layer "B.Fab")
			(effects
				(font
					(size 1.27 1.27)
				)
				(justify mirror)
			)
		)
		(duplicate_pad_numbers_are_jumpers no)
		(fp_line
			(start 0.7874 -0.4064)
			(end -0.7874 -0.4064)
			(stroke
				(width 0.1524)
				(type default)
			)
			(layer "B.SilkS")
		)
		(fp_line
			(start -0.7874 -0.4064)
			(end -0.7874 0.4064)
			(stroke
				(width 0.1524)
				(type default)
			)
			(layer "B.SilkS")
		)
		(fp_line
			(start 0.7874 0.4064)
			(end 0.7874 -0.4064)
			(stroke
				(width 0.1524)
				(type default)
			)
			(layer "B.SilkS")
		)
		(fp_line
			(start -0.7874 0.4064)
			(end 0.7874 0.4064)
			(stroke
				(width 0.1524)
				(type default)
			)
			(layer "B.SilkS")
		)
		(fp_line
			(start 0.67945 -0.305054)
			(end 0.12065 -0.305054)
			(stroke
				(width 0.1)
				(type default)
			)
			(layer "B.Fab")
		)
		(fp_line
			(start 0.12065 -0.305054)
			(end 0.12065 -0.2794)
			(stroke
				(width 0.1)
				(type default)
			)
			(layer "B.Fab")
		)
		(fp_line
			(start -0.12065 -0.3048)
			(end -0.67945 -0.3048)
			(stroke
				(width 0.1)
				(type default)
			)
			(layer "B.Fab")
		)
		(fp_line
			(start -0.67945 -0.3048)
			(end -0.67945 0.3048)
			(stroke
				(width 0.1)
				(type default)
			)
			(layer "B.Fab")
		)
		(fp_line
			(start 0.12065 -0.2794)
			(end -0.12065 -0.2794)
			(stroke
				(width 0.1)
				(type default)
			)
			(layer "B.Fab")
		)
		(fp_line
			(start -0.12065 -0.2794)
			(end -0.12065 -0.3048)
			(stroke
				(width 0.1)
				(type default)
			)
			(layer "B.Fab")
		)
		(fp_line
			(start 0.12065 0.2794)
			(end 0.12065 0.3048)
			(stroke
				(width 0.1)
				(type default)
			)
			(layer "B.Fab")
		)
		(fp_line
			(start -0.120396 0.2794)
			(end 0.12065 0.2794)
			(stroke
				(width 0.1)
				(type default)
			)
			(layer "B.Fab")
		)
		(fp_line
			(start 0.67945 0.3048)
			(end 0.67945 -0.305054)
			(stroke
				(width 0.1)
				(type default)
			)
			(layer "B.Fab")
		)
		(fp_line
			(start 0.12065 0.3048)
			(end 0.67945 0.3048)
			(stroke
				(width 0.1)
				(type default)
			)
			(layer "B.Fab")
		)
		(fp_line
			(start -0.120396 0.3048)
			(end -0.120396 0.2794)
			(stroke
				(width 0.1)
				(type default)
			)
			(layer "B.Fab")
		)
		(fp_line
			(start -0.67945 0.3048)
			(end -0.120396 0.3048)
			(stroke
				(width 0.1)
				(type default)
			)
			(layer "B.Fab")
		)
		(pad "1" smd circle
			(at 0.40005 0 270)
			(size 0 0)
			(layers "B.Cu" "B.Mask" "B.Paste")
			(net "P3V3_9ZXL045_VDD")
		)
		(pad "2" smd circle
			(at -0.40005 0 270)
			(size 0 0)
			(layers "B.Cu" "B.Mask" "B.Paste")
			(net "GND")
		)
	)
	(footprint ""
		(layer "B.Cu")
		(at 430.600104 -136.526778 180)
		(property "Reference" "C3276"
			(at 0 0 0)
			(layer "B.SilkS")
			(hide yes)
			(effects
				(font
					(size 1.27 1.27)
				)
				(justify mirror)
			)
		)
		(property "Value" ""
			(at 0 0 0)
			(layer "B.Fab")
			(effects
				(font
					(size 1.27 1.27)
				)
				(justify mirror)
			)
		)
		(duplicate_pad_numbers_are_jumpers no)
		(fp_line
			(start 0.7874 0.4064)
			(end 0.7874 -0.4064)
			(stroke
				(width 0.1524)
				(type default)
			)
			(layer "B.SilkS")
		)
		(fp_line
			(start 0.7874 -0.4064)
			(end -0.7874 -0.4064)
			(stroke
				(width 0.1524)
				(type default)
			)
			(layer "B.SilkS")
		)
		(fp_line
			(start -0.7874 0.4064)
			(end 0.7874 0.4064)
			(stroke
				(width 0.1524)
				(type default)
			)
			(layer "B.SilkS")
		)
		(fp_line
			(start -0.7874 -0.4064)
			(end -0.7874 0.4064)
			(stroke
				(width 0.1524)
				(type default)
			)
			(layer "B.SilkS")
		)
		(fp_line
			(start 0.67945 0.3048)
			(end 0.67945 -0.305054)
			(stroke
				(width 0.1)
				(type default)
			)
			(layer "B.Fab")
		)
		(fp_line
			(start 0.67945 -0.305054)
			(end 0.12065 -0.305054)
			(stroke
				(width 0.1)
				(type default)
			)
			(layer "B.Fab")
		)
		(fp_line
			(start 0.12065 0.3048)
			(end 0.67945 0.3048)
			(stroke
				(width 0.1)
				(type default)
			)
			(layer "B.Fab")
		)
		(fp_line
			(start 0.12065 0.2794)
			(end 0.12065 0.3048)
			(stroke
				(width 0.1)
				(type default)
			)
			(layer "B.Fab")
		)
		(fp_line
			(start 0.12065 -0.2794)
			(end -0.12065 -0.2794)
			(stroke
				(width 0.1)
				(type default)
			)
			(layer "B.Fab")
		)
		(fp_line
			(start 0.12065 -0.305054)
			(end 0.12065 -0.2794)
			(stroke
				(width 0.1)
				(type default)
			)
			(layer "B.Fab")
		)
		(fp_line
			(start -0.120396 0.3048)
			(end -0.120396 0.2794)
			(stroke
				(width 0.1)
				(type default)
			)
			(layer "B.Fab")
		)
		(fp_line
			(start -0.120396 0.2794)
			(end 0.12065 0.2794)
			(stroke
				(width 0.1)
				(type default)
			)
			(layer "B.Fab")
		)
		(fp_line
			(start -0.12065 -0.2794)
			(end -0.12065 -0.3048)
			(stroke
				(width 0.1)
				(type default)
			)
			(layer "B.Fab")
		)
		(fp_line
			(start -0.12065 -0.3048)
			(end -0.67945 -0.3048)
			(stroke
				(width 0.1)
				(type default)
			)
			(layer "B.Fab")
		)
		(fp_line
			(start -0.67945 0.3048)
			(end -0.120396 0.3048)
			(stroke
				(width 0.1)
				(type default)
			)
			(layer "B.Fab")
		)
		(fp_line
			(start -0.67945 -0.3048)
			(end -0.67945 0.3048)
			(stroke
				(width 0.1)
				(type default)
			)
			(layer "B.Fab")
		)
		(pad "1" smd circle
			(at 0.40005 0)
			(size 0 0)
			(layers "B.Cu" "B.Mask" "B.Paste")
			(net "PWRGD_PVCCFA_EHV_CPU0_R")
		)
		(pad "2" smd circle
			(at -0.40005 0)
			(size 0 0)
			(layers "B.Cu" "B.Mask" "B.Paste")
			(net "GND")
		)
	)
	(footprint ""
		(layer "B.Cu")
		(at 312.578242 -38.763448)
		(property "Reference" "R1499"
			(at 0 0 0)
			(layer "B.SilkS")
			(hide yes)
			(effects
				(font
					(size 1.27 1.27)
				)
				(justify mirror)
			)
		)
		(property "Value" ""
			(at 0 0 0)
			(layer "B.Fab")
			(effects
				(font
					(size 1.27 1.27)
				)
				(justify mirror)
			)
		)
		(duplicate_pad_numbers_are_jumpers no)
		(fp_line
			(start -0.7874 -0.4064)
			(end -0.7874 0.4064)
			(stroke
				(width 0.1524)
				(type default)
			)
			(layer "B.SilkS")
		)
		(fp_line
			(start -0.7874 0.4064)
			(end 0.7874 0.4064)
			(stroke
				(width 0.1524)
				(type default)
			)
			(layer "B.SilkS")
		)
		(fp_line
			(start 0.7874 -0.4064)
			(end -0.7874 -0.4064)
			(stroke
				(width 0.1524)
				(type default)
			)
			(layer "B.SilkS")
		)
		(fp_line
			(start 0.7874 0.4064)
			(end 0.7874 -0.4064)
			(stroke
				(width 0.1524)
				(type default)
			)
			(layer "B.SilkS")
		)
		(fp_line
			(start -0.67945 -0.3048)
			(end -0.67945 0.3048)
			(stroke
				(width 0.1)
				(type default)
			)
			(layer "B.Fab")
		)
		(fp_line
			(start -0.67945 0.3048)
			(end -0.120396 0.3048)
			(stroke
				(width 0.1)
				(type default)
			)
			(layer "B.Fab")
		)
		(fp_line
			(start -0.12065 -0.3048)
			(end -0.67945 -0.3048)
			(stroke
				(width 0.1)
				(type default)
			)
			(layer "B.Fab")
		)
		(fp_line
			(start -0.12065 -0.2794)
			(end -0.12065 -0.3048)
			(stroke
				(width 0.1)
				(type default)
			)
			(layer "B.Fab")
		)
		(fp_line
			(start -0.120396 0.2794)
			(end 0.12065 0.2794)
			(stroke
				(width 0.1)
				(type default)
			)
			(layer "B.Fab")
		)
		(fp_line
			(start -0.120396 0.3048)
			(end -0.120396 0.2794)
			(stroke
				(width 0.1)
				(type default)
			)
			(layer "B.Fab")
		)
		(fp_line
			(start 0.12065 -0.305054)
			(end 0.12065 -0.2794)
			(stroke
				(width 0.1)
				(type default)
			)
			(layer "B.Fab")
		)
		(fp_line
			(start 0.12065 -0.2794)
			(end -0.12065 -0.2794)
			(stroke
				(width 0.1)
				(type default)
			)
			(layer "B.Fab")
		)
		(fp_line
			(start 0.12065 0.2794)
			(end 0.12065 0.3048)
			(stroke
				(width 0.1)
				(type default)
			)
			(layer "B.Fab")
		)
		(fp_line
			(start 0.12065 0.3048)
			(end 0.67945 0.3048)
			(stroke
				(width 0.1)
				(type default)
			)
			(layer "B.Fab")
		)
		(fp_line
			(start 0.67945 -0.305054)
			(end 0.12065 -0.305054)
			(stroke
				(width 0.1)
				(type default)
			)
			(layer "B.Fab")
		)
		(fp_line
			(start 0.67945 0.3048)
			(end 0.67945 -0.305054)
			(stroke
				(width 0.1)
				(type default)
			)
			(layer "B.Fab")
		)
		(pad "1" smd circle
			(at 0.40005 0 180)
			(size 0 0)
			(layers "B.Cu" "B.Mask" "B.Paste")
			(net "FM_BIOS_ADV_FUNCTIONS")
		)
		(pad "2" smd circle
			(at -0.40005 0 180)
			(size 0 0)
			(layers "B.Cu" "B.Mask" "B.Paste")
			(net "GND")
		)
	)
	(footprint ""
		(layer "B.Cu")
		(at 500.77497 -427.51502 180)
		(property "Reference" "DB13"
			(at 2.443988 -8.440928 270)
			(unlocked yes)
			(layer "B.SilkS")
			(effects
				(font
					(size 0.7874 0.5842)
					(thickness 0.1524)
				)
				(justify left mirror)
			)
		)
		(property "Value" ""
			(at 0 0 0)
			(layer "B.Fab")
			(effects
				(font
					(size 1.27 1.27)
				)
				(justify mirror)
			)
		)
		(duplicate_pad_numbers_are_jumpers no)
		(fp_line
			(start 3.330702 -4.771136)
			(end -3.330702 -4.771136)
			(stroke
				(width 0.1524)
				(type default)
			)
			(layer "B.SilkS")
		)
		(fp_line
			(start 0 4.011168)
			(end 3.330702 -4.771136)
			(stroke
				(width 0.1524)
				(type default)
			)
			(layer "B.SilkS")
		)
		(fp_line
			(start -3.330702 -4.771136)
			(end 0 4.011168)
			(stroke
				(width 0.1524)
				(type default)
			)
			(layer "B.SilkS")
		)
		(fp_line
			(start 3.330702 -4.771136)
			(end -3.330702 -4.771136)
			(stroke
				(width 0.1)
				(type default)
			)
			(layer "B.Fab")
		)
		(fp_line
			(start 0 4.011168)
			(end 3.330702 -4.771136)
			(stroke
				(width 0.1)
				(type default)
			)
			(layer "B.Fab")
		)
		(fp_line
			(start -3.330702 -4.771136)
			(end 0 4.011168)
			(stroke
				(width 0.1)
				(type default)
			)
			(layer "B.Fab")
		)
		(pad "1" thru_hole circle
			(at 0 0)
			(size 2.159 2.159)
			(drill 1.7018)
			(layers "*.Cu" "*.Mask")
			(remove_unused_layers no)
			(net "T1_GND")
			(clearance 0.0254)
			(thermal_gap 0.0254)
		)
		(pad "2" thru_hole circle
			(at 1.27 -3.348736)
			(size 2.159 2.159)
			(drill 1.7018)
			(layers "*.Cu" "*.Mask")
			(remove_unused_layers no)
			(net "TDR_SE_40_OHM_IN5")
			(clearance 0.0254)
			(thermal_gap 0.0254)
		)
		(pad "3" thru_hole circle
			(at -1.27 -3.348736)
			(size 2.159 2.159)
			(drill 1.7018)
			(layers "*.Cu" "*.Mask")
			(remove_unused_layers no)
			(net "TDR_SE_40_OHM_IN5")
			(clearance 0.0254)
			(thermal_gap 0.0254)
		)
	)
	(footprint ""
		(layer "B.Cu")
		(at 164.64788 -122.646948)
		(property "Reference" "R1414"
			(at 0 0 0)
			(layer "B.SilkS")
			(hide yes)
			(effects
				(font
					(size 1.27 1.27)
				)
				(justify mirror)
			)
		)
		(property "Value" ""
			(at 0 0 0)
			(layer "B.Fab")
			(effects
				(font
					(size 1.27 1.27)
				)
				(justify mirror)
			)
		)
		(duplicate_pad_numbers_are_jumpers no)
		(fp_line
			(start -0.7874 -0.4064)
			(end -0.7874 0.4064)
			(stroke
				(width 0.1524)
				(type default)
			)
			(layer "B.SilkS")
		)
		(fp_line
			(start -0.7874 0.4064)
			(end 0.7874 0.4064)
			(stroke
				(width 0.1524)
				(type default)
			)
			(layer "B.SilkS")
		)
		(fp_line
			(start 0.7874 -0.4064)
			(end -0.7874 -0.4064)
			(stroke
				(width 0.1524)
				(type default)
			)
			(layer "B.SilkS")
		)
		(fp_line
			(start 0.7874 0.4064)
			(end 0.7874 -0.4064)
			(stroke
				(width 0.1524)
				(type default)
			)
			(layer "B.SilkS")
		)
		(fp_line
			(start -0.67945 -0.3048)
			(end -0.67945 0.3048)
			(stroke
				(width 0.1)
				(type default)
			)
			(layer "B.Fab")
		)
		(fp_line
			(start -0.67945 0.3048)
			(end -0.120396 0.3048)
			(stroke
				(width 0.1)
				(type default)
			)
			(layer "B.Fab")
		)
		(fp_line
			(start -0.12065 -0.3048)
			(end -0.67945 -0.3048)
			(stroke
				(width 0.1)
				(type default)
			)
			(layer "B.Fab")
		)
		(fp_line
			(start -0.12065 -0.2794)
			(end -0.12065 -0.3048)
			(stroke
				(width 0.1)
				(type default)
			)
			(layer "B.Fab")
		)
		(fp_line
			(start -0.120396 0.2794)
			(end 0.12065 0.2794)
			(stroke
				(width 0.1)
				(type default)
			)
			(layer "B.Fab")
		)
		(fp_line
			(start -0.120396 0.3048)
			(end -0.120396 0.2794)
			(stroke
				(width 0.1)
				(type default)
			)
			(layer "B.Fab")
		)
		(fp_line
			(start 0.12065 -0.305054)
			(end 0.12065 -0.2794)
			(stroke
				(width 0.1)
				(type default)
			)
			(layer "B.Fab")
		)
		(fp_line
			(start 0.12065 -0.2794)
			(end -0.12065 -0.2794)
			(stroke
				(width 0.1)
				(type default)
			)
			(layer "B.Fab")
		)
		(fp_line
			(start 0.12065 0.2794)
			(end 0.12065 0.3048)
			(stroke
				(width 0.1)
				(type default)
			)
			(layer "B.Fab")
		)
		(fp_line
			(start 0.12065 0.3048)
			(end 0.67945 0.3048)
			(stroke
				(width 0.1)
				(type default)
			)
			(layer "B.Fab")
		)
		(fp_line
			(start 0.67945 -0.305054)
			(end 0.12065 -0.305054)
			(stroke
				(width 0.1)
				(type default)
			)
			(layer "B.Fab")
		)
		(fp_line
			(start 0.67945 0.3048)
			(end 0.67945 -0.305054)
			(stroke
				(width 0.1)
				(type default)
			)
			(layer "B.Fab")
		)
		(pad "1" smd circle
			(at 0.40005 0 180)
			(size 0 0)
			(layers "B.Cu" "B.Mask" "B.Paste")
			(net "FM_PVCCD_HV_CPU1_EN")
		)
		(pad "2" smd circle
			(at -0.40005 0 180)
			(size 0 0)
			(layers "B.Cu" "B.Mask" "B.Paste")
			(net "GND")
		)
	)
	(footprint ""
		(layer "B.Cu")
		(at 425.917614 -321.549776 -90)
		(property "Reference" "C37"
			(at 0 0 90)
			(layer "B.SilkS")
			(hide yes)
			(effects
				(font
					(size 1.27 1.27)
				)
				(justify mirror)
			)
		)
		(property "Value" ""
			(at 0 0 90)
			(layer "B.Fab")
			(effects
				(font
					(size 1.27 1.27)
				)
				(justify mirror)
			)
		)
		(duplicate_pad_numbers_are_jumpers no)
		(fp_line
			(start -1.524 0.762)
			(end 1.524 0.762)
			(stroke
				(width 0.1524)
				(type default)
			)
			(layer "B.SilkS")
		)
		(fp_line
			(start 1.524 0.762)
			(end 1.524 -0.762)
			(stroke
				(width 0.1524)
				(type default)
			)
			(layer "B.SilkS")
		)
		(fp_line
			(start -1.524 -0.762)
			(end -1.524 0.762)
			(stroke
				(width 0.1524)
				(type default)
			)
			(layer "B.SilkS")
		)
		(fp_line
			(start 1.524 -0.762)
			(end -1.524 -0.762)
			(stroke
				(width 0.1524)
				(type default)
			)
			(layer "B.SilkS")
		)
		(fp_line
			(start -1.1049 0.724916)
			(end -1.1049 -0.724916)
			(stroke
				(width 0.1)
				(type default)
			)
			(layer "B.Fab")
		)
		(fp_line
			(start 1.1049 0.724916)
			(end -1.1049 0.724916)
			(stroke
				(width 0.1)
				(type default)
			)
			(layer "B.Fab")
		)
		(fp_line
			(start -1.1049 -0.724916)
			(end 1.1049 -0.724916)
			(stroke
				(width 0.1)
				(type default)
			)
			(layer "B.Fab")
		)
		(fp_line
			(start 1.1049 -0.724916)
			(end 1.1049 0.724916)
			(stroke
				(width 0.1)
				(type default)
			)
			(layer "B.Fab")
		)
		(pad "1" smd rect
			(at 0.889 0 270)
			(size 1.016 1.27)
			(layers "B.Cu" "B.Mask" "B.Paste")
			(net "P12V_S3_AUX_CPU0_NVDIMM")
		)
		(pad "2" smd rect
			(at -0.889 0 270)
			(size 1.016 1.27)
			(layers "B.Cu" "B.Mask" "B.Paste")
			(net "GND")
		)
	)
	(footprint ""
		(layer "B.Cu")
		(at 27.7368 -162.270948 -90)
		(property "Reference" "PR4255"
			(at 0 0 90)
			(layer "B.SilkS")
			(hide yes)
			(effects
				(font
					(size 1.27 1.27)
				)
				(justify mirror)
			)
		)
		(property "Value" ""
			(at 0 0 90)
			(layer "B.Fab")
			(effects
				(font
					(size 1.27 1.27)
				)
				(justify mirror)
			)
		)
		(duplicate_pad_numbers_are_jumpers no)
		(fp_line
			(start -0.7874 0.4064)
			(end 0.7874 0.4064)
			(stroke
				(width 0.1524)
				(type default)
			)
			(layer "B.SilkS")
		)
		(fp_line
			(start 0.7874 0.4064)
			(end 0.7874 -0.4064)
			(stroke
				(width 0.1524)
				(type default)
			)
			(layer "B.SilkS")
		)
		(fp_line
			(start -0.7874 -0.4064)
			(end -0.7874 0.4064)
			(stroke
				(width 0.1524)
				(type default)
			)
			(layer "B.SilkS")
		)
		(fp_line
			(start 0.7874 -0.4064)
			(end -0.7874 -0.4064)
			(stroke
				(width 0.1524)
				(type default)
			)
			(layer "B.SilkS")
		)
		(fp_line
			(start -0.67945 0.3048)
			(end -0.120396 0.3048)
			(stroke
				(width 0.1)
				(type default)
			)
			(layer "B.Fab")
		)
		(fp_line
			(start -0.120396 0.3048)
			(end -0.120396 0.2794)
			(stroke
				(width 0.1)
				(type default)
			)
			(layer "B.Fab")
		)
		(fp_line
			(start 0.12065 0.3048)
			(end 0.67945 0.3048)
			(stroke
				(width 0.1)
				(type default)
			)
			(layer "B.Fab")
		)
		(fp_line
			(start 0.67945 0.3048)
			(end 0.67945 -0.305054)
			(stroke
				(width 0.1)
				(type default)
			)
			(layer "B.Fab")
		)
		(fp_line
			(start -0.120396 0.2794)
			(end 0.12065 0.2794)
			(stroke
				(width 0.1)
				(type default)
			)
			(layer "B.Fab")
		)
		(fp_line
			(start 0.12065 0.2794)
			(end 0.12065 0.3048)
			(stroke
				(width 0.1)
				(type default)
			)
			(layer "B.Fab")
		)
		(fp_line
			(start -0.12065 -0.2794)
			(end -0.12065 -0.3048)
			(stroke
				(width 0.1)
				(type default)
			)
			(layer "B.Fab")
		)
		(fp_line
			(start 0.12065 -0.2794)
			(end -0.12065 -0.2794)
			(stroke
				(width 0.1)
				(type default)
			)
			(layer "B.Fab")
		)
		(fp_line
			(start -0.67945 -0.3048)
			(end -0.67945 0.3048)
			(stroke
				(width 0.1)
				(type default)
			)
			(layer "B.Fab")
		)
		(fp_line
			(start -0.12065 -0.3048)
			(end -0.67945 -0.3048)
			(stroke
				(width 0.1)
				(type default)
			)
			(layer "B.Fab")
		)
		(fp_line
			(start 0.12065 -0.305054)
			(end 0.12065 -0.2794)
			(stroke
				(width 0.1)
				(type default)
			)
			(layer "B.Fab")
		)
		(fp_line
			(start 0.67945 -0.305054)
			(end 0.12065 -0.305054)
			(stroke
				(width 0.1)
				(type default)
			)
			(layer "B.Fab")
		)
		(pad "1" smd circle
			(at 0.40005 0 90)
			(size 0 0)
			(layers "B.Cu" "B.Mask" "B.Paste")
			(net "NC_PVCCD_HV_CPU1_ACSP6")
		)
		(pad "2" smd circle
			(at -0.40005 0 90)
			(size 0 0)
			(layers "B.Cu" "B.Mask" "B.Paste")
			(net "GND")
		)
	)
	(footprint ""
		(layer "B.Cu")
		(at 103.596694 -237.794292 -90)
		(property "Reference" "C1389"
			(at 0 0 90)
			(layer "B.SilkS")
			(hide yes)
			(effects
				(font
					(size 1.27 1.27)
				)
				(justify mirror)
			)
		)
		(property "Value" ""
			(at 0 0 90)
			(layer "B.Fab")
			(effects
				(font
					(size 1.27 1.27)
				)
				(justify mirror)
			)
		)
		(duplicate_pad_numbers_are_jumpers no)
		(fp_line
			(start -1.2954 0.5842)
			(end 1.2954 0.5842)
			(stroke
				(width 0.1524)
				(type default)
			)
			(layer "B.SilkS")
		)
		(fp_line
			(start 1.2954 0.5842)
			(end 1.2954 -0.5842)
			(stroke
				(width 0.1524)
				(type default)
			)
			(layer "B.SilkS")
		)
		(fp_line
			(start -1.2954 -0.5842)
			(end -1.2954 0.5842)
			(stroke
				(width 0.1524)
				(type default)
			)
			(layer "B.SilkS")
		)
		(fp_line
			(start 0 -0.5842)
			(end 0 0.5842)
			(stroke
				(width 0.1524)
				(type default)
			)
			(layer "B.SilkS")
		)
		(fp_line
			(start 1.2954 -0.5842)
			(end -1.2954 -0.5842)
			(stroke
				(width 0.1524)
				(type default)
			)
			(layer "B.SilkS")
		)
		(fp_line
			(start -0.8636 0.4572)
			(end 0.8636 0.4572)
			(stroke
				(width 0.1)
				(type default)
			)
			(layer "B.Fab")
		)
		(fp_line
			(start 0.8636 0.4572)
			(end 0.8636 0.4064)
			(stroke
				(width 0.1)
				(type default)
			)
			(layer "B.Fab")
		)
		(fp_line
			(start -1.1938 0.4064)
			(end -0.8636 0.4064)
			(stroke
				(width 0.1)
				(type default)
			)
			(layer "B.Fab")
		)
		(fp_line
			(start -0.8636 0.4064)
			(end -0.8636 0.4572)
			(stroke
				(width 0.1)
				(type default)
			)
			(layer "B.Fab")
		)
		(fp_line
			(start 0.8636 0.4064)
			(end 1.1938 0.4064)
			(stroke
				(width 0.1)
				(type default)
			)
			(layer "B.Fab")
		)
		(fp_line
			(start 1.1938 0.4064)
			(end 1.1938 -0.4064)
			(stroke
				(width 0.1)
				(type default)
			)
			(layer "B.Fab")
		)
		(fp_line
			(start -1.1938 -0.4064)
			(end -1.1938 0.4064)
			(stroke
				(width 0.1)
				(type default)
			)
			(layer "B.Fab")
		)
		(fp_line
			(start -0.8636 -0.4064)
			(end -1.1938 -0.4064)
			(stroke
				(width 0.1)
				(type default)
			)
			(layer "B.Fab")
		)
		(fp_line
			(start 0.8636 -0.4064)
			(end 0.8636 -0.4572)
			(stroke
				(width 0.1)
				(type default)
			)
			(layer "B.Fab")
		)
		(fp_line
			(start 1.1938 -0.4064)
			(end 0.8636 -0.4064)
			(stroke
				(width 0.1)
				(type default)
			)
			(layer "B.Fab")
		)
		(fp_line
			(start -0.8636 -0.4572)
			(end -0.8636 -0.4064)
			(stroke
				(width 0.1)
				(type default)
			)
			(layer "B.Fab")
		)
		(fp_line
			(start 0.8636 -0.4572)
			(end -0.8636 -0.4572)
			(stroke
				(width 0.1)
				(type default)
			)
			(layer "B.Fab")
		)
		(pad "1" smd rect
			(at 0.7366 0 180)
			(size 0.7112 0.8128)
			(layers "B.Cu" "B.Mask" "B.Paste")
			(net "PVNN_MAIN_CPU1")
		)
		(pad "2" smd rect
			(at -0.7366 0 180)
			(size 0.7112 0.8128)
			(layers "B.Cu" "B.Mask" "B.Paste")
			(net "GND")
		)
	)
	(footprint ""
		(layer "B.Cu")
		(at 423.807382 -137.07872 180)
		(property "Reference" "PC1271"
			(at 0 0 0)
			(layer "B.SilkS")
			(hide yes)
			(effects
				(font
					(size 1.27 1.27)
				)
				(justify mirror)
			)
		)
		(property "Value" ""
			(at 0 0 0)
			(layer "B.Fab")
			(effects
				(font
					(size 1.27 1.27)
				)
				(justify mirror)
			)
		)
		(duplicate_pad_numbers_are_jumpers no)
		(fp_line
			(start 0.7874 0.4064)
			(end 0.7874 -0.4064)
			(stroke
				(width 0.1524)
				(type default)
			)
			(layer "B.SilkS")
		)
		(fp_line
			(start 0.7874 -0.4064)
			(end -0.7874 -0.4064)
			(stroke
				(width 0.1524)
				(type default)
			)
			(layer "B.SilkS")
		)
		(fp_line
			(start -0.7874 0.4064)
			(end 0.7874 0.4064)
			(stroke
				(width 0.1524)
				(type default)
			)
			(layer "B.SilkS")
		)
		(fp_line
			(start -0.7874 -0.4064)
			(end -0.7874 0.4064)
			(stroke
				(width 0.1524)
				(type default)
			)
			(layer "B.SilkS")
		)
		(fp_line
			(start 0.67945 0.3048)
			(end 0.67945 -0.305054)
			(stroke
				(width 0.1)
				(type default)
			)
			(layer "B.Fab")
		)
		(fp_line
			(start 0.67945 -0.305054)
			(end 0.12065 -0.305054)
			(stroke
				(width 0.1)
				(type default)
			)
			(layer "B.Fab")
		)
		(fp_line
			(start 0.12065 0.3048)
			(end 0.67945 0.3048)
			(stroke
				(width 0.1)
				(type default)
			)
			(layer "B.Fab")
		)
		(fp_line
			(start 0.12065 0.2794)
			(end 0.12065 0.3048)
			(stroke
				(width 0.1)
				(type default)
			)
			(layer "B.Fab")
		)
		(fp_line
			(start 0.12065 -0.2794)
			(end -0.12065 -0.2794)
			(stroke
				(width 0.1)
				(type default)
			)
			(layer "B.Fab")
		)
		(fp_line
			(start 0.12065 -0.305054)
			(end 0.12065 -0.2794)
			(stroke
				(width 0.1)
				(type default)
			)
			(layer "B.Fab")
		)
		(fp_line
			(start -0.120396 0.3048)
			(end -0.120396 0.2794)
			(stroke
				(width 0.1)
				(type default)
			)
			(layer "B.Fab")
		)
		(fp_line
			(start -0.120396 0.2794)
			(end 0.12065 0.2794)
			(stroke
				(width 0.1)
				(type default)
			)
			(layer "B.Fab")
		)
		(fp_line
			(start -0.12065 -0.2794)
			(end -0.12065 -0.3048)
			(stroke
				(width 0.1)
				(type default)
			)
			(layer "B.Fab")
		)
		(fp_line
			(start -0.12065 -0.3048)
			(end -0.67945 -0.3048)
			(stroke
				(width 0.1)
				(type default)
			)
			(layer "B.Fab")
		)
		(fp_line
			(start -0.67945 0.3048)
			(end -0.120396 0.3048)
			(stroke
				(width 0.1)
				(type default)
			)
			(layer "B.Fab")
		)
		(fp_line
			(start -0.67945 -0.3048)
			(end -0.67945 0.3048)
			(stroke
				(width 0.1)
				(type default)
			)
			(layer "B.Fab")
		)
		(pad "1" smd circle
			(at 0.40005 0)
			(size 0 0)
			(layers "B.Cu" "B.Mask" "B.Paste")
			(net "PVCCFA_EHV_CPU0_BTSEN")
		)
		(pad "2" smd circle
			(at -0.40005 0)
			(size 0 0)
			(layers "B.Cu" "B.Mask" "B.Paste")
			(net "GND")
		)
	)
	(footprint ""
		(layer "B.Cu")
		(at 409.284932 -179.457858 180)
		(property "Reference" "PC1573"
			(at 0 0 0)
			(layer "B.SilkS")
			(hide yes)
			(effects
				(font
					(size 1.27 1.27)
				)
				(justify mirror)
			)
		)
		(property "Value" ""
			(at 0 0 0)
			(layer "B.Fab")
			(effects
				(font
					(size 1.27 1.27)
				)
				(justify mirror)
			)
		)
		(duplicate_pad_numbers_are_jumpers no)
		(fp_line
			(start 4.84378 -2.150618)
			(end 4.842256 2.163064)
			(stroke
				(width 0.1524)
				(type default)
			)
			(layer "B.SilkS")
		)
		(fp_line
			(start 4.84378 -2.150618)
			(end 4.53898 -2.150618)
			(stroke
				(width 0.1524)
				(type default)
			)
			(layer "B.SilkS")
		)
		(fp_line
			(start 4.83108 2.150364)
			(end 4.447794 2.149348)
			(stroke
				(width 0.1524)
				(type default)
			)
			(layer "B.SilkS")
		)
		(fp_line
			(start 4.69138 -2.150618)
			(end 4.692396 2.161032)
			(stroke
				(width 0.1524)
				(type default)
			)
			(layer "B.SilkS")
		)
		(fp_line
			(start 4.53898 2.15011)
			(end 4.53898 -2.15011)
			(stroke
				(width 0.1524)
				(type default)
			)
			(layer "B.SilkS")
		)
		(fp_line
			(start 4.53898 -2.15011)
			(end -4.53898 -2.15011)
			(stroke
				(width 0.1524)
				(type default)
			)
			(layer "B.SilkS")
		)
		(fp_line
			(start 4.53898 -2.150618)
			(end 4.539742 2.152142)
			(stroke
				(width 0.1524)
				(type default)
			)
			(layer "B.SilkS")
		)
		(fp_line
			(start -4.53898 2.15011)
			(end 4.53898 2.15011)
			(stroke
				(width 0.1524)
				(type default)
			)
			(layer "B.SilkS")
		)
		(fp_line
			(start -4.53898 -2.15011)
			(end -4.53898 2.15011)
			(stroke
				(width 0.1524)
				(type default)
			)
			(layer "B.SilkS")
		)
		(fp_line
			(start 3.64998 2.15011)
			(end 3.64998 -2.15011)
			(stroke
				(width 0.1)
				(type default)
			)
			(layer "B.Fab")
		)
		(fp_line
			(start 3.64998 -2.15011)
			(end -3.64998 -2.15011)
			(stroke
				(width 0.1)
				(type default)
			)
			(layer "B.Fab")
		)
		(fp_line
			(start -3.64998 2.15011)
			(end 3.64998 2.15011)
			(stroke
				(width 0.1)
				(type default)
			)
			(layer "B.Fab")
		)
		(fp_line
			(start -3.64998 -2.15011)
			(end -3.64998 2.15011)
			(stroke
				(width 0.1)
				(type default)
			)
			(layer "B.Fab")
		)
		(fp_text user "+"
			(at 6.214872 -0.337058 180)
			(unlocked yes)
			(layer "B.SilkS")
			(effects
				(font
					(size 1.905 1.4224)
					(thickness 0.1524)
				)
				(justify left mirror)
			)
		)
		(fp_text user "-"
			(at -5.123688 0.89154 180)
			(unlocked yes)
			(layer "B.SilkS")
			(effects
				(font
					(size 1.905 1.4224)
					(thickness 0.1524)
				)
				(justify left mirror)
			)
		)
		(fp_text user "+"
			(at 6.214872 -0.337058 180)
			(unlocked yes)
			(layer "B.Fab")
			(effects
				(font
					(size 1.905 1.4224)
					(thickness 0.1524)
				)
				(justify left mirror)
			)
		)
		(fp_text user "-"
			(at -4.313174 -0.094488 180)
			(unlocked yes)
			(layer "B.Fab")
			(effects
				(font
					(size 1.905 1.4224)
					(thickness 0.1524)
				)
				(justify left mirror)
			)
		)
		(pad "1" smd rect
			(at 3.199892 0)
			(size 2.413 2.8194)
			(layers "B.Cu" "B.Mask" "B.Paste")
			(net "PVCCINFAON_CPU0")
		)
		(pad "2" smd rect
			(at -3.199892 0)
			(size 2.413 2.8194)
			(layers "B.Cu" "B.Mask" "B.Paste")
			(net "GND")
		)
	)
	(footprint ""
		(layer "B.Cu")
		(at 366.450372 -337.899248)
		(property "Reference" "PR148"
			(at 0 0 0)
			(layer "B.SilkS")
			(hide yes)
			(effects
				(font
					(size 1.27 1.27)
				)
				(justify mirror)
			)
		)
		(property "Value" ""
			(at 0 0 0)
			(layer "B.Fab")
			(effects
				(font
					(size 1.27 1.27)
				)
				(justify mirror)
			)
		)
		(duplicate_pad_numbers_are_jumpers no)
		(fp_line
			(start -0.7874 -0.4064)
			(end -0.7874 0.4064)
			(stroke
				(width 0.1524)
				(type default)
			)
			(layer "B.SilkS")
		)
		(fp_line
			(start -0.7874 0.4064)
			(end 0.7874 0.4064)
			(stroke
				(width 0.1524)
				(type default)
			)
			(layer "B.SilkS")
		)
		(fp_line
			(start 0.7874 -0.4064)
			(end -0.7874 -0.4064)
			(stroke
				(width 0.1524)
				(type default)
			)
			(layer "B.SilkS")
		)
		(fp_line
			(start 0.7874 0.4064)
			(end 0.7874 -0.4064)
			(stroke
				(width 0.1524)
				(type default)
			)
			(layer "B.SilkS")
		)
		(fp_line
			(start -0.67945 -0.3048)
			(end -0.67945 0.3048)
			(stroke
				(width 0.1)
				(type default)
			)
			(layer "B.Fab")
		)
		(fp_line
			(start -0.67945 0.3048)
			(end -0.120396 0.3048)
			(stroke
				(width 0.1)
				(type default)
			)
			(layer "B.Fab")
		)
		(fp_line
			(start -0.12065 -0.3048)
			(end -0.67945 -0.3048)
			(stroke
				(width 0.1)
				(type default)
			)
			(layer "B.Fab")
		)
		(fp_line
			(start -0.12065 -0.2794)
			(end -0.12065 -0.3048)
			(stroke
				(width 0.1)
				(type default)
			)
			(layer "B.Fab")
		)
		(fp_line
			(start -0.120396 0.2794)
			(end 0.12065 0.2794)
			(stroke
				(width 0.1)
				(type default)
			)
			(layer "B.Fab")
		)
		(fp_line
			(start -0.120396 0.3048)
			(end -0.120396 0.2794)
			(stroke
				(width 0.1)
				(type default)
			)
			(layer "B.Fab")
		)
		(fp_line
			(start 0.12065 -0.305054)
			(end 0.12065 -0.2794)
			(stroke
				(width 0.1)
				(type default)
			)
			(layer "B.Fab")
		)
		(fp_line
			(start 0.12065 -0.2794)
			(end -0.12065 -0.2794)
			(stroke
				(width 0.1)
				(type default)
			)
			(layer "B.Fab")
		)
		(fp_line
			(start 0.12065 0.2794)
			(end 0.12065 0.3048)
			(stroke
				(width 0.1)
				(type default)
			)
			(layer "B.Fab")
		)
		(fp_line
			(start 0.12065 0.3048)
			(end 0.67945 0.3048)
			(stroke
				(width 0.1)
				(type default)
			)
			(layer "B.Fab")
		)
		(fp_line
			(start 0.67945 -0.305054)
			(end 0.12065 -0.305054)
			(stroke
				(width 0.1)
				(type default)
			)
			(layer "B.Fab")
		)
		(fp_line
			(start 0.67945 0.3048)
			(end 0.67945 -0.305054)
			(stroke
				(width 0.1)
				(type default)
			)
			(layer "B.Fab")
		)
		(pad "1" smd circle
			(at 0.40005 0 180)
			(size 0 0)
			(layers "B.Cu" "B.Mask" "B.Paste")
			(net "PVCCIN_CPU0_VOS4")
		)
		(pad "2" smd circle
			(at -0.40005 0 180)
			(size 0 0)
			(layers "B.Cu" "B.Mask" "B.Paste")
			(net "PVCCIN_CPU0")
		)
	)
	(footprint ""
		(layer "B.Cu")
		(at 127.83058 -31.529528 90)
		(property "Reference" "R4284"
			(at 0 0 90)
			(layer "B.SilkS")
			(hide yes)
			(effects
				(font
					(size 1.27 1.27)
				)
				(justify mirror)
			)
		)
		(property "Value" ""
			(at 0 0 90)
			(layer "B.Fab")
			(effects
				(font
					(size 1.27 1.27)
				)
				(justify mirror)
			)
		)
		(duplicate_pad_numbers_are_jumpers no)
		(fp_line
			(start 0.7874 -0.4064)
			(end -0.7874 -0.4064)
			(stroke
				(width 0.1524)
				(type default)
			)
			(layer "B.SilkS")
		)
		(fp_line
			(start -0.7874 -0.4064)
			(end -0.7874 0.4064)
			(stroke
				(width 0.1524)
				(type default)
			)
			(layer "B.SilkS")
		)
		(fp_line
			(start 0.7874 0.4064)
			(end 0.7874 -0.4064)
			(stroke
				(width 0.1524)
				(type default)
			)
			(layer "B.SilkS")
		)
		(fp_line
			(start -0.7874 0.4064)
			(end 0.7874 0.4064)
			(stroke
				(width 0.1524)
				(type default)
			)
			(layer "B.SilkS")
		)
		(fp_line
			(start 0.67945 -0.305054)
			(end 0.12065 -0.305054)
			(stroke
				(width 0.1)
				(type default)
			)
			(layer "B.Fab")
		)
		(fp_line
			(start 0.12065 -0.305054)
			(end 0.12065 -0.2794)
			(stroke
				(width 0.1)
				(type default)
			)
			(layer "B.Fab")
		)
		(fp_line
			(start -0.12065 -0.3048)
			(end -0.67945 -0.3048)
			(stroke
				(width 0.1)
				(type default)
			)
			(layer "B.Fab")
		)
		(fp_line
			(start -0.67945 -0.3048)
			(end -0.67945 0.3048)
			(stroke
				(width 0.1)
				(type default)
			)
			(layer "B.Fab")
		)
		(fp_line
			(start 0.12065 -0.2794)
			(end -0.12065 -0.2794)
			(stroke
				(width 0.1)
				(type default)
			)
			(layer "B.Fab")
		)
		(fp_line
			(start -0.12065 -0.2794)
			(end -0.12065 -0.3048)
			(stroke
				(width 0.1)
				(type default)
			)
			(layer "B.Fab")
		)
		(fp_line
			(start 0.12065 0.2794)
			(end 0.12065 0.3048)
			(stroke
				(width 0.1)
				(type default)
			)
			(layer "B.Fab")
		)
		(fp_line
			(start -0.120396 0.2794)
			(end 0.12065 0.2794)
			(stroke
				(width 0.1)
				(type default)
			)
			(layer "B.Fab")
		)
		(fp_line
			(start 0.67945 0.3048)
			(end 0.67945 -0.305054)
			(stroke
				(width 0.1)
				(type default)
			)
			(layer "B.Fab")
		)
		(fp_line
			(start 0.12065 0.3048)
			(end 0.67945 0.3048)
			(stroke
				(width 0.1)
				(type default)
			)
			(layer "B.Fab")
		)
		(fp_line
			(start -0.120396 0.3048)
			(end -0.120396 0.2794)
			(stroke
				(width 0.1)
				(type default)
			)
			(layer "B.Fab")
		)
		(fp_line
			(start -0.67945 0.3048)
			(end -0.120396 0.3048)
			(stroke
				(width 0.1)
				(type default)
			)
			(layer "B.Fab")
		)
		(pad "1" smd circle
			(at 0.40005 0 270)
			(size 0 0)
			(layers "B.Cu" "B.Mask" "B.Paste")
			(net "P3V3_AUX")
		)
		(pad "2" smd circle
			(at -0.40005 0 270)
			(size 0 0)
			(layers "B.Cu" "B.Mask" "B.Paste")
			(net "FM_USB3_1_SWB")
		)
	)
	(footprint ""
		(layer "B.Cu")
		(at 102.495604 -296.05478 180)
		(property "Reference" "C342"
			(at 0 0 0)
			(layer "B.SilkS")
			(hide yes)
			(effects
				(font
					(size 1.27 1.27)
				)
				(justify mirror)
			)
		)
		(property "Value" ""
			(at 0 0 0)
			(layer "B.Fab")
			(effects
				(font
					(size 1.27 1.27)
				)
				(justify mirror)
			)
		)
		(duplicate_pad_numbers_are_jumpers no)
		(fp_line
			(start 1.524 0.762)
			(end 1.524 -0.762)
			(stroke
				(width 0.1524)
				(type default)
			)
			(layer "B.SilkS")
		)
		(fp_line
			(start 1.524 -0.762)
			(end -1.524 -0.762)
			(stroke
				(width 0.1524)
				(type default)
			)
			(layer "B.SilkS")
		)
		(fp_line
			(start -1.524 0.762)
			(end 1.524 0.762)
			(stroke
				(width 0.1524)
				(type default)
			)
			(layer "B.SilkS")
		)
		(fp_line
			(start -1.524 -0.762)
			(end -1.524 0.762)
			(stroke
				(width 0.1524)
				(type default)
			)
			(layer "B.SilkS")
		)
		(fp_line
			(start 1.1049 0.724916)
			(end -1.1049 0.724916)
			(stroke
				(width 0.1)
				(type default)
			)
			(layer "B.Fab")
		)
		(fp_line
			(start 1.1049 -0.724916)
			(end 1.1049 0.724916)
			(stroke
				(width 0.1)
				(type default)
			)
			(layer "B.Fab")
		)
		(fp_line
			(start -1.1049 0.724916)
			(end -1.1049 -0.724916)
			(stroke
				(width 0.1)
				(type default)
			)
			(layer "B.Fab")
		)
		(fp_line
			(start -1.1049 -0.724916)
			(end 1.1049 -0.724916)
			(stroke
				(width 0.1)
				(type default)
			)
			(layer "B.Fab")
		)
		(pad "1" smd rect
			(at 0.889 0 180)
			(size 1.016 1.27)
			(layers "B.Cu" "B.Mask" "B.Paste")
			(net "PVCCIN_CPU1")
		)
		(pad "2" smd rect
			(at -0.889 0 180)
			(size 1.016 1.27)
			(layers "B.Cu" "B.Mask" "B.Paste")
			(net "GND")
		)
	)
	(footprint ""
		(layer "B.Cu")
		(at 236.76991 -130.072892)
		(property "Reference" "R4510"
			(at 0 0 0)
			(layer "B.SilkS")
			(hide yes)
			(effects
				(font
					(size 1.27 1.27)
				)
				(justify mirror)
			)
		)
		(property "Value" ""
			(at 0 0 0)
			(layer "B.Fab")
			(effects
				(font
					(size 1.27 1.27)
				)
				(justify mirror)
			)
		)
		(duplicate_pad_numbers_are_jumpers no)
		(fp_line
			(start -0.7874 -0.4064)
			(end -0.7874 0.4064)
			(stroke
				(width 0.1524)
				(type default)
			)
			(layer "B.SilkS")
		)
		(fp_line
			(start -0.7874 0.4064)
			(end 0.7874 0.4064)
			(stroke
				(width 0.1524)
				(type default)
			)
			(layer "B.SilkS")
		)
		(fp_line
			(start 0.7874 -0.4064)
			(end -0.7874 -0.4064)
			(stroke
				(width 0.1524)
				(type default)
			)
			(layer "B.SilkS")
		)
		(fp_line
			(start 0.7874 0.4064)
			(end 0.7874 -0.4064)
			(stroke
				(width 0.1524)
				(type default)
			)
			(layer "B.SilkS")
		)
		(fp_line
			(start -0.67945 -0.3048)
			(end -0.67945 0.3048)
			(stroke
				(width 0.1)
				(type default)
			)
			(layer "B.Fab")
		)
		(fp_line
			(start -0.67945 0.3048)
			(end -0.120396 0.3048)
			(stroke
				(width 0.1)
				(type default)
			)
			(layer "B.Fab")
		)
		(fp_line
			(start -0.12065 -0.3048)
			(end -0.67945 -0.3048)
			(stroke
				(width 0.1)
				(type default)
			)
			(layer "B.Fab")
		)
		(fp_line
			(start -0.12065 -0.2794)
			(end -0.12065 -0.3048)
			(stroke
				(width 0.1)
				(type default)
			)
			(layer "B.Fab")
		)
		(fp_line
			(start -0.120396 0.2794)
			(end 0.12065 0.2794)
			(stroke
				(width 0.1)
				(type default)
			)
			(layer "B.Fab")
		)
		(fp_line
			(start -0.120396 0.3048)
			(end -0.120396 0.2794)
			(stroke
				(width 0.1)
				(type default)
			)
			(layer "B.Fab")
		)
		(fp_line
			(start 0.12065 -0.305054)
			(end 0.12065 -0.2794)
			(stroke
				(width 0.1)
				(type default)
			)
			(layer "B.Fab")
		)
		(fp_line
			(start 0.12065 -0.2794)
			(end -0.12065 -0.2794)
			(stroke
				(width 0.1)
				(type default)
			)
			(layer "B.Fab")
		)
		(fp_line
			(start 0.12065 0.2794)
			(end 0.12065 0.3048)
			(stroke
				(width 0.1)
				(type default)
			)
			(layer "B.Fab")
		)
		(fp_line
			(start 0.12065 0.3048)
			(end 0.67945 0.3048)
			(stroke
				(width 0.1)
				(type default)
			)
			(layer "B.Fab")
		)
		(fp_line
			(start 0.67945 -0.305054)
			(end 0.12065 -0.305054)
			(stroke
				(width 0.1)
				(type default)
			)
			(layer "B.Fab")
		)
		(fp_line
			(start 0.67945 0.3048)
			(end 0.67945 -0.305054)
			(stroke
				(width 0.1)
				(type default)
			)
			(layer "B.Fab")
		)
		(pad "1" smd circle
			(at 0.40005 0 180)
			(size 0 0)
			(layers "B.Cu" "B.Mask" "B.Paste")
			(net "SMB_HOST_3V3AUX_SCL")
		)
		(pad "2" smd circle
			(at -0.40005 0 180)
			(size 0 0)
			(layers "B.Cu" "B.Mask" "B.Paste")
			(net "SMB_HOST_3V3AUX_SCL_R4")
		)
	)
	(footprint ""
		(layer "B.Cu")
		(at 329.240388 -2.156206)
		(property "Reference" "J82"
			(at 4.361942 1.140206 270)
			(unlocked yes)
			(layer "B.SilkS")
			(effects
				(font
					(size 0.7874 0.5842)
					(thickness 0.1524)
				)
				(justify left mirror)
			)
		)
		(property "Value" ""
			(at 0 0 0)
			(layer "B.Fab")
			(effects
				(font
					(size 1.27 1.27)
				)
				(justify mirror)
			)
		)
		(duplicate_pad_numbers_are_jumpers no)
		(fp_line
			(start -1.2192 -2.1082)
			(end -1.2192 2.1082)
			(stroke
				(width 0.1524)
				(type default)
			)
			(layer "B.SilkS")
		)
		(fp_line
			(start -1.2192 2.1082)
			(end 1.2192 2.1082)
			(stroke
				(width 0.1524)
				(type default)
			)
			(layer "B.SilkS")
		)
		(fp_line
			(start 1.2192 -2.1082)
			(end -1.2192 -2.1082)
			(stroke
				(width 0.1524)
				(type default)
			)
			(layer "B.SilkS")
		)
		(fp_line
			(start 1.2192 2.1082)
			(end 1.2192 -2.1082)
			(stroke
				(width 0.1524)
				(type default)
			)
			(layer "B.SilkS")
		)
		(pad "" np_thru_hole circle
			(at -3.4671 -1.27 270)
			(size 1.0414 1.0414)
			(drill 1.0414)
			(layers "*.Cu" "*.Mask")
			(clearance 0.381)
			(thermal_gap 0.381)
		)
		(pad "" np_thru_hole circle
			(at -3.4671 1.27 270)
			(size 1.0414 1.0414)
			(drill 1.0414)
			(layers "*.Cu" "*.Mask")
			(clearance 0.381)
			(thermal_gap 0.381)
		)
		(pad "" np_thru_hole circle
			(at 2.8829 -1.27 270)
			(size 1.0414 1.0414)
			(drill 1.0414)
			(layers "*.Cu" "*.Mask")
			(clearance 0.381)
			(thermal_gap 0.381)
		)
		(pad "" np_thru_hole circle
			(at 2.8829 1.27 270)
			(size 1.0414 1.0414)
			(drill 1.0414)
			(layers "*.Cu" "*.Mask")
			(clearance 0.381)
			(thermal_gap 0.381)
		)
		(pad "1" smd rect
			(at -0.8255 -0.249936 270)
			(size 0.3048 0.508)
			(layers "B.Cu" "B.Mask" "B.Paste")
			(net "DELTA_L_85_10INCH_BOT_DN")
		)
		(pad "2" smd rect
			(at -0.8255 0.249936 270)
			(size 0.3048 0.508)
			(layers "B.Cu" "B.Mask" "B.Paste")
			(net "DELTA_L_85_10INCH_BOT_DP")
		)
		(pad "3" smd circle
			(at 0 0 180)
			(size 0 0)
			(layers "B.Cu" "B.Mask" "B.Paste")
			(net "DELTA_L_GND_1")
		)
		(zone
			(layers "F.Cu" "B.Cu" "In1.Cu" "In2.Cu" "In3.Cu" "In4.Cu" "In5.Cu" "In6.Cu"
				"In7.Cu" "In8.Cu" "In9.Cu" "In10.Cu" "In11.Cu" "In12.Cu" "In13.Cu" "In14.Cu"
				"In15.Cu" "In16.Cu"
			)
			(hatch none 0.5)
			(connect_pads
				(clearance 0)
			)
			(min_thickness 0.25)
			(keepout
				(tracks not_allowed)
				(vias allowed)
				(pads allowed)
				(copperpour not_allowed)
				(footprints allowed)
			)
			(placement
				(enabled no)
				(sheetname "")
			)
			(fill
				(thermal_gap 0.5)
				(thermal_bridge_width 0.5)
				(island_removal_mode 0)
			)
			(polygon
				(pts
					(arc
						(start 326.700388 -3.426206)
						(mid 324.846188 -3.426206)
						(end 326.700388 -3.426206)
					)
				)
			)
		)
		(zone
			(layers "F.Cu" "B.Cu" "In1.Cu" "In2.Cu" "In3.Cu" "In4.Cu" "In5.Cu" "In6.Cu"
				"In7.Cu" "In8.Cu" "In9.Cu" "In10.Cu" "In11.Cu" "In12.Cu" "In13.Cu" "In14.Cu"
				"In15.Cu" "In16.Cu"
			)
			(hatch none 0.5)
			(connect_pads
				(clearance 0)
			)
			(min_thickness 0.25)
			(keepout
				(tracks not_allowed)
				(vias allowed)
				(pads allowed)
				(copperpour not_allowed)
				(footprints allowed)
			)
			(placement
				(enabled no)
				(sheetname "")
			)
			(fill
				(thermal_gap 0.5)
				(thermal_bridge_width 0.5)
				(island_removal_mode 0)
			)
			(polygon
				(pts
					(arc
						(start 326.700388 -0.886206)
						(mid 324.846188 -0.886206)
						(end 326.700388 -0.886206)
					)
				)
			)
		)
		(zone
			(layers "F.Cu" "B.Cu" "In1.Cu" "In2.Cu" "In3.Cu" "In4.Cu" "In5.Cu" "In6.Cu"
				"In7.Cu" "In8.Cu" "In9.Cu" "In10.Cu" "In11.Cu" "In12.Cu" "In13.Cu" "In14.Cu"
				"In15.Cu" "In16.Cu"
			)
			(hatch none 0.5)
			(connect_pads
				(clearance 0)
			)
			(min_thickness 0.25)
			(keepout
				(tracks not_allowed)
				(vias allowed)
				(pads allowed)
				(copperpour not_allowed)
				(footprints allowed)
			)
			(placement
				(enabled no)
				(sheetname "")
			)
			(fill
				(thermal_gap 0.5)
				(thermal_bridge_width 0.5)
				(island_removal_mode 0)
			)
			(polygon
				(pts
					(arc
						(start 333.050388 -3.426206)
						(mid 331.196188 -3.426206)
						(end 333.050388 -3.426206)
					)
				)
			)
		)
		(zone
			(layers "F.Cu" "B.Cu" "In1.Cu" "In2.Cu" "In3.Cu" "In4.Cu" "In5.Cu" "In6.Cu"
				"In7.Cu" "In8.Cu" "In9.Cu" "In10.Cu" "In11.Cu" "In12.Cu" "In13.Cu" "In14.Cu"
				"In15.Cu" "In16.Cu"
			)
			(hatch none 0.5)
			(connect_pads
				(clearance 0)
			)
			(min_thickness 0.25)
			(keepout
				(tracks not_allowed)
				(vias allowed)
				(pads allowed)
				(copperpour not_allowed)
				(footprints allowed)
			)
			(placement
				(enabled no)
				(sheetname "")
			)
			(fill
				(thermal_gap 0.5)
				(thermal_bridge_width 0.5)
				(island_removal_mode 0)
			)
			(polygon
				(pts
					(arc
						(start 333.050388 -0.886206)
						(mid 331.196188 -0.886206)
						(end 333.050388 -0.886206)
					)
				)
			)
		)
		(zone
			(layer "B.Cu")
			(hatch none 0.5)
			(connect_pads
				(clearance 0)
			)
			(min_thickness 0.25)
			(keepout
				(tracks not_allowed)
				(vias allowed)
				(pads allowed)
				(copperpour not_allowed)
				(footprints allowed)
			)
			(placement
				(enabled no)
				(sheetname "")
			)
			(fill
				(thermal_gap 0.5)
				(thermal_bridge_width 0.5)
				(island_removal_mode 0)
			)
			(polygon
				(pts
					(xy 328.122788 -2.704846) (xy 328.122788 -2.609342) (xy 328.719688 -2.609342) (xy 328.719688 -2.202942)
					(xy 328.122788 -2.202942) (xy 328.122788 -2.10947) (xy 328.719688 -2.10947) (xy 328.719688 -1.70307)
					(xy 328.122788 -1.70307) (xy 328.122788 -1.607566) (xy 328.821288 -1.607566) (xy 328.821288 -2.704846)
				)
			)
		)
	)
	(footprint ""
		(layer "B.Cu")
		(at 48.506634 -357.92918 -90)
		(property "Reference" "PR1332"
			(at 0 0 90)
			(layer "B.SilkS")
			(hide yes)
			(effects
				(font
					(size 1.27 1.27)
				)
				(justify mirror)
			)
		)
		(property "Value" ""
			(at 0 0 90)
			(layer "B.Fab")
			(effects
				(font
					(size 1.27 1.27)
				)
				(justify mirror)
			)
		)
		(duplicate_pad_numbers_are_jumpers no)
		(fp_line
			(start -0.7874 0.4064)
			(end 0.7874 0.4064)
			(stroke
				(width 0.1524)
				(type default)
			)
			(layer "B.SilkS")
		)
		(fp_line
			(start 0.7874 0.4064)
			(end 0.7874 -0.4064)
			(stroke
				(width 0.1524)
				(type default)
			)
			(layer "B.SilkS")
		)
		(fp_line
			(start -0.7874 -0.4064)
			(end -0.7874 0.4064)
			(stroke
				(width 0.1524)
				(type default)
			)
			(layer "B.SilkS")
		)
		(fp_line
			(start 0.7874 -0.4064)
			(end -0.7874 -0.4064)
			(stroke
				(width 0.1524)
				(type default)
			)
			(layer "B.SilkS")
		)
		(fp_line
			(start -0.67945 0.3048)
			(end -0.120396 0.3048)
			(stroke
				(width 0.1)
				(type default)
			)
			(layer "B.Fab")
		)
		(fp_line
			(start -0.120396 0.3048)
			(end -0.120396 0.2794)
			(stroke
				(width 0.1)
				(type default)
			)
			(layer "B.Fab")
		)
		(fp_line
			(start 0.12065 0.3048)
			(end 0.67945 0.3048)
			(stroke
				(width 0.1)
				(type default)
			)
			(layer "B.Fab")
		)
		(fp_line
			(start 0.67945 0.3048)
			(end 0.67945 -0.305054)
			(stroke
				(width 0.1)
				(type default)
			)
			(layer "B.Fab")
		)
		(fp_line
			(start -0.120396 0.2794)
			(end 0.12065 0.2794)
			(stroke
				(width 0.1)
				(type default)
			)
			(layer "B.Fab")
		)
		(fp_line
			(start 0.12065 0.2794)
			(end 0.12065 0.3048)
			(stroke
				(width 0.1)
				(type default)
			)
			(layer "B.Fab")
		)
		(fp_line
			(start -0.12065 -0.2794)
			(end -0.12065 -0.3048)
			(stroke
				(width 0.1)
				(type default)
			)
			(layer "B.Fab")
		)
		(fp_line
			(start 0.12065 -0.2794)
			(end -0.12065 -0.2794)
			(stroke
				(width 0.1)
				(type default)
			)
			(layer "B.Fab")
		)
		(fp_line
			(start -0.67945 -0.3048)
			(end -0.67945 0.3048)
			(stroke
				(width 0.1)
				(type default)
			)
			(layer "B.Fab")
		)
		(fp_line
			(start -0.12065 -0.3048)
			(end -0.67945 -0.3048)
			(stroke
				(width 0.1)
				(type default)
			)
			(layer "B.Fab")
		)
		(fp_line
			(start 0.12065 -0.305054)
			(end 0.12065 -0.2794)
			(stroke
				(width 0.1)
				(type default)
			)
			(layer "B.Fab")
		)
		(fp_line
			(start 0.67945 -0.305054)
			(end 0.12065 -0.305054)
			(stroke
				(width 0.1)
				(type default)
			)
			(layer "B.Fab")
		)
		(pad "1" smd circle
			(at 0.40005 0 90)
			(size 0 0)
			(layers "B.Cu" "B.Mask" "B.Paste")
			(net "PVCCFA_EHV_FIVRA_CPU1_VOS2")
		)
		(pad "2" smd circle
			(at -0.40005 0 90)
			(size 0 0)
			(layers "B.Cu" "B.Mask" "B.Paste")
			(net "PVCCFA_EHV_FIVRA_CPU1")
		)
	)
	(footprint ""
		(layer "B.Cu")
		(at 159.279082 -37.323268)
		(property "Reference" "C2316"
			(at 0 0 0)
			(layer "B.SilkS")
			(hide yes)
			(effects
				(font
					(size 1.27 1.27)
				)
				(justify mirror)
			)
		)
		(property "Value" ""
			(at 0 0 0)
			(layer "B.Fab")
			(effects
				(font
					(size 1.27 1.27)
				)
				(justify mirror)
			)
		)
		(duplicate_pad_numbers_are_jumpers no)
		(fp_line
			(start -0.7874 -0.4064)
			(end -0.7874 0.4064)
			(stroke
				(width 0.1524)
				(type default)
			)
			(layer "B.SilkS")
		)
		(fp_line
			(start -0.7874 0.4064)
			(end 0.7874 0.4064)
			(stroke
				(width 0.1524)
				(type default)
			)
			(layer "B.SilkS")
		)
		(fp_line
			(start 0.7874 -0.4064)
			(end -0.7874 -0.4064)
			(stroke
				(width 0.1524)
				(type default)
			)
			(layer "B.SilkS")
		)
		(fp_line
			(start 0.7874 0.4064)
			(end 0.7874 -0.4064)
			(stroke
				(width 0.1524)
				(type default)
			)
			(layer "B.SilkS")
		)
		(fp_line
			(start -0.67945 -0.3048)
			(end -0.67945 0.3048)
			(stroke
				(width 0.1)
				(type default)
			)
			(layer "B.Fab")
		)
		(fp_line
			(start -0.67945 0.3048)
			(end -0.120396 0.3048)
			(stroke
				(width 0.1)
				(type default)
			)
			(layer "B.Fab")
		)
		(fp_line
			(start -0.12065 -0.3048)
			(end -0.67945 -0.3048)
			(stroke
				(width 0.1)
				(type default)
			)
			(layer "B.Fab")
		)
		(fp_line
			(start -0.12065 -0.2794)
			(end -0.12065 -0.3048)
			(stroke
				(width 0.1)
				(type default)
			)
			(layer "B.Fab")
		)
		(fp_line
			(start -0.120396 0.2794)
			(end 0.12065 0.2794)
			(stroke
				(width 0.1)
				(type default)
			)
			(layer "B.Fab")
		)
		(fp_line
			(start -0.120396 0.3048)
			(end -0.120396 0.2794)
			(stroke
				(width 0.1)
				(type default)
			)
			(layer "B.Fab")
		)
		(fp_line
			(start 0.12065 -0.305054)
			(end 0.12065 -0.2794)
			(stroke
				(width 0.1)
				(type default)
			)
			(layer "B.Fab")
		)
		(fp_line
			(start 0.12065 -0.2794)
			(end -0.12065 -0.2794)
			(stroke
				(width 0.1)
				(type default)
			)
			(layer "B.Fab")
		)
		(fp_line
			(start 0.12065 0.2794)
			(end 0.12065 0.3048)
			(stroke
				(width 0.1)
				(type default)
			)
			(layer "B.Fab")
		)
		(fp_line
			(start 0.12065 0.3048)
			(end 0.67945 0.3048)
			(stroke
				(width 0.1)
				(type default)
			)
			(layer "B.Fab")
		)
		(fp_line
			(start 0.67945 -0.305054)
			(end 0.12065 -0.305054)
			(stroke
				(width 0.1)
				(type default)
			)
			(layer "B.Fab")
		)
		(fp_line
			(start 0.67945 0.3048)
			(end 0.67945 -0.305054)
			(stroke
				(width 0.1)
				(type default)
			)
			(layer "B.Fab")
		)
		(pad "1" smd circle
			(at 0.40005 0 180)
			(size 0 0)
			(layers "B.Cu" "B.Mask" "B.Paste")
			(net "P3V3_AUX_USB_HUB_2")
		)
		(pad "2" smd circle
			(at -0.40005 0 180)
			(size 0 0)
			(layers "B.Cu" "B.Mask" "B.Paste")
			(net "GND")
		)
	)
	(footprint ""
		(layer "B.Cu")
		(at 337.903312 -187.996068 90)
		(property "Reference" "R741"
			(at 0 0 90)
			(layer "B.SilkS")
			(hide yes)
			(effects
				(font
					(size 1.27 1.27)
				)
				(justify mirror)
			)
		)
		(property "Value" ""
			(at 0 0 90)
			(layer "B.Fab")
			(effects
				(font
					(size 1.27 1.27)
				)
				(justify mirror)
			)
		)
		(duplicate_pad_numbers_are_jumpers no)
		(fp_line
			(start 0.7874 -0.4064)
			(end -0.7874 -0.4064)
			(stroke
				(width 0.1524)
				(type default)
			)
			(layer "B.SilkS")
		)
		(fp_line
			(start -0.7874 -0.4064)
			(end -0.7874 0.4064)
			(stroke
				(width 0.1524)
				(type default)
			)
			(layer "B.SilkS")
		)
		(fp_line
			(start 0.7874 0.4064)
			(end 0.7874 -0.4064)
			(stroke
				(width 0.1524)
				(type default)
			)
			(layer "B.SilkS")
		)
		(fp_line
			(start -0.7874 0.4064)
			(end 0.7874 0.4064)
			(stroke
				(width 0.1524)
				(type default)
			)
			(layer "B.SilkS")
		)
		(fp_line
			(start 0.67945 -0.305054)
			(end 0.12065 -0.305054)
			(stroke
				(width 0.1)
				(type default)
			)
			(layer "B.Fab")
		)
		(fp_line
			(start 0.12065 -0.305054)
			(end 0.12065 -0.2794)
			(stroke
				(width 0.1)
				(type default)
			)
			(layer "B.Fab")
		)
		(fp_line
			(start -0.12065 -0.3048)
			(end -0.67945 -0.3048)
			(stroke
				(width 0.1)
				(type default)
			)
			(layer "B.Fab")
		)
		(fp_line
			(start -0.67945 -0.3048)
			(end -0.67945 0.3048)
			(stroke
				(width 0.1)
				(type default)
			)
			(layer "B.Fab")
		)
		(fp_line
			(start 0.12065 -0.2794)
			(end -0.12065 -0.2794)
			(stroke
				(width 0.1)
				(type default)
			)
			(layer "B.Fab")
		)
		(fp_line
			(start -0.12065 -0.2794)
			(end -0.12065 -0.3048)
			(stroke
				(width 0.1)
				(type default)
			)
			(layer "B.Fab")
		)
		(fp_line
			(start 0.12065 0.2794)
			(end 0.12065 0.3048)
			(stroke
				(width 0.1)
				(type default)
			)
			(layer "B.Fab")
		)
		(fp_line
			(start -0.120396 0.2794)
			(end 0.12065 0.2794)
			(stroke
				(width 0.1)
				(type default)
			)
			(layer "B.Fab")
		)
		(fp_line
			(start 0.67945 0.3048)
			(end 0.67945 -0.305054)
			(stroke
				(width 0.1)
				(type default)
			)
			(layer "B.Fab")
		)
		(fp_line
			(start 0.12065 0.3048)
			(end 0.67945 0.3048)
			(stroke
				(width 0.1)
				(type default)
			)
			(layer "B.Fab")
		)
		(fp_line
			(start -0.120396 0.3048)
			(end -0.120396 0.2794)
			(stroke
				(width 0.1)
				(type default)
			)
			(layer "B.Fab")
		)
		(fp_line
			(start -0.67945 0.3048)
			(end -0.120396 0.3048)
			(stroke
				(width 0.1)
				(type default)
			)
			(layer "B.Fab")
		)
		(pad "1" smd circle
			(at 0.40005 0 270)
			(size 0 0)
			(layers "B.Cu" "B.Mask" "B.Paste")
			(net "PVNN_TERM_CPU0")
		)
		(pad "2" smd circle
			(at -0.40005 0 270)
			(size 0 0)
			(layers "B.Cu" "B.Mask" "B.Paste")
			(net "JTAG_MUX_CPU0_GTL_TDI")
		)
	)
	(footprint ""
		(layer "B.Cu")
		(at 182.68188 -102.707948)
		(property "Reference" "C1941"
			(at 0 0 0)
			(layer "B.SilkS")
			(hide yes)
			(effects
				(font
					(size 1.27 1.27)
				)
				(justify mirror)
			)
		)
		(property "Value" ""
			(at 0 0 0)
			(layer "B.Fab")
			(effects
				(font
					(size 1.27 1.27)
				)
				(justify mirror)
			)
		)
		(duplicate_pad_numbers_are_jumpers no)
		(fp_line
			(start -0.7874 -0.4064)
			(end -0.7874 0.4064)
			(stroke
				(width 0.1524)
				(type default)
			)
			(layer "B.SilkS")
		)
		(fp_line
			(start -0.7874 0.4064)
			(end 0.7874 0.4064)
			(stroke
				(width 0.1524)
				(type default)
			)
			(layer "B.SilkS")
		)
		(fp_line
			(start 0.7874 -0.4064)
			(end -0.7874 -0.4064)
			(stroke
				(width 0.1524)
				(type default)
			)
			(layer "B.SilkS")
		)
		(fp_line
			(start 0.7874 0.4064)
			(end 0.7874 -0.4064)
			(stroke
				(width 0.1524)
				(type default)
			)
			(layer "B.SilkS")
		)
		(fp_line
			(start -0.67945 -0.3048)
			(end -0.67945 0.3048)
			(stroke
				(width 0.1)
				(type default)
			)
			(layer "B.Fab")
		)
		(fp_line
			(start -0.67945 0.3048)
			(end -0.120396 0.3048)
			(stroke
				(width 0.1)
				(type default)
			)
			(layer "B.Fab")
		)
		(fp_line
			(start -0.12065 -0.3048)
			(end -0.67945 -0.3048)
			(stroke
				(width 0.1)
				(type default)
			)
			(layer "B.Fab")
		)
		(fp_line
			(start -0.12065 -0.2794)
			(end -0.12065 -0.3048)
			(stroke
				(width 0.1)
				(type default)
			)
			(layer "B.Fab")
		)
		(fp_line
			(start -0.120396 0.2794)
			(end 0.12065 0.2794)
			(stroke
				(width 0.1)
				(type default)
			)
			(layer "B.Fab")
		)
		(fp_line
			(start -0.120396 0.3048)
			(end -0.120396 0.2794)
			(stroke
				(width 0.1)
				(type default)
			)
			(layer "B.Fab")
		)
		(fp_line
			(start 0.12065 -0.305054)
			(end 0.12065 -0.2794)
			(stroke
				(width 0.1)
				(type default)
			)
			(layer "B.Fab")
		)
		(fp_line
			(start 0.12065 -0.2794)
			(end -0.12065 -0.2794)
			(stroke
				(width 0.1)
				(type default)
			)
			(layer "B.Fab")
		)
		(fp_line
			(start 0.12065 0.2794)
			(end 0.12065 0.3048)
			(stroke
				(width 0.1)
				(type default)
			)
			(layer "B.Fab")
		)
		(fp_line
			(start 0.12065 0.3048)
			(end 0.67945 0.3048)
			(stroke
				(width 0.1)
				(type default)
			)
			(layer "B.Fab")
		)
		(fp_line
			(start 0.67945 -0.305054)
			(end 0.12065 -0.305054)
			(stroke
				(width 0.1)
				(type default)
			)
			(layer "B.Fab")
		)
		(fp_line
			(start 0.67945 0.3048)
			(end 0.67945 -0.305054)
			(stroke
				(width 0.1)
				(type default)
			)
			(layer "B.Fab")
		)
		(pad "1" smd circle
			(at 0.40005 0 180)
			(size 0 0)
			(layers "B.Cu" "B.Mask" "B.Paste")
			(net "P3V3_AUX_FPGA_VCCIO3")
		)
		(pad "2" smd circle
			(at -0.40005 0 180)
			(size 0 0)
			(layers "B.Cu" "B.Mask" "B.Paste")
			(net "GND")
		)
	)
	(footprint ""
		(layer "B.Cu")
		(at 108.845604 -296.05478 180)
		(property "Reference" "C346"
			(at 0 0 0)
			(layer "B.SilkS")
			(hide yes)
			(effects
				(font
					(size 1.27 1.27)
				)
				(justify mirror)
			)
		)
		(property "Value" ""
			(at 0 0 0)
			(layer "B.Fab")
			(effects
				(font
					(size 1.27 1.27)
				)
				(justify mirror)
			)
		)
		(duplicate_pad_numbers_are_jumpers no)
		(fp_line
			(start 1.524 0.762)
			(end 1.524 -0.762)
			(stroke
				(width 0.1524)
				(type default)
			)
			(layer "B.SilkS")
		)
		(fp_line
			(start 1.524 -0.762)
			(end -1.524 -0.762)
			(stroke
				(width 0.1524)
				(type default)
			)
			(layer "B.SilkS")
		)
		(fp_line
			(start -1.524 0.762)
			(end 1.524 0.762)
			(stroke
				(width 0.1524)
				(type default)
			)
			(layer "B.SilkS")
		)
		(fp_line
			(start -1.524 -0.762)
			(end -1.524 0.762)
			(stroke
				(width 0.1524)
				(type default)
			)
			(layer "B.SilkS")
		)
		(fp_line
			(start 1.1049 0.724916)
			(end -1.1049 0.724916)
			(stroke
				(width 0.1)
				(type default)
			)
			(layer "B.Fab")
		)
		(fp_line
			(start 1.1049 -0.724916)
			(end 1.1049 0.724916)
			(stroke
				(width 0.1)
				(type default)
			)
			(layer "B.Fab")
		)
		(fp_line
			(start -1.1049 0.724916)
			(end -1.1049 -0.724916)
			(stroke
				(width 0.1)
				(type default)
			)
			(layer "B.Fab")
		)
		(fp_line
			(start -1.1049 -0.724916)
			(end 1.1049 -0.724916)
			(stroke
				(width 0.1)
				(type default)
			)
			(layer "B.Fab")
		)
		(pad "1" smd rect
			(at 0.889 0 180)
			(size 1.016 1.27)
			(layers "B.Cu" "B.Mask" "B.Paste")
			(net "PVCCIN_CPU1")
		)
		(pad "2" smd rect
			(at -0.889 0 180)
			(size 1.016 1.27)
			(layers "B.Cu" "B.Mask" "B.Paste")
			(net "GND")
		)
	)
	(footprint ""
		(layer "B.Cu")
		(at 216.18448 -54.955948)
		(property "Reference" "C2069"
			(at 0 0 0)
			(layer "B.SilkS")
			(hide yes)
			(effects
				(font
					(size 1.27 1.27)
				)
				(justify mirror)
			)
		)
		(property "Value" ""
			(at 0 0 0)
			(layer "B.Fab")
			(effects
				(font
					(size 1.27 1.27)
				)
				(justify mirror)
			)
		)
		(duplicate_pad_numbers_are_jumpers no)
		(fp_line
			(start -0.7874 -0.4064)
			(end -0.7874 0.4064)
			(stroke
				(width 0.1524)
				(type default)
			)
			(layer "B.SilkS")
		)
		(fp_line
			(start -0.7874 0.4064)
			(end 0.7874 0.4064)
			(stroke
				(width 0.1524)
				(type default)
			)
			(layer "B.SilkS")
		)
		(fp_line
			(start 0.7874 -0.4064)
			(end -0.7874 -0.4064)
			(stroke
				(width 0.1524)
				(type default)
			)
			(layer "B.SilkS")
		)
		(fp_line
			(start 0.7874 0.4064)
			(end 0.7874 -0.4064)
			(stroke
				(width 0.1524)
				(type default)
			)
			(layer "B.SilkS")
		)
		(fp_line
			(start -0.67945 -0.3048)
			(end -0.67945 0.3048)
			(stroke
				(width 0.1)
				(type default)
			)
			(layer "B.Fab")
		)
		(fp_line
			(start -0.67945 0.3048)
			(end -0.120396 0.3048)
			(stroke
				(width 0.1)
				(type default)
			)
			(layer "B.Fab")
		)
		(fp_line
			(start -0.12065 -0.3048)
			(end -0.67945 -0.3048)
			(stroke
				(width 0.1)
				(type default)
			)
			(layer "B.Fab")
		)
		(fp_line
			(start -0.12065 -0.2794)
			(end -0.12065 -0.3048)
			(stroke
				(width 0.1)
				(type default)
			)
			(layer "B.Fab")
		)
		(fp_line
			(start -0.120396 0.2794)
			(end 0.12065 0.2794)
			(stroke
				(width 0.1)
				(type default)
			)
			(layer "B.Fab")
		)
		(fp_line
			(start -0.120396 0.3048)
			(end -0.120396 0.2794)
			(stroke
				(width 0.1)
				(type default)
			)
			(layer "B.Fab")
		)
		(fp_line
			(start 0.12065 -0.305054)
			(end 0.12065 -0.2794)
			(stroke
				(width 0.1)
				(type default)
			)
			(layer "B.Fab")
		)
		(fp_line
			(start 0.12065 -0.2794)
			(end -0.12065 -0.2794)
			(stroke
				(width 0.1)
				(type default)
			)
			(layer "B.Fab")
		)
		(fp_line
			(start 0.12065 0.2794)
			(end 0.12065 0.3048)
			(stroke
				(width 0.1)
				(type default)
			)
			(layer "B.Fab")
		)
		(fp_line
			(start 0.12065 0.3048)
			(end 0.67945 0.3048)
			(stroke
				(width 0.1)
				(type default)
			)
			(layer "B.Fab")
		)
		(fp_line
			(start 0.67945 -0.305054)
			(end 0.12065 -0.305054)
			(stroke
				(width 0.1)
				(type default)
			)
			(layer "B.Fab")
		)
		(fp_line
			(start 0.67945 0.3048)
			(end 0.67945 -0.305054)
			(stroke
				(width 0.1)
				(type default)
			)
			(layer "B.Fab")
		)
		(pad "1" smd circle
			(at 0.40005 0 180)
			(size 0 0)
			(layers "B.Cu" "B.Mask" "B.Paste")
			(net "P3V3_E1S_0_R")
		)
		(pad "2" smd circle
			(at -0.40005 0 180)
			(size 0 0)
			(layers "B.Cu" "B.Mask" "B.Paste")
			(net "GND")
		)
	)
	(footprint ""
		(layer "B.Cu")
		(at 324.332854 -66.83375 -90)
		(property "Reference" "C1201"
			(at 0 0 90)
			(layer "B.SilkS")
			(hide yes)
			(effects
				(font
					(size 1.27 1.27)
				)
				(justify mirror)
			)
		)
		(property "Value" ""
			(at 0 0 90)
			(layer "B.Fab")
			(effects
				(font
					(size 1.27 1.27)
				)
				(justify mirror)
			)
		)
		(duplicate_pad_numbers_are_jumpers no)
		(fp_line
			(start -1.2954 0.5842)
			(end 1.2954 0.5842)
			(stroke
				(width 0.1524)
				(type default)
			)
			(layer "B.SilkS")
		)
		(fp_line
			(start 1.2954 0.5842)
			(end 1.2954 -0.5842)
			(stroke
				(width 0.1524)
				(type default)
			)
			(layer "B.SilkS")
		)
		(fp_line
			(start -1.2954 -0.5842)
			(end -1.2954 0.5842)
			(stroke
				(width 0.1524)
				(type default)
			)
			(layer "B.SilkS")
		)
		(fp_line
			(start 0 -0.5842)
			(end 0 0.5842)
			(stroke
				(width 0.1524)
				(type default)
			)
			(layer "B.SilkS")
		)
		(fp_line
			(start 1.2954 -0.5842)
			(end -1.2954 -0.5842)
			(stroke
				(width 0.1524)
				(type default)
			)
			(layer "B.SilkS")
		)
		(fp_line
			(start -0.8636 0.4572)
			(end 0.8636 0.4572)
			(stroke
				(width 0.1)
				(type default)
			)
			(layer "B.Fab")
		)
		(fp_line
			(start 0.8636 0.4572)
			(end 0.8636 0.4064)
			(stroke
				(width 0.1)
				(type default)
			)
			(layer "B.Fab")
		)
		(fp_line
			(start -1.1938 0.4064)
			(end -0.8636 0.4064)
			(stroke
				(width 0.1)
				(type default)
			)
			(layer "B.Fab")
		)
		(fp_line
			(start -0.8636 0.4064)
			(end -0.8636 0.4572)
			(stroke
				(width 0.1)
				(type default)
			)
			(layer "B.Fab")
		)
		(fp_line
			(start 0.8636 0.4064)
			(end 1.1938 0.4064)
			(stroke
				(width 0.1)
				(type default)
			)
			(layer "B.Fab")
		)
		(fp_line
			(start 1.1938 0.4064)
			(end 1.1938 -0.4064)
			(stroke
				(width 0.1)
				(type default)
			)
			(layer "B.Fab")
		)
		(fp_line
			(start -1.1938 -0.4064)
			(end -1.1938 0.4064)
			(stroke
				(width 0.1)
				(type default)
			)
			(layer "B.Fab")
		)
		(fp_line
			(start -0.8636 -0.4064)
			(end -1.1938 -0.4064)
			(stroke
				(width 0.1)
				(type default)
			)
			(layer "B.Fab")
		)
		(fp_line
			(start 0.8636 -0.4064)
			(end 0.8636 -0.4572)
			(stroke
				(width 0.1)
				(type default)
			)
			(layer "B.Fab")
		)
		(fp_line
			(start 1.1938 -0.4064)
			(end 0.8636 -0.4064)
			(stroke
				(width 0.1)
				(type default)
			)
			(layer "B.Fab")
		)
		(fp_line
			(start -0.8636 -0.4572)
			(end -0.8636 -0.4064)
			(stroke
				(width 0.1)
				(type default)
			)
			(layer "B.Fab")
		)
		(fp_line
			(start 0.8636 -0.4572)
			(end -0.8636 -0.4572)
			(stroke
				(width 0.1)
				(type default)
			)
			(layer "B.Fab")
		)
		(pad "1" smd rect
			(at 0.7366 0 180)
			(size 0.7112 0.8128)
			(layers "B.Cu" "B.Mask" "B.Paste")
			(net "P3V3_AUX")
		)
		(pad "2" smd rect
			(at -0.7366 0 180)
			(size 0.7112 0.8128)
			(layers "B.Cu" "B.Mask" "B.Paste")
			(net "GND")
		)
	)
	(footprint ""
		(layer "B.Cu")
		(at 348.2467 -359.788714 180)
		(property "Reference" "R2379"
			(at 0 0 0)
			(layer "B.SilkS")
			(hide yes)
			(effects
				(font
					(size 1.27 1.27)
				)
				(justify mirror)
			)
		)
		(property "Value" ""
			(at 0 0 0)
			(layer "B.Fab")
			(effects
				(font
					(size 1.27 1.27)
				)
				(justify mirror)
			)
		)
		(duplicate_pad_numbers_are_jumpers no)
		(fp_line
			(start 0.7874 0.4064)
			(end 0.7874 -0.4064)
			(stroke
				(width 0.1524)
				(type default)
			)
			(layer "B.SilkS")
		)
		(fp_line
			(start 0.7874 -0.4064)
			(end -0.7874 -0.4064)
			(stroke
				(width 0.1524)
				(type default)
			)
			(layer "B.SilkS")
		)
		(fp_line
			(start -0.7874 0.4064)
			(end 0.7874 0.4064)
			(stroke
				(width 0.1524)
				(type default)
			)
			(layer "B.SilkS")
		)
		(fp_line
			(start -0.7874 -0.4064)
			(end -0.7874 0.4064)
			(stroke
				(width 0.1524)
				(type default)
			)
			(layer "B.SilkS")
		)
		(fp_line
			(start 0.67945 0.3048)
			(end 0.67945 -0.305054)
			(stroke
				(width 0.1)
				(type default)
			)
			(layer "B.Fab")
		)
		(fp_line
			(start 0.67945 -0.305054)
			(end 0.12065 -0.305054)
			(stroke
				(width 0.1)
				(type default)
			)
			(layer "B.Fab")
		)
		(fp_line
			(start 0.12065 0.3048)
			(end 0.67945 0.3048)
			(stroke
				(width 0.1)
				(type default)
			)
			(layer "B.Fab")
		)
		(fp_line
			(start 0.12065 0.2794)
			(end 0.12065 0.3048)
			(stroke
				(width 0.1)
				(type default)
			)
			(layer "B.Fab")
		)
		(fp_line
			(start 0.12065 -0.2794)
			(end -0.12065 -0.2794)
			(stroke
				(width 0.1)
				(type default)
			)
			(layer "B.Fab")
		)
		(fp_line
			(start 0.12065 -0.305054)
			(end 0.12065 -0.2794)
			(stroke
				(width 0.1)
				(type default)
			)
			(layer "B.Fab")
		)
		(fp_line
			(start -0.120396 0.3048)
			(end -0.120396 0.2794)
			(stroke
				(width 0.1)
				(type default)
			)
			(layer "B.Fab")
		)
		(fp_line
			(start -0.120396 0.2794)
			(end 0.12065 0.2794)
			(stroke
				(width 0.1)
				(type default)
			)
			(layer "B.Fab")
		)
		(fp_line
			(start -0.12065 -0.2794)
			(end -0.12065 -0.3048)
			(stroke
				(width 0.1)
				(type default)
			)
			(layer "B.Fab")
		)
		(fp_line
			(start -0.12065 -0.3048)
			(end -0.67945 -0.3048)
			(stroke
				(width 0.1)
				(type default)
			)
			(layer "B.Fab")
		)
		(fp_line
			(start -0.67945 0.3048)
			(end -0.120396 0.3048)
			(stroke
				(width 0.1)
				(type default)
			)
			(layer "B.Fab")
		)
		(fp_line
			(start -0.67945 -0.3048)
			(end -0.67945 0.3048)
			(stroke
				(width 0.1)
				(type default)
			)
			(layer "B.Fab")
		)
		(pad "1" smd circle
			(at 0.40005 0)
			(size 0 0)
			(layers "B.Cu" "B.Mask" "B.Paste")
			(net "PWRGD_PVCCFA_EHV_FIVRA_CPU0")
		)
		(pad "2" smd circle
			(at -0.40005 0)
			(size 0 0)
			(layers "B.Cu" "B.Mask" "B.Paste")
			(net "PWRGD_PVCCFA_EHV_FIVRA_CPU0_R")
		)
	)
	(footprint ""
		(layer "B.Cu")
		(at 456.24496 -32.250888)
		(property "Reference" ""
			(at 0 0 0)
			(layer "B.SilkS")
			(hide yes)
			(effects
				(font
					(size 1.27 1.27)
				)
				(justify mirror)
			)
		)
		(property "Value" ""
			(at 0 0 0)
			(layer "B.Fab")
			(effects
				(font
					(size 1.27 1.27)
				)
				(justify mirror)
			)
		)
		(duplicate_pad_numbers_are_jumpers no)
		(pad "1" smd circle
			(at 0 0 180)
			(size 0.9906 0.9906)
			(layers "B.Cu" "B.Mask" "B.Paste")
			(net "Net_292")
		)
		(zone
			(layer "B.Cu")
			(hatch none 0.5)
			(connect_pads
				(clearance 0)
			)
			(min_thickness 0.25)
			(keepout
				(tracks not_allowed)
				(vias allowed)
				(pads allowed)
				(copperpour not_allowed)
				(footprints allowed)
			)
			(placement
				(enabled no)
				(sheetname "")
			)
			(fill
				(thermal_gap 0.5)
				(thermal_bridge_width 0.5)
				(island_removal_mode 0)
			)
			(polygon
				(pts
					(arc
						(start 457.87056 -32.250888)
						(mid 454.61936 -32.250888)
						(end 457.87056 -32.250888)
					)
				)
			)
		)
	)
	(footprint ""
		(layer "B.Cu")
		(at 107.457494 -241.21872 90)
		(property "Reference" "C315"
			(at 0 0 90)
			(layer "B.SilkS")
			(hide yes)
			(effects
				(font
					(size 1.27 1.27)
				)
				(justify mirror)
			)
		)
		(property "Value" ""
			(at 0 0 90)
			(layer "B.Fab")
			(effects
				(font
					(size 1.27 1.27)
				)
				(justify mirror)
			)
		)
		(duplicate_pad_numbers_are_jumpers no)
		(fp_line
			(start 1.524 -0.762)
			(end -1.524 -0.762)
			(stroke
				(width 0.1524)
				(type default)
			)
			(layer "B.SilkS")
		)
		(fp_line
			(start -1.524 -0.762)
			(end -1.524 0.762)
			(stroke
				(width 0.1524)
				(type default)
			)
			(layer "B.SilkS")
		)
		(fp_line
			(start 1.524 0.762)
			(end 1.524 -0.762)
			(stroke
				(width 0.1524)
				(type default)
			)
			(layer "B.SilkS")
		)
		(fp_line
			(start -1.524 0.762)
			(end 1.524 0.762)
			(stroke
				(width 0.1524)
				(type default)
			)
			(layer "B.SilkS")
		)
		(fp_line
			(start 1.1049 -0.724916)
			(end 1.1049 0.724916)
			(stroke
				(width 0.1)
				(type default)
			)
			(layer "B.Fab")
		)
		(fp_line
			(start -1.1049 -0.724916)
			(end 1.1049 -0.724916)
			(stroke
				(width 0.1)
				(type default)
			)
			(layer "B.Fab")
		)
		(fp_line
			(start 1.1049 0.724916)
			(end -1.1049 0.724916)
			(stroke
				(width 0.1)
				(type default)
			)
			(layer "B.Fab")
		)
		(fp_line
			(start -1.1049 0.724916)
			(end -1.1049 -0.724916)
			(stroke
				(width 0.1)
				(type default)
			)
			(layer "B.Fab")
		)
		(pad "1" smd rect
			(at 0.889 0 90)
			(size 1.016 1.27)
			(layers "B.Cu" "B.Mask" "B.Paste")
			(net "PVCCIN_CPU1")
		)
		(pad "2" smd rect
			(at -0.889 0 90)
			(size 1.016 1.27)
			(layers "B.Cu" "B.Mask" "B.Paste")
			(net "GND")
		)
	)
	(footprint ""
		(layer "B.Cu")
		(at 53.415946 -321.554856 -90)
		(property "Reference" "C52"
			(at 0 0 90)
			(layer "B.SilkS")
			(hide yes)
			(effects
				(font
					(size 1.27 1.27)
				)
				(justify mirror)
			)
		)
		(property "Value" ""
			(at 0 0 90)
			(layer "B.Fab")
			(effects
				(font
					(size 1.27 1.27)
				)
				(justify mirror)
			)
		)
		(duplicate_pad_numbers_are_jumpers no)
		(fp_line
			(start -1.524 0.762)
			(end 1.524 0.762)
			(stroke
				(width 0.1524)
				(type default)
			)
			(layer "B.SilkS")
		)
		(fp_line
			(start 1.524 0.762)
			(end 1.524 -0.762)
			(stroke
				(width 0.1524)
				(type default)
			)
			(layer "B.SilkS")
		)
		(fp_line
			(start -1.524 -0.762)
			(end -1.524 0.762)
			(stroke
				(width 0.1524)
				(type default)
			)
			(layer "B.SilkS")
		)
		(fp_line
			(start 1.524 -0.762)
			(end -1.524 -0.762)
			(stroke
				(width 0.1524)
				(type default)
			)
			(layer "B.SilkS")
		)
		(fp_line
			(start -1.1049 0.724916)
			(end -1.1049 -0.724916)
			(stroke
				(width 0.1)
				(type default)
			)
			(layer "B.Fab")
		)
		(fp_line
			(start 1.1049 0.724916)
			(end -1.1049 0.724916)
			(stroke
				(width 0.1)
				(type default)
			)
			(layer "B.Fab")
		)
		(fp_line
			(start -1.1049 -0.724916)
			(end 1.1049 -0.724916)
			(stroke
				(width 0.1)
				(type default)
			)
			(layer "B.Fab")
		)
		(fp_line
			(start 1.1049 -0.724916)
			(end 1.1049 0.724916)
			(stroke
				(width 0.1)
				(type default)
			)
			(layer "B.Fab")
		)
		(pad "1" smd rect
			(at 0.889 0 270)
			(size 1.016 1.27)
			(layers "B.Cu" "B.Mask" "B.Paste")
			(net "P12V_S3_AUX_CPU1_NVDIMM")
		)
		(pad "2" smd rect
			(at -0.889 0 270)
			(size 1.016 1.27)
			(layers "B.Cu" "B.Mask" "B.Paste")
			(net "GND")
		)
	)
	(footprint ""
		(layer "B.Cu")
		(at 258.384802 -106.819192 180)
		(property "Reference" "R1196"
			(at 0 0 0)
			(layer "B.SilkS")
			(hide yes)
			(effects
				(font
					(size 1.27 1.27)
				)
				(justify mirror)
			)
		)
		(property "Value" ""
			(at 0 0 0)
			(layer "B.Fab")
			(effects
				(font
					(size 1.27 1.27)
				)
				(justify mirror)
			)
		)
		(duplicate_pad_numbers_are_jumpers no)
		(fp_line
			(start 0.7874 0.4064)
			(end 0.7874 -0.4064)
			(stroke
				(width 0.1524)
				(type default)
			)
			(layer "B.SilkS")
		)
		(fp_line
			(start 0.7874 -0.4064)
			(end -0.7874 -0.4064)
			(stroke
				(width 0.1524)
				(type default)
			)
			(layer "B.SilkS")
		)
		(fp_line
			(start -0.7874 0.4064)
			(end 0.7874 0.4064)
			(stroke
				(width 0.1524)
				(type default)
			)
			(layer "B.SilkS")
		)
		(fp_line
			(start -0.7874 -0.4064)
			(end -0.7874 0.4064)
			(stroke
				(width 0.1524)
				(type default)
			)
			(layer "B.SilkS")
		)
		(fp_line
			(start 0.67945 0.3048)
			(end 0.67945 -0.305054)
			(stroke
				(width 0.1)
				(type default)
			)
			(layer "B.Fab")
		)
		(fp_line
			(start 0.67945 -0.305054)
			(end 0.12065 -0.305054)
			(stroke
				(width 0.1)
				(type default)
			)
			(layer "B.Fab")
		)
		(fp_line
			(start 0.12065 0.3048)
			(end 0.67945 0.3048)
			(stroke
				(width 0.1)
				(type default)
			)
			(layer "B.Fab")
		)
		(fp_line
			(start 0.12065 0.2794)
			(end 0.12065 0.3048)
			(stroke
				(width 0.1)
				(type default)
			)
			(layer "B.Fab")
		)
		(fp_line
			(start 0.12065 -0.2794)
			(end -0.12065 -0.2794)
			(stroke
				(width 0.1)
				(type default)
			)
			(layer "B.Fab")
		)
		(fp_line
			(start 0.12065 -0.305054)
			(end 0.12065 -0.2794)
			(stroke
				(width 0.1)
				(type default)
			)
			(layer "B.Fab")
		)
		(fp_line
			(start -0.120396 0.3048)
			(end -0.120396 0.2794)
			(stroke
				(width 0.1)
				(type default)
			)
			(layer "B.Fab")
		)
		(fp_line
			(start -0.120396 0.2794)
			(end 0.12065 0.2794)
			(stroke
				(width 0.1)
				(type default)
			)
			(layer "B.Fab")
		)
		(fp_line
			(start -0.12065 -0.2794)
			(end -0.12065 -0.3048)
			(stroke
				(width 0.1)
				(type default)
			)
			(layer "B.Fab")
		)
		(fp_line
			(start -0.12065 -0.3048)
			(end -0.67945 -0.3048)
			(stroke
				(width 0.1)
				(type default)
			)
			(layer "B.Fab")
		)
		(fp_line
			(start -0.67945 0.3048)
			(end -0.120396 0.3048)
			(stroke
				(width 0.1)
				(type default)
			)
			(layer "B.Fab")
		)
		(fp_line
			(start -0.67945 -0.3048)
			(end -0.67945 0.3048)
			(stroke
				(width 0.1)
				(type default)
			)
			(layer "B.Fab")
		)
		(pad "1" smd circle
			(at 0.40005 0)
			(size 0 0)
			(layers "B.Cu" "B.Mask" "B.Paste")
			(net "FM_CK440_MXCK_25M_100M")
		)
		(pad "2" smd circle
			(at -0.40005 0)
			(size 0 0)
			(layers "B.Cu" "B.Mask" "B.Paste")
			(net "GND")
		)
	)
	(footprint ""
		(layer "B.Cu")
		(at 340.033864 -337.145884 90)
		(property "Reference" "PC260_P0_6"
			(at 0 0 90)
			(layer "B.SilkS")
			(hide yes)
			(effects
				(font
					(size 1.27 1.27)
				)
				(justify mirror)
			)
		)
		(property "Value" ""
			(at 0 0 90)
			(layer "B.Fab")
			(effects
				(font
					(size 1.27 1.27)
				)
				(justify mirror)
			)
		)
		(duplicate_pad_numbers_are_jumpers no)
		(fp_line
			(start 1.524 -0.762)
			(end -1.524 -0.762)
			(stroke
				(width 0.1524)
				(type default)
			)
			(layer "B.SilkS")
		)
		(fp_line
			(start -1.524 -0.762)
			(end -1.524 0.762)
			(stroke
				(width 0.1524)
				(type default)
			)
			(layer "B.SilkS")
		)
		(fp_line
			(start 1.524 0.762)
			(end 1.524 -0.762)
			(stroke
				(width 0.1524)
				(type default)
			)
			(layer "B.SilkS")
		)
		(fp_line
			(start -1.524 0.762)
			(end 1.524 0.762)
			(stroke
				(width 0.1524)
				(type default)
			)
			(layer "B.SilkS")
		)
		(fp_line
			(start 1.1049 -0.724916)
			(end 1.1049 0.724916)
			(stroke
				(width 0.1)
				(type default)
			)
			(layer "B.Fab")
		)
		(fp_line
			(start -1.1049 -0.724916)
			(end 1.1049 -0.724916)
			(stroke
				(width 0.1)
				(type default)
			)
			(layer "B.Fab")
		)
		(fp_line
			(start 1.1049 0.724916)
			(end -1.1049 0.724916)
			(stroke
				(width 0.1)
				(type default)
			)
			(layer "B.Fab")
		)
		(fp_line
			(start -1.1049 0.724916)
			(end -1.1049 -0.724916)
			(stroke
				(width 0.1)
				(type default)
			)
			(layer "B.Fab")
		)
		(pad "1" smd rect
			(at 0.889 0 90)
			(size 1.016 1.27)
			(layers "B.Cu" "B.Mask" "B.Paste")
			(net "SW_P12V_PVCCIN_CPU0_FLT")
		)
		(pad "2" smd rect
			(at -0.889 0 90)
			(size 1.016 1.27)
			(layers "B.Cu" "B.Mask" "B.Paste")
			(net "GND")
		)
	)
	(footprint ""
		(layer "B.Cu")
		(at 322.080382 -38.794944 45)
		(property "Reference" "R1736"
			(at 0 0 45)
			(layer "B.SilkS")
			(hide yes)
			(effects
				(font
					(size 1.27 1.27)
				)
				(justify mirror)
			)
		)
		(property "Value" ""
			(at 0 0 45)
			(layer "B.Fab")
			(effects
				(font
					(size 1.27 1.27)
				)
				(justify mirror)
			)
		)
		(duplicate_pad_numbers_are_jumpers no)
		(fp_line
			(start -0.787389 -0.406267)
			(end -0.787389 0.406267)
			(stroke
				(width 0.1524)
				(type default)
			)
			(layer "B.SilkS")
		)
		(fp_line
			(start -0.787389 0.406267)
			(end 0.787389 0.406267)
			(stroke
				(width 0.1524)
				(type default)
			)
			(layer "B.SilkS")
		)
		(fp_line
			(start 0.787389 -0.406267)
			(end -0.787389 -0.406267)
			(stroke
				(width 0.1524)
				(type default)
			)
			(layer "B.SilkS")
		)
		(fp_line
			(start 0.787389 0.406267)
			(end 0.787389 -0.406267)
			(stroke
				(width 0.1524)
				(type default)
			)
			(layer "B.SilkS")
		)
		(fp_line
			(start -0.679446 -0.30479)
			(end -0.679446 0.30479)
			(stroke
				(width 0.1)
				(type default)
			)
			(layer "B.Fab")
		)
		(fp_line
			(start -0.120515 -0.30479)
			(end -0.679446 -0.30479)
			(stroke
				(width 0.1)
				(type default)
			)
			(layer "B.Fab")
		)
		(fp_line
			(start -0.120695 -0.279466)
			(end -0.120515 -0.30479)
			(stroke
				(width 0.1)
				(type default)
			)
			(layer "B.Fab")
		)
		(fp_line
			(start -0.679446 0.30479)
			(end -0.120515 0.30479)
			(stroke
				(width 0.1)
				(type default)
			)
			(layer "B.Fab")
		)
		(fp_line
			(start 0.120695 -0.304969)
			(end 0.120695 -0.279466)
			(stroke
				(width 0.1)
				(type default)
			)
			(layer "B.Fab")
		)
		(fp_line
			(start 0.120695 -0.279466)
			(end -0.120695 -0.279466)
			(stroke
				(width 0.1)
				(type default)
			)
			(layer "B.Fab")
		)
		(fp_line
			(start -0.120335 0.279466)
			(end 0.120695 0.279466)
			(stroke
				(width 0.1)
				(type default)
			)
			(layer "B.Fab")
		)
		(fp_line
			(start -0.120515 0.30479)
			(end -0.120335 0.279466)
			(stroke
				(width 0.1)
				(type default)
			)
			(layer "B.Fab")
		)
		(fp_line
			(start 0.679446 -0.305149)
			(end 0.120695 -0.304969)
			(stroke
				(width 0.1)
				(type default)
			)
			(layer "B.Fab")
		)
		(fp_line
			(start 0.120695 0.279466)
			(end 0.120515 0.30479)
			(stroke
				(width 0.1)
				(type default)
			)
			(layer "B.Fab")
		)
		(fp_line
			(start 0.120515 0.30479)
			(end 0.679446 0.30479)
			(stroke
				(width 0.1)
				(type default)
			)
			(layer "B.Fab")
		)
		(fp_line
			(start 0.679446 0.30479)
			(end 0.679446 -0.305149)
			(stroke
				(width 0.1)
				(type default)
			)
			(layer "B.Fab")
		)
		(pad "1" smd circle
			(at 0.40005 0 225)
			(size 0 0)
			(layers "B.Cu" "B.Mask" "B.Paste")
			(net "FM_PCH_SLP_SUS_N")
		)
		(pad "2" smd circle
			(at -0.40005 0 225)
			(size 0 0)
			(layers "B.Cu" "B.Mask" "B.Paste")
			(net "FM_SLP_SUS_RSM_RST_N")
		)
	)
	(footprint ""
		(layer "B.Cu")
		(at 333.653638 -188.92393 -90)
		(property "Reference" "R18"
			(at 0 0 90)
			(layer "B.SilkS")
			(hide yes)
			(effects
				(font
					(size 1.27 1.27)
				)
				(justify mirror)
			)
		)
		(property "Value" ""
			(at 0 0 90)
			(layer "B.Fab")
			(effects
				(font
					(size 1.27 1.27)
				)
				(justify mirror)
			)
		)
		(duplicate_pad_numbers_are_jumpers no)
		(fp_line
			(start -0.7874 0.4064)
			(end 0.7874 0.4064)
			(stroke
				(width 0.1524)
				(type default)
			)
			(layer "B.SilkS")
		)
		(fp_line
			(start 0.7874 0.4064)
			(end 0.7874 -0.4064)
			(stroke
				(width 0.1524)
				(type default)
			)
			(layer "B.SilkS")
		)
		(fp_line
			(start -0.7874 -0.4064)
			(end -0.7874 0.4064)
			(stroke
				(width 0.1524)
				(type default)
			)
			(layer "B.SilkS")
		)
		(fp_line
			(start 0.7874 -0.4064)
			(end -0.7874 -0.4064)
			(stroke
				(width 0.1524)
				(type default)
			)
			(layer "B.SilkS")
		)
		(fp_line
			(start -0.67945 0.3048)
			(end -0.120396 0.3048)
			(stroke
				(width 0.1)
				(type default)
			)
			(layer "B.Fab")
		)
		(fp_line
			(start -0.120396 0.3048)
			(end -0.120396 0.2794)
			(stroke
				(width 0.1)
				(type default)
			)
			(layer "B.Fab")
		)
		(fp_line
			(start 0.12065 0.3048)
			(end 0.67945 0.3048)
			(stroke
				(width 0.1)
				(type default)
			)
			(layer "B.Fab")
		)
		(fp_line
			(start 0.67945 0.3048)
			(end 0.67945 -0.305054)
			(stroke
				(width 0.1)
				(type default)
			)
			(layer "B.Fab")
		)
		(fp_line
			(start -0.120396 0.2794)
			(end 0.12065 0.2794)
			(stroke
				(width 0.1)
				(type default)
			)
			(layer "B.Fab")
		)
		(fp_line
			(start 0.12065 0.2794)
			(end 0.12065 0.3048)
			(stroke
				(width 0.1)
				(type default)
			)
			(layer "B.Fab")
		)
		(fp_line
			(start -0.12065 -0.2794)
			(end -0.12065 -0.3048)
			(stroke
				(width 0.1)
				(type default)
			)
			(layer "B.Fab")
		)
		(fp_line
			(start 0.12065 -0.2794)
			(end -0.12065 -0.2794)
			(stroke
				(width 0.1)
				(type default)
			)
			(layer "B.Fab")
		)
		(fp_line
			(start -0.67945 -0.3048)
			(end -0.67945 0.3048)
			(stroke
				(width 0.1)
				(type default)
			)
			(layer "B.Fab")
		)
		(fp_line
			(start -0.12065 -0.3048)
			(end -0.67945 -0.3048)
			(stroke
				(width 0.1)
				(type default)
			)
			(layer "B.Fab")
		)
		(fp_line
			(start 0.12065 -0.305054)
			(end 0.12065 -0.2794)
			(stroke
				(width 0.1)
				(type default)
			)
			(layer "B.Fab")
		)
		(fp_line
			(start 0.67945 -0.305054)
			(end 0.12065 -0.305054)
			(stroke
				(width 0.1)
				(type default)
			)
			(layer "B.Fab")
		)
		(pad "1" smd circle
			(at 0.40005 0 90)
			(size 0 0)
			(layers "B.Cu" "B.Mask" "B.Paste")
			(net "PVNN_TERM_CPU0")
		)
		(pad "2" smd circle
			(at -0.40005 0 90)
			(size 0 0)
			(layers "B.Cu" "B.Mask" "B.Paste")
			(net "DBP_CPU_MBP0_GTL_N")
		)
	)
	(footprint ""
		(layer "B.Cu")
		(at 347.32468 -325.135748 -90)
		(property "Reference" "PR4219"
			(at 0 0 90)
			(layer "B.SilkS")
			(hide yes)
			(effects
				(font
					(size 1.27 1.27)
				)
				(justify mirror)
			)
		)
		(property "Value" ""
			(at 0 0 90)
			(layer "B.Fab")
			(effects
				(font
					(size 1.27 1.27)
				)
				(justify mirror)
			)
		)
		(duplicate_pad_numbers_are_jumpers no)
		(fp_line
			(start -0.7874 0.4064)
			(end 0.7874 0.4064)
			(stroke
				(width 0.1524)
				(type default)
			)
			(layer "B.SilkS")
		)
		(fp_line
			(start 0.7874 0.4064)
			(end 0.7874 -0.4064)
			(stroke
				(width 0.1524)
				(type default)
			)
			(layer "B.SilkS")
		)
		(fp_line
			(start -0.7874 -0.4064)
			(end -0.7874 0.4064)
			(stroke
				(width 0.1524)
				(type default)
			)
			(layer "B.SilkS")
		)
		(fp_line
			(start 0.7874 -0.4064)
			(end -0.7874 -0.4064)
			(stroke
				(width 0.1524)
				(type default)
			)
			(layer "B.SilkS")
		)
		(fp_line
			(start -0.67945 0.3048)
			(end -0.120396 0.3048)
			(stroke
				(width 0.1)
				(type default)
			)
			(layer "B.Fab")
		)
		(fp_line
			(start -0.120396 0.3048)
			(end -0.120396 0.2794)
			(stroke
				(width 0.1)
				(type default)
			)
			(layer "B.Fab")
		)
		(fp_line
			(start 0.12065 0.3048)
			(end 0.67945 0.3048)
			(stroke
				(width 0.1)
				(type default)
			)
			(layer "B.Fab")
		)
		(fp_line
			(start 0.67945 0.3048)
			(end 0.67945 -0.305054)
			(stroke
				(width 0.1)
				(type default)
			)
			(layer "B.Fab")
		)
		(fp_line
			(start -0.120396 0.2794)
			(end 0.12065 0.2794)
			(stroke
				(width 0.1)
				(type default)
			)
			(layer "B.Fab")
		)
		(fp_line
			(start 0.12065 0.2794)
			(end 0.12065 0.3048)
			(stroke
				(width 0.1)
				(type default)
			)
			(layer "B.Fab")
		)
		(fp_line
			(start -0.12065 -0.2794)
			(end -0.12065 -0.3048)
			(stroke
				(width 0.1)
				(type default)
			)
			(layer "B.Fab")
		)
		(fp_line
			(start 0.12065 -0.2794)
			(end -0.12065 -0.2794)
			(stroke
				(width 0.1)
				(type default)
			)
			(layer "B.Fab")
		)
		(fp_line
			(start -0.67945 -0.3048)
			(end -0.67945 0.3048)
			(stroke
				(width 0.1)
				(type default)
			)
			(layer "B.Fab")
		)
		(fp_line
			(start -0.12065 -0.3048)
			(end -0.67945 -0.3048)
			(stroke
				(width 0.1)
				(type default)
			)
			(layer "B.Fab")
		)
		(fp_line
			(start 0.12065 -0.305054)
			(end 0.12065 -0.2794)
			(stroke
				(width 0.1)
				(type default)
			)
			(layer "B.Fab")
		)
		(fp_line
			(start 0.67945 -0.305054)
			(end 0.12065 -0.305054)
			(stroke
				(width 0.1)
				(type default)
			)
			(layer "B.Fab")
		)
		(pad "1" smd circle
			(at 0.40005 0 90)
			(size 0 0)
			(layers "B.Cu" "B.Mask" "B.Paste")
			(net "PVCCIN_CPU0")
		)
		(pad "2" smd circle
			(at -0.40005 0 90)
			(size 0 0)
			(layers "B.Cu" "B.Mask" "B.Paste")
			(net "GND")
		)
	)
	(footprint ""
		(layer "B.Cu")
		(at 83.082384 -188.035692 -90)
		(property "Reference" "R263"
			(at 0 0 90)
			(layer "B.SilkS")
			(hide yes)
			(effects
				(font
					(size 1.27 1.27)
				)
				(justify mirror)
			)
		)
		(property "Value" ""
			(at 0 0 90)
			(layer "B.Fab")
			(effects
				(font
					(size 1.27 1.27)
				)
				(justify mirror)
			)
		)
		(duplicate_pad_numbers_are_jumpers no)
		(fp_line
			(start -0.7874 0.4064)
			(end 0.7874 0.4064)
			(stroke
				(width 0.1524)
				(type default)
			)
			(layer "B.SilkS")
		)
		(fp_line
			(start 0.7874 0.4064)
			(end 0.7874 -0.4064)
			(stroke
				(width 0.1524)
				(type default)
			)
			(layer "B.SilkS")
		)
		(fp_line
			(start -0.7874 -0.4064)
			(end -0.7874 0.4064)
			(stroke
				(width 0.1524)
				(type default)
			)
			(layer "B.SilkS")
		)
		(fp_line
			(start 0.7874 -0.4064)
			(end -0.7874 -0.4064)
			(stroke
				(width 0.1524)
				(type default)
			)
			(layer "B.SilkS")
		)
		(fp_line
			(start -0.67945 0.3048)
			(end -0.120396 0.3048)
			(stroke
				(width 0.1)
				(type default)
			)
			(layer "B.Fab")
		)
		(fp_line
			(start -0.120396 0.3048)
			(end -0.120396 0.2794)
			(stroke
				(width 0.1)
				(type default)
			)
			(layer "B.Fab")
		)
		(fp_line
			(start 0.12065 0.3048)
			(end 0.67945 0.3048)
			(stroke
				(width 0.1)
				(type default)
			)
			(layer "B.Fab")
		)
		(fp_line
			(start 0.67945 0.3048)
			(end 0.67945 -0.305054)
			(stroke
				(width 0.1)
				(type default)
			)
			(layer "B.Fab")
		)
		(fp_line
			(start -0.120396 0.2794)
			(end 0.12065 0.2794)
			(stroke
				(width 0.1)
				(type default)
			)
			(layer "B.Fab")
		)
		(fp_line
			(start 0.12065 0.2794)
			(end 0.12065 0.3048)
			(stroke
				(width 0.1)
				(type default)
			)
			(layer "B.Fab")
		)
		(fp_line
			(start -0.12065 -0.2794)
			(end -0.12065 -0.3048)
			(stroke
				(width 0.1)
				(type default)
			)
			(layer "B.Fab")
		)
		(fp_line
			(start 0.12065 -0.2794)
			(end -0.12065 -0.2794)
			(stroke
				(width 0.1)
				(type default)
			)
			(layer "B.Fab")
		)
		(fp_line
			(start -0.67945 -0.3048)
			(end -0.67945 0.3048)
			(stroke
				(width 0.1)
				(type default)
			)
			(layer "B.Fab")
		)
		(fp_line
			(start -0.12065 -0.3048)
			(end -0.67945 -0.3048)
			(stroke
				(width 0.1)
				(type default)
			)
			(layer "B.Fab")
		)
		(fp_line
			(start 0.12065 -0.305054)
			(end 0.12065 -0.2794)
			(stroke
				(width 0.1)
				(type default)
			)
			(layer "B.Fab")
		)
		(fp_line
			(start 0.67945 -0.305054)
			(end 0.12065 -0.305054)
			(stroke
				(width 0.1)
				(type default)
			)
			(layer "B.Fab")
		)
		(pad "1" smd circle
			(at 0.40005 0 90)
			(size 0 0)
			(layers "B.Cu" "B.Mask" "B.Paste")
			(net "PVNN_TERM_CPU1")
		)
		(pad "2" smd circle
			(at -0.40005 0 90)
			(size 0 0)
			(layers "B.Cu" "B.Mask" "B.Paste")
			(net "PU_CPU1_FRMAGENT")
		)
	)
	(footprint ""
		(layer "B.Cu")
		(at 289.988498 -400.999452 -90)
		(property "Reference" "PR2525"
			(at 0 0 90)
			(layer "B.SilkS")
			(hide yes)
			(effects
				(font
					(size 1.27 1.27)
				)
				(justify mirror)
			)
		)
		(property "Value" ""
			(at 0 0 90)
			(layer "B.Fab")
			(effects
				(font
					(size 1.27 1.27)
				)
				(justify mirror)
			)
		)
		(duplicate_pad_numbers_are_jumpers no)
		(fp_line
			(start -0.7874 0.4064)
			(end 0.7874 0.4064)
			(stroke
				(width 0.1524)
				(type default)
			)
			(layer "B.SilkS")
		)
		(fp_line
			(start 0.7874 0.4064)
			(end 0.7874 -0.4064)
			(stroke
				(width 0.1524)
				(type default)
			)
			(layer "B.SilkS")
		)
		(fp_line
			(start -0.7874 -0.4064)
			(end -0.7874 0.4064)
			(stroke
				(width 0.1524)
				(type default)
			)
			(layer "B.SilkS")
		)
		(fp_line
			(start 0.7874 -0.4064)
			(end -0.7874 -0.4064)
			(stroke
				(width 0.1524)
				(type default)
			)
			(layer "B.SilkS")
		)
		(fp_line
			(start -0.67945 0.3048)
			(end -0.120396 0.3048)
			(stroke
				(width 0.1)
				(type default)
			)
			(layer "B.Fab")
		)
		(fp_line
			(start -0.120396 0.3048)
			(end -0.120396 0.2794)
			(stroke
				(width 0.1)
				(type default)
			)
			(layer "B.Fab")
		)
		(fp_line
			(start 0.12065 0.3048)
			(end 0.67945 0.3048)
			(stroke
				(width 0.1)
				(type default)
			)
			(layer "B.Fab")
		)
		(fp_line
			(start 0.67945 0.3048)
			(end 0.67945 -0.305054)
			(stroke
				(width 0.1)
				(type default)
			)
			(layer "B.Fab")
		)
		(fp_line
			(start -0.120396 0.2794)
			(end 0.12065 0.2794)
			(stroke
				(width 0.1)
				(type default)
			)
			(layer "B.Fab")
		)
		(fp_line
			(start 0.12065 0.2794)
			(end 0.12065 0.3048)
			(stroke
				(width 0.1)
				(type default)
			)
			(layer "B.Fab")
		)
		(fp_line
			(start -0.12065 -0.2794)
			(end -0.12065 -0.3048)
			(stroke
				(width 0.1)
				(type default)
			)
			(layer "B.Fab")
		)
		(fp_line
			(start 0.12065 -0.2794)
			(end -0.12065 -0.2794)
			(stroke
				(width 0.1)
				(type default)
			)
			(layer "B.Fab")
		)
		(fp_line
			(start -0.67945 -0.3048)
			(end -0.67945 0.3048)
			(stroke
				(width 0.1)
				(type default)
			)
			(layer "B.Fab")
		)
		(fp_line
			(start -0.12065 -0.3048)
			(end -0.67945 -0.3048)
			(stroke
				(width 0.1)
				(type default)
			)
			(layer "B.Fab")
		)
		(fp_line
			(start 0.12065 -0.305054)
			(end 0.12065 -0.2794)
			(stroke
				(width 0.1)
				(type default)
			)
			(layer "B.Fab")
		)
		(fp_line
			(start 0.67945 -0.305054)
			(end 0.12065 -0.305054)
			(stroke
				(width 0.1)
				(type default)
			)
			(layer "B.Fab")
		)
		(pad "1" smd circle
			(at 0.40005 0 90)
			(size 0 0)
			(layers "B.Cu" "B.Mask" "B.Paste")
			(net "P12V_HSC_SENSE2_N")
		)
		(pad "2" smd circle
			(at -0.40005 0 90)
			(size 0 0)
			(layers "B.Cu" "B.Mask" "B.Paste")
			(net "P12V_HSC_SENSE2_R2_N")
		)
	)
	(footprint ""
		(layer "B.Cu")
		(at 53.746908 -193.25971 -90)
		(property "Reference" "R92"
			(at 0 0 90)
			(layer "B.SilkS")
			(hide yes)
			(effects
				(font
					(size 1.27 1.27)
				)
				(justify mirror)
			)
		)
		(property "Value" ""
			(at 0 0 90)
			(layer "B.Fab")
			(effects
				(font
					(size 1.27 1.27)
				)
				(justify mirror)
			)
		)
		(duplicate_pad_numbers_are_jumpers no)
		(fp_line
			(start -0.7874 0.4064)
			(end 0.7874 0.4064)
			(stroke
				(width 0.1524)
				(type default)
			)
			(layer "B.SilkS")
		)
		(fp_line
			(start 0.7874 0.4064)
			(end 0.7874 -0.4064)
			(stroke
				(width 0.1524)
				(type default)
			)
			(layer "B.SilkS")
		)
		(fp_line
			(start -0.7874 -0.4064)
			(end -0.7874 0.4064)
			(stroke
				(width 0.1524)
				(type default)
			)
			(layer "B.SilkS")
		)
		(fp_line
			(start 0.7874 -0.4064)
			(end -0.7874 -0.4064)
			(stroke
				(width 0.1524)
				(type default)
			)
			(layer "B.SilkS")
		)
		(fp_line
			(start -0.67945 0.3048)
			(end -0.120396 0.3048)
			(stroke
				(width 0.1)
				(type default)
			)
			(layer "B.Fab")
		)
		(fp_line
			(start -0.120396 0.3048)
			(end -0.120396 0.2794)
			(stroke
				(width 0.1)
				(type default)
			)
			(layer "B.Fab")
		)
		(fp_line
			(start 0.12065 0.3048)
			(end 0.67945 0.3048)
			(stroke
				(width 0.1)
				(type default)
			)
			(layer "B.Fab")
		)
		(fp_line
			(start 0.67945 0.3048)
			(end 0.67945 -0.305054)
			(stroke
				(width 0.1)
				(type default)
			)
			(layer "B.Fab")
		)
		(fp_line
			(start -0.120396 0.2794)
			(end 0.12065 0.2794)
			(stroke
				(width 0.1)
				(type default)
			)
			(layer "B.Fab")
		)
		(fp_line
			(start 0.12065 0.2794)
			(end 0.12065 0.3048)
			(stroke
				(width 0.1)
				(type default)
			)
			(layer "B.Fab")
		)
		(fp_line
			(start -0.12065 -0.2794)
			(end -0.12065 -0.3048)
			(stroke
				(width 0.1)
				(type default)
			)
			(layer "B.Fab")
		)
		(fp_line
			(start 0.12065 -0.2794)
			(end -0.12065 -0.2794)
			(stroke
				(width 0.1)
				(type default)
			)
			(layer "B.Fab")
		)
		(fp_line
			(start -0.67945 -0.3048)
			(end -0.67945 0.3048)
			(stroke
				(width 0.1)
				(type default)
			)
			(layer "B.Fab")
		)
		(fp_line
			(start -0.12065 -0.3048)
			(end -0.67945 -0.3048)
			(stroke
				(width 0.1)
				(type default)
			)
			(layer "B.Fab")
		)
		(fp_line
			(start 0.12065 -0.305054)
			(end 0.12065 -0.2794)
			(stroke
				(width 0.1)
				(type default)
			)
			(layer "B.Fab")
		)
		(fp_line
			(start 0.67945 -0.305054)
			(end 0.12065 -0.305054)
			(stroke
				(width 0.1)
				(type default)
			)
			(layer "B.Fab")
		)
		(pad "1" smd circle
			(at 0.40005 0 90)
			(size 0 0)
			(layers "B.Cu" "B.Mask" "B.Paste")
			(net "PVNN_TERM_CPU1")
		)
		(pad "2" smd circle
			(at -0.40005 0 90)
			(size 0 0)
			(layers "B.Cu" "B.Mask" "B.Paste")
			(net "PU_CPU1_UPI2_AC_COUPLING")
		)
	)
	(footprint ""
		(layer "B.Cu")
		(at 326.743822 -70.207378)
		(property "Reference" "C1250"
			(at 0 0 0)
			(layer "B.SilkS")
			(hide yes)
			(effects
				(font
					(size 1.27 1.27)
				)
				(justify mirror)
			)
		)
		(property "Value" ""
			(at 0 0 0)
			(layer "B.Fab")
			(effects
				(font
					(size 1.27 1.27)
				)
				(justify mirror)
			)
		)
		(duplicate_pad_numbers_are_jumpers no)
		(fp_line
			(start -0.7874 -0.4064)
			(end -0.7874 0.4064)
			(stroke
				(width 0.1524)
				(type default)
			)
			(layer "B.SilkS")
		)
		(fp_line
			(start -0.7874 0.4064)
			(end 0.7874 0.4064)
			(stroke
				(width 0.1524)
				(type default)
			)
			(layer "B.SilkS")
		)
		(fp_line
			(start 0.7874 -0.4064)
			(end -0.7874 -0.4064)
			(stroke
				(width 0.1524)
				(type default)
			)
			(layer "B.SilkS")
		)
		(fp_line
			(start 0.7874 0.4064)
			(end 0.7874 -0.4064)
			(stroke
				(width 0.1524)
				(type default)
			)
			(layer "B.SilkS")
		)
		(fp_line
			(start -0.67945 -0.3048)
			(end -0.67945 0.3048)
			(stroke
				(width 0.1)
				(type default)
			)
			(layer "B.Fab")
		)
		(fp_line
			(start -0.67945 0.3048)
			(end -0.120396 0.3048)
			(stroke
				(width 0.1)
				(type default)
			)
			(layer "B.Fab")
		)
		(fp_line
			(start -0.12065 -0.3048)
			(end -0.67945 -0.3048)
			(stroke
				(width 0.1)
				(type default)
			)
			(layer "B.Fab")
		)
		(fp_line
			(start -0.12065 -0.2794)
			(end -0.12065 -0.3048)
			(stroke
				(width 0.1)
				(type default)
			)
			(layer "B.Fab")
		)
		(fp_line
			(start -0.120396 0.2794)
			(end 0.12065 0.2794)
			(stroke
				(width 0.1)
				(type default)
			)
			(layer "B.Fab")
		)
		(fp_line
			(start -0.120396 0.3048)
			(end -0.120396 0.2794)
			(stroke
				(width 0.1)
				(type default)
			)
			(layer "B.Fab")
		)
		(fp_line
			(start 0.12065 -0.305054)
			(end 0.12065 -0.2794)
			(stroke
				(width 0.1)
				(type default)
			)
			(layer "B.Fab")
		)
		(fp_line
			(start 0.12065 -0.2794)
			(end -0.12065 -0.2794)
			(stroke
				(width 0.1)
				(type default)
			)
			(layer "B.Fab")
		)
		(fp_line
			(start 0.12065 0.2794)
			(end 0.12065 0.3048)
			(stroke
				(width 0.1)
				(type default)
			)
			(layer "B.Fab")
		)
		(fp_line
			(start 0.12065 0.3048)
			(end 0.67945 0.3048)
			(stroke
				(width 0.1)
				(type default)
			)
			(layer "B.Fab")
		)
		(fp_line
			(start 0.67945 -0.305054)
			(end 0.12065 -0.305054)
			(stroke
				(width 0.1)
				(type default)
			)
			(layer "B.Fab")
		)
		(fp_line
			(start 0.67945 0.3048)
			(end 0.67945 -0.305054)
			(stroke
				(width 0.1)
				(type default)
			)
			(layer "B.Fab")
		)
		(pad "1" smd circle
			(at 0.40005 0 180)
			(size 0 0)
			(layers "B.Cu" "B.Mask" "B.Paste")
			(net "P1V05_PCH_AUX")
		)
		(pad "2" smd circle
			(at -0.40005 0 180)
			(size 0 0)
			(layers "B.Cu" "B.Mask" "B.Paste")
			(net "GND")
		)
	)
	(footprint ""
		(layer "B.Cu")
		(at 164.64788 -117.566948 180)
		(property "Reference" "R919"
			(at 0 0 0)
			(layer "B.SilkS")
			(hide yes)
			(effects
				(font
					(size 1.27 1.27)
				)
				(justify mirror)
			)
		)
		(property "Value" ""
			(at 0 0 0)
			(layer "B.Fab")
			(effects
				(font
					(size 1.27 1.27)
				)
				(justify mirror)
			)
		)
		(duplicate_pad_numbers_are_jumpers no)
		(fp_line
			(start 0.7874 0.4064)
			(end 0.7874 -0.4064)
			(stroke
				(width 0.1524)
				(type default)
			)
			(layer "B.SilkS")
		)
		(fp_line
			(start 0.7874 -0.4064)
			(end -0.7874 -0.4064)
			(stroke
				(width 0.1524)
				(type default)
			)
			(layer "B.SilkS")
		)
		(fp_line
			(start -0.7874 0.4064)
			(end 0.7874 0.4064)
			(stroke
				(width 0.1524)
				(type default)
			)
			(layer "B.SilkS")
		)
		(fp_line
			(start -0.7874 -0.4064)
			(end -0.7874 0.4064)
			(stroke
				(width 0.1524)
				(type default)
			)
			(layer "B.SilkS")
		)
		(fp_line
			(start 0.67945 0.3048)
			(end 0.67945 -0.305054)
			(stroke
				(width 0.1)
				(type default)
			)
			(layer "B.Fab")
		)
		(fp_line
			(start 0.67945 -0.305054)
			(end 0.12065 -0.305054)
			(stroke
				(width 0.1)
				(type default)
			)
			(layer "B.Fab")
		)
		(fp_line
			(start 0.12065 0.3048)
			(end 0.67945 0.3048)
			(stroke
				(width 0.1)
				(type default)
			)
			(layer "B.Fab")
		)
		(fp_line
			(start 0.12065 0.2794)
			(end 0.12065 0.3048)
			(stroke
				(width 0.1)
				(type default)
			)
			(layer "B.Fab")
		)
		(fp_line
			(start 0.12065 -0.2794)
			(end -0.12065 -0.2794)
			(stroke
				(width 0.1)
				(type default)
			)
			(layer "B.Fab")
		)
		(fp_line
			(start 0.12065 -0.305054)
			(end 0.12065 -0.2794)
			(stroke
				(width 0.1)
				(type default)
			)
			(layer "B.Fab")
		)
		(fp_line
			(start -0.120396 0.3048)
			(end -0.120396 0.2794)
			(stroke
				(width 0.1)
				(type default)
			)
			(layer "B.Fab")
		)
		(fp_line
			(start -0.120396 0.2794)
			(end 0.12065 0.2794)
			(stroke
				(width 0.1)
				(type default)
			)
			(layer "B.Fab")
		)
		(fp_line
			(start -0.12065 -0.2794)
			(end -0.12065 -0.3048)
			(stroke
				(width 0.1)
				(type default)
			)
			(layer "B.Fab")
		)
		(fp_line
			(start -0.12065 -0.3048)
			(end -0.67945 -0.3048)
			(stroke
				(width 0.1)
				(type default)
			)
			(layer "B.Fab")
		)
		(fp_line
			(start -0.67945 0.3048)
			(end -0.120396 0.3048)
			(stroke
				(width 0.1)
				(type default)
			)
			(layer "B.Fab")
		)
		(fp_line
			(start -0.67945 -0.3048)
			(end -0.67945 0.3048)
			(stroke
				(width 0.1)
				(type default)
			)
			(layer "B.Fab")
		)
		(pad "1" smd circle
			(at 0.40005 0)
			(size 0 0)
			(layers "B.Cu" "B.Mask" "B.Paste")
			(net "P3V3_AUX")
		)
		(pad "2" smd circle
			(at -0.40005 0)
			(size 0 0)
			(layers "B.Cu" "B.Mask" "B.Paste")
			(net "JTAG_PLD_JTAGEN")
		)
	)
	(footprint ""
		(layer "B.Cu")
		(at 361.617768 -326.87006 -90)
		(property "Reference" "PC1920"
			(at 0 0 90)
			(layer "B.SilkS")
			(hide yes)
			(effects
				(font
					(size 1.27 1.27)
				)
				(justify mirror)
			)
		)
		(property "Value" ""
			(at 0 0 90)
			(layer "B.Fab")
			(effects
				(font
					(size 1.27 1.27)
				)
				(justify mirror)
			)
		)
		(duplicate_pad_numbers_are_jumpers no)
		(fp_line
			(start -4.533392 2.249932)
			(end 4.533392 2.249932)
			(stroke
				(width 0.1524)
				(type default)
			)
			(layer "B.SilkS")
		)
		(fp_line
			(start 4.533392 2.249932)
			(end 4.533392 -2.249932)
			(stroke
				(width 0.1524)
				(type default)
			)
			(layer "B.SilkS")
		)
		(fp_line
			(start -4.533392 -2.249932)
			(end -4.533392 2.249932)
			(stroke
				(width 0.1524)
				(type default)
			)
			(layer "B.SilkS")
		)
		(fp_line
			(start 4.533392 -2.249932)
			(end -4.533392 -2.249932)
			(stroke
				(width 0.1524)
				(type default)
			)
			(layer "B.SilkS")
		)
		(fp_rect
			(start 5.39242 2.326132)
			(end 4.533392 -2.326132)
			(stroke
				(width 0)
				(type default)
			)
			(fill yes)
			(layer "B.SilkS")
		)
		(fp_line
			(start -3.750056 2.249932)
			(end 3.750056 2.249932)
			(stroke
				(width 0.1)
				(type default)
			)
			(layer "B.Fab")
		)
		(fp_line
			(start 3.750056 2.249932)
			(end 3.750056 -2.249932)
			(stroke
				(width 0.1)
				(type default)
			)
			(layer "B.Fab")
		)
		(fp_line
			(start -3.750056 -2.249932)
			(end -3.750056 2.249932)
			(stroke
				(width 0.1)
				(type default)
			)
			(layer "B.Fab")
		)
		(fp_line
			(start 3.750056 -2.249932)
			(end -3.750056 -2.249932)
			(stroke
				(width 0.1)
				(type default)
			)
			(layer "B.Fab")
		)
		(fp_text user "-"
			(at -4.615688 1.650238 270)
			(unlocked yes)
			(layer "B.SilkS")
			(effects
				(font
					(size 1.905 1.4224)
					(thickness 0.1524)
				)
				(justify left mirror)
			)
		)
		(fp_text user "+"
			(at 6.322314 0.786384 180)
			(unlocked yes)
			(layer "B.SilkS")
			(effects
				(font
					(size 1.905 1.4224)
					(thickness 0.1524)
				)
				(justify left mirror)
			)
		)
		(fp_text user "+"
			(at 6.322314 0.786384 180)
			(unlocked yes)
			(layer "B.Fab")
			(effects
				(font
					(size 1.905 1.4224)
					(thickness 0.1524)
				)
				(justify left mirror)
			)
		)
		(fp_text user "-"
			(at -4.8514 -0.14605 270)
			(unlocked yes)
			(layer "B.Fab")
			(effects
				(font
					(size 1.905 1.4224)
					(thickness 0.1524)
				)
				(justify left mirror)
			)
		)
		(pad "1" smd rect
			(at 3.199892 0 90)
			(size 2.413 2.8194)
			(layers "B.Cu" "B.Mask" "B.Paste")
			(net "PVCCIN_CPU0")
		)
		(pad "2" smd rect
			(at -3.199892 0 90)
			(size 2.413 2.8194)
			(layers "B.Cu" "B.Mask" "B.Paste")
			(net "GND")
		)
	)
	(footprint ""
		(layer "B.Cu")
		(at 191.47409 -79.05623 -90)
		(property "Reference" "R1290"
			(at 0 0 90)
			(layer "B.SilkS")
			(hide yes)
			(effects
				(font
					(size 1.27 1.27)
				)
				(justify mirror)
			)
		)
		(property "Value" ""
			(at 0 0 90)
			(layer "B.Fab")
			(effects
				(font
					(size 1.27 1.27)
				)
				(justify mirror)
			)
		)
		(duplicate_pad_numbers_are_jumpers no)
		(fp_line
			(start -0.7874 0.4064)
			(end 0.7874 0.4064)
			(stroke
				(width 0.1524)
				(type default)
			)
			(layer "B.SilkS")
		)
		(fp_line
			(start 0.7874 0.4064)
			(end 0.7874 -0.4064)
			(stroke
				(width 0.1524)
				(type default)
			)
			(layer "B.SilkS")
		)
		(fp_line
			(start -0.7874 -0.4064)
			(end -0.7874 0.4064)
			(stroke
				(width 0.1524)
				(type default)
			)
			(layer "B.SilkS")
		)
		(fp_line
			(start 0.7874 -0.4064)
			(end -0.7874 -0.4064)
			(stroke
				(width 0.1524)
				(type default)
			)
			(layer "B.SilkS")
		)
		(fp_line
			(start -0.67945 0.3048)
			(end -0.120396 0.3048)
			(stroke
				(width 0.1)
				(type default)
			)
			(layer "B.Fab")
		)
		(fp_line
			(start -0.120396 0.3048)
			(end -0.120396 0.2794)
			(stroke
				(width 0.1)
				(type default)
			)
			(layer "B.Fab")
		)
		(fp_line
			(start 0.12065 0.3048)
			(end 0.67945 0.3048)
			(stroke
				(width 0.1)
				(type default)
			)
			(layer "B.Fab")
		)
		(fp_line
			(start 0.67945 0.3048)
			(end 0.67945 -0.305054)
			(stroke
				(width 0.1)
				(type default)
			)
			(layer "B.Fab")
		)
		(fp_line
			(start -0.120396 0.2794)
			(end 0.12065 0.2794)
			(stroke
				(width 0.1)
				(type default)
			)
			(layer "B.Fab")
		)
		(fp_line
			(start 0.12065 0.2794)
			(end 0.12065 0.3048)
			(stroke
				(width 0.1)
				(type default)
			)
			(layer "B.Fab")
		)
		(fp_line
			(start -0.12065 -0.2794)
			(end -0.12065 -0.3048)
			(stroke
				(width 0.1)
				(type default)
			)
			(layer "B.Fab")
		)
		(fp_line
			(start 0.12065 -0.2794)
			(end -0.12065 -0.2794)
			(stroke
				(width 0.1)
				(type default)
			)
			(layer "B.Fab")
		)
		(fp_line
			(start -0.67945 -0.3048)
			(end -0.67945 0.3048)
			(stroke
				(width 0.1)
				(type default)
			)
			(layer "B.Fab")
		)
		(fp_line
			(start -0.12065 -0.3048)
			(end -0.67945 -0.3048)
			(stroke
				(width 0.1)
				(type default)
			)
			(layer "B.Fab")
		)
		(fp_line
			(start 0.12065 -0.305054)
			(end 0.12065 -0.2794)
			(stroke
				(width 0.1)
				(type default)
			)
			(layer "B.Fab")
		)
		(fp_line
			(start 0.67945 -0.305054)
			(end 0.12065 -0.305054)
			(stroke
				(width 0.1)
				(type default)
			)
			(layer "B.Fab")
		)
		(pad "1" smd rect
			(at 0.40005 0 270)
			(size 0.4572 0.508)
			(layers "B.Cu" "B.Mask" "B.Paste")
			(net "OCP_SFF_RBT_ARB_IN_R")
		)
		(pad "2" smd rect
			(at -0.40005 0 270)
			(size 0.4572 0.508)
			(layers "B.Cu" "B.Mask" "B.Paste")
			(net "OCP_SFF_RBT_ARB_IN")
		)
	)
	(footprint ""
		(layer "B.Cu")
		(at 364.342934 -252.176026 -90)
		(property "Reference" "C364"
			(at 0 0 90)
			(layer "B.SilkS")
			(hide yes)
			(effects
				(font
					(size 1.27 1.27)
				)
				(justify mirror)
			)
		)
		(property "Value" ""
			(at 0 0 90)
			(layer "B.Fab")
			(effects
				(font
					(size 1.27 1.27)
				)
				(justify mirror)
			)
		)
		(duplicate_pad_numbers_are_jumpers no)
		(fp_line
			(start -1.524 0.762)
			(end 1.524 0.762)
			(stroke
				(width 0.1524)
				(type default)
			)
			(layer "B.SilkS")
		)
		(fp_line
			(start 1.524 0.762)
			(end 1.524 -0.762)
			(stroke
				(width 0.1524)
				(type default)
			)
			(layer "B.SilkS")
		)
		(fp_line
			(start -1.524 -0.762)
			(end -1.524 0.762)
			(stroke
				(width 0.1524)
				(type default)
			)
			(layer "B.SilkS")
		)
		(fp_line
			(start 1.524 -0.762)
			(end -1.524 -0.762)
			(stroke
				(width 0.1524)
				(type default)
			)
			(layer "B.SilkS")
		)
		(fp_line
			(start -1.1049 0.724916)
			(end -1.1049 -0.724916)
			(stroke
				(width 0.1)
				(type default)
			)
			(layer "B.Fab")
		)
		(fp_line
			(start 1.1049 0.724916)
			(end -1.1049 0.724916)
			(stroke
				(width 0.1)
				(type default)
			)
			(layer "B.Fab")
		)
		(fp_line
			(start -1.1049 -0.724916)
			(end 1.1049 -0.724916)
			(stroke
				(width 0.1)
				(type default)
			)
			(layer "B.Fab")
		)
		(fp_line
			(start 1.1049 -0.724916)
			(end 1.1049 0.724916)
			(stroke
				(width 0.1)
				(type default)
			)
			(layer "B.Fab")
		)
		(pad "1" smd rect
			(at 0.889 0 270)
			(size 1.016 1.27)
			(layers "B.Cu" "B.Mask" "B.Paste")
			(net "PVCCIN_CPU0")
		)
		(pad "2" smd rect
			(at -0.889 0 270)
			(size 1.016 1.27)
			(layers "B.Cu" "B.Mask" "B.Paste")
			(net "GND")
		)
	)
	(footprint ""
		(layer "B.Cu")
		(at 493.36833 2.324608 90)
		(property "Reference" "X30"
			(at 1.283208 3.38328 270)
			(unlocked yes)
			(layer "B.SilkS")
			(effects
				(font
					(size 0.7874 0.5842)
					(thickness 0.1524)
				)
				(justify left mirror)
			)
		)
		(property "Value" ""
			(at 0 0 90)
			(layer "B.Fab")
			(effects
				(font
					(size 1.27 1.27)
				)
				(justify mirror)
			)
		)
		(property "Device Type" "TP_TDR_4P_FTS_TH-TP_TDR_4P_DIPA"
			(at -1.30175 1.27 0)
			(unlocked yes)
			(layer "B.Fab")
			(hide yes)
			(effects
				(font
					(size 0.635 0.4064)
					(thickness 0.1524)
				)
				(justify mirror)
			)
		)
		(property "User Part Number" "N_A"
			(at -1.30175 1.27 0)
			(unlocked yes)
			(layer "Cmts.User")
			(hide yes)
			(effects
				(font
					(size 0.635 0.4064)
					(thickness 0.1524)
				)
				(justify mirror)
			)
		)
		(duplicate_pad_numbers_are_jumpers no)
		(fp_line
			(start 0 -1.27)
			(end 0 -0.635)
			(stroke
				(width 0.1524)
				(type default)
			)
			(layer "B.SilkS")
		)
		(fp_line
			(start -2.54 -1.27)
			(end 0 -1.27)
			(stroke
				(width 0.1524)
				(type default)
			)
			(layer "B.SilkS")
		)
		(fp_line
			(start -2.54 -1.1303)
			(end -2.54 -1.27)
			(stroke
				(width 0.1524)
				(type default)
			)
			(layer "B.SilkS")
		)
		(fp_line
			(start 0 0.635)
			(end 0 1.905)
			(stroke
				(width 0.1524)
				(type default)
			)
			(layer "B.SilkS")
		)
		(fp_line
			(start -2.54 1.4097)
			(end -2.54 1.1303)
			(stroke
				(width 0.1524)
				(type default)
			)
			(layer "B.SilkS")
		)
		(fp_line
			(start 0 3.175)
			(end 0 3.81)
			(stroke
				(width 0.1524)
				(type default)
			)
			(layer "B.SilkS")
		)
		(fp_line
			(start 0 3.81)
			(end -2.54 3.81)
			(stroke
				(width 0.1524)
				(type default)
			)
			(layer "B.SilkS")
		)
		(fp_line
			(start -2.54 3.81)
			(end -2.54 3.6703)
			(stroke
				(width 0.1524)
				(type default)
			)
			(layer "B.SilkS")
		)
		(fp_poly
			(pts
				(xy 2.285746 -0.762) (xy 2.285746 0.762) (xy 0.761746 0)
			)
			(stroke
				(width 0)
				(type default)
			)
			(fill yes)
			(layer "B.SilkS")
		)
		(fp_line
			(start 0 -1.27)
			(end 0 3.81)
			(stroke
				(width 0.1)
				(type default)
			)
			(layer "B.Fab")
		)
		(fp_line
			(start -2.54 -1.27)
			(end 0 -1.27)
			(stroke
				(width 0.1)
				(type default)
			)
			(layer "B.Fab")
		)
		(fp_line
			(start 0 3.81)
			(end -2.54 3.81)
			(stroke
				(width 0.1)
				(type default)
			)
			(layer "B.Fab")
		)
		(fp_line
			(start -2.54 3.81)
			(end -2.54 -1.27)
			(stroke
				(width 0.1)
				(type default)
			)
			(layer "B.Fab")
		)
		(fp_poly
			(pts
				(xy 0.761746 0) (xy 2.285746 -0.762) (xy 2.285746 0.762)
			)
			(stroke
				(width 0)
				(type default)
			)
			(fill yes)
			(layer "B.Fab")
		)
		(pad "1" thru_hole circle
			(at 0 0 270)
			(size 1.0033 1.0033)
			(drill 0.249936)
			(layers "*.Cu" "*.Mask")
			(remove_unused_layers no)
			(net "TDR_DIFF_100_IN6_DP")
			(clearance 0.10795)
			(padstack
				(mode front_inner_back)
				(layer "Inner"
					(shape circle)
					(size 0.8001 0.8001)
					(clearance 0.1524)
				)
				(layer "B.Cu"
					(shape circle)
					(size 1.0033 1.0033)
					(thermal_gap 0.10795)
					(clearance 0.10795)
				)
			)
		)
		(pad "2" thru_hole circle
			(at -2.54 0 270)
			(size 1.9939 1.9939)
			(drill 0.249936)
			(layers "*.Cu" "*.Mask")
			(remove_unused_layers no)
			(net "T1_GND")
			(clearance 0.10795)
			(padstack
				(mode front_inner_back)
				(layer "Inner"
					(shape circle)
					(size 0.8001 0.8001)
					(clearance 0.1524)
				)
				(layer "B.Cu"
					(shape circle)
					(size 1.9939 1.9939)
					(thermal_gap 0.10795)
					(clearance 0.10795)
				)
			)
		)
		(pad "3" thru_hole circle
			(at -2.54 2.54 270)
			(size 1.9939 1.9939)
			(drill 0.249936)
			(layers "*.Cu" "*.Mask")
			(remove_unused_layers no)
			(net "T1_GND")
			(clearance 0.10795)
			(padstack
				(mode front_inner_back)
				(layer "Inner"
					(shape circle)
					(size 0.8001 0.8001)
					(clearance 0.1524)
				)
				(layer "B.Cu"
					(shape circle)
					(size 1.9939 1.9939)
					(thermal_gap 0.10795)
					(clearance 0.10795)
				)
			)
		)
		(pad "4" thru_hole circle
			(at 0 2.54 270)
			(size 1.0033 1.0033)
			(drill 0.249936)
			(layers "*.Cu" "*.Mask")
			(remove_unused_layers no)
			(net "TDR_DIFF_100_IN6_DN")
			(clearance 0.10795)
			(padstack
				(mode front_inner_back)
				(layer "Inner"
					(shape circle)
					(size 0.8001 0.8001)
					(clearance 0.1524)
				)
				(layer "B.Cu"
					(shape circle)
					(size 1.0033 1.0033)
					(thermal_gap 0.10795)
					(clearance 0.10795)
				)
			)
		)
	)
	(footprint ""
		(layer "B.Cu")
		(at 118.370604 -294.01008)
		(property "Reference" "C345"
			(at 0 0 0)
			(layer "B.SilkS")
			(hide yes)
			(effects
				(font
					(size 1.27 1.27)
				)
				(justify mirror)
			)
		)
		(property "Value" ""
			(at 0 0 0)
			(layer "B.Fab")
			(effects
				(font
					(size 1.27 1.27)
				)
				(justify mirror)
			)
		)
		(duplicate_pad_numbers_are_jumpers no)
		(fp_line
			(start -1.524 -0.762)
			(end -1.524 0.762)
			(stroke
				(width 0.1524)
				(type default)
			)
			(layer "B.SilkS")
		)
		(fp_line
			(start -1.524 0.762)
			(end 1.524 0.762)
			(stroke
				(width 0.1524)
				(type default)
			)
			(layer "B.SilkS")
		)
		(fp_line
			(start 1.524 -0.762)
			(end -1.524 -0.762)
			(stroke
				(width 0.1524)
				(type default)
			)
			(layer "B.SilkS")
		)
		(fp_line
			(start 1.524 0.762)
			(end 1.524 -0.762)
			(stroke
				(width 0.1524)
				(type default)
			)
			(layer "B.SilkS")
		)
		(fp_line
			(start -1.1049 -0.724916)
			(end 1.1049 -0.724916)
			(stroke
				(width 0.1)
				(type default)
			)
			(layer "B.Fab")
		)
		(fp_line
			(start -1.1049 0.724916)
			(end -1.1049 -0.724916)
			(stroke
				(width 0.1)
				(type default)
			)
			(layer "B.Fab")
		)
		(fp_line
			(start 1.1049 -0.724916)
			(end 1.1049 0.724916)
			(stroke
				(width 0.1)
				(type default)
			)
			(layer "B.Fab")
		)
		(fp_line
			(start 1.1049 0.724916)
			(end -1.1049 0.724916)
			(stroke
				(width 0.1)
				(type default)
			)
			(layer "B.Fab")
		)
		(pad "1" smd rect
			(at 0.889 0)
			(size 1.016 1.27)
			(layers "B.Cu" "B.Mask" "B.Paste")
			(net "PVCCIN_CPU1")
		)
		(pad "2" smd rect
			(at -0.889 0)
			(size 1.016 1.27)
			(layers "B.Cu" "B.Mask" "B.Paste")
			(net "GND")
		)
	)
	(footprint ""
		(layer "B.Cu")
		(at 343.524332 -324.873366 -90)
		(property "Reference" "PC314_P0_1"
			(at 0 0 90)
			(layer "B.SilkS")
			(hide yes)
			(effects
				(font
					(size 1.27 1.27)
				)
				(justify mirror)
			)
		)
		(property "Value" ""
			(at 0 0 90)
			(layer "B.Fab")
			(effects
				(font
					(size 1.27 1.27)
				)
				(justify mirror)
			)
		)
		(duplicate_pad_numbers_are_jumpers no)
		(fp_line
			(start -1.524 0.762)
			(end 1.524 0.762)
			(stroke
				(width 0.1524)
				(type default)
			)
			(layer "B.SilkS")
		)
		(fp_line
			(start 1.524 0.762)
			(end 1.524 -0.762)
			(stroke
				(width 0.1524)
				(type default)
			)
			(layer "B.SilkS")
		)
		(fp_line
			(start -1.524 -0.762)
			(end -1.524 0.762)
			(stroke
				(width 0.1524)
				(type default)
			)
			(layer "B.SilkS")
		)
		(fp_line
			(start 1.524 -0.762)
			(end -1.524 -0.762)
			(stroke
				(width 0.1524)
				(type default)
			)
			(layer "B.SilkS")
		)
		(fp_line
			(start -1.1049 0.724916)
			(end -1.1049 -0.724916)
			(stroke
				(width 0.1)
				(type default)
			)
			(layer "B.Fab")
		)
		(fp_line
			(start 1.1049 0.724916)
			(end -1.1049 0.724916)
			(stroke
				(width 0.1)
				(type default)
			)
			(layer "B.Fab")
		)
		(fp_line
			(start -1.1049 -0.724916)
			(end 1.1049 -0.724916)
			(stroke
				(width 0.1)
				(type default)
			)
			(layer "B.Fab")
		)
		(fp_line
			(start 1.1049 -0.724916)
			(end 1.1049 0.724916)
			(stroke
				(width 0.1)
				(type default)
			)
			(layer "B.Fab")
		)
		(pad "1" smd rect
			(at 0.889 0 270)
			(size 1.016 1.27)
			(layers "B.Cu" "B.Mask" "B.Paste")
			(net "PVCCIN_CPU0")
		)
		(pad "2" smd rect
			(at -0.889 0 270)
			(size 1.016 1.27)
			(layers "B.Cu" "B.Mask" "B.Paste")
			(net "GND")
		)
	)
	(footprint ""
		(layer "B.Cu")
		(at 175.355758 -112.175544 180)
		(property "Reference" "C1914"
			(at 0 0 0)
			(layer "B.SilkS")
			(hide yes)
			(effects
				(font
					(size 1.27 1.27)
				)
				(justify mirror)
			)
		)
		(property "Value" ""
			(at 0 0 0)
			(layer "B.Fab")
			(effects
				(font
					(size 1.27 1.27)
				)
				(justify mirror)
			)
		)
		(duplicate_pad_numbers_are_jumpers no)
		(fp_line
			(start 0.69215 0.2921)
			(end 0.69215 -0.2921)
			(stroke
				(width 0.1524)
				(type default)
			)
			(layer "B.SilkS")
		)
		(fp_line
			(start 0.69215 -0.2921)
			(end -0.69215 -0.2921)
			(stroke
				(width 0.1524)
				(type default)
			)
			(layer "B.SilkS")
		)
		(fp_line
			(start -0.69215 0.2921)
			(end 0.69215 0.2921)
			(stroke
				(width 0.1524)
				(type default)
			)
			(layer "B.SilkS")
		)
		(fp_line
			(start -0.69215 -0.2921)
			(end -0.69215 0.2921)
			(stroke
				(width 0.1524)
				(type default)
			)
			(layer "B.SilkS")
		)
		(fp_line
			(start 0.51435 0.2794)
			(end 0.51435 -0.2794)
			(stroke
				(width 0.1)
				(type default)
			)
			(layer "B.Fab")
		)
		(fp_line
			(start 0.51435 -0.2794)
			(end -0.51435 -0.2794)
			(stroke
				(width 0.1)
				(type default)
			)
			(layer "B.Fab")
		)
		(fp_line
			(start -0.51435 0.2794)
			(end 0.51435 0.2794)
			(stroke
				(width 0.1)
				(type default)
			)
			(layer "B.Fab")
		)
		(fp_line
			(start -0.51435 -0.2794)
			(end -0.51435 0.2794)
			(stroke
				(width 0.1)
				(type default)
			)
			(layer "B.Fab")
		)
		(pad "1" smd circle
			(at 0.40005 0)
			(size 0 0)
			(layers "B.Cu" "B.Mask" "B.Paste")
			(net "P3V3_AUX_FPGA_VCCIO0")
		)
		(pad "2" smd circle
			(at -0.40005 0)
			(size 0 0)
			(layers "B.Cu" "B.Mask" "B.Paste")
			(net "GND")
		)
		(zone
			(layer "B.Cu")
			(hatch none 0.5)
			(connect_pads
				(clearance 0)
			)
			(min_thickness 0.25)
			(keepout
				(tracks not_allowed)
				(vias allowed)
				(pads allowed)
				(copperpour not_allowed)
				(footprints allowed)
			)
			(placement
				(enabled no)
				(sheetname "")
			)
			(fill
				(thermal_gap 0.5)
				(thermal_bridge_width 0.5)
				(island_removal_mode 0)
			)
			(polygon
				(pts
					(xy 175.165258 -112.263174) (xy 175.256698 -112.32134) (xy 175.456088 -112.32134) (xy 175.546258 -112.263174)
					(xy 175.546258 -112.087914) (xy 175.456088 -112.029494) (xy 175.256698 -112.029494) (xy 175.165258 -112.08766)
				)
			)
		)
	)
	(footprint ""
		(layer "B.Cu")
		(at 175.355758 -114.575336 180)
		(property "Reference" "C1932"
			(at 0 0 0)
			(layer "B.SilkS")
			(hide yes)
			(effects
				(font
					(size 1.27 1.27)
				)
				(justify mirror)
			)
		)
		(property "Value" ""
			(at 0 0 0)
			(layer "B.Fab")
			(effects
				(font
					(size 1.27 1.27)
				)
				(justify mirror)
			)
		)
		(duplicate_pad_numbers_are_jumpers no)
		(fp_line
			(start 0.69215 0.2921)
			(end 0.69215 -0.2921)
			(stroke
				(width 0.1524)
				(type default)
			)
			(layer "B.SilkS")
		)
		(fp_line
			(start 0.69215 -0.2921)
			(end -0.69215 -0.2921)
			(stroke
				(width 0.1524)
				(type default)
			)
			(layer "B.SilkS")
		)
		(fp_line
			(start -0.69215 0.2921)
			(end 0.69215 0.2921)
			(stroke
				(width 0.1524)
				(type default)
			)
			(layer "B.SilkS")
		)
		(fp_line
			(start -0.69215 -0.2921)
			(end -0.69215 0.2921)
			(stroke
				(width 0.1524)
				(type default)
			)
			(layer "B.SilkS")
		)
		(fp_line
			(start 0.51435 0.2794)
			(end 0.51435 -0.2794)
			(stroke
				(width 0.1)
				(type default)
			)
			(layer "B.Fab")
		)
		(fp_line
			(start 0.51435 -0.2794)
			(end -0.51435 -0.2794)
			(stroke
				(width 0.1)
				(type default)
			)
			(layer "B.Fab")
		)
		(fp_line
			(start -0.51435 0.2794)
			(end 0.51435 0.2794)
			(stroke
				(width 0.1)
				(type default)
			)
			(layer "B.Fab")
		)
		(fp_line
			(start -0.51435 -0.2794)
			(end -0.51435 0.2794)
			(stroke
				(width 0.1)
				(type default)
			)
			(layer "B.Fab")
		)
		(pad "1" smd circle
			(at 0.40005 0)
			(size 0 0)
			(layers "B.Cu" "B.Mask" "B.Paste")
			(net "P3V3_AUX_FPGA_VCCIO0")
		)
		(pad "2" smd circle
			(at -0.40005 0)
			(size 0 0)
			(layers "B.Cu" "B.Mask" "B.Paste")
			(net "GND")
		)
		(zone
			(layer "B.Cu")
			(hatch none 0.5)
			(connect_pads
				(clearance 0)
			)
			(min_thickness 0.25)
			(keepout
				(tracks not_allowed)
				(vias allowed)
				(pads allowed)
				(copperpour not_allowed)
				(footprints allowed)
			)
			(placement
				(enabled no)
				(sheetname "")
			)
			(fill
				(thermal_gap 0.5)
				(thermal_bridge_width 0.5)
				(island_removal_mode 0)
			)
			(polygon
				(pts
					(xy 175.165258 -114.662966) (xy 175.256698 -114.721132) (xy 175.456088 -114.721132) (xy 175.546258 -114.662966)
					(xy 175.546258 -114.487706) (xy 175.456088 -114.429286) (xy 175.256698 -114.429286) (xy 175.165258 -114.487452)
				)
			)
		)
	)
	(footprint ""
		(layer "B.Cu")
		(at 97.748598 -324.753986 -90)
		(property "Reference" "PC578_P1_1"
			(at 0 0 90)
			(layer "B.SilkS")
			(hide yes)
			(effects
				(font
					(size 1.27 1.27)
				)
				(justify mirror)
			)
		)
		(property "Value" ""
			(at 0 0 90)
			(layer "B.Fab")
			(effects
				(font
					(size 1.27 1.27)
				)
				(justify mirror)
			)
		)
		(duplicate_pad_numbers_are_jumpers no)
		(fp_line
			(start -1.524 0.762)
			(end 1.524 0.762)
			(stroke
				(width 0.1524)
				(type default)
			)
			(layer "B.SilkS")
		)
		(fp_line
			(start 1.524 0.762)
			(end 1.524 -0.762)
			(stroke
				(width 0.1524)
				(type default)
			)
			(layer "B.SilkS")
		)
		(fp_line
			(start -1.524 -0.762)
			(end -1.524 0.762)
			(stroke
				(width 0.1524)
				(type default)
			)
			(layer "B.SilkS")
		)
		(fp_line
			(start 1.524 -0.762)
			(end -1.524 -0.762)
			(stroke
				(width 0.1524)
				(type default)
			)
			(layer "B.SilkS")
		)
		(fp_line
			(start -1.1049 0.724916)
			(end -1.1049 -0.724916)
			(stroke
				(width 0.1)
				(type default)
			)
			(layer "B.Fab")
		)
		(fp_line
			(start 1.1049 0.724916)
			(end -1.1049 0.724916)
			(stroke
				(width 0.1)
				(type default)
			)
			(layer "B.Fab")
		)
		(fp_line
			(start -1.1049 -0.724916)
			(end 1.1049 -0.724916)
			(stroke
				(width 0.1)
				(type default)
			)
			(layer "B.Fab")
		)
		(fp_line
			(start 1.1049 -0.724916)
			(end 1.1049 0.724916)
			(stroke
				(width 0.1)
				(type default)
			)
			(layer "B.Fab")
		)
		(pad "1" smd rect
			(at 0.889 0 270)
			(size 1.016 1.27)
			(layers "B.Cu" "B.Mask" "B.Paste")
			(net "PVCCIN_CPU1")
		)
		(pad "2" smd rect
			(at -0.889 0 270)
			(size 1.016 1.27)
			(layers "B.Cu" "B.Mask" "B.Paste")
			(net "GND")
		)
	)
	(footprint ""
		(layer "B.Cu")
		(at 285.462726 -193.691256 -90)
		(property "Reference" "R836"
			(at 0 0 90)
			(layer "B.SilkS")
			(hide yes)
			(effects
				(font
					(size 1.27 1.27)
				)
				(justify mirror)
			)
		)
		(property "Value" ""
			(at 0 0 90)
			(layer "B.Fab")
			(effects
				(font
					(size 1.27 1.27)
				)
				(justify mirror)
			)
		)
		(duplicate_pad_numbers_are_jumpers no)
		(fp_line
			(start -0.7874 0.4064)
			(end 0.7874 0.4064)
			(stroke
				(width 0.1524)
				(type default)
			)
			(layer "B.SilkS")
		)
		(fp_line
			(start 0.7874 0.4064)
			(end 0.7874 -0.4064)
			(stroke
				(width 0.1524)
				(type default)
			)
			(layer "B.SilkS")
		)
		(fp_line
			(start -0.7874 -0.4064)
			(end -0.7874 0.4064)
			(stroke
				(width 0.1524)
				(type default)
			)
			(layer "B.SilkS")
		)
		(fp_line
			(start 0.7874 -0.4064)
			(end -0.7874 -0.4064)
			(stroke
				(width 0.1524)
				(type default)
			)
			(layer "B.SilkS")
		)
		(fp_line
			(start -0.67945 0.3048)
			(end -0.120396 0.3048)
			(stroke
				(width 0.1)
				(type default)
			)
			(layer "B.Fab")
		)
		(fp_line
			(start -0.120396 0.3048)
			(end -0.120396 0.2794)
			(stroke
				(width 0.1)
				(type default)
			)
			(layer "B.Fab")
		)
		(fp_line
			(start 0.12065 0.3048)
			(end 0.67945 0.3048)
			(stroke
				(width 0.1)
				(type default)
			)
			(layer "B.Fab")
		)
		(fp_line
			(start 0.67945 0.3048)
			(end 0.67945 -0.305054)
			(stroke
				(width 0.1)
				(type default)
			)
			(layer "B.Fab")
		)
		(fp_line
			(start -0.120396 0.2794)
			(end 0.12065 0.2794)
			(stroke
				(width 0.1)
				(type default)
			)
			(layer "B.Fab")
		)
		(fp_line
			(start 0.12065 0.2794)
			(end 0.12065 0.3048)
			(stroke
				(width 0.1)
				(type default)
			)
			(layer "B.Fab")
		)
		(fp_line
			(start -0.12065 -0.2794)
			(end -0.12065 -0.3048)
			(stroke
				(width 0.1)
				(type default)
			)
			(layer "B.Fab")
		)
		(fp_line
			(start 0.12065 -0.2794)
			(end -0.12065 -0.2794)
			(stroke
				(width 0.1)
				(type default)
			)
			(layer "B.Fab")
		)
		(fp_line
			(start -0.67945 -0.3048)
			(end -0.67945 0.3048)
			(stroke
				(width 0.1)
				(type default)
			)
			(layer "B.Fab")
		)
		(fp_line
			(start -0.12065 -0.3048)
			(end -0.67945 -0.3048)
			(stroke
				(width 0.1)
				(type default)
			)
			(layer "B.Fab")
		)
		(fp_line
			(start 0.12065 -0.305054)
			(end 0.12065 -0.2794)
			(stroke
				(width 0.1)
				(type default)
			)
			(layer "B.Fab")
		)
		(fp_line
			(start 0.67945 -0.305054)
			(end 0.12065 -0.305054)
			(stroke
				(width 0.1)
				(type default)
			)
			(layer "B.Fab")
		)
		(pad "1" smd circle
			(at 0.40005 0 90)
			(size 0 0)
			(layers "B.Cu" "B.Mask" "B.Paste")
			(net "RST_PLD_CPU0_DRAM_AB_N")
		)
		(pad "2" smd circle
			(at -0.40005 0 90)
			(size 0 0)
			(layers "B.Cu" "B.Mask" "B.Paste")
			(net "RST_M_AB_CPU0_FPGA_N")
		)
	)
	(footprint ""
		(layer "B.Cu")
		(at 245.25478 -396.43304 90)
		(property "Reference" "PC1751"
			(at 0 0 90)
			(layer "B.SilkS")
			(hide yes)
			(effects
				(font
					(size 1.27 1.27)
				)
				(justify mirror)
			)
		)
		(property "Value" ""
			(at 0 0 90)
			(layer "B.Fab")
			(effects
				(font
					(size 1.27 1.27)
				)
				(justify mirror)
			)
		)
		(duplicate_pad_numbers_are_jumpers no)
		(fp_line
			(start 0.7874 -0.4064)
			(end -0.7874 -0.4064)
			(stroke
				(width 0.1524)
				(type default)
			)
			(layer "B.SilkS")
		)
		(fp_line
			(start -0.7874 -0.4064)
			(end -0.7874 0.4064)
			(stroke
				(width 0.1524)
				(type default)
			)
			(layer "B.SilkS")
		)
		(fp_line
			(start 0.7874 0.4064)
			(end 0.7874 -0.4064)
			(stroke
				(width 0.1524)
				(type default)
			)
			(layer "B.SilkS")
		)
		(fp_line
			(start -0.7874 0.4064)
			(end 0.7874 0.4064)
			(stroke
				(width 0.1524)
				(type default)
			)
			(layer "B.SilkS")
		)
		(fp_line
			(start 0.67945 -0.305054)
			(end 0.12065 -0.305054)
			(stroke
				(width 0.1)
				(type default)
			)
			(layer "B.Fab")
		)
		(fp_line
			(start 0.12065 -0.305054)
			(end 0.12065 -0.2794)
			(stroke
				(width 0.1)
				(type default)
			)
			(layer "B.Fab")
		)
		(fp_line
			(start -0.12065 -0.3048)
			(end -0.67945 -0.3048)
			(stroke
				(width 0.1)
				(type default)
			)
			(layer "B.Fab")
		)
		(fp_line
			(start -0.67945 -0.3048)
			(end -0.67945 0.3048)
			(stroke
				(width 0.1)
				(type default)
			)
			(layer "B.Fab")
		)
		(fp_line
			(start 0.12065 -0.2794)
			(end -0.12065 -0.2794)
			(stroke
				(width 0.1)
				(type default)
			)
			(layer "B.Fab")
		)
		(fp_line
			(start -0.12065 -0.2794)
			(end -0.12065 -0.3048)
			(stroke
				(width 0.1)
				(type default)
			)
			(layer "B.Fab")
		)
		(fp_line
			(start 0.12065 0.2794)
			(end 0.12065 0.3048)
			(stroke
				(width 0.1)
				(type default)
			)
			(layer "B.Fab")
		)
		(fp_line
			(start -0.120396 0.2794)
			(end 0.12065 0.2794)
			(stroke
				(width 0.1)
				(type default)
			)
			(layer "B.Fab")
		)
		(fp_line
			(start 0.67945 0.3048)
			(end 0.67945 -0.305054)
			(stroke
				(width 0.1)
				(type default)
			)
			(layer "B.Fab")
		)
		(fp_line
			(start 0.12065 0.3048)
			(end 0.67945 0.3048)
			(stroke
				(width 0.1)
				(type default)
			)
			(layer "B.Fab")
		)
		(fp_line
			(start -0.120396 0.3048)
			(end -0.120396 0.2794)
			(stroke
				(width 0.1)
				(type default)
			)
			(layer "B.Fab")
		)
		(fp_line
			(start -0.67945 0.3048)
			(end -0.120396 0.3048)
			(stroke
				(width 0.1)
				(type default)
			)
			(layer "B.Fab")
		)
		(pad "1" smd circle
			(at 0.40005 0 270)
			(size 0 0)
			(layers "B.Cu" "B.Mask" "B.Paste")
			(net "P12V_HSC_GATE_RC")
		)
		(pad "2" smd circle
			(at -0.40005 0 270)
			(size 0 0)
			(layers "B.Cu" "B.Mask" "B.Paste")
			(net "P12V_HSC_GATE2")
		)
	)
	(footprint ""
		(layer "B.Cu")
		(at 193.38163 -127.422148 180)
		(property "Reference" "R4519"
			(at 0 0 0)
			(layer "B.SilkS")
			(hide yes)
			(effects
				(font
					(size 1.27 1.27)
				)
				(justify mirror)
			)
		)
		(property "Value" ""
			(at 0 0 0)
			(layer "B.Fab")
			(effects
				(font
					(size 1.27 1.27)
				)
				(justify mirror)
			)
		)
		(duplicate_pad_numbers_are_jumpers no)
		(fp_line
			(start 0.7874 0.4064)
			(end 0.7874 -0.4064)
			(stroke
				(width 0.1524)
				(type default)
			)
			(layer "B.SilkS")
		)
		(fp_line
			(start 0.7874 -0.4064)
			(end -0.7874 -0.4064)
			(stroke
				(width 0.1524)
				(type default)
			)
			(layer "B.SilkS")
		)
		(fp_line
			(start -0.7874 0.4064)
			(end 0.7874 0.4064)
			(stroke
				(width 0.1524)
				(type default)
			)
			(layer "B.SilkS")
		)
		(fp_line
			(start -0.7874 -0.4064)
			(end -0.7874 0.4064)
			(stroke
				(width 0.1524)
				(type default)
			)
			(layer "B.SilkS")
		)
		(fp_line
			(start 0.67945 0.3048)
			(end 0.67945 -0.305054)
			(stroke
				(width 0.1)
				(type default)
			)
			(layer "B.Fab")
		)
		(fp_line
			(start 0.67945 -0.305054)
			(end 0.12065 -0.305054)
			(stroke
				(width 0.1)
				(type default)
			)
			(layer "B.Fab")
		)
		(fp_line
			(start 0.12065 0.3048)
			(end 0.67945 0.3048)
			(stroke
				(width 0.1)
				(type default)
			)
			(layer "B.Fab")
		)
		(fp_line
			(start 0.12065 0.2794)
			(end 0.12065 0.3048)
			(stroke
				(width 0.1)
				(type default)
			)
			(layer "B.Fab")
		)
		(fp_line
			(start 0.12065 -0.2794)
			(end -0.12065 -0.2794)
			(stroke
				(width 0.1)
				(type default)
			)
			(layer "B.Fab")
		)
		(fp_line
			(start 0.12065 -0.305054)
			(end 0.12065 -0.2794)
			(stroke
				(width 0.1)
				(type default)
			)
			(layer "B.Fab")
		)
		(fp_line
			(start -0.120396 0.3048)
			(end -0.120396 0.2794)
			(stroke
				(width 0.1)
				(type default)
			)
			(layer "B.Fab")
		)
		(fp_line
			(start -0.120396 0.2794)
			(end 0.12065 0.2794)
			(stroke
				(width 0.1)
				(type default)
			)
			(layer "B.Fab")
		)
		(fp_line
			(start -0.12065 -0.2794)
			(end -0.12065 -0.3048)
			(stroke
				(width 0.1)
				(type default)
			)
			(layer "B.Fab")
		)
		(fp_line
			(start -0.12065 -0.3048)
			(end -0.67945 -0.3048)
			(stroke
				(width 0.1)
				(type default)
			)
			(layer "B.Fab")
		)
		(fp_line
			(start -0.67945 0.3048)
			(end -0.120396 0.3048)
			(stroke
				(width 0.1)
				(type default)
			)
			(layer "B.Fab")
		)
		(fp_line
			(start -0.67945 -0.3048)
			(end -0.67945 0.3048)
			(stroke
				(width 0.1)
				(type default)
			)
			(layer "B.Fab")
		)
		(pad "1" smd circle
			(at 0.40005 0)
			(size 0 0)
			(layers "B.Cu" "B.Mask" "B.Paste")
			(net "P3V3")
		)
		(pad "2" smd circle
			(at -0.40005 0)
			(size 0 0)
			(layers "B.Cu" "B.Mask" "B.Paste")
			(net "CLK_GPU_1_OE_N")
		)
	)
	(footprint ""
		(layer "B.Cu")
		(at 62.53988 -8.981948 90)
		(property "Reference" "C1837"
			(at 0 0 90)
			(layer "B.SilkS")
			(hide yes)
			(effects
				(font
					(size 1.27 1.27)
				)
				(justify mirror)
			)
		)
		(property "Value" ""
			(at 0 0 90)
			(layer "B.Fab")
			(effects
				(font
					(size 1.27 1.27)
				)
				(justify mirror)
			)
		)
		(duplicate_pad_numbers_are_jumpers no)
		(fp_line
			(start 0.7874 -0.4064)
			(end -0.7874 -0.4064)
			(stroke
				(width 0.1524)
				(type default)
			)
			(layer "B.SilkS")
		)
		(fp_line
			(start -0.7874 -0.4064)
			(end -0.7874 0.4064)
			(stroke
				(width 0.1524)
				(type default)
			)
			(layer "B.SilkS")
		)
		(fp_line
			(start 0.7874 0.4064)
			(end 0.7874 -0.4064)
			(stroke
				(width 0.1524)
				(type default)
			)
			(layer "B.SilkS")
		)
		(fp_line
			(start -0.7874 0.4064)
			(end 0.7874 0.4064)
			(stroke
				(width 0.1524)
				(type default)
			)
			(layer "B.SilkS")
		)
		(fp_line
			(start 0.67945 -0.305054)
			(end 0.12065 -0.305054)
			(stroke
				(width 0.1)
				(type default)
			)
			(layer "B.Fab")
		)
		(fp_line
			(start 0.12065 -0.305054)
			(end 0.12065 -0.2794)
			(stroke
				(width 0.1)
				(type default)
			)
			(layer "B.Fab")
		)
		(fp_line
			(start -0.12065 -0.3048)
			(end -0.67945 -0.3048)
			(stroke
				(width 0.1)
				(type default)
			)
			(layer "B.Fab")
		)
		(fp_line
			(start -0.67945 -0.3048)
			(end -0.67945 0.3048)
			(stroke
				(width 0.1)
				(type default)
			)
			(layer "B.Fab")
		)
		(fp_line
			(start 0.12065 -0.2794)
			(end -0.12065 -0.2794)
			(stroke
				(width 0.1)
				(type default)
			)
			(layer "B.Fab")
		)
		(fp_line
			(start -0.12065 -0.2794)
			(end -0.12065 -0.3048)
			(stroke
				(width 0.1)
				(type default)
			)
			(layer "B.Fab")
		)
		(fp_line
			(start 0.12065 0.2794)
			(end 0.12065 0.3048)
			(stroke
				(width 0.1)
				(type default)
			)
			(layer "B.Fab")
		)
		(fp_line
			(start -0.120396 0.2794)
			(end 0.12065 0.2794)
			(stroke
				(width 0.1)
				(type default)
			)
			(layer "B.Fab")
		)
		(fp_line
			(start 0.67945 0.3048)
			(end 0.67945 -0.305054)
			(stroke
				(width 0.1)
				(type default)
			)
			(layer "B.Fab")
		)
		(fp_line
			(start 0.12065 0.3048)
			(end 0.67945 0.3048)
			(stroke
				(width 0.1)
				(type default)
			)
			(layer "B.Fab")
		)
		(fp_line
			(start -0.120396 0.3048)
			(end -0.120396 0.2794)
			(stroke
				(width 0.1)
				(type default)
			)
			(layer "B.Fab")
		)
		(fp_line
			(start -0.67945 0.3048)
			(end -0.120396 0.3048)
			(stroke
				(width 0.1)
				(type default)
			)
			(layer "B.Fab")
		)
		(pad "1" smd circle
			(at 0.40005 0 270)
			(size 0 0)
			(layers "B.Cu" "B.Mask" "B.Paste")
			(net "P3V3_OCP_V3_2")
		)
		(pad "2" smd circle
			(at -0.40005 0 270)
			(size 0 0)
			(layers "B.Cu" "B.Mask" "B.Paste")
			(net "GND")
		)
	)
	(footprint ""
		(layer "B.Cu")
		(at 260.731508 8.003794 180)
		(property "Reference" "J118"
			(at 4.345178 -1.648206 270)
			(unlocked yes)
			(layer "B.SilkS")
			(effects
				(font
					(size 0.7874 0.5842)
					(thickness 0.1524)
				)
				(justify left mirror)
			)
		)
		(property "Value" ""
			(at 0 0 0)
			(layer "B.Fab")
			(effects
				(font
					(size 1.27 1.27)
				)
				(justify mirror)
			)
		)
		(duplicate_pad_numbers_are_jumpers no)
		(fp_line
			(start 1.2192 2.1082)
			(end 1.2192 -2.1082)
			(stroke
				(width 0.1524)
				(type default)
			)
			(layer "B.SilkS")
		)
		(fp_line
			(start 1.2192 -2.1082)
			(end -1.2192 -2.1082)
			(stroke
				(width 0.1524)
				(type default)
			)
			(layer "B.SilkS")
		)
		(fp_line
			(start -1.2192 2.1082)
			(end 1.2192 2.1082)
			(stroke
				(width 0.1524)
				(type default)
			)
			(layer "B.SilkS")
		)
		(fp_line
			(start -1.2192 -2.1082)
			(end -1.2192 2.1082)
			(stroke
				(width 0.1524)
				(type default)
			)
			(layer "B.SilkS")
		)
		(pad "" np_thru_hole circle
			(at -3.4671 -1.27 90)
			(size 1.0414 1.0414)
			(drill 1.0414)
			(layers "*.Cu" "*.Mask")
			(clearance 0.381)
			(thermal_gap 0.381)
		)
		(pad "" np_thru_hole circle
			(at -3.4671 1.27 90)
			(size 1.0414 1.0414)
			(drill 1.0414)
			(layers "*.Cu" "*.Mask")
			(clearance 0.381)
			(thermal_gap 0.381)
		)
		(pad "" np_thru_hole circle
			(at 2.8829 -1.27 90)
			(size 1.0414 1.0414)
			(drill 1.0414)
			(layers "*.Cu" "*.Mask")
			(clearance 0.381)
			(thermal_gap 0.381)
		)
		(pad "" np_thru_hole circle
			(at 2.8829 1.27 90)
			(size 1.0414 1.0414)
			(drill 1.0414)
			(layers "*.Cu" "*.Mask")
			(clearance 0.381)
			(thermal_gap 0.381)
		)
		(pad "1" smd rect
			(at -0.8255 -0.249936 90)
			(size 0.3048 0.508)
			(layers "B.Cu" "B.Mask" "B.Paste")
			(net "DELTA_L_85_10INCH_IN5_DP")
		)
		(pad "2" smd rect
			(at -0.8255 0.249936 90)
			(size 0.3048 0.508)
			(layers "B.Cu" "B.Mask" "B.Paste")
			(net "DELTA_L_85_10INCH_IN5_DN")
		)
		(pad "3" smd circle
			(at 0 0)
			(size 0 0)
			(layers "B.Cu" "B.Mask" "B.Paste")
			(net "DELTA_L_GND_1")
		)
		(zone
			(layers "F.Cu" "B.Cu" "In1.Cu" "In2.Cu" "In3.Cu" "In4.Cu" "In5.Cu" "In6.Cu"
				"In7.Cu" "In8.Cu" "In9.Cu" "In10.Cu" "In11.Cu" "In12.Cu" "In13.Cu" "In14.Cu"
				"In15.Cu" "In16.Cu"
			)
			(hatch none 0.5)
			(connect_pads
				(clearance 0)
			)
			(min_thickness 0.25)
			(keepout
				(tracks not_allowed)
				(vias allowed)
				(pads allowed)
				(copperpour not_allowed)
				(footprints allowed)
			)
			(placement
				(enabled no)
				(sheetname "")
			)
			(fill
				(thermal_gap 0.5)
				(thermal_bridge_width 0.5)
				(island_removal_mode 0)
			)
			(polygon
				(pts
					(arc
						(start 258.775708 6.733794)
						(mid 256.921508 6.733794)
						(end 258.775708 6.733794)
					)
				)
			)
		)
		(zone
			(layers "F.Cu" "B.Cu" "In1.Cu" "In2.Cu" "In3.Cu" "In4.Cu" "In5.Cu" "In6.Cu"
				"In7.Cu" "In8.Cu" "In9.Cu" "In10.Cu" "In11.Cu" "In12.Cu" "In13.Cu" "In14.Cu"
				"In15.Cu" "In16.Cu"
			)
			(hatch none 0.5)
			(connect_pads
				(clearance 0)
			)
			(min_thickness 0.25)
			(keepout
				(tracks not_allowed)
				(vias allowed)
				(pads allowed)
				(copperpour not_allowed)
				(footprints allowed)
			)
			(placement
				(enabled no)
				(sheetname "")
			)
			(fill
				(thermal_gap 0.5)
				(thermal_bridge_width 0.5)
				(island_removal_mode 0)
			)
			(polygon
				(pts
					(arc
						(start 258.775708 9.273794)
						(mid 256.921508 9.273794)
						(end 258.775708 9.273794)
					)
				)
			)
		)
		(zone
			(layers "F.Cu" "B.Cu" "In1.Cu" "In2.Cu" "In3.Cu" "In4.Cu" "In5.Cu" "In6.Cu"
				"In7.Cu" "In8.Cu" "In9.Cu" "In10.Cu" "In11.Cu" "In12.Cu" "In13.Cu" "In14.Cu"
				"In15.Cu" "In16.Cu"
			)
			(hatch none 0.5)
			(connect_pads
				(clearance 0)
			)
			(min_thickness 0.25)
			(keepout
				(tracks not_allowed)
				(vias allowed)
				(pads allowed)
				(copperpour not_allowed)
				(footprints allowed)
			)
			(placement
				(enabled no)
				(sheetname "")
			)
			(fill
				(thermal_gap 0.5)
				(thermal_bridge_width 0.5)
				(island_removal_mode 0)
			)
			(polygon
				(pts
					(arc
						(start 265.125708 6.733794)
						(mid 263.271508 6.733794)
						(end 265.125708 6.733794)
					)
				)
			)
		)
		(zone
			(layers "F.Cu" "B.Cu" "In1.Cu" "In2.Cu" "In3.Cu" "In4.Cu" "In5.Cu" "In6.Cu"
				"In7.Cu" "In8.Cu" "In9.Cu" "In10.Cu" "In11.Cu" "In12.Cu" "In13.Cu" "In14.Cu"
				"In15.Cu" "In16.Cu"
			)
			(hatch none 0.5)
			(connect_pads
				(clearance 0)
			)
			(min_thickness 0.25)
			(keepout
				(tracks not_allowed)
				(vias allowed)
				(pads allowed)
				(copperpour not_allowed)
				(footprints allowed)
			)
			(placement
				(enabled no)
				(sheetname "")
			)
			(fill
				(thermal_gap 0.5)
				(thermal_bridge_width 0.5)
				(island_removal_mode 0)
			)
			(polygon
				(pts
					(arc
						(start 265.125708 9.273794)
						(mid 263.271508 9.273794)
						(end 265.125708 9.273794)
					)
				)
			)
		)
		(zone
			(layer "B.Cu")
			(hatch none 0.5)
			(connect_pads
				(clearance 0)
			)
			(min_thickness 0.25)
			(keepout
				(tracks not_allowed)
				(vias allowed)
				(pads allowed)
				(copperpour not_allowed)
				(footprints allowed)
			)
			(placement
				(enabled no)
				(sheetname "")
			)
			(fill
				(thermal_gap 0.5)
				(thermal_bridge_width 0.5)
				(island_removal_mode 0)
			)
			(polygon
				(pts
					(xy 261.849108 8.552434) (xy 261.849108 8.45693) (xy 261.252208 8.45693) (xy 261.252208 8.05053)
					(xy 261.849108 8.05053) (xy 261.849108 7.957058) (xy 261.252208 7.957058) (xy 261.252208 7.550658)
					(xy 261.849108 7.550658) (xy 261.849108 7.455154) (xy 261.150608 7.455154) (xy 261.150608 8.552434)
				)
			)
		)
	)
	(footprint ""
		(layer "B.Cu")
		(at 433.273962 -317.102998 90)
		(property "Reference" "R2492"
			(at 0 0 90)
			(layer "B.SilkS")
			(hide yes)
			(effects
				(font
					(size 1.27 1.27)
				)
				(justify mirror)
			)
		)
		(property "Value" ""
			(at 0 0 90)
			(layer "B.Fab")
			(effects
				(font
					(size 1.27 1.27)
				)
				(justify mirror)
			)
		)
		(duplicate_pad_numbers_are_jumpers no)
		(fp_line
			(start 0.7874 -0.4064)
			(end -0.7874 -0.4064)
			(stroke
				(width 0.1524)
				(type default)
			)
			(layer "B.SilkS")
		)
		(fp_line
			(start -0.7874 -0.4064)
			(end -0.7874 0.4064)
			(stroke
				(width 0.1524)
				(type default)
			)
			(layer "B.SilkS")
		)
		(fp_line
			(start 0.7874 0.4064)
			(end 0.7874 -0.4064)
			(stroke
				(width 0.1524)
				(type default)
			)
			(layer "B.SilkS")
		)
		(fp_line
			(start -0.7874 0.4064)
			(end 0.7874 0.4064)
			(stroke
				(width 0.1524)
				(type default)
			)
			(layer "B.SilkS")
		)
		(fp_line
			(start 0.67945 -0.305054)
			(end 0.12065 -0.305054)
			(stroke
				(width 0.1)
				(type default)
			)
			(layer "B.Fab")
		)
		(fp_line
			(start 0.12065 -0.305054)
			(end 0.12065 -0.2794)
			(stroke
				(width 0.1)
				(type default)
			)
			(layer "B.Fab")
		)
		(fp_line
			(start -0.12065 -0.3048)
			(end -0.67945 -0.3048)
			(stroke
				(width 0.1)
				(type default)
			)
			(layer "B.Fab")
		)
		(fp_line
			(start -0.67945 -0.3048)
			(end -0.67945 0.3048)
			(stroke
				(width 0.1)
				(type default)
			)
			(layer "B.Fab")
		)
		(fp_line
			(start 0.12065 -0.2794)
			(end -0.12065 -0.2794)
			(stroke
				(width 0.1)
				(type default)
			)
			(layer "B.Fab")
		)
		(fp_line
			(start -0.12065 -0.2794)
			(end -0.12065 -0.3048)
			(stroke
				(width 0.1)
				(type default)
			)
			(layer "B.Fab")
		)
		(fp_line
			(start 0.12065 0.2794)
			(end 0.12065 0.3048)
			(stroke
				(width 0.1)
				(type default)
			)
			(layer "B.Fab")
		)
		(fp_line
			(start -0.120396 0.2794)
			(end 0.12065 0.2794)
			(stroke
				(width 0.1)
				(type default)
			)
			(layer "B.Fab")
		)
		(fp_line
			(start 0.67945 0.3048)
			(end 0.67945 -0.305054)
			(stroke
				(width 0.1)
				(type default)
			)
			(layer "B.Fab")
		)
		(fp_line
			(start 0.12065 0.3048)
			(end 0.67945 0.3048)
			(stroke
				(width 0.1)
				(type default)
			)
			(layer "B.Fab")
		)
		(fp_line
			(start -0.120396 0.3048)
			(end -0.120396 0.2794)
			(stroke
				(width 0.1)
				(type default)
			)
			(layer "B.Fab")
		)
		(fp_line
			(start -0.67945 0.3048)
			(end -0.120396 0.3048)
			(stroke
				(width 0.1)
				(type default)
			)
			(layer "B.Fab")
		)
		(pad "1" smd circle
			(at 0.40005 0 270)
			(size 0 0)
			(layers "B.Cu" "B.Mask" "B.Paste")
			(net "PWRGD_FAIL_CPU0_EF")
		)
		(pad "2" smd circle
			(at -0.40005 0 270)
			(size 0 0)
			(layers "B.Cu" "B.Mask" "B.Paste")
			(net "PWRGD_FAIL_CPU0_EF_R1")
		)
	)
	(footprint ""
		(layer "B.Cu")
		(at 160.28924 -12.774168 90)
		(property "Reference" "R3113"
			(at 0 0 90)
			(layer "B.SilkS")
			(hide yes)
			(effects
				(font
					(size 1.27 1.27)
				)
				(justify mirror)
			)
		)
		(property "Value" ""
			(at 0 0 90)
			(layer "B.Fab")
			(effects
				(font
					(size 1.27 1.27)
				)
				(justify mirror)
			)
		)
		(duplicate_pad_numbers_are_jumpers no)
		(fp_line
			(start 0.7874 -0.4064)
			(end -0.7874 -0.4064)
			(stroke
				(width 0.1524)
				(type default)
			)
			(layer "B.SilkS")
		)
		(fp_line
			(start -0.7874 -0.4064)
			(end -0.7874 0.4064)
			(stroke
				(width 0.1524)
				(type default)
			)
			(layer "B.SilkS")
		)
		(fp_line
			(start 0.7874 0.4064)
			(end 0.7874 -0.4064)
			(stroke
				(width 0.1524)
				(type default)
			)
			(layer "B.SilkS")
		)
		(fp_line
			(start -0.7874 0.4064)
			(end 0.7874 0.4064)
			(stroke
				(width 0.1524)
				(type default)
			)
			(layer "B.SilkS")
		)
		(fp_line
			(start 0.67945 -0.305054)
			(end 0.12065 -0.305054)
			(stroke
				(width 0.1)
				(type default)
			)
			(layer "B.Fab")
		)
		(fp_line
			(start 0.12065 -0.305054)
			(end 0.12065 -0.2794)
			(stroke
				(width 0.1)
				(type default)
			)
			(layer "B.Fab")
		)
		(fp_line
			(start -0.12065 -0.3048)
			(end -0.67945 -0.3048)
			(stroke
				(width 0.1)
				(type default)
			)
			(layer "B.Fab")
		)
		(fp_line
			(start -0.67945 -0.3048)
			(end -0.67945 0.3048)
			(stroke
				(width 0.1)
				(type default)
			)
			(layer "B.Fab")
		)
		(fp_line
			(start 0.12065 -0.2794)
			(end -0.12065 -0.2794)
			(stroke
				(width 0.1)
				(type default)
			)
			(layer "B.Fab")
		)
		(fp_line
			(start -0.12065 -0.2794)
			(end -0.12065 -0.3048)
			(stroke
				(width 0.1)
				(type default)
			)
			(layer "B.Fab")
		)
		(fp_line
			(start 0.12065 0.2794)
			(end 0.12065 0.3048)
			(stroke
				(width 0.1)
				(type default)
			)
			(layer "B.Fab")
		)
		(fp_line
			(start -0.120396 0.2794)
			(end 0.12065 0.2794)
			(stroke
				(width 0.1)
				(type default)
			)
			(layer "B.Fab")
		)
		(fp_line
			(start 0.67945 0.3048)
			(end 0.67945 -0.305054)
			(stroke
				(width 0.1)
				(type default)
			)
			(layer "B.Fab")
		)
		(fp_line
			(start 0.12065 0.3048)
			(end 0.67945 0.3048)
			(stroke
				(width 0.1)
				(type default)
			)
			(layer "B.Fab")
		)
		(fp_line
			(start -0.120396 0.3048)
			(end -0.120396 0.2794)
			(stroke
				(width 0.1)
				(type default)
			)
			(layer "B.Fab")
		)
		(fp_line
			(start -0.67945 0.3048)
			(end -0.120396 0.3048)
			(stroke
				(width 0.1)
				(type default)
			)
			(layer "B.Fab")
		)
		(pad "1" smd circle
			(at 0.40005 0 270)
			(size 0 0)
			(layers "B.Cu" "B.Mask" "B.Paste")
			(net "SMB_FAN_3V3AUX_SCL")
		)
		(pad "2" smd circle
			(at -0.40005 0 270)
			(size 0 0)
			(layers "B.Cu" "B.Mask" "B.Paste")
			(net "SMB_FAN_3V3AUX_R_SCL")
		)
	)
	(footprint ""
		(layer "B.Cu")
		(at 85.9282 -338.137246 -90)
		(property "Reference" "PR293"
			(at 0 0 90)
			(layer "B.SilkS")
			(hide yes)
			(effects
				(font
					(size 1.27 1.27)
				)
				(justify mirror)
			)
		)
		(property "Value" ""
			(at 0 0 90)
			(layer "B.Fab")
			(effects
				(font
					(size 1.27 1.27)
				)
				(justify mirror)
			)
		)
		(duplicate_pad_numbers_are_jumpers no)
		(fp_line
			(start -0.7874 0.4064)
			(end 0.7874 0.4064)
			(stroke
				(width 0.1524)
				(type default)
			)
			(layer "B.SilkS")
		)
		(fp_line
			(start 0.7874 0.4064)
			(end 0.7874 -0.4064)
			(stroke
				(width 0.1524)
				(type default)
			)
			(layer "B.SilkS")
		)
		(fp_line
			(start -0.7874 -0.4064)
			(end -0.7874 0.4064)
			(stroke
				(width 0.1524)
				(type default)
			)
			(layer "B.SilkS")
		)
		(fp_line
			(start 0.7874 -0.4064)
			(end -0.7874 -0.4064)
			(stroke
				(width 0.1524)
				(type default)
			)
			(layer "B.SilkS")
		)
		(fp_line
			(start -0.67945 0.3048)
			(end -0.120396 0.3048)
			(stroke
				(width 0.1)
				(type default)
			)
			(layer "B.Fab")
		)
		(fp_line
			(start -0.120396 0.3048)
			(end -0.120396 0.2794)
			(stroke
				(width 0.1)
				(type default)
			)
			(layer "B.Fab")
		)
		(fp_line
			(start 0.12065 0.3048)
			(end 0.67945 0.3048)
			(stroke
				(width 0.1)
				(type default)
			)
			(layer "B.Fab")
		)
		(fp_line
			(start 0.67945 0.3048)
			(end 0.67945 -0.305054)
			(stroke
				(width 0.1)
				(type default)
			)
			(layer "B.Fab")
		)
		(fp_line
			(start -0.120396 0.2794)
			(end 0.12065 0.2794)
			(stroke
				(width 0.1)
				(type default)
			)
			(layer "B.Fab")
		)
		(fp_line
			(start 0.12065 0.2794)
			(end 0.12065 0.3048)
			(stroke
				(width 0.1)
				(type default)
			)
			(layer "B.Fab")
		)
		(fp_line
			(start -0.12065 -0.2794)
			(end -0.12065 -0.3048)
			(stroke
				(width 0.1)
				(type default)
			)
			(layer "B.Fab")
		)
		(fp_line
			(start 0.12065 -0.2794)
			(end -0.12065 -0.2794)
			(stroke
				(width 0.1)
				(type default)
			)
			(layer "B.Fab")
		)
		(fp_line
			(start -0.67945 -0.3048)
			(end -0.67945 0.3048)
			(stroke
				(width 0.1)
				(type default)
			)
			(layer "B.Fab")
		)
		(fp_line
			(start -0.12065 -0.3048)
			(end -0.67945 -0.3048)
			(stroke
				(width 0.1)
				(type default)
			)
			(layer "B.Fab")
		)
		(fp_line
			(start 0.12065 -0.305054)
			(end 0.12065 -0.2794)
			(stroke
				(width 0.1)
				(type default)
			)
			(layer "B.Fab")
		)
		(fp_line
			(start 0.67945 -0.305054)
			(end 0.12065 -0.305054)
			(stroke
				(width 0.1)
				(type default)
			)
			(layer "B.Fab")
		)
		(pad "1" smd circle
			(at 0.40005 0 90)
			(size 0 0)
			(layers "B.Cu" "B.Mask" "B.Paste")
			(net "PVCCIN_CPU1_PVCC")
		)
		(pad "2" smd circle
			(at -0.40005 0 90)
			(size 0 0)
			(layers "B.Cu" "B.Mask" "B.Paste")
			(net "PVCCIN_CPU1_VDD6")
		)
	)
	(footprint ""
		(layer "B.Cu")
		(at 17.779492 -97.342198 90)
		(property "Reference" "C2040"
			(at 0 0 90)
			(layer "B.SilkS")
			(hide yes)
			(effects
				(font
					(size 1.27 1.27)
				)
				(justify mirror)
			)
		)
		(property "Value" ""
			(at 0 0 90)
			(layer "B.Fab")
			(effects
				(font
					(size 1.27 1.27)
				)
				(justify mirror)
			)
		)
		(duplicate_pad_numbers_are_jumpers no)
		(fp_line
			(start 0.7874 -0.4064)
			(end -0.7874 -0.4064)
			(stroke
				(width 0.1524)
				(type default)
			)
			(layer "B.SilkS")
		)
		(fp_line
			(start -0.7874 -0.4064)
			(end -0.7874 0.4064)
			(stroke
				(width 0.1524)
				(type default)
			)
			(layer "B.SilkS")
		)
		(fp_line
			(start 0.7874 0.4064)
			(end 0.7874 -0.4064)
			(stroke
				(width 0.1524)
				(type default)
			)
			(layer "B.SilkS")
		)
		(fp_line
			(start -0.7874 0.4064)
			(end 0.7874 0.4064)
			(stroke
				(width 0.1524)
				(type default)
			)
			(layer "B.SilkS")
		)
		(fp_line
			(start 0.67945 -0.305054)
			(end 0.12065 -0.305054)
			(stroke
				(width 0.1)
				(type default)
			)
			(layer "B.Fab")
		)
		(fp_line
			(start 0.12065 -0.305054)
			(end 0.12065 -0.2794)
			(stroke
				(width 0.1)
				(type default)
			)
			(layer "B.Fab")
		)
		(fp_line
			(start -0.12065 -0.3048)
			(end -0.67945 -0.3048)
			(stroke
				(width 0.1)
				(type default)
			)
			(layer "B.Fab")
		)
		(fp_line
			(start -0.67945 -0.3048)
			(end -0.67945 0.3048)
			(stroke
				(width 0.1)
				(type default)
			)
			(layer "B.Fab")
		)
		(fp_line
			(start 0.12065 -0.2794)
			(end -0.12065 -0.2794)
			(stroke
				(width 0.1)
				(type default)
			)
			(layer "B.Fab")
		)
		(fp_line
			(start -0.12065 -0.2794)
			(end -0.12065 -0.3048)
			(stroke
				(width 0.1)
				(type default)
			)
			(layer "B.Fab")
		)
		(fp_line
			(start 0.12065 0.2794)
			(end 0.12065 0.3048)
			(stroke
				(width 0.1)
				(type default)
			)
			(layer "B.Fab")
		)
		(fp_line
			(start -0.120396 0.2794)
			(end 0.12065 0.2794)
			(stroke
				(width 0.1)
				(type default)
			)
			(layer "B.Fab")
		)
		(fp_line
			(start 0.67945 0.3048)
			(end 0.67945 -0.305054)
			(stroke
				(width 0.1)
				(type default)
			)
			(layer "B.Fab")
		)
		(fp_line
			(start 0.12065 0.3048)
			(end 0.67945 0.3048)
			(stroke
				(width 0.1)
				(type default)
			)
			(layer "B.Fab")
		)
		(fp_line
			(start -0.120396 0.3048)
			(end -0.120396 0.2794)
			(stroke
				(width 0.1)
				(type default)
			)
			(layer "B.Fab")
		)
		(fp_line
			(start -0.67945 0.3048)
			(end -0.120396 0.3048)
			(stroke
				(width 0.1)
				(type default)
			)
			(layer "B.Fab")
		)
		(pad "1" smd circle
			(at 0.40005 0 270)
			(size 0 0)
			(layers "B.Cu" "B.Mask" "B.Paste")
			(net "P3V3_AUX_USB_HUB")
		)
		(pad "2" smd circle
			(at -0.40005 0 270)
			(size 0 0)
			(layers "B.Cu" "B.Mask" "B.Paste")
			(net "GND")
		)
	)
	(footprint ""
		(layer "B.Cu")
		(at 331.01788 -27.701748 90)
		(property "Reference" "R4095"
			(at 0 0 90)
			(layer "B.SilkS")
			(hide yes)
			(effects
				(font
					(size 1.27 1.27)
				)
				(justify mirror)
			)
		)
		(property "Value" ""
			(at 0 0 90)
			(layer "B.Fab")
			(effects
				(font
					(size 1.27 1.27)
				)
				(justify mirror)
			)
		)
		(duplicate_pad_numbers_are_jumpers no)
		(fp_line
			(start 0.7874 -0.4064)
			(end -0.7874 -0.4064)
			(stroke
				(width 0.1524)
				(type default)
			)
			(layer "B.SilkS")
		)
		(fp_line
			(start -0.7874 -0.4064)
			(end -0.7874 0.4064)
			(stroke
				(width 0.1524)
				(type default)
			)
			(layer "B.SilkS")
		)
		(fp_line
			(start 0.7874 0.4064)
			(end 0.7874 -0.4064)
			(stroke
				(width 0.1524)
				(type default)
			)
			(layer "B.SilkS")
		)
		(fp_line
			(start -0.7874 0.4064)
			(end 0.7874 0.4064)
			(stroke
				(width 0.1524)
				(type default)
			)
			(layer "B.SilkS")
		)
		(fp_line
			(start 0.67945 -0.305054)
			(end 0.12065 -0.305054)
			(stroke
				(width 0.1)
				(type default)
			)
			(layer "B.Fab")
		)
		(fp_line
			(start 0.12065 -0.305054)
			(end 0.12065 -0.2794)
			(stroke
				(width 0.1)
				(type default)
			)
			(layer "B.Fab")
		)
		(fp_line
			(start -0.12065 -0.3048)
			(end -0.67945 -0.3048)
			(stroke
				(width 0.1)
				(type default)
			)
			(layer "B.Fab")
		)
		(fp_line
			(start -0.67945 -0.3048)
			(end -0.67945 0.3048)
			(stroke
				(width 0.1)
				(type default)
			)
			(layer "B.Fab")
		)
		(fp_line
			(start 0.12065 -0.2794)
			(end -0.12065 -0.2794)
			(stroke
				(width 0.1)
				(type default)
			)
			(layer "B.Fab")
		)
		(fp_line
			(start -0.12065 -0.2794)
			(end -0.12065 -0.3048)
			(stroke
				(width 0.1)
				(type default)
			)
			(layer "B.Fab")
		)
		(fp_line
			(start 0.12065 0.2794)
			(end 0.12065 0.3048)
			(stroke
				(width 0.1)
				(type default)
			)
			(layer "B.Fab")
		)
		(fp_line
			(start -0.120396 0.2794)
			(end 0.12065 0.2794)
			(stroke
				(width 0.1)
				(type default)
			)
			(layer "B.Fab")
		)
		(fp_line
			(start 0.67945 0.3048)
			(end 0.67945 -0.305054)
			(stroke
				(width 0.1)
				(type default)
			)
			(layer "B.Fab")
		)
		(fp_line
			(start 0.12065 0.3048)
			(end 0.67945 0.3048)
			(stroke
				(width 0.1)
				(type default)
			)
			(layer "B.Fab")
		)
		(fp_line
			(start -0.120396 0.3048)
			(end -0.120396 0.2794)
			(stroke
				(width 0.1)
				(type default)
			)
			(layer "B.Fab")
		)
		(fp_line
			(start -0.67945 0.3048)
			(end -0.120396 0.3048)
			(stroke
				(width 0.1)
				(type default)
			)
			(layer "B.Fab")
		)
		(pad "1" smd circle
			(at 0.40005 0 270)
			(size 0 0)
			(layers "B.Cu" "B.Mask" "B.Paste")
			(net "PD_PCH_GPPC_A_19")
		)
		(pad "2" smd circle
			(at -0.40005 0 270)
			(size 0 0)
			(layers "B.Cu" "B.Mask" "B.Paste")
			(net "GND")
		)
	)
	(footprint ""
		(layer "B.Cu")
		(at 426.970444 -362.107226 90)
		(property "Reference" "PC1181_P0_3"
			(at 0 0 90)
			(layer "B.SilkS")
			(hide yes)
			(effects
				(font
					(size 1.27 1.27)
				)
				(justify mirror)
			)
		)
		(property "Value" ""
			(at 0 0 90)
			(layer "B.Fab")
			(effects
				(font
					(size 1.27 1.27)
				)
				(justify mirror)
			)
		)
		(duplicate_pad_numbers_are_jumpers no)
		(fp_line
			(start 1.524 -0.762)
			(end -1.524 -0.762)
			(stroke
				(width 0.1524)
				(type default)
			)
			(layer "B.SilkS")
		)
		(fp_line
			(start -1.524 -0.762)
			(end -1.524 0.762)
			(stroke
				(width 0.1524)
				(type default)
			)
			(layer "B.SilkS")
		)
		(fp_line
			(start 1.524 0.762)
			(end 1.524 -0.762)
			(stroke
				(width 0.1524)
				(type default)
			)
			(layer "B.SilkS")
		)
		(fp_line
			(start -1.524 0.762)
			(end 1.524 0.762)
			(stroke
				(width 0.1524)
				(type default)
			)
			(layer "B.SilkS")
		)
		(fp_line
			(start 1.1049 -0.724916)
			(end 1.1049 0.724916)
			(stroke
				(width 0.1)
				(type default)
			)
			(layer "B.Fab")
		)
		(fp_line
			(start -1.1049 -0.724916)
			(end 1.1049 -0.724916)
			(stroke
				(width 0.1)
				(type default)
			)
			(layer "B.Fab")
		)
		(fp_line
			(start 1.1049 0.724916)
			(end -1.1049 0.724916)
			(stroke
				(width 0.1)
				(type default)
			)
			(layer "B.Fab")
		)
		(fp_line
			(start -1.1049 0.724916)
			(end -1.1049 -0.724916)
			(stroke
				(width 0.1)
				(type default)
			)
			(layer "B.Fab")
		)
		(pad "1" smd rect
			(at 0.889 0 90)
			(size 1.016 1.27)
			(layers "B.Cu" "B.Mask" "B.Paste")
			(net "SW_P12V_PVCCFA_EHV_FIVRA_CPU0_R")
		)
		(pad "2" smd rect
			(at -0.889 0 90)
			(size 1.016 1.27)
			(layers "B.Cu" "B.Mask" "B.Paste")
			(net "GND")
		)
	)
	(footprint ""
		(layer "B.Cu")
		(at 81.74863 -52.082446)
		(property "Reference" "R3826"
			(at 0 0 0)
			(layer "B.SilkS")
			(hide yes)
			(effects
				(font
					(size 1.27 1.27)
				)
				(justify mirror)
			)
		)
		(property "Value" ""
			(at 0 0 0)
			(layer "B.Fab")
			(effects
				(font
					(size 1.27 1.27)
				)
				(justify mirror)
			)
		)
		(duplicate_pad_numbers_are_jumpers no)
		(fp_line
			(start -0.7874 -0.4064)
			(end -0.7874 0.4064)
			(stroke
				(width 0.1524)
				(type default)
			)
			(layer "B.SilkS")
		)
		(fp_line
			(start -0.7874 0.4064)
			(end 0.7874 0.4064)
			(stroke
				(width 0.1524)
				(type default)
			)
			(layer "B.SilkS")
		)
		(fp_line
			(start 0.7874 -0.4064)
			(end -0.7874 -0.4064)
			(stroke
				(width 0.1524)
				(type default)
			)
			(layer "B.SilkS")
		)
		(fp_line
			(start 0.7874 0.4064)
			(end 0.7874 -0.4064)
			(stroke
				(width 0.1524)
				(type default)
			)
			(layer "B.SilkS")
		)
		(fp_line
			(start -0.67945 -0.3048)
			(end -0.67945 0.3048)
			(stroke
				(width 0.1)
				(type default)
			)
			(layer "B.Fab")
		)
		(fp_line
			(start -0.67945 0.3048)
			(end -0.120396 0.3048)
			(stroke
				(width 0.1)
				(type default)
			)
			(layer "B.Fab")
		)
		(fp_line
			(start -0.12065 -0.3048)
			(end -0.67945 -0.3048)
			(stroke
				(width 0.1)
				(type default)
			)
			(layer "B.Fab")
		)
		(fp_line
			(start -0.12065 -0.2794)
			(end -0.12065 -0.3048)
			(stroke
				(width 0.1)
				(type default)
			)
			(layer "B.Fab")
		)
		(fp_line
			(start -0.120396 0.2794)
			(end 0.12065 0.2794)
			(stroke
				(width 0.1)
				(type default)
			)
			(layer "B.Fab")
		)
		(fp_line
			(start -0.120396 0.3048)
			(end -0.120396 0.2794)
			(stroke
				(width 0.1)
				(type default)
			)
			(layer "B.Fab")
		)
		(fp_line
			(start 0.12065 -0.305054)
			(end 0.12065 -0.2794)
			(stroke
				(width 0.1)
				(type default)
			)
			(layer "B.Fab")
		)
		(fp_line
			(start 0.12065 -0.2794)
			(end -0.12065 -0.2794)
			(stroke
				(width 0.1)
				(type default)
			)
			(layer "B.Fab")
		)
		(fp_line
			(start 0.12065 0.2794)
			(end 0.12065 0.3048)
			(stroke
				(width 0.1)
				(type default)
			)
			(layer "B.Fab")
		)
		(fp_line
			(start 0.12065 0.3048)
			(end 0.67945 0.3048)
			(stroke
				(width 0.1)
				(type default)
			)
			(layer "B.Fab")
		)
		(fp_line
			(start 0.67945 -0.305054)
			(end 0.12065 -0.305054)
			(stroke
				(width 0.1)
				(type default)
			)
			(layer "B.Fab")
		)
		(fp_line
			(start 0.67945 0.3048)
			(end 0.67945 -0.305054)
			(stroke
				(width 0.1)
				(type default)
			)
			(layer "B.Fab")
		)
		(pad "1" smd circle
			(at 0.40005 0 180)
			(size 0 0)
			(layers "B.Cu" "B.Mask" "B.Paste")
			(net "P3V3_AUX")
		)
		(pad "2" smd circle
			(at -0.40005 0 180)
			(size 0 0)
			(layers "B.Cu" "B.Mask" "B.Paste")
			(net "OCP_V3_2_P3V3_PWRGD")
		)
	)
	(footprint ""
		(layer "B.Cu")
		(at 416.02914 -161.064194)
		(property "Reference" "PC638"
			(at 0 0 0)
			(layer "B.SilkS")
			(hide yes)
			(effects
				(font
					(size 1.27 1.27)
				)
				(justify mirror)
			)
		)
		(property "Value" ""
			(at 0 0 0)
			(layer "B.Fab")
			(effects
				(font
					(size 1.27 1.27)
				)
				(justify mirror)
			)
		)
		(duplicate_pad_numbers_are_jumpers no)
		(fp_line
			(start -1.524 -0.762)
			(end -1.524 0.762)
			(stroke
				(width 0.1524)
				(type default)
			)
			(layer "B.SilkS")
		)
		(fp_line
			(start -1.524 0.762)
			(end 1.524 0.762)
			(stroke
				(width 0.1524)
				(type default)
			)
			(layer "B.SilkS")
		)
		(fp_line
			(start 1.524 -0.762)
			(end -1.524 -0.762)
			(stroke
				(width 0.1524)
				(type default)
			)
			(layer "B.SilkS")
		)
		(fp_line
			(start 1.524 0.762)
			(end 1.524 -0.762)
			(stroke
				(width 0.1524)
				(type default)
			)
			(layer "B.SilkS")
		)
		(fp_line
			(start -1.1049 -0.724916)
			(end 1.1049 -0.724916)
			(stroke
				(width 0.1)
				(type default)
			)
			(layer "B.Fab")
		)
		(fp_line
			(start -1.1049 0.724916)
			(end -1.1049 -0.724916)
			(stroke
				(width 0.1)
				(type default)
			)
			(layer "B.Fab")
		)
		(fp_line
			(start 1.1049 -0.724916)
			(end 1.1049 0.724916)
			(stroke
				(width 0.1)
				(type default)
			)
			(layer "B.Fab")
		)
		(fp_line
			(start 1.1049 0.724916)
			(end -1.1049 0.724916)
			(stroke
				(width 0.1)
				(type default)
			)
			(layer "B.Fab")
		)
		(pad "1" smd rect
			(at 0.889 0)
			(size 1.016 1.27)
			(layers "B.Cu" "B.Mask" "B.Paste")
			(net "SW_P12V_PVCCINFAON_CPU0_FLT")
		)
		(pad "2" smd rect
			(at -0.889 0)
			(size 1.016 1.27)
			(layers "B.Cu" "B.Mask" "B.Paste")
			(net "GND")
		)
	)
	(footprint ""
		(layer "B.Cu")
		(at 178.120802 -104.71277 180)
		(property "Reference" "R1302"
			(at 0 0 0)
			(layer "B.SilkS")
			(hide yes)
			(effects
				(font
					(size 1.27 1.27)
				)
				(justify mirror)
			)
		)
		(property "Value" ""
			(at 0 0 0)
			(layer "B.Fab")
			(effects
				(font
					(size 1.27 1.27)
				)
				(justify mirror)
			)
		)
		(duplicate_pad_numbers_are_jumpers no)
		(fp_line
			(start 0.7874 0.4064)
			(end 0.7874 -0.4064)
			(stroke
				(width 0.1524)
				(type default)
			)
			(layer "B.SilkS")
		)
		(fp_line
			(start 0.7874 -0.4064)
			(end -0.7874 -0.4064)
			(stroke
				(width 0.1524)
				(type default)
			)
			(layer "B.SilkS")
		)
		(fp_line
			(start -0.7874 0.4064)
			(end 0.7874 0.4064)
			(stroke
				(width 0.1524)
				(type default)
			)
			(layer "B.SilkS")
		)
		(fp_line
			(start -0.7874 -0.4064)
			(end -0.7874 0.4064)
			(stroke
				(width 0.1524)
				(type default)
			)
			(layer "B.SilkS")
		)
		(fp_line
			(start 0.67945 0.3048)
			(end 0.67945 -0.305054)
			(stroke
				(width 0.1)
				(type default)
			)
			(layer "B.Fab")
		)
		(fp_line
			(start 0.67945 -0.305054)
			(end 0.12065 -0.305054)
			(stroke
				(width 0.1)
				(type default)
			)
			(layer "B.Fab")
		)
		(fp_line
			(start 0.12065 0.3048)
			(end 0.67945 0.3048)
			(stroke
				(width 0.1)
				(type default)
			)
			(layer "B.Fab")
		)
		(fp_line
			(start 0.12065 0.2794)
			(end 0.12065 0.3048)
			(stroke
				(width 0.1)
				(type default)
			)
			(layer "B.Fab")
		)
		(fp_line
			(start 0.12065 -0.2794)
			(end -0.12065 -0.2794)
			(stroke
				(width 0.1)
				(type default)
			)
			(layer "B.Fab")
		)
		(fp_line
			(start 0.12065 -0.305054)
			(end 0.12065 -0.2794)
			(stroke
				(width 0.1)
				(type default)
			)
			(layer "B.Fab")
		)
		(fp_line
			(start -0.120396 0.3048)
			(end -0.120396 0.2794)
			(stroke
				(width 0.1)
				(type default)
			)
			(layer "B.Fab")
		)
		(fp_line
			(start -0.120396 0.2794)
			(end 0.12065 0.2794)
			(stroke
				(width 0.1)
				(type default)
			)
			(layer "B.Fab")
		)
		(fp_line
			(start -0.12065 -0.2794)
			(end -0.12065 -0.3048)
			(stroke
				(width 0.1)
				(type default)
			)
			(layer "B.Fab")
		)
		(fp_line
			(start -0.12065 -0.3048)
			(end -0.67945 -0.3048)
			(stroke
				(width 0.1)
				(type default)
			)
			(layer "B.Fab")
		)
		(fp_line
			(start -0.67945 0.3048)
			(end -0.120396 0.3048)
			(stroke
				(width 0.1)
				(type default)
			)
			(layer "B.Fab")
		)
		(fp_line
			(start -0.67945 -0.3048)
			(end -0.67945 0.3048)
			(stroke
				(width 0.1)
				(type default)
			)
			(layer "B.Fab")
		)
		(pad "1" smd circle
			(at 0.40005 0)
			(size 0 0)
			(layers "B.Cu" "B.Mask" "B.Paste")
			(net "PWRGD_DRAMPWRGD_CPU0_AB_R_LVC1")
		)
		(pad "2" smd circle
			(at -0.40005 0)
			(size 0 0)
			(layers "B.Cu" "B.Mask" "B.Paste")
			(net "GND")
		)
	)
	(footprint ""
		(layer "B.Cu")
		(at 485.20985 -211.012532 -90)
		(property "Reference" "X37"
			(at -0.442468 -2.18948 270)
			(unlocked yes)
			(layer "B.SilkS")
			(effects
				(font
					(size 0.7874 0.5842)
					(thickness 0.1524)
				)
				(justify left mirror)
			)
		)
		(property "Value" ""
			(at 0 0 90)
			(layer "B.Fab")
			(effects
				(font
					(size 1.27 1.27)
				)
				(justify mirror)
			)
		)
		(property "Device Type" "TP_TDR_4P_FTS_TH-TP_TDR_4P_DIPA"
			(at -1.30175 1.27 180)
			(unlocked yes)
			(layer "B.Fab")
			(hide yes)
			(effects
				(font
					(size 0.635 0.4064)
					(thickness 0.1524)
				)
				(justify mirror)
			)
		)
		(property "User Part Number" "N_A"
			(at -1.30175 1.27 180)
			(unlocked yes)
			(layer "Cmts.User")
			(hide yes)
			(effects
				(font
					(size 0.635 0.4064)
					(thickness 0.1524)
				)
				(justify mirror)
			)
		)
		(duplicate_pad_numbers_are_jumpers no)
		(fp_line
			(start -2.54 3.81)
			(end -2.54 3.6703)
			(stroke
				(width 0.1524)
				(type default)
			)
			(layer "B.SilkS")
		)
		(fp_line
			(start 0 3.81)
			(end -2.54 3.81)
			(stroke
				(width 0.1524)
				(type default)
			)
			(layer "B.SilkS")
		)
		(fp_line
			(start 0 3.175)
			(end 0 3.81)
			(stroke
				(width 0.1524)
				(type default)
			)
			(layer "B.SilkS")
		)
		(fp_line
			(start -2.54 1.4097)
			(end -2.54 1.1303)
			(stroke
				(width 0.1524)
				(type default)
			)
			(layer "B.SilkS")
		)
		(fp_line
			(start 0 0.635)
			(end 0 1.905)
			(stroke
				(width 0.1524)
				(type default)
			)
			(layer "B.SilkS")
		)
		(fp_line
			(start -2.54 -1.1303)
			(end -2.54 -1.27)
			(stroke
				(width 0.1524)
				(type default)
			)
			(layer "B.SilkS")
		)
		(fp_line
			(start -2.54 -1.27)
			(end 0 -1.27)
			(stroke
				(width 0.1524)
				(type default)
			)
			(layer "B.SilkS")
		)
		(fp_line
			(start 0 -1.27)
			(end 0 -0.635)
			(stroke
				(width 0.1524)
				(type default)
			)
			(layer "B.SilkS")
		)
		(fp_poly
			(pts
				(xy 0.761746 0) (xy 2.285746 -0.762) (xy 2.285746 0.762)
			)
			(stroke
				(width 0)
				(type default)
			)
			(fill yes)
			(layer "B.SilkS")
		)
		(fp_line
			(start -2.54 3.81)
			(end -2.54 -1.27)
			(stroke
				(width 0.1)
				(type default)
			)
			(layer "B.Fab")
		)
		(fp_line
			(start 0 3.81)
			(end -2.54 3.81)
			(stroke
				(width 0.1)
				(type default)
			)
			(layer "B.Fab")
		)
		(fp_line
			(start -2.54 -1.27)
			(end 0 -1.27)
			(stroke
				(width 0.1)
				(type default)
			)
			(layer "B.Fab")
		)
		(fp_line
			(start 0 -1.27)
			(end 0 3.81)
			(stroke
				(width 0.1)
				(type default)
			)
			(layer "B.Fab")
		)
		(fp_poly
			(pts
				(xy 0.761746 0) (xy 2.285746 -0.762) (xy 2.285746 0.762)
			)
			(stroke
				(width 0)
				(type default)
			)
			(fill yes)
			(layer "B.Fab")
		)
		(pad "1" thru_hole circle
			(at 0 0 90)
			(size 1.0033 1.0033)
			(drill 0.249936)
			(layers "*.Cu" "*.Mask")
			(remove_unused_layers no)
			(net "TDR_DIFF_85_NECK_IN4_DP")
			(clearance 0.10795)
			(padstack
				(mode front_inner_back)
				(layer "Inner"
					(shape circle)
					(size 0.8001 0.8001)
					(clearance 0.1524)
				)
				(layer "B.Cu"
					(shape circle)
					(size 1.0033 1.0033)
					(thermal_gap 0.10795)
					(clearance 0.10795)
				)
			)
		)
		(pad "2" thru_hole circle
			(at -2.54 0 90)
			(size 1.9939 1.9939)
			(drill 0.249936)
			(layers "*.Cu" "*.Mask")
			(remove_unused_layers no)
			(net "T1_GND")
			(clearance 0.10795)
			(padstack
				(mode front_inner_back)
				(layer "Inner"
					(shape circle)
					(size 0.8001 0.8001)
					(clearance 0.1524)
				)
				(layer "B.Cu"
					(shape circle)
					(size 1.9939 1.9939)
					(thermal_gap 0.10795)
					(clearance 0.10795)
				)
			)
		)
		(pad "3" thru_hole circle
			(at -2.54 2.54 90)
			(size 1.9939 1.9939)
			(drill 0.249936)
			(layers "*.Cu" "*.Mask")
			(remove_unused_layers no)
			(net "T1_GND")
			(clearance 0.10795)
			(padstack
				(mode front_inner_back)
				(layer "Inner"
					(shape circle)
					(size 0.8001 0.8001)
					(clearance 0.1524)
				)
				(layer "B.Cu"
					(shape circle)
					(size 1.9939 1.9939)
					(thermal_gap 0.10795)
					(clearance 0.10795)
				)
			)
		)
		(pad "4" thru_hole circle
			(at 0 2.54 90)
			(size 1.0033 1.0033)
			(drill 0.249936)
			(layers "*.Cu" "*.Mask")
			(remove_unused_layers no)
			(net "TDR_DIFF_85_NECK_IN4_DN")
			(clearance 0.10795)
			(padstack
				(mode front_inner_back)
				(layer "Inner"
					(shape circle)
					(size 0.8001 0.8001)
					(clearance 0.1524)
				)
				(layer "B.Cu"
					(shape circle)
					(size 1.0033 1.0033)
					(thermal_gap 0.10795)
					(clearance 0.10795)
				)
			)
		)
	)
	(footprint ""
		(layer "B.Cu")
		(at 452.01205 -3.866388 -90)
		(property "Reference" "R1504"
			(at 0 0 90)
			(layer "B.SilkS")
			(hide yes)
			(effects
				(font
					(size 1.27 1.27)
				)
				(justify mirror)
			)
		)
		(property "Value" ""
			(at 0 0 90)
			(layer "B.Fab")
			(effects
				(font
					(size 1.27 1.27)
				)
				(justify mirror)
			)
		)
		(duplicate_pad_numbers_are_jumpers no)
		(fp_line
			(start -0.7874 0.4064)
			(end 0.7874 0.4064)
			(stroke
				(width 0.1524)
				(type default)
			)
			(layer "B.SilkS")
		)
		(fp_line
			(start 0.7874 0.4064)
			(end 0.7874 -0.4064)
			(stroke
				(width 0.1524)
				(type default)
			)
			(layer "B.SilkS")
		)
		(fp_line
			(start -0.7874 -0.4064)
			(end -0.7874 0.4064)
			(stroke
				(width 0.1524)
				(type default)
			)
			(layer "B.SilkS")
		)
		(fp_line
			(start 0.7874 -0.4064)
			(end -0.7874 -0.4064)
			(stroke
				(width 0.1524)
				(type default)
			)
			(layer "B.SilkS")
		)
		(fp_line
			(start -0.67945 0.3048)
			(end -0.120396 0.3048)
			(stroke
				(width 0.1)
				(type default)
			)
			(layer "B.Fab")
		)
		(fp_line
			(start -0.120396 0.3048)
			(end -0.120396 0.2794)
			(stroke
				(width 0.1)
				(type default)
			)
			(layer "B.Fab")
		)
		(fp_line
			(start 0.12065 0.3048)
			(end 0.67945 0.3048)
			(stroke
				(width 0.1)
				(type default)
			)
			(layer "B.Fab")
		)
		(fp_line
			(start 0.67945 0.3048)
			(end 0.67945 -0.305054)
			(stroke
				(width 0.1)
				(type default)
			)
			(layer "B.Fab")
		)
		(fp_line
			(start -0.120396 0.2794)
			(end 0.12065 0.2794)
			(stroke
				(width 0.1)
				(type default)
			)
			(layer "B.Fab")
		)
		(fp_line
			(start 0.12065 0.2794)
			(end 0.12065 0.3048)
			(stroke
				(width 0.1)
				(type default)
			)
			(layer "B.Fab")
		)
		(fp_line
			(start -0.12065 -0.2794)
			(end -0.12065 -0.3048)
			(stroke
				(width 0.1)
				(type default)
			)
			(layer "B.Fab")
		)
		(fp_line
			(start 0.12065 -0.2794)
			(end -0.12065 -0.2794)
			(stroke
				(width 0.1)
				(type default)
			)
			(layer "B.Fab")
		)
		(fp_line
			(start -0.67945 -0.3048)
			(end -0.67945 0.3048)
			(stroke
				(width 0.1)
				(type default)
			)
			(layer "B.Fab")
		)
		(fp_line
			(start -0.12065 -0.3048)
			(end -0.67945 -0.3048)
			(stroke
				(width 0.1)
				(type default)
			)
			(layer "B.Fab")
		)
		(fp_line
			(start 0.12065 -0.305054)
			(end 0.12065 -0.2794)
			(stroke
				(width 0.1)
				(type default)
			)
			(layer "B.Fab")
		)
		(fp_line
			(start 0.67945 -0.305054)
			(end 0.12065 -0.305054)
			(stroke
				(width 0.1)
				(type default)
			)
			(layer "B.Fab")
		)
		(pad "1" smd circle
			(at 0.40005 0 90)
			(size 0 0)
			(layers "B.Cu" "B.Mask" "B.Paste")
			(net "RST_OCP_V3_1_BUF_N")
		)
		(pad "2" smd circle
			(at -0.40005 0 90)
			(size 0 0)
			(layers "B.Cu" "B.Mask" "B.Paste")
			(net "RST_PERST2_OCP_SFF_N")
		)
	)
	(footprint ""
		(layer "B.Cu")
		(at 336.269584 -58.486548 -90)
		(property "Reference" "C1202"
			(at 0 0 90)
			(layer "B.SilkS")
			(hide yes)
			(effects
				(font
					(size 1.27 1.27)
				)
				(justify mirror)
			)
		)
		(property "Value" ""
			(at 0 0 90)
			(layer "B.Fab")
			(effects
				(font
					(size 1.27 1.27)
				)
				(justify mirror)
			)
		)
		(duplicate_pad_numbers_are_jumpers no)
		(fp_line
			(start -1.2954 0.5842)
			(end 1.2954 0.5842)
			(stroke
				(width 0.1524)
				(type default)
			)
			(layer "B.SilkS")
		)
		(fp_line
			(start 1.2954 0.5842)
			(end 1.2954 -0.5842)
			(stroke
				(width 0.1524)
				(type default)
			)
			(layer "B.SilkS")
		)
		(fp_line
			(start -1.2954 -0.5842)
			(end -1.2954 0.5842)
			(stroke
				(width 0.1524)
				(type default)
			)
			(layer "B.SilkS")
		)
		(fp_line
			(start 0 -0.5842)
			(end 0 0.5842)
			(stroke
				(width 0.1524)
				(type default)
			)
			(layer "B.SilkS")
		)
		(fp_line
			(start 1.2954 -0.5842)
			(end -1.2954 -0.5842)
			(stroke
				(width 0.1524)
				(type default)
			)
			(layer "B.SilkS")
		)
		(fp_line
			(start -0.8636 0.4572)
			(end 0.8636 0.4572)
			(stroke
				(width 0.1)
				(type default)
			)
			(layer "B.Fab")
		)
		(fp_line
			(start 0.8636 0.4572)
			(end 0.8636 0.4064)
			(stroke
				(width 0.1)
				(type default)
			)
			(layer "B.Fab")
		)
		(fp_line
			(start -1.1938 0.4064)
			(end -0.8636 0.4064)
			(stroke
				(width 0.1)
				(type default)
			)
			(layer "B.Fab")
		)
		(fp_line
			(start -0.8636 0.4064)
			(end -0.8636 0.4572)
			(stroke
				(width 0.1)
				(type default)
			)
			(layer "B.Fab")
		)
		(fp_line
			(start 0.8636 0.4064)
			(end 1.1938 0.4064)
			(stroke
				(width 0.1)
				(type default)
			)
			(layer "B.Fab")
		)
		(fp_line
			(start 1.1938 0.4064)
			(end 1.1938 -0.4064)
			(stroke
				(width 0.1)
				(type default)
			)
			(layer "B.Fab")
		)
		(fp_line
			(start -1.1938 -0.4064)
			(end -1.1938 0.4064)
			(stroke
				(width 0.1)
				(type default)
			)
			(layer "B.Fab")
		)
		(fp_line
			(start -0.8636 -0.4064)
			(end -1.1938 -0.4064)
			(stroke
				(width 0.1)
				(type default)
			)
			(layer "B.Fab")
		)
		(fp_line
			(start 0.8636 -0.4064)
			(end 0.8636 -0.4572)
			(stroke
				(width 0.1)
				(type default)
			)
			(layer "B.Fab")
		)
		(fp_line
			(start 1.1938 -0.4064)
			(end 0.8636 -0.4064)
			(stroke
				(width 0.1)
				(type default)
			)
			(layer "B.Fab")
		)
		(fp_line
			(start -0.8636 -0.4572)
			(end -0.8636 -0.4064)
			(stroke
				(width 0.1)
				(type default)
			)
			(layer "B.Fab")
		)
		(fp_line
			(start 0.8636 -0.4572)
			(end -0.8636 -0.4572)
			(stroke
				(width 0.1)
				(type default)
			)
			(layer "B.Fab")
		)
		(pad "1" smd rect
			(at 0.7366 0 180)
			(size 0.7112 0.8128)
			(layers "B.Cu" "B.Mask" "B.Paste")
			(net "P1V8_PCH_AUX")
		)
		(pad "2" smd rect
			(at -0.7366 0 180)
			(size 0.7112 0.8128)
			(layers "B.Cu" "B.Mask" "B.Paste")
			(net "GND")
		)
	)
	(footprint ""
		(layer "B.Cu")
		(at 292.528498 -403.031452 90)
		(property "Reference" "PR2518"
			(at 0 0 90)
			(layer "B.SilkS")
			(hide yes)
			(effects
				(font
					(size 1.27 1.27)
				)
				(justify mirror)
			)
		)
		(property "Value" ""
			(at 0 0 90)
			(layer "B.Fab")
			(effects
				(font
					(size 1.27 1.27)
				)
				(justify mirror)
			)
		)
		(duplicate_pad_numbers_are_jumpers no)
		(fp_line
			(start 0.7874 -0.4064)
			(end -0.7874 -0.4064)
			(stroke
				(width 0.1524)
				(type default)
			)
			(layer "B.SilkS")
		)
		(fp_line
			(start -0.7874 -0.4064)
			(end -0.7874 0.4064)
			(stroke
				(width 0.1524)
				(type default)
			)
			(layer "B.SilkS")
		)
		(fp_line
			(start 0.7874 0.4064)
			(end 0.7874 -0.4064)
			(stroke
				(width 0.1524)
				(type default)
			)
			(layer "B.SilkS")
		)
		(fp_line
			(start -0.7874 0.4064)
			(end 0.7874 0.4064)
			(stroke
				(width 0.1524)
				(type default)
			)
			(layer "B.SilkS")
		)
		(fp_line
			(start 0.67945 -0.305054)
			(end 0.12065 -0.305054)
			(stroke
				(width 0.1)
				(type default)
			)
			(layer "B.Fab")
		)
		(fp_line
			(start 0.12065 -0.305054)
			(end 0.12065 -0.2794)
			(stroke
				(width 0.1)
				(type default)
			)
			(layer "B.Fab")
		)
		(fp_line
			(start -0.12065 -0.3048)
			(end -0.67945 -0.3048)
			(stroke
				(width 0.1)
				(type default)
			)
			(layer "B.Fab")
		)
		(fp_line
			(start -0.67945 -0.3048)
			(end -0.67945 0.3048)
			(stroke
				(width 0.1)
				(type default)
			)
			(layer "B.Fab")
		)
		(fp_line
			(start 0.12065 -0.2794)
			(end -0.12065 -0.2794)
			(stroke
				(width 0.1)
				(type default)
			)
			(layer "B.Fab")
		)
		(fp_line
			(start -0.12065 -0.2794)
			(end -0.12065 -0.3048)
			(stroke
				(width 0.1)
				(type default)
			)
			(layer "B.Fab")
		)
		(fp_line
			(start 0.12065 0.2794)
			(end 0.12065 0.3048)
			(stroke
				(width 0.1)
				(type default)
			)
			(layer "B.Fab")
		)
		(fp_line
			(start -0.120396 0.2794)
			(end 0.12065 0.2794)
			(stroke
				(width 0.1)
				(type default)
			)
			(layer "B.Fab")
		)
		(fp_line
			(start 0.67945 0.3048)
			(end 0.67945 -0.305054)
			(stroke
				(width 0.1)
				(type default)
			)
			(layer "B.Fab")
		)
		(fp_line
			(start 0.12065 0.3048)
			(end 0.67945 0.3048)
			(stroke
				(width 0.1)
				(type default)
			)
			(layer "B.Fab")
		)
		(fp_line
			(start -0.120396 0.3048)
			(end -0.120396 0.2794)
			(stroke
				(width 0.1)
				(type default)
			)
			(layer "B.Fab")
		)
		(fp_line
			(start -0.67945 0.3048)
			(end -0.120396 0.3048)
			(stroke
				(width 0.1)
				(type default)
			)
			(layer "B.Fab")
		)
		(pad "1" smd circle
			(at 0.40005 0 270)
			(size 0 0)
			(layers "B.Cu" "B.Mask" "B.Paste")
			(net "P12V_HSC_ADC_N")
		)
		(pad "2" smd circle
			(at -0.40005 0 270)
			(size 0 0)
			(layers "B.Cu" "B.Mask" "B.Paste")
			(net "P12V_HSC_SENSE2_R4_N")
		)
	)
	(footprint ""
		(layer "B.Cu")
		(at 243.485924 -396.056104 180)
		(property "Reference" "PC1750"
			(at 0 0 0)
			(layer "B.SilkS")
			(hide yes)
			(effects
				(font
					(size 1.27 1.27)
				)
				(justify mirror)
			)
		)
		(property "Value" ""
			(at 0 0 0)
			(layer "B.Fab")
			(effects
				(font
					(size 1.27 1.27)
				)
				(justify mirror)
			)
		)
		(duplicate_pad_numbers_are_jumpers no)
		(fp_line
			(start 0.7874 0.4064)
			(end 0.7874 -0.4064)
			(stroke
				(width 0.1524)
				(type default)
			)
			(layer "B.SilkS")
		)
		(fp_line
			(start 0.7874 -0.4064)
			(end -0.7874 -0.4064)
			(stroke
				(width 0.1524)
				(type default)
			)
			(layer "B.SilkS")
		)
		(fp_line
			(start -0.7874 0.4064)
			(end 0.7874 0.4064)
			(stroke
				(width 0.1524)
				(type default)
			)
			(layer "B.SilkS")
		)
		(fp_line
			(start -0.7874 -0.4064)
			(end -0.7874 0.4064)
			(stroke
				(width 0.1524)
				(type default)
			)
			(layer "B.SilkS")
		)
		(fp_line
			(start 0.67945 0.3048)
			(end 0.67945 -0.305054)
			(stroke
				(width 0.1)
				(type default)
			)
			(layer "B.Fab")
		)
		(fp_line
			(start 0.67945 -0.305054)
			(end 0.12065 -0.305054)
			(stroke
				(width 0.1)
				(type default)
			)
			(layer "B.Fab")
		)
		(fp_line
			(start 0.12065 0.3048)
			(end 0.67945 0.3048)
			(stroke
				(width 0.1)
				(type default)
			)
			(layer "B.Fab")
		)
		(fp_line
			(start 0.12065 0.2794)
			(end 0.12065 0.3048)
			(stroke
				(width 0.1)
				(type default)
			)
			(layer "B.Fab")
		)
		(fp_line
			(start 0.12065 -0.2794)
			(end -0.12065 -0.2794)
			(stroke
				(width 0.1)
				(type default)
			)
			(layer "B.Fab")
		)
		(fp_line
			(start 0.12065 -0.305054)
			(end 0.12065 -0.2794)
			(stroke
				(width 0.1)
				(type default)
			)
			(layer "B.Fab")
		)
		(fp_line
			(start -0.120396 0.3048)
			(end -0.120396 0.2794)
			(stroke
				(width 0.1)
				(type default)
			)
			(layer "B.Fab")
		)
		(fp_line
			(start -0.120396 0.2794)
			(end 0.12065 0.2794)
			(stroke
				(width 0.1)
				(type default)
			)
			(layer "B.Fab")
		)
		(fp_line
			(start -0.12065 -0.2794)
			(end -0.12065 -0.3048)
			(stroke
				(width 0.1)
				(type default)
			)
			(layer "B.Fab")
		)
		(fp_line
			(start -0.12065 -0.3048)
			(end -0.67945 -0.3048)
			(stroke
				(width 0.1)
				(type default)
			)
			(layer "B.Fab")
		)
		(fp_line
			(start -0.67945 0.3048)
			(end -0.120396 0.3048)
			(stroke
				(width 0.1)
				(type default)
			)
			(layer "B.Fab")
		)
		(fp_line
			(start -0.67945 -0.3048)
			(end -0.67945 0.3048)
			(stroke
				(width 0.1)
				(type default)
			)
			(layer "B.Fab")
		)
		(pad "1" smd circle
			(at 0.40005 0)
			(size 0 0)
			(layers "B.Cu" "B.Mask" "B.Paste")
			(net "P12V_AUX")
		)
		(pad "2" smd circle
			(at -0.40005 0)
			(size 0 0)
			(layers "B.Cu" "B.Mask" "B.Paste")
			(net "P12V_HSC_GATE2")
		)
	)
	(footprint ""
		(layer "B.Cu")
		(at 332.447138 -190.82893 90)
		(property "Reference" "R25"
			(at 0 0 90)
			(layer "B.SilkS")
			(hide yes)
			(effects
				(font
					(size 1.27 1.27)
				)
				(justify mirror)
			)
		)
		(property "Value" ""
			(at 0 0 90)
			(layer "B.Fab")
			(effects
				(font
					(size 1.27 1.27)
				)
				(justify mirror)
			)
		)
		(duplicate_pad_numbers_are_jumpers no)
		(fp_line
			(start 0.7874 -0.4064)
			(end -0.7874 -0.4064)
			(stroke
				(width 0.1524)
				(type default)
			)
			(layer "B.SilkS")
		)
		(fp_line
			(start -0.7874 -0.4064)
			(end -0.7874 0.4064)
			(stroke
				(width 0.1524)
				(type default)
			)
			(layer "B.SilkS")
		)
		(fp_line
			(start 0.7874 0.4064)
			(end 0.7874 -0.4064)
			(stroke
				(width 0.1524)
				(type default)
			)
			(layer "B.SilkS")
		)
		(fp_line
			(start -0.7874 0.4064)
			(end 0.7874 0.4064)
			(stroke
				(width 0.1524)
				(type default)
			)
			(layer "B.SilkS")
		)
		(fp_line
			(start 0.67945 -0.305054)
			(end 0.12065 -0.305054)
			(stroke
				(width 0.1)
				(type default)
			)
			(layer "B.Fab")
		)
		(fp_line
			(start 0.12065 -0.305054)
			(end 0.12065 -0.2794)
			(stroke
				(width 0.1)
				(type default)
			)
			(layer "B.Fab")
		)
		(fp_line
			(start -0.12065 -0.3048)
			(end -0.67945 -0.3048)
			(stroke
				(width 0.1)
				(type default)
			)
			(layer "B.Fab")
		)
		(fp_line
			(start -0.67945 -0.3048)
			(end -0.67945 0.3048)
			(stroke
				(width 0.1)
				(type default)
			)
			(layer "B.Fab")
		)
		(fp_line
			(start 0.12065 -0.2794)
			(end -0.12065 -0.2794)
			(stroke
				(width 0.1)
				(type default)
			)
			(layer "B.Fab")
		)
		(fp_line
			(start -0.12065 -0.2794)
			(end -0.12065 -0.3048)
			(stroke
				(width 0.1)
				(type default)
			)
			(layer "B.Fab")
		)
		(fp_line
			(start 0.12065 0.2794)
			(end 0.12065 0.3048)
			(stroke
				(width 0.1)
				(type default)
			)
			(layer "B.Fab")
		)
		(fp_line
			(start -0.120396 0.2794)
			(end 0.12065 0.2794)
			(stroke
				(width 0.1)
				(type default)
			)
			(layer "B.Fab")
		)
		(fp_line
			(start 0.67945 0.3048)
			(end 0.67945 -0.305054)
			(stroke
				(width 0.1)
				(type default)
			)
			(layer "B.Fab")
		)
		(fp_line
			(start 0.12065 0.3048)
			(end 0.67945 0.3048)
			(stroke
				(width 0.1)
				(type default)
			)
			(layer "B.Fab")
		)
		(fp_line
			(start -0.120396 0.3048)
			(end -0.120396 0.2794)
			(stroke
				(width 0.1)
				(type default)
			)
			(layer "B.Fab")
		)
		(fp_line
			(start -0.67945 0.3048)
			(end -0.120396 0.3048)
			(stroke
				(width 0.1)
				(type default)
			)
			(layer "B.Fab")
		)
		(pad "1" smd circle
			(at 0.40005 0 270)
			(size 0 0)
			(layers "B.Cu" "B.Mask" "B.Paste")
			(net "DBP_CPU0_HOOK9_MBP3_GTL_QS_R_N")
		)
		(pad "2" smd circle
			(at -0.40005 0 270)
			(size 0 0)
			(layers "B.Cu" "B.Mask" "B.Paste")
			(net "DBP_CPU_HOOK9_MBP3_GTL_QS_N")
		)
	)
	(footprint ""
		(layer "B.Cu")
		(at 60.873132 -258.466844 -90)
		(property "Reference" "C458"
			(at 0 0 90)
			(layer "B.SilkS")
			(hide yes)
			(effects
				(font
					(size 1.27 1.27)
				)
				(justify mirror)
			)
		)
		(property "Value" ""
			(at 0 0 90)
			(layer "B.Fab")
			(effects
				(font
					(size 1.27 1.27)
				)
				(justify mirror)
			)
		)
		(duplicate_pad_numbers_are_jumpers no)
		(fp_line
			(start -1.524 0.762)
			(end 1.524 0.762)
			(stroke
				(width 0.1524)
				(type default)
			)
			(layer "B.SilkS")
		)
		(fp_line
			(start 1.524 0.762)
			(end 1.524 -0.762)
			(stroke
				(width 0.1524)
				(type default)
			)
			(layer "B.SilkS")
		)
		(fp_line
			(start -1.524 -0.762)
			(end -1.524 0.762)
			(stroke
				(width 0.1524)
				(type default)
			)
			(layer "B.SilkS")
		)
		(fp_line
			(start 1.524 -0.762)
			(end -1.524 -0.762)
			(stroke
				(width 0.1524)
				(type default)
			)
			(layer "B.SilkS")
		)
		(fp_line
			(start -1.1049 0.724916)
			(end -1.1049 -0.724916)
			(stroke
				(width 0.1)
				(type default)
			)
			(layer "B.Fab")
		)
		(fp_line
			(start 1.1049 0.724916)
			(end -1.1049 0.724916)
			(stroke
				(width 0.1)
				(type default)
			)
			(layer "B.Fab")
		)
		(fp_line
			(start -1.1049 -0.724916)
			(end 1.1049 -0.724916)
			(stroke
				(width 0.1)
				(type default)
			)
			(layer "B.Fab")
		)
		(fp_line
			(start 1.1049 -0.724916)
			(end 1.1049 0.724916)
			(stroke
				(width 0.1)
				(type default)
			)
			(layer "B.Fab")
		)
		(pad "1" smd rect
			(at 0.889 0 270)
			(size 1.016 1.27)
			(layers "B.Cu" "B.Mask" "B.Paste")
			(net "PVCCFA_EHV_FIVRA_CPU1")
		)
		(pad "2" smd rect
			(at -0.889 0 270)
			(size 1.016 1.27)
			(layers "B.Cu" "B.Mask" "B.Paste")
			(net "GND")
		)
	)
	(footprint ""
		(layer "B.Cu")
		(at 128.85674 -20.996148 90)
		(property "Reference" "R4280"
			(at 0 0 90)
			(layer "B.SilkS")
			(hide yes)
			(effects
				(font
					(size 1.27 1.27)
				)
				(justify mirror)
			)
		)
		(property "Value" ""
			(at 0 0 90)
			(layer "B.Fab")
			(effects
				(font
					(size 1.27 1.27)
				)
				(justify mirror)
			)
		)
		(duplicate_pad_numbers_are_jumpers no)
		(fp_line
			(start 0.7874 -0.4064)
			(end -0.7874 -0.4064)
			(stroke
				(width 0.1524)
				(type default)
			)
			(layer "B.SilkS")
		)
		(fp_line
			(start -0.7874 -0.4064)
			(end -0.7874 0.4064)
			(stroke
				(width 0.1524)
				(type default)
			)
			(layer "B.SilkS")
		)
		(fp_line
			(start 0.7874 0.4064)
			(end 0.7874 -0.4064)
			(stroke
				(width 0.1524)
				(type default)
			)
			(layer "B.SilkS")
		)
		(fp_line
			(start -0.7874 0.4064)
			(end 0.7874 0.4064)
			(stroke
				(width 0.1524)
				(type default)
			)
			(layer "B.SilkS")
		)
		(fp_line
			(start 0.67945 -0.305054)
			(end 0.12065 -0.305054)
			(stroke
				(width 0.1)
				(type default)
			)
			(layer "B.Fab")
		)
		(fp_line
			(start 0.12065 -0.305054)
			(end 0.12065 -0.2794)
			(stroke
				(width 0.1)
				(type default)
			)
			(layer "B.Fab")
		)
		(fp_line
			(start -0.12065 -0.3048)
			(end -0.67945 -0.3048)
			(stroke
				(width 0.1)
				(type default)
			)
			(layer "B.Fab")
		)
		(fp_line
			(start -0.67945 -0.3048)
			(end -0.67945 0.3048)
			(stroke
				(width 0.1)
				(type default)
			)
			(layer "B.Fab")
		)
		(fp_line
			(start 0.12065 -0.2794)
			(end -0.12065 -0.2794)
			(stroke
				(width 0.1)
				(type default)
			)
			(layer "B.Fab")
		)
		(fp_line
			(start -0.12065 -0.2794)
			(end -0.12065 -0.3048)
			(stroke
				(width 0.1)
				(type default)
			)
			(layer "B.Fab")
		)
		(fp_line
			(start 0.12065 0.2794)
			(end 0.12065 0.3048)
			(stroke
				(width 0.1)
				(type default)
			)
			(layer "B.Fab")
		)
		(fp_line
			(start -0.120396 0.2794)
			(end 0.12065 0.2794)
			(stroke
				(width 0.1)
				(type default)
			)
			(layer "B.Fab")
		)
		(fp_line
			(start 0.67945 0.3048)
			(end 0.67945 -0.305054)
			(stroke
				(width 0.1)
				(type default)
			)
			(layer "B.Fab")
		)
		(fp_line
			(start 0.12065 0.3048)
			(end 0.67945 0.3048)
			(stroke
				(width 0.1)
				(type default)
			)
			(layer "B.Fab")
		)
		(fp_line
			(start -0.120396 0.3048)
			(end -0.120396 0.2794)
			(stroke
				(width 0.1)
				(type default)
			)
			(layer "B.Fab")
		)
		(fp_line
			(start -0.67945 0.3048)
			(end -0.120396 0.3048)
			(stroke
				(width 0.1)
				(type default)
			)
			(layer "B.Fab")
		)
		(pad "1" smd circle
			(at 0.40005 0 270)
			(size 0 0)
			(layers "B.Cu" "B.Mask" "B.Paste")
			(net "FM_USB3_1_FGA")
		)
		(pad "2" smd circle
			(at -0.40005 0 270)
			(size 0 0)
			(layers "B.Cu" "B.Mask" "B.Paste")
			(net "GND")
		)
	)
	(footprint ""
		(layer "B.Cu")
		(at 62.996572 -161.71926)
		(property "Reference" "PC2"
			(at 0 0 0)
			(layer "B.SilkS")
			(hide yes)
			(effects
				(font
					(size 1.27 1.27)
				)
				(justify mirror)
			)
		)
		(property "Value" ""
			(at 0 0 0)
			(layer "B.Fab")
			(effects
				(font
					(size 1.27 1.27)
				)
				(justify mirror)
			)
		)
		(duplicate_pad_numbers_are_jumpers no)
		(fp_line
			(start -1.524 -0.762)
			(end -1.524 0.762)
			(stroke
				(width 0.1524)
				(type default)
			)
			(layer "B.SilkS")
		)
		(fp_line
			(start -1.524 0.762)
			(end 1.524 0.762)
			(stroke
				(width 0.1524)
				(type default)
			)
			(layer "B.SilkS")
		)
		(fp_line
			(start 1.524 -0.762)
			(end -1.524 -0.762)
			(stroke
				(width 0.1524)
				(type default)
			)
			(layer "B.SilkS")
		)
		(fp_line
			(start 1.524 0.762)
			(end 1.524 -0.762)
			(stroke
				(width 0.1524)
				(type default)
			)
			(layer "B.SilkS")
		)
		(fp_line
			(start -1.1049 -0.724916)
			(end 1.1049 -0.724916)
			(stroke
				(width 0.1)
				(type default)
			)
			(layer "B.Fab")
		)
		(fp_line
			(start -1.1049 0.724916)
			(end -1.1049 -0.724916)
			(stroke
				(width 0.1)
				(type default)
			)
			(layer "B.Fab")
		)
		(fp_line
			(start 1.1049 -0.724916)
			(end 1.1049 0.724916)
			(stroke
				(width 0.1)
				(type default)
			)
			(layer "B.Fab")
		)
		(fp_line
			(start 1.1049 0.724916)
			(end -1.1049 0.724916)
			(stroke
				(width 0.1)
				(type default)
			)
			(layer "B.Fab")
		)
		(pad "1" smd rect
			(at 0.889 0)
			(size 1.016 1.27)
			(layers "B.Cu" "B.Mask" "B.Paste")
			(net "PVCCD_HV_CPU1")
		)
		(pad "2" smd rect
			(at -0.889 0)
			(size 1.016 1.27)
			(layers "B.Cu" "B.Mask" "B.Paste")
			(net "GND")
		)
	)
	(footprint ""
		(layer "B.Cu")
		(at 332.657196 -61.821314 45)
		(property "Reference" "C1272"
			(at 0 0 45)
			(layer "B.SilkS")
			(hide yes)
			(effects
				(font
					(size 1.27 1.27)
				)
				(justify mirror)
			)
		)
		(property "Value" ""
			(at 0 0 45)
			(layer "B.Fab")
			(effects
				(font
					(size 1.27 1.27)
				)
				(justify mirror)
			)
		)
		(duplicate_pad_numbers_are_jumpers no)
		(fp_line
			(start -1.523949 -0.762065)
			(end -1.523949 0.762065)
			(stroke
				(width 0.1524)
				(type default)
			)
			(layer "B.SilkS")
		)
		(fp_line
			(start -1.523949 0.762065)
			(end 1.523949 0.762065)
			(stroke
				(width 0.1524)
				(type default)
			)
			(layer "B.SilkS")
		)
		(fp_line
			(start 1.523949 -0.762065)
			(end -1.523949 -0.762065)
			(stroke
				(width 0.1524)
				(type default)
			)
			(layer "B.SilkS")
		)
		(fp_line
			(start 1.523949 0.762065)
			(end 1.523949 -0.762065)
			(stroke
				(width 0.1524)
				(type default)
			)
			(layer "B.SilkS")
		)
		(fp_line
			(start -1.104931 -0.724886)
			(end 1.104931 -0.724886)
			(stroke
				(width 0.1)
				(type default)
			)
			(layer "B.Fab")
		)
		(fp_line
			(start -1.104931 0.724886)
			(end -1.104931 -0.724886)
			(stroke
				(width 0.1)
				(type default)
			)
			(layer "B.Fab")
		)
		(fp_line
			(start 1.104931 -0.724886)
			(end 1.104931 0.724886)
			(stroke
				(width 0.1)
				(type default)
			)
			(layer "B.Fab")
		)
		(fp_line
			(start 1.104931 0.724886)
			(end -1.104931 0.724886)
			(stroke
				(width 0.1)
				(type default)
			)
			(layer "B.Fab")
		)
		(pad "1" smd rect
			(at 0.889 0 45)
			(size 1.016 1.27)
			(layers "B.Cu" "B.Mask" "B.Paste")
			(net "P1V05_PCH_PLL_AUX")
		)
		(pad "2" smd rect
			(at -0.889 0 45)
			(size 1.016 1.27)
			(layers "B.Cu" "B.Mask" "B.Paste")
			(net "GND")
		)
	)
	(footprint ""
		(layer "B.Cu")
		(at 180.155596 -114.575336 180)
		(property "Reference" "C1154"
			(at 0 0 0)
			(layer "B.SilkS")
			(hide yes)
			(effects
				(font
					(size 1.27 1.27)
				)
				(justify mirror)
			)
		)
		(property "Value" ""
			(at 0 0 0)
			(layer "B.Fab")
			(effects
				(font
					(size 1.27 1.27)
				)
				(justify mirror)
			)
		)
		(duplicate_pad_numbers_are_jumpers no)
		(fp_line
			(start 0.69215 0.2921)
			(end 0.69215 -0.2921)
			(stroke
				(width 0.1524)
				(type default)
			)
			(layer "B.SilkS")
		)
		(fp_line
			(start 0.69215 -0.2921)
			(end -0.69215 -0.2921)
			(stroke
				(width 0.1524)
				(type default)
			)
			(layer "B.SilkS")
		)
		(fp_line
			(start -0.69215 0.2921)
			(end 0.69215 0.2921)
			(stroke
				(width 0.1524)
				(type default)
			)
			(layer "B.SilkS")
		)
		(fp_line
			(start -0.69215 -0.2921)
			(end -0.69215 0.2921)
			(stroke
				(width 0.1524)
				(type default)
			)
			(layer "B.SilkS")
		)
		(fp_line
			(start 0.51435 0.2794)
			(end 0.51435 -0.2794)
			(stroke
				(width 0.1)
				(type default)
			)
			(layer "B.Fab")
		)
		(fp_line
			(start 0.51435 -0.2794)
			(end -0.51435 -0.2794)
			(stroke
				(width 0.1)
				(type default)
			)
			(layer "B.Fab")
		)
		(fp_line
			(start -0.51435 0.2794)
			(end 0.51435 0.2794)
			(stroke
				(width 0.1)
				(type default)
			)
			(layer "B.Fab")
		)
		(fp_line
			(start -0.51435 -0.2794)
			(end -0.51435 0.2794)
			(stroke
				(width 0.1)
				(type default)
			)
			(layer "B.Fab")
		)
		(pad "1" smd circle
			(at 0.40005 0)
			(size 0 0)
			(layers "B.Cu" "B.Mask" "B.Paste")
			(net "VCC_PLD_CORE")
		)
		(pad "2" smd circle
			(at -0.40005 0)
			(size 0 0)
			(layers "B.Cu" "B.Mask" "B.Paste")
			(net "GND")
		)
		(zone
			(layer "B.Cu")
			(hatch none 0.5)
			(connect_pads
				(clearance 0)
			)
			(min_thickness 0.25)
			(keepout
				(tracks not_allowed)
				(vias allowed)
				(pads allowed)
				(copperpour not_allowed)
				(footprints allowed)
			)
			(placement
				(enabled no)
				(sheetname "")
			)
			(fill
				(thermal_gap 0.5)
				(thermal_bridge_width 0.5)
				(island_removal_mode 0)
			)
			(polygon
				(pts
					(xy 179.965096 -114.662966) (xy 180.056536 -114.721132) (xy 180.255926 -114.721132) (xy 180.346096 -114.662966)
					(xy 180.346096 -114.487706) (xy 180.255926 -114.429286) (xy 180.056536 -114.429286) (xy 179.965096 -114.487452)
				)
			)
		)
	)
	(footprint ""
		(layer "B.Cu")
		(at 197.19036 -124.170948 180)
		(property "Reference" "R1106"
			(at 0 0 0)
			(layer "B.SilkS")
			(hide yes)
			(effects
				(font
					(size 1.27 1.27)
				)
				(justify mirror)
			)
		)
		(property "Value" ""
			(at 0 0 0)
			(layer "B.Fab")
			(effects
				(font
					(size 1.27 1.27)
				)
				(justify mirror)
			)
		)
		(duplicate_pad_numbers_are_jumpers no)
		(fp_line
			(start 0.7874 0.4064)
			(end 0.7874 -0.4064)
			(stroke
				(width 0.1524)
				(type default)
			)
			(layer "B.SilkS")
		)
		(fp_line
			(start 0.7874 -0.4064)
			(end -0.7874 -0.4064)
			(stroke
				(width 0.1524)
				(type default)
			)
			(layer "B.SilkS")
		)
		(fp_line
			(start -0.7874 0.4064)
			(end 0.7874 0.4064)
			(stroke
				(width 0.1524)
				(type default)
			)
			(layer "B.SilkS")
		)
		(fp_line
			(start -0.7874 -0.4064)
			(end -0.7874 0.4064)
			(stroke
				(width 0.1524)
				(type default)
			)
			(layer "B.SilkS")
		)
		(fp_line
			(start 0.67945 0.3048)
			(end 0.67945 -0.305054)
			(stroke
				(width 0.1)
				(type default)
			)
			(layer "B.Fab")
		)
		(fp_line
			(start 0.67945 -0.305054)
			(end 0.12065 -0.305054)
			(stroke
				(width 0.1)
				(type default)
			)
			(layer "B.Fab")
		)
		(fp_line
			(start 0.12065 0.3048)
			(end 0.67945 0.3048)
			(stroke
				(width 0.1)
				(type default)
			)
			(layer "B.Fab")
		)
		(fp_line
			(start 0.12065 0.2794)
			(end 0.12065 0.3048)
			(stroke
				(width 0.1)
				(type default)
			)
			(layer "B.Fab")
		)
		(fp_line
			(start 0.12065 -0.2794)
			(end -0.12065 -0.2794)
			(stroke
				(width 0.1)
				(type default)
			)
			(layer "B.Fab")
		)
		(fp_line
			(start 0.12065 -0.305054)
			(end 0.12065 -0.2794)
			(stroke
				(width 0.1)
				(type default)
			)
			(layer "B.Fab")
		)
		(fp_line
			(start -0.120396 0.3048)
			(end -0.120396 0.2794)
			(stroke
				(width 0.1)
				(type default)
			)
			(layer "B.Fab")
		)
		(fp_line
			(start -0.120396 0.2794)
			(end 0.12065 0.2794)
			(stroke
				(width 0.1)
				(type default)
			)
			(layer "B.Fab")
		)
		(fp_line
			(start -0.12065 -0.2794)
			(end -0.12065 -0.3048)
			(stroke
				(width 0.1)
				(type default)
			)
			(layer "B.Fab")
		)
		(fp_line
			(start -0.12065 -0.3048)
			(end -0.67945 -0.3048)
			(stroke
				(width 0.1)
				(type default)
			)
			(layer "B.Fab")
		)
		(fp_line
			(start -0.67945 0.3048)
			(end -0.120396 0.3048)
			(stroke
				(width 0.1)
				(type default)
			)
			(layer "B.Fab")
		)
		(fp_line
			(start -0.67945 -0.3048)
			(end -0.67945 0.3048)
			(stroke
				(width 0.1)
				(type default)
			)
			(layer "B.Fab")
		)
		(pad "1" smd circle
			(at 0.40005 0)
			(size 0 0)
			(layers "B.Cu" "B.Mask" "B.Paste")
			(net "P3V3_AUX")
		)
		(pad "2" smd circle
			(at -0.40005 0)
			(size 0 0)
			(layers "B.Cu" "B.Mask" "B.Paste")
			(net "FM_PLD_REV_R_N")
		)
	)
	(footprint ""
		(layer "B.Cu")
		(at 386.960872 -346.805504 -90)
		(property "Reference" "PC236_P0_8"
			(at 0 0 90)
			(layer "B.SilkS")
			(hide yes)
			(effects
				(font
					(size 1.27 1.27)
				)
				(justify mirror)
			)
		)
		(property "Value" ""
			(at 0 0 90)
			(layer "B.Fab")
			(effects
				(font
					(size 1.27 1.27)
				)
				(justify mirror)
			)
		)
		(duplicate_pad_numbers_are_jumpers no)
		(fp_line
			(start -1.524 0.762)
			(end 1.524 0.762)
			(stroke
				(width 0.1524)
				(type default)
			)
			(layer "B.SilkS")
		)
		(fp_line
			(start 1.524 0.762)
			(end 1.524 -0.762)
			(stroke
				(width 0.1524)
				(type default)
			)
			(layer "B.SilkS")
		)
		(fp_line
			(start -1.524 -0.762)
			(end -1.524 0.762)
			(stroke
				(width 0.1524)
				(type default)
			)
			(layer "B.SilkS")
		)
		(fp_line
			(start 1.524 -0.762)
			(end -1.524 -0.762)
			(stroke
				(width 0.1524)
				(type default)
			)
			(layer "B.SilkS")
		)
		(fp_line
			(start -1.1049 0.724916)
			(end -1.1049 -0.724916)
			(stroke
				(width 0.1)
				(type default)
			)
			(layer "B.Fab")
		)
		(fp_line
			(start 1.1049 0.724916)
			(end -1.1049 0.724916)
			(stroke
				(width 0.1)
				(type default)
			)
			(layer "B.Fab")
		)
		(fp_line
			(start -1.1049 -0.724916)
			(end 1.1049 -0.724916)
			(stroke
				(width 0.1)
				(type default)
			)
			(layer "B.Fab")
		)
		(fp_line
			(start 1.1049 -0.724916)
			(end 1.1049 0.724916)
			(stroke
				(width 0.1)
				(type default)
			)
			(layer "B.Fab")
		)
		(pad "1" smd rect
			(at 0.889 0 270)
			(size 1.016 1.27)
			(layers "B.Cu" "B.Mask" "B.Paste")
			(net "SW_P12V_PVCCIN_CPU0_FLT")
		)
		(pad "2" smd rect
			(at -0.889 0 270)
			(size 1.016 1.27)
			(layers "B.Cu" "B.Mask" "B.Paste")
			(net "GND")
		)
	)
	(footprint ""
		(layer "B.Cu")
		(at 109.658912 -336.186018 -90)
		(property "Reference" "PR302"
			(at 0 0 90)
			(layer "B.SilkS")
			(hide yes)
			(effects
				(font
					(size 1.27 1.27)
				)
				(justify mirror)
			)
		)
		(property "Value" ""
			(at 0 0 90)
			(layer "B.Fab")
			(effects
				(font
					(size 1.27 1.27)
				)
				(justify mirror)
			)
		)
		(duplicate_pad_numbers_are_jumpers no)
		(fp_line
			(start -0.7874 0.4064)
			(end 0.7874 0.4064)
			(stroke
				(width 0.1524)
				(type default)
			)
			(layer "B.SilkS")
		)
		(fp_line
			(start 0.7874 0.4064)
			(end 0.7874 -0.4064)
			(stroke
				(width 0.1524)
				(type default)
			)
			(layer "B.SilkS")
		)
		(fp_line
			(start -0.7874 -0.4064)
			(end -0.7874 0.4064)
			(stroke
				(width 0.1524)
				(type default)
			)
			(layer "B.SilkS")
		)
		(fp_line
			(start 0.7874 -0.4064)
			(end -0.7874 -0.4064)
			(stroke
				(width 0.1524)
				(type default)
			)
			(layer "B.SilkS")
		)
		(fp_line
			(start -0.67945 0.3048)
			(end -0.120396 0.3048)
			(stroke
				(width 0.1)
				(type default)
			)
			(layer "B.Fab")
		)
		(fp_line
			(start -0.120396 0.3048)
			(end -0.120396 0.2794)
			(stroke
				(width 0.1)
				(type default)
			)
			(layer "B.Fab")
		)
		(fp_line
			(start 0.12065 0.3048)
			(end 0.67945 0.3048)
			(stroke
				(width 0.1)
				(type default)
			)
			(layer "B.Fab")
		)
		(fp_line
			(start 0.67945 0.3048)
			(end 0.67945 -0.305054)
			(stroke
				(width 0.1)
				(type default)
			)
			(layer "B.Fab")
		)
		(fp_line
			(start -0.120396 0.2794)
			(end 0.12065 0.2794)
			(stroke
				(width 0.1)
				(type default)
			)
			(layer "B.Fab")
		)
		(fp_line
			(start 0.12065 0.2794)
			(end 0.12065 0.3048)
			(stroke
				(width 0.1)
				(type default)
			)
			(layer "B.Fab")
		)
		(fp_line
			(start -0.12065 -0.2794)
			(end -0.12065 -0.3048)
			(stroke
				(width 0.1)
				(type default)
			)
			(layer "B.Fab")
		)
		(fp_line
			(start 0.12065 -0.2794)
			(end -0.12065 -0.2794)
			(stroke
				(width 0.1)
				(type default)
			)
			(layer "B.Fab")
		)
		(fp_line
			(start -0.67945 -0.3048)
			(end -0.67945 0.3048)
			(stroke
				(width 0.1)
				(type default)
			)
			(layer "B.Fab")
		)
		(fp_line
			(start -0.12065 -0.3048)
			(end -0.67945 -0.3048)
			(stroke
				(width 0.1)
				(type default)
			)
			(layer "B.Fab")
		)
		(fp_line
			(start 0.12065 -0.305054)
			(end 0.12065 -0.2794)
			(stroke
				(width 0.1)
				(type default)
			)
			(layer "B.Fab")
		)
		(fp_line
			(start 0.67945 -0.305054)
			(end 0.12065 -0.305054)
			(stroke
				(width 0.1)
				(type default)
			)
			(layer "B.Fab")
		)
		(pad "1" smd circle
			(at 0.40005 0 90)
			(size 0 0)
			(layers "B.Cu" "B.Mask" "B.Paste")
			(net "PVCCIN_CPU1_VOS3")
		)
		(pad "2" smd circle
			(at -0.40005 0 90)
			(size 0 0)
			(layers "B.Cu" "B.Mask" "B.Paste")
			(net "PVCCIN_CPU1")
		)
	)
	(footprint ""
		(layer "B.Cu")
		(at 54.880002 -168.370758 180)
		(property "Reference" "PC378"
			(at 0 0 0)
			(layer "B.SilkS")
			(hide yes)
			(effects
				(font
					(size 1.27 1.27)
				)
				(justify mirror)
			)
		)
		(property "Value" ""
			(at 0 0 0)
			(layer "B.Fab")
			(effects
				(font
					(size 1.27 1.27)
				)
				(justify mirror)
			)
		)
		(duplicate_pad_numbers_are_jumpers no)
		(fp_line
			(start 1.524 0.762)
			(end 1.524 -0.762)
			(stroke
				(width 0.1524)
				(type default)
			)
			(layer "B.SilkS")
		)
		(fp_line
			(start 1.524 -0.762)
			(end -1.524 -0.762)
			(stroke
				(width 0.1524)
				(type default)
			)
			(layer "B.SilkS")
		)
		(fp_line
			(start -1.524 0.762)
			(end 1.524 0.762)
			(stroke
				(width 0.1524)
				(type default)
			)
			(layer "B.SilkS")
		)
		(fp_line
			(start -1.524 -0.762)
			(end -1.524 0.762)
			(stroke
				(width 0.1524)
				(type default)
			)
			(layer "B.SilkS")
		)
		(fp_line
			(start 1.1049 0.724916)
			(end -1.1049 0.724916)
			(stroke
				(width 0.1)
				(type default)
			)
			(layer "B.Fab")
		)
		(fp_line
			(start 1.1049 -0.724916)
			(end 1.1049 0.724916)
			(stroke
				(width 0.1)
				(type default)
			)
			(layer "B.Fab")
		)
		(fp_line
			(start -1.1049 0.724916)
			(end -1.1049 -0.724916)
			(stroke
				(width 0.1)
				(type default)
			)
			(layer "B.Fab")
		)
		(fp_line
			(start -1.1049 -0.724916)
			(end 1.1049 -0.724916)
			(stroke
				(width 0.1)
				(type default)
			)
			(layer "B.Fab")
		)
		(pad "1" smd rect
			(at 0.889 0 180)
			(size 1.016 1.27)
			(layers "B.Cu" "B.Mask" "B.Paste")
			(net "SW_P12V_PVCCINFAON_CPU1_FLT")
		)
		(pad "2" smd rect
			(at -0.889 0 180)
			(size 1.016 1.27)
			(layers "B.Cu" "B.Mask" "B.Paste")
			(net "GND")
		)
	)
	(footprint ""
		(layer "B.Cu")
		(at 256.631948 -419.142672 90)
		(property "Reference" "PD15"
			(at 4.7244 -3.851148 90)
			(unlocked yes)
			(layer "B.SilkS")
			(effects
				(font
					(size 0.7874 0.5842)
					(thickness 0.1524)
				)
				(justify left mirror)
			)
		)
		(property "Value" ""
			(at 0 0 90)
			(layer "B.Fab")
			(effects
				(font
					(size 1.27 1.27)
				)
				(justify mirror)
			)
		)
		(duplicate_pad_numbers_are_jumpers no)
		(fp_line
			(start 4.664456 -3.109976)
			(end -4.743704 -3.109976)
			(stroke
				(width 0.1524)
				(type default)
			)
			(layer "B.SilkS")
		)
		(fp_line
			(start -4.183126 -3.109976)
			(end -4.794504 -3.109976)
			(stroke
				(width 0.1524)
				(type default)
			)
			(layer "B.SilkS")
		)
		(fp_line
			(start -4.511802 -3.109976)
			(end -4.207002 -3.109976)
			(stroke
				(width 0.1524)
				(type default)
			)
			(layer "B.SilkS")
		)
		(fp_line
			(start -4.6101 -3.109976)
			(end -4.283202 -3.109976)
			(stroke
				(width 0.1524)
				(type default)
			)
			(layer "B.SilkS")
		)
		(fp_line
			(start -4.695444 -3.109976)
			(end -4.695444 3.109976)
			(stroke
				(width 0.1524)
				(type default)
			)
			(layer "B.SilkS")
		)
		(fp_line
			(start -4.70535 -3.109976)
			(end -4.70535 3.109976)
			(stroke
				(width 0.1524)
				(type default)
			)
			(layer "B.SilkS")
		)
		(fp_line
			(start -4.70535 -3.109976)
			(end -4.70535 3.109976)
			(stroke
				(width 0.1524)
				(type default)
			)
			(layer "B.SilkS")
		)
		(fp_line
			(start -4.70535 -3.109976)
			(end -4.70535 3.109976)
			(stroke
				(width 0.1524)
				(type default)
			)
			(layer "B.SilkS")
		)
		(fp_line
			(start -4.805426 -3.109976)
			(end -4.805426 3.109976)
			(stroke
				(width 0.1524)
				(type default)
			)
			(layer "B.SilkS")
		)
		(fp_line
			(start -4.932426 -3.109976)
			(end -4.932426 3.109976)
			(stroke
				(width 0.1524)
				(type default)
			)
			(layer "B.SilkS")
		)
		(fp_line
			(start -5.008626 -3.109976)
			(end -5.008626 3.109976)
			(stroke
				(width 0.1524)
				(type default)
			)
			(layer "B.SilkS")
		)
		(fp_line
			(start -5.110226 -3.109976)
			(end -5.110226 3.109976)
			(stroke
				(width 0.1524)
				(type default)
			)
			(layer "B.SilkS")
		)
		(fp_line
			(start -5.211826 -3.109976)
			(end -5.211826 3.109976)
			(stroke
				(width 0.1524)
				(type default)
			)
			(layer "B.SilkS")
		)
		(fp_line
			(start -5.262626 -3.109976)
			(end -5.262626 3.109976)
			(stroke
				(width 0.1524)
				(type default)
			)
			(layer "B.SilkS")
		)
		(fp_line
			(start -5.313426 -3.109976)
			(end -5.313426 3.109976)
			(stroke
				(width 0.1524)
				(type default)
			)
			(layer "B.SilkS")
		)
		(fp_line
			(start -5.4102 -3.109976)
			(end -4.783074 -3.109976)
			(stroke
				(width 0.1524)
				(type default)
			)
			(layer "B.SilkS")
		)
		(fp_line
			(start 0.508 -1.016)
			(end -0.762 0)
			(stroke
				(width 0.1524)
				(type default)
			)
			(layer "B.SilkS")
		)
		(fp_line
			(start 1.0668 0)
			(end 0.6096 0)
			(stroke
				(width 0.1524)
				(type default)
			)
			(layer "B.SilkS")
		)
		(fp_line
			(start -0.762 0)
			(end -1.2192 0)
			(stroke
				(width 0.1524)
				(type default)
			)
			(layer "B.SilkS")
		)
		(fp_line
			(start -0.762 0)
			(end 0.508 1.016)
			(stroke
				(width 0.1524)
				(type default)
			)
			(layer "B.SilkS")
		)
		(fp_line
			(start 0.508 1.016)
			(end 0.508 -1.016)
			(stroke
				(width 0.1524)
				(type default)
			)
			(layer "B.SilkS")
		)
		(fp_line
			(start -0.762 1.27)
			(end -0.762 -1.27)
			(stroke
				(width 0.1524)
				(type default)
			)
			(layer "B.SilkS")
		)
		(fp_line
			(start -4.715002 3.035554)
			(end -4.7117 2.984754)
			(stroke
				(width 0.1524)
				(type default)
			)
			(layer "B.SilkS")
		)
		(fp_line
			(start 4.664456 3.109976)
			(end 4.664456 -3.109976)
			(stroke
				(width 0.1524)
				(type default)
			)
			(layer "B.SilkS")
		)
		(fp_line
			(start -4.156202 3.109976)
			(end -4.183126 3.109976)
			(stroke
				(width 0.1524)
				(type default)
			)
			(layer "B.SilkS")
		)
		(fp_line
			(start -4.743704 3.109976)
			(end -4.6101 3.109976)
			(stroke
				(width 0.1524)
				(type default)
			)
			(layer "B.SilkS")
		)
		(fp_line
			(start -4.743704 3.109976)
			(end -5.4102 3.109976)
			(stroke
				(width 0.1524)
				(type default)
			)
			(layer "B.SilkS")
		)
		(fp_line
			(start -4.769104 3.109976)
			(end 4.664456 3.109976)
			(stroke
				(width 0.1524)
				(type default)
			)
			(layer "B.SilkS")
		)
		(fp_line
			(start -4.794504 3.109976)
			(end -3.554984 3.109976)
			(stroke
				(width 0.1524)
				(type default)
			)
			(layer "B.SilkS")
		)
		(fp_line
			(start -5.4102 3.109976)
			(end -5.4102 -3.109976)
			(stroke
				(width 0.1524)
				(type default)
			)
			(layer "B.SilkS")
		)
		(fp_line
			(start 4.065016 -3.109976)
			(end -4.065016 -3.109976)
			(stroke
				(width 0.1)
				(type default)
			)
			(layer "B.Fab")
		)
		(fp_line
			(start -4.065016 -3.109976)
			(end -4.065016 3.109976)
			(stroke
				(width 0.1)
				(type default)
			)
			(layer "B.Fab")
		)
		(fp_line
			(start 4.065016 3.109976)
			(end 4.065016 -3.109976)
			(stroke
				(width 0.1)
				(type default)
			)
			(layer "B.Fab")
		)
		(fp_line
			(start -4.065016 3.109976)
			(end 4.065016 3.109976)
			(stroke
				(width 0.1)
				(type default)
			)
			(layer "B.Fab")
		)
		(fp_text user "+"
			(at 4.5974 0.24765 270)
			(unlocked yes)
			(layer "B.SilkS")
			(effects
				(font
					(size 1.905 1.4224)
					(thickness 0.1524)
				)
				(justify left mirror)
			)
		)
		(fp_text user "-"
			(at -6.643624 0.40005 270)
			(unlocked yes)
			(layer "B.SilkS")
			(effects
				(font
					(size 1.905 1.4224)
					(thickness 0.1524)
				)
				(justify left mirror)
			)
		)
		(fp_text user "+"
			(at 4.5974 0.24765 270)
			(unlocked yes)
			(layer "B.Fab")
			(effects
				(font
					(size 1.905 1.4224)
					(thickness 0.1524)
				)
				(justify left mirror)
			)
		)
		(fp_text user "-"
			(at -6.643624 0.40005 270)
			(unlocked yes)
			(layer "B.Fab")
			(effects
				(font
					(size 1.905 1.4224)
					(thickness 0.1524)
				)
				(justify left mirror)
			)
		)
		(pad "A" smd rect
			(at 3.299968 0 90)
			(size 2.413 3.302)
			(layers "B.Cu" "B.Mask" "B.Paste")
			(net "GND")
		)
		(pad "C" smd rect
			(at -3.299968 0 90)
			(size 2.413 3.302)
			(layers "B.Cu" "B.Mask" "B.Paste")
			(net "P12V_PSU_FUSE")
		)
	)
	(footprint ""
		(layer "B.Cu")
		(at 203.072746 -75.053952)
		(property "Reference" "R3210"
			(at 0 0 0)
			(layer "B.SilkS")
			(hide yes)
			(effects
				(font
					(size 1.27 1.27)
				)
				(justify mirror)
			)
		)
		(property "Value" ""
			(at 0 0 0)
			(layer "B.Fab")
			(effects
				(font
					(size 1.27 1.27)
				)
				(justify mirror)
			)
		)
		(duplicate_pad_numbers_are_jumpers no)
		(fp_line
			(start -0.7874 -0.4064)
			(end -0.7874 0.4064)
			(stroke
				(width 0.1524)
				(type default)
			)
			(layer "B.SilkS")
		)
		(fp_line
			(start -0.7874 0.4064)
			(end 0.7874 0.4064)
			(stroke
				(width 0.1524)
				(type default)
			)
			(layer "B.SilkS")
		)
		(fp_line
			(start 0.7874 -0.4064)
			(end -0.7874 -0.4064)
			(stroke
				(width 0.1524)
				(type default)
			)
			(layer "B.SilkS")
		)
		(fp_line
			(start 0.7874 0.4064)
			(end 0.7874 -0.4064)
			(stroke
				(width 0.1524)
				(type default)
			)
			(layer "B.SilkS")
		)
		(fp_line
			(start -0.67945 -0.3048)
			(end -0.67945 0.3048)
			(stroke
				(width 0.1)
				(type default)
			)
			(layer "B.Fab")
		)
		(fp_line
			(start -0.67945 0.3048)
			(end -0.120396 0.3048)
			(stroke
				(width 0.1)
				(type default)
			)
			(layer "B.Fab")
		)
		(fp_line
			(start -0.12065 -0.3048)
			(end -0.67945 -0.3048)
			(stroke
				(width 0.1)
				(type default)
			)
			(layer "B.Fab")
		)
		(fp_line
			(start -0.12065 -0.2794)
			(end -0.12065 -0.3048)
			(stroke
				(width 0.1)
				(type default)
			)
			(layer "B.Fab")
		)
		(fp_line
			(start -0.120396 0.2794)
			(end 0.12065 0.2794)
			(stroke
				(width 0.1)
				(type default)
			)
			(layer "B.Fab")
		)
		(fp_line
			(start -0.120396 0.3048)
			(end -0.120396 0.2794)
			(stroke
				(width 0.1)
				(type default)
			)
			(layer "B.Fab")
		)
		(fp_line
			(start 0.12065 -0.305054)
			(end 0.12065 -0.2794)
			(stroke
				(width 0.1)
				(type default)
			)
			(layer "B.Fab")
		)
		(fp_line
			(start 0.12065 -0.2794)
			(end -0.12065 -0.2794)
			(stroke
				(width 0.1)
				(type default)
			)
			(layer "B.Fab")
		)
		(fp_line
			(start 0.12065 0.2794)
			(end 0.12065 0.3048)
			(stroke
				(width 0.1)
				(type default)
			)
			(layer "B.Fab")
		)
		(fp_line
			(start 0.12065 0.3048)
			(end 0.67945 0.3048)
			(stroke
				(width 0.1)
				(type default)
			)
			(layer "B.Fab")
		)
		(fp_line
			(start 0.67945 -0.305054)
			(end 0.12065 -0.305054)
			(stroke
				(width 0.1)
				(type default)
			)
			(layer "B.Fab")
		)
		(fp_line
			(start 0.67945 0.3048)
			(end 0.67945 -0.305054)
			(stroke
				(width 0.1)
				(type default)
			)
			(layer "B.Fab")
		)
		(pad "1" smd circle
			(at 0.40005 0 180)
			(size 0 0)
			(layers "B.Cu" "B.Mask" "B.Paste")
			(net "NCSI_BMC_CRS_DV_R1")
		)
		(pad "2" smd circle
			(at -0.40005 0 180)
			(size 0 0)
			(layers "B.Cu" "B.Mask" "B.Paste")
			(net "RMII_OCP_BMC_CRSDV")
		)
	)
	(footprint ""
		(layer "B.Cu")
		(at 113.78438 -362.703872 180)
		(property "Reference" "PR323"
			(at 0 0 0)
			(layer "B.SilkS")
			(hide yes)
			(effects
				(font
					(size 1.27 1.27)
				)
				(justify mirror)
			)
		)
		(property "Value" ""
			(at 0 0 0)
			(layer "B.Fab")
			(effects
				(font
					(size 1.27 1.27)
				)
				(justify mirror)
			)
		)
		(duplicate_pad_numbers_are_jumpers no)
		(fp_line
			(start 0.7874 0.4064)
			(end 0.7874 -0.4064)
			(stroke
				(width 0.1524)
				(type default)
			)
			(layer "B.SilkS")
		)
		(fp_line
			(start 0.7874 -0.4064)
			(end -0.7874 -0.4064)
			(stroke
				(width 0.1524)
				(type default)
			)
			(layer "B.SilkS")
		)
		(fp_line
			(start -0.7874 0.4064)
			(end 0.7874 0.4064)
			(stroke
				(width 0.1524)
				(type default)
			)
			(layer "B.SilkS")
		)
		(fp_line
			(start -0.7874 -0.4064)
			(end -0.7874 0.4064)
			(stroke
				(width 0.1524)
				(type default)
			)
			(layer "B.SilkS")
		)
		(fp_line
			(start 0.67945 0.3048)
			(end 0.67945 -0.305054)
			(stroke
				(width 0.1)
				(type default)
			)
			(layer "B.Fab")
		)
		(fp_line
			(start 0.67945 -0.305054)
			(end 0.12065 -0.305054)
			(stroke
				(width 0.1)
				(type default)
			)
			(layer "B.Fab")
		)
		(fp_line
			(start 0.12065 0.3048)
			(end 0.67945 0.3048)
			(stroke
				(width 0.1)
				(type default)
			)
			(layer "B.Fab")
		)
		(fp_line
			(start 0.12065 0.2794)
			(end 0.12065 0.3048)
			(stroke
				(width 0.1)
				(type default)
			)
			(layer "B.Fab")
		)
		(fp_line
			(start 0.12065 -0.2794)
			(end -0.12065 -0.2794)
			(stroke
				(width 0.1)
				(type default)
			)
			(layer "B.Fab")
		)
		(fp_line
			(start 0.12065 -0.305054)
			(end 0.12065 -0.2794)
			(stroke
				(width 0.1)
				(type default)
			)
			(layer "B.Fab")
		)
		(fp_line
			(start -0.120396 0.3048)
			(end -0.120396 0.2794)
			(stroke
				(width 0.1)
				(type default)
			)
			(layer "B.Fab")
		)
		(fp_line
			(start -0.120396 0.2794)
			(end 0.12065 0.2794)
			(stroke
				(width 0.1)
				(type default)
			)
			(layer "B.Fab")
		)
		(fp_line
			(start -0.12065 -0.2794)
			(end -0.12065 -0.3048)
			(stroke
				(width 0.1)
				(type default)
			)
			(layer "B.Fab")
		)
		(fp_line
			(start -0.12065 -0.3048)
			(end -0.67945 -0.3048)
			(stroke
				(width 0.1)
				(type default)
			)
			(layer "B.Fab")
		)
		(fp_line
			(start -0.67945 0.3048)
			(end -0.120396 0.3048)
			(stroke
				(width 0.1)
				(type default)
			)
			(layer "B.Fab")
		)
		(fp_line
			(start -0.67945 -0.3048)
			(end -0.67945 0.3048)
			(stroke
				(width 0.1)
				(type default)
			)
			(layer "B.Fab")
		)
		(pad "1" smd circle
			(at 0.40005 0)
			(size 0 0)
			(layers "B.Cu" "B.Mask" "B.Paste")
			(net "PVCCIN_CPU1_VCC")
		)
		(pad "2" smd circle
			(at -0.40005 0)
			(size 0 0)
			(layers "B.Cu" "B.Mask" "B.Paste")
			(net "P3V3_AUX")
		)
	)
	(footprint ""
		(layer "B.Cu")
		(at 351.841308 -259.532882 -90)
		(property "Reference" "C496"
			(at 0 0 90)
			(layer "B.SilkS")
			(hide yes)
			(effects
				(font
					(size 1.27 1.27)
				)
				(justify mirror)
			)
		)
		(property "Value" ""
			(at 0 0 90)
			(layer "B.Fab")
			(effects
				(font
					(size 1.27 1.27)
				)
				(justify mirror)
			)
		)
		(duplicate_pad_numbers_are_jumpers no)
		(fp_line
			(start -1.524 0.762)
			(end 1.524 0.762)
			(stroke
				(width 0.1524)
				(type default)
			)
			(layer "B.SilkS")
		)
		(fp_line
			(start 1.524 0.762)
			(end 1.524 -0.762)
			(stroke
				(width 0.1524)
				(type default)
			)
			(layer "B.SilkS")
		)
		(fp_line
			(start -1.524 -0.762)
			(end -1.524 0.762)
			(stroke
				(width 0.1524)
				(type default)
			)
			(layer "B.SilkS")
		)
		(fp_line
			(start 1.524 -0.762)
			(end -1.524 -0.762)
			(stroke
				(width 0.1524)
				(type default)
			)
			(layer "B.SilkS")
		)
		(fp_line
			(start -1.1049 0.724916)
			(end -1.1049 -0.724916)
			(stroke
				(width 0.1)
				(type default)
			)
			(layer "B.Fab")
		)
		(fp_line
			(start 1.1049 0.724916)
			(end -1.1049 0.724916)
			(stroke
				(width 0.1)
				(type default)
			)
			(layer "B.Fab")
		)
		(fp_line
			(start -1.1049 -0.724916)
			(end 1.1049 -0.724916)
			(stroke
				(width 0.1)
				(type default)
			)
			(layer "B.Fab")
		)
		(fp_line
			(start 1.1049 -0.724916)
			(end 1.1049 0.724916)
			(stroke
				(width 0.1)
				(type default)
			)
			(layer "B.Fab")
		)
		(pad "1" smd rect
			(at 0.889 0 270)
			(size 1.016 1.27)
			(layers "B.Cu" "B.Mask" "B.Paste")
			(net "PVCCFA_EHV_CPU0")
		)
		(pad "2" smd rect
			(at -0.889 0 270)
			(size 1.016 1.27)
			(layers "B.Cu" "B.Mask" "B.Paste")
			(net "GND")
		)
	)
	(footprint ""
		(layer "B.Cu")
		(at 72.401684 -190.744856 90)
		(property "Reference" "R58"
			(at 0 0 90)
			(layer "B.SilkS")
			(hide yes)
			(effects
				(font
					(size 1.27 1.27)
				)
				(justify mirror)
			)
		)
		(property "Value" ""
			(at 0 0 90)
			(layer "B.Fab")
			(effects
				(font
					(size 1.27 1.27)
				)
				(justify mirror)
			)
		)
		(duplicate_pad_numbers_are_jumpers no)
		(fp_line
			(start 0.7874 -0.4064)
			(end -0.7874 -0.4064)
			(stroke
				(width 0.1524)
				(type default)
			)
			(layer "B.SilkS")
		)
		(fp_line
			(start -0.7874 -0.4064)
			(end -0.7874 0.4064)
			(stroke
				(width 0.1524)
				(type default)
			)
			(layer "B.SilkS")
		)
		(fp_line
			(start 0.7874 0.4064)
			(end 0.7874 -0.4064)
			(stroke
				(width 0.1524)
				(type default)
			)
			(layer "B.SilkS")
		)
		(fp_line
			(start -0.7874 0.4064)
			(end 0.7874 0.4064)
			(stroke
				(width 0.1524)
				(type default)
			)
			(layer "B.SilkS")
		)
		(fp_line
			(start 0.67945 -0.305054)
			(end 0.12065 -0.305054)
			(stroke
				(width 0.1)
				(type default)
			)
			(layer "B.Fab")
		)
		(fp_line
			(start 0.12065 -0.305054)
			(end 0.12065 -0.2794)
			(stroke
				(width 0.1)
				(type default)
			)
			(layer "B.Fab")
		)
		(fp_line
			(start -0.12065 -0.3048)
			(end -0.67945 -0.3048)
			(stroke
				(width 0.1)
				(type default)
			)
			(layer "B.Fab")
		)
		(fp_line
			(start -0.67945 -0.3048)
			(end -0.67945 0.3048)
			(stroke
				(width 0.1)
				(type default)
			)
			(layer "B.Fab")
		)
		(fp_line
			(start 0.12065 -0.2794)
			(end -0.12065 -0.2794)
			(stroke
				(width 0.1)
				(type default)
			)
			(layer "B.Fab")
		)
		(fp_line
			(start -0.12065 -0.2794)
			(end -0.12065 -0.3048)
			(stroke
				(width 0.1)
				(type default)
			)
			(layer "B.Fab")
		)
		(fp_line
			(start 0.12065 0.2794)
			(end 0.12065 0.3048)
			(stroke
				(width 0.1)
				(type default)
			)
			(layer "B.Fab")
		)
		(fp_line
			(start -0.120396 0.2794)
			(end 0.12065 0.2794)
			(stroke
				(width 0.1)
				(type default)
			)
			(layer "B.Fab")
		)
		(fp_line
			(start 0.67945 0.3048)
			(end 0.67945 -0.305054)
			(stroke
				(width 0.1)
				(type default)
			)
			(layer "B.Fab")
		)
		(fp_line
			(start 0.12065 0.3048)
			(end 0.67945 0.3048)
			(stroke
				(width 0.1)
				(type default)
			)
			(layer "B.Fab")
		)
		(fp_line
			(start -0.120396 0.3048)
			(end -0.120396 0.2794)
			(stroke
				(width 0.1)
				(type default)
			)
			(layer "B.Fab")
		)
		(fp_line
			(start -0.67945 0.3048)
			(end -0.120396 0.3048)
			(stroke
				(width 0.1)
				(type default)
			)
			(layer "B.Fab")
		)
		(pad "1" smd circle
			(at 0.40005 0 270)
			(size 0 0)
			(layers "B.Cu" "B.Mask" "B.Paste")
			(net "SVID_DIO1_CPU1")
		)
		(pad "2" smd circle
			(at -0.40005 0 270)
			(size 0 0)
			(layers "B.Cu" "B.Mask" "B.Paste")
			(net "SVID_DIO1_CPU1_R")
		)
	)
	(footprint ""
		(layer "B.Cu")
		(at 297.45813 -400.999452 -90)
		(property "Reference" "PR2524"
			(at 0 0 90)
			(layer "B.SilkS")
			(hide yes)
			(effects
				(font
					(size 1.27 1.27)
				)
				(justify mirror)
			)
		)
		(property "Value" ""
			(at 0 0 90)
			(layer "B.Fab")
			(effects
				(font
					(size 1.27 1.27)
				)
				(justify mirror)
			)
		)
		(duplicate_pad_numbers_are_jumpers no)
		(fp_line
			(start -0.7874 0.4064)
			(end 0.7874 0.4064)
			(stroke
				(width 0.1524)
				(type default)
			)
			(layer "B.SilkS")
		)
		(fp_line
			(start 0.7874 0.4064)
			(end 0.7874 -0.4064)
			(stroke
				(width 0.1524)
				(type default)
			)
			(layer "B.SilkS")
		)
		(fp_line
			(start -0.7874 -0.4064)
			(end -0.7874 0.4064)
			(stroke
				(width 0.1524)
				(type default)
			)
			(layer "B.SilkS")
		)
		(fp_line
			(start 0.7874 -0.4064)
			(end -0.7874 -0.4064)
			(stroke
				(width 0.1524)
				(type default)
			)
			(layer "B.SilkS")
		)
		(fp_line
			(start -0.67945 0.3048)
			(end -0.120396 0.3048)
			(stroke
				(width 0.1)
				(type default)
			)
			(layer "B.Fab")
		)
		(fp_line
			(start -0.120396 0.3048)
			(end -0.120396 0.2794)
			(stroke
				(width 0.1)
				(type default)
			)
			(layer "B.Fab")
		)
		(fp_line
			(start 0.12065 0.3048)
			(end 0.67945 0.3048)
			(stroke
				(width 0.1)
				(type default)
			)
			(layer "B.Fab")
		)
		(fp_line
			(start 0.67945 0.3048)
			(end 0.67945 -0.305054)
			(stroke
				(width 0.1)
				(type default)
			)
			(layer "B.Fab")
		)
		(fp_line
			(start -0.120396 0.2794)
			(end 0.12065 0.2794)
			(stroke
				(width 0.1)
				(type default)
			)
			(layer "B.Fab")
		)
		(fp_line
			(start 0.12065 0.2794)
			(end 0.12065 0.3048)
			(stroke
				(width 0.1)
				(type default)
			)
			(layer "B.Fab")
		)
		(fp_line
			(start -0.12065 -0.2794)
			(end -0.12065 -0.3048)
			(stroke
				(width 0.1)
				(type default)
			)
			(layer "B.Fab")
		)
		(fp_line
			(start 0.12065 -0.2794)
			(end -0.12065 -0.2794)
			(stroke
				(width 0.1)
				(type default)
			)
			(layer "B.Fab")
		)
		(fp_line
			(start -0.67945 -0.3048)
			(end -0.67945 0.3048)
			(stroke
				(width 0.1)
				(type default)
			)
			(layer "B.Fab")
		)
		(fp_line
			(start -0.12065 -0.3048)
			(end -0.67945 -0.3048)
			(stroke
				(width 0.1)
				(type default)
			)
			(layer "B.Fab")
		)
		(fp_line
			(start 0.12065 -0.305054)
			(end 0.12065 -0.2794)
			(stroke
				(width 0.1)
				(type default)
			)
			(layer "B.Fab")
		)
		(fp_line
			(start 0.67945 -0.305054)
			(end 0.12065 -0.305054)
			(stroke
				(width 0.1)
				(type default)
			)
			(layer "B.Fab")
		)
		(pad "1" smd circle
			(at 0.40005 0 90)
			(size 0 0)
			(layers "B.Cu" "B.Mask" "B.Paste")
			(net "P12V_HSC_SENSE2_N")
		)
		(pad "2" smd circle
			(at -0.40005 0 90)
			(size 0 0)
			(layers "B.Cu" "B.Mask" "B.Paste")
			(net "P12V_HSC_SENSE2_R1_N")
		)
	)
	(footprint ""
		(layer "B.Cu")
		(at 338.4042 -52.0446 180)
		(property "Reference" "R4803"
			(at 0 0 0)
			(layer "B.SilkS")
			(hide yes)
			(effects
				(font
					(size 1.27 1.27)
				)
				(justify mirror)
			)
		)
		(property "Value" ""
			(at 0 0 0)
			(layer "B.Fab")
			(effects
				(font
					(size 1.27 1.27)
				)
				(justify mirror)
			)
		)
		(duplicate_pad_numbers_are_jumpers no)
		(fp_line
			(start 0.7874 0.4064)
			(end 0.7874 -0.4064)
			(stroke
				(width 0.1524)
				(type default)
			)
			(layer "B.SilkS")
		)
		(fp_line
			(start 0.7874 -0.4064)
			(end -0.7874 -0.4064)
			(stroke
				(width 0.1524)
				(type default)
			)
			(layer "B.SilkS")
		)
		(fp_line
			(start -0.7874 0.4064)
			(end 0.7874 0.4064)
			(stroke
				(width 0.1524)
				(type default)
			)
			(layer "B.SilkS")
		)
		(fp_line
			(start -0.7874 -0.4064)
			(end -0.7874 0.4064)
			(stroke
				(width 0.1524)
				(type default)
			)
			(layer "B.SilkS")
		)
		(fp_line
			(start 0.67945 0.3048)
			(end 0.67945 -0.305054)
			(stroke
				(width 0.1)
				(type default)
			)
			(layer "B.Fab")
		)
		(fp_line
			(start 0.67945 -0.305054)
			(end 0.12065 -0.305054)
			(stroke
				(width 0.1)
				(type default)
			)
			(layer "B.Fab")
		)
		(fp_line
			(start 0.12065 0.3048)
			(end 0.67945 0.3048)
			(stroke
				(width 0.1)
				(type default)
			)
			(layer "B.Fab")
		)
		(fp_line
			(start 0.12065 0.2794)
			(end 0.12065 0.3048)
			(stroke
				(width 0.1)
				(type default)
			)
			(layer "B.Fab")
		)
		(fp_line
			(start 0.12065 -0.2794)
			(end -0.12065 -0.2794)
			(stroke
				(width 0.1)
				(type default)
			)
			(layer "B.Fab")
		)
		(fp_line
			(start 0.12065 -0.305054)
			(end 0.12065 -0.2794)
			(stroke
				(width 0.1)
				(type default)
			)
			(layer "B.Fab")
		)
		(fp_line
			(start -0.120396 0.3048)
			(end -0.120396 0.2794)
			(stroke
				(width 0.1)
				(type default)
			)
			(layer "B.Fab")
		)
		(fp_line
			(start -0.120396 0.2794)
			(end 0.12065 0.2794)
			(stroke
				(width 0.1)
				(type default)
			)
			(layer "B.Fab")
		)
		(fp_line
			(start -0.12065 -0.2794)
			(end -0.12065 -0.3048)
			(stroke
				(width 0.1)
				(type default)
			)
			(layer "B.Fab")
		)
		(fp_line
			(start -0.12065 -0.3048)
			(end -0.67945 -0.3048)
			(stroke
				(width 0.1)
				(type default)
			)
			(layer "B.Fab")
		)
		(fp_line
			(start -0.67945 0.3048)
			(end -0.120396 0.3048)
			(stroke
				(width 0.1)
				(type default)
			)
			(layer "B.Fab")
		)
		(fp_line
			(start -0.67945 -0.3048)
			(end -0.67945 0.3048)
			(stroke
				(width 0.1)
				(type default)
			)
			(layer "B.Fab")
		)
		(pad "1" smd circle
			(at 0.40005 0)
			(size 0 0)
			(layers "B.Cu" "B.Mask" "B.Paste")
			(net "P1V05_PCH_AUX")
		)
		(pad "2" smd circle
			(at -0.40005 0)
			(size 0 0)
			(layers "B.Cu" "B.Mask" "B.Paste")
			(net "P1V05_PCH_PLL_AUX")
		)
	)
	(footprint ""
		(layer "B.Cu")
		(at 312.578242 -39.794688 180)
		(property "Reference" "R1498"
			(at 0 0 0)
			(layer "B.SilkS")
			(hide yes)
			(effects
				(font
					(size 1.27 1.27)
				)
				(justify mirror)
			)
		)
		(property "Value" ""
			(at 0 0 0)
			(layer "B.Fab")
			(effects
				(font
					(size 1.27 1.27)
				)
				(justify mirror)
			)
		)
		(duplicate_pad_numbers_are_jumpers no)
		(fp_line
			(start 0.7874 0.4064)
			(end 0.7874 -0.4064)
			(stroke
				(width 0.1524)
				(type default)
			)
			(layer "B.SilkS")
		)
		(fp_line
			(start 0.7874 -0.4064)
			(end -0.7874 -0.4064)
			(stroke
				(width 0.1524)
				(type default)
			)
			(layer "B.SilkS")
		)
		(fp_line
			(start -0.7874 0.4064)
			(end 0.7874 0.4064)
			(stroke
				(width 0.1524)
				(type default)
			)
			(layer "B.SilkS")
		)
		(fp_line
			(start -0.7874 -0.4064)
			(end -0.7874 0.4064)
			(stroke
				(width 0.1524)
				(type default)
			)
			(layer "B.SilkS")
		)
		(fp_line
			(start 0.67945 0.3048)
			(end 0.67945 -0.305054)
			(stroke
				(width 0.1)
				(type default)
			)
			(layer "B.Fab")
		)
		(fp_line
			(start 0.67945 -0.305054)
			(end 0.12065 -0.305054)
			(stroke
				(width 0.1)
				(type default)
			)
			(layer "B.Fab")
		)
		(fp_line
			(start 0.12065 0.3048)
			(end 0.67945 0.3048)
			(stroke
				(width 0.1)
				(type default)
			)
			(layer "B.Fab")
		)
		(fp_line
			(start 0.12065 0.2794)
			(end 0.12065 0.3048)
			(stroke
				(width 0.1)
				(type default)
			)
			(layer "B.Fab")
		)
		(fp_line
			(start 0.12065 -0.2794)
			(end -0.12065 -0.2794)
			(stroke
				(width 0.1)
				(type default)
			)
			(layer "B.Fab")
		)
		(fp_line
			(start 0.12065 -0.305054)
			(end 0.12065 -0.2794)
			(stroke
				(width 0.1)
				(type default)
			)
			(layer "B.Fab")
		)
		(fp_line
			(start -0.120396 0.3048)
			(end -0.120396 0.2794)
			(stroke
				(width 0.1)
				(type default)
			)
			(layer "B.Fab")
		)
		(fp_line
			(start -0.120396 0.2794)
			(end 0.12065 0.2794)
			(stroke
				(width 0.1)
				(type default)
			)
			(layer "B.Fab")
		)
		(fp_line
			(start -0.12065 -0.2794)
			(end -0.12065 -0.3048)
			(stroke
				(width 0.1)
				(type default)
			)
			(layer "B.Fab")
		)
		(fp_line
			(start -0.12065 -0.3048)
			(end -0.67945 -0.3048)
			(stroke
				(width 0.1)
				(type default)
			)
			(layer "B.Fab")
		)
		(fp_line
			(start -0.67945 0.3048)
			(end -0.120396 0.3048)
			(stroke
				(width 0.1)
				(type default)
			)
			(layer "B.Fab")
		)
		(fp_line
			(start -0.67945 -0.3048)
			(end -0.67945 0.3048)
			(stroke
				(width 0.1)
				(type default)
			)
			(layer "B.Fab")
		)
		(pad "1" smd circle
			(at 0.40005 0)
			(size 0 0)
			(layers "B.Cu" "B.Mask" "B.Paste")
			(net "P1V05_PCH_AUX")
		)
		(pad "2" smd circle
			(at -0.40005 0)
			(size 0 0)
			(layers "B.Cu" "B.Mask" "B.Paste")
			(net "FM_BIOS_ADV_FUNCTIONS")
		)
	)
	(footprint ""
		(layer "B.Cu")
		(at 428.669958 -118.6053)
		(property "Reference" "PR375"
			(at 0 0 0)
			(layer "B.SilkS")
			(hide yes)
			(effects
				(font
					(size 1.27 1.27)
				)
				(justify mirror)
			)
		)
		(property "Value" ""
			(at 0 0 0)
			(layer "B.Fab")
			(effects
				(font
					(size 1.27 1.27)
				)
				(justify mirror)
			)
		)
		(duplicate_pad_numbers_are_jumpers no)
		(fp_line
			(start -0.7874 -0.4064)
			(end -0.7874 0.4064)
			(stroke
				(width 0.1524)
				(type default)
			)
			(layer "B.SilkS")
		)
		(fp_line
			(start -0.7874 0.4064)
			(end 0.7874 0.4064)
			(stroke
				(width 0.1524)
				(type default)
			)
			(layer "B.SilkS")
		)
		(fp_line
			(start 0.7874 -0.4064)
			(end -0.7874 -0.4064)
			(stroke
				(width 0.1524)
				(type default)
			)
			(layer "B.SilkS")
		)
		(fp_line
			(start 0.7874 0.4064)
			(end 0.7874 -0.4064)
			(stroke
				(width 0.1524)
				(type default)
			)
			(layer "B.SilkS")
		)
		(fp_line
			(start -0.67945 -0.3048)
			(end -0.67945 0.3048)
			(stroke
				(width 0.1)
				(type default)
			)
			(layer "B.Fab")
		)
		(fp_line
			(start -0.67945 0.3048)
			(end -0.120396 0.3048)
			(stroke
				(width 0.1)
				(type default)
			)
			(layer "B.Fab")
		)
		(fp_line
			(start -0.12065 -0.3048)
			(end -0.67945 -0.3048)
			(stroke
				(width 0.1)
				(type default)
			)
			(layer "B.Fab")
		)
		(fp_line
			(start -0.12065 -0.2794)
			(end -0.12065 -0.3048)
			(stroke
				(width 0.1)
				(type default)
			)
			(layer "B.Fab")
		)
		(fp_line
			(start -0.120396 0.2794)
			(end 0.12065 0.2794)
			(stroke
				(width 0.1)
				(type default)
			)
			(layer "B.Fab")
		)
		(fp_line
			(start -0.120396 0.3048)
			(end -0.120396 0.2794)
			(stroke
				(width 0.1)
				(type default)
			)
			(layer "B.Fab")
		)
		(fp_line
			(start 0.12065 -0.305054)
			(end 0.12065 -0.2794)
			(stroke
				(width 0.1)
				(type default)
			)
			(layer "B.Fab")
		)
		(fp_line
			(start 0.12065 -0.2794)
			(end -0.12065 -0.2794)
			(stroke
				(width 0.1)
				(type default)
			)
			(layer "B.Fab")
		)
		(fp_line
			(start 0.12065 0.2794)
			(end 0.12065 0.3048)
			(stroke
				(width 0.1)
				(type default)
			)
			(layer "B.Fab")
		)
		(fp_line
			(start 0.12065 0.3048)
			(end 0.67945 0.3048)
			(stroke
				(width 0.1)
				(type default)
			)
			(layer "B.Fab")
		)
		(fp_line
			(start 0.67945 -0.305054)
			(end 0.12065 -0.305054)
			(stroke
				(width 0.1)
				(type default)
			)
			(layer "B.Fab")
		)
		(fp_line
			(start 0.67945 0.3048)
			(end 0.67945 -0.305054)
			(stroke
				(width 0.1)
				(type default)
			)
			(layer "B.Fab")
		)
		(pad "1" smd circle
			(at 0.40005 0 180)
			(size 0 0)
			(layers "B.Cu" "B.Mask" "B.Paste")
			(net "PVCCD_HV_CPU0_VCC")
		)
		(pad "2" smd circle
			(at -0.40005 0 180)
			(size 0 0)
			(layers "B.Cu" "B.Mask" "B.Paste")
			(net "P3V3_AUX")
		)
	)
	(footprint ""
		(layer "B.Cu")
		(at 315.110622 -53.203348)
		(property "Reference" "R4108"
			(at 0 0 0)
			(layer "B.SilkS")
			(hide yes)
			(effects
				(font
					(size 1.27 1.27)
				)
				(justify mirror)
			)
		)
		(property "Value" ""
			(at 0 0 0)
			(layer "B.Fab")
			(effects
				(font
					(size 1.27 1.27)
				)
				(justify mirror)
			)
		)
		(duplicate_pad_numbers_are_jumpers no)
		(fp_line
			(start -0.7874 -0.4064)
			(end -0.7874 0.4064)
			(stroke
				(width 0.1524)
				(type default)
			)
			(layer "B.SilkS")
		)
		(fp_line
			(start -0.7874 0.4064)
			(end 0.7874 0.4064)
			(stroke
				(width 0.1524)
				(type default)
			)
			(layer "B.SilkS")
		)
		(fp_line
			(start 0.7874 -0.4064)
			(end -0.7874 -0.4064)
			(stroke
				(width 0.1524)
				(type default)
			)
			(layer "B.SilkS")
		)
		(fp_line
			(start 0.7874 0.4064)
			(end 0.7874 -0.4064)
			(stroke
				(width 0.1524)
				(type default)
			)
			(layer "B.SilkS")
		)
		(fp_line
			(start -0.67945 -0.3048)
			(end -0.67945 0.3048)
			(stroke
				(width 0.1)
				(type default)
			)
			(layer "B.Fab")
		)
		(fp_line
			(start -0.67945 0.3048)
			(end -0.120396 0.3048)
			(stroke
				(width 0.1)
				(type default)
			)
			(layer "B.Fab")
		)
		(fp_line
			(start -0.12065 -0.3048)
			(end -0.67945 -0.3048)
			(stroke
				(width 0.1)
				(type default)
			)
			(layer "B.Fab")
		)
		(fp_line
			(start -0.12065 -0.2794)
			(end -0.12065 -0.3048)
			(stroke
				(width 0.1)
				(type default)
			)
			(layer "B.Fab")
		)
		(fp_line
			(start -0.120396 0.2794)
			(end 0.12065 0.2794)
			(stroke
				(width 0.1)
				(type default)
			)
			(layer "B.Fab")
		)
		(fp_line
			(start -0.120396 0.3048)
			(end -0.120396 0.2794)
			(stroke
				(width 0.1)
				(type default)
			)
			(layer "B.Fab")
		)
		(fp_line
			(start 0.12065 -0.305054)
			(end 0.12065 -0.2794)
			(stroke
				(width 0.1)
				(type default)
			)
			(layer "B.Fab")
		)
		(fp_line
			(start 0.12065 -0.2794)
			(end -0.12065 -0.2794)
			(stroke
				(width 0.1)
				(type default)
			)
			(layer "B.Fab")
		)
		(fp_line
			(start 0.12065 0.2794)
			(end 0.12065 0.3048)
			(stroke
				(width 0.1)
				(type default)
			)
			(layer "B.Fab")
		)
		(fp_line
			(start 0.12065 0.3048)
			(end 0.67945 0.3048)
			(stroke
				(width 0.1)
				(type default)
			)
			(layer "B.Fab")
		)
		(fp_line
			(start 0.67945 -0.305054)
			(end 0.12065 -0.305054)
			(stroke
				(width 0.1)
				(type default)
			)
			(layer "B.Fab")
		)
		(fp_line
			(start 0.67945 0.3048)
			(end 0.67945 -0.305054)
			(stroke
				(width 0.1)
				(type default)
			)
			(layer "B.Fab")
		)
		(pad "1" smd circle
			(at 0.40005 0 180)
			(size 0 0)
			(layers "B.Cu" "B.Mask" "B.Paste")
			(net "PD_GPP_I_16")
		)
		(pad "2" smd circle
			(at -0.40005 0 180)
			(size 0 0)
			(layers "B.Cu" "B.Mask" "B.Paste")
			(net "GND")
		)
	)
	(footprint ""
		(layer "B.Cu")
		(at 387.90499 -190.82131 90)
		(property "Reference" "R322"
			(at 0 0 90)
			(layer "B.SilkS")
			(hide yes)
			(effects
				(font
					(size 1.27 1.27)
				)
				(justify mirror)
			)
		)
		(property "Value" ""
			(at 0 0 90)
			(layer "B.Fab")
			(effects
				(font
					(size 1.27 1.27)
				)
				(justify mirror)
			)
		)
		(duplicate_pad_numbers_are_jumpers no)
		(fp_line
			(start 0.7874 -0.4064)
			(end -0.7874 -0.4064)
			(stroke
				(width 0.1524)
				(type default)
			)
			(layer "B.SilkS")
		)
		(fp_line
			(start -0.7874 -0.4064)
			(end -0.7874 0.4064)
			(stroke
				(width 0.1524)
				(type default)
			)
			(layer "B.SilkS")
		)
		(fp_line
			(start 0.7874 0.4064)
			(end 0.7874 -0.4064)
			(stroke
				(width 0.1524)
				(type default)
			)
			(layer "B.SilkS")
		)
		(fp_line
			(start -0.7874 0.4064)
			(end 0.7874 0.4064)
			(stroke
				(width 0.1524)
				(type default)
			)
			(layer "B.SilkS")
		)
		(fp_line
			(start 0.67945 -0.305054)
			(end 0.12065 -0.305054)
			(stroke
				(width 0.1)
				(type default)
			)
			(layer "B.Fab")
		)
		(fp_line
			(start 0.12065 -0.305054)
			(end 0.12065 -0.2794)
			(stroke
				(width 0.1)
				(type default)
			)
			(layer "B.Fab")
		)
		(fp_line
			(start -0.12065 -0.3048)
			(end -0.67945 -0.3048)
			(stroke
				(width 0.1)
				(type default)
			)
			(layer "B.Fab")
		)
		(fp_line
			(start -0.67945 -0.3048)
			(end -0.67945 0.3048)
			(stroke
				(width 0.1)
				(type default)
			)
			(layer "B.Fab")
		)
		(fp_line
			(start 0.12065 -0.2794)
			(end -0.12065 -0.2794)
			(stroke
				(width 0.1)
				(type default)
			)
			(layer "B.Fab")
		)
		(fp_line
			(start -0.12065 -0.2794)
			(end -0.12065 -0.3048)
			(stroke
				(width 0.1)
				(type default)
			)
			(layer "B.Fab")
		)
		(fp_line
			(start 0.12065 0.2794)
			(end 0.12065 0.3048)
			(stroke
				(width 0.1)
				(type default)
			)
			(layer "B.Fab")
		)
		(fp_line
			(start -0.120396 0.2794)
			(end 0.12065 0.2794)
			(stroke
				(width 0.1)
				(type default)
			)
			(layer "B.Fab")
		)
		(fp_line
			(start 0.67945 0.3048)
			(end 0.67945 -0.305054)
			(stroke
				(width 0.1)
				(type default)
			)
			(layer "B.Fab")
		)
		(fp_line
			(start 0.12065 0.3048)
			(end 0.67945 0.3048)
			(stroke
				(width 0.1)
				(type default)
			)
			(layer "B.Fab")
		)
		(fp_line
			(start -0.120396 0.3048)
			(end -0.120396 0.2794)
			(stroke
				(width 0.1)
				(type default)
			)
			(layer "B.Fab")
		)
		(fp_line
			(start -0.67945 0.3048)
			(end -0.120396 0.3048)
			(stroke
				(width 0.1)
				(type default)
			)
			(layer "B.Fab")
		)
		(pad "1" smd circle
			(at 0.40005 0 270)
			(size 0 0)
			(layers "B.Cu" "B.Mask" "B.Paste")
			(net "H_CPU0_PMSYNC_CPU1_R")
		)
		(pad "2" smd circle
			(at -0.40005 0 270)
			(size 0 0)
			(layers "B.Cu" "B.Mask" "B.Paste")
			(net "H_CPU0_PMSYNC_CPU1_R1")
		)
	)
	(footprint ""
		(layer "B.Cu")
		(at 180.449982 -105.120186 90)
		(property "Reference" "R166"
			(at 0 0 90)
			(layer "B.SilkS")
			(hide yes)
			(effects
				(font
					(size 1.27 1.27)
				)
				(justify mirror)
			)
		)
		(property "Value" ""
			(at 0 0 90)
			(layer "B.Fab")
			(effects
				(font
					(size 1.27 1.27)
				)
				(justify mirror)
			)
		)
		(duplicate_pad_numbers_are_jumpers no)
		(fp_line
			(start 0.7874 -0.4064)
			(end -0.7874 -0.4064)
			(stroke
				(width 0.1524)
				(type default)
			)
			(layer "B.SilkS")
		)
		(fp_line
			(start -0.7874 -0.4064)
			(end -0.7874 0.4064)
			(stroke
				(width 0.1524)
				(type default)
			)
			(layer "B.SilkS")
		)
		(fp_line
			(start 0.7874 0.4064)
			(end 0.7874 -0.4064)
			(stroke
				(width 0.1524)
				(type default)
			)
			(layer "B.SilkS")
		)
		(fp_line
			(start -0.7874 0.4064)
			(end 0.7874 0.4064)
			(stroke
				(width 0.1524)
				(type default)
			)
			(layer "B.SilkS")
		)
		(fp_line
			(start 0.67945 -0.305054)
			(end 0.12065 -0.305054)
			(stroke
				(width 0.1)
				(type default)
			)
			(layer "B.Fab")
		)
		(fp_line
			(start 0.12065 -0.305054)
			(end 0.12065 -0.2794)
			(stroke
				(width 0.1)
				(type default)
			)
			(layer "B.Fab")
		)
		(fp_line
			(start -0.12065 -0.3048)
			(end -0.67945 -0.3048)
			(stroke
				(width 0.1)
				(type default)
			)
			(layer "B.Fab")
		)
		(fp_line
			(start -0.67945 -0.3048)
			(end -0.67945 0.3048)
			(stroke
				(width 0.1)
				(type default)
			)
			(layer "B.Fab")
		)
		(fp_line
			(start 0.12065 -0.2794)
			(end -0.12065 -0.2794)
			(stroke
				(width 0.1)
				(type default)
			)
			(layer "B.Fab")
		)
		(fp_line
			(start -0.12065 -0.2794)
			(end -0.12065 -0.3048)
			(stroke
				(width 0.1)
				(type default)
			)
			(layer "B.Fab")
		)
		(fp_line
			(start 0.12065 0.2794)
			(end 0.12065 0.3048)
			(stroke
				(width 0.1)
				(type default)
			)
			(layer "B.Fab")
		)
		(fp_line
			(start -0.120396 0.2794)
			(end 0.12065 0.2794)
			(stroke
				(width 0.1)
				(type default)
			)
			(layer "B.Fab")
		)
		(fp_line
			(start 0.67945 0.3048)
			(end 0.67945 -0.305054)
			(stroke
				(width 0.1)
				(type default)
			)
			(layer "B.Fab")
		)
		(fp_line
			(start 0.12065 0.3048)
			(end 0.67945 0.3048)
			(stroke
				(width 0.1)
				(type default)
			)
			(layer "B.Fab")
		)
		(fp_line
			(start -0.120396 0.3048)
			(end -0.120396 0.2794)
			(stroke
				(width 0.1)
				(type default)
			)
			(layer "B.Fab")
		)
		(fp_line
			(start -0.67945 0.3048)
			(end -0.120396 0.3048)
			(stroke
				(width 0.1)
				(type default)
			)
			(layer "B.Fab")
		)
		(pad "1" smd circle
			(at 0.40005 0 270)
			(size 0 0)
			(layers "B.Cu" "B.Mask" "B.Paste")
			(net "PWRGD_DRAMPWRGD_CPU0_GH_R_LVC1")
		)
		(pad "2" smd circle
			(at -0.40005 0 270)
			(size 0 0)
			(layers "B.Cu" "B.Mask" "B.Paste")
			(net "PWRGD_DRAMPWRGD_CPU0_GH_LVC1_R2")
		)
	)
	(footprint ""
		(layer "B.Cu")
		(at 283.82468 -354.028502 -90)
		(property "Reference" "PR4265"
			(at 0 0 90)
			(layer "B.SilkS")
			(hide yes)
			(effects
				(font
					(size 1.27 1.27)
				)
				(justify mirror)
			)
		)
		(property "Value" ""
			(at 0 0 90)
			(layer "B.Fab")
			(effects
				(font
					(size 1.27 1.27)
				)
				(justify mirror)
			)
		)
		(duplicate_pad_numbers_are_jumpers no)
		(fp_line
			(start -0.7874 0.4064)
			(end 0.7874 0.4064)
			(stroke
				(width 0.1524)
				(type default)
			)
			(layer "B.SilkS")
		)
		(fp_line
			(start 0.7874 0.4064)
			(end 0.7874 -0.4064)
			(stroke
				(width 0.1524)
				(type default)
			)
			(layer "B.SilkS")
		)
		(fp_line
			(start -0.7874 -0.4064)
			(end -0.7874 0.4064)
			(stroke
				(width 0.1524)
				(type default)
			)
			(layer "B.SilkS")
		)
		(fp_line
			(start 0.7874 -0.4064)
			(end -0.7874 -0.4064)
			(stroke
				(width 0.1524)
				(type default)
			)
			(layer "B.SilkS")
		)
		(fp_line
			(start -0.67945 0.3048)
			(end -0.120396 0.3048)
			(stroke
				(width 0.1)
				(type default)
			)
			(layer "B.Fab")
		)
		(fp_line
			(start -0.120396 0.3048)
			(end -0.120396 0.2794)
			(stroke
				(width 0.1)
				(type default)
			)
			(layer "B.Fab")
		)
		(fp_line
			(start 0.12065 0.3048)
			(end 0.67945 0.3048)
			(stroke
				(width 0.1)
				(type default)
			)
			(layer "B.Fab")
		)
		(fp_line
			(start 0.67945 0.3048)
			(end 0.67945 -0.305054)
			(stroke
				(width 0.1)
				(type default)
			)
			(layer "B.Fab")
		)
		(fp_line
			(start -0.120396 0.2794)
			(end 0.12065 0.2794)
			(stroke
				(width 0.1)
				(type default)
			)
			(layer "B.Fab")
		)
		(fp_line
			(start 0.12065 0.2794)
			(end 0.12065 0.3048)
			(stroke
				(width 0.1)
				(type default)
			)
			(layer "B.Fab")
		)
		(fp_line
			(start -0.12065 -0.2794)
			(end -0.12065 -0.3048)
			(stroke
				(width 0.1)
				(type default)
			)
			(layer "B.Fab")
		)
		(fp_line
			(start 0.12065 -0.2794)
			(end -0.12065 -0.2794)
			(stroke
				(width 0.1)
				(type default)
			)
			(layer "B.Fab")
		)
		(fp_line
			(start -0.67945 -0.3048)
			(end -0.67945 0.3048)
			(stroke
				(width 0.1)
				(type default)
			)
			(layer "B.Fab")
		)
		(fp_line
			(start -0.12065 -0.3048)
			(end -0.67945 -0.3048)
			(stroke
				(width 0.1)
				(type default)
			)
			(layer "B.Fab")
		)
		(fp_line
			(start 0.12065 -0.305054)
			(end 0.12065 -0.2794)
			(stroke
				(width 0.1)
				(type default)
			)
			(layer "B.Fab")
		)
		(fp_line
			(start 0.67945 -0.305054)
			(end 0.12065 -0.305054)
			(stroke
				(width 0.1)
				(type default)
			)
			(layer "B.Fab")
		)
		(pad "1" smd circle
			(at 0.40005 0 90)
			(size 0 0)
			(layers "B.Cu" "B.Mask" "B.Paste")
			(net "PVCCFA_EHV_FIVRA_CPU0")
		)
		(pad "2" smd circle
			(at -0.40005 0 90)
			(size 0 0)
			(layers "B.Cu" "B.Mask" "B.Paste")
			(net "GND")
		)
	)
	(footprint ""
		(layer "B.Cu")
		(at 272.444972 -68.4784)
		(property "Reference" "PC1226"
			(at 0 0 0)
			(layer "B.SilkS")
			(hide yes)
			(effects
				(font
					(size 1.27 1.27)
				)
				(justify mirror)
			)
		)
		(property "Value" ""
			(at 0 0 0)
			(layer "B.Fab")
			(effects
				(font
					(size 1.27 1.27)
				)
				(justify mirror)
			)
		)
		(duplicate_pad_numbers_are_jumpers no)
		(fp_line
			(start -1.524 -0.762)
			(end -1.524 0.762)
			(stroke
				(width 0.1524)
				(type default)
			)
			(layer "B.SilkS")
		)
		(fp_line
			(start -1.524 0.762)
			(end 1.524 0.762)
			(stroke
				(width 0.1524)
				(type default)
			)
			(layer "B.SilkS")
		)
		(fp_line
			(start 1.524 -0.762)
			(end -1.524 -0.762)
			(stroke
				(width 0.1524)
				(type default)
			)
			(layer "B.SilkS")
		)
		(fp_line
			(start 1.524 0.762)
			(end 1.524 -0.762)
			(stroke
				(width 0.1524)
				(type default)
			)
			(layer "B.SilkS")
		)
		(fp_line
			(start -1.1049 -0.724916)
			(end 1.1049 -0.724916)
			(stroke
				(width 0.1)
				(type default)
			)
			(layer "B.Fab")
		)
		(fp_line
			(start -1.1049 0.724916)
			(end -1.1049 -0.724916)
			(stroke
				(width 0.1)
				(type default)
			)
			(layer "B.Fab")
		)
		(fp_line
			(start 1.1049 -0.724916)
			(end 1.1049 0.724916)
			(stroke
				(width 0.1)
				(type default)
			)
			(layer "B.Fab")
		)
		(fp_line
			(start 1.1049 0.724916)
			(end -1.1049 0.724916)
			(stroke
				(width 0.1)
				(type default)
			)
			(layer "B.Fab")
		)
		(pad "1" smd rect
			(at 0.889 0)
			(size 1.016 1.27)
			(layers "B.Cu" "B.Mask" "B.Paste")
			(net "P1V05_PCH_AUX")
		)
		(pad "2" smd rect
			(at -0.889 0)
			(size 1.016 1.27)
			(layers "B.Cu" "B.Mask" "B.Paste")
			(net "GND")
		)
	)
	(footprint ""
		(layer "B.Cu")
		(at 186.331352 -344.656664 -90)
		(property "Reference" "PC1206_P1_3"
			(at 0 0 90)
			(layer "B.SilkS")
			(hide yes)
			(effects
				(font
					(size 1.27 1.27)
				)
				(justify mirror)
			)
		)
		(property "Value" ""
			(at 0 0 90)
			(layer "B.Fab")
			(effects
				(font
					(size 1.27 1.27)
				)
				(justify mirror)
			)
		)
		(duplicate_pad_numbers_are_jumpers no)
		(fp_line
			(start -1.524 0.762)
			(end 1.524 0.762)
			(stroke
				(width 0.1524)
				(type default)
			)
			(layer "B.SilkS")
		)
		(fp_line
			(start 1.524 0.762)
			(end 1.524 -0.762)
			(stroke
				(width 0.1524)
				(type default)
			)
			(layer "B.SilkS")
		)
		(fp_line
			(start -1.524 -0.762)
			(end -1.524 0.762)
			(stroke
				(width 0.1524)
				(type default)
			)
			(layer "B.SilkS")
		)
		(fp_line
			(start 1.524 -0.762)
			(end -1.524 -0.762)
			(stroke
				(width 0.1524)
				(type default)
			)
			(layer "B.SilkS")
		)
		(fp_line
			(start -1.1049 0.724916)
			(end -1.1049 -0.724916)
			(stroke
				(width 0.1)
				(type default)
			)
			(layer "B.Fab")
		)
		(fp_line
			(start 1.1049 0.724916)
			(end -1.1049 0.724916)
			(stroke
				(width 0.1)
				(type default)
			)
			(layer "B.Fab")
		)
		(fp_line
			(start -1.1049 -0.724916)
			(end 1.1049 -0.724916)
			(stroke
				(width 0.1)
				(type default)
			)
			(layer "B.Fab")
		)
		(fp_line
			(start 1.1049 -0.724916)
			(end 1.1049 0.724916)
			(stroke
				(width 0.1)
				(type default)
			)
			(layer "B.Fab")
		)
		(pad "1" smd rect
			(at 0.889 0 270)
			(size 1.016 1.27)
			(layers "B.Cu" "B.Mask" "B.Paste")
			(net "PVCCFA_EHV_FIVRA_CPU1")
		)
		(pad "2" smd rect
			(at -0.889 0 270)
			(size 1.016 1.27)
			(layers "B.Cu" "B.Mask" "B.Paste")
			(net "GND")
		)
	)
	(footprint ""
		(layer "B.Cu")
		(at 180.90388 -329.479148 180)
		(property "Reference" "R1932"
			(at 0 0 0)
			(layer "B.SilkS")
			(hide yes)
			(effects
				(font
					(size 1.27 1.27)
				)
				(justify mirror)
			)
		)
		(property "Value" ""
			(at 0 0 0)
			(layer "B.Fab")
			(effects
				(font
					(size 1.27 1.27)
				)
				(justify mirror)
			)
		)
		(duplicate_pad_numbers_are_jumpers no)
		(fp_line
			(start 0.7874 0.4064)
			(end 0.7874 -0.4064)
			(stroke
				(width 0.1524)
				(type default)
			)
			(layer "B.SilkS")
		)
		(fp_line
			(start 0.7874 -0.4064)
			(end -0.7874 -0.4064)
			(stroke
				(width 0.1524)
				(type default)
			)
			(layer "B.SilkS")
		)
		(fp_line
			(start -0.7874 0.4064)
			(end 0.7874 0.4064)
			(stroke
				(width 0.1524)
				(type default)
			)
			(layer "B.SilkS")
		)
		(fp_line
			(start -0.7874 -0.4064)
			(end -0.7874 0.4064)
			(stroke
				(width 0.1524)
				(type default)
			)
			(layer "B.SilkS")
		)
		(fp_line
			(start 0.67945 0.3048)
			(end 0.67945 -0.305054)
			(stroke
				(width 0.1)
				(type default)
			)
			(layer "B.Fab")
		)
		(fp_line
			(start 0.67945 -0.305054)
			(end 0.12065 -0.305054)
			(stroke
				(width 0.1)
				(type default)
			)
			(layer "B.Fab")
		)
		(fp_line
			(start 0.12065 0.3048)
			(end 0.67945 0.3048)
			(stroke
				(width 0.1)
				(type default)
			)
			(layer "B.Fab")
		)
		(fp_line
			(start 0.12065 0.2794)
			(end 0.12065 0.3048)
			(stroke
				(width 0.1)
				(type default)
			)
			(layer "B.Fab")
		)
		(fp_line
			(start 0.12065 -0.2794)
			(end -0.12065 -0.2794)
			(stroke
				(width 0.1)
				(type default)
			)
			(layer "B.Fab")
		)
		(fp_line
			(start 0.12065 -0.305054)
			(end 0.12065 -0.2794)
			(stroke
				(width 0.1)
				(type default)
			)
			(layer "B.Fab")
		)
		(fp_line
			(start -0.120396 0.3048)
			(end -0.120396 0.2794)
			(stroke
				(width 0.1)
				(type default)
			)
			(layer "B.Fab")
		)
		(fp_line
			(start -0.120396 0.2794)
			(end 0.12065 0.2794)
			(stroke
				(width 0.1)
				(type default)
			)
			(layer "B.Fab")
		)
		(fp_line
			(start -0.12065 -0.2794)
			(end -0.12065 -0.3048)
			(stroke
				(width 0.1)
				(type default)
			)
			(layer "B.Fab")
		)
		(fp_line
			(start -0.12065 -0.3048)
			(end -0.67945 -0.3048)
			(stroke
				(width 0.1)
				(type default)
			)
			(layer "B.Fab")
		)
		(fp_line
			(start -0.67945 0.3048)
			(end -0.120396 0.3048)
			(stroke
				(width 0.1)
				(type default)
			)
			(layer "B.Fab")
		)
		(fp_line
			(start -0.67945 -0.3048)
			(end -0.67945 0.3048)
			(stroke
				(width 0.1)
				(type default)
			)
			(layer "B.Fab")
		)
		(pad "1" smd circle
			(at 0.40005 0)
			(size 0 0)
			(layers "B.Cu" "B.Mask" "B.Paste")
			(net "SMB_S3M_CPU0_PIROM_3V3AUX_SCL")
		)
		(pad "2" smd circle
			(at -0.40005 0)
			(size 0 0)
			(layers "B.Cu" "B.Mask" "B.Paste")
			(net "SMB_S3M_CPU0_PIROM_3V3AUX_SCL_1")
		)
	)
	(footprint ""
		(layer "B.Cu")
		(at 336.494882 -187.387738 180)
		(property "Reference" "R687"
			(at 0 0 0)
			(layer "B.SilkS")
			(hide yes)
			(effects
				(font
					(size 1.27 1.27)
				)
				(justify mirror)
			)
		)
		(property "Value" ""
			(at 0 0 0)
			(layer "B.Fab")
			(effects
				(font
					(size 1.27 1.27)
				)
				(justify mirror)
			)
		)
		(duplicate_pad_numbers_are_jumpers no)
		(fp_line
			(start 0.7874 0.4064)
			(end 0.7874 -0.4064)
			(stroke
				(width 0.1524)
				(type default)
			)
			(layer "B.SilkS")
		)
		(fp_line
			(start 0.7874 -0.4064)
			(end -0.7874 -0.4064)
			(stroke
				(width 0.1524)
				(type default)
			)
			(layer "B.SilkS")
		)
		(fp_line
			(start -0.7874 0.4064)
			(end 0.7874 0.4064)
			(stroke
				(width 0.1524)
				(type default)
			)
			(layer "B.SilkS")
		)
		(fp_line
			(start -0.7874 -0.4064)
			(end -0.7874 0.4064)
			(stroke
				(width 0.1524)
				(type default)
			)
			(layer "B.SilkS")
		)
		(fp_line
			(start 0.67945 0.3048)
			(end 0.67945 -0.305054)
			(stroke
				(width 0.1)
				(type default)
			)
			(layer "B.Fab")
		)
		(fp_line
			(start 0.67945 -0.305054)
			(end 0.12065 -0.305054)
			(stroke
				(width 0.1)
				(type default)
			)
			(layer "B.Fab")
		)
		(fp_line
			(start 0.12065 0.3048)
			(end 0.67945 0.3048)
			(stroke
				(width 0.1)
				(type default)
			)
			(layer "B.Fab")
		)
		(fp_line
			(start 0.12065 0.2794)
			(end 0.12065 0.3048)
			(stroke
				(width 0.1)
				(type default)
			)
			(layer "B.Fab")
		)
		(fp_line
			(start 0.12065 -0.2794)
			(end -0.12065 -0.2794)
			(stroke
				(width 0.1)
				(type default)
			)
			(layer "B.Fab")
		)
		(fp_line
			(start 0.12065 -0.305054)
			(end 0.12065 -0.2794)
			(stroke
				(width 0.1)
				(type default)
			)
			(layer "B.Fab")
		)
		(fp_line
			(start -0.120396 0.3048)
			(end -0.120396 0.2794)
			(stroke
				(width 0.1)
				(type default)
			)
			(layer "B.Fab")
		)
		(fp_line
			(start -0.120396 0.2794)
			(end 0.12065 0.2794)
			(stroke
				(width 0.1)
				(type default)
			)
			(layer "B.Fab")
		)
		(fp_line
			(start -0.12065 -0.2794)
			(end -0.12065 -0.3048)
			(stroke
				(width 0.1)
				(type default)
			)
			(layer "B.Fab")
		)
		(fp_line
			(start -0.12065 -0.3048)
			(end -0.67945 -0.3048)
			(stroke
				(width 0.1)
				(type default)
			)
			(layer "B.Fab")
		)
		(fp_line
			(start -0.67945 0.3048)
			(end -0.120396 0.3048)
			(stroke
				(width 0.1)
				(type default)
			)
			(layer "B.Fab")
		)
		(fp_line
			(start -0.67945 -0.3048)
			(end -0.67945 0.3048)
			(stroke
				(width 0.1)
				(type default)
			)
			(layer "B.Fab")
		)
		(pad "1" smd circle
			(at 0.40005 0)
			(size 0 0)
			(layers "B.Cu" "B.Mask" "B.Paste")
			(net "I3C_SPD_DDRABCD_CPU0_SCL")
		)
		(pad "2" smd circle
			(at -0.40005 0)
			(size 0 0)
			(layers "B.Cu" "B.Mask" "B.Paste")
			(net "I3C_SPD_DDRABCD_CPU0_R_SCL")
		)
	)
	(footprint ""
		(layer "B.Cu")
		(at 162.95624 -250.300236 90)
		(property "Reference" "C485"
			(at 0 0 90)
			(layer "B.SilkS")
			(hide yes)
			(effects
				(font
					(size 1.27 1.27)
				)
				(justify mirror)
			)
		)
		(property "Value" ""
			(at 0 0 90)
			(layer "B.Fab")
			(effects
				(font
					(size 1.27 1.27)
				)
				(justify mirror)
			)
		)
		(duplicate_pad_numbers_are_jumpers no)
		(fp_line
			(start 1.524 -0.762)
			(end -1.524 -0.762)
			(stroke
				(width 0.1524)
				(type default)
			)
			(layer "B.SilkS")
		)
		(fp_line
			(start -1.524 -0.762)
			(end -1.524 0.762)
			(stroke
				(width 0.1524)
				(type default)
			)
			(layer "B.SilkS")
		)
		(fp_line
			(start 1.524 0.762)
			(end 1.524 -0.762)
			(stroke
				(width 0.1524)
				(type default)
			)
			(layer "B.SilkS")
		)
		(fp_line
			(start -1.524 0.762)
			(end 1.524 0.762)
			(stroke
				(width 0.1524)
				(type default)
			)
			(layer "B.SilkS")
		)
		(fp_line
			(start 1.1049 -0.724916)
			(end 1.1049 0.724916)
			(stroke
				(width 0.1)
				(type default)
			)
			(layer "B.Fab")
		)
		(fp_line
			(start -1.1049 -0.724916)
			(end 1.1049 -0.724916)
			(stroke
				(width 0.1)
				(type default)
			)
			(layer "B.Fab")
		)
		(fp_line
			(start 1.1049 0.724916)
			(end -1.1049 0.724916)
			(stroke
				(width 0.1)
				(type default)
			)
			(layer "B.Fab")
		)
		(fp_line
			(start -1.1049 0.724916)
			(end -1.1049 -0.724916)
			(stroke
				(width 0.1)
				(type default)
			)
			(layer "B.Fab")
		)
		(pad "1" smd rect
			(at 0.889 0 90)
			(size 1.016 1.27)
			(layers "B.Cu" "B.Mask" "B.Paste")
			(net "PVCCFA_EHV_FIVRA_CPU1")
		)
		(pad "2" smd rect
			(at -0.889 0 90)
			(size 1.016 1.27)
			(layers "B.Cu" "B.Mask" "B.Paste")
			(net "GND")
		)
	)
	(footprint ""
		(layer "B.Cu")
		(at 94.209108 -190.705232 -90)
		(property "Reference" "R663"
			(at 0 0 90)
			(layer "B.SilkS")
			(hide yes)
			(effects
				(font
					(size 1.27 1.27)
				)
				(justify mirror)
			)
		)
		(property "Value" ""
			(at 0 0 90)
			(layer "B.Fab")
			(effects
				(font
					(size 1.27 1.27)
				)
				(justify mirror)
			)
		)
		(duplicate_pad_numbers_are_jumpers no)
		(fp_line
			(start -0.7874 0.4064)
			(end 0.7874 0.4064)
			(stroke
				(width 0.1524)
				(type default)
			)
			(layer "B.SilkS")
		)
		(fp_line
			(start 0.7874 0.4064)
			(end 0.7874 -0.4064)
			(stroke
				(width 0.1524)
				(type default)
			)
			(layer "B.SilkS")
		)
		(fp_line
			(start -0.7874 -0.4064)
			(end -0.7874 0.4064)
			(stroke
				(width 0.1524)
				(type default)
			)
			(layer "B.SilkS")
		)
		(fp_line
			(start 0.7874 -0.4064)
			(end -0.7874 -0.4064)
			(stroke
				(width 0.1524)
				(type default)
			)
			(layer "B.SilkS")
		)
		(fp_line
			(start -0.67945 0.3048)
			(end -0.120396 0.3048)
			(stroke
				(width 0.1)
				(type default)
			)
			(layer "B.Fab")
		)
		(fp_line
			(start -0.120396 0.3048)
			(end -0.120396 0.2794)
			(stroke
				(width 0.1)
				(type default)
			)
			(layer "B.Fab")
		)
		(fp_line
			(start 0.12065 0.3048)
			(end 0.67945 0.3048)
			(stroke
				(width 0.1)
				(type default)
			)
			(layer "B.Fab")
		)
		(fp_line
			(start 0.67945 0.3048)
			(end 0.67945 -0.305054)
			(stroke
				(width 0.1)
				(type default)
			)
			(layer "B.Fab")
		)
		(fp_line
			(start -0.120396 0.2794)
			(end 0.12065 0.2794)
			(stroke
				(width 0.1)
				(type default)
			)
			(layer "B.Fab")
		)
		(fp_line
			(start 0.12065 0.2794)
			(end 0.12065 0.3048)
			(stroke
				(width 0.1)
				(type default)
			)
			(layer "B.Fab")
		)
		(fp_line
			(start -0.12065 -0.2794)
			(end -0.12065 -0.3048)
			(stroke
				(width 0.1)
				(type default)
			)
			(layer "B.Fab")
		)
		(fp_line
			(start 0.12065 -0.2794)
			(end -0.12065 -0.2794)
			(stroke
				(width 0.1)
				(type default)
			)
			(layer "B.Fab")
		)
		(fp_line
			(start -0.67945 -0.3048)
			(end -0.67945 0.3048)
			(stroke
				(width 0.1)
				(type default)
			)
			(layer "B.Fab")
		)
		(fp_line
			(start -0.12065 -0.3048)
			(end -0.67945 -0.3048)
			(stroke
				(width 0.1)
				(type default)
			)
			(layer "B.Fab")
		)
		(fp_line
			(start 0.12065 -0.305054)
			(end 0.12065 -0.2794)
			(stroke
				(width 0.1)
				(type default)
			)
			(layer "B.Fab")
		)
		(fp_line
			(start 0.67945 -0.305054)
			(end 0.12065 -0.305054)
			(stroke
				(width 0.1)
				(type default)
			)
			(layer "B.Fab")
		)
		(pad "1" smd circle
			(at 0.40005 0 90)
			(size 0 0)
			(layers "B.Cu" "B.Mask" "B.Paste")
			(net "PVNN_TERM_CPU1")
		)
		(pad "2" smd circle
			(at -0.40005 0 90)
			(size 0 0)
			(layers "B.Cu" "B.Mask" "B.Paste")
			(net "I3C_SPD_DDRABCD_CPU1_SDA")
		)
	)
	(footprint ""
		(layer "B.Cu")
		(at 477.30537 -90.156792 90)
		(property "Reference" "X47"
			(at -2.272792 -2.22504 270)
			(unlocked yes)
			(layer "B.SilkS")
			(effects
				(font
					(size 0.7874 0.5842)
					(thickness 0.1524)
				)
				(justify left mirror)
			)
		)
		(property "Value" ""
			(at 0 0 90)
			(layer "B.Fab")
			(effects
				(font
					(size 1.27 1.27)
				)
				(justify mirror)
			)
		)
		(property "Device Type" "TP_TDR_4P_FTS_TH-TP_TDR_4P_DIPA"
			(at -1.30175 1.27 0)
			(unlocked yes)
			(layer "B.Fab")
			(hide yes)
			(effects
				(font
					(size 0.635 0.4064)
					(thickness 0.1524)
				)
				(justify mirror)
			)
		)
		(property "User Part Number" "N_A"
			(at -1.30175 1.27 0)
			(unlocked yes)
			(layer "Cmts.User")
			(hide yes)
			(effects
				(font
					(size 0.635 0.4064)
					(thickness 0.1524)
				)
				(justify mirror)
			)
		)
		(duplicate_pad_numbers_are_jumpers no)
		(fp_line
			(start 0 -1.27)
			(end 0 -0.635)
			(stroke
				(width 0.1524)
				(type default)
			)
			(layer "B.SilkS")
		)
		(fp_line
			(start -2.54 -1.27)
			(end 0 -1.27)
			(stroke
				(width 0.1524)
				(type default)
			)
			(layer "B.SilkS")
		)
		(fp_line
			(start -2.54 -1.1303)
			(end -2.54 -1.27)
			(stroke
				(width 0.1524)
				(type default)
			)
			(layer "B.SilkS")
		)
		(fp_line
			(start 0 0.635)
			(end 0 1.905)
			(stroke
				(width 0.1524)
				(type default)
			)
			(layer "B.SilkS")
		)
		(fp_line
			(start -2.54 1.4097)
			(end -2.54 1.1303)
			(stroke
				(width 0.1524)
				(type default)
			)
			(layer "B.SilkS")
		)
		(fp_line
			(start 0 3.175)
			(end 0 3.81)
			(stroke
				(width 0.1524)
				(type default)
			)
			(layer "B.SilkS")
		)
		(fp_line
			(start 0 3.81)
			(end -2.54 3.81)
			(stroke
				(width 0.1524)
				(type default)
			)
			(layer "B.SilkS")
		)
		(fp_line
			(start -2.54 3.81)
			(end -2.54 3.6703)
			(stroke
				(width 0.1524)
				(type default)
			)
			(layer "B.SilkS")
		)
		(fp_poly
			(pts
				(xy 0.761746 0) (xy 2.285746 -0.762) (xy 2.285746 0.762)
			)
			(stroke
				(width 0)
				(type default)
			)
			(fill yes)
			(layer "B.SilkS")
		)
		(fp_line
			(start 0 -1.27)
			(end 0 3.81)
			(stroke
				(width 0.1)
				(type default)
			)
			(layer "B.Fab")
		)
		(fp_line
			(start -2.54 -1.27)
			(end 0 -1.27)
			(stroke
				(width 0.1)
				(type default)
			)
			(layer "B.Fab")
		)
		(fp_line
			(start 0 3.81)
			(end -2.54 3.81)
			(stroke
				(width 0.1)
				(type default)
			)
			(layer "B.Fab")
		)
		(fp_line
			(start -2.54 3.81)
			(end -2.54 -1.27)
			(stroke
				(width 0.1)
				(type default)
			)
			(layer "B.Fab")
		)
		(fp_poly
			(pts
				(xy 0.761746 0) (xy 2.285746 -0.762) (xy 2.285746 0.762)
			)
			(stroke
				(width 0)
				(type default)
			)
			(fill yes)
			(layer "B.Fab")
		)
		(pad "1" thru_hole circle
			(at 0 0 270)
			(size 1.0033 1.0033)
			(drill 0.249936)
			(layers "*.Cu" "*.Mask")
			(remove_unused_layers no)
			(net "TDR_DIFF_85_NECK_IN6_DN")
			(clearance 0.10795)
			(padstack
				(mode front_inner_back)
				(layer "Inner"
					(shape circle)
					(size 0.8001 0.8001)
					(clearance 0.1524)
				)
				(layer "B.Cu"
					(shape circle)
					(size 1.0033 1.0033)
					(thermal_gap 0.10795)
					(clearance 0.10795)
				)
			)
		)
		(pad "2" thru_hole circle
			(at -2.54 0 270)
			(size 1.9939 1.9939)
			(drill 0.249936)
			(layers "*.Cu" "*.Mask")
			(remove_unused_layers no)
			(net "T1_GND")
			(clearance 0.10795)
			(padstack
				(mode front_inner_back)
				(layer "Inner"
					(shape circle)
					(size 0.8001 0.8001)
					(clearance 0.1524)
				)
				(layer "B.Cu"
					(shape circle)
					(size 1.9939 1.9939)
					(thermal_gap 0.10795)
					(clearance 0.10795)
				)
			)
		)
		(pad "3" thru_hole circle
			(at -2.54 2.54 270)
			(size 1.9939 1.9939)
			(drill 0.249936)
			(layers "*.Cu" "*.Mask")
			(remove_unused_layers no)
			(net "T1_GND")
			(clearance 0.10795)
			(padstack
				(mode front_inner_back)
				(layer "Inner"
					(shape circle)
					(size 0.8001 0.8001)
					(clearance 0.1524)
				)
				(layer "B.Cu"
					(shape circle)
					(size 1.9939 1.9939)
					(thermal_gap 0.10795)
					(clearance 0.10795)
				)
			)
		)
		(pad "4" thru_hole circle
			(at 0 2.54 270)
			(size 1.0033 1.0033)
			(drill 0.249936)
			(layers "*.Cu" "*.Mask")
			(remove_unused_layers no)
			(net "TDR_DIFF_85_NECK_IN6_DP")
			(clearance 0.10795)
			(padstack
				(mode front_inner_back)
				(layer "Inner"
					(shape circle)
					(size 0.8001 0.8001)
					(clearance 0.1524)
				)
				(layer "B.Cu"
					(shape circle)
					(size 1.0033 1.0033)
					(thermal_gap 0.10795)
					(clearance 0.10795)
				)
			)
		)
	)
	(footprint ""
		(layer "B.Cu")
		(at 250.000516 -105.256584 90)
		(property "Reference" "R1483"
			(at 0 0 90)
			(layer "B.SilkS")
			(hide yes)
			(effects
				(font
					(size 1.27 1.27)
				)
				(justify mirror)
			)
		)
		(property "Value" ""
			(at 0 0 90)
			(layer "B.Fab")
			(effects
				(font
					(size 1.27 1.27)
				)
				(justify mirror)
			)
		)
		(duplicate_pad_numbers_are_jumpers no)
		(fp_line
			(start 0.7874 -0.4064)
			(end -0.7874 -0.4064)
			(stroke
				(width 0.1524)
				(type default)
			)
			(layer "B.SilkS")
		)
		(fp_line
			(start -0.7874 -0.4064)
			(end -0.7874 0.4064)
			(stroke
				(width 0.1524)
				(type default)
			)
			(layer "B.SilkS")
		)
		(fp_line
			(start 0.7874 0.4064)
			(end 0.7874 -0.4064)
			(stroke
				(width 0.1524)
				(type default)
			)
			(layer "B.SilkS")
		)
		(fp_line
			(start -0.7874 0.4064)
			(end 0.7874 0.4064)
			(stroke
				(width 0.1524)
				(type default)
			)
			(layer "B.SilkS")
		)
		(fp_line
			(start 0.67945 -0.305054)
			(end 0.12065 -0.305054)
			(stroke
				(width 0.1)
				(type default)
			)
			(layer "B.Fab")
		)
		(fp_line
			(start 0.12065 -0.305054)
			(end 0.12065 -0.2794)
			(stroke
				(width 0.1)
				(type default)
			)
			(layer "B.Fab")
		)
		(fp_line
			(start -0.12065 -0.3048)
			(end -0.67945 -0.3048)
			(stroke
				(width 0.1)
				(type default)
			)
			(layer "B.Fab")
		)
		(fp_line
			(start -0.67945 -0.3048)
			(end -0.67945 0.3048)
			(stroke
				(width 0.1)
				(type default)
			)
			(layer "B.Fab")
		)
		(fp_line
			(start 0.12065 -0.2794)
			(end -0.12065 -0.2794)
			(stroke
				(width 0.1)
				(type default)
			)
			(layer "B.Fab")
		)
		(fp_line
			(start -0.12065 -0.2794)
			(end -0.12065 -0.3048)
			(stroke
				(width 0.1)
				(type default)
			)
			(layer "B.Fab")
		)
		(fp_line
			(start 0.12065 0.2794)
			(end 0.12065 0.3048)
			(stroke
				(width 0.1)
				(type default)
			)
			(layer "B.Fab")
		)
		(fp_line
			(start -0.120396 0.2794)
			(end 0.12065 0.2794)
			(stroke
				(width 0.1)
				(type default)
			)
			(layer "B.Fab")
		)
		(fp_line
			(start 0.67945 0.3048)
			(end 0.67945 -0.305054)
			(stroke
				(width 0.1)
				(type default)
			)
			(layer "B.Fab")
		)
		(fp_line
			(start 0.12065 0.3048)
			(end 0.67945 0.3048)
			(stroke
				(width 0.1)
				(type default)
			)
			(layer "B.Fab")
		)
		(fp_line
			(start -0.120396 0.3048)
			(end -0.120396 0.2794)
			(stroke
				(width 0.1)
				(type default)
			)
			(layer "B.Fab")
		)
		(fp_line
			(start -0.67945 0.3048)
			(end -0.120396 0.3048)
			(stroke
				(width 0.1)
				(type default)
			)
			(layer "B.Fab")
		)
		(pad "1" smd circle
			(at 0.40005 0 270)
			(size 0 0)
			(layers "B.Cu" "B.Mask" "B.Paste")
			(net "P3V3_AUX")
		)
		(pad "2" smd circle
			(at -0.40005 0 270)
			(size 0 0)
			(layers "B.Cu" "B.Mask" "B.Paste")
			(net "FM_CK440Q_DEV_25M_EN")
		)
	)
	(footprint ""
		(layer "B.Cu")
		(at 187.34913 -13.60043 -90)
		(property "Reference" "R596"
			(at 0 0 90)
			(layer "B.SilkS")
			(hide yes)
			(effects
				(font
					(size 1.27 1.27)
				)
				(justify mirror)
			)
		)
		(property "Value" ""
			(at 0 0 90)
			(layer "B.Fab")
			(effects
				(font
					(size 1.27 1.27)
				)
				(justify mirror)
			)
		)
		(duplicate_pad_numbers_are_jumpers no)
		(fp_line
			(start -0.7874 0.4064)
			(end 0.7874 0.4064)
			(stroke
				(width 0.1524)
				(type default)
			)
			(layer "B.SilkS")
		)
		(fp_line
			(start 0.7874 0.4064)
			(end 0.7874 -0.4064)
			(stroke
				(width 0.1524)
				(type default)
			)
			(layer "B.SilkS")
		)
		(fp_line
			(start -0.7874 -0.4064)
			(end -0.7874 0.4064)
			(stroke
				(width 0.1524)
				(type default)
			)
			(layer "B.SilkS")
		)
		(fp_line
			(start 0.7874 -0.4064)
			(end -0.7874 -0.4064)
			(stroke
				(width 0.1524)
				(type default)
			)
			(layer "B.SilkS")
		)
		(fp_line
			(start -0.67945 0.3048)
			(end -0.120396 0.3048)
			(stroke
				(width 0.1)
				(type default)
			)
			(layer "B.Fab")
		)
		(fp_line
			(start -0.120396 0.3048)
			(end -0.120396 0.2794)
			(stroke
				(width 0.1)
				(type default)
			)
			(layer "B.Fab")
		)
		(fp_line
			(start 0.12065 0.3048)
			(end 0.67945 0.3048)
			(stroke
				(width 0.1)
				(type default)
			)
			(layer "B.Fab")
		)
		(fp_line
			(start 0.67945 0.3048)
			(end 0.67945 -0.305054)
			(stroke
				(width 0.1)
				(type default)
			)
			(layer "B.Fab")
		)
		(fp_line
			(start -0.120396 0.2794)
			(end 0.12065 0.2794)
			(stroke
				(width 0.1)
				(type default)
			)
			(layer "B.Fab")
		)
		(fp_line
			(start 0.12065 0.2794)
			(end 0.12065 0.3048)
			(stroke
				(width 0.1)
				(type default)
			)
			(layer "B.Fab")
		)
		(fp_line
			(start -0.12065 -0.2794)
			(end -0.12065 -0.3048)
			(stroke
				(width 0.1)
				(type default)
			)
			(layer "B.Fab")
		)
		(fp_line
			(start 0.12065 -0.2794)
			(end -0.12065 -0.2794)
			(stroke
				(width 0.1)
				(type default)
			)
			(layer "B.Fab")
		)
		(fp_line
			(start -0.67945 -0.3048)
			(end -0.67945 0.3048)
			(stroke
				(width 0.1)
				(type default)
			)
			(layer "B.Fab")
		)
		(fp_line
			(start -0.12065 -0.3048)
			(end -0.67945 -0.3048)
			(stroke
				(width 0.1)
				(type default)
			)
			(layer "B.Fab")
		)
		(fp_line
			(start 0.12065 -0.305054)
			(end 0.12065 -0.2794)
			(stroke
				(width 0.1)
				(type default)
			)
			(layer "B.Fab")
		)
		(fp_line
			(start 0.67945 -0.305054)
			(end 0.12065 -0.305054)
			(stroke
				(width 0.1)
				(type default)
			)
			(layer "B.Fab")
		)
		(pad "1" smd circle
			(at 0.40005 0 90)
			(size 0 0)
			(layers "B.Cu" "B.Mask" "B.Paste")
			(net "I3C_SPD_DDREFGH_CPU0_BMC_R_SDA")
		)
		(pad "2" smd circle
			(at -0.40005 0 90)
			(size 0 0)
			(layers "B.Cu" "B.Mask" "B.Paste")
			(net "I3C_SPD_DDREFGH_CPU0_BMC_SDA")
		)
	)
	(footprint ""
		(layer "B.Cu")
		(at 333.935578 -185.76925 180)
		(property "Reference" "R20"
			(at 0 0 0)
			(layer "B.SilkS")
			(hide yes)
			(effects
				(font
					(size 1.27 1.27)
				)
				(justify mirror)
			)
		)
		(property "Value" ""
			(at 0 0 0)
			(layer "B.Fab")
			(effects
				(font
					(size 1.27 1.27)
				)
				(justify mirror)
			)
		)
		(duplicate_pad_numbers_are_jumpers no)
		(fp_line
			(start 0.7874 0.4064)
			(end 0.7874 -0.4064)
			(stroke
				(width 0.1524)
				(type default)
			)
			(layer "B.SilkS")
		)
		(fp_line
			(start 0.7874 -0.4064)
			(end -0.7874 -0.4064)
			(stroke
				(width 0.1524)
				(type default)
			)
			(layer "B.SilkS")
		)
		(fp_line
			(start -0.7874 0.4064)
			(end 0.7874 0.4064)
			(stroke
				(width 0.1524)
				(type default)
			)
			(layer "B.SilkS")
		)
		(fp_line
			(start -0.7874 -0.4064)
			(end -0.7874 0.4064)
			(stroke
				(width 0.1524)
				(type default)
			)
			(layer "B.SilkS")
		)
		(fp_line
			(start 0.67945 0.3048)
			(end 0.67945 -0.305054)
			(stroke
				(width 0.1)
				(type default)
			)
			(layer "B.Fab")
		)
		(fp_line
			(start 0.67945 -0.305054)
			(end 0.12065 -0.305054)
			(stroke
				(width 0.1)
				(type default)
			)
			(layer "B.Fab")
		)
		(fp_line
			(start 0.12065 0.3048)
			(end 0.67945 0.3048)
			(stroke
				(width 0.1)
				(type default)
			)
			(layer "B.Fab")
		)
		(fp_line
			(start 0.12065 0.2794)
			(end 0.12065 0.3048)
			(stroke
				(width 0.1)
				(type default)
			)
			(layer "B.Fab")
		)
		(fp_line
			(start 0.12065 -0.2794)
			(end -0.12065 -0.2794)
			(stroke
				(width 0.1)
				(type default)
			)
			(layer "B.Fab")
		)
		(fp_line
			(start 0.12065 -0.305054)
			(end 0.12065 -0.2794)
			(stroke
				(width 0.1)
				(type default)
			)
			(layer "B.Fab")
		)
		(fp_line
			(start -0.120396 0.3048)
			(end -0.120396 0.2794)
			(stroke
				(width 0.1)
				(type default)
			)
			(layer "B.Fab")
		)
		(fp_line
			(start -0.120396 0.2794)
			(end 0.12065 0.2794)
			(stroke
				(width 0.1)
				(type default)
			)
			(layer "B.Fab")
		)
		(fp_line
			(start -0.12065 -0.2794)
			(end -0.12065 -0.3048)
			(stroke
				(width 0.1)
				(type default)
			)
			(layer "B.Fab")
		)
		(fp_line
			(start -0.12065 -0.3048)
			(end -0.67945 -0.3048)
			(stroke
				(width 0.1)
				(type default)
			)
			(layer "B.Fab")
		)
		(fp_line
			(start -0.67945 0.3048)
			(end -0.120396 0.3048)
			(stroke
				(width 0.1)
				(type default)
			)
			(layer "B.Fab")
		)
		(fp_line
			(start -0.67945 -0.3048)
			(end -0.67945 0.3048)
			(stroke
				(width 0.1)
				(type default)
			)
			(layer "B.Fab")
		)
		(pad "1" smd circle
			(at 0.40005 0)
			(size 0 0)
			(layers "B.Cu" "B.Mask" "B.Paste")
			(net "DBP_CPU_MBP0_GTL_N")
		)
		(pad "2" smd circle
			(at -0.40005 0)
			(size 0 0)
			(layers "B.Cu" "B.Mask" "B.Paste")
			(net "FM_PCH_TRIGGER0_N")
		)
	)
	(footprint ""
		(layer "B.Cu")
		(at 65.067688 -250.792996 90)
		(property "Reference" "C453"
			(at 0 0 90)
			(layer "B.SilkS")
			(hide yes)
			(effects
				(font
					(size 1.27 1.27)
				)
				(justify mirror)
			)
		)
		(property "Value" ""
			(at 0 0 90)
			(layer "B.Fab")
			(effects
				(font
					(size 1.27 1.27)
				)
				(justify mirror)
			)
		)
		(duplicate_pad_numbers_are_jumpers no)
		(fp_line
			(start 1.524 -0.762)
			(end -1.524 -0.762)
			(stroke
				(width 0.1524)
				(type default)
			)
			(layer "B.SilkS")
		)
		(fp_line
			(start -1.524 -0.762)
			(end -1.524 0.762)
			(stroke
				(width 0.1524)
				(type default)
			)
			(layer "B.SilkS")
		)
		(fp_line
			(start 1.524 0.762)
			(end 1.524 -0.762)
			(stroke
				(width 0.1524)
				(type default)
			)
			(layer "B.SilkS")
		)
		(fp_line
			(start -1.524 0.762)
			(end 1.524 0.762)
			(stroke
				(width 0.1524)
				(type default)
			)
			(layer "B.SilkS")
		)
		(fp_line
			(start 1.1049 -0.724916)
			(end 1.1049 0.724916)
			(stroke
				(width 0.1)
				(type default)
			)
			(layer "B.Fab")
		)
		(fp_line
			(start -1.1049 -0.724916)
			(end 1.1049 -0.724916)
			(stroke
				(width 0.1)
				(type default)
			)
			(layer "B.Fab")
		)
		(fp_line
			(start 1.1049 0.724916)
			(end -1.1049 0.724916)
			(stroke
				(width 0.1)
				(type default)
			)
			(layer "B.Fab")
		)
		(fp_line
			(start -1.1049 0.724916)
			(end -1.1049 -0.724916)
			(stroke
				(width 0.1)
				(type default)
			)
			(layer "B.Fab")
		)
		(pad "1" smd rect
			(at 0.889 0 90)
			(size 1.016 1.27)
			(layers "B.Cu" "B.Mask" "B.Paste")
			(net "PVCCFA_EHV_FIVRA_CPU1")
		)
		(pad "2" smd rect
			(at -0.889 0 90)
			(size 1.016 1.27)
			(layers "B.Cu" "B.Mask" "B.Paste")
			(net "GND")
		)
	)
	(footprint ""
		(layer "B.Cu")
		(at 383.650998 -80.09255 90)
		(property "Reference" "R2358"
			(at 0 0 90)
			(layer "B.SilkS")
			(hide yes)
			(effects
				(font
					(size 1.27 1.27)
				)
				(justify mirror)
			)
		)
		(property "Value" ""
			(at 0 0 90)
			(layer "B.Fab")
			(effects
				(font
					(size 1.27 1.27)
				)
				(justify mirror)
			)
		)
		(duplicate_pad_numbers_are_jumpers no)
		(fp_line
			(start 0.7874 -0.4064)
			(end -0.7874 -0.4064)
			(stroke
				(width 0.1524)
				(type default)
			)
			(layer "B.SilkS")
		)
		(fp_line
			(start -0.7874 -0.4064)
			(end -0.7874 0.4064)
			(stroke
				(width 0.1524)
				(type default)
			)
			(layer "B.SilkS")
		)
		(fp_line
			(start 0.7874 0.4064)
			(end 0.7874 -0.4064)
			(stroke
				(width 0.1524)
				(type default)
			)
			(layer "B.SilkS")
		)
		(fp_line
			(start -0.7874 0.4064)
			(end 0.7874 0.4064)
			(stroke
				(width 0.1524)
				(type default)
			)
			(layer "B.SilkS")
		)
		(fp_line
			(start 0.67945 -0.305054)
			(end 0.12065 -0.305054)
			(stroke
				(width 0.1)
				(type default)
			)
			(layer "B.Fab")
		)
		(fp_line
			(start 0.12065 -0.305054)
			(end 0.12065 -0.2794)
			(stroke
				(width 0.1)
				(type default)
			)
			(layer "B.Fab")
		)
		(fp_line
			(start -0.12065 -0.3048)
			(end -0.67945 -0.3048)
			(stroke
				(width 0.1)
				(type default)
			)
			(layer "B.Fab")
		)
		(fp_line
			(start -0.67945 -0.3048)
			(end -0.67945 0.3048)
			(stroke
				(width 0.1)
				(type default)
			)
			(layer "B.Fab")
		)
		(fp_line
			(start 0.12065 -0.2794)
			(end -0.12065 -0.2794)
			(stroke
				(width 0.1)
				(type default)
			)
			(layer "B.Fab")
		)
		(fp_line
			(start -0.12065 -0.2794)
			(end -0.12065 -0.3048)
			(stroke
				(width 0.1)
				(type default)
			)
			(layer "B.Fab")
		)
		(fp_line
			(start 0.12065 0.2794)
			(end 0.12065 0.3048)
			(stroke
				(width 0.1)
				(type default)
			)
			(layer "B.Fab")
		)
		(fp_line
			(start -0.120396 0.2794)
			(end 0.12065 0.2794)
			(stroke
				(width 0.1)
				(type default)
			)
			(layer "B.Fab")
		)
		(fp_line
			(start 0.67945 0.3048)
			(end 0.67945 -0.305054)
			(stroke
				(width 0.1)
				(type default)
			)
			(layer "B.Fab")
		)
		(fp_line
			(start 0.12065 0.3048)
			(end 0.67945 0.3048)
			(stroke
				(width 0.1)
				(type default)
			)
			(layer "B.Fab")
		)
		(fp_line
			(start -0.120396 0.3048)
			(end -0.120396 0.2794)
			(stroke
				(width 0.1)
				(type default)
			)
			(layer "B.Fab")
		)
		(fp_line
			(start -0.67945 0.3048)
			(end -0.120396 0.3048)
			(stroke
				(width 0.1)
				(type default)
			)
			(layer "B.Fab")
		)
		(pad "1" smd circle
			(at 0.40005 0 270)
			(size 0 0)
			(layers "B.Cu" "B.Mask" "B.Paste")
			(net "FM_PCH_P1V8_AUX_EN")
		)
		(pad "2" smd circle
			(at -0.40005 0 270)
			(size 0 0)
			(layers "B.Cu" "B.Mask" "B.Paste")
			(net "FM_PCH_P1V8_AUX_EN_R")
		)
	)
	(footprint ""
		(layer "B.Cu")
		(at 458.42428 -319.132204)
		(property "Reference" "C44"
			(at 0 0 0)
			(layer "B.SilkS")
			(hide yes)
			(effects
				(font
					(size 1.27 1.27)
				)
				(justify mirror)
			)
		)
		(property "Value" ""
			(at 0 0 0)
			(layer "B.Fab")
			(effects
				(font
					(size 1.27 1.27)
				)
				(justify mirror)
			)
		)
		(duplicate_pad_numbers_are_jumpers no)
		(fp_line
			(start -0.7874 -0.4064)
			(end -0.7874 0.4064)
			(stroke
				(width 0.1524)
				(type default)
			)
			(layer "B.SilkS")
		)
		(fp_line
			(start -0.7874 0.4064)
			(end 0.7874 0.4064)
			(stroke
				(width 0.1524)
				(type default)
			)
			(layer "B.SilkS")
		)
		(fp_line
			(start 0.7874 -0.4064)
			(end -0.7874 -0.4064)
			(stroke
				(width 0.1524)
				(type default)
			)
			(layer "B.SilkS")
		)
		(fp_line
			(start 0.7874 0.4064)
			(end 0.7874 -0.4064)
			(stroke
				(width 0.1524)
				(type default)
			)
			(layer "B.SilkS")
		)
		(fp_line
			(start -0.67945 -0.3048)
			(end -0.67945 0.3048)
			(stroke
				(width 0.1)
				(type default)
			)
			(layer "B.Fab")
		)
		(fp_line
			(start -0.67945 0.3048)
			(end -0.120396 0.3048)
			(stroke
				(width 0.1)
				(type default)
			)
			(layer "B.Fab")
		)
		(fp_line
			(start -0.12065 -0.3048)
			(end -0.67945 -0.3048)
			(stroke
				(width 0.1)
				(type default)
			)
			(layer "B.Fab")
		)
		(fp_line
			(start -0.12065 -0.2794)
			(end -0.12065 -0.3048)
			(stroke
				(width 0.1)
				(type default)
			)
			(layer "B.Fab")
		)
		(fp_line
			(start -0.120396 0.2794)
			(end 0.12065 0.2794)
			(stroke
				(width 0.1)
				(type default)
			)
			(layer "B.Fab")
		)
		(fp_line
			(start -0.120396 0.3048)
			(end -0.120396 0.2794)
			(stroke
				(width 0.1)
				(type default)
			)
			(layer "B.Fab")
		)
		(fp_line
			(start 0.12065 -0.305054)
			(end 0.12065 -0.2794)
			(stroke
				(width 0.1)
				(type default)
			)
			(layer "B.Fab")
		)
		(fp_line
			(start 0.12065 -0.2794)
			(end -0.12065 -0.2794)
			(stroke
				(width 0.1)
				(type default)
			)
			(layer "B.Fab")
		)
		(fp_line
			(start 0.12065 0.2794)
			(end 0.12065 0.3048)
			(stroke
				(width 0.1)
				(type default)
			)
			(layer "B.Fab")
		)
		(fp_line
			(start 0.12065 0.3048)
			(end 0.67945 0.3048)
			(stroke
				(width 0.1)
				(type default)
			)
			(layer "B.Fab")
		)
		(fp_line
			(start 0.67945 -0.305054)
			(end 0.12065 -0.305054)
			(stroke
				(width 0.1)
				(type default)
			)
			(layer "B.Fab")
		)
		(fp_line
			(start 0.67945 0.3048)
			(end 0.67945 -0.305054)
			(stroke
				(width 0.1)
				(type default)
			)
			(layer "B.Fab")
		)
		(pad "1" smd circle
			(at 0.40005 0 180)
			(size 0 0)
			(layers "B.Cu" "B.Mask" "B.Paste")
			(net "P3V3_AUX")
		)
		(pad "2" smd circle
			(at -0.40005 0 180)
			(size 0 0)
			(layers "B.Cu" "B.Mask" "B.Paste")
			(net "GND")
		)
	)
	(footprint ""
		(layer "B.Cu")
		(at 422.5163 -154.262328)
		(property "Reference" "PR4227"
			(at 0 0 0)
			(layer "B.SilkS")
			(hide yes)
			(effects
				(font
					(size 1.27 1.27)
				)
				(justify mirror)
			)
		)
		(property "Value" ""
			(at 0 0 0)
			(layer "B.Fab")
			(effects
				(font
					(size 1.27 1.27)
				)
				(justify mirror)
			)
		)
		(duplicate_pad_numbers_are_jumpers no)
		(fp_line
			(start -0.7874 -0.4064)
			(end -0.7874 0.4064)
			(stroke
				(width 0.1524)
				(type default)
			)
			(layer "B.SilkS")
		)
		(fp_line
			(start -0.7874 0.4064)
			(end 0.7874 0.4064)
			(stroke
				(width 0.1524)
				(type default)
			)
			(layer "B.SilkS")
		)
		(fp_line
			(start 0.7874 -0.4064)
			(end -0.7874 -0.4064)
			(stroke
				(width 0.1524)
				(type default)
			)
			(layer "B.SilkS")
		)
		(fp_line
			(start 0.7874 0.4064)
			(end 0.7874 -0.4064)
			(stroke
				(width 0.1524)
				(type default)
			)
			(layer "B.SilkS")
		)
		(fp_line
			(start -0.67945 -0.3048)
			(end -0.67945 0.3048)
			(stroke
				(width 0.1)
				(type default)
			)
			(layer "B.Fab")
		)
		(fp_line
			(start -0.67945 0.3048)
			(end -0.120396 0.3048)
			(stroke
				(width 0.1)
				(type default)
			)
			(layer "B.Fab")
		)
		(fp_line
			(start -0.12065 -0.3048)
			(end -0.67945 -0.3048)
			(stroke
				(width 0.1)
				(type default)
			)
			(layer "B.Fab")
		)
		(fp_line
			(start -0.12065 -0.2794)
			(end -0.12065 -0.3048)
			(stroke
				(width 0.1)
				(type default)
			)
			(layer "B.Fab")
		)
		(fp_line
			(start -0.120396 0.2794)
			(end 0.12065 0.2794)
			(stroke
				(width 0.1)
				(type default)
			)
			(layer "B.Fab")
		)
		(fp_line
			(start -0.120396 0.3048)
			(end -0.120396 0.2794)
			(stroke
				(width 0.1)
				(type default)
			)
			(layer "B.Fab")
		)
		(fp_line
			(start 0.12065 -0.305054)
			(end 0.12065 -0.2794)
			(stroke
				(width 0.1)
				(type default)
			)
			(layer "B.Fab")
		)
		(fp_line
			(start 0.12065 -0.2794)
			(end -0.12065 -0.2794)
			(stroke
				(width 0.1)
				(type default)
			)
			(layer "B.Fab")
		)
		(fp_line
			(start 0.12065 0.2794)
			(end 0.12065 0.3048)
			(stroke
				(width 0.1)
				(type default)
			)
			(layer "B.Fab")
		)
		(fp_line
			(start 0.12065 0.3048)
			(end 0.67945 0.3048)
			(stroke
				(width 0.1)
				(type default)
			)
			(layer "B.Fab")
		)
		(fp_line
			(start 0.67945 -0.305054)
			(end 0.12065 -0.305054)
			(stroke
				(width 0.1)
				(type default)
			)
			(layer "B.Fab")
		)
		(fp_line
			(start 0.67945 0.3048)
			(end 0.67945 -0.305054)
			(stroke
				(width 0.1)
				(type default)
			)
			(layer "B.Fab")
		)
		(pad "1" smd circle
			(at 0.40005 0 180)
			(size 0 0)
			(layers "B.Cu" "B.Mask" "B.Paste")
			(net "PVCCFA_EHV_CPU0_VDD1")
		)
		(pad "2" smd circle
			(at -0.40005 0 180)
			(size 0 0)
			(layers "B.Cu" "B.Mask" "B.Paste")
			(net "PVCCFA_EHV_CPU0_NC2")
		)
	)
	(footprint ""
		(layer "B.Cu")
		(at 170.824398 -193.02603 90)
		(property "Reference" "R153"
			(at 0 0 90)
			(layer "B.SilkS")
			(hide yes)
			(effects
				(font
					(size 1.27 1.27)
				)
				(justify mirror)
			)
		)
		(property "Value" ""
			(at 0 0 90)
			(layer "B.Fab")
			(effects
				(font
					(size 1.27 1.27)
				)
				(justify mirror)
			)
		)
		(duplicate_pad_numbers_are_jumpers no)
		(fp_line
			(start 0.7874 -0.4064)
			(end -0.7874 -0.4064)
			(stroke
				(width 0.1524)
				(type default)
			)
			(layer "B.SilkS")
		)
		(fp_line
			(start -0.7874 -0.4064)
			(end -0.7874 0.4064)
			(stroke
				(width 0.1524)
				(type default)
			)
			(layer "B.SilkS")
		)
		(fp_line
			(start 0.7874 0.4064)
			(end 0.7874 -0.4064)
			(stroke
				(width 0.1524)
				(type default)
			)
			(layer "B.SilkS")
		)
		(fp_line
			(start -0.7874 0.4064)
			(end 0.7874 0.4064)
			(stroke
				(width 0.1524)
				(type default)
			)
			(layer "B.SilkS")
		)
		(fp_line
			(start 0.67945 -0.305054)
			(end 0.12065 -0.305054)
			(stroke
				(width 0.1)
				(type default)
			)
			(layer "B.Fab")
		)
		(fp_line
			(start 0.12065 -0.305054)
			(end 0.12065 -0.2794)
			(stroke
				(width 0.1)
				(type default)
			)
			(layer "B.Fab")
		)
		(fp_line
			(start -0.12065 -0.3048)
			(end -0.67945 -0.3048)
			(stroke
				(width 0.1)
				(type default)
			)
			(layer "B.Fab")
		)
		(fp_line
			(start -0.67945 -0.3048)
			(end -0.67945 0.3048)
			(stroke
				(width 0.1)
				(type default)
			)
			(layer "B.Fab")
		)
		(fp_line
			(start 0.12065 -0.2794)
			(end -0.12065 -0.2794)
			(stroke
				(width 0.1)
				(type default)
			)
			(layer "B.Fab")
		)
		(fp_line
			(start -0.12065 -0.2794)
			(end -0.12065 -0.3048)
			(stroke
				(width 0.1)
				(type default)
			)
			(layer "B.Fab")
		)
		(fp_line
			(start 0.12065 0.2794)
			(end 0.12065 0.3048)
			(stroke
				(width 0.1)
				(type default)
			)
			(layer "B.Fab")
		)
		(fp_line
			(start -0.120396 0.2794)
			(end 0.12065 0.2794)
			(stroke
				(width 0.1)
				(type default)
			)
			(layer "B.Fab")
		)
		(fp_line
			(start 0.67945 0.3048)
			(end 0.67945 -0.305054)
			(stroke
				(width 0.1)
				(type default)
			)
			(layer "B.Fab")
		)
		(fp_line
			(start 0.12065 0.3048)
			(end 0.67945 0.3048)
			(stroke
				(width 0.1)
				(type default)
			)
			(layer "B.Fab")
		)
		(fp_line
			(start -0.120396 0.3048)
			(end -0.120396 0.2794)
			(stroke
				(width 0.1)
				(type default)
			)
			(layer "B.Fab")
		)
		(fp_line
			(start -0.67945 0.3048)
			(end -0.120396 0.3048)
			(stroke
				(width 0.1)
				(type default)
			)
			(layer "B.Fab")
		)
		(pad "1" smd circle
			(at 0.40005 0 270)
			(size 0 0)
			(layers "B.Cu" "B.Mask" "B.Paste")
			(net "PWRGD_DRAMPWRGD_CPU1_GH_LVC1_R2")
		)
		(pad "2" smd circle
			(at -0.40005 0 270)
			(size 0 0)
			(layers "B.Cu" "B.Mask" "B.Paste")
			(net "PVCCD_HV_CPU1")
		)
	)
	(footprint ""
		(layer "B.Cu")
		(at 325.688706 -73.499472 180)
		(property "Reference" "PJ62"
			(at -4.991354 -1.577594 0)
			(unlocked yes)
			(layer "B.SilkS")
			(effects
				(font
					(size 0.7874 0.5842)
					(thickness 0.1524)
				)
				(justify left mirror)
			)
		)
		(property "Value" ""
			(at 0 0 0)
			(layer "B.Fab")
			(effects
				(font
					(size 1.27 1.27)
				)
				(justify mirror)
			)
		)
		(duplicate_pad_numbers_are_jumpers no)
		(pad "1" smd circle
			(at 0.7493 0 270)
			(size 0 0)
			(layers "B.Cu" "B.Mask" "B.Paste")
			(net "SH_P1V05_PCH_AUX_P")
		)
		(pad "2" smd rect
			(at -0.7493 0 90)
			(size 0.7112 0.8128)
			(layers "B.Cu" "B.Mask" "B.Paste")
			(net "P1V05_PCH_AUX")
		)
		(zone
			(layer "B.Cu")
			(hatch none 0.5)
			(connect_pads
				(clearance 0)
			)
			(min_thickness 0.25)
			(keepout
				(tracks allowed)
				(vias not_allowed)
				(pads allowed)
				(copperpour not_allowed)
				(footprints allowed)
			)
			(placement
				(enabled no)
				(sheetname "")
			)
			(fill
				(thermal_gap 0.5)
				(thermal_bridge_width 0.5)
				(island_removal_mode 0)
			)
			(polygon
				(pts
					(xy 324.507606 -73.910952) (xy 324.507606 -73.093326) (xy 326.895206 -73.093326) (xy 326.895206 -73.910952)
				)
			)
		)
	)
	(footprint ""
		(layer "B.Cu")
		(at 410.830014 -321.549776 -90)
		(property "Reference" "C30"
			(at 0 0 90)
			(layer "B.SilkS")
			(hide yes)
			(effects
				(font
					(size 1.27 1.27)
				)
				(justify mirror)
			)
		)
		(property "Value" ""
			(at 0 0 90)
			(layer "B.Fab")
			(effects
				(font
					(size 1.27 1.27)
				)
				(justify mirror)
			)
		)
		(duplicate_pad_numbers_are_jumpers no)
		(fp_line
			(start -1.524 0.762)
			(end 1.524 0.762)
			(stroke
				(width 0.1524)
				(type default)
			)
			(layer "B.SilkS")
		)
		(fp_line
			(start 1.524 0.762)
			(end 1.524 -0.762)
			(stroke
				(width 0.1524)
				(type default)
			)
			(layer "B.SilkS")
		)
		(fp_line
			(start -1.524 -0.762)
			(end -1.524 0.762)
			(stroke
				(width 0.1524)
				(type default)
			)
			(layer "B.SilkS")
		)
		(fp_line
			(start 1.524 -0.762)
			(end -1.524 -0.762)
			(stroke
				(width 0.1524)
				(type default)
			)
			(layer "B.SilkS")
		)
		(fp_line
			(start -1.1049 0.724916)
			(end -1.1049 -0.724916)
			(stroke
				(width 0.1)
				(type default)
			)
			(layer "B.Fab")
		)
		(fp_line
			(start 1.1049 0.724916)
			(end -1.1049 0.724916)
			(stroke
				(width 0.1)
				(type default)
			)
			(layer "B.Fab")
		)
		(fp_line
			(start -1.1049 -0.724916)
			(end 1.1049 -0.724916)
			(stroke
				(width 0.1)
				(type default)
			)
			(layer "B.Fab")
		)
		(fp_line
			(start 1.1049 -0.724916)
			(end 1.1049 0.724916)
			(stroke
				(width 0.1)
				(type default)
			)
			(layer "B.Fab")
		)
		(pad "1" smd rect
			(at 0.889 0 270)
			(size 1.016 1.27)
			(layers "B.Cu" "B.Mask" "B.Paste")
			(net "P12V_S3_AUX_CPU0_NVDIMM")
		)
		(pad "2" smd rect
			(at -0.889 0 270)
			(size 1.016 1.27)
			(layers "B.Cu" "B.Mask" "B.Paste")
			(net "GND")
		)
	)
	(footprint ""
		(layer "B.Cu")
		(at 430.600104 -133.478778)
		(property "Reference" "R2595"
			(at 0 0 0)
			(layer "B.SilkS")
			(hide yes)
			(effects
				(font
					(size 1.27 1.27)
				)
				(justify mirror)
			)
		)
		(property "Value" ""
			(at 0 0 0)
			(layer "B.Fab")
			(effects
				(font
					(size 1.27 1.27)
				)
				(justify mirror)
			)
		)
		(duplicate_pad_numbers_are_jumpers no)
		(fp_line
			(start -0.7874 -0.4064)
			(end -0.7874 0.4064)
			(stroke
				(width 0.1524)
				(type default)
			)
			(layer "B.SilkS")
		)
		(fp_line
			(start -0.7874 0.4064)
			(end 0.7874 0.4064)
			(stroke
				(width 0.1524)
				(type default)
			)
			(layer "B.SilkS")
		)
		(fp_line
			(start 0.7874 -0.4064)
			(end -0.7874 -0.4064)
			(stroke
				(width 0.1524)
				(type default)
			)
			(layer "B.SilkS")
		)
		(fp_line
			(start 0.7874 0.4064)
			(end 0.7874 -0.4064)
			(stroke
				(width 0.1524)
				(type default)
			)
			(layer "B.SilkS")
		)
		(fp_line
			(start -0.67945 -0.3048)
			(end -0.67945 0.3048)
			(stroke
				(width 0.1)
				(type default)
			)
			(layer "B.Fab")
		)
		(fp_line
			(start -0.67945 0.3048)
			(end -0.120396 0.3048)
			(stroke
				(width 0.1)
				(type default)
			)
			(layer "B.Fab")
		)
		(fp_line
			(start -0.12065 -0.3048)
			(end -0.67945 -0.3048)
			(stroke
				(width 0.1)
				(type default)
			)
			(layer "B.Fab")
		)
		(fp_line
			(start -0.12065 -0.2794)
			(end -0.12065 -0.3048)
			(stroke
				(width 0.1)
				(type default)
			)
			(layer "B.Fab")
		)
		(fp_line
			(start -0.120396 0.2794)
			(end 0.12065 0.2794)
			(stroke
				(width 0.1)
				(type default)
			)
			(layer "B.Fab")
		)
		(fp_line
			(start -0.120396 0.3048)
			(end -0.120396 0.2794)
			(stroke
				(width 0.1)
				(type default)
			)
			(layer "B.Fab")
		)
		(fp_line
			(start 0.12065 -0.305054)
			(end 0.12065 -0.2794)
			(stroke
				(width 0.1)
				(type default)
			)
			(layer "B.Fab")
		)
		(fp_line
			(start 0.12065 -0.2794)
			(end -0.12065 -0.2794)
			(stroke
				(width 0.1)
				(type default)
			)
			(layer "B.Fab")
		)
		(fp_line
			(start 0.12065 0.2794)
			(end 0.12065 0.3048)
			(stroke
				(width 0.1)
				(type default)
			)
			(layer "B.Fab")
		)
		(fp_line
			(start 0.12065 0.3048)
			(end 0.67945 0.3048)
			(stroke
				(width 0.1)
				(type default)
			)
			(layer "B.Fab")
		)
		(fp_line
			(start 0.67945 -0.305054)
			(end 0.12065 -0.305054)
			(stroke
				(width 0.1)
				(type default)
			)
			(layer "B.Fab")
		)
		(fp_line
			(start 0.67945 0.3048)
			(end 0.67945 -0.305054)
			(stroke
				(width 0.1)
				(type default)
			)
			(layer "B.Fab")
		)
		(pad "1" smd circle
			(at 0.40005 0 180)
			(size 0 0)
			(layers "B.Cu" "B.Mask" "B.Paste")
			(net "PWRGD_PVCCINFAON_CPU0")
		)
		(pad "2" smd circle
			(at -0.40005 0 180)
			(size 0 0)
			(layers "B.Cu" "B.Mask" "B.Paste")
			(net "PWRGD_PVCCINFAON_CPU0_R")
		)
	)
	(footprint ""
		(layer "B.Cu")
		(at 322.926456 -49.941988 180)
		(property "Reference" "R2971"
			(at 0 0 0)
			(layer "B.SilkS")
			(hide yes)
			(effects
				(font
					(size 1.27 1.27)
				)
				(justify mirror)
			)
		)
		(property "Value" ""
			(at 0 0 0)
			(layer "B.Fab")
			(effects
				(font
					(size 1.27 1.27)
				)
				(justify mirror)
			)
		)
		(duplicate_pad_numbers_are_jumpers no)
		(fp_line
			(start 0.7874 0.4064)
			(end 0.7874 -0.4064)
			(stroke
				(width 0.1524)
				(type default)
			)
			(layer "B.SilkS")
		)
		(fp_line
			(start 0.7874 -0.4064)
			(end -0.7874 -0.4064)
			(stroke
				(width 0.1524)
				(type default)
			)
			(layer "B.SilkS")
		)
		(fp_line
			(start -0.7874 0.4064)
			(end 0.7874 0.4064)
			(stroke
				(width 0.1524)
				(type default)
			)
			(layer "B.SilkS")
		)
		(fp_line
			(start -0.7874 -0.4064)
			(end -0.7874 0.4064)
			(stroke
				(width 0.1524)
				(type default)
			)
			(layer "B.SilkS")
		)
		(fp_line
			(start 0.67945 0.3048)
			(end 0.67945 -0.305054)
			(stroke
				(width 0.1)
				(type default)
			)
			(layer "B.Fab")
		)
		(fp_line
			(start 0.67945 -0.305054)
			(end 0.12065 -0.305054)
			(stroke
				(width 0.1)
				(type default)
			)
			(layer "B.Fab")
		)
		(fp_line
			(start 0.12065 0.3048)
			(end 0.67945 0.3048)
			(stroke
				(width 0.1)
				(type default)
			)
			(layer "B.Fab")
		)
		(fp_line
			(start 0.12065 0.2794)
			(end 0.12065 0.3048)
			(stroke
				(width 0.1)
				(type default)
			)
			(layer "B.Fab")
		)
		(fp_line
			(start 0.12065 -0.2794)
			(end -0.12065 -0.2794)
			(stroke
				(width 0.1)
				(type default)
			)
			(layer "B.Fab")
		)
		(fp_line
			(start 0.12065 -0.305054)
			(end 0.12065 -0.2794)
			(stroke
				(width 0.1)
				(type default)
			)
			(layer "B.Fab")
		)
		(fp_line
			(start -0.120396 0.3048)
			(end -0.120396 0.2794)
			(stroke
				(width 0.1)
				(type default)
			)
			(layer "B.Fab")
		)
		(fp_line
			(start -0.120396 0.2794)
			(end 0.12065 0.2794)
			(stroke
				(width 0.1)
				(type default)
			)
			(layer "B.Fab")
		)
		(fp_line
			(start -0.12065 -0.2794)
			(end -0.12065 -0.3048)
			(stroke
				(width 0.1)
				(type default)
			)
			(layer "B.Fab")
		)
		(fp_line
			(start -0.12065 -0.3048)
			(end -0.67945 -0.3048)
			(stroke
				(width 0.1)
				(type default)
			)
			(layer "B.Fab")
		)
		(fp_line
			(start -0.67945 0.3048)
			(end -0.120396 0.3048)
			(stroke
				(width 0.1)
				(type default)
			)
			(layer "B.Fab")
		)
		(fp_line
			(start -0.67945 -0.3048)
			(end -0.67945 0.3048)
			(stroke
				(width 0.1)
				(type default)
			)
			(layer "B.Fab")
		)
		(pad "1" smd circle
			(at 0.40005 0)
			(size 0 0)
			(layers "B.Cu" "B.Mask" "B.Paste")
			(net "FM_BIOS_DEBUG_EN_N")
		)
		(pad "2" smd circle
			(at -0.40005 0)
			(size 0 0)
			(layers "B.Cu" "B.Mask" "B.Paste")
			(net "FM_BIOS_DEBUG_EN_R_N")
		)
	)
	(footprint ""
		(layer "B.Cu")
		(at 288.746946 -356.036372 -90)
		(property "Reference" "PC623"
			(at 0 0 90)
			(layer "B.SilkS")
			(hide yes)
			(effects
				(font
					(size 1.27 1.27)
				)
				(justify mirror)
			)
		)
		(property "Value" ""
			(at 0 0 90)
			(layer "B.Fab")
			(effects
				(font
					(size 1.27 1.27)
				)
				(justify mirror)
			)
		)
		(duplicate_pad_numbers_are_jumpers no)
		(fp_line
			(start -4.533392 2.249932)
			(end 4.533392 2.249932)
			(stroke
				(width 0.1524)
				(type default)
			)
			(layer "B.SilkS")
		)
		(fp_line
			(start 4.533392 2.249932)
			(end 4.533392 -2.249932)
			(stroke
				(width 0.1524)
				(type default)
			)
			(layer "B.SilkS")
		)
		(fp_line
			(start -4.533392 -2.249932)
			(end -4.533392 2.249932)
			(stroke
				(width 0.1524)
				(type default)
			)
			(layer "B.SilkS")
		)
		(fp_line
			(start 4.533392 -2.249932)
			(end -4.533392 -2.249932)
			(stroke
				(width 0.1524)
				(type default)
			)
			(layer "B.SilkS")
		)
		(fp_poly
			(pts
				(xy 4.533392 -2.326132) (xy 5.39242 -2.326132) (xy 5.39242 2.326132) (xy 4.533392 2.326132)
			)
			(stroke
				(width 0)
				(type default)
			)
			(fill yes)
			(layer "B.SilkS")
		)
		(fp_line
			(start -3.750056 2.249932)
			(end 3.750056 2.249932)
			(stroke
				(width 0.1)
				(type default)
			)
			(layer "B.Fab")
		)
		(fp_line
			(start 3.750056 2.249932)
			(end 3.750056 -2.249932)
			(stroke
				(width 0.1)
				(type default)
			)
			(layer "B.Fab")
		)
		(fp_line
			(start -3.750056 -2.249932)
			(end -3.750056 2.249932)
			(stroke
				(width 0.1)
				(type default)
			)
			(layer "B.Fab")
		)
		(fp_line
			(start 3.750056 -2.249932)
			(end -3.750056 -2.249932)
			(stroke
				(width 0.1)
				(type default)
			)
			(layer "B.Fab")
		)
		(fp_text user "+"
			(at 6.322314 0.786384 180)
			(unlocked yes)
			(layer "B.SilkS")
			(effects
				(font
					(size 1.905 1.4224)
					(thickness 0.1524)
				)
				(justify left mirror)
			)
		)
		(fp_text user "-"
			(at -4.8514 -0.14605 270)
			(unlocked yes)
			(layer "B.SilkS")
			(effects
				(font
					(size 1.905 1.4224)
					(thickness 0.1524)
				)
				(justify left mirror)
			)
		)
		(fp_text user "+"
			(at 6.322314 0.786384 180)
			(unlocked yes)
			(layer "B.Fab")
			(effects
				(font
					(size 1.905 1.4224)
					(thickness 0.1524)
				)
				(justify left mirror)
			)
		)
		(fp_text user "-"
			(at -4.8514 -0.14605 270)
			(unlocked yes)
			(layer "B.Fab")
			(effects
				(font
					(size 1.905 1.4224)
					(thickness 0.1524)
				)
				(justify left mirror)
			)
		)
		(pad "1" smd rect
			(at 3.199892 0 90)
			(size 2.413 2.8194)
			(layers "B.Cu" "B.Mask" "B.Paste")
			(net "PVCCFA_EHV_FIVRA_CPU0")
		)
		(pad "2" smd rect
			(at -3.199892 0 90)
			(size 2.413 2.8194)
			(layers "B.Cu" "B.Mask" "B.Paste")
			(net "GND")
		)
	)
	(footprint ""
		(layer "B.Cu")
		(at 151.69388 -22.824948 -90)
		(property "Reference" "R2212"
			(at 0 0 90)
			(layer "B.SilkS")
			(hide yes)
			(effects
				(font
					(size 1.27 1.27)
				)
				(justify mirror)
			)
		)
		(property "Value" ""
			(at 0 0 90)
			(layer "B.Fab")
			(effects
				(font
					(size 1.27 1.27)
				)
				(justify mirror)
			)
		)
		(duplicate_pad_numbers_are_jumpers no)
		(fp_line
			(start -0.7874 0.4064)
			(end 0.7874 0.4064)
			(stroke
				(width 0.1524)
				(type default)
			)
			(layer "B.SilkS")
		)
		(fp_line
			(start 0.7874 0.4064)
			(end 0.7874 -0.4064)
			(stroke
				(width 0.1524)
				(type default)
			)
			(layer "B.SilkS")
		)
		(fp_line
			(start -0.7874 -0.4064)
			(end -0.7874 0.4064)
			(stroke
				(width 0.1524)
				(type default)
			)
			(layer "B.SilkS")
		)
		(fp_line
			(start 0.7874 -0.4064)
			(end -0.7874 -0.4064)
			(stroke
				(width 0.1524)
				(type default)
			)
			(layer "B.SilkS")
		)
		(fp_line
			(start -0.67945 0.3048)
			(end -0.120396 0.3048)
			(stroke
				(width 0.1)
				(type default)
			)
			(layer "B.Fab")
		)
		(fp_line
			(start -0.120396 0.3048)
			(end -0.120396 0.2794)
			(stroke
				(width 0.1)
				(type default)
			)
			(layer "B.Fab")
		)
		(fp_line
			(start 0.12065 0.3048)
			(end 0.67945 0.3048)
			(stroke
				(width 0.1)
				(type default)
			)
			(layer "B.Fab")
		)
		(fp_line
			(start 0.67945 0.3048)
			(end 0.67945 -0.305054)
			(stroke
				(width 0.1)
				(type default)
			)
			(layer "B.Fab")
		)
		(fp_line
			(start -0.120396 0.2794)
			(end 0.12065 0.2794)
			(stroke
				(width 0.1)
				(type default)
			)
			(layer "B.Fab")
		)
		(fp_line
			(start 0.12065 0.2794)
			(end 0.12065 0.3048)
			(stroke
				(width 0.1)
				(type default)
			)
			(layer "B.Fab")
		)
		(fp_line
			(start -0.12065 -0.2794)
			(end -0.12065 -0.3048)
			(stroke
				(width 0.1)
				(type default)
			)
			(layer "B.Fab")
		)
		(fp_line
			(start 0.12065 -0.2794)
			(end -0.12065 -0.2794)
			(stroke
				(width 0.1)
				(type default)
			)
			(layer "B.Fab")
		)
		(fp_line
			(start -0.67945 -0.3048)
			(end -0.67945 0.3048)
			(stroke
				(width 0.1)
				(type default)
			)
			(layer "B.Fab")
		)
		(fp_line
			(start -0.12065 -0.3048)
			(end -0.67945 -0.3048)
			(stroke
				(width 0.1)
				(type default)
			)
			(layer "B.Fab")
		)
		(fp_line
			(start 0.12065 -0.305054)
			(end 0.12065 -0.2794)
			(stroke
				(width 0.1)
				(type default)
			)
			(layer "B.Fab")
		)
		(fp_line
			(start 0.67945 -0.305054)
			(end 0.12065 -0.305054)
			(stroke
				(width 0.1)
				(type default)
			)
			(layer "B.Fab")
		)
		(pad "1" smd circle
			(at 0.40005 0 90)
			(size 0 0)
			(layers "B.Cu" "B.Mask" "B.Paste")
			(net "SMB_S3M_CPU_3V3AUX_SCL")
		)
		(pad "2" smd circle
			(at -0.40005 0 90)
			(size 0 0)
			(layers "B.Cu" "B.Mask" "B.Paste")
			(net "P3V3_AUX")
		)
	)
	(footprint ""
		(layer "B.Cu")
		(at 245.58752 -418.05098 180)
		(property "Reference" "FS1"
			(at 6.7183 -2.619248 180)
			(unlocked yes)
			(layer "B.SilkS")
			(effects
				(font
					(size 0.7874 0.5842)
					(thickness 0.1524)
				)
				(justify left mirror)
			)
		)
		(property "Value" ""
			(at 0 0 0)
			(layer "B.Fab")
			(effects
				(font
					(size 1.27 1.27)
				)
				(justify mirror)
			)
		)
		(duplicate_pad_numbers_are_jumpers no)
		(fp_line
			(start 6.427724 1.8415)
			(end -6.427724 1.8415)
			(stroke
				(width 0.1524)
				(type default)
			)
			(layer "B.SilkS")
		)
		(fp_line
			(start 6.427724 -1.8415)
			(end 6.427724 1.8415)
			(stroke
				(width 0.1524)
				(type default)
			)
			(layer "B.SilkS")
		)
		(fp_line
			(start -6.427724 1.8415)
			(end -6.427724 -1.8415)
			(stroke
				(width 0.1524)
				(type default)
			)
			(layer "B.SilkS")
		)
		(fp_line
			(start -6.427724 -1.8415)
			(end 6.427724 -1.8415)
			(stroke
				(width 0.1524)
				(type default)
			)
			(layer "B.SilkS")
		)
		(fp_line
			(start 5.050028 1.560068)
			(end -5.050028 1.560068)
			(stroke
				(width 0.1)
				(type default)
			)
			(layer "B.Fab")
		)
		(fp_line
			(start 5.050028 -1.560068)
			(end 5.050028 1.560068)
			(stroke
				(width 0.1)
				(type default)
			)
			(layer "B.Fab")
		)
		(fp_line
			(start -5.050028 1.560068)
			(end -5.050028 -1.560068)
			(stroke
				(width 0.1)
				(type default)
			)
			(layer "B.Fab")
		)
		(fp_line
			(start -5.050028 -1.560068)
			(end 5.050028 -1.560068)
			(stroke
				(width 0.1)
				(type default)
			)
			(layer "B.Fab")
		)
		(pad "1" smd rect
			(at 4.675124 0)
			(size 3.2512 3.429)
			(layers "B.Cu" "B.Mask" "B.Paste")
			(net "P12V_PSU")
		)
		(pad "2" smd rect
			(at -4.675124 0)
			(size 3.2512 3.429)
			(layers "B.Cu" "B.Mask" "B.Paste")
			(net "P12V_PSU_FUSE")
		)
	)
	(footprint ""
		(layer "B.Cu")
		(at 318.323468 -35.170872 -135)
		(property "Reference" "R1423"
			(at 0 0 45)
			(layer "B.SilkS")
			(hide yes)
			(effects
				(font
					(size 1.27 1.27)
				)
				(justify mirror)
			)
		)
		(property "Value" ""
			(at 0 0 45)
			(layer "B.Fab")
			(effects
				(font
					(size 1.27 1.27)
				)
				(justify mirror)
			)
		)
		(duplicate_pad_numbers_are_jumpers no)
		(fp_line
			(start 0.787389 0.406267)
			(end 0.787389 -0.406267)
			(stroke
				(width 0.1524)
				(type default)
			)
			(layer "B.SilkS")
		)
		(fp_line
			(start 0.787389 -0.406267)
			(end -0.787389 -0.406267)
			(stroke
				(width 0.1524)
				(type default)
			)
			(layer "B.SilkS")
		)
		(fp_line
			(start -0.787389 0.406267)
			(end 0.787389 0.406267)
			(stroke
				(width 0.1524)
				(type default)
			)
			(layer "B.SilkS")
		)
		(fp_line
			(start -0.787389 -0.406267)
			(end -0.787389 0.406267)
			(stroke
				(width 0.1524)
				(type default)
			)
			(layer "B.SilkS")
		)
		(fp_line
			(start 0.679446 0.30479)
			(end 0.679446 -0.305149)
			(stroke
				(width 0.1)
				(type default)
			)
			(layer "B.Fab")
		)
		(fp_line
			(start 0.120515 0.30479)
			(end 0.679446 0.30479)
			(stroke
				(width 0.1)
				(type default)
			)
			(layer "B.Fab")
		)
		(fp_line
			(start 0.120695 0.279466)
			(end 0.120515 0.30479)
			(stroke
				(width 0.1)
				(type default)
			)
			(layer "B.Fab")
		)
		(fp_line
			(start 0.679446 -0.305149)
			(end 0.120695 -0.304969)
			(stroke
				(width 0.1)
				(type default)
			)
			(layer "B.Fab")
		)
		(fp_line
			(start -0.120515 0.30479)
			(end -0.120335 0.279466)
			(stroke
				(width 0.1)
				(type default)
			)
			(layer "B.Fab")
		)
		(fp_line
			(start -0.120335 0.279466)
			(end 0.120695 0.279466)
			(stroke
				(width 0.1)
				(type default)
			)
			(layer "B.Fab")
		)
		(fp_line
			(start 0.120695 -0.279466)
			(end -0.120695 -0.279466)
			(stroke
				(width 0.1)
				(type default)
			)
			(layer "B.Fab")
		)
		(fp_line
			(start 0.120695 -0.304969)
			(end 0.120695 -0.279466)
			(stroke
				(width 0.1)
				(type default)
			)
			(layer "B.Fab")
		)
		(fp_line
			(start -0.679446 0.30479)
			(end -0.120515 0.30479)
			(stroke
				(width 0.1)
				(type default)
			)
			(layer "B.Fab")
		)
		(fp_line
			(start -0.120695 -0.279466)
			(end -0.120515 -0.30479)
			(stroke
				(width 0.1)
				(type default)
			)
			(layer "B.Fab")
		)
		(fp_line
			(start -0.120515 -0.30479)
			(end -0.679446 -0.30479)
			(stroke
				(width 0.1)
				(type default)
			)
			(layer "B.Fab")
		)
		(fp_line
			(start -0.679446 -0.30479)
			(end -0.679446 0.30479)
			(stroke
				(width 0.1)
				(type default)
			)
			(layer "B.Fab")
		)
		(pad "1" smd circle
			(at 0.40005 0 45)
			(size 0 0)
			(layers "B.Cu" "B.Mask" "B.Paste")
			(net "PWRGD_SYS_PWROK_R")
		)
		(pad "2" smd circle
			(at -0.40005 0 45)
			(size 0 0)
			(layers "B.Cu" "B.Mask" "B.Paste")
			(net "PWRGD_SYS_PWROK")
		)
	)
	(footprint ""
		(layer "B.Cu")
		(at 55.280052 -319.009776)
		(property "Reference" "R42"
			(at 0 0 0)
			(layer "B.SilkS")
			(hide yes)
			(effects
				(font
					(size 1.27 1.27)
				)
				(justify mirror)
			)
		)
		(property "Value" ""
			(at 0 0 0)
			(layer "B.Fab")
			(effects
				(font
					(size 1.27 1.27)
				)
				(justify mirror)
			)
		)
		(duplicate_pad_numbers_are_jumpers no)
		(fp_line
			(start -0.7874 -0.4064)
			(end -0.7874 0.4064)
			(stroke
				(width 0.1524)
				(type default)
			)
			(layer "B.SilkS")
		)
		(fp_line
			(start -0.7874 0.4064)
			(end 0.7874 0.4064)
			(stroke
				(width 0.1524)
				(type default)
			)
			(layer "B.SilkS")
		)
		(fp_line
			(start 0.7874 -0.4064)
			(end -0.7874 -0.4064)
			(stroke
				(width 0.1524)
				(type default)
			)
			(layer "B.SilkS")
		)
		(fp_line
			(start 0.7874 0.4064)
			(end 0.7874 -0.4064)
			(stroke
				(width 0.1524)
				(type default)
			)
			(layer "B.SilkS")
		)
		(fp_line
			(start -0.67945 -0.3048)
			(end -0.67945 0.3048)
			(stroke
				(width 0.1)
				(type default)
			)
			(layer "B.Fab")
		)
		(fp_line
			(start -0.67945 0.3048)
			(end -0.120396 0.3048)
			(stroke
				(width 0.1)
				(type default)
			)
			(layer "B.Fab")
		)
		(fp_line
			(start -0.12065 -0.3048)
			(end -0.67945 -0.3048)
			(stroke
				(width 0.1)
				(type default)
			)
			(layer "B.Fab")
		)
		(fp_line
			(start -0.12065 -0.2794)
			(end -0.12065 -0.3048)
			(stroke
				(width 0.1)
				(type default)
			)
			(layer "B.Fab")
		)
		(fp_line
			(start -0.120396 0.2794)
			(end 0.12065 0.2794)
			(stroke
				(width 0.1)
				(type default)
			)
			(layer "B.Fab")
		)
		(fp_line
			(start -0.120396 0.3048)
			(end -0.120396 0.2794)
			(stroke
				(width 0.1)
				(type default)
			)
			(layer "B.Fab")
		)
		(fp_line
			(start 0.12065 -0.305054)
			(end 0.12065 -0.2794)
			(stroke
				(width 0.1)
				(type default)
			)
			(layer "B.Fab")
		)
		(fp_line
			(start 0.12065 -0.2794)
			(end -0.12065 -0.2794)
			(stroke
				(width 0.1)
				(type default)
			)
			(layer "B.Fab")
		)
		(fp_line
			(start 0.12065 0.2794)
			(end 0.12065 0.3048)
			(stroke
				(width 0.1)
				(type default)
			)
			(layer "B.Fab")
		)
		(fp_line
			(start 0.12065 0.3048)
			(end 0.67945 0.3048)
			(stroke
				(width 0.1)
				(type default)
			)
			(layer "B.Fab")
		)
		(fp_line
			(start 0.67945 -0.305054)
			(end 0.12065 -0.305054)
			(stroke
				(width 0.1)
				(type default)
			)
			(layer "B.Fab")
		)
		(fp_line
			(start 0.67945 0.3048)
			(end 0.67945 -0.305054)
			(stroke
				(width 0.1)
				(type default)
			)
			(layer "B.Fab")
		)
		(pad "1" smd circle
			(at 0.40005 0 180)
			(size 0 0)
			(layers "B.Cu" "B.Mask" "B.Paste")
			(net "PD_CHA_CPU1_DIMM1_SAA")
		)
		(pad "2" smd circle
			(at -0.40005 0 180)
			(size 0 0)
			(layers "B.Cu" "B.Mask" "B.Paste")
			(net "GND")
		)
	)
	(footprint ""
		(layer "B.Cu")
		(at 216.25306 -78.448408 180)
		(property "Reference" "R3212"
			(at 0 0 0)
			(layer "B.SilkS")
			(hide yes)
			(effects
				(font
					(size 1.27 1.27)
				)
				(justify mirror)
			)
		)
		(property "Value" ""
			(at 0 0 0)
			(layer "B.Fab")
			(effects
				(font
					(size 1.27 1.27)
				)
				(justify mirror)
			)
		)
		(duplicate_pad_numbers_are_jumpers no)
		(fp_line
			(start 0.7874 0.4064)
			(end 0.7874 -0.4064)
			(stroke
				(width 0.1524)
				(type default)
			)
			(layer "B.SilkS")
		)
		(fp_line
			(start 0.7874 -0.4064)
			(end -0.7874 -0.4064)
			(stroke
				(width 0.1524)
				(type default)
			)
			(layer "B.SilkS")
		)
		(fp_line
			(start -0.7874 0.4064)
			(end 0.7874 0.4064)
			(stroke
				(width 0.1524)
				(type default)
			)
			(layer "B.SilkS")
		)
		(fp_line
			(start -0.7874 -0.4064)
			(end -0.7874 0.4064)
			(stroke
				(width 0.1524)
				(type default)
			)
			(layer "B.SilkS")
		)
		(fp_line
			(start 0.67945 0.3048)
			(end 0.67945 -0.305054)
			(stroke
				(width 0.1)
				(type default)
			)
			(layer "B.Fab")
		)
		(fp_line
			(start 0.67945 -0.305054)
			(end 0.12065 -0.305054)
			(stroke
				(width 0.1)
				(type default)
			)
			(layer "B.Fab")
		)
		(fp_line
			(start 0.12065 0.3048)
			(end 0.67945 0.3048)
			(stroke
				(width 0.1)
				(type default)
			)
			(layer "B.Fab")
		)
		(fp_line
			(start 0.12065 0.2794)
			(end 0.12065 0.3048)
			(stroke
				(width 0.1)
				(type default)
			)
			(layer "B.Fab")
		)
		(fp_line
			(start 0.12065 -0.2794)
			(end -0.12065 -0.2794)
			(stroke
				(width 0.1)
				(type default)
			)
			(layer "B.Fab")
		)
		(fp_line
			(start 0.12065 -0.305054)
			(end 0.12065 -0.2794)
			(stroke
				(width 0.1)
				(type default)
			)
			(layer "B.Fab")
		)
		(fp_line
			(start -0.120396 0.3048)
			(end -0.120396 0.2794)
			(stroke
				(width 0.1)
				(type default)
			)
			(layer "B.Fab")
		)
		(fp_line
			(start -0.120396 0.2794)
			(end 0.12065 0.2794)
			(stroke
				(width 0.1)
				(type default)
			)
			(layer "B.Fab")
		)
		(fp_line
			(start -0.12065 -0.2794)
			(end -0.12065 -0.3048)
			(stroke
				(width 0.1)
				(type default)
			)
			(layer "B.Fab")
		)
		(fp_line
			(start -0.12065 -0.3048)
			(end -0.67945 -0.3048)
			(stroke
				(width 0.1)
				(type default)
			)
			(layer "B.Fab")
		)
		(fp_line
			(start -0.67945 0.3048)
			(end -0.120396 0.3048)
			(stroke
				(width 0.1)
				(type default)
			)
			(layer "B.Fab")
		)
		(fp_line
			(start -0.67945 -0.3048)
			(end -0.67945 0.3048)
			(stroke
				(width 0.1)
				(type default)
			)
			(layer "B.Fab")
		)
		(pad "1" smd circle
			(at 0.40005 0)
			(size 0 0)
			(layers "B.Cu" "B.Mask" "B.Paste")
			(net "NCSI_BMC_RXD1_R1")
		)
		(pad "2" smd circle
			(at -0.40005 0)
			(size 0 0)
			(layers "B.Cu" "B.Mask" "B.Paste")
			(net "RMII_OCP_BMC_RXD_1")
		)
	)
	(footprint ""
		(layer "B.Cu")
		(at 267.701014 -321.549776 -90)
		(property "Reference" "C24"
			(at 0 0 90)
			(layer "B.SilkS")
			(hide yes)
			(effects
				(font
					(size 1.27 1.27)
				)
				(justify mirror)
			)
		)
		(property "Value" ""
			(at 0 0 90)
			(layer "B.Fab")
			(effects
				(font
					(size 1.27 1.27)
				)
				(justify mirror)
			)
		)
		(duplicate_pad_numbers_are_jumpers no)
		(fp_line
			(start -1.524 0.762)
			(end 1.524 0.762)
			(stroke
				(width 0.1524)
				(type default)
			)
			(layer "B.SilkS")
		)
		(fp_line
			(start 1.524 0.762)
			(end 1.524 -0.762)
			(stroke
				(width 0.1524)
				(type default)
			)
			(layer "B.SilkS")
		)
		(fp_line
			(start -1.524 -0.762)
			(end -1.524 0.762)
			(stroke
				(width 0.1524)
				(type default)
			)
			(layer "B.SilkS")
		)
		(fp_line
			(start 1.524 -0.762)
			(end -1.524 -0.762)
			(stroke
				(width 0.1524)
				(type default)
			)
			(layer "B.SilkS")
		)
		(fp_line
			(start -1.1049 0.724916)
			(end -1.1049 -0.724916)
			(stroke
				(width 0.1)
				(type default)
			)
			(layer "B.Fab")
		)
		(fp_line
			(start 1.1049 0.724916)
			(end -1.1049 0.724916)
			(stroke
				(width 0.1)
				(type default)
			)
			(layer "B.Fab")
		)
		(fp_line
			(start -1.1049 -0.724916)
			(end 1.1049 -0.724916)
			(stroke
				(width 0.1)
				(type default)
			)
			(layer "B.Fab")
		)
		(fp_line
			(start 1.1049 -0.724916)
			(end 1.1049 0.724916)
			(stroke
				(width 0.1)
				(type default)
			)
			(layer "B.Fab")
		)
		(pad "1" smd rect
			(at 0.889 0 270)
			(size 1.016 1.27)
			(layers "B.Cu" "B.Mask" "B.Paste")
			(net "P12V_S3_AUX_CPU0_NVDIMM")
		)
		(pad "2" smd rect
			(at -0.889 0 270)
			(size 1.016 1.27)
			(layers "B.Cu" "B.Mask" "B.Paste")
			(net "GND")
		)
	)
	(footprint ""
		(layer "B.Cu")
		(at 434.57241 -193.567304 -90)
		(property "Reference" "R835"
			(at 0 0 90)
			(layer "B.SilkS")
			(hide yes)
			(effects
				(font
					(size 1.27 1.27)
				)
				(justify mirror)
			)
		)
		(property "Value" ""
			(at 0 0 90)
			(layer "B.Fab")
			(effects
				(font
					(size 1.27 1.27)
				)
				(justify mirror)
			)
		)
		(duplicate_pad_numbers_are_jumpers no)
		(fp_line
			(start -0.7874 0.4064)
			(end 0.7874 0.4064)
			(stroke
				(width 0.1524)
				(type default)
			)
			(layer "B.SilkS")
		)
		(fp_line
			(start 0.7874 0.4064)
			(end 0.7874 -0.4064)
			(stroke
				(width 0.1524)
				(type default)
			)
			(layer "B.SilkS")
		)
		(fp_line
			(start -0.7874 -0.4064)
			(end -0.7874 0.4064)
			(stroke
				(width 0.1524)
				(type default)
			)
			(layer "B.SilkS")
		)
		(fp_line
			(start 0.7874 -0.4064)
			(end -0.7874 -0.4064)
			(stroke
				(width 0.1524)
				(type default)
			)
			(layer "B.SilkS")
		)
		(fp_line
			(start -0.67945 0.3048)
			(end -0.120396 0.3048)
			(stroke
				(width 0.1)
				(type default)
			)
			(layer "B.Fab")
		)
		(fp_line
			(start -0.120396 0.3048)
			(end -0.120396 0.2794)
			(stroke
				(width 0.1)
				(type default)
			)
			(layer "B.Fab")
		)
		(fp_line
			(start 0.12065 0.3048)
			(end 0.67945 0.3048)
			(stroke
				(width 0.1)
				(type default)
			)
			(layer "B.Fab")
		)
		(fp_line
			(start 0.67945 0.3048)
			(end 0.67945 -0.305054)
			(stroke
				(width 0.1)
				(type default)
			)
			(layer "B.Fab")
		)
		(fp_line
			(start -0.120396 0.2794)
			(end 0.12065 0.2794)
			(stroke
				(width 0.1)
				(type default)
			)
			(layer "B.Fab")
		)
		(fp_line
			(start 0.12065 0.2794)
			(end 0.12065 0.3048)
			(stroke
				(width 0.1)
				(type default)
			)
			(layer "B.Fab")
		)
		(fp_line
			(start -0.12065 -0.2794)
			(end -0.12065 -0.3048)
			(stroke
				(width 0.1)
				(type default)
			)
			(layer "B.Fab")
		)
		(fp_line
			(start 0.12065 -0.2794)
			(end -0.12065 -0.2794)
			(stroke
				(width 0.1)
				(type default)
			)
			(layer "B.Fab")
		)
		(fp_line
			(start -0.67945 -0.3048)
			(end -0.67945 0.3048)
			(stroke
				(width 0.1)
				(type default)
			)
			(layer "B.Fab")
		)
		(fp_line
			(start -0.12065 -0.3048)
			(end -0.67945 -0.3048)
			(stroke
				(width 0.1)
				(type default)
			)
			(layer "B.Fab")
		)
		(fp_line
			(start 0.12065 -0.305054)
			(end 0.12065 -0.2794)
			(stroke
				(width 0.1)
				(type default)
			)
			(layer "B.Fab")
		)
		(fp_line
			(start 0.67945 -0.305054)
			(end 0.12065 -0.305054)
			(stroke
				(width 0.1)
				(type default)
			)
			(layer "B.Fab")
		)
		(pad "1" smd circle
			(at 0.40005 0 90)
			(size 0 0)
			(layers "B.Cu" "B.Mask" "B.Paste")
			(net "RST_PLD_CPU0_DRAM_GH_N")
		)
		(pad "2" smd circle
			(at -0.40005 0 90)
			(size 0 0)
			(layers "B.Cu" "B.Mask" "B.Paste")
			(net "RST_M_GH_CPU0_FPGA_N")
		)
	)
	(footprint ""
		(layer "B.Cu")
		(at 328.169778 -185.09869 -90)
		(property "Reference" "R278"
			(at 0 0 90)
			(layer "B.SilkS")
			(hide yes)
			(effects
				(font
					(size 1.27 1.27)
				)
				(justify mirror)
			)
		)
		(property "Value" ""
			(at 0 0 90)
			(layer "B.Fab")
			(effects
				(font
					(size 1.27 1.27)
				)
				(justify mirror)
			)
		)
		(duplicate_pad_numbers_are_jumpers no)
		(fp_line
			(start -0.7874 0.4064)
			(end 0.7874 0.4064)
			(stroke
				(width 0.1524)
				(type default)
			)
			(layer "B.SilkS")
		)
		(fp_line
			(start 0.7874 0.4064)
			(end 0.7874 -0.4064)
			(stroke
				(width 0.1524)
				(type default)
			)
			(layer "B.SilkS")
		)
		(fp_line
			(start -0.7874 -0.4064)
			(end -0.7874 0.4064)
			(stroke
				(width 0.1524)
				(type default)
			)
			(layer "B.SilkS")
		)
		(fp_line
			(start 0.7874 -0.4064)
			(end -0.7874 -0.4064)
			(stroke
				(width 0.1524)
				(type default)
			)
			(layer "B.SilkS")
		)
		(fp_line
			(start -0.67945 0.3048)
			(end -0.120396 0.3048)
			(stroke
				(width 0.1)
				(type default)
			)
			(layer "B.Fab")
		)
		(fp_line
			(start -0.120396 0.3048)
			(end -0.120396 0.2794)
			(stroke
				(width 0.1)
				(type default)
			)
			(layer "B.Fab")
		)
		(fp_line
			(start 0.12065 0.3048)
			(end 0.67945 0.3048)
			(stroke
				(width 0.1)
				(type default)
			)
			(layer "B.Fab")
		)
		(fp_line
			(start 0.67945 0.3048)
			(end 0.67945 -0.305054)
			(stroke
				(width 0.1)
				(type default)
			)
			(layer "B.Fab")
		)
		(fp_line
			(start -0.120396 0.2794)
			(end 0.12065 0.2794)
			(stroke
				(width 0.1)
				(type default)
			)
			(layer "B.Fab")
		)
		(fp_line
			(start 0.12065 0.2794)
			(end 0.12065 0.3048)
			(stroke
				(width 0.1)
				(type default)
			)
			(layer "B.Fab")
		)
		(fp_line
			(start -0.12065 -0.2794)
			(end -0.12065 -0.3048)
			(stroke
				(width 0.1)
				(type default)
			)
			(layer "B.Fab")
		)
		(fp_line
			(start 0.12065 -0.2794)
			(end -0.12065 -0.2794)
			(stroke
				(width 0.1)
				(type default)
			)
			(layer "B.Fab")
		)
		(fp_line
			(start -0.67945 -0.3048)
			(end -0.67945 0.3048)
			(stroke
				(width 0.1)
				(type default)
			)
			(layer "B.Fab")
		)
		(fp_line
			(start -0.12065 -0.3048)
			(end -0.67945 -0.3048)
			(stroke
				(width 0.1)
				(type default)
			)
			(layer "B.Fab")
		)
		(fp_line
			(start 0.12065 -0.305054)
			(end 0.12065 -0.2794)
			(stroke
				(width 0.1)
				(type default)
			)
			(layer "B.Fab")
		)
		(fp_line
			(start 0.67945 -0.305054)
			(end 0.12065 -0.305054)
			(stroke
				(width 0.1)
				(type default)
			)
			(layer "B.Fab")
		)
		(pad "1" smd circle
			(at 0.40005 0 90)
			(size 0 0)
			(layers "B.Cu" "B.Mask" "B.Paste")
			(net "PVNN_TERM_CPU0")
		)
		(pad "2" smd circle
			(at -0.40005 0 90)
			(size 0 0)
			(layers "B.Cu" "B.Mask" "B.Paste")
			(net "H_CPU0_BMCINIT_LVC1")
		)
	)
	(footprint ""
		(layer "B.Cu")
		(at 68.337684 -185.791856 -90)
		(property "Reference" "R1008"
			(at 0 0 90)
			(layer "B.SilkS")
			(hide yes)
			(effects
				(font
					(size 1.27 1.27)
				)
				(justify mirror)
			)
		)
		(property "Value" ""
			(at 0 0 90)
			(layer "B.Fab")
			(effects
				(font
					(size 1.27 1.27)
				)
				(justify mirror)
			)
		)
		(duplicate_pad_numbers_are_jumpers no)
		(fp_line
			(start -0.7874 0.4064)
			(end 0.7874 0.4064)
			(stroke
				(width 0.1524)
				(type default)
			)
			(layer "B.SilkS")
		)
		(fp_line
			(start 0.7874 0.4064)
			(end 0.7874 -0.4064)
			(stroke
				(width 0.1524)
				(type default)
			)
			(layer "B.SilkS")
		)
		(fp_line
			(start -0.7874 -0.4064)
			(end -0.7874 0.4064)
			(stroke
				(width 0.1524)
				(type default)
			)
			(layer "B.SilkS")
		)
		(fp_line
			(start 0.7874 -0.4064)
			(end -0.7874 -0.4064)
			(stroke
				(width 0.1524)
				(type default)
			)
			(layer "B.SilkS")
		)
		(fp_line
			(start -0.67945 0.3048)
			(end -0.120396 0.3048)
			(stroke
				(width 0.1)
				(type default)
			)
			(layer "B.Fab")
		)
		(fp_line
			(start -0.120396 0.3048)
			(end -0.120396 0.2794)
			(stroke
				(width 0.1)
				(type default)
			)
			(layer "B.Fab")
		)
		(fp_line
			(start 0.12065 0.3048)
			(end 0.67945 0.3048)
			(stroke
				(width 0.1)
				(type default)
			)
			(layer "B.Fab")
		)
		(fp_line
			(start 0.67945 0.3048)
			(end 0.67945 -0.305054)
			(stroke
				(width 0.1)
				(type default)
			)
			(layer "B.Fab")
		)
		(fp_line
			(start -0.120396 0.2794)
			(end 0.12065 0.2794)
			(stroke
				(width 0.1)
				(type default)
			)
			(layer "B.Fab")
		)
		(fp_line
			(start 0.12065 0.2794)
			(end 0.12065 0.3048)
			(stroke
				(width 0.1)
				(type default)
			)
			(layer "B.Fab")
		)
		(fp_line
			(start -0.12065 -0.2794)
			(end -0.12065 -0.3048)
			(stroke
				(width 0.1)
				(type default)
			)
			(layer "B.Fab")
		)
		(fp_line
			(start 0.12065 -0.2794)
			(end -0.12065 -0.2794)
			(stroke
				(width 0.1)
				(type default)
			)
			(layer "B.Fab")
		)
		(fp_line
			(start -0.67945 -0.3048)
			(end -0.67945 0.3048)
			(stroke
				(width 0.1)
				(type default)
			)
			(layer "B.Fab")
		)
		(fp_line
			(start -0.12065 -0.3048)
			(end -0.67945 -0.3048)
			(stroke
				(width 0.1)
				(type default)
			)
			(layer "B.Fab")
		)
		(fp_line
			(start 0.12065 -0.305054)
			(end 0.12065 -0.2794)
			(stroke
				(width 0.1)
				(type default)
			)
			(layer "B.Fab")
		)
		(fp_line
			(start 0.67945 -0.305054)
			(end 0.12065 -0.305054)
			(stroke
				(width 0.1)
				(type default)
			)
			(layer "B.Fab")
		)
		(pad "1" smd circle
			(at 0.40005 0 90)
			(size 0 0)
			(layers "B.Cu" "B.Mask" "B.Paste")
			(net "PVNN_TERM_CPU1")
		)
		(pad "2" smd circle
			(at -0.40005 0 90)
			(size 0 0)
			(layers "B.Cu" "B.Mask" "B.Paste")
			(net "PU_TAP_ODT_CPU1_EN")
		)
	)
	(footprint ""
		(layer "B.Cu")
		(at 411.172152 -193.08953 -90)
		(property "Reference" "R97"
			(at 0 0 90)
			(layer "B.SilkS")
			(hide yes)
			(effects
				(font
					(size 1.27 1.27)
				)
				(justify mirror)
			)
		)
		(property "Value" ""
			(at 0 0 90)
			(layer "B.Fab")
			(effects
				(font
					(size 1.27 1.27)
				)
				(justify mirror)
			)
		)
		(duplicate_pad_numbers_are_jumpers no)
		(fp_line
			(start -0.7874 0.4064)
			(end 0.7874 0.4064)
			(stroke
				(width 0.1524)
				(type default)
			)
			(layer "B.SilkS")
		)
		(fp_line
			(start 0.7874 0.4064)
			(end 0.7874 -0.4064)
			(stroke
				(width 0.1524)
				(type default)
			)
			(layer "B.SilkS")
		)
		(fp_line
			(start -0.7874 -0.4064)
			(end -0.7874 0.4064)
			(stroke
				(width 0.1524)
				(type default)
			)
			(layer "B.SilkS")
		)
		(fp_line
			(start 0.7874 -0.4064)
			(end -0.7874 -0.4064)
			(stroke
				(width 0.1524)
				(type default)
			)
			(layer "B.SilkS")
		)
		(fp_line
			(start -0.67945 0.3048)
			(end -0.120396 0.3048)
			(stroke
				(width 0.1)
				(type default)
			)
			(layer "B.Fab")
		)
		(fp_line
			(start -0.120396 0.3048)
			(end -0.120396 0.2794)
			(stroke
				(width 0.1)
				(type default)
			)
			(layer "B.Fab")
		)
		(fp_line
			(start 0.12065 0.3048)
			(end 0.67945 0.3048)
			(stroke
				(width 0.1)
				(type default)
			)
			(layer "B.Fab")
		)
		(fp_line
			(start 0.67945 0.3048)
			(end 0.67945 -0.305054)
			(stroke
				(width 0.1)
				(type default)
			)
			(layer "B.Fab")
		)
		(fp_line
			(start -0.120396 0.2794)
			(end 0.12065 0.2794)
			(stroke
				(width 0.1)
				(type default)
			)
			(layer "B.Fab")
		)
		(fp_line
			(start 0.12065 0.2794)
			(end 0.12065 0.3048)
			(stroke
				(width 0.1)
				(type default)
			)
			(layer "B.Fab")
		)
		(fp_line
			(start -0.12065 -0.2794)
			(end -0.12065 -0.3048)
			(stroke
				(width 0.1)
				(type default)
			)
			(layer "B.Fab")
		)
		(fp_line
			(start 0.12065 -0.2794)
			(end -0.12065 -0.2794)
			(stroke
				(width 0.1)
				(type default)
			)
			(layer "B.Fab")
		)
		(fp_line
			(start -0.67945 -0.3048)
			(end -0.67945 0.3048)
			(stroke
				(width 0.1)
				(type default)
			)
			(layer "B.Fab")
		)
		(fp_line
			(start -0.12065 -0.3048)
			(end -0.67945 -0.3048)
			(stroke
				(width 0.1)
				(type default)
			)
			(layer "B.Fab")
		)
		(fp_line
			(start 0.12065 -0.305054)
			(end 0.12065 -0.2794)
			(stroke
				(width 0.1)
				(type default)
			)
			(layer "B.Fab")
		)
		(fp_line
			(start 0.67945 -0.305054)
			(end 0.12065 -0.305054)
			(stroke
				(width 0.1)
				(type default)
			)
			(layer "B.Fab")
		)
		(pad "1" smd circle
			(at 0.40005 0 90)
			(size 0 0)
			(layers "B.Cu" "B.Mask" "B.Paste")
			(net "PVNN_TERM_CPU0")
		)
		(pad "2" smd circle
			(at -0.40005 0 90)
			(size 0 0)
			(layers "B.Cu" "B.Mask" "B.Paste")
			(net "PU_CPU0_UPI3_AC_COUPLING")
		)
	)
	(footprint ""
		(layer "B.Cu")
		(at 107.457494 -244.82044 -90)
		(property "Reference" "C318"
			(at 0 0 90)
			(layer "B.SilkS")
			(hide yes)
			(effects
				(font
					(size 1.27 1.27)
				)
				(justify mirror)
			)
		)
		(property "Value" ""
			(at 0 0 90)
			(layer "B.Fab")
			(effects
				(font
					(size 1.27 1.27)
				)
				(justify mirror)
			)
		)
		(duplicate_pad_numbers_are_jumpers no)
		(fp_line
			(start -1.524 0.762)
			(end 1.524 0.762)
			(stroke
				(width 0.1524)
				(type default)
			)
			(layer "B.SilkS")
		)
		(fp_line
			(start 1.524 0.762)
			(end 1.524 -0.762)
			(stroke
				(width 0.1524)
				(type default)
			)
			(layer "B.SilkS")
		)
		(fp_line
			(start -1.524 -0.762)
			(end -1.524 0.762)
			(stroke
				(width 0.1524)
				(type default)
			)
			(layer "B.SilkS")
		)
		(fp_line
			(start 1.524 -0.762)
			(end -1.524 -0.762)
			(stroke
				(width 0.1524)
				(type default)
			)
			(layer "B.SilkS")
		)
		(fp_line
			(start -1.1049 0.724916)
			(end -1.1049 -0.724916)
			(stroke
				(width 0.1)
				(type default)
			)
			(layer "B.Fab")
		)
		(fp_line
			(start 1.1049 0.724916)
			(end -1.1049 0.724916)
			(stroke
				(width 0.1)
				(type default)
			)
			(layer "B.Fab")
		)
		(fp_line
			(start -1.1049 -0.724916)
			(end 1.1049 -0.724916)
			(stroke
				(width 0.1)
				(type default)
			)
			(layer "B.Fab")
		)
		(fp_line
			(start 1.1049 -0.724916)
			(end 1.1049 0.724916)
			(stroke
				(width 0.1)
				(type default)
			)
			(layer "B.Fab")
		)
		(pad "1" smd rect
			(at 0.889 0 270)
			(size 1.016 1.27)
			(layers "B.Cu" "B.Mask" "B.Paste")
			(net "PVCCIN_CPU1")
		)
		(pad "2" smd rect
			(at -0.889 0 270)
			(size 1.016 1.27)
			(layers "B.Cu" "B.Mask" "B.Paste")
			(net "GND")
		)
	)
	(footprint ""
		(layer "B.Cu")
		(at 24.0538 -391.483088 90)
		(property "Reference" "C1864"
			(at 0 0 90)
			(layer "B.SilkS")
			(hide yes)
			(effects
				(font
					(size 1.27 1.27)
				)
				(justify mirror)
			)
		)
		(property "Value" ""
			(at 0 0 90)
			(layer "B.Fab")
			(effects
				(font
					(size 1.27 1.27)
				)
				(justify mirror)
			)
		)
		(duplicate_pad_numbers_are_jumpers no)
		(fp_line
			(start 0.7874 -0.4064)
			(end -0.7874 -0.4064)
			(stroke
				(width 0.1524)
				(type default)
			)
			(layer "B.SilkS")
		)
		(fp_line
			(start -0.7874 -0.4064)
			(end -0.7874 0.4064)
			(stroke
				(width 0.1524)
				(type default)
			)
			(layer "B.SilkS")
		)
		(fp_line
			(start 0.7874 0.4064)
			(end 0.7874 -0.4064)
			(stroke
				(width 0.1524)
				(type default)
			)
			(layer "B.SilkS")
		)
		(fp_line
			(start -0.7874 0.4064)
			(end 0.7874 0.4064)
			(stroke
				(width 0.1524)
				(type default)
			)
			(layer "B.SilkS")
		)
		(fp_line
			(start 0.67945 -0.305054)
			(end 0.12065 -0.305054)
			(stroke
				(width 0.1)
				(type default)
			)
			(layer "B.Fab")
		)
		(fp_line
			(start 0.12065 -0.305054)
			(end 0.12065 -0.2794)
			(stroke
				(width 0.1)
				(type default)
			)
			(layer "B.Fab")
		)
		(fp_line
			(start -0.12065 -0.3048)
			(end -0.67945 -0.3048)
			(stroke
				(width 0.1)
				(type default)
			)
			(layer "B.Fab")
		)
		(fp_line
			(start -0.67945 -0.3048)
			(end -0.67945 0.3048)
			(stroke
				(width 0.1)
				(type default)
			)
			(layer "B.Fab")
		)
		(fp_line
			(start 0.12065 -0.2794)
			(end -0.12065 -0.2794)
			(stroke
				(width 0.1)
				(type default)
			)
			(layer "B.Fab")
		)
		(fp_line
			(start -0.12065 -0.2794)
			(end -0.12065 -0.3048)
			(stroke
				(width 0.1)
				(type default)
			)
			(layer "B.Fab")
		)
		(fp_line
			(start 0.12065 0.2794)
			(end 0.12065 0.3048)
			(stroke
				(width 0.1)
				(type default)
			)
			(layer "B.Fab")
		)
		(fp_line
			(start -0.120396 0.2794)
			(end 0.12065 0.2794)
			(stroke
				(width 0.1)
				(type default)
			)
			(layer "B.Fab")
		)
		(fp_line
			(start 0.67945 0.3048)
			(end 0.67945 -0.305054)
			(stroke
				(width 0.1)
				(type default)
			)
			(layer "B.Fab")
		)
		(fp_line
			(start 0.12065 0.3048)
			(end 0.67945 0.3048)
			(stroke
				(width 0.1)
				(type default)
			)
			(layer "B.Fab")
		)
		(fp_line
			(start -0.120396 0.3048)
			(end -0.120396 0.2794)
			(stroke
				(width 0.1)
				(type default)
			)
			(layer "B.Fab")
		)
		(fp_line
			(start -0.67945 0.3048)
			(end -0.120396 0.3048)
			(stroke
				(width 0.1)
				(type default)
			)
			(layer "B.Fab")
		)
		(pad "1" smd circle
			(at 0.40005 0 270)
			(size 0 0)
			(layers "B.Cu" "B.Mask" "B.Paste")
			(net "P3V3_AUX")
		)
		(pad "2" smd circle
			(at -0.40005 0 270)
			(size 0 0)
			(layers "B.Cu" "B.Mask" "B.Paste")
			(net "GND")
		)
	)
	(footprint ""
		(layer "B.Cu")
		(at 364.342934 -241.142266 -90)
		(property "Reference" "C387"
			(at 0 0 90)
			(layer "B.SilkS")
			(hide yes)
			(effects
				(font
					(size 1.27 1.27)
				)
				(justify mirror)
			)
		)
		(property "Value" ""
			(at 0 0 90)
			(layer "B.Fab")
			(effects
				(font
					(size 1.27 1.27)
				)
				(justify mirror)
			)
		)
		(duplicate_pad_numbers_are_jumpers no)
		(fp_line
			(start -1.524 0.762)
			(end 1.524 0.762)
			(stroke
				(width 0.1524)
				(type default)
			)
			(layer "B.SilkS")
		)
		(fp_line
			(start 1.524 0.762)
			(end 1.524 -0.762)
			(stroke
				(width 0.1524)
				(type default)
			)
			(layer "B.SilkS")
		)
		(fp_line
			(start -1.524 -0.762)
			(end -1.524 0.762)
			(stroke
				(width 0.1524)
				(type default)
			)
			(layer "B.SilkS")
		)
		(fp_line
			(start 1.524 -0.762)
			(end -1.524 -0.762)
			(stroke
				(width 0.1524)
				(type default)
			)
			(layer "B.SilkS")
		)
		(fp_line
			(start -1.1049 0.724916)
			(end -1.1049 -0.724916)
			(stroke
				(width 0.1)
				(type default)
			)
			(layer "B.Fab")
		)
		(fp_line
			(start 1.1049 0.724916)
			(end -1.1049 0.724916)
			(stroke
				(width 0.1)
				(type default)
			)
			(layer "B.Fab")
		)
		(fp_line
			(start -1.1049 -0.724916)
			(end 1.1049 -0.724916)
			(stroke
				(width 0.1)
				(type default)
			)
			(layer "B.Fab")
		)
		(fp_line
			(start 1.1049 -0.724916)
			(end 1.1049 0.724916)
			(stroke
				(width 0.1)
				(type default)
			)
			(layer "B.Fab")
		)
		(pad "1" smd rect
			(at 0.889 0 270)
			(size 1.016 1.27)
			(layers "B.Cu" "B.Mask" "B.Paste")
			(net "PVCCIN_CPU0")
		)
		(pad "2" smd rect
			(at -0.889 0 270)
			(size 1.016 1.27)
			(layers "B.Cu" "B.Mask" "B.Paste")
			(net "GND")
		)
	)
	(footprint ""
		(layer "B.Cu")
		(at 431.248058 -366.70869 180)
		(property "Reference" "PC1676"
			(at 0 0 0)
			(layer "B.SilkS")
			(hide yes)
			(effects
				(font
					(size 1.27 1.27)
				)
				(justify mirror)
			)
		)
		(property "Value" ""
			(at 0 0 0)
			(layer "B.Fab")
			(effects
				(font
					(size 1.27 1.27)
				)
				(justify mirror)
			)
		)
		(duplicate_pad_numbers_are_jumpers no)
		(fp_line
			(start 1.524 0.762)
			(end 1.524 -0.762)
			(stroke
				(width 0.1524)
				(type default)
			)
			(layer "B.SilkS")
		)
		(fp_line
			(start 1.524 -0.762)
			(end -1.524 -0.762)
			(stroke
				(width 0.1524)
				(type default)
			)
			(layer "B.SilkS")
		)
		(fp_line
			(start -1.524 0.762)
			(end 1.524 0.762)
			(stroke
				(width 0.1524)
				(type default)
			)
			(layer "B.SilkS")
		)
		(fp_line
			(start -1.524 -0.762)
			(end -1.524 0.762)
			(stroke
				(width 0.1524)
				(type default)
			)
			(layer "B.SilkS")
		)
		(fp_line
			(start 1.1049 0.724916)
			(end -1.1049 0.724916)
			(stroke
				(width 0.1)
				(type default)
			)
			(layer "B.Fab")
		)
		(fp_line
			(start 1.1049 -0.724916)
			(end 1.1049 0.724916)
			(stroke
				(width 0.1)
				(type default)
			)
			(layer "B.Fab")
		)
		(fp_line
			(start -1.1049 0.724916)
			(end -1.1049 -0.724916)
			(stroke
				(width 0.1)
				(type default)
			)
			(layer "B.Fab")
		)
		(fp_line
			(start -1.1049 -0.724916)
			(end 1.1049 -0.724916)
			(stroke
				(width 0.1)
				(type default)
			)
			(layer "B.Fab")
		)
		(pad "1" smd rect
			(at 0.889 0 180)
			(size 1.016 1.27)
			(layers "B.Cu" "B.Mask" "B.Paste")
			(net "SW_P12V_PVCCFA_EHV_FIVRA_CPU0_R")
		)
		(pad "2" smd rect
			(at -0.889 0 180)
			(size 1.016 1.27)
			(layers "B.Cu" "B.Mask" "B.Paste")
			(net "GND")
		)
	)
	(footprint ""
		(layer "B.Cu")
		(at 41.535858 -346.579952 -90)
		(property "Reference" "PC2172"
			(at 0 0 90)
			(layer "B.SilkS")
			(hide yes)
			(effects
				(font
					(size 1.27 1.27)
				)
				(justify mirror)
			)
		)
		(property "Value" ""
			(at 0 0 90)
			(layer "B.Fab")
			(effects
				(font
					(size 1.27 1.27)
				)
				(justify mirror)
			)
		)
		(duplicate_pad_numbers_are_jumpers no)
		(fp_line
			(start -4.533392 2.249932)
			(end 4.533392 2.249932)
			(stroke
				(width 0.1524)
				(type default)
			)
			(layer "B.SilkS")
		)
		(fp_line
			(start 4.533392 2.249932)
			(end 4.533392 -2.249932)
			(stroke
				(width 0.1524)
				(type default)
			)
			(layer "B.SilkS")
		)
		(fp_line
			(start -4.533392 -2.249932)
			(end -4.533392 2.249932)
			(stroke
				(width 0.1524)
				(type default)
			)
			(layer "B.SilkS")
		)
		(fp_line
			(start 4.533392 -2.249932)
			(end -4.533392 -2.249932)
			(stroke
				(width 0.1524)
				(type default)
			)
			(layer "B.SilkS")
		)
		(fp_poly
			(pts
				(xy 4.533392 -2.326132) (xy 5.39242 -2.326132) (xy 5.39242 2.326132) (xy 4.533392 2.326132)
			)
			(stroke
				(width 0)
				(type default)
			)
			(fill yes)
			(layer "B.SilkS")
		)
		(fp_line
			(start -3.750056 2.249932)
			(end 3.750056 2.249932)
			(stroke
				(width 0.1)
				(type default)
			)
			(layer "B.Fab")
		)
		(fp_line
			(start 3.750056 2.249932)
			(end 3.750056 -2.249932)
			(stroke
				(width 0.1)
				(type default)
			)
			(layer "B.Fab")
		)
		(fp_line
			(start -3.750056 -2.249932)
			(end -3.750056 2.249932)
			(stroke
				(width 0.1)
				(type default)
			)
			(layer "B.Fab")
		)
		(fp_line
			(start 3.750056 -2.249932)
			(end -3.750056 -2.249932)
			(stroke
				(width 0.1)
				(type default)
			)
			(layer "B.Fab")
		)
		(fp_text user "+"
			(at 6.322314 0.786384 180)
			(unlocked yes)
			(layer "B.SilkS")
			(effects
				(font
					(size 1.905 1.4224)
					(thickness 0.1524)
				)
				(justify left mirror)
			)
		)
		(fp_text user "-"
			(at -4.8514 -0.14605 270)
			(unlocked yes)
			(layer "B.SilkS")
			(effects
				(font
					(size 1.905 1.4224)
					(thickness 0.1524)
				)
				(justify left mirror)
			)
		)
		(fp_text user "+"
			(at 6.322314 0.786384 180)
			(unlocked yes)
			(layer "B.Fab")
			(effects
				(font
					(size 1.905 1.4224)
					(thickness 0.1524)
				)
				(justify left mirror)
			)
		)
		(fp_text user "-"
			(at -4.8514 -0.14605 270)
			(unlocked yes)
			(layer "B.Fab")
			(effects
				(font
					(size 1.905 1.4224)
					(thickness 0.1524)
				)
				(justify left mirror)
			)
		)
		(pad "1" smd rect
			(at 3.199892 0 90)
			(size 2.413 2.8194)
			(layers "B.Cu" "B.Mask" "B.Paste")
			(net "PVCCFA_EHV_FIVRA_CPU1")
		)
		(pad "2" smd rect
			(at -3.199892 0 90)
			(size 2.413 2.8194)
			(layers "B.Cu" "B.Mask" "B.Paste")
			(net "GND")
		)
	)
	(footprint ""
		(layer "B.Cu")
		(at 178.06035 -106.045 180)
		(property "Reference" "R164"
			(at 0 0 0)
			(layer "B.SilkS")
			(hide yes)
			(effects
				(font
					(size 1.27 1.27)
				)
				(justify mirror)
			)
		)
		(property "Value" ""
			(at 0 0 0)
			(layer "B.Fab")
			(effects
				(font
					(size 1.27 1.27)
				)
				(justify mirror)
			)
		)
		(duplicate_pad_numbers_are_jumpers no)
		(fp_line
			(start 0.7874 0.4064)
			(end 0.7874 -0.4064)
			(stroke
				(width 0.1524)
				(type default)
			)
			(layer "B.SilkS")
		)
		(fp_line
			(start 0.7874 -0.4064)
			(end -0.7874 -0.4064)
			(stroke
				(width 0.1524)
				(type default)
			)
			(layer "B.SilkS")
		)
		(fp_line
			(start -0.7874 0.4064)
			(end 0.7874 0.4064)
			(stroke
				(width 0.1524)
				(type default)
			)
			(layer "B.SilkS")
		)
		(fp_line
			(start -0.7874 -0.4064)
			(end -0.7874 0.4064)
			(stroke
				(width 0.1524)
				(type default)
			)
			(layer "B.SilkS")
		)
		(fp_line
			(start 0.67945 0.3048)
			(end 0.67945 -0.305054)
			(stroke
				(width 0.1)
				(type default)
			)
			(layer "B.Fab")
		)
		(fp_line
			(start 0.67945 -0.305054)
			(end 0.12065 -0.305054)
			(stroke
				(width 0.1)
				(type default)
			)
			(layer "B.Fab")
		)
		(fp_line
			(start 0.12065 0.3048)
			(end 0.67945 0.3048)
			(stroke
				(width 0.1)
				(type default)
			)
			(layer "B.Fab")
		)
		(fp_line
			(start 0.12065 0.2794)
			(end 0.12065 0.3048)
			(stroke
				(width 0.1)
				(type default)
			)
			(layer "B.Fab")
		)
		(fp_line
			(start 0.12065 -0.2794)
			(end -0.12065 -0.2794)
			(stroke
				(width 0.1)
				(type default)
			)
			(layer "B.Fab")
		)
		(fp_line
			(start 0.12065 -0.305054)
			(end 0.12065 -0.2794)
			(stroke
				(width 0.1)
				(type default)
			)
			(layer "B.Fab")
		)
		(fp_line
			(start -0.120396 0.3048)
			(end -0.120396 0.2794)
			(stroke
				(width 0.1)
				(type default)
			)
			(layer "B.Fab")
		)
		(fp_line
			(start -0.120396 0.2794)
			(end 0.12065 0.2794)
			(stroke
				(width 0.1)
				(type default)
			)
			(layer "B.Fab")
		)
		(fp_line
			(start -0.12065 -0.2794)
			(end -0.12065 -0.3048)
			(stroke
				(width 0.1)
				(type default)
			)
			(layer "B.Fab")
		)
		(fp_line
			(start -0.12065 -0.3048)
			(end -0.67945 -0.3048)
			(stroke
				(width 0.1)
				(type default)
			)
			(layer "B.Fab")
		)
		(fp_line
			(start -0.67945 0.3048)
			(end -0.120396 0.3048)
			(stroke
				(width 0.1)
				(type default)
			)
			(layer "B.Fab")
		)
		(fp_line
			(start -0.67945 -0.3048)
			(end -0.67945 0.3048)
			(stroke
				(width 0.1)
				(type default)
			)
			(layer "B.Fab")
		)
		(pad "1" smd circle
			(at 0.40005 0)
			(size 0 0)
			(layers "B.Cu" "B.Mask" "B.Paste")
			(net "PWRGD_DRAMPWRGD_CPU0_EF_R_LVC1")
		)
		(pad "2" smd circle
			(at -0.40005 0)
			(size 0 0)
			(layers "B.Cu" "B.Mask" "B.Paste")
			(net "PWRGD_DRAMPWRGD_CPU0_EF_LVC1_R2")
		)
	)
	(footprint ""
		(layer "B.Cu")
		(at 352.777298 -235.916724 180)
		(property "Reference" "C1"
			(at 0 0 0)
			(layer "B.SilkS")
			(hide yes)
			(effects
				(font
					(size 1.27 1.27)
				)
				(justify mirror)
			)
		)
		(property "Value" ""
			(at 0 0 0)
			(layer "B.Fab")
			(effects
				(font
					(size 1.27 1.27)
				)
				(justify mirror)
			)
		)
		(duplicate_pad_numbers_are_jumpers no)
		(fp_line
			(start 0.7874 0.4064)
			(end 0.7874 -0.4064)
			(stroke
				(width 0.1524)
				(type default)
			)
			(layer "B.SilkS")
		)
		(fp_line
			(start 0.7874 -0.4064)
			(end -0.7874 -0.4064)
			(stroke
				(width 0.1524)
				(type default)
			)
			(layer "B.SilkS")
		)
		(fp_line
			(start -0.7874 0.4064)
			(end 0.7874 0.4064)
			(stroke
				(width 0.1524)
				(type default)
			)
			(layer "B.SilkS")
		)
		(fp_line
			(start -0.7874 -0.4064)
			(end -0.7874 0.4064)
			(stroke
				(width 0.1524)
				(type default)
			)
			(layer "B.SilkS")
		)
		(fp_line
			(start 0.67945 0.3048)
			(end 0.67945 -0.305054)
			(stroke
				(width 0.1)
				(type default)
			)
			(layer "B.Fab")
		)
		(fp_line
			(start 0.67945 -0.305054)
			(end 0.12065 -0.305054)
			(stroke
				(width 0.1)
				(type default)
			)
			(layer "B.Fab")
		)
		(fp_line
			(start 0.12065 0.3048)
			(end 0.67945 0.3048)
			(stroke
				(width 0.1)
				(type default)
			)
			(layer "B.Fab")
		)
		(fp_line
			(start 0.12065 0.2794)
			(end 0.12065 0.3048)
			(stroke
				(width 0.1)
				(type default)
			)
			(layer "B.Fab")
		)
		(fp_line
			(start 0.12065 -0.2794)
			(end -0.12065 -0.2794)
			(stroke
				(width 0.1)
				(type default)
			)
			(layer "B.Fab")
		)
		(fp_line
			(start 0.12065 -0.305054)
			(end 0.12065 -0.2794)
			(stroke
				(width 0.1)
				(type default)
			)
			(layer "B.Fab")
		)
		(fp_line
			(start -0.120396 0.3048)
			(end -0.120396 0.2794)
			(stroke
				(width 0.1)
				(type default)
			)
			(layer "B.Fab")
		)
		(fp_line
			(start -0.120396 0.2794)
			(end 0.12065 0.2794)
			(stroke
				(width 0.1)
				(type default)
			)
			(layer "B.Fab")
		)
		(fp_line
			(start -0.12065 -0.2794)
			(end -0.12065 -0.3048)
			(stroke
				(width 0.1)
				(type default)
			)
			(layer "B.Fab")
		)
		(fp_line
			(start -0.12065 -0.3048)
			(end -0.67945 -0.3048)
			(stroke
				(width 0.1)
				(type default)
			)
			(layer "B.Fab")
		)
		(fp_line
			(start -0.67945 0.3048)
			(end -0.120396 0.3048)
			(stroke
				(width 0.1)
				(type default)
			)
			(layer "B.Fab")
		)
		(fp_line
			(start -0.67945 -0.3048)
			(end -0.67945 0.3048)
			(stroke
				(width 0.1)
				(type default)
			)
			(layer "B.Fab")
		)
		(pad "1" smd circle
			(at 0.40005 0)
			(size 0 0)
			(layers "B.Cu" "B.Mask" "B.Paste")
			(net "P3V3_AUX")
		)
		(pad "2" smd circle
			(at -0.40005 0)
			(size 0 0)
			(layers "B.Cu" "B.Mask" "B.Paste")
			(net "GND")
		)
	)
	(footprint ""
		(layer "B.Cu")
		(at 185.521346 -321.554856 -90)
		(property "Reference" "C89"
			(at 0 0 90)
			(layer "B.SilkS")
			(hide yes)
			(effects
				(font
					(size 1.27 1.27)
				)
				(justify mirror)
			)
		)
		(property "Value" ""
			(at 0 0 90)
			(layer "B.Fab")
			(effects
				(font
					(size 1.27 1.27)
				)
				(justify mirror)
			)
		)
		(duplicate_pad_numbers_are_jumpers no)
		(fp_line
			(start -1.524 0.762)
			(end 1.524 0.762)
			(stroke
				(width 0.1524)
				(type default)
			)
			(layer "B.SilkS")
		)
		(fp_line
			(start 1.524 0.762)
			(end 1.524 -0.762)
			(stroke
				(width 0.1524)
				(type default)
			)
			(layer "B.SilkS")
		)
		(fp_line
			(start -1.524 -0.762)
			(end -1.524 0.762)
			(stroke
				(width 0.1524)
				(type default)
			)
			(layer "B.SilkS")
		)
		(fp_line
			(start 1.524 -0.762)
			(end -1.524 -0.762)
			(stroke
				(width 0.1524)
				(type default)
			)
			(layer "B.SilkS")
		)
		(fp_line
			(start -1.1049 0.724916)
			(end -1.1049 -0.724916)
			(stroke
				(width 0.1)
				(type default)
			)
			(layer "B.Fab")
		)
		(fp_line
			(start 1.1049 0.724916)
			(end -1.1049 0.724916)
			(stroke
				(width 0.1)
				(type default)
			)
			(layer "B.Fab")
		)
		(fp_line
			(start -1.1049 -0.724916)
			(end 1.1049 -0.724916)
			(stroke
				(width 0.1)
				(type default)
			)
			(layer "B.Fab")
		)
		(fp_line
			(start 1.1049 -0.724916)
			(end 1.1049 0.724916)
			(stroke
				(width 0.1)
				(type default)
			)
			(layer "B.Fab")
		)
		(pad "1" smd rect
			(at 0.889 0 270)
			(size 1.016 1.27)
			(layers "B.Cu" "B.Mask" "B.Paste")
			(net "P12V_S3_AUX_CPU1_NVDIMM")
		)
		(pad "2" smd rect
			(at -0.889 0 270)
			(size 1.016 1.27)
			(layers "B.Cu" "B.Mask" "B.Paste")
			(net "GND")
		)
	)
	(footprint ""
		(layer "B.Cu")
		(at 335.099152 -31.394908 90)
		(property "Reference" "R499"
			(at 0 0 90)
			(layer "B.SilkS")
			(hide yes)
			(effects
				(font
					(size 1.27 1.27)
				)
				(justify mirror)
			)
		)
		(property "Value" ""
			(at 0 0 90)
			(layer "B.Fab")
			(effects
				(font
					(size 1.27 1.27)
				)
				(justify mirror)
			)
		)
		(duplicate_pad_numbers_are_jumpers no)
		(fp_line
			(start 0.7874 -0.4064)
			(end -0.7874 -0.4064)
			(stroke
				(width 0.1524)
				(type default)
			)
			(layer "B.SilkS")
		)
		(fp_line
			(start -0.7874 -0.4064)
			(end -0.7874 0.4064)
			(stroke
				(width 0.1524)
				(type default)
			)
			(layer "B.SilkS")
		)
		(fp_line
			(start 0.7874 0.4064)
			(end 0.7874 -0.4064)
			(stroke
				(width 0.1524)
				(type default)
			)
			(layer "B.SilkS")
		)
		(fp_line
			(start -0.7874 0.4064)
			(end 0.7874 0.4064)
			(stroke
				(width 0.1524)
				(type default)
			)
			(layer "B.SilkS")
		)
		(fp_line
			(start 0.67945 -0.305054)
			(end 0.12065 -0.305054)
			(stroke
				(width 0.1)
				(type default)
			)
			(layer "B.Fab")
		)
		(fp_line
			(start 0.12065 -0.305054)
			(end 0.12065 -0.2794)
			(stroke
				(width 0.1)
				(type default)
			)
			(layer "B.Fab")
		)
		(fp_line
			(start -0.12065 -0.3048)
			(end -0.67945 -0.3048)
			(stroke
				(width 0.1)
				(type default)
			)
			(layer "B.Fab")
		)
		(fp_line
			(start -0.67945 -0.3048)
			(end -0.67945 0.3048)
			(stroke
				(width 0.1)
				(type default)
			)
			(layer "B.Fab")
		)
		(fp_line
			(start 0.12065 -0.2794)
			(end -0.12065 -0.2794)
			(stroke
				(width 0.1)
				(type default)
			)
			(layer "B.Fab")
		)
		(fp_line
			(start -0.12065 -0.2794)
			(end -0.12065 -0.3048)
			(stroke
				(width 0.1)
				(type default)
			)
			(layer "B.Fab")
		)
		(fp_line
			(start 0.12065 0.2794)
			(end 0.12065 0.3048)
			(stroke
				(width 0.1)
				(type default)
			)
			(layer "B.Fab")
		)
		(fp_line
			(start -0.120396 0.2794)
			(end 0.12065 0.2794)
			(stroke
				(width 0.1)
				(type default)
			)
			(layer "B.Fab")
		)
		(fp_line
			(start 0.67945 0.3048)
			(end 0.67945 -0.305054)
			(stroke
				(width 0.1)
				(type default)
			)
			(layer "B.Fab")
		)
		(fp_line
			(start 0.12065 0.3048)
			(end 0.67945 0.3048)
			(stroke
				(width 0.1)
				(type default)
			)
			(layer "B.Fab")
		)
		(fp_line
			(start -0.120396 0.3048)
			(end -0.120396 0.2794)
			(stroke
				(width 0.1)
				(type default)
			)
			(layer "B.Fab")
		)
		(fp_line
			(start -0.67945 0.3048)
			(end -0.120396 0.3048)
			(stroke
				(width 0.1)
				(type default)
			)
			(layer "B.Fab")
		)
		(pad "1" smd circle
			(at 0.40005 0 270)
			(size 0 0)
			(layers "B.Cu" "B.Mask" "B.Paste")
			(net "SPI_PCH_CLK")
		)
		(pad "2" smd circle
			(at -0.40005 0 270)
			(size 0 0)
			(layers "B.Cu" "B.Mask" "B.Paste")
			(net "SPI_SYS_CLK")
		)
	)
	(footprint ""
		(layer "B.Cu")
		(at 355.91369 -324.911466 -90)
		(property "Reference" "PC313_P0_2"
			(at 0 0 90)
			(layer "B.SilkS")
			(hide yes)
			(effects
				(font
					(size 1.27 1.27)
				)
				(justify mirror)
			)
		)
		(property "Value" ""
			(at 0 0 90)
			(layer "B.Fab")
			(effects
				(font
					(size 1.27 1.27)
				)
				(justify mirror)
			)
		)
		(duplicate_pad_numbers_are_jumpers no)
		(fp_line
			(start -1.524 0.762)
			(end 1.524 0.762)
			(stroke
				(width 0.1524)
				(type default)
			)
			(layer "B.SilkS")
		)
		(fp_line
			(start 1.524 0.762)
			(end 1.524 -0.762)
			(stroke
				(width 0.1524)
				(type default)
			)
			(layer "B.SilkS")
		)
		(fp_line
			(start -1.524 -0.762)
			(end -1.524 0.762)
			(stroke
				(width 0.1524)
				(type default)
			)
			(layer "B.SilkS")
		)
		(fp_line
			(start 1.524 -0.762)
			(end -1.524 -0.762)
			(stroke
				(width 0.1524)
				(type default)
			)
			(layer "B.SilkS")
		)
		(fp_line
			(start -1.1049 0.724916)
			(end -1.1049 -0.724916)
			(stroke
				(width 0.1)
				(type default)
			)
			(layer "B.Fab")
		)
		(fp_line
			(start 1.1049 0.724916)
			(end -1.1049 0.724916)
			(stroke
				(width 0.1)
				(type default)
			)
			(layer "B.Fab")
		)
		(fp_line
			(start -1.1049 -0.724916)
			(end 1.1049 -0.724916)
			(stroke
				(width 0.1)
				(type default)
			)
			(layer "B.Fab")
		)
		(fp_line
			(start 1.1049 -0.724916)
			(end 1.1049 0.724916)
			(stroke
				(width 0.1)
				(type default)
			)
			(layer "B.Fab")
		)
		(pad "1" smd rect
			(at 0.889 0 270)
			(size 1.016 1.27)
			(layers "B.Cu" "B.Mask" "B.Paste")
			(net "PVCCIN_CPU0")
		)
		(pad "2" smd rect
			(at -0.889 0 270)
			(size 1.016 1.27)
			(layers "B.Cu" "B.Mask" "B.Paste")
			(net "GND")
		)
	)
	(footprint ""
		(layer "B.Cu")
		(at 161.29 -13.426948 90)
		(property "Reference" "R4507"
			(at 0 0 90)
			(layer "B.SilkS")
			(hide yes)
			(effects
				(font
					(size 1.27 1.27)
				)
				(justify mirror)
			)
		)
		(property "Value" ""
			(at 0 0 90)
			(layer "B.Fab")
			(effects
				(font
					(size 1.27 1.27)
				)
				(justify mirror)
			)
		)
		(duplicate_pad_numbers_are_jumpers no)
		(fp_line
			(start 0.7874 -0.4064)
			(end -0.7874 -0.4064)
			(stroke
				(width 0.1524)
				(type default)
			)
			(layer "B.SilkS")
		)
		(fp_line
			(start -0.7874 -0.4064)
			(end -0.7874 0.4064)
			(stroke
				(width 0.1524)
				(type default)
			)
			(layer "B.SilkS")
		)
		(fp_line
			(start 0.7874 0.4064)
			(end 0.7874 -0.4064)
			(stroke
				(width 0.1524)
				(type default)
			)
			(layer "B.SilkS")
		)
		(fp_line
			(start -0.7874 0.4064)
			(end 0.7874 0.4064)
			(stroke
				(width 0.1524)
				(type default)
			)
			(layer "B.SilkS")
		)
		(fp_line
			(start 0.67945 -0.305054)
			(end 0.12065 -0.305054)
			(stroke
				(width 0.1)
				(type default)
			)
			(layer "B.Fab")
		)
		(fp_line
			(start 0.12065 -0.305054)
			(end 0.12065 -0.2794)
			(stroke
				(width 0.1)
				(type default)
			)
			(layer "B.Fab")
		)
		(fp_line
			(start -0.12065 -0.3048)
			(end -0.67945 -0.3048)
			(stroke
				(width 0.1)
				(type default)
			)
			(layer "B.Fab")
		)
		(fp_line
			(start -0.67945 -0.3048)
			(end -0.67945 0.3048)
			(stroke
				(width 0.1)
				(type default)
			)
			(layer "B.Fab")
		)
		(fp_line
			(start 0.12065 -0.2794)
			(end -0.12065 -0.2794)
			(stroke
				(width 0.1)
				(type default)
			)
			(layer "B.Fab")
		)
		(fp_line
			(start -0.12065 -0.2794)
			(end -0.12065 -0.3048)
			(stroke
				(width 0.1)
				(type default)
			)
			(layer "B.Fab")
		)
		(fp_line
			(start 0.12065 0.2794)
			(end 0.12065 0.3048)
			(stroke
				(width 0.1)
				(type default)
			)
			(layer "B.Fab")
		)
		(fp_line
			(start -0.120396 0.2794)
			(end 0.12065 0.2794)
			(stroke
				(width 0.1)
				(type default)
			)
			(layer "B.Fab")
		)
		(fp_line
			(start 0.67945 0.3048)
			(end 0.67945 -0.305054)
			(stroke
				(width 0.1)
				(type default)
			)
			(layer "B.Fab")
		)
		(fp_line
			(start 0.12065 0.3048)
			(end 0.67945 0.3048)
			(stroke
				(width 0.1)
				(type default)
			)
			(layer "B.Fab")
		)
		(fp_line
			(start -0.120396 0.3048)
			(end -0.120396 0.2794)
			(stroke
				(width 0.1)
				(type default)
			)
			(layer "B.Fab")
		)
		(fp_line
			(start -0.67945 0.3048)
			(end -0.120396 0.3048)
			(stroke
				(width 0.1)
				(type default)
			)
			(layer "B.Fab")
		)
		(pad "1" smd circle
			(at 0.40005 0 270)
			(size 0 0)
			(layers "B.Cu" "B.Mask" "B.Paste")
			(net "SMB_SML0_3V3AUX_SDA")
		)
		(pad "2" smd circle
			(at -0.40005 0 270)
			(size 0 0)
			(layers "B.Cu" "B.Mask" "B.Paste")
			(net "SMB_SML0_3V3AUX_SDA_R1")
		)
	)
	(footprint ""
		(layer "B.Cu")
		(at 418.57549 -149.950424)
		(property "Reference" "PC179"
			(at 0 0 0)
			(layer "B.SilkS")
			(hide yes)
			(effects
				(font
					(size 1.27 1.27)
				)
				(justify mirror)
			)
		)
		(property "Value" ""
			(at 0 0 0)
			(layer "B.Fab")
			(effects
				(font
					(size 1.27 1.27)
				)
				(justify mirror)
			)
		)
		(duplicate_pad_numbers_are_jumpers no)
		(fp_line
			(start -1.524 -0.762)
			(end -1.524 0.762)
			(stroke
				(width 0.1524)
				(type default)
			)
			(layer "B.SilkS")
		)
		(fp_line
			(start -1.524 0.762)
			(end 1.524 0.762)
			(stroke
				(width 0.1524)
				(type default)
			)
			(layer "B.SilkS")
		)
		(fp_line
			(start 1.524 -0.762)
			(end -1.524 -0.762)
			(stroke
				(width 0.1524)
				(type default)
			)
			(layer "B.SilkS")
		)
		(fp_line
			(start 1.524 0.762)
			(end 1.524 -0.762)
			(stroke
				(width 0.1524)
				(type default)
			)
			(layer "B.SilkS")
		)
		(fp_line
			(start -1.1049 -0.724916)
			(end 1.1049 -0.724916)
			(stroke
				(width 0.1)
				(type default)
			)
			(layer "B.Fab")
		)
		(fp_line
			(start -1.1049 0.724916)
			(end -1.1049 -0.724916)
			(stroke
				(width 0.1)
				(type default)
			)
			(layer "B.Fab")
		)
		(fp_line
			(start 1.1049 -0.724916)
			(end 1.1049 0.724916)
			(stroke
				(width 0.1)
				(type default)
			)
			(layer "B.Fab")
		)
		(fp_line
			(start 1.1049 0.724916)
			(end -1.1049 0.724916)
			(stroke
				(width 0.1)
				(type default)
			)
			(layer "B.Fab")
		)
		(pad "1" smd rect
			(at 0.889 0)
			(size 1.016 1.27)
			(layers "B.Cu" "B.Mask" "B.Paste")
			(net "SW_P12V_PVCCINFAON_CPU0_FLT")
		)
		(pad "2" smd rect
			(at -0.889 0)
			(size 1.016 1.27)
			(layers "B.Cu" "B.Mask" "B.Paste")
			(net "GND")
		)
	)
	(footprint ""
		(layer "B.Cu")
		(at 36.956238 -130.80492)
		(property "Reference" "R2571"
			(at 0 0 0)
			(layer "B.SilkS")
			(hide yes)
			(effects
				(font
					(size 1.27 1.27)
				)
				(justify mirror)
			)
		)
		(property "Value" ""
			(at 0 0 0)
			(layer "B.Fab")
			(effects
				(font
					(size 1.27 1.27)
				)
				(justify mirror)
			)
		)
		(duplicate_pad_numbers_are_jumpers no)
		(fp_line
			(start -0.7874 -0.4064)
			(end -0.7874 0.4064)
			(stroke
				(width 0.1524)
				(type default)
			)
			(layer "B.SilkS")
		)
		(fp_line
			(start -0.7874 0.4064)
			(end 0.7874 0.4064)
			(stroke
				(width 0.1524)
				(type default)
			)
			(layer "B.SilkS")
		)
		(fp_line
			(start 0.7874 -0.4064)
			(end -0.7874 -0.4064)
			(stroke
				(width 0.1524)
				(type default)
			)
			(layer "B.SilkS")
		)
		(fp_line
			(start 0.7874 0.4064)
			(end 0.7874 -0.4064)
			(stroke
				(width 0.1524)
				(type default)
			)
			(layer "B.SilkS")
		)
		(fp_line
			(start -0.67945 -0.3048)
			(end -0.67945 0.3048)
			(stroke
				(width 0.1)
				(type default)
			)
			(layer "B.Fab")
		)
		(fp_line
			(start -0.67945 0.3048)
			(end -0.120396 0.3048)
			(stroke
				(width 0.1)
				(type default)
			)
			(layer "B.Fab")
		)
		(fp_line
			(start -0.12065 -0.3048)
			(end -0.67945 -0.3048)
			(stroke
				(width 0.1)
				(type default)
			)
			(layer "B.Fab")
		)
		(fp_line
			(start -0.12065 -0.2794)
			(end -0.12065 -0.3048)
			(stroke
				(width 0.1)
				(type default)
			)
			(layer "B.Fab")
		)
		(fp_line
			(start -0.120396 0.2794)
			(end 0.12065 0.2794)
			(stroke
				(width 0.1)
				(type default)
			)
			(layer "B.Fab")
		)
		(fp_line
			(start -0.120396 0.3048)
			(end -0.120396 0.2794)
			(stroke
				(width 0.1)
				(type default)
			)
			(layer "B.Fab")
		)
		(fp_line
			(start 0.12065 -0.305054)
			(end 0.12065 -0.2794)
			(stroke
				(width 0.1)
				(type default)
			)
			(layer "B.Fab")
		)
		(fp_line
			(start 0.12065 -0.2794)
			(end -0.12065 -0.2794)
			(stroke
				(width 0.1)
				(type default)
			)
			(layer "B.Fab")
		)
		(fp_line
			(start 0.12065 0.2794)
			(end 0.12065 0.3048)
			(stroke
				(width 0.1)
				(type default)
			)
			(layer "B.Fab")
		)
		(fp_line
			(start 0.12065 0.3048)
			(end 0.67945 0.3048)
			(stroke
				(width 0.1)
				(type default)
			)
			(layer "B.Fab")
		)
		(fp_line
			(start 0.67945 -0.305054)
			(end 0.12065 -0.305054)
			(stroke
				(width 0.1)
				(type default)
			)
			(layer "B.Fab")
		)
		(fp_line
			(start 0.67945 0.3048)
			(end 0.67945 -0.305054)
			(stroke
				(width 0.1)
				(type default)
			)
			(layer "B.Fab")
		)
		(pad "1" smd circle
			(at 0.40005 0 180)
			(size 0 0)
			(layers "B.Cu" "B.Mask" "B.Paste")
			(net "P3V3_AUX")
		)
		(pad "2" smd circle
			(at -0.40005 0 180)
			(size 0 0)
			(layers "B.Cu" "B.Mask" "B.Paste")
			(net "PWRGD_PVCCFA_EHV_CPU1_R")
		)
	)
	(footprint ""
		(layer "B.Cu")
		(at 178.05019 -107.07116 180)
		(property "Reference" "R1327"
			(at 0 0 0)
			(layer "B.SilkS")
			(hide yes)
			(effects
				(font
					(size 1.27 1.27)
				)
				(justify mirror)
			)
		)
		(property "Value" ""
			(at 0 0 0)
			(layer "B.Fab")
			(effects
				(font
					(size 1.27 1.27)
				)
				(justify mirror)
			)
		)
		(duplicate_pad_numbers_are_jumpers no)
		(fp_line
			(start 0.7874 0.4064)
			(end 0.7874 -0.4064)
			(stroke
				(width 0.1524)
				(type default)
			)
			(layer "B.SilkS")
		)
		(fp_line
			(start 0.7874 -0.4064)
			(end -0.7874 -0.4064)
			(stroke
				(width 0.1524)
				(type default)
			)
			(layer "B.SilkS")
		)
		(fp_line
			(start -0.7874 0.4064)
			(end 0.7874 0.4064)
			(stroke
				(width 0.1524)
				(type default)
			)
			(layer "B.SilkS")
		)
		(fp_line
			(start -0.7874 -0.4064)
			(end -0.7874 0.4064)
			(stroke
				(width 0.1524)
				(type default)
			)
			(layer "B.SilkS")
		)
		(fp_line
			(start 0.67945 0.3048)
			(end 0.67945 -0.305054)
			(stroke
				(width 0.1)
				(type default)
			)
			(layer "B.Fab")
		)
		(fp_line
			(start 0.67945 -0.305054)
			(end 0.12065 -0.305054)
			(stroke
				(width 0.1)
				(type default)
			)
			(layer "B.Fab")
		)
		(fp_line
			(start 0.12065 0.3048)
			(end 0.67945 0.3048)
			(stroke
				(width 0.1)
				(type default)
			)
			(layer "B.Fab")
		)
		(fp_line
			(start 0.12065 0.2794)
			(end 0.12065 0.3048)
			(stroke
				(width 0.1)
				(type default)
			)
			(layer "B.Fab")
		)
		(fp_line
			(start 0.12065 -0.2794)
			(end -0.12065 -0.2794)
			(stroke
				(width 0.1)
				(type default)
			)
			(layer "B.Fab")
		)
		(fp_line
			(start 0.12065 -0.305054)
			(end 0.12065 -0.2794)
			(stroke
				(width 0.1)
				(type default)
			)
			(layer "B.Fab")
		)
		(fp_line
			(start -0.120396 0.3048)
			(end -0.120396 0.2794)
			(stroke
				(width 0.1)
				(type default)
			)
			(layer "B.Fab")
		)
		(fp_line
			(start -0.120396 0.2794)
			(end 0.12065 0.2794)
			(stroke
				(width 0.1)
				(type default)
			)
			(layer "B.Fab")
		)
		(fp_line
			(start -0.12065 -0.2794)
			(end -0.12065 -0.3048)
			(stroke
				(width 0.1)
				(type default)
			)
			(layer "B.Fab")
		)
		(fp_line
			(start -0.12065 -0.3048)
			(end -0.67945 -0.3048)
			(stroke
				(width 0.1)
				(type default)
			)
			(layer "B.Fab")
		)
		(fp_line
			(start -0.67945 0.3048)
			(end -0.120396 0.3048)
			(stroke
				(width 0.1)
				(type default)
			)
			(layer "B.Fab")
		)
		(fp_line
			(start -0.67945 -0.3048)
			(end -0.67945 0.3048)
			(stroke
				(width 0.1)
				(type default)
			)
			(layer "B.Fab")
		)
		(pad "1" smd circle
			(at 0.40005 0)
			(size 0 0)
			(layers "B.Cu" "B.Mask" "B.Paste")
			(net "PWRGD_DRAMPWRGD_CPU0_EF_R_LVC1")
		)
		(pad "2" smd circle
			(at -0.40005 0)
			(size 0 0)
			(layers "B.Cu" "B.Mask" "B.Paste")
			(net "GND")
		)
	)
	(footprint ""
		(layer "B.Cu")
		(at 81.446624 -184.096152 -90)
		(property "Reference" "R196"
			(at 0 0 90)
			(layer "B.SilkS")
			(hide yes)
			(effects
				(font
					(size 1.27 1.27)
				)
				(justify mirror)
			)
		)
		(property "Value" ""
			(at 0 0 90)
			(layer "B.Fab")
			(effects
				(font
					(size 1.27 1.27)
				)
				(justify mirror)
			)
		)
		(duplicate_pad_numbers_are_jumpers no)
		(fp_line
			(start -0.7874 0.4064)
			(end 0.7874 0.4064)
			(stroke
				(width 0.1524)
				(type default)
			)
			(layer "B.SilkS")
		)
		(fp_line
			(start 0.7874 0.4064)
			(end 0.7874 -0.4064)
			(stroke
				(width 0.1524)
				(type default)
			)
			(layer "B.SilkS")
		)
		(fp_line
			(start -0.7874 -0.4064)
			(end -0.7874 0.4064)
			(stroke
				(width 0.1524)
				(type default)
			)
			(layer "B.SilkS")
		)
		(fp_line
			(start 0.7874 -0.4064)
			(end -0.7874 -0.4064)
			(stroke
				(width 0.1524)
				(type default)
			)
			(layer "B.SilkS")
		)
		(fp_line
			(start -0.67945 0.3048)
			(end -0.120396 0.3048)
			(stroke
				(width 0.1)
				(type default)
			)
			(layer "B.Fab")
		)
		(fp_line
			(start -0.120396 0.3048)
			(end -0.120396 0.2794)
			(stroke
				(width 0.1)
				(type default)
			)
			(layer "B.Fab")
		)
		(fp_line
			(start 0.12065 0.3048)
			(end 0.67945 0.3048)
			(stroke
				(width 0.1)
				(type default)
			)
			(layer "B.Fab")
		)
		(fp_line
			(start 0.67945 0.3048)
			(end 0.67945 -0.305054)
			(stroke
				(width 0.1)
				(type default)
			)
			(layer "B.Fab")
		)
		(fp_line
			(start -0.120396 0.2794)
			(end 0.12065 0.2794)
			(stroke
				(width 0.1)
				(type default)
			)
			(layer "B.Fab")
		)
		(fp_line
			(start 0.12065 0.2794)
			(end 0.12065 0.3048)
			(stroke
				(width 0.1)
				(type default)
			)
			(layer "B.Fab")
		)
		(fp_line
			(start -0.12065 -0.2794)
			(end -0.12065 -0.3048)
			(stroke
				(width 0.1)
				(type default)
			)
			(layer "B.Fab")
		)
		(fp_line
			(start 0.12065 -0.2794)
			(end -0.12065 -0.2794)
			(stroke
				(width 0.1)
				(type default)
			)
			(layer "B.Fab")
		)
		(fp_line
			(start -0.67945 -0.3048)
			(end -0.67945 0.3048)
			(stroke
				(width 0.1)
				(type default)
			)
			(layer "B.Fab")
		)
		(fp_line
			(start -0.12065 -0.3048)
			(end -0.67945 -0.3048)
			(stroke
				(width 0.1)
				(type default)
			)
			(layer "B.Fab")
		)
		(fp_line
			(start 0.12065 -0.305054)
			(end 0.12065 -0.2794)
			(stroke
				(width 0.1)
				(type default)
			)
			(layer "B.Fab")
		)
		(fp_line
			(start 0.67945 -0.305054)
			(end 0.12065 -0.305054)
			(stroke
				(width 0.1)
				(type default)
			)
			(layer "B.Fab")
		)
		(pad "1" smd circle
			(at 0.40005 0 90)
			(size 0 0)
			(layers "B.Cu" "B.Mask" "B.Paste")
			(net "H_CPU_NMI_LVC1_N")
		)
		(pad "2" smd circle
			(at -0.40005 0 90)
			(size 0 0)
			(layers "B.Cu" "B.Mask" "B.Paste")
			(net "H_CPU1_NMI_LVC1_N")
		)
	)
	(footprint ""
		(layer "B.Cu")
		(at 449.808092 -58.325512 -90)
		(property "Reference" "PC1599"
			(at 0 0 90)
			(layer "B.SilkS")
			(hide yes)
			(effects
				(font
					(size 1.27 1.27)
				)
				(justify mirror)
			)
		)
		(property "Value" ""
			(at 0 0 90)
			(layer "B.Fab")
			(effects
				(font
					(size 1.27 1.27)
				)
				(justify mirror)
			)
		)
		(duplicate_pad_numbers_are_jumpers no)
		(fp_line
			(start -1.524 0.762)
			(end 1.524 0.762)
			(stroke
				(width 0.1524)
				(type default)
			)
			(layer "B.SilkS")
		)
		(fp_line
			(start 1.524 0.762)
			(end 1.524 -0.762)
			(stroke
				(width 0.1524)
				(type default)
			)
			(layer "B.SilkS")
		)
		(fp_line
			(start -1.524 -0.762)
			(end -1.524 0.762)
			(stroke
				(width 0.1524)
				(type default)
			)
			(layer "B.SilkS")
		)
		(fp_line
			(start 1.524 -0.762)
			(end -1.524 -0.762)
			(stroke
				(width 0.1524)
				(type default)
			)
			(layer "B.SilkS")
		)
		(fp_line
			(start -1.1049 0.724916)
			(end -1.1049 -0.724916)
			(stroke
				(width 0.1)
				(type default)
			)
			(layer "B.Fab")
		)
		(fp_line
			(start 1.1049 0.724916)
			(end -1.1049 0.724916)
			(stroke
				(width 0.1)
				(type default)
			)
			(layer "B.Fab")
		)
		(fp_line
			(start -1.1049 -0.724916)
			(end 1.1049 -0.724916)
			(stroke
				(width 0.1)
				(type default)
			)
			(layer "B.Fab")
		)
		(fp_line
			(start 1.1049 -0.724916)
			(end 1.1049 0.724916)
			(stroke
				(width 0.1)
				(type default)
			)
			(layer "B.Fab")
		)
		(pad "1" smd rect
			(at 0.889 0 270)
			(size 1.016 1.27)
			(layers "B.Cu" "B.Mask" "B.Paste")
			(net "P3V3_AUX")
		)
		(pad "2" smd rect
			(at -0.889 0 270)
			(size 1.016 1.27)
			(layers "B.Cu" "B.Mask" "B.Paste")
			(net "GND")
		)
	)
	(footprint ""
		(layer "B.Cu")
		(at 177.977546 -321.554856 -90)
		(property "Reference" "C85"
			(at 0 0 90)
			(layer "B.SilkS")
			(hide yes)
			(effects
				(font
					(size 1.27 1.27)
				)
				(justify mirror)
			)
		)
		(property "Value" ""
			(at 0 0 90)
			(layer "B.Fab")
			(effects
				(font
					(size 1.27 1.27)
				)
				(justify mirror)
			)
		)
		(duplicate_pad_numbers_are_jumpers no)
		(fp_line
			(start -1.524 0.762)
			(end 1.524 0.762)
			(stroke
				(width 0.1524)
				(type default)
			)
			(layer "B.SilkS")
		)
		(fp_line
			(start 1.524 0.762)
			(end 1.524 -0.762)
			(stroke
				(width 0.1524)
				(type default)
			)
			(layer "B.SilkS")
		)
		(fp_line
			(start -1.524 -0.762)
			(end -1.524 0.762)
			(stroke
				(width 0.1524)
				(type default)
			)
			(layer "B.SilkS")
		)
		(fp_line
			(start 1.524 -0.762)
			(end -1.524 -0.762)
			(stroke
				(width 0.1524)
				(type default)
			)
			(layer "B.SilkS")
		)
		(fp_line
			(start -1.1049 0.724916)
			(end -1.1049 -0.724916)
			(stroke
				(width 0.1)
				(type default)
			)
			(layer "B.Fab")
		)
		(fp_line
			(start 1.1049 0.724916)
			(end -1.1049 0.724916)
			(stroke
				(width 0.1)
				(type default)
			)
			(layer "B.Fab")
		)
		(fp_line
			(start -1.1049 -0.724916)
			(end 1.1049 -0.724916)
			(stroke
				(width 0.1)
				(type default)
			)
			(layer "B.Fab")
		)
		(fp_line
			(start 1.1049 -0.724916)
			(end 1.1049 0.724916)
			(stroke
				(width 0.1)
				(type default)
			)
			(layer "B.Fab")
		)
		(pad "1" smd rect
			(at 0.889 0 270)
			(size 1.016 1.27)
			(layers "B.Cu" "B.Mask" "B.Paste")
			(net "P12V_S3_AUX_CPU1_NVDIMM")
		)
		(pad "2" smd rect
			(at -0.889 0 270)
			(size 1.016 1.27)
			(layers "B.Cu" "B.Mask" "B.Paste")
			(net "GND")
		)
	)
	(footprint ""
		(layer "B.Cu")
		(at 197.19036 -120.614948)
		(property "Reference" "R1541"
			(at 0 0 0)
			(layer "B.SilkS")
			(hide yes)
			(effects
				(font
					(size 1.27 1.27)
				)
				(justify mirror)
			)
		)
		(property "Value" ""
			(at 0 0 0)
			(layer "B.Fab")
			(effects
				(font
					(size 1.27 1.27)
				)
				(justify mirror)
			)
		)
		(duplicate_pad_numbers_are_jumpers no)
		(fp_line
			(start -0.7874 -0.4064)
			(end -0.7874 0.4064)
			(stroke
				(width 0.1524)
				(type default)
			)
			(layer "B.SilkS")
		)
		(fp_line
			(start -0.7874 0.4064)
			(end 0.7874 0.4064)
			(stroke
				(width 0.1524)
				(type default)
			)
			(layer "B.SilkS")
		)
		(fp_line
			(start 0.7874 -0.4064)
			(end -0.7874 -0.4064)
			(stroke
				(width 0.1524)
				(type default)
			)
			(layer "B.SilkS")
		)
		(fp_line
			(start 0.7874 0.4064)
			(end 0.7874 -0.4064)
			(stroke
				(width 0.1524)
				(type default)
			)
			(layer "B.SilkS")
		)
		(fp_line
			(start -0.67945 -0.3048)
			(end -0.67945 0.3048)
			(stroke
				(width 0.1)
				(type default)
			)
			(layer "B.Fab")
		)
		(fp_line
			(start -0.67945 0.3048)
			(end -0.120396 0.3048)
			(stroke
				(width 0.1)
				(type default)
			)
			(layer "B.Fab")
		)
		(fp_line
			(start -0.12065 -0.3048)
			(end -0.67945 -0.3048)
			(stroke
				(width 0.1)
				(type default)
			)
			(layer "B.Fab")
		)
		(fp_line
			(start -0.12065 -0.2794)
			(end -0.12065 -0.3048)
			(stroke
				(width 0.1)
				(type default)
			)
			(layer "B.Fab")
		)
		(fp_line
			(start -0.120396 0.2794)
			(end 0.12065 0.2794)
			(stroke
				(width 0.1)
				(type default)
			)
			(layer "B.Fab")
		)
		(fp_line
			(start -0.120396 0.3048)
			(end -0.120396 0.2794)
			(stroke
				(width 0.1)
				(type default)
			)
			(layer "B.Fab")
		)
		(fp_line
			(start 0.12065 -0.305054)
			(end 0.12065 -0.2794)
			(stroke
				(width 0.1)
				(type default)
			)
			(layer "B.Fab")
		)
		(fp_line
			(start 0.12065 -0.2794)
			(end -0.12065 -0.2794)
			(stroke
				(width 0.1)
				(type default)
			)
			(layer "B.Fab")
		)
		(fp_line
			(start 0.12065 0.2794)
			(end 0.12065 0.3048)
			(stroke
				(width 0.1)
				(type default)
			)
			(layer "B.Fab")
		)
		(fp_line
			(start 0.12065 0.3048)
			(end 0.67945 0.3048)
			(stroke
				(width 0.1)
				(type default)
			)
			(layer "B.Fab")
		)
		(fp_line
			(start 0.67945 -0.305054)
			(end 0.12065 -0.305054)
			(stroke
				(width 0.1)
				(type default)
			)
			(layer "B.Fab")
		)
		(fp_line
			(start 0.67945 0.3048)
			(end 0.67945 -0.305054)
			(stroke
				(width 0.1)
				(type default)
			)
			(layer "B.Fab")
		)
		(pad "1" smd circle
			(at 0.40005 0 180)
			(size 0 0)
			(layers "B.Cu" "B.Mask" "B.Paste")
			(net "GND")
		)
		(pad "2" smd circle
			(at -0.40005 0 180)
			(size 0 0)
			(layers "B.Cu" "B.Mask" "B.Paste")
			(net "RST_PLTRST_N")
		)
	)
	(footprint ""
		(layer "B.Cu")
		(at 277.868888 -317.857886 180)
		(property "Reference" "R3880"
			(at 0 0 0)
			(layer "B.SilkS")
			(hide yes)
			(effects
				(font
					(size 1.27 1.27)
				)
				(justify mirror)
			)
		)
		(property "Value" ""
			(at 0 0 0)
			(layer "B.Fab")
			(effects
				(font
					(size 1.27 1.27)
				)
				(justify mirror)
			)
		)
		(duplicate_pad_numbers_are_jumpers no)
		(fp_line
			(start 0.7874 0.4064)
			(end 0.7874 -0.4064)
			(stroke
				(width 0.1524)
				(type default)
			)
			(layer "B.SilkS")
		)
		(fp_line
			(start 0.7874 -0.4064)
			(end -0.7874 -0.4064)
			(stroke
				(width 0.1524)
				(type default)
			)
			(layer "B.SilkS")
		)
		(fp_line
			(start -0.7874 0.4064)
			(end 0.7874 0.4064)
			(stroke
				(width 0.1524)
				(type default)
			)
			(layer "B.SilkS")
		)
		(fp_line
			(start -0.7874 -0.4064)
			(end -0.7874 0.4064)
			(stroke
				(width 0.1524)
				(type default)
			)
			(layer "B.SilkS")
		)
		(fp_line
			(start 0.67945 0.3048)
			(end 0.67945 -0.305054)
			(stroke
				(width 0.1)
				(type default)
			)
			(layer "B.Fab")
		)
		(fp_line
			(start 0.67945 -0.305054)
			(end 0.12065 -0.305054)
			(stroke
				(width 0.1)
				(type default)
			)
			(layer "B.Fab")
		)
		(fp_line
			(start 0.12065 0.3048)
			(end 0.67945 0.3048)
			(stroke
				(width 0.1)
				(type default)
			)
			(layer "B.Fab")
		)
		(fp_line
			(start 0.12065 0.2794)
			(end 0.12065 0.3048)
			(stroke
				(width 0.1)
				(type default)
			)
			(layer "B.Fab")
		)
		(fp_line
			(start 0.12065 -0.2794)
			(end -0.12065 -0.2794)
			(stroke
				(width 0.1)
				(type default)
			)
			(layer "B.Fab")
		)
		(fp_line
			(start 0.12065 -0.305054)
			(end 0.12065 -0.2794)
			(stroke
				(width 0.1)
				(type default)
			)
			(layer "B.Fab")
		)
		(fp_line
			(start -0.120396 0.3048)
			(end -0.120396 0.2794)
			(stroke
				(width 0.1)
				(type default)
			)
			(layer "B.Fab")
		)
		(fp_line
			(start -0.120396 0.2794)
			(end 0.12065 0.2794)
			(stroke
				(width 0.1)
				(type default)
			)
			(layer "B.Fab")
		)
		(fp_line
			(start -0.12065 -0.2794)
			(end -0.12065 -0.3048)
			(stroke
				(width 0.1)
				(type default)
			)
			(layer "B.Fab")
		)
		(fp_line
			(start -0.12065 -0.3048)
			(end -0.67945 -0.3048)
			(stroke
				(width 0.1)
				(type default)
			)
			(layer "B.Fab")
		)
		(fp_line
			(start -0.67945 0.3048)
			(end -0.120396 0.3048)
			(stroke
				(width 0.1)
				(type default)
			)
			(layer "B.Fab")
		)
		(fp_line
			(start -0.67945 -0.3048)
			(end -0.67945 0.3048)
			(stroke
				(width 0.1)
				(type default)
			)
			(layer "B.Fab")
		)
		(pad "1" smd circle
			(at 0.40005 0)
			(size 0 0)
			(layers "B.Cu" "B.Mask" "B.Paste")
			(net "I3C_SPD_DDRABCD_CPU0_LVC1_SCL_5")
		)
		(pad "2" smd circle
			(at -0.40005 0)
			(size 0 0)
			(layers "B.Cu" "B.Mask" "B.Paste")
			(net "I3C_SPD_DDRABCD_CPU0_LVC1_SCL")
		)
	)
	(footprint ""
		(layer "B.Cu")
		(at 272.949416 -318.644016)
		(property "Reference" "R30"
			(at 0 0 0)
			(layer "B.SilkS")
			(hide yes)
			(effects
				(font
					(size 1.27 1.27)
				)
				(justify mirror)
			)
		)
		(property "Value" ""
			(at 0 0 0)
			(layer "B.Fab")
			(effects
				(font
					(size 1.27 1.27)
				)
				(justify mirror)
			)
		)
		(duplicate_pad_numbers_are_jumpers no)
		(fp_line
			(start -0.7874 -0.4064)
			(end -0.7874 0.4064)
			(stroke
				(width 0.1524)
				(type default)
			)
			(layer "B.SilkS")
		)
		(fp_line
			(start -0.7874 0.4064)
			(end 0.7874 0.4064)
			(stroke
				(width 0.1524)
				(type default)
			)
			(layer "B.SilkS")
		)
		(fp_line
			(start 0.7874 -0.4064)
			(end -0.7874 -0.4064)
			(stroke
				(width 0.1524)
				(type default)
			)
			(layer "B.SilkS")
		)
		(fp_line
			(start 0.7874 0.4064)
			(end 0.7874 -0.4064)
			(stroke
				(width 0.1524)
				(type default)
			)
			(layer "B.SilkS")
		)
		(fp_line
			(start -0.67945 -0.3048)
			(end -0.67945 0.3048)
			(stroke
				(width 0.1)
				(type default)
			)
			(layer "B.Fab")
		)
		(fp_line
			(start -0.67945 0.3048)
			(end -0.120396 0.3048)
			(stroke
				(width 0.1)
				(type default)
			)
			(layer "B.Fab")
		)
		(fp_line
			(start -0.12065 -0.3048)
			(end -0.67945 -0.3048)
			(stroke
				(width 0.1)
				(type default)
			)
			(layer "B.Fab")
		)
		(fp_line
			(start -0.12065 -0.2794)
			(end -0.12065 -0.3048)
			(stroke
				(width 0.1)
				(type default)
			)
			(layer "B.Fab")
		)
		(fp_line
			(start -0.120396 0.2794)
			(end 0.12065 0.2794)
			(stroke
				(width 0.1)
				(type default)
			)
			(layer "B.Fab")
		)
		(fp_line
			(start -0.120396 0.3048)
			(end -0.120396 0.2794)
			(stroke
				(width 0.1)
				(type default)
			)
			(layer "B.Fab")
		)
		(fp_line
			(start 0.12065 -0.305054)
			(end 0.12065 -0.2794)
			(stroke
				(width 0.1)
				(type default)
			)
			(layer "B.Fab")
		)
		(fp_line
			(start 0.12065 -0.2794)
			(end -0.12065 -0.2794)
			(stroke
				(width 0.1)
				(type default)
			)
			(layer "B.Fab")
		)
		(fp_line
			(start 0.12065 0.2794)
			(end 0.12065 0.3048)
			(stroke
				(width 0.1)
				(type default)
			)
			(layer "B.Fab")
		)
		(fp_line
			(start 0.12065 0.3048)
			(end 0.67945 0.3048)
			(stroke
				(width 0.1)
				(type default)
			)
			(layer "B.Fab")
		)
		(fp_line
			(start 0.67945 -0.305054)
			(end 0.12065 -0.305054)
			(stroke
				(width 0.1)
				(type default)
			)
			(layer "B.Fab")
		)
		(fp_line
			(start 0.67945 0.3048)
			(end 0.67945 -0.305054)
			(stroke
				(width 0.1)
				(type default)
			)
			(layer "B.Fab")
		)
		(pad "1" smd circle
			(at 0.40005 0 180)
			(size 0 0)
			(layers "B.Cu" "B.Mask" "B.Paste")
			(net "PD_CHC_CPU0_DIMM1_SAA")
		)
		(pad "2" smd circle
			(at -0.40005 0 180)
			(size 0 0)
			(layers "B.Cu" "B.Mask" "B.Paste")
			(net "GND")
		)
	)
	(footprint ""
		(layer "B.Cu")
		(at 345.992196 -333.639922 90)
		(property "Reference" "PC303_P0_1"
			(at 0 0 90)
			(layer "B.SilkS")
			(hide yes)
			(effects
				(font
					(size 1.27 1.27)
				)
				(justify mirror)
			)
		)
		(property "Value" ""
			(at 0 0 90)
			(layer "B.Fab")
			(effects
				(font
					(size 1.27 1.27)
				)
				(justify mirror)
			)
		)
		(duplicate_pad_numbers_are_jumpers no)
		(fp_line
			(start 1.524 -0.762)
			(end -1.524 -0.762)
			(stroke
				(width 0.1524)
				(type default)
			)
			(layer "B.SilkS")
		)
		(fp_line
			(start -1.524 -0.762)
			(end -1.524 0.762)
			(stroke
				(width 0.1524)
				(type default)
			)
			(layer "B.SilkS")
		)
		(fp_line
			(start 1.524 0.762)
			(end 1.524 -0.762)
			(stroke
				(width 0.1524)
				(type default)
			)
			(layer "B.SilkS")
		)
		(fp_line
			(start -1.524 0.762)
			(end 1.524 0.762)
			(stroke
				(width 0.1524)
				(type default)
			)
			(layer "B.SilkS")
		)
		(fp_line
			(start 1.1049 -0.724916)
			(end 1.1049 0.724916)
			(stroke
				(width 0.1)
				(type default)
			)
			(layer "B.Fab")
		)
		(fp_line
			(start -1.1049 -0.724916)
			(end 1.1049 -0.724916)
			(stroke
				(width 0.1)
				(type default)
			)
			(layer "B.Fab")
		)
		(fp_line
			(start 1.1049 0.724916)
			(end -1.1049 0.724916)
			(stroke
				(width 0.1)
				(type default)
			)
			(layer "B.Fab")
		)
		(fp_line
			(start -1.1049 0.724916)
			(end -1.1049 -0.724916)
			(stroke
				(width 0.1)
				(type default)
			)
			(layer "B.Fab")
		)
		(pad "1" smd rect
			(at 0.889 0 90)
			(size 1.016 1.27)
			(layers "B.Cu" "B.Mask" "B.Paste")
			(net "SW_P12V_PVCCIN_CPU0_FLT")
		)
		(pad "2" smd rect
			(at -0.889 0 90)
			(size 1.016 1.27)
			(layers "B.Cu" "B.Mask" "B.Paste")
			(net "GND")
		)
	)
	(footprint ""
		(layer "B.Cu")
		(at 77.776578 -343.927938 -90)
		(property "Reference" "PR288"
			(at 0 0 90)
			(layer "B.SilkS")
			(hide yes)
			(effects
				(font
					(size 1.27 1.27)
				)
				(justify mirror)
			)
		)
		(property "Value" ""
			(at 0 0 90)
			(layer "B.Fab")
			(effects
				(font
					(size 1.27 1.27)
				)
				(justify mirror)
			)
		)
		(duplicate_pad_numbers_are_jumpers no)
		(fp_line
			(start -0.7874 0.4064)
			(end 0.7874 0.4064)
			(stroke
				(width 0.1524)
				(type default)
			)
			(layer "B.SilkS")
		)
		(fp_line
			(start 0.7874 0.4064)
			(end 0.7874 -0.4064)
			(stroke
				(width 0.1524)
				(type default)
			)
			(layer "B.SilkS")
		)
		(fp_line
			(start -0.7874 -0.4064)
			(end -0.7874 0.4064)
			(stroke
				(width 0.1524)
				(type default)
			)
			(layer "B.SilkS")
		)
		(fp_line
			(start 0.7874 -0.4064)
			(end -0.7874 -0.4064)
			(stroke
				(width 0.1524)
				(type default)
			)
			(layer "B.SilkS")
		)
		(fp_line
			(start -0.67945 0.3048)
			(end -0.120396 0.3048)
			(stroke
				(width 0.1)
				(type default)
			)
			(layer "B.Fab")
		)
		(fp_line
			(start -0.120396 0.3048)
			(end -0.120396 0.2794)
			(stroke
				(width 0.1)
				(type default)
			)
			(layer "B.Fab")
		)
		(fp_line
			(start 0.12065 0.3048)
			(end 0.67945 0.3048)
			(stroke
				(width 0.1)
				(type default)
			)
			(layer "B.Fab")
		)
		(fp_line
			(start 0.67945 0.3048)
			(end 0.67945 -0.305054)
			(stroke
				(width 0.1)
				(type default)
			)
			(layer "B.Fab")
		)
		(fp_line
			(start -0.120396 0.2794)
			(end 0.12065 0.2794)
			(stroke
				(width 0.1)
				(type default)
			)
			(layer "B.Fab")
		)
		(fp_line
			(start 0.12065 0.2794)
			(end 0.12065 0.3048)
			(stroke
				(width 0.1)
				(type default)
			)
			(layer "B.Fab")
		)
		(fp_line
			(start -0.12065 -0.2794)
			(end -0.12065 -0.3048)
			(stroke
				(width 0.1)
				(type default)
			)
			(layer "B.Fab")
		)
		(fp_line
			(start 0.12065 -0.2794)
			(end -0.12065 -0.2794)
			(stroke
				(width 0.1)
				(type default)
			)
			(layer "B.Fab")
		)
		(fp_line
			(start -0.67945 -0.3048)
			(end -0.67945 0.3048)
			(stroke
				(width 0.1)
				(type default)
			)
			(layer "B.Fab")
		)
		(fp_line
			(start -0.12065 -0.3048)
			(end -0.67945 -0.3048)
			(stroke
				(width 0.1)
				(type default)
			)
			(layer "B.Fab")
		)
		(fp_line
			(start 0.12065 -0.305054)
			(end 0.12065 -0.2794)
			(stroke
				(width 0.1)
				(type default)
			)
			(layer "B.Fab")
		)
		(fp_line
			(start 0.67945 -0.305054)
			(end 0.12065 -0.305054)
			(stroke
				(width 0.1)
				(type default)
			)
			(layer "B.Fab")
		)
		(pad "1" smd circle
			(at 0.40005 0 90)
			(size 0 0)
			(layers "B.Cu" "B.Mask" "B.Paste")
			(net "PVCCIN_CPU1_PVCC")
		)
		(pad "2" smd circle
			(at -0.40005 0 90)
			(size 0 0)
			(layers "B.Cu" "B.Mask" "B.Paste")
			(net "PVCCIN_CPU1_VDD7")
		)
	)
	(footprint ""
		(layer "B.Cu")
		(at 107.887008 -210.194144 180)
		(property "Reference" "C468"
			(at 0 0 0)
			(layer "B.SilkS")
			(hide yes)
			(effects
				(font
					(size 1.27 1.27)
				)
				(justify mirror)
			)
		)
		(property "Value" ""
			(at 0 0 0)
			(layer "B.Fab")
			(effects
				(font
					(size 1.27 1.27)
				)
				(justify mirror)
			)
		)
		(duplicate_pad_numbers_are_jumpers no)
		(fp_line
			(start 1.524 0.762)
			(end 1.524 -0.762)
			(stroke
				(width 0.1524)
				(type default)
			)
			(layer "B.SilkS")
		)
		(fp_line
			(start 1.524 -0.762)
			(end -1.524 -0.762)
			(stroke
				(width 0.1524)
				(type default)
			)
			(layer "B.SilkS")
		)
		(fp_line
			(start -1.524 0.762)
			(end 1.524 0.762)
			(stroke
				(width 0.1524)
				(type default)
			)
			(layer "B.SilkS")
		)
		(fp_line
			(start -1.524 -0.762)
			(end -1.524 0.762)
			(stroke
				(width 0.1524)
				(type default)
			)
			(layer "B.SilkS")
		)
		(fp_line
			(start 1.1049 0.724916)
			(end -1.1049 0.724916)
			(stroke
				(width 0.1)
				(type default)
			)
			(layer "B.Fab")
		)
		(fp_line
			(start 1.1049 -0.724916)
			(end 1.1049 0.724916)
			(stroke
				(width 0.1)
				(type default)
			)
			(layer "B.Fab")
		)
		(fp_line
			(start -1.1049 0.724916)
			(end -1.1049 -0.724916)
			(stroke
				(width 0.1)
				(type default)
			)
			(layer "B.Fab")
		)
		(fp_line
			(start -1.1049 -0.724916)
			(end 1.1049 -0.724916)
			(stroke
				(width 0.1)
				(type default)
			)
			(layer "B.Fab")
		)
		(pad "1" smd rect
			(at 0.889 0 180)
			(size 1.016 1.27)
			(layers "B.Cu" "B.Mask" "B.Paste")
			(net "PVCCFA_EHV_CPU1")
		)
		(pad "2" smd rect
			(at -0.889 0 180)
			(size 1.016 1.27)
			(layers "B.Cu" "B.Mask" "B.Paste")
			(net "GND")
		)
	)
	(footprint ""
		(layer "B.Cu")
		(at 19.760946 -321.554856 -90)
		(property "Reference" "C97"
			(at 0 0 90)
			(layer "B.SilkS")
			(hide yes)
			(effects
				(font
					(size 1.27 1.27)
				)
				(justify mirror)
			)
		)
		(property "Value" ""
			(at 0 0 90)
			(layer "B.Fab")
			(effects
				(font
					(size 1.27 1.27)
				)
				(justify mirror)
			)
		)
		(duplicate_pad_numbers_are_jumpers no)
		(fp_line
			(start -1.524 0.762)
			(end 1.524 0.762)
			(stroke
				(width 0.1524)
				(type default)
			)
			(layer "B.SilkS")
		)
		(fp_line
			(start 1.524 0.762)
			(end 1.524 -0.762)
			(stroke
				(width 0.1524)
				(type default)
			)
			(layer "B.SilkS")
		)
		(fp_line
			(start -1.524 -0.762)
			(end -1.524 0.762)
			(stroke
				(width 0.1524)
				(type default)
			)
			(layer "B.SilkS")
		)
		(fp_line
			(start 1.524 -0.762)
			(end -1.524 -0.762)
			(stroke
				(width 0.1524)
				(type default)
			)
			(layer "B.SilkS")
		)
		(fp_line
			(start -1.1049 0.724916)
			(end -1.1049 -0.724916)
			(stroke
				(width 0.1)
				(type default)
			)
			(layer "B.Fab")
		)
		(fp_line
			(start 1.1049 0.724916)
			(end -1.1049 0.724916)
			(stroke
				(width 0.1)
				(type default)
			)
			(layer "B.Fab")
		)
		(fp_line
			(start -1.1049 -0.724916)
			(end 1.1049 -0.724916)
			(stroke
				(width 0.1)
				(type default)
			)
			(layer "B.Fab")
		)
		(fp_line
			(start 1.1049 -0.724916)
			(end 1.1049 0.724916)
			(stroke
				(width 0.1)
				(type default)
			)
			(layer "B.Fab")
		)
		(pad "1" smd rect
			(at 0.889 0 270)
			(size 1.016 1.27)
			(layers "B.Cu" "B.Mask" "B.Paste")
			(net "P12V_S3_AUX_CPU1_NVDIMM")
		)
		(pad "2" smd rect
			(at -0.889 0 270)
			(size 1.016 1.27)
			(layers "B.Cu" "B.Mask" "B.Paste")
			(net "GND")
		)
	)
	(footprint ""
		(layer "B.Cu")
		(at 422.939718 -363.098588 -90)
		(property "Reference" "PR1299"
			(at 0 0 90)
			(layer "B.SilkS")
			(hide yes)
			(effects
				(font
					(size 1.27 1.27)
				)
				(justify mirror)
			)
		)
		(property "Value" ""
			(at 0 0 90)
			(layer "B.Fab")
			(effects
				(font
					(size 1.27 1.27)
				)
				(justify mirror)
			)
		)
		(duplicate_pad_numbers_are_jumpers no)
		(fp_line
			(start -0.7874 0.4064)
			(end 0.7874 0.4064)
			(stroke
				(width 0.1524)
				(type default)
			)
			(layer "B.SilkS")
		)
		(fp_line
			(start 0.7874 0.4064)
			(end 0.7874 -0.4064)
			(stroke
				(width 0.1524)
				(type default)
			)
			(layer "B.SilkS")
		)
		(fp_line
			(start -0.7874 -0.4064)
			(end -0.7874 0.4064)
			(stroke
				(width 0.1524)
				(type default)
			)
			(layer "B.SilkS")
		)
		(fp_line
			(start 0.7874 -0.4064)
			(end -0.7874 -0.4064)
			(stroke
				(width 0.1524)
				(type default)
			)
			(layer "B.SilkS")
		)
		(fp_line
			(start -0.67945 0.3048)
			(end -0.120396 0.3048)
			(stroke
				(width 0.1)
				(type default)
			)
			(layer "B.Fab")
		)
		(fp_line
			(start -0.120396 0.3048)
			(end -0.120396 0.2794)
			(stroke
				(width 0.1)
				(type default)
			)
			(layer "B.Fab")
		)
		(fp_line
			(start 0.12065 0.3048)
			(end 0.67945 0.3048)
			(stroke
				(width 0.1)
				(type default)
			)
			(layer "B.Fab")
		)
		(fp_line
			(start 0.67945 0.3048)
			(end 0.67945 -0.305054)
			(stroke
				(width 0.1)
				(type default)
			)
			(layer "B.Fab")
		)
		(fp_line
			(start -0.120396 0.2794)
			(end 0.12065 0.2794)
			(stroke
				(width 0.1)
				(type default)
			)
			(layer "B.Fab")
		)
		(fp_line
			(start 0.12065 0.2794)
			(end 0.12065 0.3048)
			(stroke
				(width 0.1)
				(type default)
			)
			(layer "B.Fab")
		)
		(fp_line
			(start -0.12065 -0.2794)
			(end -0.12065 -0.3048)
			(stroke
				(width 0.1)
				(type default)
			)
			(layer "B.Fab")
		)
		(fp_line
			(start 0.12065 -0.2794)
			(end -0.12065 -0.2794)
			(stroke
				(width 0.1)
				(type default)
			)
			(layer "B.Fab")
		)
		(fp_line
			(start -0.67945 -0.3048)
			(end -0.67945 0.3048)
			(stroke
				(width 0.1)
				(type default)
			)
			(layer "B.Fab")
		)
		(fp_line
			(start -0.12065 -0.3048)
			(end -0.67945 -0.3048)
			(stroke
				(width 0.1)
				(type default)
			)
			(layer "B.Fab")
		)
		(fp_line
			(start 0.12065 -0.305054)
			(end 0.12065 -0.2794)
			(stroke
				(width 0.1)
				(type default)
			)
			(layer "B.Fab")
		)
		(fp_line
			(start 0.67945 -0.305054)
			(end 0.12065 -0.305054)
			(stroke
				(width 0.1)
				(type default)
			)
			(layer "B.Fab")
		)
		(pad "1" smd circle
			(at 0.40005 0 90)
			(size 0 0)
			(layers "B.Cu" "B.Mask" "B.Paste")
			(net "PVCCFA_EHV_FIVRA_CPU0_PVCC1")
		)
		(pad "2" smd circle
			(at -0.40005 0 90)
			(size 0 0)
			(layers "B.Cu" "B.Mask" "B.Paste")
			(net "PVCCFA_EHV_FIVRA_CPU0_VDD3")
		)
	)
	(footprint ""
		(layer "B.Cu")
		(at 178.9557 -112.57534 90)
		(property "Reference" "C1928"
			(at 0 0 90)
			(layer "B.SilkS")
			(hide yes)
			(effects
				(font
					(size 1.27 1.27)
				)
				(justify mirror)
			)
		)
		(property "Value" ""
			(at 0 0 90)
			(layer "B.Fab")
			(effects
				(font
					(size 1.27 1.27)
				)
				(justify mirror)
			)
		)
		(duplicate_pad_numbers_are_jumpers no)
		(fp_line
			(start 0.69215 -0.2921)
			(end -0.69215 -0.2921)
			(stroke
				(width 0.1524)
				(type default)
			)
			(layer "B.SilkS")
		)
		(fp_line
			(start -0.69215 -0.2921)
			(end -0.69215 0.2921)
			(stroke
				(width 0.1524)
				(type default)
			)
			(layer "B.SilkS")
		)
		(fp_line
			(start 0.69215 0.2921)
			(end 0.69215 -0.2921)
			(stroke
				(width 0.1524)
				(type default)
			)
			(layer "B.SilkS")
		)
		(fp_line
			(start -0.69215 0.2921)
			(end 0.69215 0.2921)
			(stroke
				(width 0.1524)
				(type default)
			)
			(layer "B.SilkS")
		)
		(fp_line
			(start 0.51435 -0.2794)
			(end -0.51435 -0.2794)
			(stroke
				(width 0.1)
				(type default)
			)
			(layer "B.Fab")
		)
		(fp_line
			(start -0.51435 -0.2794)
			(end -0.51435 0.2794)
			(stroke
				(width 0.1)
				(type default)
			)
			(layer "B.Fab")
		)
		(fp_line
			(start 0.51435 0.2794)
			(end 0.51435 -0.2794)
			(stroke
				(width 0.1)
				(type default)
			)
			(layer "B.Fab")
		)
		(fp_line
			(start -0.51435 0.2794)
			(end 0.51435 0.2794)
			(stroke
				(width 0.1)
				(type default)
			)
			(layer "B.Fab")
		)
		(pad "1" smd circle
			(at 0.40005 0 270)
			(size 0 0)
			(layers "B.Cu" "B.Mask" "B.Paste")
			(net "VCC_PLD_CORE")
		)
		(pad "2" smd circle
			(at -0.40005 0 270)
			(size 0 0)
			(layers "B.Cu" "B.Mask" "B.Paste")
			(net "GND")
		)
		(zone
			(layer "B.Cu")
			(hatch none 0.5)
			(connect_pads
				(clearance 0)
			)
			(min_thickness 0.25)
			(keepout
				(tracks not_allowed)
				(vias allowed)
				(pads allowed)
				(copperpour not_allowed)
				(footprints allowed)
			)
			(placement
				(enabled no)
				(sheetname "")
			)
			(fill
				(thermal_gap 0.5)
				(thermal_bridge_width 0.5)
				(island_removal_mode 0)
			)
			(polygon
				(pts
					(xy 179.04333 -112.76584) (xy 179.101496 -112.6744) (xy 179.101496 -112.47501) (xy 179.04333 -112.38484)
					(xy 178.86807 -112.38484) (xy 178.80965 -112.47501) (xy 178.80965 -112.6744) (xy 178.867816 -112.76584)
				)
			)
		)
	)
	(footprint ""
		(layer "B.Cu")
		(at 183.995568 -407.863802 -90)
		(property "Reference" "PR3927"
			(at 0 0 90)
			(layer "B.SilkS")
			(hide yes)
			(effects
				(font
					(size 1.27 1.27)
				)
				(justify mirror)
			)
		)
		(property "Value" ""
			(at 0 0 90)
			(layer "B.Fab")
			(effects
				(font
					(size 1.27 1.27)
				)
				(justify mirror)
			)
		)
		(duplicate_pad_numbers_are_jumpers no)
		(fp_line
			(start -0.7874 0.4064)
			(end 0.7874 0.4064)
			(stroke
				(width 0.1524)
				(type default)
			)
			(layer "B.SilkS")
		)
		(fp_line
			(start 0.7874 0.4064)
			(end 0.7874 -0.4064)
			(stroke
				(width 0.1524)
				(type default)
			)
			(layer "B.SilkS")
		)
		(fp_line
			(start -0.7874 -0.4064)
			(end -0.7874 0.4064)
			(stroke
				(width 0.1524)
				(type default)
			)
			(layer "B.SilkS")
		)
		(fp_line
			(start 0.7874 -0.4064)
			(end -0.7874 -0.4064)
			(stroke
				(width 0.1524)
				(type default)
			)
			(layer "B.SilkS")
		)
		(fp_line
			(start -0.67945 0.3048)
			(end -0.120396 0.3048)
			(stroke
				(width 0.1)
				(type default)
			)
			(layer "B.Fab")
		)
		(fp_line
			(start -0.120396 0.3048)
			(end -0.120396 0.2794)
			(stroke
				(width 0.1)
				(type default)
			)
			(layer "B.Fab")
		)
		(fp_line
			(start 0.12065 0.3048)
			(end 0.67945 0.3048)
			(stroke
				(width 0.1)
				(type default)
			)
			(layer "B.Fab")
		)
		(fp_line
			(start 0.67945 0.3048)
			(end 0.67945 -0.305054)
			(stroke
				(width 0.1)
				(type default)
			)
			(layer "B.Fab")
		)
		(fp_line
			(start -0.120396 0.2794)
			(end 0.12065 0.2794)
			(stroke
				(width 0.1)
				(type default)
			)
			(layer "B.Fab")
		)
		(fp_line
			(start 0.12065 0.2794)
			(end 0.12065 0.3048)
			(stroke
				(width 0.1)
				(type default)
			)
			(layer "B.Fab")
		)
		(fp_line
			(start -0.12065 -0.2794)
			(end -0.12065 -0.3048)
			(stroke
				(width 0.1)
				(type default)
			)
			(layer "B.Fab")
		)
		(fp_line
			(start 0.12065 -0.2794)
			(end -0.12065 -0.2794)
			(stroke
				(width 0.1)
				(type default)
			)
			(layer "B.Fab")
		)
		(fp_line
			(start -0.67945 -0.3048)
			(end -0.67945 0.3048)
			(stroke
				(width 0.1)
				(type default)
			)
			(layer "B.Fab")
		)
		(fp_line
			(start -0.12065 -0.3048)
			(end -0.67945 -0.3048)
			(stroke
				(width 0.1)
				(type default)
			)
			(layer "B.Fab")
		)
		(fp_line
			(start 0.12065 -0.305054)
			(end 0.12065 -0.2794)
			(stroke
				(width 0.1)
				(type default)
			)
			(layer "B.Fab")
		)
		(fp_line
			(start 0.67945 -0.305054)
			(end 0.12065 -0.305054)
			(stroke
				(width 0.1)
				(type default)
			)
			(layer "B.Fab")
		)
		(pad "1" smd circle
			(at 0.40005 0 90)
			(size 0 0)
			(layers "B.Cu" "B.Mask" "B.Paste")
			(net "HSC_VSENSE")
		)
		(pad "2" smd circle
			(at -0.40005 0 90)
			(size 0 0)
			(layers "B.Cu" "B.Mask" "B.Paste")
			(net "AGND_HSC")
		)
	)
	(footprint ""
		(layer "B.Cu")
		(at 409.30957 -149.65299 180)
		(property "Reference" "PC186"
			(at 0 0 0)
			(layer "B.SilkS")
			(hide yes)
			(effects
				(font
					(size 1.27 1.27)
				)
				(justify mirror)
			)
		)
		(property "Value" ""
			(at 0 0 0)
			(layer "B.Fab")
			(effects
				(font
					(size 1.27 1.27)
				)
				(justify mirror)
			)
		)
		(duplicate_pad_numbers_are_jumpers no)
		(fp_line
			(start 1.524 0.762)
			(end 1.524 -0.762)
			(stroke
				(width 0.1524)
				(type default)
			)
			(layer "B.SilkS")
		)
		(fp_line
			(start 1.524 -0.762)
			(end -1.524 -0.762)
			(stroke
				(width 0.1524)
				(type default)
			)
			(layer "B.SilkS")
		)
		(fp_line
			(start -1.524 0.762)
			(end 1.524 0.762)
			(stroke
				(width 0.1524)
				(type default)
			)
			(layer "B.SilkS")
		)
		(fp_line
			(start -1.524 -0.762)
			(end -1.524 0.762)
			(stroke
				(width 0.1524)
				(type default)
			)
			(layer "B.SilkS")
		)
		(fp_line
			(start 1.1049 0.724916)
			(end -1.1049 0.724916)
			(stroke
				(width 0.1)
				(type default)
			)
			(layer "B.Fab")
		)
		(fp_line
			(start 1.1049 -0.724916)
			(end 1.1049 0.724916)
			(stroke
				(width 0.1)
				(type default)
			)
			(layer "B.Fab")
		)
		(fp_line
			(start -1.1049 0.724916)
			(end -1.1049 -0.724916)
			(stroke
				(width 0.1)
				(type default)
			)
			(layer "B.Fab")
		)
		(fp_line
			(start -1.1049 -0.724916)
			(end 1.1049 -0.724916)
			(stroke
				(width 0.1)
				(type default)
			)
			(layer "B.Fab")
		)
		(pad "1" smd rect
			(at 0.889 0 180)
			(size 1.016 1.27)
			(layers "B.Cu" "B.Mask" "B.Paste")
			(net "PVCCFA_EHV_CPU0")
		)
		(pad "2" smd rect
			(at -0.889 0 180)
			(size 1.016 1.27)
			(layers "B.Cu" "B.Mask" "B.Paste")
			(net "GND")
		)
	)
	(footprint ""
		(layer "B.Cu")
		(at 96.241108 -190.705232 -90)
		(property "Reference" "R3024"
			(at 0 0 90)
			(layer "B.SilkS")
			(hide yes)
			(effects
				(font
					(size 1.27 1.27)
				)
				(justify mirror)
			)
		)
		(property "Value" ""
			(at 0 0 90)
			(layer "B.Fab")
			(effects
				(font
					(size 1.27 1.27)
				)
				(justify mirror)
			)
		)
		(duplicate_pad_numbers_are_jumpers no)
		(fp_line
			(start -0.7874 0.4064)
			(end 0.7874 0.4064)
			(stroke
				(width 0.1524)
				(type default)
			)
			(layer "B.SilkS")
		)
		(fp_line
			(start 0.7874 0.4064)
			(end 0.7874 -0.4064)
			(stroke
				(width 0.1524)
				(type default)
			)
			(layer "B.SilkS")
		)
		(fp_line
			(start -0.7874 -0.4064)
			(end -0.7874 0.4064)
			(stroke
				(width 0.1524)
				(type default)
			)
			(layer "B.SilkS")
		)
		(fp_line
			(start 0.7874 -0.4064)
			(end -0.7874 -0.4064)
			(stroke
				(width 0.1524)
				(type default)
			)
			(layer "B.SilkS")
		)
		(fp_line
			(start -0.67945 0.3048)
			(end -0.120396 0.3048)
			(stroke
				(width 0.1)
				(type default)
			)
			(layer "B.Fab")
		)
		(fp_line
			(start -0.120396 0.3048)
			(end -0.120396 0.2794)
			(stroke
				(width 0.1)
				(type default)
			)
			(layer "B.Fab")
		)
		(fp_line
			(start 0.12065 0.3048)
			(end 0.67945 0.3048)
			(stroke
				(width 0.1)
				(type default)
			)
			(layer "B.Fab")
		)
		(fp_line
			(start 0.67945 0.3048)
			(end 0.67945 -0.305054)
			(stroke
				(width 0.1)
				(type default)
			)
			(layer "B.Fab")
		)
		(fp_line
			(start -0.120396 0.2794)
			(end 0.12065 0.2794)
			(stroke
				(width 0.1)
				(type default)
			)
			(layer "B.Fab")
		)
		(fp_line
			(start 0.12065 0.2794)
			(end 0.12065 0.3048)
			(stroke
				(width 0.1)
				(type default)
			)
			(layer "B.Fab")
		)
		(fp_line
			(start -0.12065 -0.2794)
			(end -0.12065 -0.3048)
			(stroke
				(width 0.1)
				(type default)
			)
			(layer "B.Fab")
		)
		(fp_line
			(start 0.12065 -0.2794)
			(end -0.12065 -0.2794)
			(stroke
				(width 0.1)
				(type default)
			)
			(layer "B.Fab")
		)
		(fp_line
			(start -0.67945 -0.3048)
			(end -0.67945 0.3048)
			(stroke
				(width 0.1)
				(type default)
			)
			(layer "B.Fab")
		)
		(fp_line
			(start -0.12065 -0.3048)
			(end -0.67945 -0.3048)
			(stroke
				(width 0.1)
				(type default)
			)
			(layer "B.Fab")
		)
		(fp_line
			(start 0.12065 -0.305054)
			(end 0.12065 -0.2794)
			(stroke
				(width 0.1)
				(type default)
			)
			(layer "B.Fab")
		)
		(fp_line
			(start 0.67945 -0.305054)
			(end 0.12065 -0.305054)
			(stroke
				(width 0.1)
				(type default)
			)
			(layer "B.Fab")
		)
		(pad "1" smd circle
			(at 0.40005 0 90)
			(size 0 0)
			(layers "B.Cu" "B.Mask" "B.Paste")
			(net "GND")
		)
		(pad "2" smd circle
			(at -0.40005 0 90)
			(size 0 0)
			(layers "B.Cu" "B.Mask" "B.Paste")
			(net "PD_EXT_CLK_SEL_CPU1")
		)
	)
	(footprint ""
		(layer "B.Cu")
		(at 61.690758 -179.02555)
		(property "Reference" "PR4250"
			(at 0 0 0)
			(layer "B.SilkS")
			(hide yes)
			(effects
				(font
					(size 1.27 1.27)
				)
				(justify mirror)
			)
		)
		(property "Value" ""
			(at 0 0 0)
			(layer "B.Fab")
			(effects
				(font
					(size 1.27 1.27)
				)
				(justify mirror)
			)
		)
		(duplicate_pad_numbers_are_jumpers no)
		(fp_line
			(start -0.7874 -0.4064)
			(end -0.7874 0.4064)
			(stroke
				(width 0.1524)
				(type default)
			)
			(layer "B.SilkS")
		)
		(fp_line
			(start -0.7874 0.4064)
			(end 0.7874 0.4064)
			(stroke
				(width 0.1524)
				(type default)
			)
			(layer "B.SilkS")
		)
		(fp_line
			(start 0.7874 -0.4064)
			(end -0.7874 -0.4064)
			(stroke
				(width 0.1524)
				(type default)
			)
			(layer "B.SilkS")
		)
		(fp_line
			(start 0.7874 0.4064)
			(end 0.7874 -0.4064)
			(stroke
				(width 0.1524)
				(type default)
			)
			(layer "B.SilkS")
		)
		(fp_line
			(start -0.67945 -0.3048)
			(end -0.67945 0.3048)
			(stroke
				(width 0.1)
				(type default)
			)
			(layer "B.Fab")
		)
		(fp_line
			(start -0.67945 0.3048)
			(end -0.120396 0.3048)
			(stroke
				(width 0.1)
				(type default)
			)
			(layer "B.Fab")
		)
		(fp_line
			(start -0.12065 -0.3048)
			(end -0.67945 -0.3048)
			(stroke
				(width 0.1)
				(type default)
			)
			(layer "B.Fab")
		)
		(fp_line
			(start -0.12065 -0.2794)
			(end -0.12065 -0.3048)
			(stroke
				(width 0.1)
				(type default)
			)
			(layer "B.Fab")
		)
		(fp_line
			(start -0.120396 0.2794)
			(end 0.12065 0.2794)
			(stroke
				(width 0.1)
				(type default)
			)
			(layer "B.Fab")
		)
		(fp_line
			(start -0.120396 0.3048)
			(end -0.120396 0.2794)
			(stroke
				(width 0.1)
				(type default)
			)
			(layer "B.Fab")
		)
		(fp_line
			(start 0.12065 -0.305054)
			(end 0.12065 -0.2794)
			(stroke
				(width 0.1)
				(type default)
			)
			(layer "B.Fab")
		)
		(fp_line
			(start 0.12065 -0.2794)
			(end -0.12065 -0.2794)
			(stroke
				(width 0.1)
				(type default)
			)
			(layer "B.Fab")
		)
		(fp_line
			(start 0.12065 0.2794)
			(end 0.12065 0.3048)
			(stroke
				(width 0.1)
				(type default)
			)
			(layer "B.Fab")
		)
		(fp_line
			(start 0.12065 0.3048)
			(end 0.67945 0.3048)
			(stroke
				(width 0.1)
				(type default)
			)
			(layer "B.Fab")
		)
		(fp_line
			(start 0.67945 -0.305054)
			(end 0.12065 -0.305054)
			(stroke
				(width 0.1)
				(type default)
			)
			(layer "B.Fab")
		)
		(fp_line
			(start 0.67945 0.3048)
			(end 0.67945 -0.305054)
			(stroke
				(width 0.1)
				(type default)
			)
			(layer "B.Fab")
		)
		(pad "1" smd circle
			(at 0.40005 0 180)
			(size 0 0)
			(layers "B.Cu" "B.Mask" "B.Paste")
			(net "PVCCFA_EHV_CPU1")
		)
		(pad "2" smd circle
			(at -0.40005 0 180)
			(size 0 0)
			(layers "B.Cu" "B.Mask" "B.Paste")
			(net "GND")
		)
	)
	(footprint ""
		(layer "B.Cu")
		(at 317.90259 -30.507178 180)
		(property "Reference" "R3038"
			(at 0 0 0)
			(layer "B.SilkS")
			(hide yes)
			(effects
				(font
					(size 1.27 1.27)
				)
				(justify mirror)
			)
		)
		(property "Value" ""
			(at 0 0 0)
			(layer "B.Fab")
			(effects
				(font
					(size 1.27 1.27)
				)
				(justify mirror)
			)
		)
		(duplicate_pad_numbers_are_jumpers no)
		(fp_line
			(start 0.7874 0.4064)
			(end 0.7874 -0.4064)
			(stroke
				(width 0.1524)
				(type default)
			)
			(layer "B.SilkS")
		)
		(fp_line
			(start 0.7874 -0.4064)
			(end -0.7874 -0.4064)
			(stroke
				(width 0.1524)
				(type default)
			)
			(layer "B.SilkS")
		)
		(fp_line
			(start -0.7874 0.4064)
			(end 0.7874 0.4064)
			(stroke
				(width 0.1524)
				(type default)
			)
			(layer "B.SilkS")
		)
		(fp_line
			(start -0.7874 -0.4064)
			(end -0.7874 0.4064)
			(stroke
				(width 0.1524)
				(type default)
			)
			(layer "B.SilkS")
		)
		(fp_line
			(start 0.67945 0.3048)
			(end 0.67945 -0.305054)
			(stroke
				(width 0.1)
				(type default)
			)
			(layer "B.Fab")
		)
		(fp_line
			(start 0.67945 -0.305054)
			(end 0.12065 -0.305054)
			(stroke
				(width 0.1)
				(type default)
			)
			(layer "B.Fab")
		)
		(fp_line
			(start 0.12065 0.3048)
			(end 0.67945 0.3048)
			(stroke
				(width 0.1)
				(type default)
			)
			(layer "B.Fab")
		)
		(fp_line
			(start 0.12065 0.2794)
			(end 0.12065 0.3048)
			(stroke
				(width 0.1)
				(type default)
			)
			(layer "B.Fab")
		)
		(fp_line
			(start 0.12065 -0.2794)
			(end -0.12065 -0.2794)
			(stroke
				(width 0.1)
				(type default)
			)
			(layer "B.Fab")
		)
		(fp_line
			(start 0.12065 -0.305054)
			(end 0.12065 -0.2794)
			(stroke
				(width 0.1)
				(type default)
			)
			(layer "B.Fab")
		)
		(fp_line
			(start -0.120396 0.3048)
			(end -0.120396 0.2794)
			(stroke
				(width 0.1)
				(type default)
			)
			(layer "B.Fab")
		)
		(fp_line
			(start -0.120396 0.2794)
			(end 0.12065 0.2794)
			(stroke
				(width 0.1)
				(type default)
			)
			(layer "B.Fab")
		)
		(fp_line
			(start -0.12065 -0.2794)
			(end -0.12065 -0.3048)
			(stroke
				(width 0.1)
				(type default)
			)
			(layer "B.Fab")
		)
		(fp_line
			(start -0.12065 -0.3048)
			(end -0.67945 -0.3048)
			(stroke
				(width 0.1)
				(type default)
			)
			(layer "B.Fab")
		)
		(fp_line
			(start -0.67945 0.3048)
			(end -0.120396 0.3048)
			(stroke
				(width 0.1)
				(type default)
			)
			(layer "B.Fab")
		)
		(fp_line
			(start -0.67945 -0.3048)
			(end -0.67945 0.3048)
			(stroke
				(width 0.1)
				(type default)
			)
			(layer "B.Fab")
		)
		(pad "1" smd circle
			(at 0.40005 0)
			(size 0 0)
			(layers "B.Cu" "B.Mask" "B.Paste")
			(net "P3V3_AUX")
		)
		(pad "2" smd circle
			(at -0.40005 0)
			(size 0 0)
			(layers "B.Cu" "B.Mask" "B.Paste")
			(net "FM_PCH_SPARE0")
		)
	)
	(footprint ""
		(layer "B.Cu")
		(at 176.555654 -115.775486 90)
		(property "Reference" "C1933"
			(at 0 0 90)
			(layer "B.SilkS")
			(hide yes)
			(effects
				(font
					(size 1.27 1.27)
				)
				(justify mirror)
			)
		)
		(property "Value" ""
			(at 0 0 90)
			(layer "B.Fab")
			(effects
				(font
					(size 1.27 1.27)
				)
				(justify mirror)
			)
		)
		(duplicate_pad_numbers_are_jumpers no)
		(fp_line
			(start 0.69215 -0.2921)
			(end -0.69215 -0.2921)
			(stroke
				(width 0.1524)
				(type default)
			)
			(layer "B.SilkS")
		)
		(fp_line
			(start -0.69215 -0.2921)
			(end -0.69215 0.2921)
			(stroke
				(width 0.1524)
				(type default)
			)
			(layer "B.SilkS")
		)
		(fp_line
			(start 0.69215 0.2921)
			(end 0.69215 -0.2921)
			(stroke
				(width 0.1524)
				(type default)
			)
			(layer "B.SilkS")
		)
		(fp_line
			(start -0.69215 0.2921)
			(end 0.69215 0.2921)
			(stroke
				(width 0.1524)
				(type default)
			)
			(layer "B.SilkS")
		)
		(fp_line
			(start 0.51435 -0.2794)
			(end -0.51435 -0.2794)
			(stroke
				(width 0.1)
				(type default)
			)
			(layer "B.Fab")
		)
		(fp_line
			(start -0.51435 -0.2794)
			(end -0.51435 0.2794)
			(stroke
				(width 0.1)
				(type default)
			)
			(layer "B.Fab")
		)
		(fp_line
			(start 0.51435 0.2794)
			(end 0.51435 -0.2794)
			(stroke
				(width 0.1)
				(type default)
			)
			(layer "B.Fab")
		)
		(fp_line
			(start -0.51435 0.2794)
			(end 0.51435 0.2794)
			(stroke
				(width 0.1)
				(type default)
			)
			(layer "B.Fab")
		)
		(pad "1" smd circle
			(at 0.40005 0 270)
			(size 0 0)
			(layers "B.Cu" "B.Mask" "B.Paste")
			(net "P3V3_AUX_FPGA_VCCIO1")
		)
		(pad "2" smd circle
			(at -0.40005 0 270)
			(size 0 0)
			(layers "B.Cu" "B.Mask" "B.Paste")
			(net "GND")
		)
		(zone
			(layer "B.Cu")
			(hatch none 0.5)
			(connect_pads
				(clearance 0)
			)
			(min_thickness 0.25)
			(keepout
				(tracks not_allowed)
				(vias allowed)
				(pads allowed)
				(copperpour not_allowed)
				(footprints allowed)
			)
			(placement
				(enabled no)
				(sheetname "")
			)
			(fill
				(thermal_gap 0.5)
				(thermal_bridge_width 0.5)
				(island_removal_mode 0)
			)
			(polygon
				(pts
					(xy 176.643284 -115.965986) (xy 176.70145 -115.874546) (xy 176.70145 -115.675156) (xy 176.643284 -115.584986)
					(xy 176.468024 -115.584986) (xy 176.409604 -115.675156) (xy 176.409604 -115.874546) (xy 176.46777 -115.965986)
				)
			)
		)
	)
	(footprint ""
		(layer "B.Cu")
		(at 193.38036 -118.074948 180)
		(property "Reference" "R1419"
			(at 0 0 0)
			(layer "B.SilkS")
			(hide yes)
			(effects
				(font
					(size 1.27 1.27)
				)
				(justify mirror)
			)
		)
		(property "Value" ""
			(at 0 0 0)
			(layer "B.Fab")
			(effects
				(font
					(size 1.27 1.27)
				)
				(justify mirror)
			)
		)
		(duplicate_pad_numbers_are_jumpers no)
		(fp_line
			(start 0.7874 0.4064)
			(end 0.7874 -0.4064)
			(stroke
				(width 0.1524)
				(type default)
			)
			(layer "B.SilkS")
		)
		(fp_line
			(start 0.7874 -0.4064)
			(end -0.7874 -0.4064)
			(stroke
				(width 0.1524)
				(type default)
			)
			(layer "B.SilkS")
		)
		(fp_line
			(start -0.7874 0.4064)
			(end 0.7874 0.4064)
			(stroke
				(width 0.1524)
				(type default)
			)
			(layer "B.SilkS")
		)
		(fp_line
			(start -0.7874 -0.4064)
			(end -0.7874 0.4064)
			(stroke
				(width 0.1524)
				(type default)
			)
			(layer "B.SilkS")
		)
		(fp_line
			(start 0.67945 0.3048)
			(end 0.67945 -0.305054)
			(stroke
				(width 0.1)
				(type default)
			)
			(layer "B.Fab")
		)
		(fp_line
			(start 0.67945 -0.305054)
			(end 0.12065 -0.305054)
			(stroke
				(width 0.1)
				(type default)
			)
			(layer "B.Fab")
		)
		(fp_line
			(start 0.12065 0.3048)
			(end 0.67945 0.3048)
			(stroke
				(width 0.1)
				(type default)
			)
			(layer "B.Fab")
		)
		(fp_line
			(start 0.12065 0.2794)
			(end 0.12065 0.3048)
			(stroke
				(width 0.1)
				(type default)
			)
			(layer "B.Fab")
		)
		(fp_line
			(start 0.12065 -0.2794)
			(end -0.12065 -0.2794)
			(stroke
				(width 0.1)
				(type default)
			)
			(layer "B.Fab")
		)
		(fp_line
			(start 0.12065 -0.305054)
			(end 0.12065 -0.2794)
			(stroke
				(width 0.1)
				(type default)
			)
			(layer "B.Fab")
		)
		(fp_line
			(start -0.120396 0.3048)
			(end -0.120396 0.2794)
			(stroke
				(width 0.1)
				(type default)
			)
			(layer "B.Fab")
		)
		(fp_line
			(start -0.120396 0.2794)
			(end 0.12065 0.2794)
			(stroke
				(width 0.1)
				(type default)
			)
			(layer "B.Fab")
		)
		(fp_line
			(start -0.12065 -0.2794)
			(end -0.12065 -0.3048)
			(stroke
				(width 0.1)
				(type default)
			)
			(layer "B.Fab")
		)
		(fp_line
			(start -0.12065 -0.3048)
			(end -0.67945 -0.3048)
			(stroke
				(width 0.1)
				(type default)
			)
			(layer "B.Fab")
		)
		(fp_line
			(start -0.67945 0.3048)
			(end -0.120396 0.3048)
			(stroke
				(width 0.1)
				(type default)
			)
			(layer "B.Fab")
		)
		(fp_line
			(start -0.67945 -0.3048)
			(end -0.67945 0.3048)
			(stroke
				(width 0.1)
				(type default)
			)
			(layer "B.Fab")
		)
		(pad "1" smd circle
			(at 0.40005 0)
			(size 0 0)
			(layers "B.Cu" "B.Mask" "B.Paste")
			(net "RST_PCIE_PCH_DEV_PERST_N")
		)
		(pad "2" smd circle
			(at -0.40005 0)
			(size 0 0)
			(layers "B.Cu" "B.Mask" "B.Paste")
			(net "GND")
		)
	)
	(footprint ""
		(layer "B.Cu")
		(at 208.152746 -321.554856 -90)
		(property "Reference" "C73"
			(at 0 0 90)
			(layer "B.SilkS")
			(hide yes)
			(effects
				(font
					(size 1.27 1.27)
				)
				(justify mirror)
			)
		)
		(property "Value" ""
			(at 0 0 90)
			(layer "B.Fab")
			(effects
				(font
					(size 1.27 1.27)
				)
				(justify mirror)
			)
		)
		(duplicate_pad_numbers_are_jumpers no)
		(fp_line
			(start -1.524 0.762)
			(end 1.524 0.762)
			(stroke
				(width 0.1524)
				(type default)
			)
			(layer "B.SilkS")
		)
		(fp_line
			(start 1.524 0.762)
			(end 1.524 -0.762)
			(stroke
				(width 0.1524)
				(type default)
			)
			(layer "B.SilkS")
		)
		(fp_line
			(start -1.524 -0.762)
			(end -1.524 0.762)
			(stroke
				(width 0.1524)
				(type default)
			)
			(layer "B.SilkS")
		)
		(fp_line
			(start 1.524 -0.762)
			(end -1.524 -0.762)
			(stroke
				(width 0.1524)
				(type default)
			)
			(layer "B.SilkS")
		)
		(fp_line
			(start -1.1049 0.724916)
			(end -1.1049 -0.724916)
			(stroke
				(width 0.1)
				(type default)
			)
			(layer "B.Fab")
		)
		(fp_line
			(start 1.1049 0.724916)
			(end -1.1049 0.724916)
			(stroke
				(width 0.1)
				(type default)
			)
			(layer "B.Fab")
		)
		(fp_line
			(start -1.1049 -0.724916)
			(end 1.1049 -0.724916)
			(stroke
				(width 0.1)
				(type default)
			)
			(layer "B.Fab")
		)
		(fp_line
			(start 1.1049 -0.724916)
			(end 1.1049 0.724916)
			(stroke
				(width 0.1)
				(type default)
			)
			(layer "B.Fab")
		)
		(pad "1" smd rect
			(at 0.889 0 270)
			(size 1.016 1.27)
			(layers "B.Cu" "B.Mask" "B.Paste")
			(net "P12V_S3_AUX_CPU1_NVDIMM")
		)
		(pad "2" smd rect
			(at -0.889 0 270)
			(size 1.016 1.27)
			(layers "B.Cu" "B.Mask" "B.Paste")
			(net "GND")
		)
	)
	(footprint ""
		(layer "B.Cu")
		(at 196.23278 -316.868048 90)
		(property "Reference" "R3903"
			(at 0 0 90)
			(layer "B.SilkS")
			(hide yes)
			(effects
				(font
					(size 1.27 1.27)
				)
				(justify mirror)
			)
		)
		(property "Value" ""
			(at 0 0 90)
			(layer "B.Fab")
			(effects
				(font
					(size 1.27 1.27)
				)
				(justify mirror)
			)
		)
		(duplicate_pad_numbers_are_jumpers no)
		(fp_line
			(start 0.7874 -0.4064)
			(end -0.7874 -0.4064)
			(stroke
				(width 0.1524)
				(type default)
			)
			(layer "B.SilkS")
		)
		(fp_line
			(start -0.7874 -0.4064)
			(end -0.7874 0.4064)
			(stroke
				(width 0.1524)
				(type default)
			)
			(layer "B.SilkS")
		)
		(fp_line
			(start 0.7874 0.4064)
			(end 0.7874 -0.4064)
			(stroke
				(width 0.1524)
				(type default)
			)
			(layer "B.SilkS")
		)
		(fp_line
			(start -0.7874 0.4064)
			(end 0.7874 0.4064)
			(stroke
				(width 0.1524)
				(type default)
			)
			(layer "B.SilkS")
		)
		(fp_line
			(start 0.67945 -0.305054)
			(end 0.12065 -0.305054)
			(stroke
				(width 0.1)
				(type default)
			)
			(layer "B.Fab")
		)
		(fp_line
			(start 0.12065 -0.305054)
			(end 0.12065 -0.2794)
			(stroke
				(width 0.1)
				(type default)
			)
			(layer "B.Fab")
		)
		(fp_line
			(start -0.12065 -0.3048)
			(end -0.67945 -0.3048)
			(stroke
				(width 0.1)
				(type default)
			)
			(layer "B.Fab")
		)
		(fp_line
			(start -0.67945 -0.3048)
			(end -0.67945 0.3048)
			(stroke
				(width 0.1)
				(type default)
			)
			(layer "B.Fab")
		)
		(fp_line
			(start 0.12065 -0.2794)
			(end -0.12065 -0.2794)
			(stroke
				(width 0.1)
				(type default)
			)
			(layer "B.Fab")
		)
		(fp_line
			(start -0.12065 -0.2794)
			(end -0.12065 -0.3048)
			(stroke
				(width 0.1)
				(type default)
			)
			(layer "B.Fab")
		)
		(fp_line
			(start 0.12065 0.2794)
			(end 0.12065 0.3048)
			(stroke
				(width 0.1)
				(type default)
			)
			(layer "B.Fab")
		)
		(fp_line
			(start -0.120396 0.2794)
			(end 0.12065 0.2794)
			(stroke
				(width 0.1)
				(type default)
			)
			(layer "B.Fab")
		)
		(fp_line
			(start 0.67945 0.3048)
			(end 0.67945 -0.305054)
			(stroke
				(width 0.1)
				(type default)
			)
			(layer "B.Fab")
		)
		(fp_line
			(start 0.12065 0.3048)
			(end 0.67945 0.3048)
			(stroke
				(width 0.1)
				(type default)
			)
			(layer "B.Fab")
		)
		(fp_line
			(start -0.120396 0.3048)
			(end -0.120396 0.2794)
			(stroke
				(width 0.1)
				(type default)
			)
			(layer "B.Fab")
		)
		(fp_line
			(start -0.67945 0.3048)
			(end -0.120396 0.3048)
			(stroke
				(width 0.1)
				(type default)
			)
			(layer "B.Fab")
		)
		(pad "1" smd circle
			(at 0.40005 0 270)
			(size 0 0)
			(layers "B.Cu" "B.Mask" "B.Paste")
			(net "I3C_SPD_DDREFGH_CPU1_LVC1_SCL_4")
		)
		(pad "2" smd circle
			(at -0.40005 0 270)
			(size 0 0)
			(layers "B.Cu" "B.Mask" "B.Paste")
			(net "I3C_SPD_DDREFGH_CPU1_LVC1_SCL")
		)
	)
	(footprint ""
		(layer "B.Cu")
		(at 182.908448 -407.856182 90)
		(property "Reference" "R3909"
			(at 0 0 90)
			(layer "B.SilkS")
			(hide yes)
			(effects
				(font
					(size 1.27 1.27)
				)
				(justify mirror)
			)
		)
		(property "Value" ""
			(at 0 0 90)
			(layer "B.Fab")
			(effects
				(font
					(size 1.27 1.27)
				)
				(justify mirror)
			)
		)
		(duplicate_pad_numbers_are_jumpers no)
		(fp_line
			(start 0.7874 -0.4064)
			(end -0.7874 -0.4064)
			(stroke
				(width 0.1524)
				(type default)
			)
			(layer "B.SilkS")
		)
		(fp_line
			(start -0.7874 -0.4064)
			(end -0.7874 0.4064)
			(stroke
				(width 0.1524)
				(type default)
			)
			(layer "B.SilkS")
		)
		(fp_line
			(start 0.7874 0.4064)
			(end 0.7874 -0.4064)
			(stroke
				(width 0.1524)
				(type default)
			)
			(layer "B.SilkS")
		)
		(fp_line
			(start -0.7874 0.4064)
			(end 0.7874 0.4064)
			(stroke
				(width 0.1524)
				(type default)
			)
			(layer "B.SilkS")
		)
		(fp_line
			(start 0.67945 -0.305054)
			(end 0.12065 -0.305054)
			(stroke
				(width 0.1)
				(type default)
			)
			(layer "B.Fab")
		)
		(fp_line
			(start 0.12065 -0.305054)
			(end 0.12065 -0.2794)
			(stroke
				(width 0.1)
				(type default)
			)
			(layer "B.Fab")
		)
		(fp_line
			(start -0.12065 -0.3048)
			(end -0.67945 -0.3048)
			(stroke
				(width 0.1)
				(type default)
			)
			(layer "B.Fab")
		)
		(fp_line
			(start -0.67945 -0.3048)
			(end -0.67945 0.3048)
			(stroke
				(width 0.1)
				(type default)
			)
			(layer "B.Fab")
		)
		(fp_line
			(start 0.12065 -0.2794)
			(end -0.12065 -0.2794)
			(stroke
				(width 0.1)
				(type default)
			)
			(layer "B.Fab")
		)
		(fp_line
			(start -0.12065 -0.2794)
			(end -0.12065 -0.3048)
			(stroke
				(width 0.1)
				(type default)
			)
			(layer "B.Fab")
		)
		(fp_line
			(start 0.12065 0.2794)
			(end 0.12065 0.3048)
			(stroke
				(width 0.1)
				(type default)
			)
			(layer "B.Fab")
		)
		(fp_line
			(start -0.120396 0.2794)
			(end 0.12065 0.2794)
			(stroke
				(width 0.1)
				(type default)
			)
			(layer "B.Fab")
		)
		(fp_line
			(start 0.67945 0.3048)
			(end 0.67945 -0.305054)
			(stroke
				(width 0.1)
				(type default)
			)
			(layer "B.Fab")
		)
		(fp_line
			(start 0.12065 0.3048)
			(end 0.67945 0.3048)
			(stroke
				(width 0.1)
				(type default)
			)
			(layer "B.Fab")
		)
		(fp_line
			(start -0.120396 0.3048)
			(end -0.120396 0.2794)
			(stroke
				(width 0.1)
				(type default)
			)
			(layer "B.Fab")
		)
		(fp_line
			(start -0.67945 0.3048)
			(end -0.120396 0.3048)
			(stroke
				(width 0.1)
				(type default)
			)
			(layer "B.Fab")
		)
		(pad "1" smd circle
			(at 0.40005 0 270)
			(size 0 0)
			(layers "B.Cu" "B.Mask" "B.Paste")
			(net "SMB_SML1_PMBUS_HSC_SCL")
		)
		(pad "2" smd circle
			(at -0.40005 0 270)
			(size 0 0)
			(layers "B.Cu" "B.Mask" "B.Paste")
			(net "SMB_SML1_PMBUS_HSC_L_SCL")
		)
	)
	(footprint ""
		(layer "B.Cu")
		(at 418.373814 -321.549776 -90)
		(property "Reference" "C27"
			(at 0 0 90)
			(layer "B.SilkS")
			(hide yes)
			(effects
				(font
					(size 1.27 1.27)
				)
				(justify mirror)
			)
		)
		(property "Value" ""
			(at 0 0 90)
			(layer "B.Fab")
			(effects
				(font
					(size 1.27 1.27)
				)
				(justify mirror)
			)
		)
		(duplicate_pad_numbers_are_jumpers no)
		(fp_line
			(start -1.524 0.762)
			(end 1.524 0.762)
			(stroke
				(width 0.1524)
				(type default)
			)
			(layer "B.SilkS")
		)
		(fp_line
			(start 1.524 0.762)
			(end 1.524 -0.762)
			(stroke
				(width 0.1524)
				(type default)
			)
			(layer "B.SilkS")
		)
		(fp_line
			(start -1.524 -0.762)
			(end -1.524 0.762)
			(stroke
				(width 0.1524)
				(type default)
			)
			(layer "B.SilkS")
		)
		(fp_line
			(start 1.524 -0.762)
			(end -1.524 -0.762)
			(stroke
				(width 0.1524)
				(type default)
			)
			(layer "B.SilkS")
		)
		(fp_line
			(start -1.1049 0.724916)
			(end -1.1049 -0.724916)
			(stroke
				(width 0.1)
				(type default)
			)
			(layer "B.Fab")
		)
		(fp_line
			(start 1.1049 0.724916)
			(end -1.1049 0.724916)
			(stroke
				(width 0.1)
				(type default)
			)
			(layer "B.Fab")
		)
		(fp_line
			(start -1.1049 -0.724916)
			(end 1.1049 -0.724916)
			(stroke
				(width 0.1)
				(type default)
			)
			(layer "B.Fab")
		)
		(fp_line
			(start 1.1049 -0.724916)
			(end 1.1049 0.724916)
			(stroke
				(width 0.1)
				(type default)
			)
			(layer "B.Fab")
		)
		(pad "1" smd rect
			(at 0.889 0 270)
			(size 1.016 1.27)
			(layers "B.Cu" "B.Mask" "B.Paste")
			(net "P12V_S3_AUX_CPU0_NVDIMM")
		)
		(pad "2" smd rect
			(at -0.889 0 270)
			(size 1.016 1.27)
			(layers "B.Cu" "B.Mask" "B.Paste")
			(net "GND")
		)
	)
	(footprint ""
		(layer "B.Cu")
		(at 101.404928 -212.049868 180)
		(property "Reference" "C475"
			(at 0 0 0)
			(layer "B.SilkS")
			(hide yes)
			(effects
				(font
					(size 1.27 1.27)
				)
				(justify mirror)
			)
		)
		(property "Value" ""
			(at 0 0 0)
			(layer "B.Fab")
			(effects
				(font
					(size 1.27 1.27)
				)
				(justify mirror)
			)
		)
		(duplicate_pad_numbers_are_jumpers no)
		(fp_line
			(start 1.2954 0.5842)
			(end 1.2954 -0.5842)
			(stroke
				(width 0.1524)
				(type default)
			)
			(layer "B.SilkS")
		)
		(fp_line
			(start 1.2954 -0.5842)
			(end -1.2954 -0.5842)
			(stroke
				(width 0.1524)
				(type default)
			)
			(layer "B.SilkS")
		)
		(fp_line
			(start 0 -0.5842)
			(end 0 0.5842)
			(stroke
				(width 0.1524)
				(type default)
			)
			(layer "B.SilkS")
		)
		(fp_line
			(start -1.2954 0.5842)
			(end 1.2954 0.5842)
			(stroke
				(width 0.1524)
				(type default)
			)
			(layer "B.SilkS")
		)
		(fp_line
			(start -1.2954 -0.5842)
			(end -1.2954 0.5842)
			(stroke
				(width 0.1524)
				(type default)
			)
			(layer "B.SilkS")
		)
		(fp_line
			(start 1.1938 0.4064)
			(end 1.1938 -0.4064)
			(stroke
				(width 0.1)
				(type default)
			)
			(layer "B.Fab")
		)
		(fp_line
			(start 1.1938 -0.4064)
			(end 0.8636 -0.4064)
			(stroke
				(width 0.1)
				(type default)
			)
			(layer "B.Fab")
		)
		(fp_line
			(start 0.8636 0.4572)
			(end 0.8636 0.4064)
			(stroke
				(width 0.1)
				(type default)
			)
			(layer "B.Fab")
		)
		(fp_line
			(start 0.8636 0.4064)
			(end 1.1938 0.4064)
			(stroke
				(width 0.1)
				(type default)
			)
			(layer "B.Fab")
		)
		(fp_line
			(start 0.8636 -0.4064)
			(end 0.8636 -0.4572)
			(stroke
				(width 0.1)
				(type default)
			)
			(layer "B.Fab")
		)
		(fp_line
			(start 0.8636 -0.4572)
			(end -0.8636 -0.4572)
			(stroke
				(width 0.1)
				(type default)
			)
			(layer "B.Fab")
		)
		(fp_line
			(start -0.8636 0.4572)
			(end 0.8636 0.4572)
			(stroke
				(width 0.1)
				(type default)
			)
			(layer "B.Fab")
		)
		(fp_line
			(start -0.8636 0.4064)
			(end -0.8636 0.4572)
			(stroke
				(width 0.1)
				(type default)
			)
			(layer "B.Fab")
		)
		(fp_line
			(start -0.8636 -0.4064)
			(end -1.1938 -0.4064)
			(stroke
				(width 0.1)
				(type default)
			)
			(layer "B.Fab")
		)
		(fp_line
			(start -0.8636 -0.4572)
			(end -0.8636 -0.4064)
			(stroke
				(width 0.1)
				(type default)
			)
			(layer "B.Fab")
		)
		(fp_line
			(start -1.1938 0.4064)
			(end -0.8636 0.4064)
			(stroke
				(width 0.1)
				(type default)
			)
			(layer "B.Fab")
		)
		(fp_line
			(start -1.1938 -0.4064)
			(end -1.1938 0.4064)
			(stroke
				(width 0.1)
				(type default)
			)
			(layer "B.Fab")
		)
		(pad "1" smd rect
			(at 0.7366 0 90)
			(size 0.7112 0.8128)
			(layers "B.Cu" "B.Mask" "B.Paste")
			(net "PVCCFA_EHV_CPU1")
		)
		(pad "2" smd rect
			(at -0.7366 0 90)
			(size 0.7112 0.8128)
			(layers "B.Cu" "B.Mask" "B.Paste")
			(net "GND")
		)
	)
	(footprint ""
		(layer "B.Cu")
		(at 340.521036 -53.908706 180)
		(property "Reference" "R477"
			(at 0 0 0)
			(layer "B.SilkS")
			(hide yes)
			(effects
				(font
					(size 1.27 1.27)
				)
				(justify mirror)
			)
		)
		(property "Value" ""
			(at 0 0 0)
			(layer "B.Fab")
			(effects
				(font
					(size 1.27 1.27)
				)
				(justify mirror)
			)
		)
		(duplicate_pad_numbers_are_jumpers no)
		(fp_line
			(start 0.7874 0.4064)
			(end 0.7874 -0.4064)
			(stroke
				(width 0.1524)
				(type default)
			)
			(layer "B.SilkS")
		)
		(fp_line
			(start 0.7874 -0.4064)
			(end -0.7874 -0.4064)
			(stroke
				(width 0.1524)
				(type default)
			)
			(layer "B.SilkS")
		)
		(fp_line
			(start -0.308864 0.4064)
			(end 0.7874 0.4064)
			(stroke
				(width 0.1524)
				(type default)
			)
			(layer "B.SilkS")
		)
		(fp_line
			(start -0.7874 -0.4064)
			(end -0.7874 0.247142)
			(stroke
				(width 0.1524)
				(type default)
			)
			(layer "B.SilkS")
		)
		(fp_line
			(start 0.67945 0.3048)
			(end 0.67945 -0.305054)
			(stroke
				(width 0.1)
				(type default)
			)
			(layer "B.Fab")
		)
		(fp_line
			(start 0.67945 -0.305054)
			(end 0.12065 -0.305054)
			(stroke
				(width 0.1)
				(type default)
			)
			(layer "B.Fab")
		)
		(fp_line
			(start 0.12065 0.3048)
			(end 0.67945 0.3048)
			(stroke
				(width 0.1)
				(type default)
			)
			(layer "B.Fab")
		)
		(fp_line
			(start 0.12065 0.2794)
			(end 0.12065 0.3048)
			(stroke
				(width 0.1)
				(type default)
			)
			(layer "B.Fab")
		)
		(fp_line
			(start 0.12065 -0.2794)
			(end -0.12065 -0.2794)
			(stroke
				(width 0.1)
				(type default)
			)
			(layer "B.Fab")
		)
		(fp_line
			(start 0.12065 -0.305054)
			(end 0.12065 -0.2794)
			(stroke
				(width 0.1)
				(type default)
			)
			(layer "B.Fab")
		)
		(fp_line
			(start -0.120396 0.3048)
			(end -0.120396 0.2794)
			(stroke
				(width 0.1)
				(type default)
			)
			(layer "B.Fab")
		)
		(fp_line
			(start -0.120396 0.2794)
			(end 0.12065 0.2794)
			(stroke
				(width 0.1)
				(type default)
			)
			(layer "B.Fab")
		)
		(fp_line
			(start -0.12065 -0.2794)
			(end -0.12065 -0.3048)
			(stroke
				(width 0.1)
				(type default)
			)
			(layer "B.Fab")
		)
		(fp_line
			(start -0.12065 -0.3048)
			(end -0.67945 -0.3048)
			(stroke
				(width 0.1)
				(type default)
			)
			(layer "B.Fab")
		)
		(fp_line
			(start -0.67945 0.3048)
			(end -0.120396 0.3048)
			(stroke
				(width 0.1)
				(type default)
			)
			(layer "B.Fab")
		)
		(fp_line
			(start -0.67945 -0.3048)
			(end -0.67945 0.3048)
			(stroke
				(width 0.1)
				(type default)
			)
			(layer "B.Fab")
		)
		(pad "1" smd circle
			(at 0.40005 0)
			(size 0 0)
			(layers "B.Cu" "B.Mask" "B.Paste")
			(net "PD_PCH_XCLK_BIASREF")
		)
		(pad "2" smd circle
			(at -0.40005 0)
			(size 0 0)
			(layers "B.Cu" "B.Mask" "B.Paste")
			(net "GND")
		)
	)
	(footprint ""
		(layer "B.Cu")
		(at 302.218852 -54.389782 180)
		(property "Reference" "C1192"
			(at 0 0 0)
			(layer "B.SilkS")
			(hide yes)
			(effects
				(font
					(size 1.27 1.27)
				)
				(justify mirror)
			)
		)
		(property "Value" ""
			(at 0 0 0)
			(layer "B.Fab")
			(effects
				(font
					(size 1.27 1.27)
				)
				(justify mirror)
			)
		)
		(duplicate_pad_numbers_are_jumpers no)
		(fp_line
			(start 1.2954 0.5842)
			(end 1.2954 -0.5842)
			(stroke
				(width 0.1524)
				(type default)
			)
			(layer "B.SilkS")
		)
		(fp_line
			(start 1.2954 -0.5842)
			(end -1.2954 -0.5842)
			(stroke
				(width 0.1524)
				(type default)
			)
			(layer "B.SilkS")
		)
		(fp_line
			(start 0 -0.5842)
			(end 0 0.5842)
			(stroke
				(width 0.1524)
				(type default)
			)
			(layer "B.SilkS")
		)
		(fp_line
			(start -1.2954 0.5842)
			(end 1.2954 0.5842)
			(stroke
				(width 0.1524)
				(type default)
			)
			(layer "B.SilkS")
		)
		(fp_line
			(start -1.2954 -0.5842)
			(end -1.2954 0.5842)
			(stroke
				(width 0.1524)
				(type default)
			)
			(layer "B.SilkS")
		)
		(fp_line
			(start 1.1938 0.4064)
			(end 1.1938 -0.4064)
			(stroke
				(width 0.1)
				(type default)
			)
			(layer "B.Fab")
		)
		(fp_line
			(start 1.1938 -0.4064)
			(end 0.8636 -0.4064)
			(stroke
				(width 0.1)
				(type default)
			)
			(layer "B.Fab")
		)
		(fp_line
			(start 0.8636 0.4572)
			(end 0.8636 0.4064)
			(stroke
				(width 0.1)
				(type default)
			)
			(layer "B.Fab")
		)
		(fp_line
			(start 0.8636 0.4064)
			(end 1.1938 0.4064)
			(stroke
				(width 0.1)
				(type default)
			)
			(layer "B.Fab")
		)
		(fp_line
			(start 0.8636 -0.4064)
			(end 0.8636 -0.4572)
			(stroke
				(width 0.1)
				(type default)
			)
			(layer "B.Fab")
		)
		(fp_line
			(start 0.8636 -0.4572)
			(end -0.8636 -0.4572)
			(stroke
				(width 0.1)
				(type default)
			)
			(layer "B.Fab")
		)
		(fp_line
			(start -0.8636 0.4572)
			(end 0.8636 0.4572)
			(stroke
				(width 0.1)
				(type default)
			)
			(layer "B.Fab")
		)
		(fp_line
			(start -0.8636 0.4064)
			(end -0.8636 0.4572)
			(stroke
				(width 0.1)
				(type default)
			)
			(layer "B.Fab")
		)
		(fp_line
			(start -0.8636 -0.4064)
			(end -1.1938 -0.4064)
			(stroke
				(width 0.1)
				(type default)
			)
			(layer "B.Fab")
		)
		(fp_line
			(start -0.8636 -0.4572)
			(end -0.8636 -0.4064)
			(stroke
				(width 0.1)
				(type default)
			)
			(layer "B.Fab")
		)
		(fp_line
			(start -1.1938 0.4064)
			(end -0.8636 0.4064)
			(stroke
				(width 0.1)
				(type default)
			)
			(layer "B.Fab")
		)
		(fp_line
			(start -1.1938 -0.4064)
			(end -1.1938 0.4064)
			(stroke
				(width 0.1)
				(type default)
			)
			(layer "B.Fab")
		)
		(pad "1" smd rect
			(at 0.7366 0 90)
			(size 0.7112 0.8128)
			(layers "B.Cu" "B.Mask" "B.Paste")
			(net "P1V05_PCH_AUX")
		)
		(pad "2" smd rect
			(at -0.7366 0 90)
			(size 0.7112 0.8128)
			(layers "B.Cu" "B.Mask" "B.Paste")
			(net "GND")
		)
	)
	(footprint ""
		(layer "B.Cu")
		(at 36.968938 -126.40056)
		(property "Reference" "R4781"
			(at 0 0 0)
			(layer "B.SilkS")
			(hide yes)
			(effects
				(font
					(size 1.27 1.27)
				)
				(justify mirror)
			)
		)
		(property "Value" ""
			(at 0 0 0)
			(layer "B.Fab")
			(effects
				(font
					(size 1.27 1.27)
				)
				(justify mirror)
			)
		)
		(duplicate_pad_numbers_are_jumpers no)
		(fp_line
			(start -0.7874 -0.4064)
			(end -0.7874 0.4064)
			(stroke
				(width 0.1524)
				(type default)
			)
			(layer "B.SilkS")
		)
		(fp_line
			(start -0.7874 0.4064)
			(end 0.7874 0.4064)
			(stroke
				(width 0.1524)
				(type default)
			)
			(layer "B.SilkS")
		)
		(fp_line
			(start 0.7874 -0.4064)
			(end -0.7874 -0.4064)
			(stroke
				(width 0.1524)
				(type default)
			)
			(layer "B.SilkS")
		)
		(fp_line
			(start 0.7874 0.4064)
			(end 0.7874 -0.4064)
			(stroke
				(width 0.1524)
				(type default)
			)
			(layer "B.SilkS")
		)
		(fp_line
			(start -0.67945 -0.3048)
			(end -0.67945 0.3048)
			(stroke
				(width 0.1)
				(type default)
			)
			(layer "B.Fab")
		)
		(fp_line
			(start -0.67945 0.3048)
			(end -0.120396 0.3048)
			(stroke
				(width 0.1)
				(type default)
			)
			(layer "B.Fab")
		)
		(fp_line
			(start -0.12065 -0.3048)
			(end -0.67945 -0.3048)
			(stroke
				(width 0.1)
				(type default)
			)
			(layer "B.Fab")
		)
		(fp_line
			(start -0.12065 -0.2794)
			(end -0.12065 -0.3048)
			(stroke
				(width 0.1)
				(type default)
			)
			(layer "B.Fab")
		)
		(fp_line
			(start -0.120396 0.2794)
			(end 0.12065 0.2794)
			(stroke
				(width 0.1)
				(type default)
			)
			(layer "B.Fab")
		)
		(fp_line
			(start -0.120396 0.3048)
			(end -0.120396 0.2794)
			(stroke
				(width 0.1)
				(type default)
			)
			(layer "B.Fab")
		)
		(fp_line
			(start 0.12065 -0.305054)
			(end 0.12065 -0.2794)
			(stroke
				(width 0.1)
				(type default)
			)
			(layer "B.Fab")
		)
		(fp_line
			(start 0.12065 -0.2794)
			(end -0.12065 -0.2794)
			(stroke
				(width 0.1)
				(type default)
			)
			(layer "B.Fab")
		)
		(fp_line
			(start 0.12065 0.2794)
			(end 0.12065 0.3048)
			(stroke
				(width 0.1)
				(type default)
			)
			(layer "B.Fab")
		)
		(fp_line
			(start 0.12065 0.3048)
			(end 0.67945 0.3048)
			(stroke
				(width 0.1)
				(type default)
			)
			(layer "B.Fab")
		)
		(fp_line
			(start 0.67945 -0.305054)
			(end 0.12065 -0.305054)
			(stroke
				(width 0.1)
				(type default)
			)
			(layer "B.Fab")
		)
		(fp_line
			(start 0.67945 0.3048)
			(end 0.67945 -0.305054)
			(stroke
				(width 0.1)
				(type default)
			)
			(layer "B.Fab")
		)
		(pad "1" smd circle
			(at 0.40005 0 180)
			(size 0 0)
			(layers "B.Cu" "B.Mask" "B.Paste")
			(net "PWRGD_PVCCINFAON_CPU1")
		)
		(pad "2" smd circle
			(at -0.40005 0 180)
			(size 0 0)
			(layers "B.Cu" "B.Mask" "B.Paste")
			(net "PWRGD_PVCCINFAON_CPU1_R")
		)
	)
	(footprint ""
		(layer "B.Cu")
		(at 117.87632 -237.709456 -90)
		(property "Reference" "C489"
			(at 0 0 90)
			(layer "B.SilkS")
			(hide yes)
			(effects
				(font
					(size 1.27 1.27)
				)
				(justify mirror)
			)
		)
		(property "Value" ""
			(at 0 0 90)
			(layer "B.Fab")
			(effects
				(font
					(size 1.27 1.27)
				)
				(justify mirror)
			)
		)
		(duplicate_pad_numbers_are_jumpers no)
		(fp_line
			(start -1.2954 0.5842)
			(end 1.2954 0.5842)
			(stroke
				(width 0.1524)
				(type default)
			)
			(layer "B.SilkS")
		)
		(fp_line
			(start 1.2954 0.5842)
			(end 1.2954 -0.5842)
			(stroke
				(width 0.1524)
				(type default)
			)
			(layer "B.SilkS")
		)
		(fp_line
			(start -1.2954 -0.5842)
			(end -1.2954 0.5842)
			(stroke
				(width 0.1524)
				(type default)
			)
			(layer "B.SilkS")
		)
		(fp_line
			(start 0 -0.5842)
			(end 0 0.5842)
			(stroke
				(width 0.1524)
				(type default)
			)
			(layer "B.SilkS")
		)
		(fp_line
			(start 1.2954 -0.5842)
			(end -1.2954 -0.5842)
			(stroke
				(width 0.1524)
				(type default)
			)
			(layer "B.SilkS")
		)
		(fp_line
			(start -0.8636 0.4572)
			(end 0.8636 0.4572)
			(stroke
				(width 0.1)
				(type default)
			)
			(layer "B.Fab")
		)
		(fp_line
			(start 0.8636 0.4572)
			(end 0.8636 0.4064)
			(stroke
				(width 0.1)
				(type default)
			)
			(layer "B.Fab")
		)
		(fp_line
			(start -1.1938 0.4064)
			(end -0.8636 0.4064)
			(stroke
				(width 0.1)
				(type default)
			)
			(layer "B.Fab")
		)
		(fp_line
			(start -0.8636 0.4064)
			(end -0.8636 0.4572)
			(stroke
				(width 0.1)
				(type default)
			)
			(layer "B.Fab")
		)
		(fp_line
			(start 0.8636 0.4064)
			(end 1.1938 0.4064)
			(stroke
				(width 0.1)
				(type default)
			)
			(layer "B.Fab")
		)
		(fp_line
			(start 1.1938 0.4064)
			(end 1.1938 -0.4064)
			(stroke
				(width 0.1)
				(type default)
			)
			(layer "B.Fab")
		)
		(fp_line
			(start -1.1938 -0.4064)
			(end -1.1938 0.4064)
			(stroke
				(width 0.1)
				(type default)
			)
			(layer "B.Fab")
		)
		(fp_line
			(start -0.8636 -0.4064)
			(end -1.1938 -0.4064)
			(stroke
				(width 0.1)
				(type default)
			)
			(layer "B.Fab")
		)
		(fp_line
			(start 0.8636 -0.4064)
			(end 0.8636 -0.4572)
			(stroke
				(width 0.1)
				(type default)
			)
			(layer "B.Fab")
		)
		(fp_line
			(start 1.1938 -0.4064)
			(end 0.8636 -0.4064)
			(stroke
				(width 0.1)
				(type default)
			)
			(layer "B.Fab")
		)
		(fp_line
			(start -0.8636 -0.4572)
			(end -0.8636 -0.4064)
			(stroke
				(width 0.1)
				(type default)
			)
			(layer "B.Fab")
		)
		(fp_line
			(start 0.8636 -0.4572)
			(end -0.8636 -0.4572)
			(stroke
				(width 0.1)
				(type default)
			)
			(layer "B.Fab")
		)
		(pad "1" smd rect
			(at 0.7366 0 180)
			(size 0.7112 0.8128)
			(layers "B.Cu" "B.Mask" "B.Paste")
			(net "PVCCINFAON_CPU1")
		)
		(pad "2" smd rect
			(at -0.7366 0 180)
			(size 0.7112 0.8128)
			(layers "B.Cu" "B.Mask" "B.Paste")
			(net "GND")
		)
	)
	(footprint ""
		(layer "B.Cu")
		(at 114.369596 -357.436166)
		(property "Reference" "PR306"
			(at 0 0 0)
			(layer "B.SilkS")
			(hide yes)
			(effects
				(font
					(size 1.27 1.27)
				)
				(justify mirror)
			)
		)
		(property "Value" ""
			(at 0 0 0)
			(layer "B.Fab")
			(effects
				(font
					(size 1.27 1.27)
				)
				(justify mirror)
			)
		)
		(duplicate_pad_numbers_are_jumpers no)
		(fp_line
			(start -0.7874 -0.4064)
			(end -0.7874 0.4064)
			(stroke
				(width 0.1524)
				(type default)
			)
			(layer "B.SilkS")
		)
		(fp_line
			(start -0.7874 0.4064)
			(end 0.7874 0.4064)
			(stroke
				(width 0.1524)
				(type default)
			)
			(layer "B.SilkS")
		)
		(fp_line
			(start 0.7874 -0.4064)
			(end -0.7874 -0.4064)
			(stroke
				(width 0.1524)
				(type default)
			)
			(layer "B.SilkS")
		)
		(fp_line
			(start 0.7874 0.4064)
			(end 0.7874 -0.4064)
			(stroke
				(width 0.1524)
				(type default)
			)
			(layer "B.SilkS")
		)
		(fp_line
			(start -0.67945 -0.3048)
			(end -0.67945 0.3048)
			(stroke
				(width 0.1)
				(type default)
			)
			(layer "B.Fab")
		)
		(fp_line
			(start -0.67945 0.3048)
			(end -0.120396 0.3048)
			(stroke
				(width 0.1)
				(type default)
			)
			(layer "B.Fab")
		)
		(fp_line
			(start -0.12065 -0.3048)
			(end -0.67945 -0.3048)
			(stroke
				(width 0.1)
				(type default)
			)
			(layer "B.Fab")
		)
		(fp_line
			(start -0.12065 -0.2794)
			(end -0.12065 -0.3048)
			(stroke
				(width 0.1)
				(type default)
			)
			(layer "B.Fab")
		)
		(fp_line
			(start -0.120396 0.2794)
			(end 0.12065 0.2794)
			(stroke
				(width 0.1)
				(type default)
			)
			(layer "B.Fab")
		)
		(fp_line
			(start -0.120396 0.3048)
			(end -0.120396 0.2794)
			(stroke
				(width 0.1)
				(type default)
			)
			(layer "B.Fab")
		)
		(fp_line
			(start 0.12065 -0.305054)
			(end 0.12065 -0.2794)
			(stroke
				(width 0.1)
				(type default)
			)
			(layer "B.Fab")
		)
		(fp_line
			(start 0.12065 -0.2794)
			(end -0.12065 -0.2794)
			(stroke
				(width 0.1)
				(type default)
			)
			(layer "B.Fab")
		)
		(fp_line
			(start 0.12065 0.2794)
			(end 0.12065 0.3048)
			(stroke
				(width 0.1)
				(type default)
			)
			(layer "B.Fab")
		)
		(fp_line
			(start 0.12065 0.3048)
			(end 0.67945 0.3048)
			(stroke
				(width 0.1)
				(type default)
			)
			(layer "B.Fab")
		)
		(fp_line
			(start 0.67945 -0.305054)
			(end 0.12065 -0.305054)
			(stroke
				(width 0.1)
				(type default)
			)
			(layer "B.Fab")
		)
		(fp_line
			(start 0.67945 0.3048)
			(end 0.67945 -0.305054)
			(stroke
				(width 0.1)
				(type default)
			)
			(layer "B.Fab")
		)
		(pad "1" smd circle
			(at 0.40005 0 180)
			(size 0 0)
			(layers "B.Cu" "B.Mask" "B.Paste")
			(net "PVCCIN_CPU1_VREF")
		)
		(pad "2" smd circle
			(at -0.40005 0 180)
			(size 0 0)
			(layers "B.Cu" "B.Mask" "B.Paste")
			(net "PVCCIN_CPU1_ADDR")
		)
	)
	(footprint ""
		(layer "B.Cu")
		(at 459.572614 -321.549776 -90)
		(property "Reference" "C45"
			(at 0 0 90)
			(layer "B.SilkS")
			(hide yes)
			(effects
				(font
					(size 1.27 1.27)
				)
				(justify mirror)
			)
		)
		(property "Value" ""
			(at 0 0 90)
			(layer "B.Fab")
			(effects
				(font
					(size 1.27 1.27)
				)
				(justify mirror)
			)
		)
		(duplicate_pad_numbers_are_jumpers no)
		(fp_line
			(start -1.524 0.762)
			(end 1.524 0.762)
			(stroke
				(width 0.1524)
				(type default)
			)
			(layer "B.SilkS")
		)
		(fp_line
			(start 1.524 0.762)
			(end 1.524 -0.762)
			(stroke
				(width 0.1524)
				(type default)
			)
			(layer "B.SilkS")
		)
		(fp_line
			(start -1.524 -0.762)
			(end -1.524 0.762)
			(stroke
				(width 0.1524)
				(type default)
			)
			(layer "B.SilkS")
		)
		(fp_line
			(start 1.524 -0.762)
			(end -1.524 -0.762)
			(stroke
				(width 0.1524)
				(type default)
			)
			(layer "B.SilkS")
		)
		(fp_line
			(start -1.1049 0.724916)
			(end -1.1049 -0.724916)
			(stroke
				(width 0.1)
				(type default)
			)
			(layer "B.Fab")
		)
		(fp_line
			(start 1.1049 0.724916)
			(end -1.1049 0.724916)
			(stroke
				(width 0.1)
				(type default)
			)
			(layer "B.Fab")
		)
		(fp_line
			(start -1.1049 -0.724916)
			(end 1.1049 -0.724916)
			(stroke
				(width 0.1)
				(type default)
			)
			(layer "B.Fab")
		)
		(fp_line
			(start 1.1049 -0.724916)
			(end 1.1049 0.724916)
			(stroke
				(width 0.1)
				(type default)
			)
			(layer "B.Fab")
		)
		(pad "1" smd rect
			(at 0.889 0 270)
			(size 1.016 1.27)
			(layers "B.Cu" "B.Mask" "B.Paste")
			(net "P12V_S3_AUX_CPU0_NVDIMM")
		)
		(pad "2" smd rect
			(at -0.889 0 270)
			(size 1.016 1.27)
			(layers "B.Cu" "B.Mask" "B.Paste")
			(net "GND")
		)
	)
	(footprint ""
		(layer "B.Cu")
		(at 303.149254 -319.05956)
		(property "Reference" "R26"
			(at 0 0 0)
			(layer "B.SilkS")
			(hide yes)
			(effects
				(font
					(size 1.27 1.27)
				)
				(justify mirror)
			)
		)
		(property "Value" ""
			(at 0 0 0)
			(layer "B.Fab")
			(effects
				(font
					(size 1.27 1.27)
				)
				(justify mirror)
			)
		)
		(duplicate_pad_numbers_are_jumpers no)
		(fp_line
			(start -0.7874 -0.4064)
			(end -0.7874 0.4064)
			(stroke
				(width 0.1524)
				(type default)
			)
			(layer "B.SilkS")
		)
		(fp_line
			(start -0.7874 0.4064)
			(end 0.7874 0.4064)
			(stroke
				(width 0.1524)
				(type default)
			)
			(layer "B.SilkS")
		)
		(fp_line
			(start 0.7874 -0.4064)
			(end -0.7874 -0.4064)
			(stroke
				(width 0.1524)
				(type default)
			)
			(layer "B.SilkS")
		)
		(fp_line
			(start 0.7874 0.4064)
			(end 0.7874 -0.4064)
			(stroke
				(width 0.1524)
				(type default)
			)
			(layer "B.SilkS")
		)
		(fp_line
			(start -0.67945 -0.3048)
			(end -0.67945 0.3048)
			(stroke
				(width 0.1)
				(type default)
			)
			(layer "B.Fab")
		)
		(fp_line
			(start -0.67945 0.3048)
			(end -0.120396 0.3048)
			(stroke
				(width 0.1)
				(type default)
			)
			(layer "B.Fab")
		)
		(fp_line
			(start -0.12065 -0.3048)
			(end -0.67945 -0.3048)
			(stroke
				(width 0.1)
				(type default)
			)
			(layer "B.Fab")
		)
		(fp_line
			(start -0.12065 -0.2794)
			(end -0.12065 -0.3048)
			(stroke
				(width 0.1)
				(type default)
			)
			(layer "B.Fab")
		)
		(fp_line
			(start -0.120396 0.2794)
			(end 0.12065 0.2794)
			(stroke
				(width 0.1)
				(type default)
			)
			(layer "B.Fab")
		)
		(fp_line
			(start -0.120396 0.3048)
			(end -0.120396 0.2794)
			(stroke
				(width 0.1)
				(type default)
			)
			(layer "B.Fab")
		)
		(fp_line
			(start 0.12065 -0.305054)
			(end 0.12065 -0.2794)
			(stroke
				(width 0.1)
				(type default)
			)
			(layer "B.Fab")
		)
		(fp_line
			(start 0.12065 -0.2794)
			(end -0.12065 -0.2794)
			(stroke
				(width 0.1)
				(type default)
			)
			(layer "B.Fab")
		)
		(fp_line
			(start 0.12065 0.2794)
			(end 0.12065 0.3048)
			(stroke
				(width 0.1)
				(type default)
			)
			(layer "B.Fab")
		)
		(fp_line
			(start 0.12065 0.3048)
			(end 0.67945 0.3048)
			(stroke
				(width 0.1)
				(type default)
			)
			(layer "B.Fab")
		)
		(fp_line
			(start 0.67945 -0.305054)
			(end 0.12065 -0.305054)
			(stroke
				(width 0.1)
				(type default)
			)
			(layer "B.Fab")
		)
		(fp_line
			(start 0.67945 0.3048)
			(end 0.67945 -0.305054)
			(stroke
				(width 0.1)
				(type default)
			)
			(layer "B.Fab")
		)
		(pad "1" smd circle
			(at 0.40005 0 180)
			(size 0 0)
			(layers "B.Cu" "B.Mask" "B.Paste")
			(net "PD_CHA_CPU0_DIMM1_SAA")
		)
		(pad "2" smd circle
			(at -0.40005 0 180)
			(size 0 0)
			(layers "B.Cu" "B.Mask" "B.Paste")
			(net "GND")
		)
	)
	(footprint ""
		(layer "B.Cu")
		(at 16.610838 -97.314512 90)
		(property "Reference" "C2039"
			(at 0 0 90)
			(layer "B.SilkS")
			(hide yes)
			(effects
				(font
					(size 1.27 1.27)
				)
				(justify mirror)
			)
		)
		(property "Value" ""
			(at 0 0 90)
			(layer "B.Fab")
			(effects
				(font
					(size 1.27 1.27)
				)
				(justify mirror)
			)
		)
		(duplicate_pad_numbers_are_jumpers no)
		(fp_line
			(start 0.7874 -0.4064)
			(end -0.7874 -0.4064)
			(stroke
				(width 0.1524)
				(type default)
			)
			(layer "B.SilkS")
		)
		(fp_line
			(start -0.7874 -0.4064)
			(end -0.7874 0.4064)
			(stroke
				(width 0.1524)
				(type default)
			)
			(layer "B.SilkS")
		)
		(fp_line
			(start 0.7874 0.4064)
			(end 0.7874 -0.4064)
			(stroke
				(width 0.1524)
				(type default)
			)
			(layer "B.SilkS")
		)
		(fp_line
			(start -0.7874 0.4064)
			(end 0.7874 0.4064)
			(stroke
				(width 0.1524)
				(type default)
			)
			(layer "B.SilkS")
		)
		(fp_line
			(start 0.67945 -0.305054)
			(end 0.12065 -0.305054)
			(stroke
				(width 0.1)
				(type default)
			)
			(layer "B.Fab")
		)
		(fp_line
			(start 0.12065 -0.305054)
			(end 0.12065 -0.2794)
			(stroke
				(width 0.1)
				(type default)
			)
			(layer "B.Fab")
		)
		(fp_line
			(start -0.12065 -0.3048)
			(end -0.67945 -0.3048)
			(stroke
				(width 0.1)
				(type default)
			)
			(layer "B.Fab")
		)
		(fp_line
			(start -0.67945 -0.3048)
			(end -0.67945 0.3048)
			(stroke
				(width 0.1)
				(type default)
			)
			(layer "B.Fab")
		)
		(fp_line
			(start 0.12065 -0.2794)
			(end -0.12065 -0.2794)
			(stroke
				(width 0.1)
				(type default)
			)
			(layer "B.Fab")
		)
		(fp_line
			(start -0.12065 -0.2794)
			(end -0.12065 -0.3048)
			(stroke
				(width 0.1)
				(type default)
			)
			(layer "B.Fab")
		)
		(fp_line
			(start 0.12065 0.2794)
			(end 0.12065 0.3048)
			(stroke
				(width 0.1)
				(type default)
			)
			(layer "B.Fab")
		)
		(fp_line
			(start -0.120396 0.2794)
			(end 0.12065 0.2794)
			(stroke
				(width 0.1)
				(type default)
			)
			(layer "B.Fab")
		)
		(fp_line
			(start 0.67945 0.3048)
			(end 0.67945 -0.305054)
			(stroke
				(width 0.1)
				(type default)
			)
			(layer "B.Fab")
		)
		(fp_line
			(start 0.12065 0.3048)
			(end 0.67945 0.3048)
			(stroke
				(width 0.1)
				(type default)
			)
			(layer "B.Fab")
		)
		(fp_line
			(start -0.120396 0.3048)
			(end -0.120396 0.2794)
			(stroke
				(width 0.1)
				(type default)
			)
			(layer "B.Fab")
		)
		(fp_line
			(start -0.67945 0.3048)
			(end -0.120396 0.3048)
			(stroke
				(width 0.1)
				(type default)
			)
			(layer "B.Fab")
		)
		(pad "1" smd circle
			(at 0.40005 0 270)
			(size 0 0)
			(layers "B.Cu" "B.Mask" "B.Paste")
			(net "P3V3_AUX_USB_HUB")
		)
		(pad "2" smd circle
			(at -0.40005 0 270)
			(size 0 0)
			(layers "B.Cu" "B.Mask" "B.Paste")
			(net "GND")
		)
	)
	(footprint ""
		(layer "B.Cu")
		(at 244.20703 -97.219516 -90)
		(property "Reference" "C112"
			(at 0 0 90)
			(layer "B.SilkS")
			(hide yes)
			(effects
				(font
					(size 1.27 1.27)
				)
				(justify mirror)
			)
		)
		(property "Value" ""
			(at 0 0 90)
			(layer "B.Fab")
			(effects
				(font
					(size 1.27 1.27)
				)
				(justify mirror)
			)
		)
		(duplicate_pad_numbers_are_jumpers no)
		(fp_line
			(start -0.7874 0.4064)
			(end 0.7874 0.4064)
			(stroke
				(width 0.1524)
				(type default)
			)
			(layer "B.SilkS")
		)
		(fp_line
			(start 0.7874 0.4064)
			(end 0.7874 -0.4064)
			(stroke
				(width 0.1524)
				(type default)
			)
			(layer "B.SilkS")
		)
		(fp_line
			(start -0.7874 -0.4064)
			(end -0.7874 0.4064)
			(stroke
				(width 0.1524)
				(type default)
			)
			(layer "B.SilkS")
		)
		(fp_line
			(start 0.7874 -0.4064)
			(end -0.7874 -0.4064)
			(stroke
				(width 0.1524)
				(type default)
			)
			(layer "B.SilkS")
		)
		(fp_line
			(start -0.67945 0.3048)
			(end -0.120396 0.3048)
			(stroke
				(width 0.1)
				(type default)
			)
			(layer "B.Fab")
		)
		(fp_line
			(start -0.120396 0.3048)
			(end -0.120396 0.2794)
			(stroke
				(width 0.1)
				(type default)
			)
			(layer "B.Fab")
		)
		(fp_line
			(start 0.12065 0.3048)
			(end 0.67945 0.3048)
			(stroke
				(width 0.1)
				(type default)
			)
			(layer "B.Fab")
		)
		(fp_line
			(start 0.67945 0.3048)
			(end 0.67945 -0.305054)
			(stroke
				(width 0.1)
				(type default)
			)
			(layer "B.Fab")
		)
		(fp_line
			(start -0.120396 0.2794)
			(end 0.12065 0.2794)
			(stroke
				(width 0.1)
				(type default)
			)
			(layer "B.Fab")
		)
		(fp_line
			(start 0.12065 0.2794)
			(end 0.12065 0.3048)
			(stroke
				(width 0.1)
				(type default)
			)
			(layer "B.Fab")
		)
		(fp_line
			(start -0.12065 -0.2794)
			(end -0.12065 -0.3048)
			(stroke
				(width 0.1)
				(type default)
			)
			(layer "B.Fab")
		)
		(fp_line
			(start 0.12065 -0.2794)
			(end -0.12065 -0.2794)
			(stroke
				(width 0.1)
				(type default)
			)
			(layer "B.Fab")
		)
		(fp_line
			(start -0.67945 -0.3048)
			(end -0.67945 0.3048)
			(stroke
				(width 0.1)
				(type default)
			)
			(layer "B.Fab")
		)
		(fp_line
			(start -0.12065 -0.3048)
			(end -0.67945 -0.3048)
			(stroke
				(width 0.1)
				(type default)
			)
			(layer "B.Fab")
		)
		(fp_line
			(start 0.12065 -0.305054)
			(end 0.12065 -0.2794)
			(stroke
				(width 0.1)
				(type default)
			)
			(layer "B.Fab")
		)
		(fp_line
			(start 0.67945 -0.305054)
			(end 0.12065 -0.305054)
			(stroke
				(width 0.1)
				(type default)
			)
			(layer "B.Fab")
		)
		(pad "1" smd circle
			(at 0.40005 0 90)
			(size 0 0)
			(layers "B.Cu" "B.Mask" "B.Paste")
			(net "P3V3_AUX_CLK_GEN_VDDXTAL_CK440")
		)
		(pad "2" smd circle
			(at -0.40005 0 90)
			(size 0 0)
			(layers "B.Cu" "B.Mask" "B.Paste")
			(net "GND")
		)
	)
	(footprint ""
		(layer "B.Cu")
		(at 185.691526 -312.982864 90)
		(property "Reference" "R2504"
			(at 0 0 90)
			(layer "B.SilkS")
			(hide yes)
			(effects
				(font
					(size 1.27 1.27)
				)
				(justify mirror)
			)
		)
		(property "Value" ""
			(at 0 0 90)
			(layer "B.Fab")
			(effects
				(font
					(size 1.27 1.27)
				)
				(justify mirror)
			)
		)
		(duplicate_pad_numbers_are_jumpers no)
		(fp_line
			(start 0.7874 -0.4064)
			(end -0.7874 -0.4064)
			(stroke
				(width 0.1524)
				(type default)
			)
			(layer "B.SilkS")
		)
		(fp_line
			(start -0.7874 -0.4064)
			(end -0.7874 0.4064)
			(stroke
				(width 0.1524)
				(type default)
			)
			(layer "B.SilkS")
		)
		(fp_line
			(start 0.7874 0.4064)
			(end 0.7874 -0.4064)
			(stroke
				(width 0.1524)
				(type default)
			)
			(layer "B.SilkS")
		)
		(fp_line
			(start -0.7874 0.4064)
			(end 0.7874 0.4064)
			(stroke
				(width 0.1524)
				(type default)
			)
			(layer "B.SilkS")
		)
		(fp_line
			(start 0.67945 -0.305054)
			(end 0.12065 -0.305054)
			(stroke
				(width 0.1)
				(type default)
			)
			(layer "B.Fab")
		)
		(fp_line
			(start 0.12065 -0.305054)
			(end 0.12065 -0.2794)
			(stroke
				(width 0.1)
				(type default)
			)
			(layer "B.Fab")
		)
		(fp_line
			(start -0.12065 -0.3048)
			(end -0.67945 -0.3048)
			(stroke
				(width 0.1)
				(type default)
			)
			(layer "B.Fab")
		)
		(fp_line
			(start -0.67945 -0.3048)
			(end -0.67945 0.3048)
			(stroke
				(width 0.1)
				(type default)
			)
			(layer "B.Fab")
		)
		(fp_line
			(start 0.12065 -0.2794)
			(end -0.12065 -0.2794)
			(stroke
				(width 0.1)
				(type default)
			)
			(layer "B.Fab")
		)
		(fp_line
			(start -0.12065 -0.2794)
			(end -0.12065 -0.3048)
			(stroke
				(width 0.1)
				(type default)
			)
			(layer "B.Fab")
		)
		(fp_line
			(start 0.12065 0.2794)
			(end 0.12065 0.3048)
			(stroke
				(width 0.1)
				(type default)
			)
			(layer "B.Fab")
		)
		(fp_line
			(start -0.120396 0.2794)
			(end 0.12065 0.2794)
			(stroke
				(width 0.1)
				(type default)
			)
			(layer "B.Fab")
		)
		(fp_line
			(start 0.67945 0.3048)
			(end 0.67945 -0.305054)
			(stroke
				(width 0.1)
				(type default)
			)
			(layer "B.Fab")
		)
		(fp_line
			(start 0.12065 0.3048)
			(end 0.67945 0.3048)
			(stroke
				(width 0.1)
				(type default)
			)
			(layer "B.Fab")
		)
		(fp_line
			(start -0.120396 0.3048)
			(end -0.120396 0.2794)
			(stroke
				(width 0.1)
				(type default)
			)
			(layer "B.Fab")
		)
		(fp_line
			(start -0.67945 0.3048)
			(end -0.120396 0.3048)
			(stroke
				(width 0.1)
				(type default)
			)
			(layer "B.Fab")
		)
		(pad "1" smd circle
			(at 0.40005 0 270)
			(size 0 0)
			(layers "B.Cu" "B.Mask" "B.Paste")
			(net "PWRGD_FAIL_CPU1_EF_R1")
		)
		(pad "2" smd circle
			(at -0.40005 0 270)
			(size 0 0)
			(layers "B.Cu" "B.Mask" "B.Paste")
			(net "PWRGD_FAIL_CPU1_EF_R")
		)
	)
	(footprint ""
		(layer "B.Cu")
		(at 174.155608 -105.375456 90)
		(property "Reference" "C1913"
			(at 0 0 90)
			(layer "B.SilkS")
			(hide yes)
			(effects
				(font
					(size 1.27 1.27)
				)
				(justify mirror)
			)
		)
		(property "Value" ""
			(at 0 0 90)
			(layer "B.Fab")
			(effects
				(font
					(size 1.27 1.27)
				)
				(justify mirror)
			)
		)
		(duplicate_pad_numbers_are_jumpers no)
		(fp_line
			(start 0.69215 -0.2921)
			(end -0.69215 -0.2921)
			(stroke
				(width 0.1524)
				(type default)
			)
			(layer "B.SilkS")
		)
		(fp_line
			(start -0.69215 -0.2921)
			(end -0.69215 0.2921)
			(stroke
				(width 0.1524)
				(type default)
			)
			(layer "B.SilkS")
		)
		(fp_line
			(start 0.69215 0.2921)
			(end 0.69215 -0.2921)
			(stroke
				(width 0.1524)
				(type default)
			)
			(layer "B.SilkS")
		)
		(fp_line
			(start -0.69215 0.2921)
			(end 0.69215 0.2921)
			(stroke
				(width 0.1524)
				(type default)
			)
			(layer "B.SilkS")
		)
		(fp_line
			(start 0.51435 -0.2794)
			(end -0.51435 -0.2794)
			(stroke
				(width 0.1)
				(type default)
			)
			(layer "B.Fab")
		)
		(fp_line
			(start -0.51435 -0.2794)
			(end -0.51435 0.2794)
			(stroke
				(width 0.1)
				(type default)
			)
			(layer "B.Fab")
		)
		(fp_line
			(start 0.51435 0.2794)
			(end 0.51435 -0.2794)
			(stroke
				(width 0.1)
				(type default)
			)
			(layer "B.Fab")
		)
		(fp_line
			(start -0.51435 0.2794)
			(end 0.51435 0.2794)
			(stroke
				(width 0.1)
				(type default)
			)
			(layer "B.Fab")
		)
		(pad "1" smd circle
			(at 0.40005 0 270)
			(size 0 0)
			(layers "B.Cu" "B.Mask" "B.Paste")
			(net "P3V3_AUX_FPGA_VCCIO5")
		)
		(pad "2" smd circle
			(at -0.40005 0 270)
			(size 0 0)
			(layers "B.Cu" "B.Mask" "B.Paste")
			(net "GND")
		)
		(zone
			(layer "B.Cu")
			(hatch none 0.5)
			(connect_pads
				(clearance 0)
			)
			(min_thickness 0.25)
			(keepout
				(tracks not_allowed)
				(vias allowed)
				(pads allowed)
				(copperpour not_allowed)
				(footprints allowed)
			)
			(placement
				(enabled no)
				(sheetname "")
			)
			(fill
				(thermal_gap 0.5)
				(thermal_bridge_width 0.5)
				(island_removal_mode 0)
			)
			(polygon
				(pts
					(xy 174.243238 -105.565956) (xy 174.301404 -105.474516) (xy 174.301404 -105.275126) (xy 174.243238 -105.184956)
					(xy 174.067978 -105.184956) (xy 174.009558 -105.275126) (xy 174.009558 -105.474516) (xy 174.067724 -105.565956)
				)
			)
		)
	)
	(footprint ""
		(layer "B.Cu")
		(at 482.66985 -184.609232 90)
		(property "Reference" "X45"
			(at -2.237232 4.72948 270)
			(unlocked yes)
			(layer "B.SilkS")
			(effects
				(font
					(size 0.7874 0.5842)
					(thickness 0.1524)
				)
				(justify left mirror)
			)
		)
		(property "Value" ""
			(at 0 0 90)
			(layer "B.Fab")
			(effects
				(font
					(size 1.27 1.27)
				)
				(justify mirror)
			)
		)
		(property "Device Type" "TP_TDR_4P_FTS_TH-TP_TDR_4P_DIPA"
			(at -1.30175 1.27 0)
			(unlocked yes)
			(layer "B.Fab")
			(hide yes)
			(effects
				(font
					(size 0.635 0.4064)
					(thickness 0.1524)
				)
				(justify mirror)
			)
		)
		(property "User Part Number" "N_A"
			(at -1.30175 1.27 0)
			(unlocked yes)
			(layer "Cmts.User")
			(hide yes)
			(effects
				(font
					(size 0.635 0.4064)
					(thickness 0.1524)
				)
				(justify mirror)
			)
		)
		(duplicate_pad_numbers_are_jumpers no)
		(fp_line
			(start 0 -1.27)
			(end 0 -0.635)
			(stroke
				(width 0.1524)
				(type default)
			)
			(layer "B.SilkS")
		)
		(fp_line
			(start -2.54 -1.27)
			(end 0 -1.27)
			(stroke
				(width 0.1524)
				(type default)
			)
			(layer "B.SilkS")
		)
		(fp_line
			(start -2.54 -1.1303)
			(end -2.54 -1.27)
			(stroke
				(width 0.1524)
				(type default)
			)
			(layer "B.SilkS")
		)
		(fp_line
			(start 0 0.635)
			(end 0 1.905)
			(stroke
				(width 0.1524)
				(type default)
			)
			(layer "B.SilkS")
		)
		(fp_line
			(start -2.54 1.4097)
			(end -2.54 1.1303)
			(stroke
				(width 0.1524)
				(type default)
			)
			(layer "B.SilkS")
		)
		(fp_line
			(start 0 3.175)
			(end 0 3.81)
			(stroke
				(width 0.1524)
				(type default)
			)
			(layer "B.SilkS")
		)
		(fp_line
			(start 0 3.81)
			(end -2.54 3.81)
			(stroke
				(width 0.1524)
				(type default)
			)
			(layer "B.SilkS")
		)
		(fp_line
			(start -2.54 3.81)
			(end -2.54 3.6703)
			(stroke
				(width 0.1524)
				(type default)
			)
			(layer "B.SilkS")
		)
		(fp_poly
			(pts
				(xy 0.761746 0) (xy 2.285746 -0.762) (xy 2.285746 0.762)
			)
			(stroke
				(width 0)
				(type default)
			)
			(fill yes)
			(layer "B.SilkS")
		)
		(fp_line
			(start 0 -1.27)
			(end 0 3.81)
			(stroke
				(width 0.1)
				(type default)
			)
			(layer "B.Fab")
		)
		(fp_line
			(start -2.54 -1.27)
			(end 0 -1.27)
			(stroke
				(width 0.1)
				(type default)
			)
			(layer "B.Fab")
		)
		(fp_line
			(start 0 3.81)
			(end -2.54 3.81)
			(stroke
				(width 0.1)
				(type default)
			)
			(layer "B.Fab")
		)
		(fp_line
			(start -2.54 3.81)
			(end -2.54 -1.27)
			(stroke
				(width 0.1)
				(type default)
			)
			(layer "B.Fab")
		)
		(fp_poly
			(pts
				(xy 0.761746 0) (xy 2.285746 -0.762) (xy 2.285746 0.762)
			)
			(stroke
				(width 0)
				(type default)
			)
			(fill yes)
			(layer "B.Fab")
		)
		(pad "1" thru_hole circle
			(at 0 0 270)
			(size 1.0033 1.0033)
			(drill 0.249936)
			(layers "*.Cu" "*.Mask")
			(remove_unused_layers no)
			(net "TDR_DIFF_85_NECK_IN4_DN")
			(clearance 0.10795)
			(padstack
				(mode front_inner_back)
				(layer "Inner"
					(shape circle)
					(size 0.8001 0.8001)
					(clearance 0.1524)
				)
				(layer "B.Cu"
					(shape circle)
					(size 1.0033 1.0033)
					(thermal_gap 0.10795)
					(clearance 0.10795)
				)
			)
		)
		(pad "2" thru_hole circle
			(at -2.54 0 270)
			(size 1.9939 1.9939)
			(drill 0.249936)
			(layers "*.Cu" "*.Mask")
			(remove_unused_layers no)
			(net "T1_GND")
			(clearance 0.10795)
			(padstack
				(mode front_inner_back)
				(layer "Inner"
					(shape circle)
					(size 0.8001 0.8001)
					(clearance 0.1524)
				)
				(layer "B.Cu"
					(shape circle)
					(size 1.9939 1.9939)
					(thermal_gap 0.10795)
					(clearance 0.10795)
				)
			)
		)
		(pad "3" thru_hole circle
			(at -2.54 2.54 270)
			(size 1.9939 1.9939)
			(drill 0.249936)
			(layers "*.Cu" "*.Mask")
			(remove_unused_layers no)
			(net "T1_GND")
			(clearance 0.10795)
			(padstack
				(mode front_inner_back)
				(layer "Inner"
					(shape circle)
					(size 0.8001 0.8001)
					(clearance 0.1524)
				)
				(layer "B.Cu"
					(shape circle)
					(size 1.9939 1.9939)
					(thermal_gap 0.10795)
					(clearance 0.10795)
				)
			)
		)
		(pad "4" thru_hole circle
			(at 0 2.54 270)
			(size 1.0033 1.0033)
			(drill 0.249936)
			(layers "*.Cu" "*.Mask")
			(remove_unused_layers no)
			(net "TDR_DIFF_85_NECK_IN4_DP")
			(clearance 0.10795)
			(padstack
				(mode front_inner_back)
				(layer "Inner"
					(shape circle)
					(size 0.8001 0.8001)
					(clearance 0.1524)
				)
				(layer "B.Cu"
					(shape circle)
					(size 1.0033 1.0033)
					(thermal_gap 0.10795)
					(clearance 0.10795)
				)
			)
		)
	)
	(footprint ""
		(layer "B.Cu")
		(at 168.133268 -356.42169 -90)
		(property "Reference" "PR1331"
			(at 0 0 90)
			(layer "B.SilkS")
			(hide yes)
			(effects
				(font
					(size 1.27 1.27)
				)
				(justify mirror)
			)
		)
		(property "Value" ""
			(at 0 0 90)
			(layer "B.Fab")
			(effects
				(font
					(size 1.27 1.27)
				)
				(justify mirror)
			)
		)
		(duplicate_pad_numbers_are_jumpers no)
		(fp_line
			(start -0.7874 0.4064)
			(end 0.7874 0.4064)
			(stroke
				(width 0.1524)
				(type default)
			)
			(layer "B.SilkS")
		)
		(fp_line
			(start 0.7874 0.4064)
			(end 0.7874 -0.4064)
			(stroke
				(width 0.1524)
				(type default)
			)
			(layer "B.SilkS")
		)
		(fp_line
			(start -0.7874 -0.4064)
			(end -0.7874 0.4064)
			(stroke
				(width 0.1524)
				(type default)
			)
			(layer "B.SilkS")
		)
		(fp_line
			(start 0.7874 -0.4064)
			(end -0.7874 -0.4064)
			(stroke
				(width 0.1524)
				(type default)
			)
			(layer "B.SilkS")
		)
		(fp_line
			(start -0.67945 0.3048)
			(end -0.120396 0.3048)
			(stroke
				(width 0.1)
				(type default)
			)
			(layer "B.Fab")
		)
		(fp_line
			(start -0.120396 0.3048)
			(end -0.120396 0.2794)
			(stroke
				(width 0.1)
				(type default)
			)
			(layer "B.Fab")
		)
		(fp_line
			(start 0.12065 0.3048)
			(end 0.67945 0.3048)
			(stroke
				(width 0.1)
				(type default)
			)
			(layer "B.Fab")
		)
		(fp_line
			(start 0.67945 0.3048)
			(end 0.67945 -0.305054)
			(stroke
				(width 0.1)
				(type default)
			)
			(layer "B.Fab")
		)
		(fp_line
			(start -0.120396 0.2794)
			(end 0.12065 0.2794)
			(stroke
				(width 0.1)
				(type default)
			)
			(layer "B.Fab")
		)
		(fp_line
			(start 0.12065 0.2794)
			(end 0.12065 0.3048)
			(stroke
				(width 0.1)
				(type default)
			)
			(layer "B.Fab")
		)
		(fp_line
			(start -0.12065 -0.2794)
			(end -0.12065 -0.3048)
			(stroke
				(width 0.1)
				(type default)
			)
			(layer "B.Fab")
		)
		(fp_line
			(start 0.12065 -0.2794)
			(end -0.12065 -0.2794)
			(stroke
				(width 0.1)
				(type default)
			)
			(layer "B.Fab")
		)
		(fp_line
			(start -0.67945 -0.3048)
			(end -0.67945 0.3048)
			(stroke
				(width 0.1)
				(type default)
			)
			(layer "B.Fab")
		)
		(fp_line
			(start -0.12065 -0.3048)
			(end -0.67945 -0.3048)
			(stroke
				(width 0.1)
				(type default)
			)
			(layer "B.Fab")
		)
		(fp_line
			(start 0.12065 -0.305054)
			(end 0.12065 -0.2794)
			(stroke
				(width 0.1)
				(type default)
			)
			(layer "B.Fab")
		)
		(fp_line
			(start 0.67945 -0.305054)
			(end 0.12065 -0.305054)
			(stroke
				(width 0.1)
				(type default)
			)
			(layer "B.Fab")
		)
		(pad "1" smd circle
			(at 0.40005 0 90)
			(size 0 0)
			(layers "B.Cu" "B.Mask" "B.Paste")
			(net "PVCCFA_EHV_FIVRA_CPU1_VOS1")
		)
		(pad "2" smd circle
			(at -0.40005 0 90)
			(size 0 0)
			(layers "B.Cu" "B.Mask" "B.Paste")
			(net "PVCCFA_EHV_FIVRA_CPU1")
		)
	)
	(footprint ""
		(layer "B.Cu")
		(at 286.268414 -321.549776 -90)
		(property "Reference" "C9"
			(at 0 0 90)
			(layer "B.SilkS")
			(hide yes)
			(effects
				(font
					(size 1.27 1.27)
				)
				(justify mirror)
			)
		)
		(property "Value" ""
			(at 0 0 90)
			(layer "B.Fab")
			(effects
				(font
					(size 1.27 1.27)
				)
				(justify mirror)
			)
		)
		(duplicate_pad_numbers_are_jumpers no)
		(fp_line
			(start -1.524 0.762)
			(end 1.524 0.762)
			(stroke
				(width 0.1524)
				(type default)
			)
			(layer "B.SilkS")
		)
		(fp_line
			(start 1.524 0.762)
			(end 1.524 -0.762)
			(stroke
				(width 0.1524)
				(type default)
			)
			(layer "B.SilkS")
		)
		(fp_line
			(start -1.524 -0.762)
			(end -1.524 0.762)
			(stroke
				(width 0.1524)
				(type default)
			)
			(layer "B.SilkS")
		)
		(fp_line
			(start 1.524 -0.762)
			(end -1.524 -0.762)
			(stroke
				(width 0.1524)
				(type default)
			)
			(layer "B.SilkS")
		)
		(fp_line
			(start -1.1049 0.724916)
			(end -1.1049 -0.724916)
			(stroke
				(width 0.1)
				(type default)
			)
			(layer "B.Fab")
		)
		(fp_line
			(start 1.1049 0.724916)
			(end -1.1049 0.724916)
			(stroke
				(width 0.1)
				(type default)
			)
			(layer "B.Fab")
		)
		(fp_line
			(start -1.1049 -0.724916)
			(end 1.1049 -0.724916)
			(stroke
				(width 0.1)
				(type default)
			)
			(layer "B.Fab")
		)
		(fp_line
			(start 1.1049 -0.724916)
			(end 1.1049 0.724916)
			(stroke
				(width 0.1)
				(type default)
			)
			(layer "B.Fab")
		)
		(pad "1" smd rect
			(at 0.889 0 270)
			(size 1.016 1.27)
			(layers "B.Cu" "B.Mask" "B.Paste")
			(net "P12V_S3_AUX_CPU0_NVDIMM")
		)
		(pad "2" smd rect
			(at -0.889 0 270)
			(size 1.016 1.27)
			(layers "B.Cu" "B.Mask" "B.Paste")
			(net "GND")
		)
	)
	(footprint ""
		(layer "B.Cu")
		(at 187.096654 -19.417792 -90)
		(property "Reference" "R2256"
			(at 0 0 90)
			(layer "B.SilkS")
			(hide yes)
			(effects
				(font
					(size 1.27 1.27)
				)
				(justify mirror)
			)
		)
		(property "Value" ""
			(at 0 0 90)
			(layer "B.Fab")
			(effects
				(font
					(size 1.27 1.27)
				)
				(justify mirror)
			)
		)
		(duplicate_pad_numbers_are_jumpers no)
		(fp_line
			(start -0.361696 0.4064)
			(end 0.522224 0.4064)
			(stroke
				(width 0.1524)
				(type default)
			)
			(layer "B.SilkS")
		)
		(fp_line
			(start 0.7874 0.137414)
			(end 0.7874 -0.4064)
			(stroke
				(width 0.1524)
				(type default)
			)
			(layer "B.SilkS")
		)
		(fp_line
			(start -0.7874 -0.4064)
			(end -0.7874 -0.055626)
			(stroke
				(width 0.1524)
				(type default)
			)
			(layer "B.SilkS")
		)
		(fp_line
			(start 0.7874 -0.4064)
			(end -0.7874 -0.4064)
			(stroke
				(width 0.1524)
				(type default)
			)
			(layer "B.SilkS")
		)
		(fp_line
			(start -0.67945 0.3048)
			(end -0.120396 0.3048)
			(stroke
				(width 0.1)
				(type default)
			)
			(layer "B.Fab")
		)
		(fp_line
			(start -0.120396 0.3048)
			(end -0.120396 0.2794)
			(stroke
				(width 0.1)
				(type default)
			)
			(layer "B.Fab")
		)
		(fp_line
			(start 0.12065 0.3048)
			(end 0.67945 0.3048)
			(stroke
				(width 0.1)
				(type default)
			)
			(layer "B.Fab")
		)
		(fp_line
			(start 0.67945 0.3048)
			(end 0.67945 -0.305054)
			(stroke
				(width 0.1)
				(type default)
			)
			(layer "B.Fab")
		)
		(fp_line
			(start -0.120396 0.2794)
			(end 0.12065 0.2794)
			(stroke
				(width 0.1)
				(type default)
			)
			(layer "B.Fab")
		)
		(fp_line
			(start 0.12065 0.2794)
			(end 0.12065 0.3048)
			(stroke
				(width 0.1)
				(type default)
			)
			(layer "B.Fab")
		)
		(fp_line
			(start -0.12065 -0.2794)
			(end -0.12065 -0.3048)
			(stroke
				(width 0.1)
				(type default)
			)
			(layer "B.Fab")
		)
		(fp_line
			(start 0.12065 -0.2794)
			(end -0.12065 -0.2794)
			(stroke
				(width 0.1)
				(type default)
			)
			(layer "B.Fab")
		)
		(fp_line
			(start -0.67945 -0.3048)
			(end -0.67945 0.3048)
			(stroke
				(width 0.1)
				(type default)
			)
			(layer "B.Fab")
		)
		(fp_line
			(start -0.12065 -0.3048)
			(end -0.67945 -0.3048)
			(stroke
				(width 0.1)
				(type default)
			)
			(layer "B.Fab")
		)
		(fp_line
			(start 0.12065 -0.305054)
			(end 0.12065 -0.2794)
			(stroke
				(width 0.1)
				(type default)
			)
			(layer "B.Fab")
		)
		(fp_line
			(start 0.67945 -0.305054)
			(end 0.12065 -0.305054)
			(stroke
				(width 0.1)
				(type default)
			)
			(layer "B.Fab")
		)
		(pad "1" smd circle
			(at 0.40005 0 90)
			(size 0 0)
			(layers "B.Cu" "B.Mask" "B.Paste")
			(net "USB2_7_R_DP")
		)
		(pad "2" smd circle
			(at -0.40005 0 90)
			(size 0 0)
			(layers "B.Cu" "B.Mask" "B.Paste")
			(net "USB2_7_DP")
		)
	)
	(footprint ""
		(layer "B.Cu")
		(at 169.66692 -53.431948 180)
		(property "Reference" "C1923"
			(at 0 0 0)
			(layer "B.SilkS")
			(hide yes)
			(effects
				(font
					(size 1.27 1.27)
				)
				(justify mirror)
			)
		)
		(property "Value" ""
			(at 0 0 0)
			(layer "B.Fab")
			(effects
				(font
					(size 1.27 1.27)
				)
				(justify mirror)
			)
		)
		(duplicate_pad_numbers_are_jumpers no)
		(fp_line
			(start 0.7874 0.4064)
			(end 0.7874 -0.4064)
			(stroke
				(width 0.1524)
				(type default)
			)
			(layer "B.SilkS")
		)
		(fp_line
			(start 0.7874 -0.4064)
			(end -0.7874 -0.4064)
			(stroke
				(width 0.1524)
				(type default)
			)
			(layer "B.SilkS")
		)
		(fp_line
			(start -0.7874 0.4064)
			(end 0.7874 0.4064)
			(stroke
				(width 0.1524)
				(type default)
			)
			(layer "B.SilkS")
		)
		(fp_line
			(start -0.7874 -0.4064)
			(end -0.7874 0.4064)
			(stroke
				(width 0.1524)
				(type default)
			)
			(layer "B.SilkS")
		)
		(fp_line
			(start 0.67945 0.3048)
			(end 0.67945 -0.305054)
			(stroke
				(width 0.1)
				(type default)
			)
			(layer "B.Fab")
		)
		(fp_line
			(start 0.67945 -0.305054)
			(end 0.12065 -0.305054)
			(stroke
				(width 0.1)
				(type default)
			)
			(layer "B.Fab")
		)
		(fp_line
			(start 0.12065 0.3048)
			(end 0.67945 0.3048)
			(stroke
				(width 0.1)
				(type default)
			)
			(layer "B.Fab")
		)
		(fp_line
			(start 0.12065 0.2794)
			(end 0.12065 0.3048)
			(stroke
				(width 0.1)
				(type default)
			)
			(layer "B.Fab")
		)
		(fp_line
			(start 0.12065 -0.2794)
			(end -0.12065 -0.2794)
			(stroke
				(width 0.1)
				(type default)
			)
			(layer "B.Fab")
		)
		(fp_line
			(start 0.12065 -0.305054)
			(end 0.12065 -0.2794)
			(stroke
				(width 0.1)
				(type default)
			)
			(layer "B.Fab")
		)
		(fp_line
			(start -0.120396 0.3048)
			(end -0.120396 0.2794)
			(stroke
				(width 0.1)
				(type default)
			)
			(layer "B.Fab")
		)
		(fp_line
			(start -0.120396 0.2794)
			(end 0.12065 0.2794)
			(stroke
				(width 0.1)
				(type default)
			)
			(layer "B.Fab")
		)
		(fp_line
			(start -0.12065 -0.2794)
			(end -0.12065 -0.3048)
			(stroke
				(width 0.1)
				(type default)
			)
			(layer "B.Fab")
		)
		(fp_line
			(start -0.12065 -0.3048)
			(end -0.67945 -0.3048)
			(stroke
				(width 0.1)
				(type default)
			)
			(layer "B.Fab")
		)
		(fp_line
			(start -0.67945 0.3048)
			(end -0.120396 0.3048)
			(stroke
				(width 0.1)
				(type default)
			)
			(layer "B.Fab")
		)
		(fp_line
			(start -0.67945 -0.3048)
			(end -0.67945 0.3048)
			(stroke
				(width 0.1)
				(type default)
			)
			(layer "B.Fab")
		)
		(pad "1" smd circle
			(at 0.40005 0)
			(size 0 0)
			(layers "B.Cu" "B.Mask" "B.Paste")
			(net "P3V3_M2_0")
		)
		(pad "2" smd circle
			(at -0.40005 0)
			(size 0 0)
			(layers "B.Cu" "B.Mask" "B.Paste")
			(net "GND")
		)
	)
	(footprint ""
		(layer "B.Cu")
		(at 48.666908 -193.25971 -90)
		(property "Reference" "R255"
			(at 0 0 90)
			(layer "B.SilkS")
			(hide yes)
			(effects
				(font
					(size 1.27 1.27)
				)
				(justify mirror)
			)
		)
		(property "Value" ""
			(at 0 0 90)
			(layer "B.Fab")
			(effects
				(font
					(size 1.27 1.27)
				)
				(justify mirror)
			)
		)
		(duplicate_pad_numbers_are_jumpers no)
		(fp_line
			(start -0.7874 0.4064)
			(end 0.7874 0.4064)
			(stroke
				(width 0.1524)
				(type default)
			)
			(layer "B.SilkS")
		)
		(fp_line
			(start 0.7874 0.4064)
			(end 0.7874 -0.4064)
			(stroke
				(width 0.1524)
				(type default)
			)
			(layer "B.SilkS")
		)
		(fp_line
			(start -0.7874 -0.4064)
			(end -0.7874 0.4064)
			(stroke
				(width 0.1524)
				(type default)
			)
			(layer "B.SilkS")
		)
		(fp_line
			(start 0.7874 -0.4064)
			(end -0.7874 -0.4064)
			(stroke
				(width 0.1524)
				(type default)
			)
			(layer "B.SilkS")
		)
		(fp_line
			(start -0.67945 0.3048)
			(end -0.120396 0.3048)
			(stroke
				(width 0.1)
				(type default)
			)
			(layer "B.Fab")
		)
		(fp_line
			(start -0.120396 0.3048)
			(end -0.120396 0.2794)
			(stroke
				(width 0.1)
				(type default)
			)
			(layer "B.Fab")
		)
		(fp_line
			(start 0.12065 0.3048)
			(end 0.67945 0.3048)
			(stroke
				(width 0.1)
				(type default)
			)
			(layer "B.Fab")
		)
		(fp_line
			(start 0.67945 0.3048)
			(end 0.67945 -0.305054)
			(stroke
				(width 0.1)
				(type default)
			)
			(layer "B.Fab")
		)
		(fp_line
			(start -0.120396 0.2794)
			(end 0.12065 0.2794)
			(stroke
				(width 0.1)
				(type default)
			)
			(layer "B.Fab")
		)
		(fp_line
			(start 0.12065 0.2794)
			(end 0.12065 0.3048)
			(stroke
				(width 0.1)
				(type default)
			)
			(layer "B.Fab")
		)
		(fp_line
			(start -0.12065 -0.2794)
			(end -0.12065 -0.3048)
			(stroke
				(width 0.1)
				(type default)
			)
			(layer "B.Fab")
		)
		(fp_line
			(start 0.12065 -0.2794)
			(end -0.12065 -0.2794)
			(stroke
				(width 0.1)
				(type default)
			)
			(layer "B.Fab")
		)
		(fp_line
			(start -0.67945 -0.3048)
			(end -0.67945 0.3048)
			(stroke
				(width 0.1)
				(type default)
			)
			(layer "B.Fab")
		)
		(fp_line
			(start -0.12065 -0.3048)
			(end -0.67945 -0.3048)
			(stroke
				(width 0.1)
				(type default)
			)
			(layer "B.Fab")
		)
		(fp_line
			(start 0.12065 -0.305054)
			(end 0.12065 -0.2794)
			(stroke
				(width 0.1)
				(type default)
			)
			(layer "B.Fab")
		)
		(fp_line
			(start 0.67945 -0.305054)
			(end 0.12065 -0.305054)
			(stroke
				(width 0.1)
				(type default)
			)
			(layer "B.Fab")
		)
		(pad "1" smd circle
			(at 0.40005 0 90)
			(size 0 0)
			(layers "B.Cu" "B.Mask" "B.Paste")
			(net "PVNN_TERM_CPU1")
		)
		(pad "2" smd circle
			(at -0.40005 0 90)
			(size 0 0)
			(layers "B.Cu" "B.Mask" "B.Paste")
			(net "FM_S3M_CPU1_LVC1_GPIO_0")
		)
	)
	(footprint ""
		(layer "B.Cu")
		(at 410.816044 -258.207764 -90)
		(property "Reference" "C514"
			(at 0 0 90)
			(layer "B.SilkS")
			(hide yes)
			(effects
				(font
					(size 1.27 1.27)
				)
				(justify mirror)
			)
		)
		(property "Value" ""
			(at 0 0 90)
			(layer "B.Fab")
			(effects
				(font
					(size 1.27 1.27)
				)
				(justify mirror)
			)
		)
		(duplicate_pad_numbers_are_jumpers no)
		(fp_line
			(start -1.524 0.762)
			(end 1.524 0.762)
			(stroke
				(width 0.1524)
				(type default)
			)
			(layer "B.SilkS")
		)
		(fp_line
			(start 1.524 0.762)
			(end 1.524 -0.762)
			(stroke
				(width 0.1524)
				(type default)
			)
			(layer "B.SilkS")
		)
		(fp_line
			(start -1.524 -0.762)
			(end -1.524 0.762)
			(stroke
				(width 0.1524)
				(type default)
			)
			(layer "B.SilkS")
		)
		(fp_line
			(start 1.524 -0.762)
			(end -1.524 -0.762)
			(stroke
				(width 0.1524)
				(type default)
			)
			(layer "B.SilkS")
		)
		(fp_line
			(start -1.1049 0.724916)
			(end -1.1049 -0.724916)
			(stroke
				(width 0.1)
				(type default)
			)
			(layer "B.Fab")
		)
		(fp_line
			(start 1.1049 0.724916)
			(end -1.1049 0.724916)
			(stroke
				(width 0.1)
				(type default)
			)
			(layer "B.Fab")
		)
		(fp_line
			(start -1.1049 -0.724916)
			(end 1.1049 -0.724916)
			(stroke
				(width 0.1)
				(type default)
			)
			(layer "B.Fab")
		)
		(fp_line
			(start 1.1049 -0.724916)
			(end 1.1049 0.724916)
			(stroke
				(width 0.1)
				(type default)
			)
			(layer "B.Fab")
		)
		(pad "1" smd rect
			(at 0.889 0 270)
			(size 1.016 1.27)
			(layers "B.Cu" "B.Mask" "B.Paste")
			(net "PVCCFA_EHV_FIVRA_CPU0")
		)
		(pad "2" smd rect
			(at -0.889 0 270)
			(size 1.016 1.27)
			(layers "B.Cu" "B.Mask" "B.Paste")
			(net "GND")
		)
	)
	(footprint ""
		(layer "B.Cu")
		(at 345.657932 -324.873366 -90)
		(property "Reference" "PC312_P0_1"
			(at 0 0 90)
			(layer "B.SilkS")
			(hide yes)
			(effects
				(font
					(size 1.27 1.27)
				)
				(justify mirror)
			)
		)
		(property "Value" ""
			(at 0 0 90)
			(layer "B.Fab")
			(effects
				(font
					(size 1.27 1.27)
				)
				(justify mirror)
			)
		)
		(duplicate_pad_numbers_are_jumpers no)
		(fp_line
			(start -1.524 0.762)
			(end 1.524 0.762)
			(stroke
				(width 0.1524)
				(type default)
			)
			(layer "B.SilkS")
		)
		(fp_line
			(start 1.524 0.762)
			(end 1.524 -0.762)
			(stroke
				(width 0.1524)
				(type default)
			)
			(layer "B.SilkS")
		)
		(fp_line
			(start -1.524 -0.762)
			(end -1.524 0.762)
			(stroke
				(width 0.1524)
				(type default)
			)
			(layer "B.SilkS")
		)
		(fp_line
			(start 1.524 -0.762)
			(end -1.524 -0.762)
			(stroke
				(width 0.1524)
				(type default)
			)
			(layer "B.SilkS")
		)
		(fp_line
			(start -1.1049 0.724916)
			(end -1.1049 -0.724916)
			(stroke
				(width 0.1)
				(type default)
			)
			(layer "B.Fab")
		)
		(fp_line
			(start 1.1049 0.724916)
			(end -1.1049 0.724916)
			(stroke
				(width 0.1)
				(type default)
			)
			(layer "B.Fab")
		)
		(fp_line
			(start -1.1049 -0.724916)
			(end 1.1049 -0.724916)
			(stroke
				(width 0.1)
				(type default)
			)
			(layer "B.Fab")
		)
		(fp_line
			(start 1.1049 -0.724916)
			(end 1.1049 0.724916)
			(stroke
				(width 0.1)
				(type default)
			)
			(layer "B.Fab")
		)
		(pad "1" smd rect
			(at 0.889 0 270)
			(size 1.016 1.27)
			(layers "B.Cu" "B.Mask" "B.Paste")
			(net "PVCCIN_CPU0")
		)
		(pad "2" smd rect
			(at -0.889 0 270)
			(size 1.016 1.27)
			(layers "B.Cu" "B.Mask" "B.Paste")
			(net "GND")
		)
	)
	(footprint ""
		(layer "B.Cu")
		(at 95.225108 -190.705232 90)
		(property "Reference" "R671"
			(at 0 0 90)
			(layer "B.SilkS")
			(hide yes)
			(effects
				(font
					(size 1.27 1.27)
				)
				(justify mirror)
			)
		)
		(property "Value" ""
			(at 0 0 90)
			(layer "B.Fab")
			(effects
				(font
					(size 1.27 1.27)
				)
				(justify mirror)
			)
		)
		(duplicate_pad_numbers_are_jumpers no)
		(fp_line
			(start 0.7874 -0.4064)
			(end -0.7874 -0.4064)
			(stroke
				(width 0.1524)
				(type default)
			)
			(layer "B.SilkS")
		)
		(fp_line
			(start -0.7874 -0.4064)
			(end -0.7874 0.4064)
			(stroke
				(width 0.1524)
				(type default)
			)
			(layer "B.SilkS")
		)
		(fp_line
			(start 0.7874 0.4064)
			(end 0.7874 -0.4064)
			(stroke
				(width 0.1524)
				(type default)
			)
			(layer "B.SilkS")
		)
		(fp_line
			(start -0.7874 0.4064)
			(end 0.7874 0.4064)
			(stroke
				(width 0.1524)
				(type default)
			)
			(layer "B.SilkS")
		)
		(fp_line
			(start 0.67945 -0.305054)
			(end 0.12065 -0.305054)
			(stroke
				(width 0.1)
				(type default)
			)
			(layer "B.Fab")
		)
		(fp_line
			(start 0.12065 -0.305054)
			(end 0.12065 -0.2794)
			(stroke
				(width 0.1)
				(type default)
			)
			(layer "B.Fab")
		)
		(fp_line
			(start -0.12065 -0.3048)
			(end -0.67945 -0.3048)
			(stroke
				(width 0.1)
				(type default)
			)
			(layer "B.Fab")
		)
		(fp_line
			(start -0.67945 -0.3048)
			(end -0.67945 0.3048)
			(stroke
				(width 0.1)
				(type default)
			)
			(layer "B.Fab")
		)
		(fp_line
			(start 0.12065 -0.2794)
			(end -0.12065 -0.2794)
			(stroke
				(width 0.1)
				(type default)
			)
			(layer "B.Fab")
		)
		(fp_line
			(start -0.12065 -0.2794)
			(end -0.12065 -0.3048)
			(stroke
				(width 0.1)
				(type default)
			)
			(layer "B.Fab")
		)
		(fp_line
			(start 0.12065 0.2794)
			(end 0.12065 0.3048)
			(stroke
				(width 0.1)
				(type default)
			)
			(layer "B.Fab")
		)
		(fp_line
			(start -0.120396 0.2794)
			(end 0.12065 0.2794)
			(stroke
				(width 0.1)
				(type default)
			)
			(layer "B.Fab")
		)
		(fp_line
			(start 0.67945 0.3048)
			(end 0.67945 -0.305054)
			(stroke
				(width 0.1)
				(type default)
			)
			(layer "B.Fab")
		)
		(fp_line
			(start 0.12065 0.3048)
			(end 0.67945 0.3048)
			(stroke
				(width 0.1)
				(type default)
			)
			(layer "B.Fab")
		)
		(fp_line
			(start -0.120396 0.3048)
			(end -0.120396 0.2794)
			(stroke
				(width 0.1)
				(type default)
			)
			(layer "B.Fab")
		)
		(fp_line
			(start -0.67945 0.3048)
			(end -0.120396 0.3048)
			(stroke
				(width 0.1)
				(type default)
			)
			(layer "B.Fab")
		)
		(pad "1" smd circle
			(at 0.40005 0 270)
			(size 0 0)
			(layers "B.Cu" "B.Mask" "B.Paste")
			(net "I3C_SPD_DDRABCD_CPU1_SDA")
		)
		(pad "2" smd circle
			(at -0.40005 0 270)
			(size 0 0)
			(layers "B.Cu" "B.Mask" "B.Paste")
			(net "I3C_SPD_DDRABCD_CPU1_R_SDA")
		)
	)
	(footprint ""
		(layer "B.Cu")
		(at 32.557212 -318.650112)
		(property "Reference" "R47"
			(at 0 0 0)
			(layer "B.SilkS")
			(hide yes)
			(effects
				(font
					(size 1.27 1.27)
				)
				(justify mirror)
			)
		)
		(property "Value" ""
			(at 0 0 0)
			(layer "B.Fab")
			(effects
				(font
					(size 1.27 1.27)
				)
				(justify mirror)
			)
		)
		(duplicate_pad_numbers_are_jumpers no)
		(fp_line
			(start -0.7874 -0.4064)
			(end -0.7874 0.4064)
			(stroke
				(width 0.1524)
				(type default)
			)
			(layer "B.SilkS")
		)
		(fp_line
			(start -0.7874 0.4064)
			(end 0.7874 0.4064)
			(stroke
				(width 0.1524)
				(type default)
			)
			(layer "B.SilkS")
		)
		(fp_line
			(start 0.7874 -0.4064)
			(end -0.7874 -0.4064)
			(stroke
				(width 0.1524)
				(type default)
			)
			(layer "B.SilkS")
		)
		(fp_line
			(start 0.7874 0.4064)
			(end 0.7874 -0.4064)
			(stroke
				(width 0.1524)
				(type default)
			)
			(layer "B.SilkS")
		)
		(fp_line
			(start -0.67945 -0.3048)
			(end -0.67945 0.3048)
			(stroke
				(width 0.1)
				(type default)
			)
			(layer "B.Fab")
		)
		(fp_line
			(start -0.67945 0.3048)
			(end -0.120396 0.3048)
			(stroke
				(width 0.1)
				(type default)
			)
			(layer "B.Fab")
		)
		(fp_line
			(start -0.12065 -0.3048)
			(end -0.67945 -0.3048)
			(stroke
				(width 0.1)
				(type default)
			)
			(layer "B.Fab")
		)
		(fp_line
			(start -0.12065 -0.2794)
			(end -0.12065 -0.3048)
			(stroke
				(width 0.1)
				(type default)
			)
			(layer "B.Fab")
		)
		(fp_line
			(start -0.120396 0.2794)
			(end 0.12065 0.2794)
			(stroke
				(width 0.1)
				(type default)
			)
			(layer "B.Fab")
		)
		(fp_line
			(start -0.120396 0.3048)
			(end -0.120396 0.2794)
			(stroke
				(width 0.1)
				(type default)
			)
			(layer "B.Fab")
		)
		(fp_line
			(start 0.12065 -0.305054)
			(end 0.12065 -0.2794)
			(stroke
				(width 0.1)
				(type default)
			)
			(layer "B.Fab")
		)
		(fp_line
			(start 0.12065 -0.2794)
			(end -0.12065 -0.2794)
			(stroke
				(width 0.1)
				(type default)
			)
			(layer "B.Fab")
		)
		(fp_line
			(start 0.12065 0.2794)
			(end 0.12065 0.3048)
			(stroke
				(width 0.1)
				(type default)
			)
			(layer "B.Fab")
		)
		(fp_line
			(start 0.12065 0.3048)
			(end 0.67945 0.3048)
			(stroke
				(width 0.1)
				(type default)
			)
			(layer "B.Fab")
		)
		(fp_line
			(start 0.67945 -0.305054)
			(end 0.12065 -0.305054)
			(stroke
				(width 0.1)
				(type default)
			)
			(layer "B.Fab")
		)
		(fp_line
			(start 0.67945 0.3048)
			(end 0.67945 -0.305054)
			(stroke
				(width 0.1)
				(type default)
			)
			(layer "B.Fab")
		)
		(pad "1" smd circle
			(at 0.40005 0 180)
			(size 0 0)
			(layers "B.Cu" "B.Mask" "B.Paste")
			(net "PD_CHC_CPU1_DIMM2_SAA")
		)
		(pad "2" smd circle
			(at -0.40005 0 180)
			(size 0 0)
			(layers "B.Cu" "B.Mask" "B.Paste")
			(net "GND")
		)
	)
	(footprint ""
		(layer "B.Cu")
		(at 290.301934 -319.068958 -90)
		(property "Reference" "R2728"
			(at 0 0 90)
			(layer "B.SilkS")
			(hide yes)
			(effects
				(font
					(size 1.27 1.27)
				)
				(justify mirror)
			)
		)
		(property "Value" ""
			(at 0 0 90)
			(layer "B.Fab")
			(effects
				(font
					(size 1.27 1.27)
				)
				(justify mirror)
			)
		)
		(duplicate_pad_numbers_are_jumpers no)
		(fp_line
			(start -0.7874 0.4064)
			(end 0.7874 0.4064)
			(stroke
				(width 0.1524)
				(type default)
			)
			(layer "B.SilkS")
		)
		(fp_line
			(start 0.7874 0.4064)
			(end 0.7874 -0.4064)
			(stroke
				(width 0.1524)
				(type default)
			)
			(layer "B.SilkS")
		)
		(fp_line
			(start -0.7874 -0.4064)
			(end -0.7874 0.4064)
			(stroke
				(width 0.1524)
				(type default)
			)
			(layer "B.SilkS")
		)
		(fp_line
			(start 0.7874 -0.4064)
			(end -0.7874 -0.4064)
			(stroke
				(width 0.1524)
				(type default)
			)
			(layer "B.SilkS")
		)
		(fp_line
			(start -0.67945 0.3048)
			(end -0.120396 0.3048)
			(stroke
				(width 0.1)
				(type default)
			)
			(layer "B.Fab")
		)
		(fp_line
			(start -0.120396 0.3048)
			(end -0.120396 0.2794)
			(stroke
				(width 0.1)
				(type default)
			)
			(layer "B.Fab")
		)
		(fp_line
			(start 0.12065 0.3048)
			(end 0.67945 0.3048)
			(stroke
				(width 0.1)
				(type default)
			)
			(layer "B.Fab")
		)
		(fp_line
			(start 0.67945 0.3048)
			(end 0.67945 -0.305054)
			(stroke
				(width 0.1)
				(type default)
			)
			(layer "B.Fab")
		)
		(fp_line
			(start -0.120396 0.2794)
			(end 0.12065 0.2794)
			(stroke
				(width 0.1)
				(type default)
			)
			(layer "B.Fab")
		)
		(fp_line
			(start 0.12065 0.2794)
			(end 0.12065 0.3048)
			(stroke
				(width 0.1)
				(type default)
			)
			(layer "B.Fab")
		)
		(fp_line
			(start -0.12065 -0.2794)
			(end -0.12065 -0.3048)
			(stroke
				(width 0.1)
				(type default)
			)
			(layer "B.Fab")
		)
		(fp_line
			(start 0.12065 -0.2794)
			(end -0.12065 -0.2794)
			(stroke
				(width 0.1)
				(type default)
			)
			(layer "B.Fab")
		)
		(fp_line
			(start -0.67945 -0.3048)
			(end -0.67945 0.3048)
			(stroke
				(width 0.1)
				(type default)
			)
			(layer "B.Fab")
		)
		(fp_line
			(start -0.12065 -0.3048)
			(end -0.67945 -0.3048)
			(stroke
				(width 0.1)
				(type default)
			)
			(layer "B.Fab")
		)
		(fp_line
			(start 0.12065 -0.305054)
			(end 0.12065 -0.2794)
			(stroke
				(width 0.1)
				(type default)
			)
			(layer "B.Fab")
		)
		(fp_line
			(start 0.67945 -0.305054)
			(end 0.12065 -0.305054)
			(stroke
				(width 0.1)
				(type default)
			)
			(layer "B.Fab")
		)
		(pad "1" smd circle
			(at 0.40005 0 90)
			(size 0 0)
			(layers "B.Cu" "B.Mask" "B.Paste")
			(net "PWRGD_CHB_CPU0_DIMM1")
		)
		(pad "2" smd circle
			(at -0.40005 0 90)
			(size 0 0)
			(layers "B.Cu" "B.Mask" "B.Paste")
			(net "PWRGD_FAIL_CPU0_AB")
		)
	)
	(footprint ""
		(layer "B.Cu")
		(at 164.64788 -116.296948 180)
		(property "Reference" "R1919"
			(at 0 0 0)
			(layer "B.SilkS")
			(hide yes)
			(effects
				(font
					(size 1.27 1.27)
				)
				(justify mirror)
			)
		)
		(property "Value" ""
			(at 0 0 0)
			(layer "B.Fab")
			(effects
				(font
					(size 1.27 1.27)
				)
				(justify mirror)
			)
		)
		(duplicate_pad_numbers_are_jumpers no)
		(fp_line
			(start 0.7874 0.4064)
			(end 0.7874 -0.4064)
			(stroke
				(width 0.1524)
				(type default)
			)
			(layer "B.SilkS")
		)
		(fp_line
			(start 0.7874 -0.4064)
			(end -0.7874 -0.4064)
			(stroke
				(width 0.1524)
				(type default)
			)
			(layer "B.SilkS")
		)
		(fp_line
			(start -0.7874 0.4064)
			(end 0.7874 0.4064)
			(stroke
				(width 0.1524)
				(type default)
			)
			(layer "B.SilkS")
		)
		(fp_line
			(start -0.7874 -0.4064)
			(end -0.7874 0.4064)
			(stroke
				(width 0.1524)
				(type default)
			)
			(layer "B.SilkS")
		)
		(fp_line
			(start 0.67945 0.3048)
			(end 0.67945 -0.305054)
			(stroke
				(width 0.1)
				(type default)
			)
			(layer "B.Fab")
		)
		(fp_line
			(start 0.67945 -0.305054)
			(end 0.12065 -0.305054)
			(stroke
				(width 0.1)
				(type default)
			)
			(layer "B.Fab")
		)
		(fp_line
			(start 0.12065 0.3048)
			(end 0.67945 0.3048)
			(stroke
				(width 0.1)
				(type default)
			)
			(layer "B.Fab")
		)
		(fp_line
			(start 0.12065 0.2794)
			(end 0.12065 0.3048)
			(stroke
				(width 0.1)
				(type default)
			)
			(layer "B.Fab")
		)
		(fp_line
			(start 0.12065 -0.2794)
			(end -0.12065 -0.2794)
			(stroke
				(width 0.1)
				(type default)
			)
			(layer "B.Fab")
		)
		(fp_line
			(start 0.12065 -0.305054)
			(end 0.12065 -0.2794)
			(stroke
				(width 0.1)
				(type default)
			)
			(layer "B.Fab")
		)
		(fp_line
			(start -0.120396 0.3048)
			(end -0.120396 0.2794)
			(stroke
				(width 0.1)
				(type default)
			)
			(layer "B.Fab")
		)
		(fp_line
			(start -0.120396 0.2794)
			(end 0.12065 0.2794)
			(stroke
				(width 0.1)
				(type default)
			)
			(layer "B.Fab")
		)
		(fp_line
			(start -0.12065 -0.2794)
			(end -0.12065 -0.3048)
			(stroke
				(width 0.1)
				(type default)
			)
			(layer "B.Fab")
		)
		(fp_line
			(start -0.12065 -0.3048)
			(end -0.67945 -0.3048)
			(stroke
				(width 0.1)
				(type default)
			)
			(layer "B.Fab")
		)
		(fp_line
			(start -0.67945 0.3048)
			(end -0.120396 0.3048)
			(stroke
				(width 0.1)
				(type default)
			)
			(layer "B.Fab")
		)
		(fp_line
			(start -0.67945 -0.3048)
			(end -0.67945 0.3048)
			(stroke
				(width 0.1)
				(type default)
			)
			(layer "B.Fab")
		)
		(pad "1" smd circle
			(at 0.40005 0)
			(size 0 0)
			(layers "B.Cu" "B.Mask" "B.Paste")
			(net "PWRGD_P3V3_AUX")
		)
		(pad "2" smd circle
			(at -0.40005 0)
			(size 0 0)
			(layers "B.Cu" "B.Mask" "B.Paste")
			(net "PWRGD_P3V3_AUX_PLD")
		)
	)
	(footprint ""
		(layer "B.Cu")
		(at 183.755538 -121.375424 -90)
		(property "Reference" "C1911"
			(at 0 0 90)
			(layer "B.SilkS")
			(hide yes)
			(effects
				(font
					(size 1.27 1.27)
				)
				(justify mirror)
			)
		)
		(property "Value" ""
			(at 0 0 90)
			(layer "B.Fab")
			(effects
				(font
					(size 1.27 1.27)
				)
				(justify mirror)
			)
		)
		(duplicate_pad_numbers_are_jumpers no)
		(fp_line
			(start -0.69215 0.2921)
			(end 0.69215 0.2921)
			(stroke
				(width 0.1524)
				(type default)
			)
			(layer "B.SilkS")
		)
		(fp_line
			(start 0.69215 0.2921)
			(end 0.69215 -0.2921)
			(stroke
				(width 0.1524)
				(type default)
			)
			(layer "B.SilkS")
		)
		(fp_line
			(start -0.69215 -0.2921)
			(end -0.69215 0.2921)
			(stroke
				(width 0.1524)
				(type default)
			)
			(layer "B.SilkS")
		)
		(fp_line
			(start 0.69215 -0.2921)
			(end -0.69215 -0.2921)
			(stroke
				(width 0.1524)
				(type default)
			)
			(layer "B.SilkS")
		)
		(fp_line
			(start -0.51435 0.2794)
			(end 0.51435 0.2794)
			(stroke
				(width 0.1)
				(type default)
			)
			(layer "B.Fab")
		)
		(fp_line
			(start 0.51435 0.2794)
			(end 0.51435 -0.2794)
			(stroke
				(width 0.1)
				(type default)
			)
			(layer "B.Fab")
		)
		(fp_line
			(start -0.51435 -0.2794)
			(end -0.51435 0.2794)
			(stroke
				(width 0.1)
				(type default)
			)
			(layer "B.Fab")
		)
		(fp_line
			(start 0.51435 -0.2794)
			(end -0.51435 -0.2794)
			(stroke
				(width 0.1)
				(type default)
			)
			(layer "B.Fab")
		)
		(pad "1" smd circle
			(at 0.40005 0 90)
			(size 0 0)
			(layers "B.Cu" "B.Mask" "B.Paste")
			(net "P3V3_AUX_FPGA_VCCIO1")
		)
		(pad "2" smd circle
			(at -0.40005 0 90)
			(size 0 0)
			(layers "B.Cu" "B.Mask" "B.Paste")
			(net "GND")
		)
		(zone
			(layer "B.Cu")
			(hatch none 0.5)
			(connect_pads
				(clearance 0)
			)
			(min_thickness 0.25)
			(keepout
				(tracks not_allowed)
				(vias allowed)
				(pads allowed)
				(copperpour not_allowed)
				(footprints allowed)
			)
			(placement
				(enabled no)
				(sheetname "")
			)
			(fill
				(thermal_gap 0.5)
				(thermal_bridge_width 0.5)
				(island_removal_mode 0)
			)
			(polygon
				(pts
					(xy 183.667908 -121.184924) (xy 183.609742 -121.276364) (xy 183.609742 -121.475754) (xy 183.667908 -121.565924)
					(xy 183.843168 -121.565924) (xy 183.901588 -121.475754) (xy 183.901588 -121.276364) (xy 183.843422 -121.184924)
				)
			)
		)
	)
	(footprint ""
		(layer "B.Cu")
		(at 303.554638 -194.72021 90)
		(property "Reference" "R14"
			(at 0 0 90)
			(layer "B.SilkS")
			(hide yes)
			(effects
				(font
					(size 1.27 1.27)
				)
				(justify mirror)
			)
		)
		(property "Value" ""
			(at 0 0 90)
			(layer "B.Fab")
			(effects
				(font
					(size 1.27 1.27)
				)
				(justify mirror)
			)
		)
		(duplicate_pad_numbers_are_jumpers no)
		(fp_line
			(start 0.7874 -0.4064)
			(end -0.7874 -0.4064)
			(stroke
				(width 0.1524)
				(type default)
			)
			(layer "B.SilkS")
		)
		(fp_line
			(start -0.7874 -0.4064)
			(end -0.7874 0.4064)
			(stroke
				(width 0.1524)
				(type default)
			)
			(layer "B.SilkS")
		)
		(fp_line
			(start 0.7874 0.4064)
			(end 0.7874 -0.4064)
			(stroke
				(width 0.1524)
				(type default)
			)
			(layer "B.SilkS")
		)
		(fp_line
			(start -0.7874 0.4064)
			(end 0.7874 0.4064)
			(stroke
				(width 0.1524)
				(type default)
			)
			(layer "B.SilkS")
		)
		(fp_line
			(start 0.67945 -0.305054)
			(end 0.12065 -0.305054)
			(stroke
				(width 0.1)
				(type default)
			)
			(layer "B.Fab")
		)
		(fp_line
			(start 0.12065 -0.305054)
			(end 0.12065 -0.2794)
			(stroke
				(width 0.1)
				(type default)
			)
			(layer "B.Fab")
		)
		(fp_line
			(start -0.12065 -0.3048)
			(end -0.67945 -0.3048)
			(stroke
				(width 0.1)
				(type default)
			)
			(layer "B.Fab")
		)
		(fp_line
			(start -0.67945 -0.3048)
			(end -0.67945 0.3048)
			(stroke
				(width 0.1)
				(type default)
			)
			(layer "B.Fab")
		)
		(fp_line
			(start 0.12065 -0.2794)
			(end -0.12065 -0.2794)
			(stroke
				(width 0.1)
				(type default)
			)
			(layer "B.Fab")
		)
		(fp_line
			(start -0.12065 -0.2794)
			(end -0.12065 -0.3048)
			(stroke
				(width 0.1)
				(type default)
			)
			(layer "B.Fab")
		)
		(fp_line
			(start 0.12065 0.2794)
			(end 0.12065 0.3048)
			(stroke
				(width 0.1)
				(type default)
			)
			(layer "B.Fab")
		)
		(fp_line
			(start -0.120396 0.2794)
			(end 0.12065 0.2794)
			(stroke
				(width 0.1)
				(type default)
			)
			(layer "B.Fab")
		)
		(fp_line
			(start 0.67945 0.3048)
			(end 0.67945 -0.305054)
			(stroke
				(width 0.1)
				(type default)
			)
			(layer "B.Fab")
		)
		(fp_line
			(start 0.12065 0.3048)
			(end 0.67945 0.3048)
			(stroke
				(width 0.1)
				(type default)
			)
			(layer "B.Fab")
		)
		(fp_line
			(start -0.120396 0.3048)
			(end -0.120396 0.2794)
			(stroke
				(width 0.1)
				(type default)
			)
			(layer "B.Fab")
		)
		(fp_line
			(start -0.67945 0.3048)
			(end -0.120396 0.3048)
			(stroke
				(width 0.1)
				(type default)
			)
			(layer "B.Fab")
		)
		(pad "1" smd circle
			(at 0.40005 0 270)
			(size 0 0)
			(layers "B.Cu" "B.Mask" "B.Paste")
			(net "SVID_ALERT0_CPU0_N")
		)
		(pad "2" smd circle
			(at -0.40005 0 270)
			(size 0 0)
			(layers "B.Cu" "B.Mask" "B.Paste")
			(net "SVID_ALERT0_CPU0_R_N")
		)
	)
	(footprint ""
		(layer "B.Cu")
		(at 103.979218 -241.20729 90)
		(property "Reference" "C474"
			(at 0 0 90)
			(layer "B.SilkS")
			(hide yes)
			(effects
				(font
					(size 1.27 1.27)
				)
				(justify mirror)
			)
		)
		(property "Value" ""
			(at 0 0 90)
			(layer "B.Fab")
			(effects
				(font
					(size 1.27 1.27)
				)
				(justify mirror)
			)
		)
		(duplicate_pad_numbers_are_jumpers no)
		(fp_line
			(start 1.524 -0.762)
			(end -1.524 -0.762)
			(stroke
				(width 0.1524)
				(type default)
			)
			(layer "B.SilkS")
		)
		(fp_line
			(start -1.524 -0.762)
			(end -1.524 0.762)
			(stroke
				(width 0.1524)
				(type default)
			)
			(layer "B.SilkS")
		)
		(fp_line
			(start 1.524 0.762)
			(end 1.524 -0.762)
			(stroke
				(width 0.1524)
				(type default)
			)
			(layer "B.SilkS")
		)
		(fp_line
			(start -1.524 0.762)
			(end 1.524 0.762)
			(stroke
				(width 0.1524)
				(type default)
			)
			(layer "B.SilkS")
		)
		(fp_line
			(start 1.1049 -0.724916)
			(end 1.1049 0.724916)
			(stroke
				(width 0.1)
				(type default)
			)
			(layer "B.Fab")
		)
		(fp_line
			(start -1.1049 -0.724916)
			(end 1.1049 -0.724916)
			(stroke
				(width 0.1)
				(type default)
			)
			(layer "B.Fab")
		)
		(fp_line
			(start 1.1049 0.724916)
			(end -1.1049 0.724916)
			(stroke
				(width 0.1)
				(type default)
			)
			(layer "B.Fab")
		)
		(fp_line
			(start -1.1049 0.724916)
			(end -1.1049 -0.724916)
			(stroke
				(width 0.1)
				(type default)
			)
			(layer "B.Fab")
		)
		(pad "1" smd rect
			(at 0.889 0 90)
			(size 1.016 1.27)
			(layers "B.Cu" "B.Mask" "B.Paste")
			(net "PVCCD_HV_CPU1")
		)
		(pad "2" smd rect
			(at -0.889 0 90)
			(size 1.016 1.27)
			(layers "B.Cu" "B.Mask" "B.Paste")
			(net "GND")
		)
	)
	(footprint ""
		(layer "B.Cu")
		(at 174.997618 -200.403968 -90)
		(property "Reference" "R265"
			(at 0 0 90)
			(layer "B.SilkS")
			(hide yes)
			(effects
				(font
					(size 1.27 1.27)
				)
				(justify mirror)
			)
		)
		(property "Value" ""
			(at 0 0 90)
			(layer "B.Fab")
			(effects
				(font
					(size 1.27 1.27)
				)
				(justify mirror)
			)
		)
		(duplicate_pad_numbers_are_jumpers no)
		(fp_line
			(start -0.7874 0.4064)
			(end 0.7874 0.4064)
			(stroke
				(width 0.1524)
				(type default)
			)
			(layer "B.SilkS")
		)
		(fp_line
			(start 0.7874 0.4064)
			(end 0.7874 -0.4064)
			(stroke
				(width 0.1524)
				(type default)
			)
			(layer "B.SilkS")
		)
		(fp_line
			(start -0.7874 -0.4064)
			(end -0.7874 0.4064)
			(stroke
				(width 0.1524)
				(type default)
			)
			(layer "B.SilkS")
		)
		(fp_line
			(start 0.7874 -0.4064)
			(end -0.7874 -0.4064)
			(stroke
				(width 0.1524)
				(type default)
			)
			(layer "B.SilkS")
		)
		(fp_line
			(start -0.67945 0.3048)
			(end -0.120396 0.3048)
			(stroke
				(width 0.1)
				(type default)
			)
			(layer "B.Fab")
		)
		(fp_line
			(start -0.120396 0.3048)
			(end -0.120396 0.2794)
			(stroke
				(width 0.1)
				(type default)
			)
			(layer "B.Fab")
		)
		(fp_line
			(start 0.12065 0.3048)
			(end 0.67945 0.3048)
			(stroke
				(width 0.1)
				(type default)
			)
			(layer "B.Fab")
		)
		(fp_line
			(start 0.67945 0.3048)
			(end 0.67945 -0.305054)
			(stroke
				(width 0.1)
				(type default)
			)
			(layer "B.Fab")
		)
		(fp_line
			(start -0.120396 0.2794)
			(end 0.12065 0.2794)
			(stroke
				(width 0.1)
				(type default)
			)
			(layer "B.Fab")
		)
		(fp_line
			(start 0.12065 0.2794)
			(end 0.12065 0.3048)
			(stroke
				(width 0.1)
				(type default)
			)
			(layer "B.Fab")
		)
		(fp_line
			(start -0.12065 -0.2794)
			(end -0.12065 -0.3048)
			(stroke
				(width 0.1)
				(type default)
			)
			(layer "B.Fab")
		)
		(fp_line
			(start 0.12065 -0.2794)
			(end -0.12065 -0.2794)
			(stroke
				(width 0.1)
				(type default)
			)
			(layer "B.Fab")
		)
		(fp_line
			(start -0.67945 -0.3048)
			(end -0.67945 0.3048)
			(stroke
				(width 0.1)
				(type default)
			)
			(layer "B.Fab")
		)
		(fp_line
			(start -0.12065 -0.3048)
			(end -0.67945 -0.3048)
			(stroke
				(width 0.1)
				(type default)
			)
			(layer "B.Fab")
		)
		(fp_line
			(start 0.12065 -0.305054)
			(end 0.12065 -0.2794)
			(stroke
				(width 0.1)
				(type default)
			)
			(layer "B.Fab")
		)
		(fp_line
			(start 0.67945 -0.305054)
			(end 0.12065 -0.305054)
			(stroke
				(width 0.1)
				(type default)
			)
			(layer "B.Fab")
		)
		(pad "1" smd circle
			(at 0.40005 0 90)
			(size 0 0)
			(layers "B.Cu" "B.Mask" "B.Paste")
			(net "PVNN_TERM_CPU1")
		)
		(pad "2" smd circle
			(at -0.40005 0 90)
			(size 0 0)
			(layers "B.Cu" "B.Mask" "B.Paste")
			(net "PU_CPU1_SOCKET_ID0")
		)
	)
	(footprint ""
		(layer "B.Cu")
		(at 66.149982 -15.32763)
		(property "Reference" "C1834"
			(at 0 0 0)
			(layer "B.SilkS")
			(hide yes)
			(effects
				(font
					(size 1.27 1.27)
				)
				(justify mirror)
			)
		)
		(property "Value" ""
			(at 0 0 0)
			(layer "B.Fab")
			(effects
				(font
					(size 1.27 1.27)
				)
				(justify mirror)
			)
		)
		(duplicate_pad_numbers_are_jumpers no)
		(fp_line
			(start -0.7874 -0.4064)
			(end -0.7874 0.4064)
			(stroke
				(width 0.1524)
				(type default)
			)
			(layer "B.SilkS")
		)
		(fp_line
			(start -0.7874 0.4064)
			(end 0.7874 0.4064)
			(stroke
				(width 0.1524)
				(type default)
			)
			(layer "B.SilkS")
		)
		(fp_line
			(start 0.7874 -0.4064)
			(end -0.7874 -0.4064)
			(stroke
				(width 0.1524)
				(type default)
			)
			(layer "B.SilkS")
		)
		(fp_line
			(start 0.7874 0.4064)
			(end 0.7874 -0.4064)
			(stroke
				(width 0.1524)
				(type default)
			)
			(layer "B.SilkS")
		)
		(fp_line
			(start -0.67945 -0.3048)
			(end -0.67945 0.3048)
			(stroke
				(width 0.1)
				(type default)
			)
			(layer "B.Fab")
		)
		(fp_line
			(start -0.67945 0.3048)
			(end -0.120396 0.3048)
			(stroke
				(width 0.1)
				(type default)
			)
			(layer "B.Fab")
		)
		(fp_line
			(start -0.12065 -0.3048)
			(end -0.67945 -0.3048)
			(stroke
				(width 0.1)
				(type default)
			)
			(layer "B.Fab")
		)
		(fp_line
			(start -0.12065 -0.2794)
			(end -0.12065 -0.3048)
			(stroke
				(width 0.1)
				(type default)
			)
			(layer "B.Fab")
		)
		(fp_line
			(start -0.120396 0.2794)
			(end 0.12065 0.2794)
			(stroke
				(width 0.1)
				(type default)
			)
			(layer "B.Fab")
		)
		(fp_line
			(start -0.120396 0.3048)
			(end -0.120396 0.2794)
			(stroke
				(width 0.1)
				(type default)
			)
			(layer "B.Fab")
		)
		(fp_line
			(start 0.12065 -0.305054)
			(end 0.12065 -0.2794)
			(stroke
				(width 0.1)
				(type default)
			)
			(layer "B.Fab")
		)
		(fp_line
			(start 0.12065 -0.2794)
			(end -0.12065 -0.2794)
			(stroke
				(width 0.1)
				(type default)
			)
			(layer "B.Fab")
		)
		(fp_line
			(start 0.12065 0.2794)
			(end 0.12065 0.3048)
			(stroke
				(width 0.1)
				(type default)
			)
			(layer "B.Fab")
		)
		(fp_line
			(start 0.12065 0.3048)
			(end 0.67945 0.3048)
			(stroke
				(width 0.1)
				(type default)
			)
			(layer "B.Fab")
		)
		(fp_line
			(start 0.67945 -0.305054)
			(end 0.12065 -0.305054)
			(stroke
				(width 0.1)
				(type default)
			)
			(layer "B.Fab")
		)
		(fp_line
			(start 0.67945 0.3048)
			(end 0.67945 -0.305054)
			(stroke
				(width 0.1)
				(type default)
			)
			(layer "B.Fab")
		)
		(pad "1" smd circle
			(at 0.40005 0 180)
			(size 0 0)
			(layers "B.Cu" "B.Mask" "B.Paste")
			(net "P12V_OCP_V3_2")
		)
		(pad "2" smd circle
			(at -0.40005 0 180)
			(size 0 0)
			(layers "B.Cu" "B.Mask" "B.Paste")
			(net "GND")
		)
	)
	(footprint ""
		(layer "B.Cu")
		(at 174.814738 -97.32137 -90)
		(property "Reference" "R1326"
			(at 0 0 90)
			(layer "B.SilkS")
			(hide yes)
			(effects
				(font
					(size 1.27 1.27)
				)
				(justify mirror)
			)
		)
		(property "Value" ""
			(at 0 0 90)
			(layer "B.Fab")
			(effects
				(font
					(size 1.27 1.27)
				)
				(justify mirror)
			)
		)
		(duplicate_pad_numbers_are_jumpers no)
		(fp_line
			(start -0.7874 0.4064)
			(end 0.7874 0.4064)
			(stroke
				(width 0.1524)
				(type default)
			)
			(layer "B.SilkS")
		)
		(fp_line
			(start 0.7874 0.4064)
			(end 0.7874 -0.4064)
			(stroke
				(width 0.1524)
				(type default)
			)
			(layer "B.SilkS")
		)
		(fp_line
			(start -0.7874 -0.4064)
			(end -0.7874 0.4064)
			(stroke
				(width 0.1524)
				(type default)
			)
			(layer "B.SilkS")
		)
		(fp_line
			(start 0.7874 -0.4064)
			(end -0.7874 -0.4064)
			(stroke
				(width 0.1524)
				(type default)
			)
			(layer "B.SilkS")
		)
		(fp_line
			(start -0.67945 0.3048)
			(end -0.120396 0.3048)
			(stroke
				(width 0.1)
				(type default)
			)
			(layer "B.Fab")
		)
		(fp_line
			(start -0.120396 0.3048)
			(end -0.120396 0.2794)
			(stroke
				(width 0.1)
				(type default)
			)
			(layer "B.Fab")
		)
		(fp_line
			(start 0.12065 0.3048)
			(end 0.67945 0.3048)
			(stroke
				(width 0.1)
				(type default)
			)
			(layer "B.Fab")
		)
		(fp_line
			(start 0.67945 0.3048)
			(end 0.67945 -0.305054)
			(stroke
				(width 0.1)
				(type default)
			)
			(layer "B.Fab")
		)
		(fp_line
			(start -0.120396 0.2794)
			(end 0.12065 0.2794)
			(stroke
				(width 0.1)
				(type default)
			)
			(layer "B.Fab")
		)
		(fp_line
			(start 0.12065 0.2794)
			(end 0.12065 0.3048)
			(stroke
				(width 0.1)
				(type default)
			)
			(layer "B.Fab")
		)
		(fp_line
			(start -0.12065 -0.2794)
			(end -0.12065 -0.3048)
			(stroke
				(width 0.1)
				(type default)
			)
			(layer "B.Fab")
		)
		(fp_line
			(start 0.12065 -0.2794)
			(end -0.12065 -0.2794)
			(stroke
				(width 0.1)
				(type default)
			)
			(layer "B.Fab")
		)
		(fp_line
			(start -0.67945 -0.3048)
			(end -0.67945 0.3048)
			(stroke
				(width 0.1)
				(type default)
			)
			(layer "B.Fab")
		)
		(fp_line
			(start -0.12065 -0.3048)
			(end -0.67945 -0.3048)
			(stroke
				(width 0.1)
				(type default)
			)
			(layer "B.Fab")
		)
		(fp_line
			(start 0.12065 -0.305054)
			(end 0.12065 -0.2794)
			(stroke
				(width 0.1)
				(type default)
			)
			(layer "B.Fab")
		)
		(fp_line
			(start 0.67945 -0.305054)
			(end 0.12065 -0.305054)
			(stroke
				(width 0.1)
				(type default)
			)
			(layer "B.Fab")
		)
		(pad "1" smd circle
			(at 0.40005 0 90)
			(size 0 0)
			(layers "B.Cu" "B.Mask" "B.Paste")
			(net "PWRGD_DRAMPWRGD_CPU0_CD_R_LVC1")
		)
		(pad "2" smd circle
			(at -0.40005 0 90)
			(size 0 0)
			(layers "B.Cu" "B.Mask" "B.Paste")
			(net "GND")
		)
	)
	(footprint ""
		(layer "B.Cu")
		(at 327.522586 -333.628492 -90)
		(property "Reference" "PC247_P0_7"
			(at 0 0 90)
			(layer "B.SilkS")
			(hide yes)
			(effects
				(font
					(size 1.27 1.27)
				)
				(justify mirror)
			)
		)
		(property "Value" ""
			(at 0 0 90)
			(layer "B.Fab")
			(effects
				(font
					(size 1.27 1.27)
				)
				(justify mirror)
			)
		)
		(duplicate_pad_numbers_are_jumpers no)
		(fp_line
			(start -1.524 0.762)
			(end 1.524 0.762)
			(stroke
				(width 0.1524)
				(type default)
			)
			(layer "B.SilkS")
		)
		(fp_line
			(start 1.524 0.762)
			(end 1.524 -0.762)
			(stroke
				(width 0.1524)
				(type default)
			)
			(layer "B.SilkS")
		)
		(fp_line
			(start -1.524 -0.762)
			(end -1.524 0.762)
			(stroke
				(width 0.1524)
				(type default)
			)
			(layer "B.SilkS")
		)
		(fp_line
			(start 1.524 -0.762)
			(end -1.524 -0.762)
			(stroke
				(width 0.1524)
				(type default)
			)
			(layer "B.SilkS")
		)
		(fp_line
			(start -1.1049 0.724916)
			(end -1.1049 -0.724916)
			(stroke
				(width 0.1)
				(type default)
			)
			(layer "B.Fab")
		)
		(fp_line
			(start 1.1049 0.724916)
			(end -1.1049 0.724916)
			(stroke
				(width 0.1)
				(type default)
			)
			(layer "B.Fab")
		)
		(fp_line
			(start -1.1049 -0.724916)
			(end 1.1049 -0.724916)
			(stroke
				(width 0.1)
				(type default)
			)
			(layer "B.Fab")
		)
		(fp_line
			(start 1.1049 -0.724916)
			(end 1.1049 0.724916)
			(stroke
				(width 0.1)
				(type default)
			)
			(layer "B.Fab")
		)
		(pad "1" smd rect
			(at 0.889 0 270)
			(size 1.016 1.27)
			(layers "B.Cu" "B.Mask" "B.Paste")
			(net "PVCCIN_CPU0")
		)
		(pad "2" smd rect
			(at -0.889 0 270)
			(size 1.016 1.27)
			(layers "B.Cu" "B.Mask" "B.Paste")
			(net "GND")
		)
	)
	(footprint ""
		(layer "B.Cu")
		(at 409.30957 -156.642054 180)
		(property "Reference" "PC184"
			(at 0 0 0)
			(layer "B.SilkS")
			(hide yes)
			(effects
				(font
					(size 1.27 1.27)
				)
				(justify mirror)
			)
		)
		(property "Value" ""
			(at 0 0 0)
			(layer "B.Fab")
			(effects
				(font
					(size 1.27 1.27)
				)
				(justify mirror)
			)
		)
		(duplicate_pad_numbers_are_jumpers no)
		(fp_line
			(start 1.524 0.762)
			(end 1.524 -0.762)
			(stroke
				(width 0.1524)
				(type default)
			)
			(layer "B.SilkS")
		)
		(fp_line
			(start 1.524 -0.762)
			(end -1.524 -0.762)
			(stroke
				(width 0.1524)
				(type default)
			)
			(layer "B.SilkS")
		)
		(fp_line
			(start -1.524 0.762)
			(end 1.524 0.762)
			(stroke
				(width 0.1524)
				(type default)
			)
			(layer "B.SilkS")
		)
		(fp_line
			(start -1.524 -0.762)
			(end -1.524 0.762)
			(stroke
				(width 0.1524)
				(type default)
			)
			(layer "B.SilkS")
		)
		(fp_line
			(start 1.1049 0.724916)
			(end -1.1049 0.724916)
			(stroke
				(width 0.1)
				(type default)
			)
			(layer "B.Fab")
		)
		(fp_line
			(start 1.1049 -0.724916)
			(end 1.1049 0.724916)
			(stroke
				(width 0.1)
				(type default)
			)
			(layer "B.Fab")
		)
		(fp_line
			(start -1.1049 0.724916)
			(end -1.1049 -0.724916)
			(stroke
				(width 0.1)
				(type default)
			)
			(layer "B.Fab")
		)
		(fp_line
			(start -1.1049 -0.724916)
			(end 1.1049 -0.724916)
			(stroke
				(width 0.1)
				(type default)
			)
			(layer "B.Fab")
		)
		(pad "1" smd rect
			(at 0.889 0 180)
			(size 1.016 1.27)
			(layers "B.Cu" "B.Mask" "B.Paste")
			(net "PVCCFA_EHV_CPU0")
		)
		(pad "2" smd rect
			(at -0.889 0 180)
			(size 1.016 1.27)
			(layers "B.Cu" "B.Mask" "B.Paste")
			(net "GND")
		)
	)
	(footprint ""
		(layer "B.Cu")
		(at 177.123344 -192.699894 -90)
		(property "Reference" "R266"
			(at 0 0 90)
			(layer "B.SilkS")
			(hide yes)
			(effects
				(font
					(size 1.27 1.27)
				)
				(justify mirror)
			)
		)
		(property "Value" ""
			(at 0 0 90)
			(layer "B.Fab")
			(effects
				(font
					(size 1.27 1.27)
				)
				(justify mirror)
			)
		)
		(duplicate_pad_numbers_are_jumpers no)
		(fp_line
			(start -0.7874 0.4064)
			(end 0.7874 0.4064)
			(stroke
				(width 0.1524)
				(type default)
			)
			(layer "B.SilkS")
		)
		(fp_line
			(start 0.7874 0.4064)
			(end 0.7874 -0.4064)
			(stroke
				(width 0.1524)
				(type default)
			)
			(layer "B.SilkS")
		)
		(fp_line
			(start -0.7874 -0.4064)
			(end -0.7874 0.4064)
			(stroke
				(width 0.1524)
				(type default)
			)
			(layer "B.SilkS")
		)
		(fp_line
			(start 0.7874 -0.4064)
			(end -0.7874 -0.4064)
			(stroke
				(width 0.1524)
				(type default)
			)
			(layer "B.SilkS")
		)
		(fp_line
			(start -0.67945 0.3048)
			(end -0.120396 0.3048)
			(stroke
				(width 0.1)
				(type default)
			)
			(layer "B.Fab")
		)
		(fp_line
			(start -0.120396 0.3048)
			(end -0.120396 0.2794)
			(stroke
				(width 0.1)
				(type default)
			)
			(layer "B.Fab")
		)
		(fp_line
			(start 0.12065 0.3048)
			(end 0.67945 0.3048)
			(stroke
				(width 0.1)
				(type default)
			)
			(layer "B.Fab")
		)
		(fp_line
			(start 0.67945 0.3048)
			(end 0.67945 -0.305054)
			(stroke
				(width 0.1)
				(type default)
			)
			(layer "B.Fab")
		)
		(fp_line
			(start -0.120396 0.2794)
			(end 0.12065 0.2794)
			(stroke
				(width 0.1)
				(type default)
			)
			(layer "B.Fab")
		)
		(fp_line
			(start 0.12065 0.2794)
			(end 0.12065 0.3048)
			(stroke
				(width 0.1)
				(type default)
			)
			(layer "B.Fab")
		)
		(fp_line
			(start -0.12065 -0.2794)
			(end -0.12065 -0.3048)
			(stroke
				(width 0.1)
				(type default)
			)
			(layer "B.Fab")
		)
		(fp_line
			(start 0.12065 -0.2794)
			(end -0.12065 -0.2794)
			(stroke
				(width 0.1)
				(type default)
			)
			(layer "B.Fab")
		)
		(fp_line
			(start -0.67945 -0.3048)
			(end -0.67945 0.3048)
			(stroke
				(width 0.1)
				(type default)
			)
			(layer "B.Fab")
		)
		(fp_line
			(start -0.12065 -0.3048)
			(end -0.67945 -0.3048)
			(stroke
				(width 0.1)
				(type default)
			)
			(layer "B.Fab")
		)
		(fp_line
			(start 0.12065 -0.305054)
			(end 0.12065 -0.2794)
			(stroke
				(width 0.1)
				(type default)
			)
			(layer "B.Fab")
		)
		(fp_line
			(start 0.67945 -0.305054)
			(end 0.12065 -0.305054)
			(stroke
				(width 0.1)
				(type default)
			)
			(layer "B.Fab")
		)
		(pad "1" smd circle
			(at 0.40005 0 90)
			(size 0 0)
			(layers "B.Cu" "B.Mask" "B.Paste")
			(net "PVNN_TERM_CPU1")
		)
		(pad "2" smd circle
			(at -0.40005 0 90)
			(size 0 0)
			(layers "B.Cu" "B.Mask" "B.Paste")
			(net "PU_CPU1_SOCKET_ID1")
		)
	)
	(footprint ""
		(layer "B.Cu")
		(at 299.596048 -362.795058 90)
		(property "Reference" "PC609_P0_2"
			(at 0 0 90)
			(layer "B.SilkS")
			(hide yes)
			(effects
				(font
					(size 1.27 1.27)
				)
				(justify mirror)
			)
		)
		(property "Value" ""
			(at 0 0 90)
			(layer "B.Fab")
			(effects
				(font
					(size 1.27 1.27)
				)
				(justify mirror)
			)
		)
		(duplicate_pad_numbers_are_jumpers no)
		(fp_line
			(start 1.524 -0.762)
			(end -1.524 -0.762)
			(stroke
				(width 0.1524)
				(type default)
			)
			(layer "B.SilkS")
		)
		(fp_line
			(start -1.524 -0.762)
			(end -1.524 0.762)
			(stroke
				(width 0.1524)
				(type default)
			)
			(layer "B.SilkS")
		)
		(fp_line
			(start 1.524 0.762)
			(end 1.524 -0.762)
			(stroke
				(width 0.1524)
				(type default)
			)
			(layer "B.SilkS")
		)
		(fp_line
			(start -1.524 0.762)
			(end 1.524 0.762)
			(stroke
				(width 0.1524)
				(type default)
			)
			(layer "B.SilkS")
		)
		(fp_line
			(start 1.1049 -0.724916)
			(end 1.1049 0.724916)
			(stroke
				(width 0.1)
				(type default)
			)
			(layer "B.Fab")
		)
		(fp_line
			(start -1.1049 -0.724916)
			(end 1.1049 -0.724916)
			(stroke
				(width 0.1)
				(type default)
			)
			(layer "B.Fab")
		)
		(fp_line
			(start 1.1049 0.724916)
			(end -1.1049 0.724916)
			(stroke
				(width 0.1)
				(type default)
			)
			(layer "B.Fab")
		)
		(fp_line
			(start -1.1049 0.724916)
			(end -1.1049 -0.724916)
			(stroke
				(width 0.1)
				(type default)
			)
			(layer "B.Fab")
		)
		(pad "1" smd rect
			(at 0.889 0 90)
			(size 1.016 1.27)
			(layers "B.Cu" "B.Mask" "B.Paste")
			(net "SW_P12V_PVCCFA_EHV_FIVRA_CPU0_L")
		)
		(pad "2" smd rect
			(at -0.889 0 90)
			(size 1.016 1.27)
			(layers "B.Cu" "B.Mask" "B.Paste")
			(net "GND")
		)
	)
	(footprint ""
		(layer "B.Cu")
		(at 27.0383 -131.55295 180)
		(property "Reference" "PR258"
			(at 0 0 0)
			(layer "B.SilkS")
			(hide yes)
			(effects
				(font
					(size 1.27 1.27)
				)
				(justify mirror)
			)
		)
		(property "Value" ""
			(at 0 0 0)
			(layer "B.Fab")
			(effects
				(font
					(size 1.27 1.27)
				)
				(justify mirror)
			)
		)
		(duplicate_pad_numbers_are_jumpers no)
		(fp_line
			(start 0.7874 0.4064)
			(end 0.7874 -0.4064)
			(stroke
				(width 0.1524)
				(type default)
			)
			(layer "B.SilkS")
		)
		(fp_line
			(start 0.7874 -0.4064)
			(end -0.7874 -0.4064)
			(stroke
				(width 0.1524)
				(type default)
			)
			(layer "B.SilkS")
		)
		(fp_line
			(start -0.7874 0.4064)
			(end 0.7874 0.4064)
			(stroke
				(width 0.1524)
				(type default)
			)
			(layer "B.SilkS")
		)
		(fp_line
			(start -0.7874 -0.4064)
			(end -0.7874 0.4064)
			(stroke
				(width 0.1524)
				(type default)
			)
			(layer "B.SilkS")
		)
		(fp_line
			(start 0.67945 0.3048)
			(end 0.67945 -0.305054)
			(stroke
				(width 0.1)
				(type default)
			)
			(layer "B.Fab")
		)
		(fp_line
			(start 0.67945 -0.305054)
			(end 0.12065 -0.305054)
			(stroke
				(width 0.1)
				(type default)
			)
			(layer "B.Fab")
		)
		(fp_line
			(start 0.12065 0.3048)
			(end 0.67945 0.3048)
			(stroke
				(width 0.1)
				(type default)
			)
			(layer "B.Fab")
		)
		(fp_line
			(start 0.12065 0.2794)
			(end 0.12065 0.3048)
			(stroke
				(width 0.1)
				(type default)
			)
			(layer "B.Fab")
		)
		(fp_line
			(start 0.12065 -0.2794)
			(end -0.12065 -0.2794)
			(stroke
				(width 0.1)
				(type default)
			)
			(layer "B.Fab")
		)
		(fp_line
			(start 0.12065 -0.305054)
			(end 0.12065 -0.2794)
			(stroke
				(width 0.1)
				(type default)
			)
			(layer "B.Fab")
		)
		(fp_line
			(start -0.120396 0.3048)
			(end -0.120396 0.2794)
			(stroke
				(width 0.1)
				(type default)
			)
			(layer "B.Fab")
		)
		(fp_line
			(start -0.120396 0.2794)
			(end 0.12065 0.2794)
			(stroke
				(width 0.1)
				(type default)
			)
			(layer "B.Fab")
		)
		(fp_line
			(start -0.12065 -0.2794)
			(end -0.12065 -0.3048)
			(stroke
				(width 0.1)
				(type default)
			)
			(layer "B.Fab")
		)
		(fp_line
			(start -0.12065 -0.3048)
			(end -0.67945 -0.3048)
			(stroke
				(width 0.1)
				(type default)
			)
			(layer "B.Fab")
		)
		(fp_line
			(start -0.67945 0.3048)
			(end -0.120396 0.3048)
			(stroke
				(width 0.1)
				(type default)
			)
			(layer "B.Fab")
		)
		(fp_line
			(start -0.67945 -0.3048)
			(end -0.67945 0.3048)
			(stroke
				(width 0.1)
				(type default)
			)
			(layer "B.Fab")
		)
		(pad "1" smd circle
			(at 0.40005 0)
			(size 0 0)
			(layers "B.Cu" "B.Mask" "B.Paste")
			(net "PVCCINFAON_CPU1_VREF")
		)
		(pad "2" smd circle
			(at -0.40005 0)
			(size 0 0)
			(layers "B.Cu" "B.Mask" "B.Paste")
			(net "PVCCINFAON_CPU1_ADDR")
		)
	)
	(footprint ""
		(layer "B.Cu")
		(at 352.097848 -54.435756 90)
		(property "Reference" "C1259"
			(at 0 0 90)
			(layer "B.SilkS")
			(hide yes)
			(effects
				(font
					(size 1.27 1.27)
				)
				(justify mirror)
			)
		)
		(property "Value" ""
			(at 0 0 90)
			(layer "B.Fab")
			(effects
				(font
					(size 1.27 1.27)
				)
				(justify mirror)
			)
		)
		(duplicate_pad_numbers_are_jumpers no)
		(fp_line
			(start 1.524 -0.762)
			(end -1.524 -0.762)
			(stroke
				(width 0.1524)
				(type default)
			)
			(layer "B.SilkS")
		)
		(fp_line
			(start -1.524 -0.762)
			(end -1.524 0.762)
			(stroke
				(width 0.1524)
				(type default)
			)
			(layer "B.SilkS")
		)
		(fp_line
			(start 1.524 0.762)
			(end 1.524 -0.762)
			(stroke
				(width 0.1524)
				(type default)
			)
			(layer "B.SilkS")
		)
		(fp_line
			(start -1.524 0.762)
			(end 1.524 0.762)
			(stroke
				(width 0.1524)
				(type default)
			)
			(layer "B.SilkS")
		)
		(fp_line
			(start 1.1049 -0.724916)
			(end 1.1049 0.724916)
			(stroke
				(width 0.1)
				(type default)
			)
			(layer "B.Fab")
		)
		(fp_line
			(start -1.1049 -0.724916)
			(end 1.1049 -0.724916)
			(stroke
				(width 0.1)
				(type default)
			)
			(layer "B.Fab")
		)
		(fp_line
			(start 1.1049 0.724916)
			(end -1.1049 0.724916)
			(stroke
				(width 0.1)
				(type default)
			)
			(layer "B.Fab")
		)
		(fp_line
			(start -1.1049 0.724916)
			(end -1.1049 -0.724916)
			(stroke
				(width 0.1)
				(type default)
			)
			(layer "B.Fab")
		)
		(pad "1" smd rect
			(at 0.889 0 90)
			(size 1.016 1.27)
			(layers "B.Cu" "B.Mask" "B.Paste")
			(net "P1V8_PCH_PLL_AUX")
		)
		(pad "2" smd rect
			(at -0.889 0 90)
			(size 1.016 1.27)
			(layers "B.Cu" "B.Mask" "B.Paste")
			(net "GND")
		)
	)
	(footprint ""
		(layer "B.Cu")
		(at 259.37464 -49.430686 180)
		(property "Reference" "PC2341"
			(at 0 0 0)
			(layer "B.SilkS")
			(hide yes)
			(effects
				(font
					(size 1.27 1.27)
				)
				(justify mirror)
			)
		)
		(property "Value" ""
			(at 0 0 0)
			(layer "B.Fab")
			(effects
				(font
					(size 1.27 1.27)
				)
				(justify mirror)
			)
		)
		(duplicate_pad_numbers_are_jumpers no)
		(fp_line
			(start 0.7874 0.4064)
			(end 0.7874 -0.4064)
			(stroke
				(width 0.1524)
				(type default)
			)
			(layer "B.SilkS")
		)
		(fp_line
			(start 0.7874 -0.4064)
			(end -0.7874 -0.4064)
			(stroke
				(width 0.1524)
				(type default)
			)
			(layer "B.SilkS")
		)
		(fp_line
			(start -0.7874 0.4064)
			(end 0.7874 0.4064)
			(stroke
				(width 0.1524)
				(type default)
			)
			(layer "B.SilkS")
		)
		(fp_line
			(start -0.7874 -0.4064)
			(end -0.7874 0.4064)
			(stroke
				(width 0.1524)
				(type default)
			)
			(layer "B.SilkS")
		)
		(fp_line
			(start 0.67945 0.3048)
			(end 0.67945 -0.305054)
			(stroke
				(width 0.1)
				(type default)
			)
			(layer "B.Fab")
		)
		(fp_line
			(start 0.67945 -0.305054)
			(end 0.12065 -0.305054)
			(stroke
				(width 0.1)
				(type default)
			)
			(layer "B.Fab")
		)
		(fp_line
			(start 0.12065 0.3048)
			(end 0.67945 0.3048)
			(stroke
				(width 0.1)
				(type default)
			)
			(layer "B.Fab")
		)
		(fp_line
			(start 0.12065 0.2794)
			(end 0.12065 0.3048)
			(stroke
				(width 0.1)
				(type default)
			)
			(layer "B.Fab")
		)
		(fp_line
			(start 0.12065 -0.2794)
			(end -0.12065 -0.2794)
			(stroke
				(width 0.1)
				(type default)
			)
			(layer "B.Fab")
		)
		(fp_line
			(start 0.12065 -0.305054)
			(end 0.12065 -0.2794)
			(stroke
				(width 0.1)
				(type default)
			)
			(layer "B.Fab")
		)
		(fp_line
			(start -0.120396 0.3048)
			(end -0.120396 0.2794)
			(stroke
				(width 0.1)
				(type default)
			)
			(layer "B.Fab")
		)
		(fp_line
			(start -0.120396 0.2794)
			(end 0.12065 0.2794)
			(stroke
				(width 0.1)
				(type default)
			)
			(layer "B.Fab")
		)
		(fp_line
			(start -0.12065 -0.2794)
			(end -0.12065 -0.3048)
			(stroke
				(width 0.1)
				(type default)
			)
			(layer "B.Fab")
		)
		(fp_line
			(start -0.12065 -0.3048)
			(end -0.67945 -0.3048)
			(stroke
				(width 0.1)
				(type default)
			)
			(layer "B.Fab")
		)
		(fp_line
			(start -0.67945 0.3048)
			(end -0.120396 0.3048)
			(stroke
				(width 0.1)
				(type default)
			)
			(layer "B.Fab")
		)
		(fp_line
			(start -0.67945 -0.3048)
			(end -0.67945 0.3048)
			(stroke
				(width 0.1)
				(type default)
			)
			(layer "B.Fab")
		)
		(pad "1" smd circle
			(at 0.40005 0)
			(size 0 0)
			(layers "B.Cu" "B.Mask" "B.Paste")
			(net "P12V_E1S_ISET_0_R")
		)
		(pad "2" smd circle
			(at -0.40005 0)
			(size 0 0)
			(layers "B.Cu" "B.Mask" "B.Paste")
			(net "GND")
		)
	)
	(footprint ""
		(layer "B.Cu")
		(at 372.613936 -325.098156 -90)
		(property "Reference" "PC310_P0_1"
			(at 0 0 90)
			(layer "B.SilkS")
			(hide yes)
			(effects
				(font
					(size 1.27 1.27)
				)
				(justify mirror)
			)
		)
		(property "Value" ""
			(at 0 0 90)
			(layer "B.Fab")
			(effects
				(font
					(size 1.27 1.27)
				)
				(justify mirror)
			)
		)
		(duplicate_pad_numbers_are_jumpers no)
		(fp_line
			(start -0.7874 0.4064)
			(end 0.7874 0.4064)
			(stroke
				(width 0.1524)
				(type default)
			)
			(layer "B.SilkS")
		)
		(fp_line
			(start 0.7874 0.4064)
			(end 0.7874 -0.4064)
			(stroke
				(width 0.1524)
				(type default)
			)
			(layer "B.SilkS")
		)
		(fp_line
			(start -0.7874 -0.4064)
			(end -0.7874 0.4064)
			(stroke
				(width 0.1524)
				(type default)
			)
			(layer "B.SilkS")
		)
		(fp_line
			(start 0.7874 -0.4064)
			(end -0.7874 -0.4064)
			(stroke
				(width 0.1524)
				(type default)
			)
			(layer "B.SilkS")
		)
		(fp_line
			(start -0.67945 0.3048)
			(end -0.120396 0.3048)
			(stroke
				(width 0.1)
				(type default)
			)
			(layer "B.Fab")
		)
		(fp_line
			(start -0.120396 0.3048)
			(end -0.120396 0.2794)
			(stroke
				(width 0.1)
				(type default)
			)
			(layer "B.Fab")
		)
		(fp_line
			(start 0.12065 0.3048)
			(end 0.67945 0.3048)
			(stroke
				(width 0.1)
				(type default)
			)
			(layer "B.Fab")
		)
		(fp_line
			(start 0.67945 0.3048)
			(end 0.67945 -0.305054)
			(stroke
				(width 0.1)
				(type default)
			)
			(layer "B.Fab")
		)
		(fp_line
			(start -0.120396 0.2794)
			(end 0.12065 0.2794)
			(stroke
				(width 0.1)
				(type default)
			)
			(layer "B.Fab")
		)
		(fp_line
			(start 0.12065 0.2794)
			(end 0.12065 0.3048)
			(stroke
				(width 0.1)
				(type default)
			)
			(layer "B.Fab")
		)
		(fp_line
			(start -0.12065 -0.2794)
			(end -0.12065 -0.3048)
			(stroke
				(width 0.1)
				(type default)
			)
			(layer "B.Fab")
		)
		(fp_line
			(start 0.12065 -0.2794)
			(end -0.12065 -0.2794)
			(stroke
				(width 0.1)
				(type default)
			)
			(layer "B.Fab")
		)
		(fp_line
			(start -0.67945 -0.3048)
			(end -0.67945 0.3048)
			(stroke
				(width 0.1)
				(type default)
			)
			(layer "B.Fab")
		)
		(fp_line
			(start -0.12065 -0.3048)
			(end -0.67945 -0.3048)
			(stroke
				(width 0.1)
				(type default)
			)
			(layer "B.Fab")
		)
		(fp_line
			(start 0.12065 -0.305054)
			(end 0.12065 -0.2794)
			(stroke
				(width 0.1)
				(type default)
			)
			(layer "B.Fab")
		)
		(fp_line
			(start 0.67945 -0.305054)
			(end 0.12065 -0.305054)
			(stroke
				(width 0.1)
				(type default)
			)
			(layer "B.Fab")
		)
		(pad "1" smd circle
			(at 0.40005 0 90)
			(size 0 0)
			(layers "B.Cu" "B.Mask" "B.Paste")
			(net "PVCCIN_CPU0")
		)
		(pad "2" smd circle
			(at -0.40005 0 90)
			(size 0 0)
			(layers "B.Cu" "B.Mask" "B.Paste")
			(net "GND")
		)
	)
	(footprint ""
		(layer "B.Cu")
		(at 116.40312 -241.14252 -90)
		(property "Reference" "C311"
			(at 0 0 90)
			(layer "B.SilkS")
			(hide yes)
			(effects
				(font
					(size 1.27 1.27)
				)
				(justify mirror)
			)
		)
		(property "Value" ""
			(at 0 0 90)
			(layer "B.Fab")
			(effects
				(font
					(size 1.27 1.27)
				)
				(justify mirror)
			)
		)
		(duplicate_pad_numbers_are_jumpers no)
		(fp_line
			(start -1.524 0.762)
			(end 1.524 0.762)
			(stroke
				(width 0.1524)
				(type default)
			)
			(layer "B.SilkS")
		)
		(fp_line
			(start 1.524 0.762)
			(end 1.524 -0.762)
			(stroke
				(width 0.1524)
				(type default)
			)
			(layer "B.SilkS")
		)
		(fp_line
			(start -1.524 -0.762)
			(end -1.524 0.762)
			(stroke
				(width 0.1524)
				(type default)
			)
			(layer "B.SilkS")
		)
		(fp_line
			(start 1.524 -0.762)
			(end -1.524 -0.762)
			(stroke
				(width 0.1524)
				(type default)
			)
			(layer "B.SilkS")
		)
		(fp_line
			(start -1.1049 0.724916)
			(end -1.1049 -0.724916)
			(stroke
				(width 0.1)
				(type default)
			)
			(layer "B.Fab")
		)
		(fp_line
			(start 1.1049 0.724916)
			(end -1.1049 0.724916)
			(stroke
				(width 0.1)
				(type default)
			)
			(layer "B.Fab")
		)
		(fp_line
			(start -1.1049 -0.724916)
			(end 1.1049 -0.724916)
			(stroke
				(width 0.1)
				(type default)
			)
			(layer "B.Fab")
		)
		(fp_line
			(start 1.1049 -0.724916)
			(end 1.1049 0.724916)
			(stroke
				(width 0.1)
				(type default)
			)
			(layer "B.Fab")
		)
		(pad "1" smd rect
			(at 0.889 0 270)
			(size 1.016 1.27)
			(layers "B.Cu" "B.Mask" "B.Paste")
			(net "PVCCIN_CPU1")
		)
		(pad "2" smd rect
			(at -0.889 0 270)
			(size 1.016 1.27)
			(layers "B.Cu" "B.Mask" "B.Paste")
			(net "GND")
		)
	)
	(footprint ""
		(layer "B.Cu")
		(at 339.97773 -190.703454 90)
		(property "Reference" "R1237"
			(at 0 0 90)
			(layer "B.SilkS")
			(hide yes)
			(effects
				(font
					(size 1.27 1.27)
				)
				(justify mirror)
			)
		)
		(property "Value" ""
			(at 0 0 90)
			(layer "B.Fab")
			(effects
				(font
					(size 1.27 1.27)
				)
				(justify mirror)
			)
		)
		(duplicate_pad_numbers_are_jumpers no)
		(fp_line
			(start 0.7874 -0.4064)
			(end -0.7874 -0.4064)
			(stroke
				(width 0.1524)
				(type default)
			)
			(layer "B.SilkS")
		)
		(fp_line
			(start -0.7874 -0.4064)
			(end -0.7874 0.4064)
			(stroke
				(width 0.1524)
				(type default)
			)
			(layer "B.SilkS")
		)
		(fp_line
			(start 0.7874 0.4064)
			(end 0.7874 -0.4064)
			(stroke
				(width 0.1524)
				(type default)
			)
			(layer "B.SilkS")
		)
		(fp_line
			(start -0.7874 0.4064)
			(end 0.7874 0.4064)
			(stroke
				(width 0.1524)
				(type default)
			)
			(layer "B.SilkS")
		)
		(fp_line
			(start 0.67945 -0.305054)
			(end 0.12065 -0.305054)
			(stroke
				(width 0.1)
				(type default)
			)
			(layer "B.Fab")
		)
		(fp_line
			(start 0.12065 -0.305054)
			(end 0.12065 -0.2794)
			(stroke
				(width 0.1)
				(type default)
			)
			(layer "B.Fab")
		)
		(fp_line
			(start -0.12065 -0.3048)
			(end -0.67945 -0.3048)
			(stroke
				(width 0.1)
				(type default)
			)
			(layer "B.Fab")
		)
		(fp_line
			(start -0.67945 -0.3048)
			(end -0.67945 0.3048)
			(stroke
				(width 0.1)
				(type default)
			)
			(layer "B.Fab")
		)
		(fp_line
			(start 0.12065 -0.2794)
			(end -0.12065 -0.2794)
			(stroke
				(width 0.1)
				(type default)
			)
			(layer "B.Fab")
		)
		(fp_line
			(start -0.12065 -0.2794)
			(end -0.12065 -0.3048)
			(stroke
				(width 0.1)
				(type default)
			)
			(layer "B.Fab")
		)
		(fp_line
			(start 0.12065 0.2794)
			(end 0.12065 0.3048)
			(stroke
				(width 0.1)
				(type default)
			)
			(layer "B.Fab")
		)
		(fp_line
			(start -0.120396 0.2794)
			(end 0.12065 0.2794)
			(stroke
				(width 0.1)
				(type default)
			)
			(layer "B.Fab")
		)
		(fp_line
			(start 0.67945 0.3048)
			(end 0.67945 -0.305054)
			(stroke
				(width 0.1)
				(type default)
			)
			(layer "B.Fab")
		)
		(fp_line
			(start 0.12065 0.3048)
			(end 0.67945 0.3048)
			(stroke
				(width 0.1)
				(type default)
			)
			(layer "B.Fab")
		)
		(fp_line
			(start -0.120396 0.3048)
			(end -0.120396 0.2794)
			(stroke
				(width 0.1)
				(type default)
			)
			(layer "B.Fab")
		)
		(fp_line
			(start -0.67945 0.3048)
			(end -0.120396 0.3048)
			(stroke
				(width 0.1)
				(type default)
			)
			(layer "B.Fab")
		)
		(pad "1" smd circle
			(at 0.40005 0 270)
			(size 0 0)
			(layers "B.Cu" "B.Mask" "B.Paste")
			(net "GND")
		)
		(pad "2" smd circle
			(at -0.40005 0 270)
			(size 0 0)
			(layers "B.Cu" "B.Mask" "B.Paste")
			(net "PD_EXT_CLK_SEL_CPU0")
		)
	)
	(footprint ""
		(layer "B.Cu")
		(at 362.629704 -358.675432 180)
		(property "Reference" "PR400"
			(at 0 0 0)
			(layer "B.SilkS")
			(hide yes)
			(effects
				(font
					(size 1.27 1.27)
				)
				(justify mirror)
			)
		)
		(property "Value" ""
			(at 0 0 0)
			(layer "B.Fab")
			(effects
				(font
					(size 1.27 1.27)
				)
				(justify mirror)
			)
		)
		(duplicate_pad_numbers_are_jumpers no)
		(fp_line
			(start 0.7874 0.4064)
			(end 0.7874 -0.4064)
			(stroke
				(width 0.1524)
				(type default)
			)
			(layer "B.SilkS")
		)
		(fp_line
			(start 0.7874 -0.4064)
			(end -0.7874 -0.4064)
			(stroke
				(width 0.1524)
				(type default)
			)
			(layer "B.SilkS")
		)
		(fp_line
			(start -0.7874 0.4064)
			(end 0.7874 0.4064)
			(stroke
				(width 0.1524)
				(type default)
			)
			(layer "B.SilkS")
		)
		(fp_line
			(start -0.7874 -0.4064)
			(end -0.7874 0.4064)
			(stroke
				(width 0.1524)
				(type default)
			)
			(layer "B.SilkS")
		)
		(fp_line
			(start 0.67945 0.3048)
			(end 0.67945 -0.305054)
			(stroke
				(width 0.1)
				(type default)
			)
			(layer "B.Fab")
		)
		(fp_line
			(start 0.67945 -0.305054)
			(end 0.12065 -0.305054)
			(stroke
				(width 0.1)
				(type default)
			)
			(layer "B.Fab")
		)
		(fp_line
			(start 0.12065 0.3048)
			(end 0.67945 0.3048)
			(stroke
				(width 0.1)
				(type default)
			)
			(layer "B.Fab")
		)
		(fp_line
			(start 0.12065 0.2794)
			(end 0.12065 0.3048)
			(stroke
				(width 0.1)
				(type default)
			)
			(layer "B.Fab")
		)
		(fp_line
			(start 0.12065 -0.2794)
			(end -0.12065 -0.2794)
			(stroke
				(width 0.1)
				(type default)
			)
			(layer "B.Fab")
		)
		(fp_line
			(start 0.12065 -0.305054)
			(end 0.12065 -0.2794)
			(stroke
				(width 0.1)
				(type default)
			)
			(layer "B.Fab")
		)
		(fp_line
			(start -0.120396 0.3048)
			(end -0.120396 0.2794)
			(stroke
				(width 0.1)
				(type default)
			)
			(layer "B.Fab")
		)
		(fp_line
			(start -0.120396 0.2794)
			(end 0.12065 0.2794)
			(stroke
				(width 0.1)
				(type default)
			)
			(layer "B.Fab")
		)
		(fp_line
			(start -0.12065 -0.2794)
			(end -0.12065 -0.3048)
			(stroke
				(width 0.1)
				(type default)
			)
			(layer "B.Fab")
		)
		(fp_line
			(start -0.12065 -0.3048)
			(end -0.67945 -0.3048)
			(stroke
				(width 0.1)
				(type default)
			)
			(layer "B.Fab")
		)
		(fp_line
			(start -0.67945 0.3048)
			(end -0.120396 0.3048)
			(stroke
				(width 0.1)
				(type default)
			)
			(layer "B.Fab")
		)
		(fp_line
			(start -0.67945 -0.3048)
			(end -0.67945 0.3048)
			(stroke
				(width 0.1)
				(type default)
			)
			(layer "B.Fab")
		)
		(pad "1" smd circle
			(at 0.40005 0)
			(size 0 0)
			(layers "B.Cu" "B.Mask" "B.Paste")
			(net "PVCCIN_CPU0_ATSEN")
		)
		(pad "2" smd circle
			(at -0.40005 0)
			(size 0 0)
			(layers "B.Cu" "B.Mask" "B.Paste")
			(net "GND")
		)
	)
	(footprint ""
		(layer "B.Cu")
		(at 115.195604 -294.01008 180)
		(property "Reference" "C343"
			(at 0 0 0)
			(layer "B.SilkS")
			(hide yes)
			(effects
				(font
					(size 1.27 1.27)
				)
				(justify mirror)
			)
		)
		(property "Value" ""
			(at 0 0 0)
			(layer "B.Fab")
			(effects
				(font
					(size 1.27 1.27)
				)
				(justify mirror)
			)
		)
		(duplicate_pad_numbers_are_jumpers no)
		(fp_line
			(start 1.524 0.762)
			(end 1.524 -0.762)
			(stroke
				(width 0.1524)
				(type default)
			)
			(layer "B.SilkS")
		)
		(fp_line
			(start 1.524 -0.762)
			(end -1.524 -0.762)
			(stroke
				(width 0.1524)
				(type default)
			)
			(layer "B.SilkS")
		)
		(fp_line
			(start -1.524 0.762)
			(end 1.524 0.762)
			(stroke
				(width 0.1524)
				(type default)
			)
			(layer "B.SilkS")
		)
		(fp_line
			(start -1.524 -0.762)
			(end -1.524 0.762)
			(stroke
				(width 0.1524)
				(type default)
			)
			(layer "B.SilkS")
		)
		(fp_line
			(start 1.1049 0.724916)
			(end -1.1049 0.724916)
			(stroke
				(width 0.1)
				(type default)
			)
			(layer "B.Fab")
		)
		(fp_line
			(start 1.1049 -0.724916)
			(end 1.1049 0.724916)
			(stroke
				(width 0.1)
				(type default)
			)
			(layer "B.Fab")
		)
		(fp_line
			(start -1.1049 0.724916)
			(end -1.1049 -0.724916)
			(stroke
				(width 0.1)
				(type default)
			)
			(layer "B.Fab")
		)
		(fp_line
			(start -1.1049 -0.724916)
			(end 1.1049 -0.724916)
			(stroke
				(width 0.1)
				(type default)
			)
			(layer "B.Fab")
		)
		(pad "1" smd rect
			(at 0.889 0 180)
			(size 1.016 1.27)
			(layers "B.Cu" "B.Mask" "B.Paste")
			(net "PVCCIN_CPU1")
		)
		(pad "2" smd rect
			(at -0.889 0 180)
			(size 1.016 1.27)
			(layers "B.Cu" "B.Mask" "B.Paste")
			(net "GND")
		)
	)
	(footprint ""
		(layer "B.Cu")
		(at 367.012474 -334.693514 -90)
		(property "Reference" "PR146"
			(at 0 0 90)
			(layer "B.SilkS")
			(hide yes)
			(effects
				(font
					(size 1.27 1.27)
				)
				(justify mirror)
			)
		)
		(property "Value" ""
			(at 0 0 90)
			(layer "B.Fab")
			(effects
				(font
					(size 1.27 1.27)
				)
				(justify mirror)
			)
		)
		(duplicate_pad_numbers_are_jumpers no)
		(fp_line
			(start -0.7874 0.4064)
			(end 0.7874 0.4064)
			(stroke
				(width 0.1524)
				(type default)
			)
			(layer "B.SilkS")
		)
		(fp_line
			(start 0.7874 0.4064)
			(end 0.7874 -0.4064)
			(stroke
				(width 0.1524)
				(type default)
			)
			(layer "B.SilkS")
		)
		(fp_line
			(start -0.7874 -0.4064)
			(end -0.7874 0.4064)
			(stroke
				(width 0.1524)
				(type default)
			)
			(layer "B.SilkS")
		)
		(fp_line
			(start 0.7874 -0.4064)
			(end -0.7874 -0.4064)
			(stroke
				(width 0.1524)
				(type default)
			)
			(layer "B.SilkS")
		)
		(fp_line
			(start -0.67945 0.3048)
			(end -0.120396 0.3048)
			(stroke
				(width 0.1)
				(type default)
			)
			(layer "B.Fab")
		)
		(fp_line
			(start -0.120396 0.3048)
			(end -0.120396 0.2794)
			(stroke
				(width 0.1)
				(type default)
			)
			(layer "B.Fab")
		)
		(fp_line
			(start 0.12065 0.3048)
			(end 0.67945 0.3048)
			(stroke
				(width 0.1)
				(type default)
			)
			(layer "B.Fab")
		)
		(fp_line
			(start 0.67945 0.3048)
			(end 0.67945 -0.305054)
			(stroke
				(width 0.1)
				(type default)
			)
			(layer "B.Fab")
		)
		(fp_line
			(start -0.120396 0.2794)
			(end 0.12065 0.2794)
			(stroke
				(width 0.1)
				(type default)
			)
			(layer "B.Fab")
		)
		(fp_line
			(start 0.12065 0.2794)
			(end 0.12065 0.3048)
			(stroke
				(width 0.1)
				(type default)
			)
			(layer "B.Fab")
		)
		(fp_line
			(start -0.12065 -0.2794)
			(end -0.12065 -0.3048)
			(stroke
				(width 0.1)
				(type default)
			)
			(layer "B.Fab")
		)
		(fp_line
			(start 0.12065 -0.2794)
			(end -0.12065 -0.2794)
			(stroke
				(width 0.1)
				(type default)
			)
			(layer "B.Fab")
		)
		(fp_line
			(start -0.67945 -0.3048)
			(end -0.67945 0.3048)
			(stroke
				(width 0.1)
				(type default)
			)
			(layer "B.Fab")
		)
		(fp_line
			(start -0.12065 -0.3048)
			(end -0.67945 -0.3048)
			(stroke
				(width 0.1)
				(type default)
			)
			(layer "B.Fab")
		)
		(fp_line
			(start 0.12065 -0.305054)
			(end 0.12065 -0.2794)
			(stroke
				(width 0.1)
				(type default)
			)
			(layer "B.Fab")
		)
		(fp_line
			(start 0.67945 -0.305054)
			(end 0.12065 -0.305054)
			(stroke
				(width 0.1)
				(type default)
			)
			(layer "B.Fab")
		)
		(pad "1" smd circle
			(at 0.40005 0 90)
			(size 0 0)
			(layers "B.Cu" "B.Mask" "B.Paste")
			(net "PVCCIN_CPU0_PVCC")
		)
		(pad "2" smd circle
			(at -0.40005 0 90)
			(size 0 0)
			(layers "B.Cu" "B.Mask" "B.Paste")
			(net "PVCCIN_CPU0_VDD4")
		)
	)
	(footprint ""
		(layer "B.Cu")
		(at 154.48915 -192.79362 -90)
		(property "Reference" "R3023"
			(at 0 0 90)
			(layer "B.SilkS")
			(hide yes)
			(effects
				(font
					(size 1.27 1.27)
				)
				(justify mirror)
			)
		)
		(property "Value" ""
			(at 0 0 90)
			(layer "B.Fab")
			(effects
				(font
					(size 1.27 1.27)
				)
				(justify mirror)
			)
		)
		(duplicate_pad_numbers_are_jumpers no)
		(fp_line
			(start -0.7874 0.4064)
			(end 0.7874 0.4064)
			(stroke
				(width 0.1524)
				(type default)
			)
			(layer "B.SilkS")
		)
		(fp_line
			(start 0.7874 0.4064)
			(end 0.7874 -0.4064)
			(stroke
				(width 0.1524)
				(type default)
			)
			(layer "B.SilkS")
		)
		(fp_line
			(start -0.7874 -0.4064)
			(end -0.7874 0.4064)
			(stroke
				(width 0.1524)
				(type default)
			)
			(layer "B.SilkS")
		)
		(fp_line
			(start 0.7874 -0.4064)
			(end -0.7874 -0.4064)
			(stroke
				(width 0.1524)
				(type default)
			)
			(layer "B.SilkS")
		)
		(fp_line
			(start -0.67945 0.3048)
			(end -0.120396 0.3048)
			(stroke
				(width 0.1)
				(type default)
			)
			(layer "B.Fab")
		)
		(fp_line
			(start -0.120396 0.3048)
			(end -0.120396 0.2794)
			(stroke
				(width 0.1)
				(type default)
			)
			(layer "B.Fab")
		)
		(fp_line
			(start 0.12065 0.3048)
			(end 0.67945 0.3048)
			(stroke
				(width 0.1)
				(type default)
			)
			(layer "B.Fab")
		)
		(fp_line
			(start 0.67945 0.3048)
			(end 0.67945 -0.305054)
			(stroke
				(width 0.1)
				(type default)
			)
			(layer "B.Fab")
		)
		(fp_line
			(start -0.120396 0.2794)
			(end 0.12065 0.2794)
			(stroke
				(width 0.1)
				(type default)
			)
			(layer "B.Fab")
		)
		(fp_line
			(start 0.12065 0.2794)
			(end 0.12065 0.3048)
			(stroke
				(width 0.1)
				(type default)
			)
			(layer "B.Fab")
		)
		(fp_line
			(start -0.12065 -0.2794)
			(end -0.12065 -0.3048)
			(stroke
				(width 0.1)
				(type default)
			)
			(layer "B.Fab")
		)
		(fp_line
			(start 0.12065 -0.2794)
			(end -0.12065 -0.2794)
			(stroke
				(width 0.1)
				(type default)
			)
			(layer "B.Fab")
		)
		(fp_line
			(start -0.67945 -0.3048)
			(end -0.67945 0.3048)
			(stroke
				(width 0.1)
				(type default)
			)
			(layer "B.Fab")
		)
		(fp_line
			(start -0.12065 -0.3048)
			(end -0.67945 -0.3048)
			(stroke
				(width 0.1)
				(type default)
			)
			(layer "B.Fab")
		)
		(fp_line
			(start 0.12065 -0.305054)
			(end 0.12065 -0.2794)
			(stroke
				(width 0.1)
				(type default)
			)
			(layer "B.Fab")
		)
		(fp_line
			(start 0.67945 -0.305054)
			(end 0.12065 -0.305054)
			(stroke
				(width 0.1)
				(type default)
			)
			(layer "B.Fab")
		)
		(pad "1" smd circle
			(at 0.40005 0 90)
			(size 0 0)
			(layers "B.Cu" "B.Mask" "B.Paste")
			(net "H_CPU_PM_FAST_WAKE_N")
		)
		(pad "2" smd circle
			(at -0.40005 0 90)
			(size 0 0)
			(layers "B.Cu" "B.Mask" "B.Paste")
			(net "H_CPU1_PM_FAST_WAKE_N")
		)
	)
	(footprint ""
		(layer "B.Cu")
		(at 184.962546 -344.733626 -90)
		(property "Reference" "PC1204_P1_3"
			(at 0 0 90)
			(layer "B.SilkS")
			(hide yes)
			(effects
				(font
					(size 1.27 1.27)
				)
				(justify mirror)
			)
		)
		(property "Value" ""
			(at 0 0 90)
			(layer "B.Fab")
			(effects
				(font
					(size 1.27 1.27)
				)
				(justify mirror)
			)
		)
		(duplicate_pad_numbers_are_jumpers no)
		(fp_line
			(start -0.7874 0.4064)
			(end 0.7874 0.4064)
			(stroke
				(width 0.1524)
				(type default)
			)
			(layer "B.SilkS")
		)
		(fp_line
			(start 0.7874 0.4064)
			(end 0.7874 -0.4064)
			(stroke
				(width 0.1524)
				(type default)
			)
			(layer "B.SilkS")
		)
		(fp_line
			(start -0.7874 -0.4064)
			(end -0.7874 0.4064)
			(stroke
				(width 0.1524)
				(type default)
			)
			(layer "B.SilkS")
		)
		(fp_line
			(start 0.7874 -0.4064)
			(end -0.7874 -0.4064)
			(stroke
				(width 0.1524)
				(type default)
			)
			(layer "B.SilkS")
		)
		(fp_line
			(start -0.67945 0.3048)
			(end -0.120396 0.3048)
			(stroke
				(width 0.1)
				(type default)
			)
			(layer "B.Fab")
		)
		(fp_line
			(start -0.120396 0.3048)
			(end -0.120396 0.2794)
			(stroke
				(width 0.1)
				(type default)
			)
			(layer "B.Fab")
		)
		(fp_line
			(start 0.12065 0.3048)
			(end 0.67945 0.3048)
			(stroke
				(width 0.1)
				(type default)
			)
			(layer "B.Fab")
		)
		(fp_line
			(start 0.67945 0.3048)
			(end 0.67945 -0.305054)
			(stroke
				(width 0.1)
				(type default)
			)
			(layer "B.Fab")
		)
		(fp_line
			(start -0.120396 0.2794)
			(end 0.12065 0.2794)
			(stroke
				(width 0.1)
				(type default)
			)
			(layer "B.Fab")
		)
		(fp_line
			(start 0.12065 0.2794)
			(end 0.12065 0.3048)
			(stroke
				(width 0.1)
				(type default)
			)
			(layer "B.Fab")
		)
		(fp_line
			(start -0.12065 -0.2794)
			(end -0.12065 -0.3048)
			(stroke
				(width 0.1)
				(type default)
			)
			(layer "B.Fab")
		)
		(fp_line
			(start 0.12065 -0.2794)
			(end -0.12065 -0.2794)
			(stroke
				(width 0.1)
				(type default)
			)
			(layer "B.Fab")
		)
		(fp_line
			(start -0.67945 -0.3048)
			(end -0.67945 0.3048)
			(stroke
				(width 0.1)
				(type default)
			)
			(layer "B.Fab")
		)
		(fp_line
			(start -0.12065 -0.3048)
			(end -0.67945 -0.3048)
			(stroke
				(width 0.1)
				(type default)
			)
			(layer "B.Fab")
		)
		(fp_line
			(start 0.12065 -0.305054)
			(end 0.12065 -0.2794)
			(stroke
				(width 0.1)
				(type default)
			)
			(layer "B.Fab")
		)
		(fp_line
			(start 0.67945 -0.305054)
			(end 0.12065 -0.305054)
			(stroke
				(width 0.1)
				(type default)
			)
			(layer "B.Fab")
		)
		(pad "1" smd circle
			(at 0.40005 0 90)
			(size 0 0)
			(layers "B.Cu" "B.Mask" "B.Paste")
			(net "PVCCFA_EHV_FIVRA_CPU1")
		)
		(pad "2" smd circle
			(at -0.40005 0 90)
			(size 0 0)
			(layers "B.Cu" "B.Mask" "B.Paste")
			(net "GND")
		)
	)
	(footprint ""
		(layer "B.Cu")
		(at 435.255924 -180.958998 90)
		(property "Reference" "R2409"
			(at 0 0 90)
			(layer "B.SilkS")
			(hide yes)
			(effects
				(font
					(size 1.27 1.27)
				)
				(justify mirror)
			)
		)
		(property "Value" ""
			(at 0 0 90)
			(layer "B.Fab")
			(effects
				(font
					(size 1.27 1.27)
				)
				(justify mirror)
			)
		)
		(duplicate_pad_numbers_are_jumpers no)
		(fp_line
			(start 0.7874 -0.4064)
			(end -0.7874 -0.4064)
			(stroke
				(width 0.1524)
				(type default)
			)
			(layer "B.SilkS")
		)
		(fp_line
			(start -0.7874 -0.4064)
			(end -0.7874 0.4064)
			(stroke
				(width 0.1524)
				(type default)
			)
			(layer "B.SilkS")
		)
		(fp_line
			(start 0.7874 0.4064)
			(end 0.7874 -0.4064)
			(stroke
				(width 0.1524)
				(type default)
			)
			(layer "B.SilkS")
		)
		(fp_line
			(start -0.7874 0.4064)
			(end 0.7874 0.4064)
			(stroke
				(width 0.1524)
				(type default)
			)
			(layer "B.SilkS")
		)
		(fp_line
			(start 0.67945 -0.305054)
			(end 0.12065 -0.305054)
			(stroke
				(width 0.1)
				(type default)
			)
			(layer "B.Fab")
		)
		(fp_line
			(start 0.12065 -0.305054)
			(end 0.12065 -0.2794)
			(stroke
				(width 0.1)
				(type default)
			)
			(layer "B.Fab")
		)
		(fp_line
			(start -0.12065 -0.3048)
			(end -0.67945 -0.3048)
			(stroke
				(width 0.1)
				(type default)
			)
			(layer "B.Fab")
		)
		(fp_line
			(start -0.67945 -0.3048)
			(end -0.67945 0.3048)
			(stroke
				(width 0.1)
				(type default)
			)
			(layer "B.Fab")
		)
		(fp_line
			(start 0.12065 -0.2794)
			(end -0.12065 -0.2794)
			(stroke
				(width 0.1)
				(type default)
			)
			(layer "B.Fab")
		)
		(fp_line
			(start -0.12065 -0.2794)
			(end -0.12065 -0.3048)
			(stroke
				(width 0.1)
				(type default)
			)
			(layer "B.Fab")
		)
		(fp_line
			(start 0.12065 0.2794)
			(end 0.12065 0.3048)
			(stroke
				(width 0.1)
				(type default)
			)
			(layer "B.Fab")
		)
		(fp_line
			(start -0.120396 0.2794)
			(end 0.12065 0.2794)
			(stroke
				(width 0.1)
				(type default)
			)
			(layer "B.Fab")
		)
		(fp_line
			(start 0.67945 0.3048)
			(end 0.67945 -0.305054)
			(stroke
				(width 0.1)
				(type default)
			)
			(layer "B.Fab")
		)
		(fp_line
			(start 0.12065 0.3048)
			(end 0.67945 0.3048)
			(stroke
				(width 0.1)
				(type default)
			)
			(layer "B.Fab")
		)
		(fp_line
			(start -0.120396 0.3048)
			(end -0.120396 0.2794)
			(stroke
				(width 0.1)
				(type default)
			)
			(layer "B.Fab")
		)
		(fp_line
			(start -0.67945 0.3048)
			(end -0.120396 0.3048)
			(stroke
				(width 0.1)
				(type default)
			)
			(layer "B.Fab")
		)
		(pad "1" smd circle
			(at 0.40005 0 270)
			(size 0 0)
			(layers "B.Cu" "B.Mask" "B.Paste")
			(net "P3V3_AUX")
		)
		(pad "2" smd circle
			(at -0.40005 0 270)
			(size 0 0)
			(layers "B.Cu" "B.Mask" "B.Paste")
			(net "PWRGD_PVNN_MAIN_CPU0_R")
		)
	)
	(footprint ""
		(layer "B.Cu")
		(at 100.195126 -333.639922 90)
		(property "Reference" "PC567_P1_1"
			(at 0 0 90)
			(layer "B.SilkS")
			(hide yes)
			(effects
				(font
					(size 1.27 1.27)
				)
				(justify mirror)
			)
		)
		(property "Value" ""
			(at 0 0 90)
			(layer "B.Fab")
			(effects
				(font
					(size 1.27 1.27)
				)
				(justify mirror)
			)
		)
		(duplicate_pad_numbers_are_jumpers no)
		(fp_line
			(start 1.524 -0.762)
			(end -1.524 -0.762)
			(stroke
				(width 0.1524)
				(type default)
			)
			(layer "B.SilkS")
		)
		(fp_line
			(start -1.524 -0.762)
			(end -1.524 0.762)
			(stroke
				(width 0.1524)
				(type default)
			)
			(layer "B.SilkS")
		)
		(fp_line
			(start 1.524 0.762)
			(end 1.524 -0.762)
			(stroke
				(width 0.1524)
				(type default)
			)
			(layer "B.SilkS")
		)
		(fp_line
			(start -1.524 0.762)
			(end 1.524 0.762)
			(stroke
				(width 0.1524)
				(type default)
			)
			(layer "B.SilkS")
		)
		(fp_line
			(start 1.1049 -0.724916)
			(end 1.1049 0.724916)
			(stroke
				(width 0.1)
				(type default)
			)
			(layer "B.Fab")
		)
		(fp_line
			(start -1.1049 -0.724916)
			(end 1.1049 -0.724916)
			(stroke
				(width 0.1)
				(type default)
			)
			(layer "B.Fab")
		)
		(fp_line
			(start 1.1049 0.724916)
			(end -1.1049 0.724916)
			(stroke
				(width 0.1)
				(type default)
			)
			(layer "B.Fab")
		)
		(fp_line
			(start -1.1049 0.724916)
			(end -1.1049 -0.724916)
			(stroke
				(width 0.1)
				(type default)
			)
			(layer "B.Fab")
		)
		(pad "1" smd rect
			(at 0.889 0 90)
			(size 1.016 1.27)
			(layers "B.Cu" "B.Mask" "B.Paste")
			(net "SW_P12V_PVCCIN_CPU1_FLT")
		)
		(pad "2" smd rect
			(at -0.889 0 90)
			(size 1.016 1.27)
			(layers "B.Cu" "B.Mask" "B.Paste")
			(net "GND")
		)
	)
	(footprint ""
		(layer "B.Cu")
		(at 158.83636 -257.89509 -90)
		(property "Reference" "C473"
			(at 0 0 90)
			(layer "B.SilkS")
			(hide yes)
			(effects
				(font
					(size 1.27 1.27)
				)
				(justify mirror)
			)
		)
		(property "Value" ""
			(at 0 0 90)
			(layer "B.Fab")
			(effects
				(font
					(size 1.27 1.27)
				)
				(justify mirror)
			)
		)
		(duplicate_pad_numbers_are_jumpers no)
		(fp_line
			(start -1.524 0.762)
			(end 1.524 0.762)
			(stroke
				(width 0.1524)
				(type default)
			)
			(layer "B.SilkS")
		)
		(fp_line
			(start 1.524 0.762)
			(end 1.524 -0.762)
			(stroke
				(width 0.1524)
				(type default)
			)
			(layer "B.SilkS")
		)
		(fp_line
			(start -1.524 -0.762)
			(end -1.524 0.762)
			(stroke
				(width 0.1524)
				(type default)
			)
			(layer "B.SilkS")
		)
		(fp_line
			(start 1.524 -0.762)
			(end -1.524 -0.762)
			(stroke
				(width 0.1524)
				(type default)
			)
			(layer "B.SilkS")
		)
		(fp_line
			(start -1.1049 0.724916)
			(end -1.1049 -0.724916)
			(stroke
				(width 0.1)
				(type default)
			)
			(layer "B.Fab")
		)
		(fp_line
			(start 1.1049 0.724916)
			(end -1.1049 0.724916)
			(stroke
				(width 0.1)
				(type default)
			)
			(layer "B.Fab")
		)
		(fp_line
			(start -1.1049 -0.724916)
			(end 1.1049 -0.724916)
			(stroke
				(width 0.1)
				(type default)
			)
			(layer "B.Fab")
		)
		(fp_line
			(start 1.1049 -0.724916)
			(end 1.1049 0.724916)
			(stroke
				(width 0.1)
				(type default)
			)
			(layer "B.Fab")
		)
		(pad "1" smd rect
			(at 0.889 0 270)
			(size 1.016 1.27)
			(layers "B.Cu" "B.Mask" "B.Paste")
			(net "PVCCFA_EHV_FIVRA_CPU1")
		)
		(pad "2" smd rect
			(at -0.889 0 270)
			(size 1.016 1.27)
			(layers "B.Cu" "B.Mask" "B.Paste")
			(net "GND")
		)
	)
	(footprint ""
		(layer "B.Cu")
		(at 369.49888 -40.096948 180)
		(property "Reference" "R4115"
			(at 0 0 0)
			(layer "B.SilkS")
			(hide yes)
			(effects
				(font
					(size 1.27 1.27)
				)
				(justify mirror)
			)
		)
		(property "Value" ""
			(at 0 0 0)
			(layer "B.Fab")
			(effects
				(font
					(size 1.27 1.27)
				)
				(justify mirror)
			)
		)
		(duplicate_pad_numbers_are_jumpers no)
		(fp_line
			(start 0.7874 0.4064)
			(end 0.7874 -0.4064)
			(stroke
				(width 0.1524)
				(type default)
			)
			(layer "B.SilkS")
		)
		(fp_line
			(start 0.7874 -0.4064)
			(end -0.7874 -0.4064)
			(stroke
				(width 0.1524)
				(type default)
			)
			(layer "B.SilkS")
		)
		(fp_line
			(start -0.7874 0.4064)
			(end 0.7874 0.4064)
			(stroke
				(width 0.1524)
				(type default)
			)
			(layer "B.SilkS")
		)
		(fp_line
			(start -0.7874 -0.4064)
			(end -0.7874 0.4064)
			(stroke
				(width 0.1524)
				(type default)
			)
			(layer "B.SilkS")
		)
		(fp_line
			(start 0.67945 0.3048)
			(end 0.67945 -0.305054)
			(stroke
				(width 0.1)
				(type default)
			)
			(layer "B.Fab")
		)
		(fp_line
			(start 0.67945 -0.305054)
			(end 0.12065 -0.305054)
			(stroke
				(width 0.1)
				(type default)
			)
			(layer "B.Fab")
		)
		(fp_line
			(start 0.12065 0.3048)
			(end 0.67945 0.3048)
			(stroke
				(width 0.1)
				(type default)
			)
			(layer "B.Fab")
		)
		(fp_line
			(start 0.12065 0.2794)
			(end 0.12065 0.3048)
			(stroke
				(width 0.1)
				(type default)
			)
			(layer "B.Fab")
		)
		(fp_line
			(start 0.12065 -0.2794)
			(end -0.12065 -0.2794)
			(stroke
				(width 0.1)
				(type default)
			)
			(layer "B.Fab")
		)
		(fp_line
			(start 0.12065 -0.305054)
			(end 0.12065 -0.2794)
			(stroke
				(width 0.1)
				(type default)
			)
			(layer "B.Fab")
		)
		(fp_line
			(start -0.120396 0.3048)
			(end -0.120396 0.2794)
			(stroke
				(width 0.1)
				(type default)
			)
			(layer "B.Fab")
		)
		(fp_line
			(start -0.120396 0.2794)
			(end 0.12065 0.2794)
			(stroke
				(width 0.1)
				(type default)
			)
			(layer "B.Fab")
		)
		(fp_line
			(start -0.12065 -0.2794)
			(end -0.12065 -0.3048)
			(stroke
				(width 0.1)
				(type default)
			)
			(layer "B.Fab")
		)
		(fp_line
			(start -0.12065 -0.3048)
			(end -0.67945 -0.3048)
			(stroke
				(width 0.1)
				(type default)
			)
			(layer "B.Fab")
		)
		(fp_line
			(start -0.67945 0.3048)
			(end -0.120396 0.3048)
			(stroke
				(width 0.1)
				(type default)
			)
			(layer "B.Fab")
		)
		(fp_line
			(start -0.67945 -0.3048)
			(end -0.67945 0.3048)
			(stroke
				(width 0.1)
				(type default)
			)
			(layer "B.Fab")
		)
		(pad "1" smd circle
			(at 0.40005 0)
			(size 0 0)
			(layers "B.Cu" "B.Mask" "B.Paste")
			(net "PD_PCH_GPP_E_9")
		)
		(pad "2" smd circle
			(at -0.40005 0)
			(size 0 0)
			(layers "B.Cu" "B.Mask" "B.Paste")
			(net "GND")
		)
	)
	(footprint ""
		(layer "B.Cu")
		(at 446.727834 -179.862734 180)
		(property "Reference" "C1399"
			(at 0 0 0)
			(layer "B.SilkS")
			(hide yes)
			(effects
				(font
					(size 1.27 1.27)
				)
				(justify mirror)
			)
		)
		(property "Value" ""
			(at 0 0 0)
			(layer "B.Fab")
			(effects
				(font
					(size 1.27 1.27)
				)
				(justify mirror)
			)
		)
		(duplicate_pad_numbers_are_jumpers no)
		(fp_line
			(start 1.524 0.762)
			(end 1.524 -0.762)
			(stroke
				(width 0.1524)
				(type default)
			)
			(layer "B.SilkS")
		)
		(fp_line
			(start 1.524 -0.762)
			(end -1.524 -0.762)
			(stroke
				(width 0.1524)
				(type default)
			)
			(layer "B.SilkS")
		)
		(fp_line
			(start -1.524 0.762)
			(end 1.524 0.762)
			(stroke
				(width 0.1524)
				(type default)
			)
			(layer "B.SilkS")
		)
		(fp_line
			(start -1.524 -0.762)
			(end -1.524 0.762)
			(stroke
				(width 0.1524)
				(type default)
			)
			(layer "B.SilkS")
		)
		(fp_line
			(start 1.1049 0.724916)
			(end -1.1049 0.724916)
			(stroke
				(width 0.1)
				(type default)
			)
			(layer "B.Fab")
		)
		(fp_line
			(start 1.1049 -0.724916)
			(end 1.1049 0.724916)
			(stroke
				(width 0.1)
				(type default)
			)
			(layer "B.Fab")
		)
		(fp_line
			(start -1.1049 0.724916)
			(end -1.1049 -0.724916)
			(stroke
				(width 0.1)
				(type default)
			)
			(layer "B.Fab")
		)
		(fp_line
			(start -1.1049 -0.724916)
			(end 1.1049 -0.724916)
			(stroke
				(width 0.1)
				(type default)
			)
			(layer "B.Fab")
		)
		(pad "1" smd rect
			(at 0.889 0 180)
			(size 1.016 1.27)
			(layers "B.Cu" "B.Mask" "B.Paste")
			(net "PVNN_MAIN_CPU0")
		)
		(pad "2" smd rect
			(at -0.889 0 180)
			(size 1.016 1.27)
			(layers "B.Cu" "B.Mask" "B.Paste")
			(net "GND")
		)
	)
	(footprint ""
		(layer "B.Cu")
		(at 406.754838 -250.75515 90)
		(property "Reference" "C502"
			(at 0 0 90)
			(layer "B.SilkS")
			(hide yes)
			(effects
				(font
					(size 1.27 1.27)
				)
				(justify mirror)
			)
		)
		(property "Value" ""
			(at 0 0 90)
			(layer "B.Fab")
			(effects
				(font
					(size 1.27 1.27)
				)
				(justify mirror)
			)
		)
		(duplicate_pad_numbers_are_jumpers no)
		(fp_line
			(start 1.524 -0.762)
			(end -1.524 -0.762)
			(stroke
				(width 0.1524)
				(type default)
			)
			(layer "B.SilkS")
		)
		(fp_line
			(start -1.524 -0.762)
			(end -1.524 0.762)
			(stroke
				(width 0.1524)
				(type default)
			)
			(layer "B.SilkS")
		)
		(fp_line
			(start 1.524 0.762)
			(end 1.524 -0.762)
			(stroke
				(width 0.1524)
				(type default)
			)
			(layer "B.SilkS")
		)
		(fp_line
			(start -1.524 0.762)
			(end 1.524 0.762)
			(stroke
				(width 0.1524)
				(type default)
			)
			(layer "B.SilkS")
		)
		(fp_line
			(start 1.1049 -0.724916)
			(end 1.1049 0.724916)
			(stroke
				(width 0.1)
				(type default)
			)
			(layer "B.Fab")
		)
		(fp_line
			(start -1.1049 -0.724916)
			(end 1.1049 -0.724916)
			(stroke
				(width 0.1)
				(type default)
			)
			(layer "B.Fab")
		)
		(fp_line
			(start 1.1049 0.724916)
			(end -1.1049 0.724916)
			(stroke
				(width 0.1)
				(type default)
			)
			(layer "B.Fab")
		)
		(fp_line
			(start -1.1049 0.724916)
			(end -1.1049 -0.724916)
			(stroke
				(width 0.1)
				(type default)
			)
			(layer "B.Fab")
		)
		(pad "1" smd rect
			(at 0.889 0 90)
			(size 1.016 1.27)
			(layers "B.Cu" "B.Mask" "B.Paste")
			(net "PVCCFA_EHV_FIVRA_CPU0")
		)
		(pad "2" smd rect
			(at -0.889 0 90)
			(size 1.016 1.27)
			(layers "B.Cu" "B.Mask" "B.Paste")
			(net "GND")
		)
	)
	(footprint ""
		(layer "B.Cu")
		(at 362.6739 -212.049614 180)
		(property "Reference" "C503"
			(at 0 0 0)
			(layer "B.SilkS")
			(hide yes)
			(effects
				(font
					(size 1.27 1.27)
				)
				(justify mirror)
			)
		)
		(property "Value" ""
			(at 0 0 0)
			(layer "B.Fab")
			(effects
				(font
					(size 1.27 1.27)
				)
				(justify mirror)
			)
		)
		(duplicate_pad_numbers_are_jumpers no)
		(fp_line
			(start 1.524 0.762)
			(end 1.524 -0.762)
			(stroke
				(width 0.1524)
				(type default)
			)
			(layer "B.SilkS")
		)
		(fp_line
			(start 1.524 -0.762)
			(end -1.524 -0.762)
			(stroke
				(width 0.1524)
				(type default)
			)
			(layer "B.SilkS")
		)
		(fp_line
			(start -1.524 0.762)
			(end 1.524 0.762)
			(stroke
				(width 0.1524)
				(type default)
			)
			(layer "B.SilkS")
		)
		(fp_line
			(start -1.524 -0.762)
			(end -1.524 0.762)
			(stroke
				(width 0.1524)
				(type default)
			)
			(layer "B.SilkS")
		)
		(fp_line
			(start 1.1049 0.724916)
			(end -1.1049 0.724916)
			(stroke
				(width 0.1)
				(type default)
			)
			(layer "B.Fab")
		)
		(fp_line
			(start 1.1049 -0.724916)
			(end 1.1049 0.724916)
			(stroke
				(width 0.1)
				(type default)
			)
			(layer "B.Fab")
		)
		(fp_line
			(start -1.1049 0.724916)
			(end -1.1049 -0.724916)
			(stroke
				(width 0.1)
				(type default)
			)
			(layer "B.Fab")
		)
		(fp_line
			(start -1.1049 -0.724916)
			(end 1.1049 -0.724916)
			(stroke
				(width 0.1)
				(type default)
			)
			(layer "B.Fab")
		)
		(pad "1" smd rect
			(at 0.889 0 180)
			(size 1.016 1.27)
			(layers "B.Cu" "B.Mask" "B.Paste")
			(net "PVCCD_HV_CPU0")
		)
		(pad "2" smd rect
			(at -0.889 0 180)
			(size 1.016 1.27)
			(layers "B.Cu" "B.Mask" "B.Paste")
			(net "GND")
		)
	)
	(footprint ""
		(layer "B.Cu")
		(at 108.415074 -333.639922 90)
		(property "Reference" "PC570_P1_2"
			(at 0 0 90)
			(layer "B.SilkS")
			(hide yes)
			(effects
				(font
					(size 1.27 1.27)
				)
				(justify mirror)
			)
		)
		(property "Value" ""
			(at 0 0 90)
			(layer "B.Fab")
			(effects
				(font
					(size 1.27 1.27)
				)
				(justify mirror)
			)
		)
		(duplicate_pad_numbers_are_jumpers no)
		(fp_line
			(start 1.524 -0.762)
			(end -1.524 -0.762)
			(stroke
				(width 0.1524)
				(type default)
			)
			(layer "B.SilkS")
		)
		(fp_line
			(start -1.524 -0.762)
			(end -1.524 0.762)
			(stroke
				(width 0.1524)
				(type default)
			)
			(layer "B.SilkS")
		)
		(fp_line
			(start 1.524 0.762)
			(end 1.524 -0.762)
			(stroke
				(width 0.1524)
				(type default)
			)
			(layer "B.SilkS")
		)
		(fp_line
			(start -1.524 0.762)
			(end 1.524 0.762)
			(stroke
				(width 0.1524)
				(type default)
			)
			(layer "B.SilkS")
		)
		(fp_line
			(start 1.1049 -0.724916)
			(end 1.1049 0.724916)
			(stroke
				(width 0.1)
				(type default)
			)
			(layer "B.Fab")
		)
		(fp_line
			(start -1.1049 -0.724916)
			(end 1.1049 -0.724916)
			(stroke
				(width 0.1)
				(type default)
			)
			(layer "B.Fab")
		)
		(fp_line
			(start 1.1049 0.724916)
			(end -1.1049 0.724916)
			(stroke
				(width 0.1)
				(type default)
			)
			(layer "B.Fab")
		)
		(fp_line
			(start -1.1049 0.724916)
			(end -1.1049 -0.724916)
			(stroke
				(width 0.1)
				(type default)
			)
			(layer "B.Fab")
		)
		(pad "1" smd rect
			(at 0.889 0 90)
			(size 1.016 1.27)
			(layers "B.Cu" "B.Mask" "B.Paste")
			(net "SW_P12V_PVCCIN_CPU1_FLT")
		)
		(pad "2" smd rect
			(at -0.889 0 90)
			(size 1.016 1.27)
			(layers "B.Cu" "B.Mask" "B.Paste")
			(net "GND")
		)
	)
	(footprint ""
		(layer "B.Cu")
		(at 118.097554 -262.34898 180)
		(property "Reference" "C1388"
			(at 0 0 0)
			(layer "B.SilkS")
			(hide yes)
			(effects
				(font
					(size 1.27 1.27)
				)
				(justify mirror)
			)
		)
		(property "Value" ""
			(at 0 0 0)
			(layer "B.Fab")
			(effects
				(font
					(size 1.27 1.27)
				)
				(justify mirror)
			)
		)
		(duplicate_pad_numbers_are_jumpers no)
		(fp_line
			(start 1.524 0.762)
			(end 1.524 -0.762)
			(stroke
				(width 0.1524)
				(type default)
			)
			(layer "B.SilkS")
		)
		(fp_line
			(start 1.524 -0.762)
			(end -1.524 -0.762)
			(stroke
				(width 0.1524)
				(type default)
			)
			(layer "B.SilkS")
		)
		(fp_line
			(start -1.524 0.762)
			(end 1.524 0.762)
			(stroke
				(width 0.1524)
				(type default)
			)
			(layer "B.SilkS")
		)
		(fp_line
			(start -1.524 -0.762)
			(end -1.524 0.762)
			(stroke
				(width 0.1524)
				(type default)
			)
			(layer "B.SilkS")
		)
		(fp_line
			(start 1.1049 0.724916)
			(end -1.1049 0.724916)
			(stroke
				(width 0.1)
				(type default)
			)
			(layer "B.Fab")
		)
		(fp_line
			(start 1.1049 -0.724916)
			(end 1.1049 0.724916)
			(stroke
				(width 0.1)
				(type default)
			)
			(layer "B.Fab")
		)
		(fp_line
			(start -1.1049 0.724916)
			(end -1.1049 -0.724916)
			(stroke
				(width 0.1)
				(type default)
			)
			(layer "B.Fab")
		)
		(fp_line
			(start -1.1049 -0.724916)
			(end 1.1049 -0.724916)
			(stroke
				(width 0.1)
				(type default)
			)
			(layer "B.Fab")
		)
		(pad "1" smd rect
			(at 0.889 0 180)
			(size 1.016 1.27)
			(layers "B.Cu" "B.Mask" "B.Paste")
			(net "PVPP_HBM_CPU1")
		)
		(pad "2" smd rect
			(at -0.889 0 180)
			(size 1.016 1.27)
			(layers "B.Cu" "B.Mask" "B.Paste")
			(net "GND")
		)
	)
	(footprint ""
		(layer "B.Cu")
		(at 99.419918 -404.486618 -90)
		(property "Reference" "C2073"
			(at 0 0 90)
			(layer "B.SilkS")
			(hide yes)
			(effects
				(font
					(size 1.27 1.27)
				)
				(justify mirror)
			)
		)
		(property "Value" ""
			(at 0 0 90)
			(layer "B.Fab")
			(effects
				(font
					(size 1.27 1.27)
				)
				(justify mirror)
			)
		)
		(duplicate_pad_numbers_are_jumpers no)
		(fp_line
			(start -0.299974 0.150114)
			(end 0.299974 0.150114)
			(stroke
				(width 0.1)
				(type default)
			)
			(layer "B.Fab")
		)
		(fp_line
			(start 0.299974 0.150114)
			(end 0.299974 -0.150114)
			(stroke
				(width 0.1)
				(type default)
			)
			(layer "B.Fab")
		)
		(fp_line
			(start -0.299974 -0.150114)
			(end -0.299974 0.150114)
			(stroke
				(width 0.1)
				(type default)
			)
			(layer "B.Fab")
		)
		(fp_line
			(start 0.299974 -0.150114)
			(end -0.299974 -0.150114)
			(stroke
				(width 0.1)
				(type default)
			)
			(layer "B.Fab")
		)
		(pad "1" smd rect
			(at 0.2667 0 90)
			(size 0.3048 0.381)
			(layers "B.Cu" "B.Mask" "B.Paste")
			(net "P3E_PCH_NVS_TX_DP<1>")
		)
		(pad "2" smd rect
			(at -0.2667 0 90)
			(size 0.3048 0.381)
			(layers "B.Cu" "B.Mask" "B.Paste")
			(net "P3E_PCH_NVS_TX_C_DP<1>")
		)
		(zone
			(layer "In16.Cu")
			(hatch none 0.5)
			(connect_pads
				(clearance 0)
			)
			(min_thickness 0.25)
			(keepout
				(tracks not_allowed)
				(vias allowed)
				(pads allowed)
				(copperpour not_allowed)
				(footprints allowed)
			)
			(placement
				(enabled no)
				(sheetname "")
			)
			(fill
				(thermal_gap 0.5)
				(thermal_bridge_width 0.5)
				(island_removal_mode 0)
			)
			(polygon
				(pts
					(arc
						(start 99.178618 -404.626318)
						(mid 99.200936 -404.572436)
						(end 99.254818 -404.550118)
					)
					(arc
						(start 99.585018 -404.550118)
						(mid 99.6389 -404.572436)
						(end 99.661218 -404.626318)
					)
					(arc
						(start 99.661218 -404.880318)
						(mid 99.6389 -404.9342)
						(end 99.585018 -404.956518)
					)
					(arc
						(start 99.254818 -404.956518)
						(mid 99.200936 -404.9342)
						(end 99.178618 -404.880318)
					)
				)
			)
		)
		(zone
			(layer "In16.Cu")
			(hatch none 0.5)
			(connect_pads
				(clearance 0)
			)
			(min_thickness 0.25)
			(keepout
				(tracks not_allowed)
				(vias allowed)
				(pads allowed)
				(copperpour not_allowed)
				(footprints allowed)
			)
			(placement
				(enabled no)
				(sheetname "")
			)
			(fill
				(thermal_gap 0.5)
				(thermal_bridge_width 0.5)
				(island_removal_mode 0)
			)
			(polygon
				(pts
					(arc
						(start 99.178618 -404.092918)
						(mid 99.200936 -404.039036)
						(end 99.254818 -404.016718)
					)
					(arc
						(start 99.585018 -404.016718)
						(mid 99.6389 -404.039036)
						(end 99.661218 -404.092918)
					)
					(arc
						(start 99.661218 -404.346918)
						(mid 99.6389 -404.4008)
						(end 99.585018 -404.423118)
					)
					(arc
						(start 99.254818 -404.423118)
						(mid 99.200936 -404.4008)
						(end 99.178618 -404.346918)
					)
				)
			)
		)
	)
	(footprint ""
		(layer "B.Cu")
		(at 57.479946 -321.554856 -90)
		(property "Reference" "C51"
			(at 0 0 90)
			(layer "B.SilkS")
			(hide yes)
			(effects
				(font
					(size 1.27 1.27)
				)
				(justify mirror)
			)
		)
		(property "Value" ""
			(at 0 0 90)
			(layer "B.Fab")
			(effects
				(font
					(size 1.27 1.27)
				)
				(justify mirror)
			)
		)
		(duplicate_pad_numbers_are_jumpers no)
		(fp_line
			(start -1.524 0.762)
			(end 1.524 0.762)
			(stroke
				(width 0.1524)
				(type default)
			)
			(layer "B.SilkS")
		)
		(fp_line
			(start 1.524 0.762)
			(end 1.524 -0.762)
			(stroke
				(width 0.1524)
				(type default)
			)
			(layer "B.SilkS")
		)
		(fp_line
			(start -1.524 -0.762)
			(end -1.524 0.762)
			(stroke
				(width 0.1524)
				(type default)
			)
			(layer "B.SilkS")
		)
		(fp_line
			(start 1.524 -0.762)
			(end -1.524 -0.762)
			(stroke
				(width 0.1524)
				(type default)
			)
			(layer "B.SilkS")
		)
		(fp_line
			(start -1.1049 0.724916)
			(end -1.1049 -0.724916)
			(stroke
				(width 0.1)
				(type default)
			)
			(layer "B.Fab")
		)
		(fp_line
			(start 1.1049 0.724916)
			(end -1.1049 0.724916)
			(stroke
				(width 0.1)
				(type default)
			)
			(layer "B.Fab")
		)
		(fp_line
			(start -1.1049 -0.724916)
			(end 1.1049 -0.724916)
			(stroke
				(width 0.1)
				(type default)
			)
			(layer "B.Fab")
		)
		(fp_line
			(start 1.1049 -0.724916)
			(end 1.1049 0.724916)
			(stroke
				(width 0.1)
				(type default)
			)
			(layer "B.Fab")
		)
		(pad "1" smd rect
			(at 0.889 0 270)
			(size 1.016 1.27)
			(layers "B.Cu" "B.Mask" "B.Paste")
			(net "P12V_S3_AUX_CPU1_NVDIMM")
		)
		(pad "2" smd rect
			(at -0.889 0 270)
			(size 1.016 1.27)
			(layers "B.Cu" "B.Mask" "B.Paste")
			(net "GND")
		)
	)
	(footprint ""
		(layer "B.Cu")
		(at 29.586682 -164.167058)
		(property "Reference" "PR1315"
			(at 0 0 0)
			(layer "B.SilkS")
			(hide yes)
			(effects
				(font
					(size 1.27 1.27)
				)
				(justify mirror)
			)
		)
		(property "Value" ""
			(at 0 0 0)
			(layer "B.Fab")
			(effects
				(font
					(size 1.27 1.27)
				)
				(justify mirror)
			)
		)
		(duplicate_pad_numbers_are_jumpers no)
		(fp_line
			(start -0.7874 -0.4064)
			(end -0.7874 0.4064)
			(stroke
				(width 0.1524)
				(type default)
			)
			(layer "B.SilkS")
		)
		(fp_line
			(start -0.7874 0.4064)
			(end 0.7874 0.4064)
			(stroke
				(width 0.1524)
				(type default)
			)
			(layer "B.SilkS")
		)
		(fp_line
			(start 0.7874 -0.4064)
			(end -0.7874 -0.4064)
			(stroke
				(width 0.1524)
				(type default)
			)
			(layer "B.SilkS")
		)
		(fp_line
			(start 0.7874 0.4064)
			(end 0.7874 -0.4064)
			(stroke
				(width 0.1524)
				(type default)
			)
			(layer "B.SilkS")
		)
		(fp_line
			(start -0.67945 -0.3048)
			(end -0.67945 0.3048)
			(stroke
				(width 0.1)
				(type default)
			)
			(layer "B.Fab")
		)
		(fp_line
			(start -0.67945 0.3048)
			(end -0.120396 0.3048)
			(stroke
				(width 0.1)
				(type default)
			)
			(layer "B.Fab")
		)
		(fp_line
			(start -0.12065 -0.3048)
			(end -0.67945 -0.3048)
			(stroke
				(width 0.1)
				(type default)
			)
			(layer "B.Fab")
		)
		(fp_line
			(start -0.12065 -0.2794)
			(end -0.12065 -0.3048)
			(stroke
				(width 0.1)
				(type default)
			)
			(layer "B.Fab")
		)
		(fp_line
			(start -0.120396 0.2794)
			(end 0.12065 0.2794)
			(stroke
				(width 0.1)
				(type default)
			)
			(layer "B.Fab")
		)
		(fp_line
			(start -0.120396 0.3048)
			(end -0.120396 0.2794)
			(stroke
				(width 0.1)
				(type default)
			)
			(layer "B.Fab")
		)
		(fp_line
			(start 0.12065 -0.305054)
			(end 0.12065 -0.2794)
			(stroke
				(width 0.1)
				(type default)
			)
			(layer "B.Fab")
		)
		(fp_line
			(start 0.12065 -0.2794)
			(end -0.12065 -0.2794)
			(stroke
				(width 0.1)
				(type default)
			)
			(layer "B.Fab")
		)
		(fp_line
			(start 0.12065 0.2794)
			(end 0.12065 0.3048)
			(stroke
				(width 0.1)
				(type default)
			)
			(layer "B.Fab")
		)
		(fp_line
			(start 0.12065 0.3048)
			(end 0.67945 0.3048)
			(stroke
				(width 0.1)
				(type default)
			)
			(layer "B.Fab")
		)
		(fp_line
			(start 0.67945 -0.305054)
			(end 0.12065 -0.305054)
			(stroke
				(width 0.1)
				(type default)
			)
			(layer "B.Fab")
		)
		(fp_line
			(start 0.67945 0.3048)
			(end 0.67945 -0.305054)
			(stroke
				(width 0.1)
				(type default)
			)
			(layer "B.Fab")
		)
		(pad "1" smd circle
			(at 0.40005 0 180)
			(size 0 0)
			(layers "B.Cu" "B.Mask" "B.Paste")
			(net "PVCCD_HV_CPU1_ISYS_R")
		)
		(pad "2" smd circle
			(at -0.40005 0 180)
			(size 0 0)
			(layers "B.Cu" "B.Mask" "B.Paste")
			(net "GND")
		)
	)
	(footprint ""
		(layer "B.Cu")
		(at 212.725 -57.061608 90)
		(property "Reference" "R4093"
			(at 0 0 90)
			(layer "B.SilkS")
			(hide yes)
			(effects
				(font
					(size 1.27 1.27)
				)
				(justify mirror)
			)
		)
		(property "Value" ""
			(at 0 0 90)
			(layer "B.Fab")
			(effects
				(font
					(size 1.27 1.27)
				)
				(justify mirror)
			)
		)
		(duplicate_pad_numbers_are_jumpers no)
		(fp_line
			(start 0.7874 -0.4064)
			(end -0.7874 -0.4064)
			(stroke
				(width 0.1524)
				(type default)
			)
			(layer "B.SilkS")
		)
		(fp_line
			(start -0.7874 -0.4064)
			(end -0.7874 0.4064)
			(stroke
				(width 0.1524)
				(type default)
			)
			(layer "B.SilkS")
		)
		(fp_line
			(start 0.7874 0.4064)
			(end 0.7874 -0.4064)
			(stroke
				(width 0.1524)
				(type default)
			)
			(layer "B.SilkS")
		)
		(fp_line
			(start -0.7874 0.4064)
			(end 0.7874 0.4064)
			(stroke
				(width 0.1524)
				(type default)
			)
			(layer "B.SilkS")
		)
		(fp_line
			(start 0.67945 -0.305054)
			(end 0.12065 -0.305054)
			(stroke
				(width 0.1)
				(type default)
			)
			(layer "B.Fab")
		)
		(fp_line
			(start 0.12065 -0.305054)
			(end 0.12065 -0.2794)
			(stroke
				(width 0.1)
				(type default)
			)
			(layer "B.Fab")
		)
		(fp_line
			(start -0.12065 -0.3048)
			(end -0.67945 -0.3048)
			(stroke
				(width 0.1)
				(type default)
			)
			(layer "B.Fab")
		)
		(fp_line
			(start -0.67945 -0.3048)
			(end -0.67945 0.3048)
			(stroke
				(width 0.1)
				(type default)
			)
			(layer "B.Fab")
		)
		(fp_line
			(start 0.12065 -0.2794)
			(end -0.12065 -0.2794)
			(stroke
				(width 0.1)
				(type default)
			)
			(layer "B.Fab")
		)
		(fp_line
			(start -0.12065 -0.2794)
			(end -0.12065 -0.3048)
			(stroke
				(width 0.1)
				(type default)
			)
			(layer "B.Fab")
		)
		(fp_line
			(start 0.12065 0.2794)
			(end 0.12065 0.3048)
			(stroke
				(width 0.1)
				(type default)
			)
			(layer "B.Fab")
		)
		(fp_line
			(start -0.120396 0.2794)
			(end 0.12065 0.2794)
			(stroke
				(width 0.1)
				(type default)
			)
			(layer "B.Fab")
		)
		(fp_line
			(start 0.67945 0.3048)
			(end 0.67945 -0.305054)
			(stroke
				(width 0.1)
				(type default)
			)
			(layer "B.Fab")
		)
		(fp_line
			(start 0.12065 0.3048)
			(end 0.67945 0.3048)
			(stroke
				(width 0.1)
				(type default)
			)
			(layer "B.Fab")
		)
		(fp_line
			(start -0.120396 0.3048)
			(end -0.120396 0.2794)
			(stroke
				(width 0.1)
				(type default)
			)
			(layer "B.Fab")
		)
		(fp_line
			(start -0.67945 0.3048)
			(end -0.120396 0.3048)
			(stroke
				(width 0.1)
				(type default)
			)
			(layer "B.Fab")
		)
		(pad "1" smd circle
			(at 0.40005 0 270)
			(size 0 0)
			(layers "B.Cu" "B.Mask" "B.Paste")
			(net "P3V3_AUX")
		)
		(pad "2" smd circle
			(at -0.40005 0 270)
			(size 0 0)
			(layers "B.Cu" "B.Mask" "B.Paste")
			(net "E1S_0_P3V3_ADC_ALERT_R")
		)
	)
	(footprint ""
		(layer "B.Cu")
		(at 305.624738 -153.82367 180)
		(property "Reference" "R693"
			(at 0 0 0)
			(layer "B.SilkS")
			(hide yes)
			(effects
				(font
					(size 1.27 1.27)
				)
				(justify mirror)
			)
		)
		(property "Value" ""
			(at 0 0 0)
			(layer "B.Fab")
			(effects
				(font
					(size 1.27 1.27)
				)
				(justify mirror)
			)
		)
		(duplicate_pad_numbers_are_jumpers no)
		(fp_line
			(start 0.7874 0.4064)
			(end 0.7874 -0.4064)
			(stroke
				(width 0.1524)
				(type default)
			)
			(layer "B.SilkS")
		)
		(fp_line
			(start 0.7874 -0.4064)
			(end -0.7874 -0.4064)
			(stroke
				(width 0.1524)
				(type default)
			)
			(layer "B.SilkS")
		)
		(fp_line
			(start -0.7874 0.4064)
			(end 0.7874 0.4064)
			(stroke
				(width 0.1524)
				(type default)
			)
			(layer "B.SilkS")
		)
		(fp_line
			(start -0.7874 -0.4064)
			(end -0.7874 0.4064)
			(stroke
				(width 0.1524)
				(type default)
			)
			(layer "B.SilkS")
		)
		(fp_line
			(start 0.67945 0.3048)
			(end 0.67945 -0.305054)
			(stroke
				(width 0.1)
				(type default)
			)
			(layer "B.Fab")
		)
		(fp_line
			(start 0.67945 -0.305054)
			(end 0.12065 -0.305054)
			(stroke
				(width 0.1)
				(type default)
			)
			(layer "B.Fab")
		)
		(fp_line
			(start 0.12065 0.3048)
			(end 0.67945 0.3048)
			(stroke
				(width 0.1)
				(type default)
			)
			(layer "B.Fab")
		)
		(fp_line
			(start 0.12065 0.2794)
			(end 0.12065 0.3048)
			(stroke
				(width 0.1)
				(type default)
			)
			(layer "B.Fab")
		)
		(fp_line
			(start 0.12065 -0.2794)
			(end -0.12065 -0.2794)
			(stroke
				(width 0.1)
				(type default)
			)
			(layer "B.Fab")
		)
		(fp_line
			(start 0.12065 -0.305054)
			(end 0.12065 -0.2794)
			(stroke
				(width 0.1)
				(type default)
			)
			(layer "B.Fab")
		)
		(fp_line
			(start -0.120396 0.3048)
			(end -0.120396 0.2794)
			(stroke
				(width 0.1)
				(type default)
			)
			(layer "B.Fab")
		)
		(fp_line
			(start -0.120396 0.2794)
			(end 0.12065 0.2794)
			(stroke
				(width 0.1)
				(type default)
			)
			(layer "B.Fab")
		)
		(fp_line
			(start -0.12065 -0.2794)
			(end -0.12065 -0.3048)
			(stroke
				(width 0.1)
				(type default)
			)
			(layer "B.Fab")
		)
		(fp_line
			(start -0.12065 -0.3048)
			(end -0.67945 -0.3048)
			(stroke
				(width 0.1)
				(type default)
			)
			(layer "B.Fab")
		)
		(fp_line
			(start -0.67945 0.3048)
			(end -0.120396 0.3048)
			(stroke
				(width 0.1)
				(type default)
			)
			(layer "B.Fab")
		)
		(fp_line
			(start -0.67945 -0.3048)
			(end -0.67945 0.3048)
			(stroke
				(width 0.1)
				(type default)
			)
			(layer "B.Fab")
		)
		(pad "1" smd circle
			(at 0.40005 0)
			(size 0 0)
			(layers "B.Cu" "B.Mask" "B.Paste")
			(net "I3C_SPD_DDREFGH_CPU0_LVC1_R_SCL")
		)
		(pad "2" smd circle
			(at -0.40005 0)
			(size 0 0)
			(layers "B.Cu" "B.Mask" "B.Paste")
			(net "I3C_SPD_DDREFGH_CPU0_LVC1_SCL")
		)
	)
	(footprint ""
		(layer "B.Cu")
		(at 344.754708 -62.056264 90)
		(property "Reference" "C161"
			(at 0 0 90)
			(layer "B.SilkS")
			(hide yes)
			(effects
				(font
					(size 1.27 1.27)
				)
				(justify mirror)
			)
		)
		(property "Value" ""
			(at 0 0 90)
			(layer "B.Fab")
			(effects
				(font
					(size 1.27 1.27)
				)
				(justify mirror)
			)
		)
		(duplicate_pad_numbers_are_jumpers no)
		(fp_line
			(start 0.299974 -0.150114)
			(end -0.299974 -0.150114)
			(stroke
				(width 0.1)
				(type default)
			)
			(layer "B.Fab")
		)
		(fp_line
			(start -0.299974 -0.150114)
			(end -0.299974 0.150114)
			(stroke
				(width 0.1)
				(type default)
			)
			(layer "B.Fab")
		)
		(fp_line
			(start 0.299974 0.150114)
			(end 0.299974 -0.150114)
			(stroke
				(width 0.1)
				(type default)
			)
			(layer "B.Fab")
		)
		(fp_line
			(start -0.299974 0.150114)
			(end 0.299974 0.150114)
			(stroke
				(width 0.1)
				(type default)
			)
			(layer "B.Fab")
		)
		(pad "1" smd rect
			(at 0.2667 0 270)
			(size 0.3048 0.381)
			(layers "B.Cu" "B.Mask" "B.Paste")
			(net "DMI_CPU0_PCH_RX_C_DN<4>")
		)
		(pad "2" smd rect
			(at -0.2667 0 270)
			(size 0.3048 0.381)
			(layers "B.Cu" "B.Mask" "B.Paste")
			(net "DMI_CPU0_PCH_RX_DN<4>")
		)
	)
	(footprint ""
		(layer "B.Cu")
		(at 10.373106 -195.816728 -90)
		(property "Reference" "C562"
			(at 0 0 90)
			(layer "B.SilkS")
			(hide yes)
			(effects
				(font
					(size 1.27 1.27)
				)
				(justify mirror)
			)
		)
		(property "Value" ""
			(at 0 0 90)
			(layer "B.Fab")
			(effects
				(font
					(size 1.27 1.27)
				)
				(justify mirror)
			)
		)
		(duplicate_pad_numbers_are_jumpers no)
		(fp_line
			(start -0.7874 0.4064)
			(end 0.7874 0.4064)
			(stroke
				(width 0.1524)
				(type default)
			)
			(layer "B.SilkS")
		)
		(fp_line
			(start 0.7874 0.4064)
			(end 0.7874 -0.4064)
			(stroke
				(width 0.1524)
				(type default)
			)
			(layer "B.SilkS")
		)
		(fp_line
			(start -0.7874 -0.4064)
			(end -0.7874 0.4064)
			(stroke
				(width 0.1524)
				(type default)
			)
			(layer "B.SilkS")
		)
		(fp_line
			(start 0.7874 -0.4064)
			(end -0.7874 -0.4064)
			(stroke
				(width 0.1524)
				(type default)
			)
			(layer "B.SilkS")
		)
		(fp_line
			(start -0.67945 0.3048)
			(end -0.120396 0.3048)
			(stroke
				(width 0.1)
				(type default)
			)
			(layer "B.Fab")
		)
		(fp_line
			(start -0.120396 0.3048)
			(end -0.120396 0.2794)
			(stroke
				(width 0.1)
				(type default)
			)
			(layer "B.Fab")
		)
		(fp_line
			(start 0.12065 0.3048)
			(end 0.67945 0.3048)
			(stroke
				(width 0.1)
				(type default)
			)
			(layer "B.Fab")
		)
		(fp_line
			(start 0.67945 0.3048)
			(end 0.67945 -0.305054)
			(stroke
				(width 0.1)
				(type default)
			)
			(layer "B.Fab")
		)
		(fp_line
			(start -0.120396 0.2794)
			(end 0.12065 0.2794)
			(stroke
				(width 0.1)
				(type default)
			)
			(layer "B.Fab")
		)
		(fp_line
			(start 0.12065 0.2794)
			(end 0.12065 0.3048)
			(stroke
				(width 0.1)
				(type default)
			)
			(layer "B.Fab")
		)
		(fp_line
			(start -0.12065 -0.2794)
			(end -0.12065 -0.3048)
			(stroke
				(width 0.1)
				(type default)
			)
			(layer "B.Fab")
		)
		(fp_line
			(start 0.12065 -0.2794)
			(end -0.12065 -0.2794)
			(stroke
				(width 0.1)
				(type default)
			)
			(layer "B.Fab")
		)
		(fp_line
			(start -0.67945 -0.3048)
			(end -0.67945 0.3048)
			(stroke
				(width 0.1)
				(type default)
			)
			(layer "B.Fab")
		)
		(fp_line
			(start -0.12065 -0.3048)
			(end -0.67945 -0.3048)
			(stroke
				(width 0.1)
				(type default)
			)
			(layer "B.Fab")
		)
		(fp_line
			(start 0.12065 -0.305054)
			(end 0.12065 -0.2794)
			(stroke
				(width 0.1)
				(type default)
			)
			(layer "B.Fab")
		)
		(fp_line
			(start 0.67945 -0.305054)
			(end 0.12065 -0.305054)
			(stroke
				(width 0.1)
				(type default)
			)
			(layer "B.Fab")
		)
		(pad "1" smd circle
			(at 0.40005 0 90)
			(size 0 0)
			(layers "B.Cu" "B.Mask" "B.Paste")
			(net "P3V3_AUX")
		)
		(pad "2" smd circle
			(at -0.40005 0 90)
			(size 0 0)
			(layers "B.Cu" "B.Mask" "B.Paste")
			(net "GND")
		)
	)
	(footprint ""
		(layer "B.Cu")
		(at 215.206834 -318.826642 90)
		(property "Reference" "R907"
			(at 0 0 90)
			(layer "B.SilkS")
			(hide yes)
			(effects
				(font
					(size 1.27 1.27)
				)
				(justify mirror)
			)
		)
		(property "Value" ""
			(at 0 0 90)
			(layer "B.Fab")
			(effects
				(font
					(size 1.27 1.27)
				)
				(justify mirror)
			)
		)
		(duplicate_pad_numbers_are_jumpers no)
		(fp_line
			(start 0.7874 -0.4064)
			(end -0.7874 -0.4064)
			(stroke
				(width 0.1524)
				(type default)
			)
			(layer "B.SilkS")
		)
		(fp_line
			(start -0.7874 -0.4064)
			(end -0.7874 0.4064)
			(stroke
				(width 0.1524)
				(type default)
			)
			(layer "B.SilkS")
		)
		(fp_line
			(start 0.7874 0.4064)
			(end 0.7874 -0.4064)
			(stroke
				(width 0.1524)
				(type default)
			)
			(layer "B.SilkS")
		)
		(fp_line
			(start -0.7874 0.4064)
			(end 0.7874 0.4064)
			(stroke
				(width 0.1524)
				(type default)
			)
			(layer "B.SilkS")
		)
		(fp_line
			(start 0.67945 -0.305054)
			(end 0.12065 -0.305054)
			(stroke
				(width 0.1)
				(type default)
			)
			(layer "B.Fab")
		)
		(fp_line
			(start 0.12065 -0.305054)
			(end 0.12065 -0.2794)
			(stroke
				(width 0.1)
				(type default)
			)
			(layer "B.Fab")
		)
		(fp_line
			(start -0.12065 -0.3048)
			(end -0.67945 -0.3048)
			(stroke
				(width 0.1)
				(type default)
			)
			(layer "B.Fab")
		)
		(fp_line
			(start -0.67945 -0.3048)
			(end -0.67945 0.3048)
			(stroke
				(width 0.1)
				(type default)
			)
			(layer "B.Fab")
		)
		(fp_line
			(start 0.12065 -0.2794)
			(end -0.12065 -0.2794)
			(stroke
				(width 0.1)
				(type default)
			)
			(layer "B.Fab")
		)
		(fp_line
			(start -0.12065 -0.2794)
			(end -0.12065 -0.3048)
			(stroke
				(width 0.1)
				(type default)
			)
			(layer "B.Fab")
		)
		(fp_line
			(start 0.12065 0.2794)
			(end 0.12065 0.3048)
			(stroke
				(width 0.1)
				(type default)
			)
			(layer "B.Fab")
		)
		(fp_line
			(start -0.120396 0.2794)
			(end 0.12065 0.2794)
			(stroke
				(width 0.1)
				(type default)
			)
			(layer "B.Fab")
		)
		(fp_line
			(start 0.67945 0.3048)
			(end 0.67945 -0.305054)
			(stroke
				(width 0.1)
				(type default)
			)
			(layer "B.Fab")
		)
		(fp_line
			(start 0.12065 0.3048)
			(end 0.67945 0.3048)
			(stroke
				(width 0.1)
				(type default)
			)
			(layer "B.Fab")
		)
		(fp_line
			(start -0.120396 0.3048)
			(end -0.120396 0.2794)
			(stroke
				(width 0.1)
				(type default)
			)
			(layer "B.Fab")
		)
		(fp_line
			(start -0.67945 0.3048)
			(end -0.120396 0.3048)
			(stroke
				(width 0.1)
				(type default)
			)
			(layer "B.Fab")
		)
		(pad "1" smd circle
			(at 0.40005 0 270)
			(size 0 0)
			(layers "B.Cu" "B.Mask" "B.Paste")
			(net "PWRGD_CHH_CPU1_DIMM1")
		)
		(pad "2" smd circle
			(at -0.40005 0 270)
			(size 0 0)
			(layers "B.Cu" "B.Mask" "B.Paste")
			(net "PWRGD_FAIL_CPU1_GH")
		)
	)
	(footprint ""
		(layer "B.Cu")
		(at 332.7781 -33.173416 90)
		(property "Reference" "R501"
			(at 0 0 90)
			(layer "B.SilkS")
			(hide yes)
			(effects
				(font
					(size 1.27 1.27)
				)
				(justify mirror)
			)
		)
		(property "Value" ""
			(at 0 0 90)
			(layer "B.Fab")
			(effects
				(font
					(size 1.27 1.27)
				)
				(justify mirror)
			)
		)
		(duplicate_pad_numbers_are_jumpers no)
		(fp_line
			(start 0.7874 -0.4064)
			(end -0.7874 -0.4064)
			(stroke
				(width 0.1524)
				(type default)
			)
			(layer "B.SilkS")
		)
		(fp_line
			(start -0.7874 -0.4064)
			(end -0.7874 0.4064)
			(stroke
				(width 0.1524)
				(type default)
			)
			(layer "B.SilkS")
		)
		(fp_line
			(start 0.7874 0.4064)
			(end 0.7874 -0.4064)
			(stroke
				(width 0.1524)
				(type default)
			)
			(layer "B.SilkS")
		)
		(fp_line
			(start -0.7874 0.4064)
			(end 0.7874 0.4064)
			(stroke
				(width 0.1524)
				(type default)
			)
			(layer "B.SilkS")
		)
		(fp_line
			(start 0.67945 -0.305054)
			(end 0.12065 -0.305054)
			(stroke
				(width 0.1)
				(type default)
			)
			(layer "B.Fab")
		)
		(fp_line
			(start 0.12065 -0.305054)
			(end 0.12065 -0.2794)
			(stroke
				(width 0.1)
				(type default)
			)
			(layer "B.Fab")
		)
		(fp_line
			(start -0.12065 -0.3048)
			(end -0.67945 -0.3048)
			(stroke
				(width 0.1)
				(type default)
			)
			(layer "B.Fab")
		)
		(fp_line
			(start -0.67945 -0.3048)
			(end -0.67945 0.3048)
			(stroke
				(width 0.1)
				(type default)
			)
			(layer "B.Fab")
		)
		(fp_line
			(start 0.12065 -0.2794)
			(end -0.12065 -0.2794)
			(stroke
				(width 0.1)
				(type default)
			)
			(layer "B.Fab")
		)
		(fp_line
			(start -0.12065 -0.2794)
			(end -0.12065 -0.3048)
			(stroke
				(width 0.1)
				(type default)
			)
			(layer "B.Fab")
		)
		(fp_line
			(start 0.12065 0.2794)
			(end 0.12065 0.3048)
			(stroke
				(width 0.1)
				(type default)
			)
			(layer "B.Fab")
		)
		(fp_line
			(start -0.120396 0.2794)
			(end 0.12065 0.2794)
			(stroke
				(width 0.1)
				(type default)
			)
			(layer "B.Fab")
		)
		(fp_line
			(start 0.67945 0.3048)
			(end 0.67945 -0.305054)
			(stroke
				(width 0.1)
				(type default)
			)
			(layer "B.Fab")
		)
		(fp_line
			(start 0.12065 0.3048)
			(end 0.67945 0.3048)
			(stroke
				(width 0.1)
				(type default)
			)
			(layer "B.Fab")
		)
		(fp_line
			(start -0.120396 0.3048)
			(end -0.120396 0.2794)
			(stroke
				(width 0.1)
				(type default)
			)
			(layer "B.Fab")
		)
		(fp_line
			(start -0.67945 0.3048)
			(end -0.120396 0.3048)
			(stroke
				(width 0.1)
				(type default)
			)
			(layer "B.Fab")
		)
		(pad "1" smd circle
			(at 0.40005 0 270)
			(size 0 0)
			(layers "B.Cu" "B.Mask" "B.Paste")
			(net "SPI_PCH_CS0_R_N")
		)
		(pad "2" smd circle
			(at -0.40005 0 270)
			(size 0 0)
			(layers "B.Cu" "B.Mask" "B.Paste")
			(net "SPI_SYS_CS0_N")
		)
	)
	(footprint ""
		(layer "B.Cu")
		(at 54.50332 -344.727276 -90)
		(property "Reference" "PC408_P1_2"
			(at 0 0 90)
			(layer "B.SilkS")
			(hide yes)
			(effects
				(font
					(size 1.27 1.27)
				)
				(justify mirror)
			)
		)
		(property "Value" ""
			(at 0 0 90)
			(layer "B.Fab")
			(effects
				(font
					(size 1.27 1.27)
				)
				(justify mirror)
			)
		)
		(duplicate_pad_numbers_are_jumpers no)
		(fp_line
			(start -0.7874 0.4064)
			(end 0.7874 0.4064)
			(stroke
				(width 0.1524)
				(type default)
			)
			(layer "B.SilkS")
		)
		(fp_line
			(start 0.7874 0.4064)
			(end 0.7874 -0.4064)
			(stroke
				(width 0.1524)
				(type default)
			)
			(layer "B.SilkS")
		)
		(fp_line
			(start -0.7874 -0.4064)
			(end -0.7874 0.4064)
			(stroke
				(width 0.1524)
				(type default)
			)
			(layer "B.SilkS")
		)
		(fp_line
			(start 0.7874 -0.4064)
			(end -0.7874 -0.4064)
			(stroke
				(width 0.1524)
				(type default)
			)
			(layer "B.SilkS")
		)
		(fp_line
			(start -0.67945 0.3048)
			(end -0.120396 0.3048)
			(stroke
				(width 0.1)
				(type default)
			)
			(layer "B.Fab")
		)
		(fp_line
			(start -0.120396 0.3048)
			(end -0.120396 0.2794)
			(stroke
				(width 0.1)
				(type default)
			)
			(layer "B.Fab")
		)
		(fp_line
			(start 0.12065 0.3048)
			(end 0.67945 0.3048)
			(stroke
				(width 0.1)
				(type default)
			)
			(layer "B.Fab")
		)
		(fp_line
			(start 0.67945 0.3048)
			(end 0.67945 -0.305054)
			(stroke
				(width 0.1)
				(type default)
			)
			(layer "B.Fab")
		)
		(fp_line
			(start -0.120396 0.2794)
			(end 0.12065 0.2794)
			(stroke
				(width 0.1)
				(type default)
			)
			(layer "B.Fab")
		)
		(fp_line
			(start 0.12065 0.2794)
			(end 0.12065 0.3048)
			(stroke
				(width 0.1)
				(type default)
			)
			(layer "B.Fab")
		)
		(fp_line
			(start -0.12065 -0.2794)
			(end -0.12065 -0.3048)
			(stroke
				(width 0.1)
				(type default)
			)
			(layer "B.Fab")
		)
		(fp_line
			(start 0.12065 -0.2794)
			(end -0.12065 -0.2794)
			(stroke
				(width 0.1)
				(type default)
			)
			(layer "B.Fab")
		)
		(fp_line
			(start -0.67945 -0.3048)
			(end -0.67945 0.3048)
			(stroke
				(width 0.1)
				(type default)
			)
			(layer "B.Fab")
		)
		(fp_line
			(start -0.12065 -0.3048)
			(end -0.67945 -0.3048)
			(stroke
				(width 0.1)
				(type default)
			)
			(layer "B.Fab")
		)
		(fp_line
			(start 0.12065 -0.305054)
			(end 0.12065 -0.2794)
			(stroke
				(width 0.1)
				(type default)
			)
			(layer "B.Fab")
		)
		(fp_line
			(start 0.67945 -0.305054)
			(end 0.12065 -0.305054)
			(stroke
				(width 0.1)
				(type default)
			)
			(layer "B.Fab")
		)
		(pad "1" smd circle
			(at 0.40005 0 90)
			(size 0 0)
			(layers "B.Cu" "B.Mask" "B.Paste")
			(net "PVCCFA_EHV_FIVRA_CPU1")
		)
		(pad "2" smd circle
			(at -0.40005 0 90)
			(size 0 0)
			(layers "B.Cu" "B.Mask" "B.Paste")
			(net "GND")
		)
	)
	(footprint ""
		(layer "B.Cu")
		(at 288.464498 -403.031452 90)
		(property "Reference" "PR2514"
			(at 0 0 90)
			(layer "B.SilkS")
			(hide yes)
			(effects
				(font
					(size 1.27 1.27)
				)
				(justify mirror)
			)
		)
		(property "Value" ""
			(at 0 0 90)
			(layer "B.Fab")
			(effects
				(font
					(size 1.27 1.27)
				)
				(justify mirror)
			)
		)
		(duplicate_pad_numbers_are_jumpers no)
		(fp_line
			(start 0.7874 -0.4064)
			(end -0.7874 -0.4064)
			(stroke
				(width 0.1524)
				(type default)
			)
			(layer "B.SilkS")
		)
		(fp_line
			(start -0.7874 -0.4064)
			(end -0.7874 0.4064)
			(stroke
				(width 0.1524)
				(type default)
			)
			(layer "B.SilkS")
		)
		(fp_line
			(start 0.7874 0.4064)
			(end 0.7874 -0.4064)
			(stroke
				(width 0.1524)
				(type default)
			)
			(layer "B.SilkS")
		)
		(fp_line
			(start -0.7874 0.4064)
			(end 0.7874 0.4064)
			(stroke
				(width 0.1524)
				(type default)
			)
			(layer "B.SilkS")
		)
		(fp_line
			(start 0.67945 -0.305054)
			(end 0.12065 -0.305054)
			(stroke
				(width 0.1)
				(type default)
			)
			(layer "B.Fab")
		)
		(fp_line
			(start 0.12065 -0.305054)
			(end 0.12065 -0.2794)
			(stroke
				(width 0.1)
				(type default)
			)
			(layer "B.Fab")
		)
		(fp_line
			(start -0.12065 -0.3048)
			(end -0.67945 -0.3048)
			(stroke
				(width 0.1)
				(type default)
			)
			(layer "B.Fab")
		)
		(fp_line
			(start -0.67945 -0.3048)
			(end -0.67945 0.3048)
			(stroke
				(width 0.1)
				(type default)
			)
			(layer "B.Fab")
		)
		(fp_line
			(start 0.12065 -0.2794)
			(end -0.12065 -0.2794)
			(stroke
				(width 0.1)
				(type default)
			)
			(layer "B.Fab")
		)
		(fp_line
			(start -0.12065 -0.2794)
			(end -0.12065 -0.3048)
			(stroke
				(width 0.1)
				(type default)
			)
			(layer "B.Fab")
		)
		(fp_line
			(start 0.12065 0.2794)
			(end 0.12065 0.3048)
			(stroke
				(width 0.1)
				(type default)
			)
			(layer "B.Fab")
		)
		(fp_line
			(start -0.120396 0.2794)
			(end 0.12065 0.2794)
			(stroke
				(width 0.1)
				(type default)
			)
			(layer "B.Fab")
		)
		(fp_line
			(start 0.67945 0.3048)
			(end 0.67945 -0.305054)
			(stroke
				(width 0.1)
				(type default)
			)
			(layer "B.Fab")
		)
		(fp_line
			(start 0.12065 0.3048)
			(end 0.67945 0.3048)
			(stroke
				(width 0.1)
				(type default)
			)
			(layer "B.Fab")
		)
		(fp_line
			(start -0.120396 0.3048)
			(end -0.120396 0.2794)
			(stroke
				(width 0.1)
				(type default)
			)
			(layer "B.Fab")
		)
		(fp_line
			(start -0.67945 0.3048)
			(end -0.120396 0.3048)
			(stroke
				(width 0.1)
				(type default)
			)
			(layer "B.Fab")
		)
		(pad "1" smd circle
			(at 0.40005 0 270)
			(size 0 0)
			(layers "B.Cu" "B.Mask" "B.Paste")
			(net "P12V_HSC_ADC_P")
		)
		(pad "2" smd circle
			(at -0.40005 0 270)
			(size 0 0)
			(layers "B.Cu" "B.Mask" "B.Paste")
			(net "P12V_HSC_SENSE1_P")
		)
	)
	(footprint ""
		(layer "B.Cu")
		(at 433.328318 -177.15611 90)
		(property "Reference" "C1307"
			(at 0 0 90)
			(layer "B.SilkS")
			(hide yes)
			(effects
				(font
					(size 1.27 1.27)
				)
				(justify mirror)
			)
		)
		(property "Value" ""
			(at 0 0 90)
			(layer "B.Fab")
			(effects
				(font
					(size 1.27 1.27)
				)
				(justify mirror)
			)
		)
		(duplicate_pad_numbers_are_jumpers no)
		(fp_line
			(start 0.7874 -0.4064)
			(end -0.7874 -0.4064)
			(stroke
				(width 0.1524)
				(type default)
			)
			(layer "B.SilkS")
		)
		(fp_line
			(start -0.7874 -0.4064)
			(end -0.7874 0.4064)
			(stroke
				(width 0.1524)
				(type default)
			)
			(layer "B.SilkS")
		)
		(fp_line
			(start 0.7874 0.4064)
			(end 0.7874 -0.4064)
			(stroke
				(width 0.1524)
				(type default)
			)
			(layer "B.SilkS")
		)
		(fp_line
			(start -0.7874 0.4064)
			(end 0.7874 0.4064)
			(stroke
				(width 0.1524)
				(type default)
			)
			(layer "B.SilkS")
		)
		(fp_line
			(start 0.67945 -0.305054)
			(end 0.12065 -0.305054)
			(stroke
				(width 0.1)
				(type default)
			)
			(layer "B.Fab")
		)
		(fp_line
			(start 0.12065 -0.305054)
			(end 0.12065 -0.2794)
			(stroke
				(width 0.1)
				(type default)
			)
			(layer "B.Fab")
		)
		(fp_line
			(start -0.12065 -0.3048)
			(end -0.67945 -0.3048)
			(stroke
				(width 0.1)
				(type default)
			)
			(layer "B.Fab")
		)
		(fp_line
			(start -0.67945 -0.3048)
			(end -0.67945 0.3048)
			(stroke
				(width 0.1)
				(type default)
			)
			(layer "B.Fab")
		)
		(fp_line
			(start 0.12065 -0.2794)
			(end -0.12065 -0.2794)
			(stroke
				(width 0.1)
				(type default)
			)
			(layer "B.Fab")
		)
		(fp_line
			(start -0.12065 -0.2794)
			(end -0.12065 -0.3048)
			(stroke
				(width 0.1)
				(type default)
			)
			(layer "B.Fab")
		)
		(fp_line
			(start 0.12065 0.2794)
			(end 0.12065 0.3048)
			(stroke
				(width 0.1)
				(type default)
			)
			(layer "B.Fab")
		)
		(fp_line
			(start -0.120396 0.2794)
			(end 0.12065 0.2794)
			(stroke
				(width 0.1)
				(type default)
			)
			(layer "B.Fab")
		)
		(fp_line
			(start 0.67945 0.3048)
			(end 0.67945 -0.305054)
			(stroke
				(width 0.1)
				(type default)
			)
			(layer "B.Fab")
		)
		(fp_line
			(start 0.12065 0.3048)
			(end 0.67945 0.3048)
			(stroke
				(width 0.1)
				(type default)
			)
			(layer "B.Fab")
		)
		(fp_line
			(start -0.120396 0.3048)
			(end -0.120396 0.2794)
			(stroke
				(width 0.1)
				(type default)
			)
			(layer "B.Fab")
		)
		(fp_line
			(start -0.67945 0.3048)
			(end -0.120396 0.3048)
			(stroke
				(width 0.1)
				(type default)
			)
			(layer "B.Fab")
		)
		(pad "1" smd circle
			(at 0.40005 0 270)
			(size 0 0)
			(layers "B.Cu" "B.Mask" "B.Paste")
			(net "FM_PVNN_MAIN_CPU0_EN")
		)
		(pad "2" smd circle
			(at -0.40005 0 270)
			(size 0 0)
			(layers "B.Cu" "B.Mask" "B.Paste")
			(net "GND")
		)
	)
	(footprint ""
		(layer "B.Cu")
		(at 106.27995 -333.639922 90)
		(property "Reference" "PC566_P1_2"
			(at 0 0 90)
			(layer "B.SilkS")
			(hide yes)
			(effects
				(font
					(size 1.27 1.27)
				)
				(justify mirror)
			)
		)
		(property "Value" ""
			(at 0 0 90)
			(layer "B.Fab")
			(effects
				(font
					(size 1.27 1.27)
				)
				(justify mirror)
			)
		)
		(duplicate_pad_numbers_are_jumpers no)
		(fp_line
			(start 1.524 -0.762)
			(end -1.524 -0.762)
			(stroke
				(width 0.1524)
				(type default)
			)
			(layer "B.SilkS")
		)
		(fp_line
			(start -1.524 -0.762)
			(end -1.524 0.762)
			(stroke
				(width 0.1524)
				(type default)
			)
			(layer "B.SilkS")
		)
		(fp_line
			(start 1.524 0.762)
			(end 1.524 -0.762)
			(stroke
				(width 0.1524)
				(type default)
			)
			(layer "B.SilkS")
		)
		(fp_line
			(start -1.524 0.762)
			(end 1.524 0.762)
			(stroke
				(width 0.1524)
				(type default)
			)
			(layer "B.SilkS")
		)
		(fp_line
			(start 1.1049 -0.724916)
			(end 1.1049 0.724916)
			(stroke
				(width 0.1)
				(type default)
			)
			(layer "B.Fab")
		)
		(fp_line
			(start -1.1049 -0.724916)
			(end 1.1049 -0.724916)
			(stroke
				(width 0.1)
				(type default)
			)
			(layer "B.Fab")
		)
		(fp_line
			(start 1.1049 0.724916)
			(end -1.1049 0.724916)
			(stroke
				(width 0.1)
				(type default)
			)
			(layer "B.Fab")
		)
		(fp_line
			(start -1.1049 0.724916)
			(end -1.1049 -0.724916)
			(stroke
				(width 0.1)
				(type default)
			)
			(layer "B.Fab")
		)
		(pad "1" smd rect
			(at 0.889 0 90)
			(size 1.016 1.27)
			(layers "B.Cu" "B.Mask" "B.Paste")
			(net "SW_P12V_PVCCIN_CPU1_FLT")
		)
		(pad "2" smd rect
			(at -0.889 0 90)
			(size 1.016 1.27)
			(layers "B.Cu" "B.Mask" "B.Paste")
			(net "GND")
		)
	)
	(footprint ""
		(layer "B.Cu")
		(at 205.570582 -318.392048)
		(property "Reference" "R72"
			(at 0 0 0)
			(layer "B.SilkS")
			(hide yes)
			(effects
				(font
					(size 1.27 1.27)
				)
				(justify mirror)
			)
		)
		(property "Value" ""
			(at 0 0 0)
			(layer "B.Fab")
			(effects
				(font
					(size 1.27 1.27)
				)
				(justify mirror)
			)
		)
		(duplicate_pad_numbers_are_jumpers no)
		(fp_line
			(start -0.7874 -0.4064)
			(end -0.7874 0.4064)
			(stroke
				(width 0.1524)
				(type default)
			)
			(layer "B.SilkS")
		)
		(fp_line
			(start -0.7874 0.4064)
			(end 0.7874 0.4064)
			(stroke
				(width 0.1524)
				(type default)
			)
			(layer "B.SilkS")
		)
		(fp_line
			(start 0.7874 -0.4064)
			(end -0.7874 -0.4064)
			(stroke
				(width 0.1524)
				(type default)
			)
			(layer "B.SilkS")
		)
		(fp_line
			(start 0.7874 0.4064)
			(end 0.7874 -0.4064)
			(stroke
				(width 0.1524)
				(type default)
			)
			(layer "B.SilkS")
		)
		(fp_line
			(start -0.67945 -0.3048)
			(end -0.67945 0.3048)
			(stroke
				(width 0.1)
				(type default)
			)
			(layer "B.Fab")
		)
		(fp_line
			(start -0.67945 0.3048)
			(end -0.120396 0.3048)
			(stroke
				(width 0.1)
				(type default)
			)
			(layer "B.Fab")
		)
		(fp_line
			(start -0.12065 -0.3048)
			(end -0.67945 -0.3048)
			(stroke
				(width 0.1)
				(type default)
			)
			(layer "B.Fab")
		)
		(fp_line
			(start -0.12065 -0.2794)
			(end -0.12065 -0.3048)
			(stroke
				(width 0.1)
				(type default)
			)
			(layer "B.Fab")
		)
		(fp_line
			(start -0.120396 0.2794)
			(end 0.12065 0.2794)
			(stroke
				(width 0.1)
				(type default)
			)
			(layer "B.Fab")
		)
		(fp_line
			(start -0.120396 0.3048)
			(end -0.120396 0.2794)
			(stroke
				(width 0.1)
				(type default)
			)
			(layer "B.Fab")
		)
		(fp_line
			(start 0.12065 -0.305054)
			(end 0.12065 -0.2794)
			(stroke
				(width 0.1)
				(type default)
			)
			(layer "B.Fab")
		)
		(fp_line
			(start 0.12065 -0.2794)
			(end -0.12065 -0.2794)
			(stroke
				(width 0.1)
				(type default)
			)
			(layer "B.Fab")
		)
		(fp_line
			(start 0.12065 0.2794)
			(end 0.12065 0.3048)
			(stroke
				(width 0.1)
				(type default)
			)
			(layer "B.Fab")
		)
		(fp_line
			(start 0.12065 0.3048)
			(end 0.67945 0.3048)
			(stroke
				(width 0.1)
				(type default)
			)
			(layer "B.Fab")
		)
		(fp_line
			(start 0.67945 -0.305054)
			(end 0.12065 -0.305054)
			(stroke
				(width 0.1)
				(type default)
			)
			(layer "B.Fab")
		)
		(fp_line
			(start 0.67945 0.3048)
			(end 0.67945 -0.305054)
			(stroke
				(width 0.1)
				(type default)
			)
			(layer "B.Fab")
		)
		(pad "1" smd circle
			(at 0.40005 0 180)
			(size 0 0)
			(layers "B.Cu" "B.Mask" "B.Paste")
			(net "PD_CHH_CPU1_DIMM2_SAA")
		)
		(pad "2" smd circle
			(at -0.40005 0 180)
			(size 0 0)
			(layers "B.Cu" "B.Mask" "B.Paste")
			(net "GND")
		)
	)
	(footprint ""
		(layer "B.Cu")
		(at 298.566332 -152.038558 180)
		(property "Reference" "U15"
			(at -1.392936 -4.58851 0)
			(unlocked yes)
			(layer "B.SilkS")
			(effects
				(font
					(size 0.7874 0.5842)
					(thickness 0.1524)
				)
				(justify left mirror)
			)
		)
		(property "Value" ""
			(at 0 0 0)
			(layer "B.Fab")
			(effects
				(font
					(size 1.27 1.27)
				)
				(justify mirror)
			)
		)
		(duplicate_pad_numbers_are_jumpers no)
		(fp_line
			(start 1.7272 2.489962)
			(end 1.7272 -2.489962)
			(stroke
				(width 0.1524)
				(type default)
			)
			(layer "B.SilkS")
		)
		(fp_line
			(start 1.7272 -2.489962)
			(end 0.779018 -2.489962)
			(stroke
				(width 0.1524)
				(type default)
			)
			(layer "B.SilkS")
		)
		(fp_line
			(start 0.779018 -2.489962)
			(end 0 -1.710944)
			(stroke
				(width 0.1524)
				(type default)
			)
			(layer "B.SilkS")
		)
		(fp_line
			(start 0 -1.710944)
			(end -0.779018 -2.489962)
			(stroke
				(width 0.1524)
				(type default)
			)
			(layer "B.SilkS")
		)
		(fp_line
			(start -0.779018 -2.489962)
			(end -1.7272 -2.489962)
			(stroke
				(width 0.1524)
				(type default)
			)
			(layer "B.SilkS")
		)
		(fp_line
			(start -1.7272 2.489962)
			(end 1.7272 2.489962)
			(stroke
				(width 0.1524)
				(type default)
			)
			(layer "B.SilkS")
		)
		(fp_line
			(start -1.7272 -2.489962)
			(end -1.7272 2.489962)
			(stroke
				(width 0.1524)
				(type default)
			)
			(layer "B.SilkS")
		)
		(fp_poly
			(pts
				(xy 3.307842 -3.782314) (xy 2.799842 -2.766314) (xy 2.291842 -3.782314)
			)
			(stroke
				(width 0)
				(type default)
			)
			(fill yes)
			(layer "B.SilkS")
		)
		(fp_line
			(start 1.994916 2.489962)
			(end 1.994916 -2.489962)
			(stroke
				(width 0.1)
				(type default)
			)
			(layer "B.Fab")
		)
		(fp_line
			(start 1.994916 -2.489962)
			(end -1.994916 -2.489962)
			(stroke
				(width 0.1)
				(type default)
			)
			(layer "B.Fab")
		)
		(fp_line
			(start -1.994916 2.489962)
			(end 1.994916 2.489962)
			(stroke
				(width 0.1)
				(type default)
			)
			(layer "B.Fab")
		)
		(fp_line
			(start -1.994916 -2.489962)
			(end -1.994916 2.489962)
			(stroke
				(width 0.1)
				(type default)
			)
			(layer "B.Fab")
		)
		(fp_poly
			(pts
				(xy 4.837176 -2.7305) (xy 4.837176 -1.7145) (xy 3.821176 -2.2225)
			)
			(stroke
				(width 0)
				(type default)
			)
			(fill yes)
			(layer "B.Fab")
		)
		(pad "1" smd rect
			(at 2.6924 -2.2225 90)
			(size 0.4318 1.6764)
			(layers "B.Cu" "B.Mask" "B.Paste")
			(net "FM_SPD_REMOTE_EN")
		)
		(pad "2" smd rect
			(at 2.6924 -1.5875 90)
			(size 0.4318 1.6764)
			(layers "B.Cu" "B.Mask" "B.Paste")
			(net "I3C_SPD_DDRABCD_CPU0_R_SCL")
		)
		(pad "3" smd rect
			(at 2.6924 -0.9525 90)
			(size 0.4318 1.6764)
			(layers "B.Cu" "B.Mask" "B.Paste")
			(net "I3C_SPD_DDRABCD_CPU0_BMC_SCL")
		)
		(pad "4" smd rect
			(at 2.6924 -0.3175 90)
			(size 0.4318 1.6764)
			(layers "B.Cu" "B.Mask" "B.Paste")
			(net "I3C_SPD_DDRABCD_CPU0_LVC1_R_SCL")
		)
		(pad "5" smd rect
			(at 2.6924 0.3175 90)
			(size 0.4318 1.6764)
			(layers "B.Cu" "B.Mask" "B.Paste")
			(net "I3C_SPD_DDRABCD_CPU0_R_SDA")
		)
		(pad "6" smd rect
			(at 2.6924 0.9525 90)
			(size 0.4318 1.6764)
			(layers "B.Cu" "B.Mask" "B.Paste")
			(net "I3C_SPD_DDRABCD_CPU0_BMC_SDA")
		)
		(pad "7" smd rect
			(at 2.6924 1.5875 90)
			(size 0.4318 1.6764)
			(layers "B.Cu" "B.Mask" "B.Paste")
			(net "I3C_SPD_DDRABCD_CPU0_LVC1_R_SDA")
		)
		(pad "8" smd rect
			(at 2.6924 2.2225 90)
			(size 0.4318 1.6764)
			(layers "B.Cu" "B.Mask" "B.Paste")
			(net "GND")
		)
		(pad "9" smd rect
			(at -2.6924 2.2225 90)
			(size 0.4318 1.6764)
			(layers "B.Cu" "B.Mask" "B.Paste")
			(net "I3C_SPD_DDREFGH_CPU0_LVC1_R_SCL")
		)
		(pad "10" smd rect
			(at -2.6924 1.5875 90)
			(size 0.4318 1.6764)
			(layers "B.Cu" "B.Mask" "B.Paste")
			(net "I3C_SPD_DDREFGH_CPU0_BMC_SCL")
		)
		(pad "11" smd rect
			(at -2.6924 0.9525 90)
			(size 0.4318 1.6764)
			(layers "B.Cu" "B.Mask" "B.Paste")
			(net "I3C_SPD_DDREFGH_CPU0_R_SCL")
		)
		(pad "12" smd rect
			(at -2.6924 0.3175 90)
			(size 0.4318 1.6764)
			(layers "B.Cu" "B.Mask" "B.Paste")
			(net "I3C_SPD_DDREFGH_CPU0_LVC1_R_SDA")
		)
		(pad "13" smd rect
			(at -2.6924 -0.3175 90)
			(size 0.4318 1.6764)
			(layers "B.Cu" "B.Mask" "B.Paste")
			(net "I3C_SPD_DDREFGH_CPU0_BMC_SDA")
		)
		(pad "14" smd rect
			(at -2.6924 -0.9525 90)
			(size 0.4318 1.6764)
			(layers "B.Cu" "B.Mask" "B.Paste")
			(net "I3C_SPD_DDREFGH_CPU0_R_SDA")
		)
		(pad "15" smd rect
			(at -2.6924 -1.5875 90)
			(size 0.4318 1.6764)
			(layers "B.Cu" "B.Mask" "B.Paste")
			(net "PD_I3C_SPD_DDR_CPU0_OE_N")
		)
		(pad "16" smd rect
			(at -2.6924 -2.2225 90)
			(size 0.4318 1.6764)
			(layers "B.Cu" "B.Mask" "B.Paste")
			(net "P3V3_AUX")
		)
	)
	(footprint ""
		(layer "B.Cu")
		(at 181.86146 -18.710148 90)
		(property "Reference" "R2419"
			(at 0 0 90)
			(layer "B.SilkS")
			(hide yes)
			(effects
				(font
					(size 1.27 1.27)
				)
				(justify mirror)
			)
		)
		(property "Value" ""
			(at 0 0 90)
			(layer "B.Fab")
			(effects
				(font
					(size 1.27 1.27)
				)
				(justify mirror)
			)
		)
		(duplicate_pad_numbers_are_jumpers no)
		(fp_line
			(start 0.7874 -0.4064)
			(end -0.7874 -0.4064)
			(stroke
				(width 0.1524)
				(type default)
			)
			(layer "B.SilkS")
		)
		(fp_line
			(start -0.7874 -0.4064)
			(end -0.7874 0.4064)
			(stroke
				(width 0.1524)
				(type default)
			)
			(layer "B.SilkS")
		)
		(fp_line
			(start 0.7874 0.4064)
			(end 0.7874 -0.4064)
			(stroke
				(width 0.1524)
				(type default)
			)
			(layer "B.SilkS")
		)
		(fp_line
			(start -0.7874 0.4064)
			(end 0.7874 0.4064)
			(stroke
				(width 0.1524)
				(type default)
			)
			(layer "B.SilkS")
		)
		(fp_line
			(start 0.67945 -0.305054)
			(end 0.12065 -0.305054)
			(stroke
				(width 0.1)
				(type default)
			)
			(layer "B.Fab")
		)
		(fp_line
			(start 0.12065 -0.305054)
			(end 0.12065 -0.2794)
			(stroke
				(width 0.1)
				(type default)
			)
			(layer "B.Fab")
		)
		(fp_line
			(start -0.12065 -0.3048)
			(end -0.67945 -0.3048)
			(stroke
				(width 0.1)
				(type default)
			)
			(layer "B.Fab")
		)
		(fp_line
			(start -0.67945 -0.3048)
			(end -0.67945 0.3048)
			(stroke
				(width 0.1)
				(type default)
			)
			(layer "B.Fab")
		)
		(fp_line
			(start 0.12065 -0.2794)
			(end -0.12065 -0.2794)
			(stroke
				(width 0.1)
				(type default)
			)
			(layer "B.Fab")
		)
		(fp_line
			(start -0.12065 -0.2794)
			(end -0.12065 -0.3048)
			(stroke
				(width 0.1)
				(type default)
			)
			(layer "B.Fab")
		)
		(fp_line
			(start 0.12065 0.2794)
			(end 0.12065 0.3048)
			(stroke
				(width 0.1)
				(type default)
			)
			(layer "B.Fab")
		)
		(fp_line
			(start -0.120396 0.2794)
			(end 0.12065 0.2794)
			(stroke
				(width 0.1)
				(type default)
			)
			(layer "B.Fab")
		)
		(fp_line
			(start 0.67945 0.3048)
			(end 0.67945 -0.305054)
			(stroke
				(width 0.1)
				(type default)
			)
			(layer "B.Fab")
		)
		(fp_line
			(start 0.12065 0.3048)
			(end 0.67945 0.3048)
			(stroke
				(width 0.1)
				(type default)
			)
			(layer "B.Fab")
		)
		(fp_line
			(start -0.120396 0.3048)
			(end -0.120396 0.2794)
			(stroke
				(width 0.1)
				(type default)
			)
			(layer "B.Fab")
		)
		(fp_line
			(start -0.67945 0.3048)
			(end -0.120396 0.3048)
			(stroke
				(width 0.1)
				(type default)
			)
			(layer "B.Fab")
		)
		(pad "1" smd circle
			(at 0.40005 0 270)
			(size 0 0)
			(layers "B.Cu" "B.Mask" "B.Paste")
			(net "SMB_HOST_3V3AUX_SCL")
		)
		(pad "2" smd circle
			(at -0.40005 0 270)
			(size 0 0)
			(layers "B.Cu" "B.Mask" "B.Paste")
			(net "SMB_HOST_3V3AUX_SCL_R0")
		)
	)
	(footprint ""
		(layer "B.Cu")
		(at 82.462624 -184.096152 90)
		(property "Reference" "R337"
			(at 0 0 90)
			(layer "B.SilkS")
			(hide yes)
			(effects
				(font
					(size 1.27 1.27)
				)
				(justify mirror)
			)
		)
		(property "Value" ""
			(at 0 0 90)
			(layer "B.Fab")
			(effects
				(font
					(size 1.27 1.27)
				)
				(justify mirror)
			)
		)
		(duplicate_pad_numbers_are_jumpers no)
		(fp_line
			(start 0.7874 -0.4064)
			(end -0.7874 -0.4064)
			(stroke
				(width 0.1524)
				(type default)
			)
			(layer "B.SilkS")
		)
		(fp_line
			(start -0.7874 -0.4064)
			(end -0.7874 0.4064)
			(stroke
				(width 0.1524)
				(type default)
			)
			(layer "B.SilkS")
		)
		(fp_line
			(start 0.7874 0.4064)
			(end 0.7874 -0.4064)
			(stroke
				(width 0.1524)
				(type default)
			)
			(layer "B.SilkS")
		)
		(fp_line
			(start -0.7874 0.4064)
			(end 0.7874 0.4064)
			(stroke
				(width 0.1524)
				(type default)
			)
			(layer "B.SilkS")
		)
		(fp_line
			(start 0.67945 -0.305054)
			(end 0.12065 -0.305054)
			(stroke
				(width 0.1)
				(type default)
			)
			(layer "B.Fab")
		)
		(fp_line
			(start 0.12065 -0.305054)
			(end 0.12065 -0.2794)
			(stroke
				(width 0.1)
				(type default)
			)
			(layer "B.Fab")
		)
		(fp_line
			(start -0.12065 -0.3048)
			(end -0.67945 -0.3048)
			(stroke
				(width 0.1)
				(type default)
			)
			(layer "B.Fab")
		)
		(fp_line
			(start -0.67945 -0.3048)
			(end -0.67945 0.3048)
			(stroke
				(width 0.1)
				(type default)
			)
			(layer "B.Fab")
		)
		(fp_line
			(start 0.12065 -0.2794)
			(end -0.12065 -0.2794)
			(stroke
				(width 0.1)
				(type default)
			)
			(layer "B.Fab")
		)
		(fp_line
			(start -0.12065 -0.2794)
			(end -0.12065 -0.3048)
			(stroke
				(width 0.1)
				(type default)
			)
			(layer "B.Fab")
		)
		(fp_line
			(start 0.12065 0.2794)
			(end 0.12065 0.3048)
			(stroke
				(width 0.1)
				(type default)
			)
			(layer "B.Fab")
		)
		(fp_line
			(start -0.120396 0.2794)
			(end 0.12065 0.2794)
			(stroke
				(width 0.1)
				(type default)
			)
			(layer "B.Fab")
		)
		(fp_line
			(start 0.67945 0.3048)
			(end 0.67945 -0.305054)
			(stroke
				(width 0.1)
				(type default)
			)
			(layer "B.Fab")
		)
		(fp_line
			(start 0.12065 0.3048)
			(end 0.67945 0.3048)
			(stroke
				(width 0.1)
				(type default)
			)
			(layer "B.Fab")
		)
		(fp_line
			(start -0.120396 0.3048)
			(end -0.120396 0.2794)
			(stroke
				(width 0.1)
				(type default)
			)
			(layer "B.Fab")
		)
		(fp_line
			(start -0.67945 0.3048)
			(end -0.120396 0.3048)
			(stroke
				(width 0.1)
				(type default)
			)
			(layer "B.Fab")
		)
		(pad "1" smd circle
			(at 0.40005 0 270)
			(size 0 0)
			(layers "B.Cu" "B.Mask" "B.Paste")
			(net "H_CPU1_ERR0_LVC1_R_N")
		)
		(pad "2" smd circle
			(at -0.40005 0 270)
			(size 0 0)
			(layers "B.Cu" "B.Mask" "B.Paste")
			(net "H_CPU_ERR0_LVC1_R_N")
		)
	)
	(footprint ""
		(layer "B.Cu")
		(at 293.544498 -400.999452 -90)
		(property "Reference" "PR2523"
			(at 0 0 90)
			(layer "B.SilkS")
			(hide yes)
			(effects
				(font
					(size 1.27 1.27)
				)
				(justify mirror)
			)
		)
		(property "Value" ""
			(at 0 0 90)
			(layer "B.Fab")
			(effects
				(font
					(size 1.27 1.27)
				)
				(justify mirror)
			)
		)
		(duplicate_pad_numbers_are_jumpers no)
		(fp_line
			(start -0.7874 0.4064)
			(end 0.7874 0.4064)
			(stroke
				(width 0.1524)
				(type default)
			)
			(layer "B.SilkS")
		)
		(fp_line
			(start 0.7874 0.4064)
			(end 0.7874 -0.4064)
			(stroke
				(width 0.1524)
				(type default)
			)
			(layer "B.SilkS")
		)
		(fp_line
			(start -0.7874 -0.4064)
			(end -0.7874 0.4064)
			(stroke
				(width 0.1524)
				(type default)
			)
			(layer "B.SilkS")
		)
		(fp_line
			(start 0.7874 -0.4064)
			(end -0.7874 -0.4064)
			(stroke
				(width 0.1524)
				(type default)
			)
			(layer "B.SilkS")
		)
		(fp_line
			(start -0.67945 0.3048)
			(end -0.120396 0.3048)
			(stroke
				(width 0.1)
				(type default)
			)
			(layer "B.Fab")
		)
		(fp_line
			(start -0.120396 0.3048)
			(end -0.120396 0.2794)
			(stroke
				(width 0.1)
				(type default)
			)
			(layer "B.Fab")
		)
		(fp_line
			(start 0.12065 0.3048)
			(end 0.67945 0.3048)
			(stroke
				(width 0.1)
				(type default)
			)
			(layer "B.Fab")
		)
		(fp_line
			(start 0.67945 0.3048)
			(end 0.67945 -0.305054)
			(stroke
				(width 0.1)
				(type default)
			)
			(layer "B.Fab")
		)
		(fp_line
			(start -0.120396 0.2794)
			(end 0.12065 0.2794)
			(stroke
				(width 0.1)
				(type default)
			)
			(layer "B.Fab")
		)
		(fp_line
			(start 0.12065 0.2794)
			(end 0.12065 0.3048)
			(stroke
				(width 0.1)
				(type default)
			)
			(layer "B.Fab")
		)
		(fp_line
			(start -0.12065 -0.2794)
			(end -0.12065 -0.3048)
			(stroke
				(width 0.1)
				(type default)
			)
			(layer "B.Fab")
		)
		(fp_line
			(start 0.12065 -0.2794)
			(end -0.12065 -0.2794)
			(stroke
				(width 0.1)
				(type default)
			)
			(layer "B.Fab")
		)
		(fp_line
			(start -0.67945 -0.3048)
			(end -0.67945 0.3048)
			(stroke
				(width 0.1)
				(type default)
			)
			(layer "B.Fab")
		)
		(fp_line
			(start -0.12065 -0.3048)
			(end -0.67945 -0.3048)
			(stroke
				(width 0.1)
				(type default)
			)
			(layer "B.Fab")
		)
		(fp_line
			(start 0.12065 -0.305054)
			(end 0.12065 -0.2794)
			(stroke
				(width 0.1)
				(type default)
			)
			(layer "B.Fab")
		)
		(fp_line
			(start 0.67945 -0.305054)
			(end 0.12065 -0.305054)
			(stroke
				(width 0.1)
				(type default)
			)
			(layer "B.Fab")
		)
		(pad "1" smd circle
			(at 0.40005 0 90)
			(size 0 0)
			(layers "B.Cu" "B.Mask" "B.Paste")
			(net "P12V_HSC_SENSE2_P")
		)
		(pad "2" smd circle
			(at -0.40005 0 90)
			(size 0 0)
			(layers "B.Cu" "B.Mask" "B.Paste")
			(net "P12V_HSC_SENSE2_R4_P")
		)
	)
	(footprint ""
		(layer "B.Cu")
		(at 361.691174 -361.759246)
		(property "Reference" "PR156"
			(at 0 0 0)
			(layer "B.SilkS")
			(hide yes)
			(effects
				(font
					(size 1.27 1.27)
				)
				(justify mirror)
			)
		)
		(property "Value" ""
			(at 0 0 0)
			(layer "B.Fab")
			(effects
				(font
					(size 1.27 1.27)
				)
				(justify mirror)
			)
		)
		(duplicate_pad_numbers_are_jumpers no)
		(fp_line
			(start -0.7874 -0.4064)
			(end -0.7874 0.4064)
			(stroke
				(width 0.1524)
				(type default)
			)
			(layer "B.SilkS")
		)
		(fp_line
			(start -0.7874 0.4064)
			(end 0.7874 0.4064)
			(stroke
				(width 0.1524)
				(type default)
			)
			(layer "B.SilkS")
		)
		(fp_line
			(start 0.7874 -0.4064)
			(end -0.7874 -0.4064)
			(stroke
				(width 0.1524)
				(type default)
			)
			(layer "B.SilkS")
		)
		(fp_line
			(start 0.7874 0.4064)
			(end 0.7874 -0.4064)
			(stroke
				(width 0.1524)
				(type default)
			)
			(layer "B.SilkS")
		)
		(fp_line
			(start -0.67945 -0.3048)
			(end -0.67945 0.3048)
			(stroke
				(width 0.1)
				(type default)
			)
			(layer "B.Fab")
		)
		(fp_line
			(start -0.67945 0.3048)
			(end -0.120396 0.3048)
			(stroke
				(width 0.1)
				(type default)
			)
			(layer "B.Fab")
		)
		(fp_line
			(start -0.12065 -0.3048)
			(end -0.67945 -0.3048)
			(stroke
				(width 0.1)
				(type default)
			)
			(layer "B.Fab")
		)
		(fp_line
			(start -0.12065 -0.2794)
			(end -0.12065 -0.3048)
			(stroke
				(width 0.1)
				(type default)
			)
			(layer "B.Fab")
		)
		(fp_line
			(start -0.120396 0.2794)
			(end 0.12065 0.2794)
			(stroke
				(width 0.1)
				(type default)
			)
			(layer "B.Fab")
		)
		(fp_line
			(start -0.120396 0.3048)
			(end -0.120396 0.2794)
			(stroke
				(width 0.1)
				(type default)
			)
			(layer "B.Fab")
		)
		(fp_line
			(start 0.12065 -0.305054)
			(end 0.12065 -0.2794)
			(stroke
				(width 0.1)
				(type default)
			)
			(layer "B.Fab")
		)
		(fp_line
			(start 0.12065 -0.2794)
			(end -0.12065 -0.2794)
			(stroke
				(width 0.1)
				(type default)
			)
			(layer "B.Fab")
		)
		(fp_line
			(start 0.12065 0.2794)
			(end 0.12065 0.3048)
			(stroke
				(width 0.1)
				(type default)
			)
			(layer "B.Fab")
		)
		(fp_line
			(start 0.12065 0.3048)
			(end 0.67945 0.3048)
			(stroke
				(width 0.1)
				(type default)
			)
			(layer "B.Fab")
		)
		(fp_line
			(start 0.67945 -0.305054)
			(end 0.12065 -0.305054)
			(stroke
				(width 0.1)
				(type default)
			)
			(layer "B.Fab")
		)
		(fp_line
			(start 0.67945 0.3048)
			(end 0.67945 -0.305054)
			(stroke
				(width 0.1)
				(type default)
			)
			(layer "B.Fab")
		)
		(pad "1" smd circle
			(at 0.40005 0 180)
			(size 0 0)
			(layers "B.Cu" "B.Mask" "B.Paste")
			(net "P12V_AUX")
		)
		(pad "2" smd circle
			(at -0.40005 0 180)
			(size 0 0)
			(layers "B.Cu" "B.Mask" "B.Paste")
			(net "PVCCIN_CPU0_VIN_CSNIN")
		)
	)
	(footprint ""
		(layer "B.Cu")
		(at 520.044426 -153.203148 90)
		(property "Reference" "X5"
			(at 1.4732 2.650998 270)
			(unlocked yes)
			(layer "B.SilkS")
			(effects
				(font
					(size 0.7874 0.5842)
					(thickness 0.1524)
				)
				(justify left mirror)
			)
		)
		(property "Value" ""
			(at 0 0 90)
			(layer "B.Fab")
			(effects
				(font
					(size 1.27 1.27)
				)
				(justify mirror)
			)
		)
		(property "Device Type" "TP_TDR_4P_FTS_TH-TP_TDR_4P_DIPA"
			(at -1.30175 1.27 0)
			(unlocked yes)
			(layer "B.Fab")
			(hide yes)
			(effects
				(font
					(size 0.635 0.4064)
					(thickness 0.1524)
				)
				(justify mirror)
			)
		)
		(property "User Part Number" "N_A"
			(at -1.30175 1.27 0)
			(unlocked yes)
			(layer "Cmts.User")
			(hide yes)
			(effects
				(font
					(size 0.635 0.4064)
					(thickness 0.1524)
				)
				(justify mirror)
			)
		)
		(duplicate_pad_numbers_are_jumpers no)
		(fp_line
			(start 0 -1.27)
			(end 0 -0.635)
			(stroke
				(width 0.1524)
				(type default)
			)
			(layer "B.SilkS")
		)
		(fp_line
			(start -2.54 -1.27)
			(end 0 -1.27)
			(stroke
				(width 0.1524)
				(type default)
			)
			(layer "B.SilkS")
		)
		(fp_line
			(start -2.54 -1.1303)
			(end -2.54 -1.27)
			(stroke
				(width 0.1524)
				(type default)
			)
			(layer "B.SilkS")
		)
		(fp_line
			(start 0 0.635)
			(end 0 1.905)
			(stroke
				(width 0.1524)
				(type default)
			)
			(layer "B.SilkS")
		)
		(fp_line
			(start -2.54 1.4097)
			(end -2.54 1.1303)
			(stroke
				(width 0.1524)
				(type default)
			)
			(layer "B.SilkS")
		)
		(fp_line
			(start 0 3.175)
			(end 0 3.81)
			(stroke
				(width 0.1524)
				(type default)
			)
			(layer "B.SilkS")
		)
		(fp_line
			(start 0 3.81)
			(end -2.54 3.81)
			(stroke
				(width 0.1524)
				(type default)
			)
			(layer "B.SilkS")
		)
		(fp_line
			(start -2.54 3.81)
			(end -2.54 3.6703)
			(stroke
				(width 0.1524)
				(type default)
			)
			(layer "B.SilkS")
		)
		(fp_poly
			(pts
				(xy 2.76987 -0.972566) (xy 2.76987 0.551434) (xy 1.24587 -0.210566)
			)
			(stroke
				(width 0)
				(type default)
			)
			(fill yes)
			(layer "B.SilkS")
		)
		(fp_line
			(start 0 -1.27)
			(end 0 3.81)
			(stroke
				(width 0.1)
				(type default)
			)
			(layer "B.Fab")
		)
		(fp_line
			(start -2.54 -1.27)
			(end 0 -1.27)
			(stroke
				(width 0.1)
				(type default)
			)
			(layer "B.Fab")
		)
		(fp_line
			(start 0 3.81)
			(end -2.54 3.81)
			(stroke
				(width 0.1)
				(type default)
			)
			(layer "B.Fab")
		)
		(fp_line
			(start -2.54 3.81)
			(end -2.54 -1.27)
			(stroke
				(width 0.1)
				(type default)
			)
			(layer "B.Fab")
		)
		(fp_poly
			(pts
				(xy 0.761746 0) (xy 2.285746 -0.762) (xy 2.285746 0.762)
			)
			(stroke
				(width 0)
				(type default)
			)
			(fill yes)
			(layer "B.Fab")
		)
		(pad "1" thru_hole circle
			(at 0 0 270)
			(size 1.0033 1.0033)
			(drill 0.249936)
			(layers "*.Cu" "*.Mask")
			(remove_unused_layers no)
			(net "TDR_DIFF_85_IN4_DP")
			(clearance 0.10795)
			(padstack
				(mode front_inner_back)
				(layer "Inner"
					(shape circle)
					(size 0.8001 0.8001)
					(clearance 0.1524)
				)
				(layer "B.Cu"
					(shape circle)
					(size 1.0033 1.0033)
					(thermal_gap 0.10795)
					(clearance 0.10795)
				)
			)
		)
		(pad "2" thru_hole circle
			(at -2.54 0 270)
			(size 1.9939 1.9939)
			(drill 0.249936)
			(layers "*.Cu" "*.Mask")
			(remove_unused_layers no)
			(net "T1_GND")
			(clearance 0.10795)
			(padstack
				(mode front_inner_back)
				(layer "Inner"
					(shape circle)
					(size 0.8001 0.8001)
					(clearance 0.1524)
				)
				(layer "B.Cu"
					(shape circle)
					(size 1.9939 1.9939)
					(thermal_gap 0.10795)
					(clearance 0.10795)
				)
			)
		)
		(pad "3" thru_hole circle
			(at -2.54 2.54 270)
			(size 1.9939 1.9939)
			(drill 0.249936)
			(layers "*.Cu" "*.Mask")
			(remove_unused_layers no)
			(net "T1_GND")
			(clearance 0.10795)
			(padstack
				(mode front_inner_back)
				(layer "Inner"
					(shape circle)
					(size 0.8001 0.8001)
					(clearance 0.1524)
				)
				(layer "B.Cu"
					(shape circle)
					(size 1.9939 1.9939)
					(thermal_gap 0.10795)
					(clearance 0.10795)
				)
			)
		)
		(pad "4" thru_hole circle
			(at 0 2.54 270)
			(size 1.0033 1.0033)
			(drill 0.249936)
			(layers "*.Cu" "*.Mask")
			(remove_unused_layers no)
			(net "TDR_DIFF_85_IN4_DN")
			(clearance 0.10795)
			(padstack
				(mode front_inner_back)
				(layer "Inner"
					(shape circle)
					(size 0.8001 0.8001)
					(clearance 0.1524)
				)
				(layer "B.Cu"
					(shape circle)
					(size 1.0033 1.0033)
					(thermal_gap 0.10795)
					(clearance 0.10795)
				)
			)
		)
	)
	(footprint ""
		(layer "B.Cu")
		(at 229.89032 -127.922274 180)
		(property "Reference" "R4534"
			(at 0 0 0)
			(layer "B.SilkS")
			(hide yes)
			(effects
				(font
					(size 1.27 1.27)
				)
				(justify mirror)
			)
		)
		(property "Value" ""
			(at 0 0 0)
			(layer "B.Fab")
			(effects
				(font
					(size 1.27 1.27)
				)
				(justify mirror)
			)
		)
		(duplicate_pad_numbers_are_jumpers no)
		(fp_line
			(start 0.7874 0.4064)
			(end 0.7874 -0.4064)
			(stroke
				(width 0.1524)
				(type default)
			)
			(layer "B.SilkS")
		)
		(fp_line
			(start 0.7874 -0.4064)
			(end -0.7874 -0.4064)
			(stroke
				(width 0.1524)
				(type default)
			)
			(layer "B.SilkS")
		)
		(fp_line
			(start -0.7874 0.4064)
			(end 0.7874 0.4064)
			(stroke
				(width 0.1524)
				(type default)
			)
			(layer "B.SilkS")
		)
		(fp_line
			(start -0.7874 -0.4064)
			(end -0.7874 0.4064)
			(stroke
				(width 0.1524)
				(type default)
			)
			(layer "B.SilkS")
		)
		(fp_line
			(start 0.67945 0.3048)
			(end 0.67945 -0.305054)
			(stroke
				(width 0.1)
				(type default)
			)
			(layer "B.Fab")
		)
		(fp_line
			(start 0.67945 -0.305054)
			(end 0.12065 -0.305054)
			(stroke
				(width 0.1)
				(type default)
			)
			(layer "B.Fab")
		)
		(fp_line
			(start 0.12065 0.3048)
			(end 0.67945 0.3048)
			(stroke
				(width 0.1)
				(type default)
			)
			(layer "B.Fab")
		)
		(fp_line
			(start 0.12065 0.2794)
			(end 0.12065 0.3048)
			(stroke
				(width 0.1)
				(type default)
			)
			(layer "B.Fab")
		)
		(fp_line
			(start 0.12065 -0.2794)
			(end -0.12065 -0.2794)
			(stroke
				(width 0.1)
				(type default)
			)
			(layer "B.Fab")
		)
		(fp_line
			(start 0.12065 -0.305054)
			(end 0.12065 -0.2794)
			(stroke
				(width 0.1)
				(type default)
			)
			(layer "B.Fab")
		)
		(fp_line
			(start -0.120396 0.3048)
			(end -0.120396 0.2794)
			(stroke
				(width 0.1)
				(type default)
			)
			(layer "B.Fab")
		)
		(fp_line
			(start -0.120396 0.2794)
			(end 0.12065 0.2794)
			(stroke
				(width 0.1)
				(type default)
			)
			(layer "B.Fab")
		)
		(fp_line
			(start -0.12065 -0.2794)
			(end -0.12065 -0.3048)
			(stroke
				(width 0.1)
				(type default)
			)
			(layer "B.Fab")
		)
		(fp_line
			(start -0.12065 -0.3048)
			(end -0.67945 -0.3048)
			(stroke
				(width 0.1)
				(type default)
			)
			(layer "B.Fab")
		)
		(fp_line
			(start -0.67945 0.3048)
			(end -0.120396 0.3048)
			(stroke
				(width 0.1)
				(type default)
			)
			(layer "B.Fab")
		)
		(fp_line
			(start -0.67945 -0.3048)
			(end -0.67945 0.3048)
			(stroke
				(width 0.1)
				(type default)
			)
			(layer "B.Fab")
		)
		(pad "1" smd circle
			(at 0.40005 0)
			(size 0 0)
			(layers "B.Cu" "B.Mask" "B.Paste")
			(net "CLK_SWB_OE_N")
		)
		(pad "2" smd circle
			(at -0.40005 0)
			(size 0 0)
			(layers "B.Cu" "B.Mask" "B.Paste")
			(net "FM_DB2000_8_OE_N")
		)
	)
	(footprint ""
		(layer "B.Cu")
		(at 85.122004 -186.003692 -90)
		(property "Reference" "R303"
			(at 0 0 90)
			(layer "B.SilkS")
			(hide yes)
			(effects
				(font
					(size 1.27 1.27)
				)
				(justify mirror)
			)
		)
		(property "Value" ""
			(at 0 0 90)
			(layer "B.Fab")
			(effects
				(font
					(size 1.27 1.27)
				)
				(justify mirror)
			)
		)
		(duplicate_pad_numbers_are_jumpers no)
		(fp_line
			(start -0.7874 0.4064)
			(end 0.7874 0.4064)
			(stroke
				(width 0.1524)
				(type default)
			)
			(layer "B.SilkS")
		)
		(fp_line
			(start 0.7874 0.4064)
			(end 0.7874 -0.4064)
			(stroke
				(width 0.1524)
				(type default)
			)
			(layer "B.SilkS")
		)
		(fp_line
			(start -0.7874 -0.4064)
			(end -0.7874 0.4064)
			(stroke
				(width 0.1524)
				(type default)
			)
			(layer "B.SilkS")
		)
		(fp_line
			(start 0.7874 -0.4064)
			(end -0.7874 -0.4064)
			(stroke
				(width 0.1524)
				(type default)
			)
			(layer "B.SilkS")
		)
		(fp_line
			(start -0.67945 0.3048)
			(end -0.120396 0.3048)
			(stroke
				(width 0.1)
				(type default)
			)
			(layer "B.Fab")
		)
		(fp_line
			(start -0.120396 0.3048)
			(end -0.120396 0.2794)
			(stroke
				(width 0.1)
				(type default)
			)
			(layer "B.Fab")
		)
		(fp_line
			(start 0.12065 0.3048)
			(end 0.67945 0.3048)
			(stroke
				(width 0.1)
				(type default)
			)
			(layer "B.Fab")
		)
		(fp_line
			(start 0.67945 0.3048)
			(end 0.67945 -0.305054)
			(stroke
				(width 0.1)
				(type default)
			)
			(layer "B.Fab")
		)
		(fp_line
			(start -0.120396 0.2794)
			(end 0.12065 0.2794)
			(stroke
				(width 0.1)
				(type default)
			)
			(layer "B.Fab")
		)
		(fp_line
			(start 0.12065 0.2794)
			(end 0.12065 0.3048)
			(stroke
				(width 0.1)
				(type default)
			)
			(layer "B.Fab")
		)
		(fp_line
			(start -0.12065 -0.2794)
			(end -0.12065 -0.3048)
			(stroke
				(width 0.1)
				(type default)
			)
			(layer "B.Fab")
		)
		(fp_line
			(start 0.12065 -0.2794)
			(end -0.12065 -0.2794)
			(stroke
				(width 0.1)
				(type default)
			)
			(layer "B.Fab")
		)
		(fp_line
			(start -0.67945 -0.3048)
			(end -0.67945 0.3048)
			(stroke
				(width 0.1)
				(type default)
			)
			(layer "B.Fab")
		)
		(fp_line
			(start -0.12065 -0.3048)
			(end -0.67945 -0.3048)
			(stroke
				(width 0.1)
				(type default)
			)
			(layer "B.Fab")
		)
		(fp_line
			(start 0.12065 -0.305054)
			(end 0.12065 -0.2794)
			(stroke
				(width 0.1)
				(type default)
			)
			(layer "B.Fab")
		)
		(fp_line
			(start 0.67945 -0.305054)
			(end 0.12065 -0.305054)
			(stroke
				(width 0.1)
				(type default)
			)
			(layer "B.Fab")
		)
		(pad "1" smd circle
			(at 0.40005 0 90)
			(size 0 0)
			(layers "B.Cu" "B.Mask" "B.Paste")
			(net "PVNN_TERM_CPU1")
		)
		(pad "2" smd circle
			(at -0.40005 0 90)
			(size 0 0)
			(layers "B.Cu" "B.Mask" "B.Paste")
			(net "H_CPU_RMCA_LVC1_R_N")
		)
	)
	(footprint ""
		(layer "B.Cu")
		(at 406.776428 -257.89001 -90)
		(property "Reference" "C494"
			(at 0 0 90)
			(layer "B.SilkS")
			(hide yes)
			(effects
				(font
					(size 1.27 1.27)
				)
				(justify mirror)
			)
		)
		(property "Value" ""
			(at 0 0 90)
			(layer "B.Fab")
			(effects
				(font
					(size 1.27 1.27)
				)
				(justify mirror)
			)
		)
		(duplicate_pad_numbers_are_jumpers no)
		(fp_line
			(start -1.524 0.762)
			(end 1.524 0.762)
			(stroke
				(width 0.1524)
				(type default)
			)
			(layer "B.SilkS")
		)
		(fp_line
			(start 1.524 0.762)
			(end 1.524 -0.762)
			(stroke
				(width 0.1524)
				(type default)
			)
			(layer "B.SilkS")
		)
		(fp_line
			(start -1.524 -0.762)
			(end -1.524 0.762)
			(stroke
				(width 0.1524)
				(type default)
			)
			(layer "B.SilkS")
		)
		(fp_line
			(start 1.524 -0.762)
			(end -1.524 -0.762)
			(stroke
				(width 0.1524)
				(type default)
			)
			(layer "B.SilkS")
		)
		(fp_line
			(start -1.1049 0.724916)
			(end -1.1049 -0.724916)
			(stroke
				(width 0.1)
				(type default)
			)
			(layer "B.Fab")
		)
		(fp_line
			(start 1.1049 0.724916)
			(end -1.1049 0.724916)
			(stroke
				(width 0.1)
				(type default)
			)
			(layer "B.Fab")
		)
		(fp_line
			(start -1.1049 -0.724916)
			(end 1.1049 -0.724916)
			(stroke
				(width 0.1)
				(type default)
			)
			(layer "B.Fab")
		)
		(fp_line
			(start 1.1049 -0.724916)
			(end 1.1049 0.724916)
			(stroke
				(width 0.1)
				(type default)
			)
			(layer "B.Fab")
		)
		(pad "1" smd rect
			(at 0.889 0 270)
			(size 1.016 1.27)
			(layers "B.Cu" "B.Mask" "B.Paste")
			(net "PVCCFA_EHV_FIVRA_CPU0")
		)
		(pad "2" smd rect
			(at -0.889 0 270)
			(size 1.016 1.27)
			(layers "B.Cu" "B.Mask" "B.Paste")
			(net "GND")
		)
	)
	(footprint ""
		(layer "B.Cu")
		(at 420.682166 -138.333988 180)
		(property "Reference" "PR105"
			(at 0 0 0)
			(layer "B.SilkS")
			(hide yes)
			(effects
				(font
					(size 1.27 1.27)
				)
				(justify mirror)
			)
		)
		(property "Value" ""
			(at 0 0 0)
			(layer "B.Fab")
			(effects
				(font
					(size 1.27 1.27)
				)
				(justify mirror)
			)
		)
		(duplicate_pad_numbers_are_jumpers no)
		(fp_line
			(start 0.7874 0.4064)
			(end 0.7874 -0.4064)
			(stroke
				(width 0.1524)
				(type default)
			)
			(layer "B.SilkS")
		)
		(fp_line
			(start 0.7874 -0.4064)
			(end -0.7874 -0.4064)
			(stroke
				(width 0.1524)
				(type default)
			)
			(layer "B.SilkS")
		)
		(fp_line
			(start -0.7874 0.4064)
			(end 0.7874 0.4064)
			(stroke
				(width 0.1524)
				(type default)
			)
			(layer "B.SilkS")
		)
		(fp_line
			(start -0.7874 -0.4064)
			(end -0.7874 0.4064)
			(stroke
				(width 0.1524)
				(type default)
			)
			(layer "B.SilkS")
		)
		(fp_line
			(start 0.67945 0.3048)
			(end 0.67945 -0.305054)
			(stroke
				(width 0.1)
				(type default)
			)
			(layer "B.Fab")
		)
		(fp_line
			(start 0.67945 -0.305054)
			(end 0.12065 -0.305054)
			(stroke
				(width 0.1)
				(type default)
			)
			(layer "B.Fab")
		)
		(fp_line
			(start 0.12065 0.3048)
			(end 0.67945 0.3048)
			(stroke
				(width 0.1)
				(type default)
			)
			(layer "B.Fab")
		)
		(fp_line
			(start 0.12065 0.2794)
			(end 0.12065 0.3048)
			(stroke
				(width 0.1)
				(type default)
			)
			(layer "B.Fab")
		)
		(fp_line
			(start 0.12065 -0.2794)
			(end -0.12065 -0.2794)
			(stroke
				(width 0.1)
				(type default)
			)
			(layer "B.Fab")
		)
		(fp_line
			(start 0.12065 -0.305054)
			(end 0.12065 -0.2794)
			(stroke
				(width 0.1)
				(type default)
			)
			(layer "B.Fab")
		)
		(fp_line
			(start -0.120396 0.3048)
			(end -0.120396 0.2794)
			(stroke
				(width 0.1)
				(type default)
			)
			(layer "B.Fab")
		)
		(fp_line
			(start -0.120396 0.2794)
			(end 0.12065 0.2794)
			(stroke
				(width 0.1)
				(type default)
			)
			(layer "B.Fab")
		)
		(fp_line
			(start -0.12065 -0.2794)
			(end -0.12065 -0.3048)
			(stroke
				(width 0.1)
				(type default)
			)
			(layer "B.Fab")
		)
		(fp_line
			(start -0.12065 -0.3048)
			(end -0.67945 -0.3048)
			(stroke
				(width 0.1)
				(type default)
			)
			(layer "B.Fab")
		)
		(fp_line
			(start -0.67945 0.3048)
			(end -0.120396 0.3048)
			(stroke
				(width 0.1)
				(type default)
			)
			(layer "B.Fab")
		)
		(fp_line
			(start -0.67945 -0.3048)
			(end -0.67945 0.3048)
			(stroke
				(width 0.1)
				(type default)
			)
			(layer "B.Fab")
		)
		(pad "1" smd circle
			(at 0.40005 0)
			(size 0 0)
			(layers "B.Cu" "B.Mask" "B.Paste")
			(net "PVCCINFAON_CPU0_VREF")
		)
		(pad "2" smd circle
			(at -0.40005 0)
			(size 0 0)
			(layers "B.Cu" "B.Mask" "B.Paste")
			(net "PVCCINFAON_CPU0_ADDR")
		)
	)
	(footprint ""
		(layer "B.Cu")
		(at 160.83788 -107.025948 180)
		(property "Reference" "R3203"
			(at 0 0 0)
			(layer "B.SilkS")
			(hide yes)
			(effects
				(font
					(size 1.27 1.27)
				)
				(justify mirror)
			)
		)
		(property "Value" ""
			(at 0 0 0)
			(layer "B.Fab")
			(effects
				(font
					(size 1.27 1.27)
				)
				(justify mirror)
			)
		)
		(duplicate_pad_numbers_are_jumpers no)
		(fp_line
			(start 0.7874 0.4064)
			(end 0.7874 -0.4064)
			(stroke
				(width 0.1524)
				(type default)
			)
			(layer "B.SilkS")
		)
		(fp_line
			(start 0.7874 -0.4064)
			(end -0.7874 -0.4064)
			(stroke
				(width 0.1524)
				(type default)
			)
			(layer "B.SilkS")
		)
		(fp_line
			(start -0.7874 0.4064)
			(end 0.7874 0.4064)
			(stroke
				(width 0.1524)
				(type default)
			)
			(layer "B.SilkS")
		)
		(fp_line
			(start -0.7874 -0.4064)
			(end -0.7874 0.4064)
			(stroke
				(width 0.1524)
				(type default)
			)
			(layer "B.SilkS")
		)
		(fp_line
			(start 0.67945 0.3048)
			(end 0.67945 -0.305054)
			(stroke
				(width 0.1)
				(type default)
			)
			(layer "B.Fab")
		)
		(fp_line
			(start 0.67945 -0.305054)
			(end 0.12065 -0.305054)
			(stroke
				(width 0.1)
				(type default)
			)
			(layer "B.Fab")
		)
		(fp_line
			(start 0.12065 0.3048)
			(end 0.67945 0.3048)
			(stroke
				(width 0.1)
				(type default)
			)
			(layer "B.Fab")
		)
		(fp_line
			(start 0.12065 0.2794)
			(end 0.12065 0.3048)
			(stroke
				(width 0.1)
				(type default)
			)
			(layer "B.Fab")
		)
		(fp_line
			(start 0.12065 -0.2794)
			(end -0.12065 -0.2794)
			(stroke
				(width 0.1)
				(type default)
			)
			(layer "B.Fab")
		)
		(fp_line
			(start 0.12065 -0.305054)
			(end 0.12065 -0.2794)
			(stroke
				(width 0.1)
				(type default)
			)
			(layer "B.Fab")
		)
		(fp_line
			(start -0.120396 0.3048)
			(end -0.120396 0.2794)
			(stroke
				(width 0.1)
				(type default)
			)
			(layer "B.Fab")
		)
		(fp_line
			(start -0.120396 0.2794)
			(end 0.12065 0.2794)
			(stroke
				(width 0.1)
				(type default)
			)
			(layer "B.Fab")
		)
		(fp_line
			(start -0.12065 -0.2794)
			(end -0.12065 -0.3048)
			(stroke
				(width 0.1)
				(type default)
			)
			(layer "B.Fab")
		)
		(fp_line
			(start -0.12065 -0.3048)
			(end -0.67945 -0.3048)
			(stroke
				(width 0.1)
				(type default)
			)
			(layer "B.Fab")
		)
		(fp_line
			(start -0.67945 0.3048)
			(end -0.120396 0.3048)
			(stroke
				(width 0.1)
				(type default)
			)
			(layer "B.Fab")
		)
		(fp_line
			(start -0.67945 -0.3048)
			(end -0.67945 0.3048)
			(stroke
				(width 0.1)
				(type default)
			)
			(layer "B.Fab")
		)
		(pad "1" smd circle
			(at 0.40005 0)
			(size 0 0)
			(layers "B.Cu" "B.Mask" "B.Paste")
			(net "OCP_V3_2_AUX_PWR_EN")
		)
		(pad "2" smd circle
			(at -0.40005 0)
			(size 0 0)
			(layers "B.Cu" "B.Mask" "B.Paste")
			(net "OCP_V3_2_AUX_PWR_EN_R1")
		)
	)
	(footprint ""
		(layer "B.Cu")
		(at 292.980618 -149.992588 90)
		(property "Reference" "R318"
			(at 0 0 90)
			(layer "B.SilkS")
			(hide yes)
			(effects
				(font
					(size 1.27 1.27)
				)
				(justify mirror)
			)
		)
		(property "Value" ""
			(at 0 0 90)
			(layer "B.Fab")
			(effects
				(font
					(size 1.27 1.27)
				)
				(justify mirror)
			)
		)
		(duplicate_pad_numbers_are_jumpers no)
		(fp_line
			(start 0.7874 -0.4064)
			(end -0.7874 -0.4064)
			(stroke
				(width 0.1524)
				(type default)
			)
			(layer "B.SilkS")
		)
		(fp_line
			(start -0.7874 -0.4064)
			(end -0.7874 0.4064)
			(stroke
				(width 0.1524)
				(type default)
			)
			(layer "B.SilkS")
		)
		(fp_line
			(start 0.7874 0.4064)
			(end 0.7874 -0.4064)
			(stroke
				(width 0.1524)
				(type default)
			)
			(layer "B.SilkS")
		)
		(fp_line
			(start -0.7874 0.4064)
			(end 0.7874 0.4064)
			(stroke
				(width 0.1524)
				(type default)
			)
			(layer "B.SilkS")
		)
		(fp_line
			(start 0.67945 -0.305054)
			(end 0.12065 -0.305054)
			(stroke
				(width 0.1)
				(type default)
			)
			(layer "B.Fab")
		)
		(fp_line
			(start 0.12065 -0.305054)
			(end 0.12065 -0.2794)
			(stroke
				(width 0.1)
				(type default)
			)
			(layer "B.Fab")
		)
		(fp_line
			(start -0.12065 -0.3048)
			(end -0.67945 -0.3048)
			(stroke
				(width 0.1)
				(type default)
			)
			(layer "B.Fab")
		)
		(fp_line
			(start -0.67945 -0.3048)
			(end -0.67945 0.3048)
			(stroke
				(width 0.1)
				(type default)
			)
			(layer "B.Fab")
		)
		(fp_line
			(start 0.12065 -0.2794)
			(end -0.12065 -0.2794)
			(stroke
				(width 0.1)
				(type default)
			)
			(layer "B.Fab")
		)
		(fp_line
			(start -0.12065 -0.2794)
			(end -0.12065 -0.3048)
			(stroke
				(width 0.1)
				(type default)
			)
			(layer "B.Fab")
		)
		(fp_line
			(start 0.12065 0.2794)
			(end 0.12065 0.3048)
			(stroke
				(width 0.1)
				(type default)
			)
			(layer "B.Fab")
		)
		(fp_line
			(start -0.120396 0.2794)
			(end 0.12065 0.2794)
			(stroke
				(width 0.1)
				(type default)
			)
			(layer "B.Fab")
		)
		(fp_line
			(start 0.67945 0.3048)
			(end 0.67945 -0.305054)
			(stroke
				(width 0.1)
				(type default)
			)
			(layer "B.Fab")
		)
		(fp_line
			(start 0.12065 0.3048)
			(end 0.67945 0.3048)
			(stroke
				(width 0.1)
				(type default)
			)
			(layer "B.Fab")
		)
		(fp_line
			(start -0.120396 0.3048)
			(end -0.120396 0.2794)
			(stroke
				(width 0.1)
				(type default)
			)
			(layer "B.Fab")
		)
		(fp_line
			(start -0.67945 0.3048)
			(end -0.120396 0.3048)
			(stroke
				(width 0.1)
				(type default)
			)
			(layer "B.Fab")
		)
		(pad "1" smd circle
			(at 0.40005 0 270)
			(size 0 0)
			(layers "B.Cu" "B.Mask" "B.Paste")
			(net "FM_SPD_REMOTE_EN")
		)
		(pad "2" smd circle
			(at -0.40005 0 270)
			(size 0 0)
			(layers "B.Cu" "B.Mask" "B.Paste")
			(net "GND")
		)
	)
	(footprint ""
		(layer "B.Cu")
		(at 180.555646 -110.975394 -90)
		(property "Reference" "C1118"
			(at 0 0 90)
			(layer "B.SilkS")
			(hide yes)
			(effects
				(font
					(size 1.27 1.27)
				)
				(justify mirror)
			)
		)
		(property "Value" ""
			(at 0 0 90)
			(layer "B.Fab")
			(effects
				(font
					(size 1.27 1.27)
				)
				(justify mirror)
			)
		)
		(duplicate_pad_numbers_are_jumpers no)
		(fp_line
			(start -0.69215 0.2921)
			(end 0.69215 0.2921)
			(stroke
				(width 0.1524)
				(type default)
			)
			(layer "B.SilkS")
		)
		(fp_line
			(start 0.69215 0.2921)
			(end 0.69215 -0.2921)
			(stroke
				(width 0.1524)
				(type default)
			)
			(layer "B.SilkS")
		)
		(fp_line
			(start -0.69215 -0.2921)
			(end -0.69215 0.2921)
			(stroke
				(width 0.1524)
				(type default)
			)
			(layer "B.SilkS")
		)
		(fp_line
			(start 0.69215 -0.2921)
			(end -0.69215 -0.2921)
			(stroke
				(width 0.1524)
				(type default)
			)
			(layer "B.SilkS")
		)
		(fp_line
			(start -0.51435 0.2794)
			(end 0.51435 0.2794)
			(stroke
				(width 0.1)
				(type default)
			)
			(layer "B.Fab")
		)
		(fp_line
			(start 0.51435 0.2794)
			(end 0.51435 -0.2794)
			(stroke
				(width 0.1)
				(type default)
			)
			(layer "B.Fab")
		)
		(fp_line
			(start -0.51435 -0.2794)
			(end -0.51435 0.2794)
			(stroke
				(width 0.1)
				(type default)
			)
			(layer "B.Fab")
		)
		(fp_line
			(start 0.51435 -0.2794)
			(end -0.51435 -0.2794)
			(stroke
				(width 0.1)
				(type default)
			)
			(layer "B.Fab")
		)
		(pad "1" smd circle
			(at 0.40005 0 90)
			(size 0 0)
			(layers "B.Cu" "B.Mask" "B.Paste")
			(net "P3V3_AUX_FPGA_VCCIO3")
		)
		(pad "2" smd circle
			(at -0.40005 0 90)
			(size 0 0)
			(layers "B.Cu" "B.Mask" "B.Paste")
			(net "GND")
		)
		(zone
			(layer "B.Cu")
			(hatch none 0.5)
			(connect_pads
				(clearance 0)
			)
			(min_thickness 0.25)
			(keepout
				(tracks not_allowed)
				(vias allowed)
				(pads allowed)
				(copperpour not_allowed)
				(footprints allowed)
			)
			(placement
				(enabled no)
				(sheetname "")
			)
			(fill
				(thermal_gap 0.5)
				(thermal_bridge_width 0.5)
				(island_removal_mode 0)
			)
			(polygon
				(pts
					(xy 180.468016 -110.784894) (xy 180.40985 -110.876334) (xy 180.40985 -111.075724) (xy 180.468016 -111.165894)
					(xy 180.643276 -111.165894) (xy 180.701696 -111.075724) (xy 180.701696 -110.876334) (xy 180.64353 -110.784894)
				)
			)
		)
	)
	(footprint ""
		(layer "B.Cu")
		(at 101.404928 -210.418934 180)
		(property "Reference" "C472"
			(at 0 0 0)
			(layer "B.SilkS")
			(hide yes)
			(effects
				(font
					(size 1.27 1.27)
				)
				(justify mirror)
			)
		)
		(property "Value" ""
			(at 0 0 0)
			(layer "B.Fab")
			(effects
				(font
					(size 1.27 1.27)
				)
				(justify mirror)
			)
		)
		(duplicate_pad_numbers_are_jumpers no)
		(fp_line
			(start 1.2954 0.5842)
			(end 1.2954 -0.5842)
			(stroke
				(width 0.1524)
				(type default)
			)
			(layer "B.SilkS")
		)
		(fp_line
			(start 1.2954 -0.5842)
			(end -1.2954 -0.5842)
			(stroke
				(width 0.1524)
				(type default)
			)
			(layer "B.SilkS")
		)
		(fp_line
			(start 0 -0.5842)
			(end 0 0.5842)
			(stroke
				(width 0.1524)
				(type default)
			)
			(layer "B.SilkS")
		)
		(fp_line
			(start -1.2954 0.5842)
			(end 1.2954 0.5842)
			(stroke
				(width 0.1524)
				(type default)
			)
			(layer "B.SilkS")
		)
		(fp_line
			(start -1.2954 -0.5842)
			(end -1.2954 0.5842)
			(stroke
				(width 0.1524)
				(type default)
			)
			(layer "B.SilkS")
		)
		(fp_line
			(start 1.1938 0.4064)
			(end 1.1938 -0.4064)
			(stroke
				(width 0.1)
				(type default)
			)
			(layer "B.Fab")
		)
		(fp_line
			(start 1.1938 -0.4064)
			(end 0.8636 -0.4064)
			(stroke
				(width 0.1)
				(type default)
			)
			(layer "B.Fab")
		)
		(fp_line
			(start 0.8636 0.4572)
			(end 0.8636 0.4064)
			(stroke
				(width 0.1)
				(type default)
			)
			(layer "B.Fab")
		)
		(fp_line
			(start 0.8636 0.4064)
			(end 1.1938 0.4064)
			(stroke
				(width 0.1)
				(type default)
			)
			(layer "B.Fab")
		)
		(fp_line
			(start 0.8636 -0.4064)
			(end 0.8636 -0.4572)
			(stroke
				(width 0.1)
				(type default)
			)
			(layer "B.Fab")
		)
		(fp_line
			(start 0.8636 -0.4572)
			(end -0.8636 -0.4572)
			(stroke
				(width 0.1)
				(type default)
			)
			(layer "B.Fab")
		)
		(fp_line
			(start -0.8636 0.4572)
			(end 0.8636 0.4572)
			(stroke
				(width 0.1)
				(type default)
			)
			(layer "B.Fab")
		)
		(fp_line
			(start -0.8636 0.4064)
			(end -0.8636 0.4572)
			(stroke
				(width 0.1)
				(type default)
			)
			(layer "B.Fab")
		)
		(fp_line
			(start -0.8636 -0.4064)
			(end -1.1938 -0.4064)
			(stroke
				(width 0.1)
				(type default)
			)
			(layer "B.Fab")
		)
		(fp_line
			(start -0.8636 -0.4572)
			(end -0.8636 -0.4064)
			(stroke
				(width 0.1)
				(type default)
			)
			(layer "B.Fab")
		)
		(fp_line
			(start -1.1938 0.4064)
			(end -0.8636 0.4064)
			(stroke
				(width 0.1)
				(type default)
			)
			(layer "B.Fab")
		)
		(fp_line
			(start -1.1938 -0.4064)
			(end -1.1938 0.4064)
			(stroke
				(width 0.1)
				(type default)
			)
			(layer "B.Fab")
		)
		(pad "1" smd rect
			(at 0.7366 0 90)
			(size 0.7112 0.8128)
			(layers "B.Cu" "B.Mask" "B.Paste")
			(net "PVCCFA_EHV_CPU1")
		)
		(pad "2" smd rect
			(at -0.7366 0 90)
			(size 0.7112 0.8128)
			(layers "B.Cu" "B.Mask" "B.Paste")
			(net "GND")
		)
	)
	(footprint ""
		(layer "B.Cu")
		(at 292.983158 -151.775668 -90)
		(property "Reference" "R682"
			(at 0 0 90)
			(layer "B.SilkS")
			(hide yes)
			(effects
				(font
					(size 1.27 1.27)
				)
				(justify mirror)
			)
		)
		(property "Value" ""
			(at 0 0 90)
			(layer "B.Fab")
			(effects
				(font
					(size 1.27 1.27)
				)
				(justify mirror)
			)
		)
		(duplicate_pad_numbers_are_jumpers no)
		(fp_line
			(start -0.7874 0.4064)
			(end 0.7874 0.4064)
			(stroke
				(width 0.1524)
				(type default)
			)
			(layer "B.SilkS")
		)
		(fp_line
			(start 0.7874 0.4064)
			(end 0.7874 -0.4064)
			(stroke
				(width 0.1524)
				(type default)
			)
			(layer "B.SilkS")
		)
		(fp_line
			(start -0.7874 -0.4064)
			(end -0.7874 0.4064)
			(stroke
				(width 0.1524)
				(type default)
			)
			(layer "B.SilkS")
		)
		(fp_line
			(start 0.7874 -0.4064)
			(end -0.7874 -0.4064)
			(stroke
				(width 0.1524)
				(type default)
			)
			(layer "B.SilkS")
		)
		(fp_line
			(start -0.67945 0.3048)
			(end -0.120396 0.3048)
			(stroke
				(width 0.1)
				(type default)
			)
			(layer "B.Fab")
		)
		(fp_line
			(start -0.120396 0.3048)
			(end -0.120396 0.2794)
			(stroke
				(width 0.1)
				(type default)
			)
			(layer "B.Fab")
		)
		(fp_line
			(start 0.12065 0.3048)
			(end 0.67945 0.3048)
			(stroke
				(width 0.1)
				(type default)
			)
			(layer "B.Fab")
		)
		(fp_line
			(start 0.67945 0.3048)
			(end 0.67945 -0.305054)
			(stroke
				(width 0.1)
				(type default)
			)
			(layer "B.Fab")
		)
		(fp_line
			(start -0.120396 0.2794)
			(end 0.12065 0.2794)
			(stroke
				(width 0.1)
				(type default)
			)
			(layer "B.Fab")
		)
		(fp_line
			(start 0.12065 0.2794)
			(end 0.12065 0.3048)
			(stroke
				(width 0.1)
				(type default)
			)
			(layer "B.Fab")
		)
		(fp_line
			(start -0.12065 -0.2794)
			(end -0.12065 -0.3048)
			(stroke
				(width 0.1)
				(type default)
			)
			(layer "B.Fab")
		)
		(fp_line
			(start 0.12065 -0.2794)
			(end -0.12065 -0.2794)
			(stroke
				(width 0.1)
				(type default)
			)
			(layer "B.Fab")
		)
		(fp_line
			(start -0.67945 -0.3048)
			(end -0.67945 0.3048)
			(stroke
				(width 0.1)
				(type default)
			)
			(layer "B.Fab")
		)
		(fp_line
			(start -0.12065 -0.3048)
			(end -0.67945 -0.3048)
			(stroke
				(width 0.1)
				(type default)
			)
			(layer "B.Fab")
		)
		(fp_line
			(start 0.12065 -0.305054)
			(end 0.12065 -0.2794)
			(stroke
				(width 0.1)
				(type default)
			)
			(layer "B.Fab")
		)
		(fp_line
			(start 0.67945 -0.305054)
			(end 0.12065 -0.305054)
			(stroke
				(width 0.1)
				(type default)
			)
			(layer "B.Fab")
		)
		(pad "1" smd circle
			(at 0.40005 0 90)
			(size 0 0)
			(layers "B.Cu" "B.Mask" "B.Paste")
			(net "I3C_SPD_DDRABCD_CPU0_R_SCL")
		)
		(pad "2" smd circle
			(at -0.40005 0 90)
			(size 0 0)
			(layers "B.Cu" "B.Mask" "B.Paste")
			(net "I3C_SPD_DDRABCD_CPU0_LVC1_R_SCL")
		)
	)
	(footprint ""
		(layer "B.Cu")
		(at 501.233948 -303.58334 -90)
		(property "Reference" "X26"
			(at 3.427476 3.336798 270)
			(unlocked yes)
			(layer "B.SilkS")
			(effects
				(font
					(size 0.7874 0.5842)
					(thickness 0.1524)
				)
				(justify left mirror)
			)
		)
		(property "Value" ""
			(at 0 0 90)
			(layer "B.Fab")
			(effects
				(font
					(size 1.27 1.27)
				)
				(justify mirror)
			)
		)
		(property "Device Type" "TP_TDR_4P_FTS_TH-TP_TDR_4P_DIPA"
			(at -1.30175 1.27 180)
			(unlocked yes)
			(layer "B.Fab")
			(hide yes)
			(effects
				(font
					(size 0.635 0.4064)
					(thickness 0.1524)
				)
				(justify mirror)
			)
		)
		(property "User Part Number" "N_A"
			(at -1.30175 1.27 180)
			(unlocked yes)
			(layer "Cmts.User")
			(hide yes)
			(effects
				(font
					(size 0.635 0.4064)
					(thickness 0.1524)
				)
				(justify mirror)
			)
		)
		(duplicate_pad_numbers_are_jumpers no)
		(fp_line
			(start -2.54 3.81)
			(end -2.54 3.6703)
			(stroke
				(width 0.1524)
				(type default)
			)
			(layer "B.SilkS")
		)
		(fp_line
			(start 0 3.81)
			(end -2.54 3.81)
			(stroke
				(width 0.1524)
				(type default)
			)
			(layer "B.SilkS")
		)
		(fp_line
			(start 0 3.175)
			(end 0 3.81)
			(stroke
				(width 0.1524)
				(type default)
			)
			(layer "B.SilkS")
		)
		(fp_line
			(start -2.54 1.4097)
			(end -2.54 1.1303)
			(stroke
				(width 0.1524)
				(type default)
			)
			(layer "B.SilkS")
		)
		(fp_line
			(start 0 0.635)
			(end 0 1.905)
			(stroke
				(width 0.1524)
				(type default)
			)
			(layer "B.SilkS")
		)
		(fp_line
			(start -2.54 -1.1303)
			(end -2.54 -1.27)
			(stroke
				(width 0.1524)
				(type default)
			)
			(layer "B.SilkS")
		)
		(fp_line
			(start -2.54 -1.27)
			(end 0 -1.27)
			(stroke
				(width 0.1524)
				(type default)
			)
			(layer "B.SilkS")
		)
		(fp_line
			(start 0 -1.27)
			(end 0 -0.635)
			(stroke
				(width 0.1524)
				(type default)
			)
			(layer "B.SilkS")
		)
		(fp_poly
			(pts
				(xy 3.043428 -0.804164) (xy 3.043428 0.719836) (xy 1.519428 -0.042164)
			)
			(stroke
				(width 0)
				(type default)
			)
			(fill yes)
			(layer "B.SilkS")
		)
		(fp_line
			(start -2.54 3.81)
			(end -2.54 -1.27)
			(stroke
				(width 0.1)
				(type default)
			)
			(layer "B.Fab")
		)
		(fp_line
			(start 0 3.81)
			(end -2.54 3.81)
			(stroke
				(width 0.1)
				(type default)
			)
			(layer "B.Fab")
		)
		(fp_line
			(start -2.54 -1.27)
			(end 0 -1.27)
			(stroke
				(width 0.1)
				(type default)
			)
			(layer "B.Fab")
		)
		(fp_line
			(start 0 -1.27)
			(end 0 3.81)
			(stroke
				(width 0.1)
				(type default)
			)
			(layer "B.Fab")
		)
		(fp_poly
			(pts
				(xy 0.761746 0) (xy 2.285746 -0.762) (xy 2.285746 0.762)
			)
			(stroke
				(width 0)
				(type default)
			)
			(fill yes)
			(layer "B.Fab")
		)
		(pad "1" thru_hole circle
			(at 0 0 90)
			(size 1.0033 1.0033)
			(drill 0.249936)
			(layers "*.Cu" "*.Mask")
			(remove_unused_layers no)
			(net "TDR_DIFF_85_IN6_DP")
			(clearance 0.10795)
			(padstack
				(mode front_inner_back)
				(layer "Inner"
					(shape circle)
					(size 0.8001 0.8001)
					(clearance 0.1524)
				)
				(layer "B.Cu"
					(shape circle)
					(size 1.0033 1.0033)
					(thermal_gap 0.10795)
					(clearance 0.10795)
				)
			)
		)
		(pad "2" thru_hole circle
			(at -2.54 0 90)
			(size 1.9939 1.9939)
			(drill 0.249936)
			(layers "*.Cu" "*.Mask")
			(remove_unused_layers no)
			(net "T1_GND")
			(clearance 0.10795)
			(padstack
				(mode front_inner_back)
				(layer "Inner"
					(shape circle)
					(size 0.8001 0.8001)
					(clearance 0.1524)
				)
				(layer "B.Cu"
					(shape circle)
					(size 1.9939 1.9939)
					(thermal_gap 0.10795)
					(clearance 0.10795)
				)
			)
		)
		(pad "3" thru_hole circle
			(at -2.54 2.54 90)
			(size 1.9939 1.9939)
			(drill 0.249936)
			(layers "*.Cu" "*.Mask")
			(remove_unused_layers no)
			(net "T1_GND")
			(clearance 0.10795)
			(padstack
				(mode front_inner_back)
				(layer "Inner"
					(shape circle)
					(size 0.8001 0.8001)
					(clearance 0.1524)
				)
				(layer "B.Cu"
					(shape circle)
					(size 1.9939 1.9939)
					(thermal_gap 0.10795)
					(clearance 0.10795)
				)
			)
		)
		(pad "4" thru_hole circle
			(at 0 2.54 90)
			(size 1.0033 1.0033)
			(drill 0.249936)
			(layers "*.Cu" "*.Mask")
			(remove_unused_layers no)
			(net "TDR_DIFF_85_IN6_DN")
			(clearance 0.10795)
			(padstack
				(mode front_inner_back)
				(layer "Inner"
					(shape circle)
					(size 0.8001 0.8001)
					(clearance 0.1524)
				)
				(layer "B.Cu"
					(shape circle)
					(size 1.0033 1.0033)
					(thermal_gap 0.10795)
					(clearance 0.10795)
				)
			)
		)
	)
	(footprint ""
		(layer "B.Cu")
		(at 252.349 -100.613718 180)
		(property "Reference" "C1313"
			(at 0 0 0)
			(layer "B.SilkS")
			(hide yes)
			(effects
				(font
					(size 1.27 1.27)
				)
				(justify mirror)
			)
		)
		(property "Value" ""
			(at 0 0 0)
			(layer "B.Fab")
			(effects
				(font
					(size 1.27 1.27)
				)
				(justify mirror)
			)
		)
		(duplicate_pad_numbers_are_jumpers no)
		(fp_line
			(start 1.2954 0.5842)
			(end 1.2954 -0.5842)
			(stroke
				(width 0.1524)
				(type default)
			)
			(layer "B.SilkS")
		)
		(fp_line
			(start 1.2954 -0.5842)
			(end -1.2954 -0.5842)
			(stroke
				(width 0.1524)
				(type default)
			)
			(layer "B.SilkS")
		)
		(fp_line
			(start 0 -0.5842)
			(end 0 0.5842)
			(stroke
				(width 0.1524)
				(type default)
			)
			(layer "B.SilkS")
		)
		(fp_line
			(start -1.2954 0.5842)
			(end 1.2954 0.5842)
			(stroke
				(width 0.1524)
				(type default)
			)
			(layer "B.SilkS")
		)
		(fp_line
			(start -1.2954 -0.5842)
			(end -1.2954 0.5842)
			(stroke
				(width 0.1524)
				(type default)
			)
			(layer "B.SilkS")
		)
		(fp_line
			(start 1.1938 0.4064)
			(end 1.1938 -0.4064)
			(stroke
				(width 0.1)
				(type default)
			)
			(layer "B.Fab")
		)
		(fp_line
			(start 1.1938 -0.4064)
			(end 0.8636 -0.4064)
			(stroke
				(width 0.1)
				(type default)
			)
			(layer "B.Fab")
		)
		(fp_line
			(start 0.8636 0.4572)
			(end 0.8636 0.4064)
			(stroke
				(width 0.1)
				(type default)
			)
			(layer "B.Fab")
		)
		(fp_line
			(start 0.8636 0.4064)
			(end 1.1938 0.4064)
			(stroke
				(width 0.1)
				(type default)
			)
			(layer "B.Fab")
		)
		(fp_line
			(start 0.8636 -0.4064)
			(end 0.8636 -0.4572)
			(stroke
				(width 0.1)
				(type default)
			)
			(layer "B.Fab")
		)
		(fp_line
			(start 0.8636 -0.4572)
			(end -0.8636 -0.4572)
			(stroke
				(width 0.1)
				(type default)
			)
			(layer "B.Fab")
		)
		(fp_line
			(start -0.8636 0.4572)
			(end 0.8636 0.4572)
			(stroke
				(width 0.1)
				(type default)
			)
			(layer "B.Fab")
		)
		(fp_line
			(start -0.8636 0.4064)
			(end -0.8636 0.4572)
			(stroke
				(width 0.1)
				(type default)
			)
			(layer "B.Fab")
		)
		(fp_line
			(start -0.8636 -0.4064)
			(end -1.1938 -0.4064)
			(stroke
				(width 0.1)
				(type default)
			)
			(layer "B.Fab")
		)
		(fp_line
			(start -0.8636 -0.4572)
			(end -0.8636 -0.4064)
			(stroke
				(width 0.1)
				(type default)
			)
			(layer "B.Fab")
		)
		(fp_line
			(start -1.1938 0.4064)
			(end -0.8636 0.4064)
			(stroke
				(width 0.1)
				(type default)
			)
			(layer "B.Fab")
		)
		(fp_line
			(start -1.1938 -0.4064)
			(end -1.1938 0.4064)
			(stroke
				(width 0.1)
				(type default)
			)
			(layer "B.Fab")
		)
		(pad "1" smd rect
			(at 0.7366 0 90)
			(size 0.7112 0.8128)
			(layers "B.Cu" "B.Mask" "B.Paste")
			(net "P3V3_AUX_CLK_GEN_VDDA25M_CK440")
		)
		(pad "2" smd rect
			(at -0.7366 0 90)
			(size 0.7112 0.8128)
			(layers "B.Cu" "B.Mask" "B.Paste")
			(net "GND")
		)
	)
	(footprint ""
		(layer "B.Cu")
		(at 119.95912 -259.53212 90)
		(property "Reference" "C478"
			(at 0 0 90)
			(layer "B.SilkS")
			(hide yes)
			(effects
				(font
					(size 1.27 1.27)
				)
				(justify mirror)
			)
		)
		(property "Value" ""
			(at 0 0 90)
			(layer "B.Fab")
			(effects
				(font
					(size 1.27 1.27)
				)
				(justify mirror)
			)
		)
		(duplicate_pad_numbers_are_jumpers no)
		(fp_line
			(start 1.524 -0.762)
			(end -1.524 -0.762)
			(stroke
				(width 0.1524)
				(type default)
			)
			(layer "B.SilkS")
		)
		(fp_line
			(start -1.524 -0.762)
			(end -1.524 0.762)
			(stroke
				(width 0.1524)
				(type default)
			)
			(layer "B.SilkS")
		)
		(fp_line
			(start 1.524 0.762)
			(end 1.524 -0.762)
			(stroke
				(width 0.1524)
				(type default)
			)
			(layer "B.SilkS")
		)
		(fp_line
			(start -1.524 0.762)
			(end 1.524 0.762)
			(stroke
				(width 0.1524)
				(type default)
			)
			(layer "B.SilkS")
		)
		(fp_line
			(start 1.1049 -0.724916)
			(end 1.1049 0.724916)
			(stroke
				(width 0.1)
				(type default)
			)
			(layer "B.Fab")
		)
		(fp_line
			(start -1.1049 -0.724916)
			(end 1.1049 -0.724916)
			(stroke
				(width 0.1)
				(type default)
			)
			(layer "B.Fab")
		)
		(fp_line
			(start 1.1049 0.724916)
			(end -1.1049 0.724916)
			(stroke
				(width 0.1)
				(type default)
			)
			(layer "B.Fab")
		)
		(fp_line
			(start -1.1049 0.724916)
			(end -1.1049 -0.724916)
			(stroke
				(width 0.1)
				(type default)
			)
			(layer "B.Fab")
		)
		(pad "1" smd rect
			(at 0.889 0 90)
			(size 1.016 1.27)
			(layers "B.Cu" "B.Mask" "B.Paste")
			(net "PVCCINFAON_CPU1")
		)
		(pad "2" smd rect
			(at -0.889 0 90)
			(size 1.016 1.27)
			(layers "B.Cu" "B.Mask" "B.Paste")
			(net "GND")
		)
	)
	(footprint ""
		(layer "B.Cu")
		(at 175.355758 -115.375436 180)
		(property "Reference" "C1926"
			(at 0 0 0)
			(layer "B.SilkS")
			(hide yes)
			(effects
				(font
					(size 1.27 1.27)
				)
				(justify mirror)
			)
		)
		(property "Value" ""
			(at 0 0 0)
			(layer "B.Fab")
			(effects
				(font
					(size 1.27 1.27)
				)
				(justify mirror)
			)
		)
		(duplicate_pad_numbers_are_jumpers no)
		(fp_line
			(start 0.69215 0.2921)
			(end 0.69215 -0.2921)
			(stroke
				(width 0.1524)
				(type default)
			)
			(layer "B.SilkS")
		)
		(fp_line
			(start 0.69215 -0.2921)
			(end -0.69215 -0.2921)
			(stroke
				(width 0.1524)
				(type default)
			)
			(layer "B.SilkS")
		)
		(fp_line
			(start -0.69215 0.2921)
			(end 0.69215 0.2921)
			(stroke
				(width 0.1524)
				(type default)
			)
			(layer "B.SilkS")
		)
		(fp_line
			(start -0.69215 -0.2921)
			(end -0.69215 0.2921)
			(stroke
				(width 0.1524)
				(type default)
			)
			(layer "B.SilkS")
		)
		(fp_line
			(start 0.51435 0.2794)
			(end 0.51435 -0.2794)
			(stroke
				(width 0.1)
				(type default)
			)
			(layer "B.Fab")
		)
		(fp_line
			(start 0.51435 -0.2794)
			(end -0.51435 -0.2794)
			(stroke
				(width 0.1)
				(type default)
			)
			(layer "B.Fab")
		)
		(fp_line
			(start -0.51435 0.2794)
			(end 0.51435 0.2794)
			(stroke
				(width 0.1)
				(type default)
			)
			(layer "B.Fab")
		)
		(fp_line
			(start -0.51435 -0.2794)
			(end -0.51435 0.2794)
			(stroke
				(width 0.1)
				(type default)
			)
			(layer "B.Fab")
		)
		(pad "1" smd circle
			(at 0.40005 0)
			(size 0 0)
			(layers "B.Cu" "B.Mask" "B.Paste")
			(net "P3V3_AUX_FPGA_VCCIO0")
		)
		(pad "2" smd circle
			(at -0.40005 0)
			(size 0 0)
			(layers "B.Cu" "B.Mask" "B.Paste")
			(net "GND")
		)
		(zone
			(layer "B.Cu")
			(hatch none 0.5)
			(connect_pads
				(clearance 0)
			)
			(min_thickness 0.25)
			(keepout
				(tracks not_allowed)
				(vias allowed)
				(pads allowed)
				(copperpour not_allowed)
				(footprints allowed)
			)
			(placement
				(enabled no)
				(sheetname "")
			)
			(fill
				(thermal_gap 0.5)
				(thermal_bridge_width 0.5)
				(island_removal_mode 0)
			)
			(polygon
				(pts
					(xy 175.165258 -115.463066) (xy 175.256698 -115.521232) (xy 175.456088 -115.521232) (xy 175.546258 -115.463066)
					(xy 175.546258 -115.287806) (xy 175.456088 -115.229386) (xy 175.256698 -115.229386) (xy 175.165258 -115.287552)
				)
			)
		)
	)
	(footprint ""
		(layer "B.Cu")
		(at 346.441014 -337.564984 -90)
		(property "Reference" "PC307_P0_1"
			(at 0 0 90)
			(layer "B.SilkS")
			(hide yes)
			(effects
				(font
					(size 1.27 1.27)
				)
				(justify mirror)
			)
		)
		(property "Value" ""
			(at 0 0 90)
			(layer "B.Fab")
			(effects
				(font
					(size 1.27 1.27)
				)
				(justify mirror)
			)
		)
		(duplicate_pad_numbers_are_jumpers no)
		(fp_line
			(start -1.524 0.762)
			(end 1.524 0.762)
			(stroke
				(width 0.1524)
				(type default)
			)
			(layer "B.SilkS")
		)
		(fp_line
			(start 1.524 0.762)
			(end 1.524 -0.762)
			(stroke
				(width 0.1524)
				(type default)
			)
			(layer "B.SilkS")
		)
		(fp_line
			(start -1.524 -0.762)
			(end -1.524 0.762)
			(stroke
				(width 0.1524)
				(type default)
			)
			(layer "B.SilkS")
		)
		(fp_line
			(start 1.524 -0.762)
			(end -1.524 -0.762)
			(stroke
				(width 0.1524)
				(type default)
			)
			(layer "B.SilkS")
		)
		(fp_line
			(start -1.1049 0.724916)
			(end -1.1049 -0.724916)
			(stroke
				(width 0.1)
				(type default)
			)
			(layer "B.Fab")
		)
		(fp_line
			(start 1.1049 0.724916)
			(end -1.1049 0.724916)
			(stroke
				(width 0.1)
				(type default)
			)
			(layer "B.Fab")
		)
		(fp_line
			(start -1.1049 -0.724916)
			(end 1.1049 -0.724916)
			(stroke
				(width 0.1)
				(type default)
			)
			(layer "B.Fab")
		)
		(fp_line
			(start 1.1049 -0.724916)
			(end 1.1049 0.724916)
			(stroke
				(width 0.1)
				(type default)
			)
			(layer "B.Fab")
		)
		(pad "1" smd rect
			(at 0.889 0 270)
			(size 1.016 1.27)
			(layers "B.Cu" "B.Mask" "B.Paste")
			(net "SW_P12V_PVCCIN_CPU0_FLT")
		)
		(pad "2" smd rect
			(at -0.889 0 270)
			(size 1.016 1.27)
			(layers "B.Cu" "B.Mask" "B.Paste")
			(net "GND")
		)
	)
	(footprint ""
		(layer "B.Cu")
		(at 27.304746 -321.554856 -90)
		(property "Reference" "C63"
			(at 0 0 90)
			(layer "B.SilkS")
			(hide yes)
			(effects
				(font
					(size 1.27 1.27)
				)
				(justify mirror)
			)
		)
		(property "Value" ""
			(at 0 0 90)
			(layer "B.Fab")
			(effects
				(font
					(size 1.27 1.27)
				)
				(justify mirror)
			)
		)
		(duplicate_pad_numbers_are_jumpers no)
		(fp_line
			(start -1.524 0.762)
			(end 1.524 0.762)
			(stroke
				(width 0.1524)
				(type default)
			)
			(layer "B.SilkS")
		)
		(fp_line
			(start 1.524 0.762)
			(end 1.524 -0.762)
			(stroke
				(width 0.1524)
				(type default)
			)
			(layer "B.SilkS")
		)
		(fp_line
			(start -1.524 -0.762)
			(end -1.524 0.762)
			(stroke
				(width 0.1524)
				(type default)
			)
			(layer "B.SilkS")
		)
		(fp_line
			(start 1.524 -0.762)
			(end -1.524 -0.762)
			(stroke
				(width 0.1524)
				(type default)
			)
			(layer "B.SilkS")
		)
		(fp_line
			(start -1.1049 0.724916)
			(end -1.1049 -0.724916)
			(stroke
				(width 0.1)
				(type default)
			)
			(layer "B.Fab")
		)
		(fp_line
			(start 1.1049 0.724916)
			(end -1.1049 0.724916)
			(stroke
				(width 0.1)
				(type default)
			)
			(layer "B.Fab")
		)
		(fp_line
			(start -1.1049 -0.724916)
			(end 1.1049 -0.724916)
			(stroke
				(width 0.1)
				(type default)
			)
			(layer "B.Fab")
		)
		(fp_line
			(start 1.1049 -0.724916)
			(end 1.1049 0.724916)
			(stroke
				(width 0.1)
				(type default)
			)
			(layer "B.Fab")
		)
		(pad "1" smd rect
			(at 0.889 0 270)
			(size 1.016 1.27)
			(layers "B.Cu" "B.Mask" "B.Paste")
			(net "P12V_S3_AUX_CPU1_NVDIMM")
		)
		(pad "2" smd rect
			(at -0.889 0 270)
			(size 1.016 1.27)
			(layers "B.Cu" "B.Mask" "B.Paste")
			(net "GND")
		)
	)
	(footprint ""
		(layer "B.Cu")
		(at 41.830244 -100.55733 90)
		(property "Reference" "R3940"
			(at 0 0 90)
			(layer "B.SilkS")
			(hide yes)
			(effects
				(font
					(size 1.27 1.27)
				)
				(justify mirror)
			)
		)
		(property "Value" ""
			(at 0 0 90)
			(layer "B.Fab")
			(effects
				(font
					(size 1.27 1.27)
				)
				(justify mirror)
			)
		)
		(duplicate_pad_numbers_are_jumpers no)
		(fp_line
			(start 0.7874 -0.4064)
			(end -0.7874 -0.4064)
			(stroke
				(width 0.1524)
				(type default)
			)
			(layer "B.SilkS")
		)
		(fp_line
			(start -0.7874 -0.4064)
			(end -0.7874 0.4064)
			(stroke
				(width 0.1524)
				(type default)
			)
			(layer "B.SilkS")
		)
		(fp_line
			(start 0.7874 0.4064)
			(end 0.7874 -0.4064)
			(stroke
				(width 0.1524)
				(type default)
			)
			(layer "B.SilkS")
		)
		(fp_line
			(start -0.7874 0.4064)
			(end 0.7874 0.4064)
			(stroke
				(width 0.1524)
				(type default)
			)
			(layer "B.SilkS")
		)
		(fp_line
			(start 0.67945 -0.305054)
			(end 0.12065 -0.305054)
			(stroke
				(width 0.1)
				(type default)
			)
			(layer "B.Fab")
		)
		(fp_line
			(start 0.12065 -0.305054)
			(end 0.12065 -0.2794)
			(stroke
				(width 0.1)
				(type default)
			)
			(layer "B.Fab")
		)
		(fp_line
			(start -0.12065 -0.3048)
			(end -0.67945 -0.3048)
			(stroke
				(width 0.1)
				(type default)
			)
			(layer "B.Fab")
		)
		(fp_line
			(start -0.67945 -0.3048)
			(end -0.67945 0.3048)
			(stroke
				(width 0.1)
				(type default)
			)
			(layer "B.Fab")
		)
		(fp_line
			(start 0.12065 -0.2794)
			(end -0.12065 -0.2794)
			(stroke
				(width 0.1)
				(type default)
			)
			(layer "B.Fab")
		)
		(fp_line
			(start -0.12065 -0.2794)
			(end -0.12065 -0.3048)
			(stroke
				(width 0.1)
				(type default)
			)
			(layer "B.Fab")
		)
		(fp_line
			(start 0.12065 0.2794)
			(end 0.12065 0.3048)
			(stroke
				(width 0.1)
				(type default)
			)
			(layer "B.Fab")
		)
		(fp_line
			(start -0.120396 0.2794)
			(end 0.12065 0.2794)
			(stroke
				(width 0.1)
				(type default)
			)
			(layer "B.Fab")
		)
		(fp_line
			(start 0.67945 0.3048)
			(end 0.67945 -0.305054)
			(stroke
				(width 0.1)
				(type default)
			)
			(layer "B.Fab")
		)
		(fp_line
			(start 0.12065 0.3048)
			(end 0.67945 0.3048)
			(stroke
				(width 0.1)
				(type default)
			)
			(layer "B.Fab")
		)
		(fp_line
			(start -0.120396 0.3048)
			(end -0.120396 0.2794)
			(stroke
				(width 0.1)
				(type default)
			)
			(layer "B.Fab")
		)
		(fp_line
			(start -0.67945 0.3048)
			(end -0.120396 0.3048)
			(stroke
				(width 0.1)
				(type default)
			)
			(layer "B.Fab")
		)
		(pad "1" smd rect
			(at 0.40005 0 90)
			(size 0.4572 0.508)
			(layers "B.Cu" "B.Mask" "B.Paste")
			(net "P12V_E1S_0_ISENSE_MPS_MAM")
		)
		(pad "2" smd rect
			(at -0.40005 0 90)
			(size 0.4572 0.508)
			(layers "B.Cu" "B.Mask" "B.Paste")
			(net "P12V_E1S_0_ISENSE_MAM")
		)
	)
	(footprint ""
		(layer "B.Cu")
		(at 108.42117 -418.336222 180)
		(property "Reference" "R4475"
			(at 0 0 0)
			(layer "B.SilkS")
			(hide yes)
			(effects
				(font
					(size 1.27 1.27)
				)
				(justify mirror)
			)
		)
		(property "Value" ""
			(at 0 0 0)
			(layer "B.Fab")
			(effects
				(font
					(size 1.27 1.27)
				)
				(justify mirror)
			)
		)
		(duplicate_pad_numbers_are_jumpers no)
		(fp_line
			(start 1.2954 0.5842)
			(end 1.2954 -0.5842)
			(stroke
				(width 0.1524)
				(type default)
			)
			(layer "B.SilkS")
		)
		(fp_line
			(start 1.2954 -0.5842)
			(end -1.2954 -0.5842)
			(stroke
				(width 0.1524)
				(type default)
			)
			(layer "B.SilkS")
		)
		(fp_line
			(start -1.2954 0.5842)
			(end 1.2954 0.5842)
			(stroke
				(width 0.1524)
				(type default)
			)
			(layer "B.SilkS")
		)
		(fp_line
			(start -1.2954 -0.5842)
			(end -1.2954 0.5842)
			(stroke
				(width 0.1524)
				(type default)
			)
			(layer "B.SilkS")
		)
		(fp_line
			(start 1.1938 0.4064)
			(end 1.1938 -0.406654)
			(stroke
				(width 0.1)
				(type default)
			)
			(layer "B.Fab")
		)
		(fp_line
			(start 1.1938 -0.406654)
			(end 0.8636 -0.406654)
			(stroke
				(width 0.1)
				(type default)
			)
			(layer "B.Fab")
		)
		(fp_line
			(start 0.8636 0.4572)
			(end 0.8636 0.4318)
			(stroke
				(width 0.1)
				(type default)
			)
			(layer "B.Fab")
		)
		(fp_line
			(start 0.8636 0.4318)
			(end 0.8636 0.4064)
			(stroke
				(width 0.1)
				(type default)
			)
			(layer "B.Fab")
		)
		(fp_line
			(start 0.8636 0.4064)
			(end 1.1938 0.4064)
			(stroke
				(width 0.1)
				(type default)
			)
			(layer "B.Fab")
		)
		(fp_line
			(start 0.8636 -0.406654)
			(end 0.8636 -0.4572)
			(stroke
				(width 0.1)
				(type default)
			)
			(layer "B.Fab")
		)
		(fp_line
			(start 0.8636 -0.4572)
			(end -0.8636 -0.4572)
			(stroke
				(width 0.1)
				(type default)
			)
			(layer "B.Fab")
		)
		(fp_line
			(start -0.8636 0.4572)
			(end 0.8636 0.4572)
			(stroke
				(width 0.1)
				(type default)
			)
			(layer "B.Fab")
		)
		(fp_line
			(start -0.8636 0.4064)
			(end -0.8636 0.4572)
			(stroke
				(width 0.1)
				(type default)
			)
			(layer "B.Fab")
		)
		(fp_line
			(start -0.8636 -0.406654)
			(end -1.1938 -0.406654)
			(stroke
				(width 0.1)
				(type default)
			)
			(layer "B.Fab")
		)
		(fp_line
			(start -0.8636 -0.4572)
			(end -0.8636 -0.406654)
			(stroke
				(width 0.1)
				(type default)
			)
			(layer "B.Fab")
		)
		(fp_line
			(start -1.1938 0.4064)
			(end -0.8636 0.4064)
			(stroke
				(width 0.1)
				(type default)
			)
			(layer "B.Fab")
		)
		(fp_line
			(start -1.1938 -0.406654)
			(end -1.1938 0.4064)
			(stroke
				(width 0.1)
				(type default)
			)
			(layer "B.Fab")
		)
		(pad "1" smd rect
			(at 0.7366 0 90)
			(size 0.7112 0.8128)
			(layers "B.Cu" "B.Mask" "B.Paste")
			(net "P3V3_9ZXL045")
		)
		(pad "2" smd rect
			(at -0.7366 0 90)
			(size 0.7112 0.8128)
			(layers "B.Cu" "B.Mask" "B.Paste")
			(net "P3V3_9ZXL045_VDDR")
		)
	)
	(footprint ""
		(layer "B.Cu")
		(at 341.125048 -52.080922 -90)
		(property "Reference" "C1265"
			(at 0 0 90)
			(layer "B.SilkS")
			(hide yes)
			(effects
				(font
					(size 1.27 1.27)
				)
				(justify mirror)
			)
		)
		(property "Value" ""
			(at 0 0 90)
			(layer "B.Fab")
			(effects
				(font
					(size 1.27 1.27)
				)
				(justify mirror)
			)
		)
		(duplicate_pad_numbers_are_jumpers no)
		(fp_line
			(start -0.7874 0.4064)
			(end 0.7874 0.4064)
			(stroke
				(width 0.1524)
				(type default)
			)
			(layer "B.SilkS")
		)
		(fp_line
			(start 0.7874 0.4064)
			(end 0.7874 -0.4064)
			(stroke
				(width 0.1524)
				(type default)
			)
			(layer "B.SilkS")
		)
		(fp_line
			(start -0.7874 -0.4064)
			(end -0.7874 0.4064)
			(stroke
				(width 0.1524)
				(type default)
			)
			(layer "B.SilkS")
		)
		(fp_line
			(start 0.7874 -0.4064)
			(end -0.7874 -0.4064)
			(stroke
				(width 0.1524)
				(type default)
			)
			(layer "B.SilkS")
		)
		(fp_line
			(start -0.67945 0.3048)
			(end -0.120396 0.3048)
			(stroke
				(width 0.1)
				(type default)
			)
			(layer "B.Fab")
		)
		(fp_line
			(start -0.120396 0.3048)
			(end -0.120396 0.2794)
			(stroke
				(width 0.1)
				(type default)
			)
			(layer "B.Fab")
		)
		(fp_line
			(start 0.12065 0.3048)
			(end 0.67945 0.3048)
			(stroke
				(width 0.1)
				(type default)
			)
			(layer "B.Fab")
		)
		(fp_line
			(start 0.67945 0.3048)
			(end 0.67945 -0.305054)
			(stroke
				(width 0.1)
				(type default)
			)
			(layer "B.Fab")
		)
		(fp_line
			(start -0.120396 0.2794)
			(end 0.12065 0.2794)
			(stroke
				(width 0.1)
				(type default)
			)
			(layer "B.Fab")
		)
		(fp_line
			(start 0.12065 0.2794)
			(end 0.12065 0.3048)
			(stroke
				(width 0.1)
				(type default)
			)
			(layer "B.Fab")
		)
		(fp_line
			(start -0.12065 -0.2794)
			(end -0.12065 -0.3048)
			(stroke
				(width 0.1)
				(type default)
			)
			(layer "B.Fab")
		)
		(fp_line
			(start 0.12065 -0.2794)
			(end -0.12065 -0.2794)
			(stroke
				(width 0.1)
				(type default)
			)
			(layer "B.Fab")
		)
		(fp_line
			(start -0.67945 -0.3048)
			(end -0.67945 0.3048)
			(stroke
				(width 0.1)
				(type default)
			)
			(layer "B.Fab")
		)
		(fp_line
			(start -0.12065 -0.3048)
			(end -0.67945 -0.3048)
			(stroke
				(width 0.1)
				(type default)
			)
			(layer "B.Fab")
		)
		(fp_line
			(start 0.12065 -0.305054)
			(end 0.12065 -0.2794)
			(stroke
				(width 0.1)
				(type default)
			)
			(layer "B.Fab")
		)
		(fp_line
			(start 0.67945 -0.305054)
			(end 0.12065 -0.305054)
			(stroke
				(width 0.1)
				(type default)
			)
			(layer "B.Fab")
		)
		(pad "1" smd circle
			(at 0.40005 0 90)
			(size 0 0)
			(layers "B.Cu" "B.Mask" "B.Paste")
			(net "P1V8_PCH_PLL_AUX")
		)
		(pad "2" smd circle
			(at -0.40005 0 90)
			(size 0 0)
			(layers "B.Cu" "B.Mask" "B.Paste")
			(net "GND")
		)
	)
	(footprint ""
		(layer "B.Cu")
		(at 15.696946 -321.554856 -90)
		(property "Reference" "C98"
			(at 0 0 90)
			(layer "B.SilkS")
			(hide yes)
			(effects
				(font
					(size 1.27 1.27)
				)
				(justify mirror)
			)
		)
		(property "Value" ""
			(at 0 0 90)
			(layer "B.Fab")
			(effects
				(font
					(size 1.27 1.27)
				)
				(justify mirror)
			)
		)
		(duplicate_pad_numbers_are_jumpers no)
		(fp_line
			(start -1.524 0.762)
			(end 1.524 0.762)
			(stroke
				(width 0.1524)
				(type default)
			)
			(layer "B.SilkS")
		)
		(fp_line
			(start 1.524 0.762)
			(end 1.524 -0.762)
			(stroke
				(width 0.1524)
				(type default)
			)
			(layer "B.SilkS")
		)
		(fp_line
			(start -1.524 -0.762)
			(end -1.524 0.762)
			(stroke
				(width 0.1524)
				(type default)
			)
			(layer "B.SilkS")
		)
		(fp_line
			(start 1.524 -0.762)
			(end -1.524 -0.762)
			(stroke
				(width 0.1524)
				(type default)
			)
			(layer "B.SilkS")
		)
		(fp_line
			(start -1.1049 0.724916)
			(end -1.1049 -0.724916)
			(stroke
				(width 0.1)
				(type default)
			)
			(layer "B.Fab")
		)
		(fp_line
			(start 1.1049 0.724916)
			(end -1.1049 0.724916)
			(stroke
				(width 0.1)
				(type default)
			)
			(layer "B.Fab")
		)
		(fp_line
			(start -1.1049 -0.724916)
			(end 1.1049 -0.724916)
			(stroke
				(width 0.1)
				(type default)
			)
			(layer "B.Fab")
		)
		(fp_line
			(start 1.1049 -0.724916)
			(end 1.1049 0.724916)
			(stroke
				(width 0.1)
				(type default)
			)
			(layer "B.Fab")
		)
		(pad "1" smd rect
			(at 0.889 0 270)
			(size 1.016 1.27)
			(layers "B.Cu" "B.Mask" "B.Paste")
			(net "P12V_S3_AUX_CPU1_NVDIMM")
		)
		(pad "2" smd rect
			(at -0.889 0 270)
			(size 1.016 1.27)
			(layers "B.Cu" "B.Mask" "B.Paste")
			(net "GND")
		)
	)
	(footprint ""
		(layer "B.Cu")
		(at 451.962012 -58.325512 -90)
		(property "Reference" "PC1868"
			(at 0 0 90)
			(layer "B.SilkS")
			(hide yes)
			(effects
				(font
					(size 1.27 1.27)
				)
				(justify mirror)
			)
		)
		(property "Value" ""
			(at 0 0 90)
			(layer "B.Fab")
			(effects
				(font
					(size 1.27 1.27)
				)
				(justify mirror)
			)
		)
		(duplicate_pad_numbers_are_jumpers no)
		(fp_line
			(start -1.524 0.762)
			(end 1.524 0.762)
			(stroke
				(width 0.1524)
				(type default)
			)
			(layer "B.SilkS")
		)
		(fp_line
			(start 1.524 0.762)
			(end 1.524 -0.762)
			(stroke
				(width 0.1524)
				(type default)
			)
			(layer "B.SilkS")
		)
		(fp_line
			(start -1.524 -0.762)
			(end -1.524 0.762)
			(stroke
				(width 0.1524)
				(type default)
			)
			(layer "B.SilkS")
		)
		(fp_line
			(start 1.524 -0.762)
			(end -1.524 -0.762)
			(stroke
				(width 0.1524)
				(type default)
			)
			(layer "B.SilkS")
		)
		(fp_line
			(start -1.1049 0.724916)
			(end -1.1049 -0.724916)
			(stroke
				(width 0.1)
				(type default)
			)
			(layer "B.Fab")
		)
		(fp_line
			(start 1.1049 0.724916)
			(end -1.1049 0.724916)
			(stroke
				(width 0.1)
				(type default)
			)
			(layer "B.Fab")
		)
		(fp_line
			(start -1.1049 -0.724916)
			(end 1.1049 -0.724916)
			(stroke
				(width 0.1)
				(type default)
			)
			(layer "B.Fab")
		)
		(fp_line
			(start 1.1049 -0.724916)
			(end 1.1049 0.724916)
			(stroke
				(width 0.1)
				(type default)
			)
			(layer "B.Fab")
		)
		(pad "1" smd rect
			(at 0.889 0 270)
			(size 1.016 1.27)
			(layers "B.Cu" "B.Mask" "B.Paste")
			(net "P3V3_AUX")
		)
		(pad "2" smd rect
			(at -0.889 0 270)
			(size 1.016 1.27)
			(layers "B.Cu" "B.Mask" "B.Paste")
			(net "GND")
		)
	)
	(footprint ""
		(layer "B.Cu")
		(at 291.586158 -153.944828)
		(property "Reference" "R692"
			(at 0 0 0)
			(layer "B.SilkS")
			(hide yes)
			(effects
				(font
					(size 1.27 1.27)
				)
				(justify mirror)
			)
		)
		(property "Value" ""
			(at 0 0 0)
			(layer "B.Fab")
			(effects
				(font
					(size 1.27 1.27)
				)
				(justify mirror)
			)
		)
		(duplicate_pad_numbers_are_jumpers no)
		(fp_line
			(start -0.7874 -0.4064)
			(end -0.7874 0.4064)
			(stroke
				(width 0.1524)
				(type default)
			)
			(layer "B.SilkS")
		)
		(fp_line
			(start -0.7874 0.4064)
			(end 0.7874 0.4064)
			(stroke
				(width 0.1524)
				(type default)
			)
			(layer "B.SilkS")
		)
		(fp_line
			(start 0.7874 -0.4064)
			(end -0.7874 -0.4064)
			(stroke
				(width 0.1524)
				(type default)
			)
			(layer "B.SilkS")
		)
		(fp_line
			(start 0.7874 0.4064)
			(end 0.7874 -0.4064)
			(stroke
				(width 0.1524)
				(type default)
			)
			(layer "B.SilkS")
		)
		(fp_line
			(start -0.67945 -0.3048)
			(end -0.67945 0.3048)
			(stroke
				(width 0.1)
				(type default)
			)
			(layer "B.Fab")
		)
		(fp_line
			(start -0.67945 0.3048)
			(end -0.120396 0.3048)
			(stroke
				(width 0.1)
				(type default)
			)
			(layer "B.Fab")
		)
		(fp_line
			(start -0.12065 -0.3048)
			(end -0.67945 -0.3048)
			(stroke
				(width 0.1)
				(type default)
			)
			(layer "B.Fab")
		)
		(fp_line
			(start -0.12065 -0.2794)
			(end -0.12065 -0.3048)
			(stroke
				(width 0.1)
				(type default)
			)
			(layer "B.Fab")
		)
		(fp_line
			(start -0.120396 0.2794)
			(end 0.12065 0.2794)
			(stroke
				(width 0.1)
				(type default)
			)
			(layer "B.Fab")
		)
		(fp_line
			(start -0.120396 0.3048)
			(end -0.120396 0.2794)
			(stroke
				(width 0.1)
				(type default)
			)
			(layer "B.Fab")
		)
		(fp_line
			(start 0.12065 -0.305054)
			(end 0.12065 -0.2794)
			(stroke
				(width 0.1)
				(type default)
			)
			(layer "B.Fab")
		)
		(fp_line
			(start 0.12065 -0.2794)
			(end -0.12065 -0.2794)
			(stroke
				(width 0.1)
				(type default)
			)
			(layer "B.Fab")
		)
		(fp_line
			(start 0.12065 0.2794)
			(end 0.12065 0.3048)
			(stroke
				(width 0.1)
				(type default)
			)
			(layer "B.Fab")
		)
		(fp_line
			(start 0.12065 0.3048)
			(end 0.67945 0.3048)
			(stroke
				(width 0.1)
				(type default)
			)
			(layer "B.Fab")
		)
		(fp_line
			(start 0.67945 -0.305054)
			(end 0.12065 -0.305054)
			(stroke
				(width 0.1)
				(type default)
			)
			(layer "B.Fab")
		)
		(fp_line
			(start 0.67945 0.3048)
			(end 0.67945 -0.305054)
			(stroke
				(width 0.1)
				(type default)
			)
			(layer "B.Fab")
		)
		(pad "1" smd circle
			(at 0.40005 0 180)
			(size 0 0)
			(layers "B.Cu" "B.Mask" "B.Paste")
			(net "I3C_SPD_DDRABCD_CPU0_LVC1_R_SDA")
		)
		(pad "2" smd circle
			(at -0.40005 0 180)
			(size 0 0)
			(layers "B.Cu" "B.Mask" "B.Paste")
			(net "I3C_SPD_DDRABCD_CPU0_LVC1_SDA")
		)
	)
	(footprint ""
		(layer "B.Cu")
		(at 234.230926 -120.851676 180)
		(property "Reference" "R571"
			(at 0 0 0)
			(layer "B.SilkS")
			(hide yes)
			(effects
				(font
					(size 1.27 1.27)
				)
				(justify mirror)
			)
		)
		(property "Value" ""
			(at 0 0 0)
			(layer "B.Fab")
			(effects
				(font
					(size 1.27 1.27)
				)
				(justify mirror)
			)
		)
		(duplicate_pad_numbers_are_jumpers no)
		(fp_line
			(start 1.2954 0.5842)
			(end 1.2954 -0.5842)
			(stroke
				(width 0.1524)
				(type default)
			)
			(layer "B.SilkS")
		)
		(fp_line
			(start 1.2954 -0.5842)
			(end -1.2954 -0.5842)
			(stroke
				(width 0.1524)
				(type default)
			)
			(layer "B.SilkS")
		)
		(fp_line
			(start -1.2954 0.5842)
			(end 1.2954 0.5842)
			(stroke
				(width 0.1524)
				(type default)
			)
			(layer "B.SilkS")
		)
		(fp_line
			(start -1.2954 -0.5842)
			(end -1.2954 0.5842)
			(stroke
				(width 0.1524)
				(type default)
			)
			(layer "B.SilkS")
		)
		(fp_line
			(start 1.1938 0.4064)
			(end 1.1938 -0.406654)
			(stroke
				(width 0.1)
				(type default)
			)
			(layer "B.Fab")
		)
		(fp_line
			(start 1.1938 -0.406654)
			(end 0.8636 -0.406654)
			(stroke
				(width 0.1)
				(type default)
			)
			(layer "B.Fab")
		)
		(fp_line
			(start 0.8636 0.4572)
			(end 0.8636 0.4318)
			(stroke
				(width 0.1)
				(type default)
			)
			(layer "B.Fab")
		)
		(fp_line
			(start 0.8636 0.4318)
			(end 0.8636 0.4064)
			(stroke
				(width 0.1)
				(type default)
			)
			(layer "B.Fab")
		)
		(fp_line
			(start 0.8636 0.4064)
			(end 1.1938 0.4064)
			(stroke
				(width 0.1)
				(type default)
			)
			(layer "B.Fab")
		)
		(fp_line
			(start 0.8636 -0.406654)
			(end 0.8636 -0.4572)
			(stroke
				(width 0.1)
				(type default)
			)
			(layer "B.Fab")
		)
		(fp_line
			(start 0.8636 -0.4572)
			(end -0.8636 -0.4572)
			(stroke
				(width 0.1)
				(type default)
			)
			(layer "B.Fab")
		)
		(fp_line
			(start -0.8636 0.4572)
			(end 0.8636 0.4572)
			(stroke
				(width 0.1)
				(type default)
			)
			(layer "B.Fab")
		)
		(fp_line
			(start -0.8636 0.4064)
			(end -0.8636 0.4572)
			(stroke
				(width 0.1)
				(type default)
			)
			(layer "B.Fab")
		)
		(fp_line
			(start -0.8636 -0.406654)
			(end -1.1938 -0.406654)
			(stroke
				(width 0.1)
				(type default)
			)
			(layer "B.Fab")
		)
		(fp_line
			(start -0.8636 -0.4572)
			(end -0.8636 -0.406654)
			(stroke
				(width 0.1)
				(type default)
			)
			(layer "B.Fab")
		)
		(fp_line
			(start -1.1938 0.4064)
			(end -0.8636 0.4064)
			(stroke
				(width 0.1)
				(type default)
			)
			(layer "B.Fab")
		)
		(fp_line
			(start -1.1938 -0.406654)
			(end -1.1938 0.4064)
			(stroke
				(width 0.1)
				(type default)
			)
			(layer "B.Fab")
		)
		(pad "1" smd rect
			(at 0.7366 0 90)
			(size 0.7112 0.8128)
			(layers "B.Cu" "B.Mask" "B.Paste")
			(net "P3V3_DB2000_FB_VDD")
		)
		(pad "2" smd rect
			(at -0.7366 0 90)
			(size 0.7112 0.8128)
			(layers "B.Cu" "B.Mask" "B.Paste")
			(net "P3V3_DB2000_VDDR")
		)
	)
	(footprint ""
		(layer "B.Cu")
		(at 257.287268 -75.32878 90)
		(property "Reference" "R1650"
			(at 0 0 90)
			(layer "B.SilkS")
			(hide yes)
			(effects
				(font
					(size 1.27 1.27)
				)
				(justify mirror)
			)
		)
		(property "Value" ""
			(at 0 0 90)
			(layer "B.Fab")
			(effects
				(font
					(size 1.27 1.27)
				)
				(justify mirror)
			)
		)
		(duplicate_pad_numbers_are_jumpers no)
		(fp_line
			(start 0.7874 -0.4064)
			(end -0.7874 -0.4064)
			(stroke
				(width 0.1524)
				(type default)
			)
			(layer "B.SilkS")
		)
		(fp_line
			(start -0.7874 -0.4064)
			(end -0.7874 0.4064)
			(stroke
				(width 0.1524)
				(type default)
			)
			(layer "B.SilkS")
		)
		(fp_line
			(start 0.7874 0.4064)
			(end 0.7874 -0.4064)
			(stroke
				(width 0.1524)
				(type default)
			)
			(layer "B.SilkS")
		)
		(fp_line
			(start -0.7874 0.4064)
			(end 0.7874 0.4064)
			(stroke
				(width 0.1524)
				(type default)
			)
			(layer "B.SilkS")
		)
		(fp_line
			(start 0.67945 -0.305054)
			(end 0.12065 -0.305054)
			(stroke
				(width 0.1)
				(type default)
			)
			(layer "B.Fab")
		)
		(fp_line
			(start 0.12065 -0.305054)
			(end 0.12065 -0.2794)
			(stroke
				(width 0.1)
				(type default)
			)
			(layer "B.Fab")
		)
		(fp_line
			(start -0.12065 -0.3048)
			(end -0.67945 -0.3048)
			(stroke
				(width 0.1)
				(type default)
			)
			(layer "B.Fab")
		)
		(fp_line
			(start -0.67945 -0.3048)
			(end -0.67945 0.3048)
			(stroke
				(width 0.1)
				(type default)
			)
			(layer "B.Fab")
		)
		(fp_line
			(start 0.12065 -0.2794)
			(end -0.12065 -0.2794)
			(stroke
				(width 0.1)
				(type default)
			)
			(layer "B.Fab")
		)
		(fp_line
			(start -0.12065 -0.2794)
			(end -0.12065 -0.3048)
			(stroke
				(width 0.1)
				(type default)
			)
			(layer "B.Fab")
		)
		(fp_line
			(start 0.12065 0.2794)
			(end 0.12065 0.3048)
			(stroke
				(width 0.1)
				(type default)
			)
			(layer "B.Fab")
		)
		(fp_line
			(start -0.120396 0.2794)
			(end 0.12065 0.2794)
			(stroke
				(width 0.1)
				(type default)
			)
			(layer "B.Fab")
		)
		(fp_line
			(start 0.67945 0.3048)
			(end 0.67945 -0.305054)
			(stroke
				(width 0.1)
				(type default)
			)
			(layer "B.Fab")
		)
		(fp_line
			(start 0.12065 0.3048)
			(end 0.67945 0.3048)
			(stroke
				(width 0.1)
				(type default)
			)
			(layer "B.Fab")
		)
		(fp_line
			(start -0.120396 0.3048)
			(end -0.120396 0.2794)
			(stroke
				(width 0.1)
				(type default)
			)
			(layer "B.Fab")
		)
		(fp_line
			(start -0.67945 0.3048)
			(end -0.120396 0.3048)
			(stroke
				(width 0.1)
				(type default)
			)
			(layer "B.Fab")
		)
		(pad "1" smd circle
			(at 0.40005 0 270)
			(size 0 0)
			(layers "B.Cu" "B.Mask" "B.Paste")
			(net "PWRGD_P1V05_PCH_AUX_R")
		)
		(pad "2" smd circle
			(at -0.40005 0 270)
			(size 0 0)
			(layers "B.Cu" "B.Mask" "B.Paste")
			(net "PWRGD_P1V05_PCH_AUX")
		)
	)
	(footprint ""
		(layer "B.Cu")
		(at 251.175266 -107.178094)
		(property "Reference" "R1462"
			(at 0 0 0)
			(layer "B.SilkS")
			(hide yes)
			(effects
				(font
					(size 1.27 1.27)
				)
				(justify mirror)
			)
		)
		(property "Value" ""
			(at 0 0 0)
			(layer "B.Fab")
			(effects
				(font
					(size 1.27 1.27)
				)
				(justify mirror)
			)
		)
		(duplicate_pad_numbers_are_jumpers no)
		(fp_line
			(start -0.7874 -0.4064)
			(end -0.7874 0.4064)
			(stroke
				(width 0.1524)
				(type default)
			)
			(layer "B.SilkS")
		)
		(fp_line
			(start -0.7874 0.4064)
			(end 0.7874 0.4064)
			(stroke
				(width 0.1524)
				(type default)
			)
			(layer "B.SilkS")
		)
		(fp_line
			(start 0.7874 -0.4064)
			(end -0.7874 -0.4064)
			(stroke
				(width 0.1524)
				(type default)
			)
			(layer "B.SilkS")
		)
		(fp_line
			(start 0.7874 0.4064)
			(end 0.7874 -0.4064)
			(stroke
				(width 0.1524)
				(type default)
			)
			(layer "B.SilkS")
		)
		(fp_line
			(start -0.67945 -0.3048)
			(end -0.67945 0.3048)
			(stroke
				(width 0.1)
				(type default)
			)
			(layer "B.Fab")
		)
		(fp_line
			(start -0.67945 0.3048)
			(end -0.120396 0.3048)
			(stroke
				(width 0.1)
				(type default)
			)
			(layer "B.Fab")
		)
		(fp_line
			(start -0.12065 -0.3048)
			(end -0.67945 -0.3048)
			(stroke
				(width 0.1)
				(type default)
			)
			(layer "B.Fab")
		)
		(fp_line
			(start -0.12065 -0.2794)
			(end -0.12065 -0.3048)
			(stroke
				(width 0.1)
				(type default)
			)
			(layer "B.Fab")
		)
		(fp_line
			(start -0.120396 0.2794)
			(end 0.12065 0.2794)
			(stroke
				(width 0.1)
				(type default)
			)
			(layer "B.Fab")
		)
		(fp_line
			(start -0.120396 0.3048)
			(end -0.120396 0.2794)
			(stroke
				(width 0.1)
				(type default)
			)
			(layer "B.Fab")
		)
		(fp_line
			(start 0.12065 -0.305054)
			(end 0.12065 -0.2794)
			(stroke
				(width 0.1)
				(type default)
			)
			(layer "B.Fab")
		)
		(fp_line
			(start 0.12065 -0.2794)
			(end -0.12065 -0.2794)
			(stroke
				(width 0.1)
				(type default)
			)
			(layer "B.Fab")
		)
		(fp_line
			(start 0.12065 0.2794)
			(end 0.12065 0.3048)
			(stroke
				(width 0.1)
				(type default)
			)
			(layer "B.Fab")
		)
		(fp_line
			(start 0.12065 0.3048)
			(end 0.67945 0.3048)
			(stroke
				(width 0.1)
				(type default)
			)
			(layer "B.Fab")
		)
		(fp_line
			(start 0.67945 -0.305054)
			(end 0.12065 -0.305054)
			(stroke
				(width 0.1)
				(type default)
			)
			(layer "B.Fab")
		)
		(fp_line
			(start 0.67945 0.3048)
			(end 0.67945 -0.305054)
			(stroke
				(width 0.1)
				(type default)
			)
			(layer "B.Fab")
		)
		(pad "1" smd circle
			(at 0.40005 0 180)
			(size 0 0)
			(layers "B.Cu" "B.Mask" "B.Paste")
			(net "PD_CK440_SBI_CLK")
		)
		(pad "2" smd circle
			(at -0.40005 0 180)
			(size 0 0)
			(layers "B.Cu" "B.Mask" "B.Paste")
			(net "GND")
		)
	)
	(footprint ""
		(layer "B.Cu")
		(at 488.03433 -153.128472 90)
		(property "Reference" "X6"
			(at 1.617218 2.436622 270)
			(unlocked yes)
			(layer "B.SilkS")
			(effects
				(font
					(size 0.7874 0.5842)
					(thickness 0.1524)
				)
				(justify left mirror)
			)
		)
		(property "Value" ""
			(at 0 0 90)
			(layer "B.Fab")
			(effects
				(font
					(size 1.27 1.27)
				)
				(justify mirror)
			)
		)
		(property "Device Type" "TP_TDR_4P_FTS_MPKT4_H025P0200_I"
			(at -1.30175 1.27 0)
			(unlocked yes)
			(layer "B.Fab")
			(hide yes)
			(effects
				(font
					(size 0.635 0.4064)
					(thickness 0.1524)
				)
				(justify mirror)
			)
		)
		(property "User Part Number" "TP15"
			(at -1.30175 1.27 0)
			(unlocked yes)
			(layer "Cmts.User")
			(hide yes)
			(effects
				(font
					(size 0.635 0.4064)
					(thickness 0.1524)
				)
				(justify mirror)
			)
		)
		(duplicate_pad_numbers_are_jumpers no)
		(fp_line
			(start 0 -1.27)
			(end 0 -0.635)
			(stroke
				(width 0.1524)
				(type default)
			)
			(layer "B.SilkS")
		)
		(fp_line
			(start -2.54 -1.27)
			(end 0 -1.27)
			(stroke
				(width 0.1524)
				(type default)
			)
			(layer "B.SilkS")
		)
		(fp_line
			(start -2.54 -1.1303)
			(end -2.54 -1.27)
			(stroke
				(width 0.1524)
				(type default)
			)
			(layer "B.SilkS")
		)
		(fp_line
			(start 0 0.635)
			(end 0 1.905)
			(stroke
				(width 0.1524)
				(type default)
			)
			(layer "B.SilkS")
		)
		(fp_line
			(start -2.54 1.4097)
			(end -2.54 1.1303)
			(stroke
				(width 0.1524)
				(type default)
			)
			(layer "B.SilkS")
		)
		(fp_line
			(start 0 3.175)
			(end 0 3.81)
			(stroke
				(width 0.1524)
				(type default)
			)
			(layer "B.SilkS")
		)
		(fp_line
			(start 0 3.81)
			(end -2.54 3.81)
			(stroke
				(width 0.1524)
				(type default)
			)
			(layer "B.SilkS")
		)
		(fp_line
			(start -2.54 3.81)
			(end -2.54 3.6703)
			(stroke
				(width 0.1524)
				(type default)
			)
			(layer "B.SilkS")
		)
		(fp_poly
			(pts
				(xy 2.790952 -0.930402) (xy 2.790952 0.593598) (xy 1.266952 -0.168402)
			)
			(stroke
				(width 0)
				(type default)
			)
			(fill yes)
			(layer "B.SilkS")
		)
		(fp_line
			(start 0 -1.27)
			(end 0 3.81)
			(stroke
				(width 0.1)
				(type default)
			)
			(layer "B.Fab")
		)
		(fp_line
			(start -2.54 -1.27)
			(end 0 -1.27)
			(stroke
				(width 0.1)
				(type default)
			)
			(layer "B.Fab")
		)
		(fp_line
			(start 0 3.81)
			(end -2.54 3.81)
			(stroke
				(width 0.1)
				(type default)
			)
			(layer "B.Fab")
		)
		(fp_line
			(start -2.54 3.81)
			(end -2.54 -1.27)
			(stroke
				(width 0.1)
				(type default)
			)
			(layer "B.Fab")
		)
		(fp_poly
			(pts
				(xy 0.761746 0) (xy 2.285746 -0.762) (xy 2.285746 0.762)
			)
			(stroke
				(width 0)
				(type default)
			)
			(fill yes)
			(layer "B.Fab")
		)
		(pad "1" thru_hole circle
			(at 0 0 270)
			(size 1.0033 1.0033)
			(drill 0.249936)
			(layers "*.Cu" "*.Mask")
			(remove_unused_layers no)
			(net "TDR_DIFF_85_BOT_DP")
			(clearance 0.10795)
			(padstack
				(mode front_inner_back)
				(layer "Inner"
					(shape circle)
					(size 0.8001 0.8001)
					(clearance 0.1524)
				)
				(layer "B.Cu"
					(shape circle)
					(size 1.0033 1.0033)
					(thermal_gap 0.10795)
					(clearance 0.10795)
				)
			)
		)
		(pad "2" thru_hole circle
			(at -2.54 0 270)
			(size 1.9939 1.9939)
			(drill 0.249936)
			(layers "*.Cu" "*.Mask")
			(remove_unused_layers no)
			(net "T1_GND")
			(clearance 0.10795)
			(padstack
				(mode front_inner_back)
				(layer "Inner"
					(shape circle)
					(size 0.8001 0.8001)
					(clearance 0.1524)
				)
				(layer "B.Cu"
					(shape circle)
					(size 1.9939 1.9939)
					(thermal_gap 0.10795)
					(clearance 0.10795)
				)
			)
		)
		(pad "3" thru_hole circle
			(at -2.54 2.54 270)
			(size 1.9939 1.9939)
			(drill 0.249936)
			(layers "*.Cu" "*.Mask")
			(remove_unused_layers no)
			(net "T1_GND")
			(clearance 0.10795)
			(padstack
				(mode front_inner_back)
				(layer "Inner"
					(shape circle)
					(size 0.8001 0.8001)
					(clearance 0.1524)
				)
				(layer "B.Cu"
					(shape circle)
					(size 1.9939 1.9939)
					(thermal_gap 0.10795)
					(clearance 0.10795)
				)
			)
		)
		(pad "4" thru_hole circle
			(at 0 2.54 270)
			(size 1.0033 1.0033)
			(drill 0.249936)
			(layers "*.Cu" "*.Mask")
			(remove_unused_layers no)
			(net "TDR_DIFF_85_BOT_DN")
			(clearance 0.10795)
			(padstack
				(mode front_inner_back)
				(layer "Inner"
					(shape circle)
					(size 0.8001 0.8001)
					(clearance 0.1524)
				)
				(layer "B.Cu"
					(shape circle)
					(size 1.0033 1.0033)
					(thermal_gap 0.10795)
					(clearance 0.10795)
				)
			)
		)
	)
	(footprint ""
		(layer "B.Cu")
		(at 414.309814 -321.549776 -90)
		(property "Reference" "C28"
			(at 0 0 90)
			(layer "B.SilkS")
			(hide yes)
			(effects
				(font
					(size 1.27 1.27)
				)
				(justify mirror)
			)
		)
		(property "Value" ""
			(at 0 0 90)
			(layer "B.Fab")
			(effects
				(font
					(size 1.27 1.27)
				)
				(justify mirror)
			)
		)
		(duplicate_pad_numbers_are_jumpers no)
		(fp_line
			(start -1.524 0.762)
			(end 1.524 0.762)
			(stroke
				(width 0.1524)
				(type default)
			)
			(layer "B.SilkS")
		)
		(fp_line
			(start 1.524 0.762)
			(end 1.524 -0.762)
			(stroke
				(width 0.1524)
				(type default)
			)
			(layer "B.SilkS")
		)
		(fp_line
			(start -1.524 -0.762)
			(end -1.524 0.762)
			(stroke
				(width 0.1524)
				(type default)
			)
			(layer "B.SilkS")
		)
		(fp_line
			(start 1.524 -0.762)
			(end -1.524 -0.762)
			(stroke
				(width 0.1524)
				(type default)
			)
			(layer "B.SilkS")
		)
		(fp_line
			(start -1.1049 0.724916)
			(end -1.1049 -0.724916)
			(stroke
				(width 0.1)
				(type default)
			)
			(layer "B.Fab")
		)
		(fp_line
			(start 1.1049 0.724916)
			(end -1.1049 0.724916)
			(stroke
				(width 0.1)
				(type default)
			)
			(layer "B.Fab")
		)
		(fp_line
			(start -1.1049 -0.724916)
			(end 1.1049 -0.724916)
			(stroke
				(width 0.1)
				(type default)
			)
			(layer "B.Fab")
		)
		(fp_line
			(start 1.1049 -0.724916)
			(end 1.1049 0.724916)
			(stroke
				(width 0.1)
				(type default)
			)
			(layer "B.Fab")
		)
		(pad "1" smd rect
			(at 0.889 0 270)
			(size 1.016 1.27)
			(layers "B.Cu" "B.Mask" "B.Paste")
			(net "P12V_S3_AUX_CPU0_NVDIMM")
		)
		(pad "2" smd rect
			(at -0.889 0 270)
			(size 1.016 1.27)
			(layers "B.Cu" "B.Mask" "B.Paste")
			(net "GND")
		)
	)
	(footprint ""
		(layer "B.Cu")
		(at 75.06208 -4.251198 -90)
		(property "Reference" "R3166"
			(at 0 0 90)
			(layer "B.SilkS")
			(hide yes)
			(effects
				(font
					(size 1.27 1.27)
				)
				(justify mirror)
			)
		)
		(property "Value" ""
			(at 0 0 90)
			(layer "B.Fab")
			(effects
				(font
					(size 1.27 1.27)
				)
				(justify mirror)
			)
		)
		(duplicate_pad_numbers_are_jumpers no)
		(fp_line
			(start -0.7874 0.4064)
			(end 0.7874 0.4064)
			(stroke
				(width 0.1524)
				(type default)
			)
			(layer "B.SilkS")
		)
		(fp_line
			(start 0.7874 0.4064)
			(end 0.7874 -0.4064)
			(stroke
				(width 0.1524)
				(type default)
			)
			(layer "B.SilkS")
		)
		(fp_line
			(start -0.7874 -0.4064)
			(end -0.7874 0.4064)
			(stroke
				(width 0.1524)
				(type default)
			)
			(layer "B.SilkS")
		)
		(fp_line
			(start 0.7874 -0.4064)
			(end -0.7874 -0.4064)
			(stroke
				(width 0.1524)
				(type default)
			)
			(layer "B.SilkS")
		)
		(fp_line
			(start -0.67945 0.3048)
			(end -0.120396 0.3048)
			(stroke
				(width 0.1)
				(type default)
			)
			(layer "B.Fab")
		)
		(fp_line
			(start -0.120396 0.3048)
			(end -0.120396 0.2794)
			(stroke
				(width 0.1)
				(type default)
			)
			(layer "B.Fab")
		)
		(fp_line
			(start 0.12065 0.3048)
			(end 0.67945 0.3048)
			(stroke
				(width 0.1)
				(type default)
			)
			(layer "B.Fab")
		)
		(fp_line
			(start 0.67945 0.3048)
			(end 0.67945 -0.305054)
			(stroke
				(width 0.1)
				(type default)
			)
			(layer "B.Fab")
		)
		(fp_line
			(start -0.120396 0.2794)
			(end 0.12065 0.2794)
			(stroke
				(width 0.1)
				(type default)
			)
			(layer "B.Fab")
		)
		(fp_line
			(start 0.12065 0.2794)
			(end 0.12065 0.3048)
			(stroke
				(width 0.1)
				(type default)
			)
			(layer "B.Fab")
		)
		(fp_line
			(start -0.12065 -0.2794)
			(end -0.12065 -0.3048)
			(stroke
				(width 0.1)
				(type default)
			)
			(layer "B.Fab")
		)
		(fp_line
			(start 0.12065 -0.2794)
			(end -0.12065 -0.2794)
			(stroke
				(width 0.1)
				(type default)
			)
			(layer "B.Fab")
		)
		(fp_line
			(start -0.67945 -0.3048)
			(end -0.67945 0.3048)
			(stroke
				(width 0.1)
				(type default)
			)
			(layer "B.Fab")
		)
		(fp_line
			(start -0.12065 -0.3048)
			(end -0.67945 -0.3048)
			(stroke
				(width 0.1)
				(type default)
			)
			(layer "B.Fab")
		)
		(fp_line
			(start 0.12065 -0.305054)
			(end 0.12065 -0.2794)
			(stroke
				(width 0.1)
				(type default)
			)
			(layer "B.Fab")
		)
		(fp_line
			(start 0.67945 -0.305054)
			(end 0.12065 -0.305054)
			(stroke
				(width 0.1)
				(type default)
			)
			(layer "B.Fab")
		)
		(pad "1" smd circle
			(at 0.40005 0 90)
			(size 0 0)
			(layers "B.Cu" "B.Mask" "B.Paste")
			(net "P3V3_OCP_V3_2")
		)
		(pad "2" smd circle
			(at -0.40005 0 90)
			(size 0 0)
			(layers "B.Cu" "B.Mask" "B.Paste")
			(net "OCP_V3_2_ID1")
		)
	)
	(footprint ""
		(layer "B.Cu")
		(at 36.488624 -405.93137 180)
		(property "Reference" "R5234"
			(at 0 0 0)
			(layer "B.SilkS")
			(hide yes)
			(effects
				(font
					(size 1.27 1.27)
				)
				(justify mirror)
			)
		)
		(property "Value" ""
			(at 0 0 0)
			(layer "B.Fab")
			(effects
				(font
					(size 1.27 1.27)
				)
				(justify mirror)
			)
		)
		(duplicate_pad_numbers_are_jumpers no)
		(fp_line
			(start 0.7874 -0.076962)
			(end 0.7874 -0.4064)
			(stroke
				(width 0.1524)
				(type default)
			)
			(layer "B.SilkS")
		)
		(fp_line
			(start 0.7874 -0.4064)
			(end -0.7874 -0.4064)
			(stroke
				(width 0.1524)
				(type default)
			)
			(layer "B.SilkS")
		)
		(fp_line
			(start -0.407416 0.4064)
			(end 0.529844 0.4064)
			(stroke
				(width 0.1524)
				(type default)
			)
			(layer "B.SilkS")
		)
		(fp_line
			(start -0.7874 -0.4064)
			(end -0.7874 0.027178)
			(stroke
				(width 0.1524)
				(type default)
			)
			(layer "B.SilkS")
		)
		(fp_line
			(start 0.67945 0.3048)
			(end 0.67945 -0.305054)
			(stroke
				(width 0.1)
				(type default)
			)
			(layer "B.Fab")
		)
		(fp_line
			(start 0.67945 -0.305054)
			(end 0.12065 -0.305054)
			(stroke
				(width 0.1)
				(type default)
			)
			(layer "B.Fab")
		)
		(fp_line
			(start 0.12065 0.3048)
			(end 0.67945 0.3048)
			(stroke
				(width 0.1)
				(type default)
			)
			(layer "B.Fab")
		)
		(fp_line
			(start 0.12065 0.2794)
			(end 0.12065 0.3048)
			(stroke
				(width 0.1)
				(type default)
			)
			(layer "B.Fab")
		)
		(fp_line
			(start 0.12065 -0.2794)
			(end -0.12065 -0.2794)
			(stroke
				(width 0.1)
				(type default)
			)
			(layer "B.Fab")
		)
		(fp_line
			(start 0.12065 -0.305054)
			(end 0.12065 -0.2794)
			(stroke
				(width 0.1)
				(type default)
			)
			(layer "B.Fab")
		)
		(fp_line
			(start -0.120396 0.3048)
			(end -0.120396 0.2794)
			(stroke
				(width 0.1)
				(type default)
			)
			(layer "B.Fab")
		)
		(fp_line
			(start -0.120396 0.2794)
			(end 0.12065 0.2794)
			(stroke
				(width 0.1)
				(type default)
			)
			(layer "B.Fab")
		)
		(fp_line
			(start -0.12065 -0.2794)
			(end -0.12065 -0.3048)
			(stroke
				(width 0.1)
				(type default)
			)
			(layer "B.Fab")
		)
		(fp_line
			(start -0.12065 -0.3048)
			(end -0.67945 -0.3048)
			(stroke
				(width 0.1)
				(type default)
			)
			(layer "B.Fab")
		)
		(fp_line
			(start -0.67945 0.3048)
			(end -0.120396 0.3048)
			(stroke
				(width 0.1)
				(type default)
			)
			(layer "B.Fab")
		)
		(fp_line
			(start -0.67945 -0.3048)
			(end -0.67945 0.3048)
			(stroke
				(width 0.1)
				(type default)
			)
			(layer "B.Fab")
		)
		(pad "1" smd circle
			(at 0.40005 0)
			(size 0 0)
			(layers "B.Cu" "B.Mask" "B.Paste")
			(net "USB2_HUB_BUF_SWB_R_DP")
		)
		(pad "2" smd circle
			(at -0.40005 0)
			(size 0 0)
			(layers "B.Cu" "B.Mask" "B.Paste")
			(net "USB2_HUB_BUF_SWB_DP")
		)
	)
	(footprint ""
		(layer "B.Cu")
		(at 180.155596 -112.97539 180)
		(property "Reference" "C1912"
			(at 0 0 0)
			(layer "B.SilkS")
			(hide yes)
			(effects
				(font
					(size 1.27 1.27)
				)
				(justify mirror)
			)
		)
		(property "Value" ""
			(at 0 0 0)
			(layer "B.Fab")
			(effects
				(font
					(size 1.27 1.27)
				)
				(justify mirror)
			)
		)
		(duplicate_pad_numbers_are_jumpers no)
		(fp_line
			(start 0.69215 0.2921)
			(end 0.69215 -0.2921)
			(stroke
				(width 0.1524)
				(type default)
			)
			(layer "B.SilkS")
		)
		(fp_line
			(start 0.69215 -0.2921)
			(end -0.69215 -0.2921)
			(stroke
				(width 0.1524)
				(type default)
			)
			(layer "B.SilkS")
		)
		(fp_line
			(start -0.69215 0.2921)
			(end 0.69215 0.2921)
			(stroke
				(width 0.1524)
				(type default)
			)
			(layer "B.SilkS")
		)
		(fp_line
			(start -0.69215 -0.2921)
			(end -0.69215 0.2921)
			(stroke
				(width 0.1524)
				(type default)
			)
			(layer "B.SilkS")
		)
		(fp_line
			(start 0.51435 0.2794)
			(end 0.51435 -0.2794)
			(stroke
				(width 0.1)
				(type default)
			)
			(layer "B.Fab")
		)
		(fp_line
			(start 0.51435 -0.2794)
			(end -0.51435 -0.2794)
			(stroke
				(width 0.1)
				(type default)
			)
			(layer "B.Fab")
		)
		(fp_line
			(start -0.51435 0.2794)
			(end 0.51435 0.2794)
			(stroke
				(width 0.1)
				(type default)
			)
			(layer "B.Fab")
		)
		(fp_line
			(start -0.51435 -0.2794)
			(end -0.51435 0.2794)
			(stroke
				(width 0.1)
				(type default)
			)
			(layer "B.Fab")
		)
		(pad "1" smd circle
			(at 0.40005 0)
			(size 0 0)
			(layers "B.Cu" "B.Mask" "B.Paste")
			(net "VCC_PLD_CORE")
		)
		(pad "2" smd circle
			(at -0.40005 0)
			(size 0 0)
			(layers "B.Cu" "B.Mask" "B.Paste")
			(net "GND")
		)
		(zone
			(layer "B.Cu")
			(hatch none 0.5)
			(connect_pads
				(clearance 0)
			)
			(min_thickness 0.25)
			(keepout
				(tracks not_allowed)
				(vias allowed)
				(pads allowed)
				(copperpour not_allowed)
				(footprints allowed)
			)
			(placement
				(enabled no)
				(sheetname "")
			)
			(fill
				(thermal_gap 0.5)
				(thermal_bridge_width 0.5)
				(island_removal_mode 0)
			)
			(polygon
				(pts
					(xy 179.965096 -113.06302) (xy 180.056536 -113.121186) (xy 180.255926 -113.121186) (xy 180.346096 -113.06302)
					(xy 180.346096 -112.88776) (xy 180.255926 -112.82934) (xy 180.056536 -112.82934) (xy 179.965096 -112.887506)
				)
			)
		)
	)
	(footprint ""
		(layer "B.Cu")
		(at 418.540692 -174.686468 180)
		(property "Reference" "PR1776"
			(at 0 0 0)
			(layer "B.SilkS")
			(hide yes)
			(effects
				(font
					(size 1.27 1.27)
				)
				(justify mirror)
			)
		)
		(property "Value" ""
			(at 0 0 0)
			(layer "B.Fab")
			(effects
				(font
					(size 1.27 1.27)
				)
				(justify mirror)
			)
		)
		(duplicate_pad_numbers_are_jumpers no)
		(fp_line
			(start 0.7874 0.4064)
			(end 0.7874 -0.4064)
			(stroke
				(width 0.1524)
				(type default)
			)
			(layer "B.SilkS")
		)
		(fp_line
			(start 0.7874 -0.4064)
			(end -0.7874 -0.4064)
			(stroke
				(width 0.1524)
				(type default)
			)
			(layer "B.SilkS")
		)
		(fp_line
			(start -0.7874 0.4064)
			(end 0.7874 0.4064)
			(stroke
				(width 0.1524)
				(type default)
			)
			(layer "B.SilkS")
		)
		(fp_line
			(start -0.7874 -0.4064)
			(end -0.7874 0.4064)
			(stroke
				(width 0.1524)
				(type default)
			)
			(layer "B.SilkS")
		)
		(fp_line
			(start 0.67945 0.3048)
			(end 0.67945 -0.305054)
			(stroke
				(width 0.1)
				(type default)
			)
			(layer "B.Fab")
		)
		(fp_line
			(start 0.67945 -0.305054)
			(end 0.12065 -0.305054)
			(stroke
				(width 0.1)
				(type default)
			)
			(layer "B.Fab")
		)
		(fp_line
			(start 0.12065 0.3048)
			(end 0.67945 0.3048)
			(stroke
				(width 0.1)
				(type default)
			)
			(layer "B.Fab")
		)
		(fp_line
			(start 0.12065 0.2794)
			(end 0.12065 0.3048)
			(stroke
				(width 0.1)
				(type default)
			)
			(layer "B.Fab")
		)
		(fp_line
			(start 0.12065 -0.2794)
			(end -0.12065 -0.2794)
			(stroke
				(width 0.1)
				(type default)
			)
			(layer "B.Fab")
		)
		(fp_line
			(start 0.12065 -0.305054)
			(end 0.12065 -0.2794)
			(stroke
				(width 0.1)
				(type default)
			)
			(layer "B.Fab")
		)
		(fp_line
			(start -0.120396 0.3048)
			(end -0.120396 0.2794)
			(stroke
				(width 0.1)
				(type default)
			)
			(layer "B.Fab")
		)
		(fp_line
			(start -0.120396 0.2794)
			(end 0.12065 0.2794)
			(stroke
				(width 0.1)
				(type default)
			)
			(layer "B.Fab")
		)
		(fp_line
			(start -0.12065 -0.2794)
			(end -0.12065 -0.3048)
			(stroke
				(width 0.1)
				(type default)
			)
			(layer "B.Fab")
		)
		(fp_line
			(start -0.12065 -0.3048)
			(end -0.67945 -0.3048)
			(stroke
				(width 0.1)
				(type default)
			)
			(layer "B.Fab")
		)
		(fp_line
			(start -0.67945 0.3048)
			(end -0.120396 0.3048)
			(stroke
				(width 0.1)
				(type default)
			)
			(layer "B.Fab")
		)
		(fp_line
			(start -0.67945 -0.3048)
			(end -0.67945 0.3048)
			(stroke
				(width 0.1)
				(type default)
			)
			(layer "B.Fab")
		)
		(pad "1" smd circle
			(at 0.40005 0)
			(size 0 0)
			(layers "B.Cu" "B.Mask" "B.Paste")
			(net "PVCCINFAON_CPU0_VOS1")
		)
		(pad "2" smd circle
			(at -0.40005 0)
			(size 0 0)
			(layers "B.Cu" "B.Mask" "B.Paste")
			(net "PVCCINFAON_CPU0")
		)
	)
	(footprint ""
		(layer "B.Cu")
		(at 372.299738 -359.50271 -90)
		(property "Reference" "PR3335"
			(at 0 0 90)
			(layer "B.SilkS")
			(hide yes)
			(effects
				(font
					(size 1.27 1.27)
				)
				(justify mirror)
			)
		)
		(property "Value" ""
			(at 0 0 90)
			(layer "B.Fab")
			(effects
				(font
					(size 1.27 1.27)
				)
				(justify mirror)
			)
		)
		(duplicate_pad_numbers_are_jumpers no)
		(fp_line
			(start -0.7874 0.4064)
			(end 0.7874 0.4064)
			(stroke
				(width 0.1524)
				(type default)
			)
			(layer "B.SilkS")
		)
		(fp_line
			(start 0.7874 0.4064)
			(end 0.7874 -0.4064)
			(stroke
				(width 0.1524)
				(type default)
			)
			(layer "B.SilkS")
		)
		(fp_line
			(start -0.7874 -0.4064)
			(end -0.7874 0.4064)
			(stroke
				(width 0.1524)
				(type default)
			)
			(layer "B.SilkS")
		)
		(fp_line
			(start 0.7874 -0.4064)
			(end -0.7874 -0.4064)
			(stroke
				(width 0.1524)
				(type default)
			)
			(layer "B.SilkS")
		)
		(fp_line
			(start -0.67945 0.3048)
			(end -0.120396 0.3048)
			(stroke
				(width 0.1)
				(type default)
			)
			(layer "B.Fab")
		)
		(fp_line
			(start -0.120396 0.3048)
			(end -0.120396 0.2794)
			(stroke
				(width 0.1)
				(type default)
			)
			(layer "B.Fab")
		)
		(fp_line
			(start 0.12065 0.3048)
			(end 0.67945 0.3048)
			(stroke
				(width 0.1)
				(type default)
			)
			(layer "B.Fab")
		)
		(fp_line
			(start 0.67945 0.3048)
			(end 0.67945 -0.305054)
			(stroke
				(width 0.1)
				(type default)
			)
			(layer "B.Fab")
		)
		(fp_line
			(start -0.120396 0.2794)
			(end 0.12065 0.2794)
			(stroke
				(width 0.1)
				(type default)
			)
			(layer "B.Fab")
		)
		(fp_line
			(start 0.12065 0.2794)
			(end 0.12065 0.3048)
			(stroke
				(width 0.1)
				(type default)
			)
			(layer "B.Fab")
		)
		(fp_line
			(start -0.12065 -0.2794)
			(end -0.12065 -0.3048)
			(stroke
				(width 0.1)
				(type default)
			)
			(layer "B.Fab")
		)
		(fp_line
			(start 0.12065 -0.2794)
			(end -0.12065 -0.2794)
			(stroke
				(width 0.1)
				(type default)
			)
			(layer "B.Fab")
		)
		(fp_line
			(start -0.67945 -0.3048)
			(end -0.67945 0.3048)
			(stroke
				(width 0.1)
				(type default)
			)
			(layer "B.Fab")
		)
		(fp_line
			(start -0.12065 -0.3048)
			(end -0.67945 -0.3048)
			(stroke
				(width 0.1)
				(type default)
			)
			(layer "B.Fab")
		)
		(fp_line
			(start 0.12065 -0.305054)
			(end 0.12065 -0.2794)
			(stroke
				(width 0.1)
				(type default)
			)
			(layer "B.Fab")
		)
		(fp_line
			(start 0.67945 -0.305054)
			(end 0.12065 -0.305054)
			(stroke
				(width 0.1)
				(type default)
			)
			(layer "B.Fab")
		)
		(pad "1" smd circle
			(at 0.40005 0 90)
			(size 0 0)
			(layers "B.Cu" "B.Mask" "B.Paste")
			(net "PVPP_HBM_CPU0_MODE")
		)
		(pad "2" smd circle
			(at -0.40005 0 90)
			(size 0 0)
			(layers "B.Cu" "B.Mask" "B.Paste")
			(net "GND")
		)
	)
	(footprint ""
		(layer "B.Cu")
		(at 103.901494 -252.17628 -90)
		(property "Reference" "C327"
			(at 0 0 90)
			(layer "B.SilkS")
			(hide yes)
			(effects
				(font
					(size 1.27 1.27)
				)
				(justify mirror)
			)
		)
		(property "Value" ""
			(at 0 0 90)
			(layer "B.Fab")
			(effects
				(font
					(size 1.27 1.27)
				)
				(justify mirror)
			)
		)
		(duplicate_pad_numbers_are_jumpers no)
		(fp_line
			(start -1.524 0.762)
			(end 1.524 0.762)
			(stroke
				(width 0.1524)
				(type default)
			)
			(layer "B.SilkS")
		)
		(fp_line
			(start 1.524 0.762)
			(end 1.524 -0.762)
			(stroke
				(width 0.1524)
				(type default)
			)
			(layer "B.SilkS")
		)
		(fp_line
			(start -1.524 -0.762)
			(end -1.524 0.762)
			(stroke
				(width 0.1524)
				(type default)
			)
			(layer "B.SilkS")
		)
		(fp_line
			(start 1.524 -0.762)
			(end -1.524 -0.762)
			(stroke
				(width 0.1524)
				(type default)
			)
			(layer "B.SilkS")
		)
		(fp_line
			(start -1.1049 0.724916)
			(end -1.1049 -0.724916)
			(stroke
				(width 0.1)
				(type default)
			)
			(layer "B.Fab")
		)
		(fp_line
			(start 1.1049 0.724916)
			(end -1.1049 0.724916)
			(stroke
				(width 0.1)
				(type default)
			)
			(layer "B.Fab")
		)
		(fp_line
			(start -1.1049 -0.724916)
			(end 1.1049 -0.724916)
			(stroke
				(width 0.1)
				(type default)
			)
			(layer "B.Fab")
		)
		(fp_line
			(start 1.1049 -0.724916)
			(end 1.1049 0.724916)
			(stroke
				(width 0.1)
				(type default)
			)
			(layer "B.Fab")
		)
		(pad "1" smd rect
			(at 0.889 0 270)
			(size 1.016 1.27)
			(layers "B.Cu" "B.Mask" "B.Paste")
			(net "PVCCIN_CPU1")
		)
		(pad "2" smd rect
			(at -0.889 0 270)
			(size 1.016 1.27)
			(layers "B.Cu" "B.Mask" "B.Paste")
			(net "GND")
		)
	)
	(footprint ""
		(layer "B.Cu")
		(at 53.14188 -171.541948 -90)
		(property "Reference" "PR699"
			(at 0 0 90)
			(layer "B.SilkS")
			(hide yes)
			(effects
				(font
					(size 1.27 1.27)
				)
				(justify mirror)
			)
		)
		(property "Value" ""
			(at 0 0 90)
			(layer "B.Fab")
			(effects
				(font
					(size 1.27 1.27)
				)
				(justify mirror)
			)
		)
		(duplicate_pad_numbers_are_jumpers no)
		(fp_line
			(start -0.7874 0.4064)
			(end 0.7874 0.4064)
			(stroke
				(width 0.1524)
				(type default)
			)
			(layer "B.SilkS")
		)
		(fp_line
			(start 0.7874 0.4064)
			(end 0.7874 -0.4064)
			(stroke
				(width 0.1524)
				(type default)
			)
			(layer "B.SilkS")
		)
		(fp_line
			(start -0.7874 -0.4064)
			(end -0.7874 0.4064)
			(stroke
				(width 0.1524)
				(type default)
			)
			(layer "B.SilkS")
		)
		(fp_line
			(start 0.7874 -0.4064)
			(end -0.7874 -0.4064)
			(stroke
				(width 0.1524)
				(type default)
			)
			(layer "B.SilkS")
		)
		(fp_line
			(start -0.67945 0.3048)
			(end -0.120396 0.3048)
			(stroke
				(width 0.1)
				(type default)
			)
			(layer "B.Fab")
		)
		(fp_line
			(start -0.120396 0.3048)
			(end -0.120396 0.2794)
			(stroke
				(width 0.1)
				(type default)
			)
			(layer "B.Fab")
		)
		(fp_line
			(start 0.12065 0.3048)
			(end 0.67945 0.3048)
			(stroke
				(width 0.1)
				(type default)
			)
			(layer "B.Fab")
		)
		(fp_line
			(start 0.67945 0.3048)
			(end 0.67945 -0.305054)
			(stroke
				(width 0.1)
				(type default)
			)
			(layer "B.Fab")
		)
		(fp_line
			(start -0.120396 0.2794)
			(end 0.12065 0.2794)
			(stroke
				(width 0.1)
				(type default)
			)
			(layer "B.Fab")
		)
		(fp_line
			(start 0.12065 0.2794)
			(end 0.12065 0.3048)
			(stroke
				(width 0.1)
				(type default)
			)
			(layer "B.Fab")
		)
		(fp_line
			(start -0.12065 -0.2794)
			(end -0.12065 -0.3048)
			(stroke
				(width 0.1)
				(type default)
			)
			(layer "B.Fab")
		)
		(fp_line
			(start 0.12065 -0.2794)
			(end -0.12065 -0.2794)
			(stroke
				(width 0.1)
				(type default)
			)
			(layer "B.Fab")
		)
		(fp_line
			(start -0.67945 -0.3048)
			(end -0.67945 0.3048)
			(stroke
				(width 0.1)
				(type default)
			)
			(layer "B.Fab")
		)
		(fp_line
			(start -0.12065 -0.3048)
			(end -0.67945 -0.3048)
			(stroke
				(width 0.1)
				(type default)
			)
			(layer "B.Fab")
		)
		(fp_line
			(start 0.12065 -0.305054)
			(end 0.12065 -0.2794)
			(stroke
				(width 0.1)
				(type default)
			)
			(layer "B.Fab")
		)
		(fp_line
			(start 0.67945 -0.305054)
			(end 0.12065 -0.305054)
			(stroke
				(width 0.1)
				(type default)
			)
			(layer "B.Fab")
		)
		(pad "1" smd circle
			(at 0.40005 0 90)
			(size 0 0)
			(layers "B.Cu" "B.Mask" "B.Paste")
			(net "P3V3")
		)
		(pad "2" smd circle
			(at -0.40005 0 90)
			(size 0 0)
			(layers "B.Cu" "B.Mask" "B.Paste")
			(net "PVCCFA_EHV_CPU1_PVCC")
		)
	)
	(footprint ""
		(layer "B.Cu")
		(at 169.389806 -9.458198 -90)
		(property "Reference" "C2077"
			(at 0 0 90)
			(layer "B.SilkS")
			(hide yes)
			(effects
				(font
					(size 1.27 1.27)
				)
				(justify mirror)
			)
		)
		(property "Value" ""
			(at 0 0 90)
			(layer "B.Fab")
			(effects
				(font
					(size 1.27 1.27)
				)
				(justify mirror)
			)
		)
		(duplicate_pad_numbers_are_jumpers no)
		(fp_line
			(start -0.299974 0.150114)
			(end 0.299974 0.150114)
			(stroke
				(width 0.1)
				(type default)
			)
			(layer "B.Fab")
		)
		(fp_line
			(start 0.299974 0.150114)
			(end 0.299974 -0.150114)
			(stroke
				(width 0.1)
				(type default)
			)
			(layer "B.Fab")
		)
		(fp_line
			(start -0.299974 -0.150114)
			(end -0.299974 0.150114)
			(stroke
				(width 0.1)
				(type default)
			)
			(layer "B.Fab")
		)
		(fp_line
			(start 0.299974 -0.150114)
			(end -0.299974 -0.150114)
			(stroke
				(width 0.1)
				(type default)
			)
			(layer "B.Fab")
		)
		(pad "1" smd rect
			(at 0.2667 0 90)
			(size 0.3048 0.381)
			(layers "B.Cu" "B.Mask" "B.Paste")
			(net "P3E_PCH_BMC_TX_DP")
		)
		(pad "2" smd rect
			(at -0.2667 0 90)
			(size 0.3048 0.381)
			(layers "B.Cu" "B.Mask" "B.Paste")
			(net "P3E_PCH_BMC_TX_C_DP")
		)
		(zone
			(layer "In16.Cu")
			(hatch none 0.5)
			(connect_pads
				(clearance 0)
			)
			(min_thickness 0.25)
			(keepout
				(tracks not_allowed)
				(vias allowed)
				(pads allowed)
				(copperpour not_allowed)
				(footprints allowed)
			)
			(placement
				(enabled no)
				(sheetname "")
			)
			(fill
				(thermal_gap 0.5)
				(thermal_bridge_width 0.5)
				(island_removal_mode 0)
			)
			(polygon
				(pts
					(xy 169.148506 -9.521698) (xy 169.631106 -9.521698) (xy 169.631106 -9.928098) (xy 169.148506 -9.928098)
				)
			)
		)
		(zone
			(layer "In16.Cu")
			(hatch none 0.5)
			(connect_pads
				(clearance 0)
			)
			(min_thickness 0.25)
			(keepout
				(tracks not_allowed)
				(vias allowed)
				(pads allowed)
				(copperpour not_allowed)
				(footprints allowed)
			)
			(placement
				(enabled no)
				(sheetname "")
			)
			(fill
				(thermal_gap 0.5)
				(thermal_bridge_width 0.5)
				(island_removal_mode 0)
			)
			(polygon
				(pts
					(xy 169.148506 -8.988298) (xy 169.631106 -8.988298) (xy 169.631106 -9.394698) (xy 169.148506 -9.394698)
				)
			)
		)
	)
	(footprint ""
		(layer "B.Cu")
		(at 339.44306 -66.425064 90)
		(property "Reference" "C168"
			(at 0 0 90)
			(layer "B.SilkS")
			(hide yes)
			(effects
				(font
					(size 1.27 1.27)
				)
				(justify mirror)
			)
		)
		(property "Value" ""
			(at 0 0 90)
			(layer "B.Fab")
			(effects
				(font
					(size 1.27 1.27)
				)
				(justify mirror)
			)
		)
		(duplicate_pad_numbers_are_jumpers no)
		(fp_line
			(start 0.299974 -0.150114)
			(end -0.299974 -0.150114)
			(stroke
				(width 0.1)
				(type default)
			)
			(layer "B.Fab")
		)
		(fp_line
			(start -0.299974 -0.150114)
			(end -0.299974 0.150114)
			(stroke
				(width 0.1)
				(type default)
			)
			(layer "B.Fab")
		)
		(fp_line
			(start 0.299974 0.150114)
			(end 0.299974 -0.150114)
			(stroke
				(width 0.1)
				(type default)
			)
			(layer "B.Fab")
		)
		(fp_line
			(start -0.299974 0.150114)
			(end 0.299974 0.150114)
			(stroke
				(width 0.1)
				(type default)
			)
			(layer "B.Fab")
		)
		(pad "1" smd rect
			(at 0.2667 0 270)
			(size 0.3048 0.381)
			(layers "B.Cu" "B.Mask" "B.Paste")
			(net "DMI_CPU0_PCH_RX_C_DP<1>")
		)
		(pad "2" smd rect
			(at -0.2667 0 270)
			(size 0.3048 0.381)
			(layers "B.Cu" "B.Mask" "B.Paste")
			(net "DMI_CPU0_PCH_RX_DP<1>")
		)
	)
	(footprint ""
		(layer "B.Cu")
		(at 185.240422 -13.60043 -90)
		(property "Reference" "R598"
			(at 0 0 90)
			(layer "B.SilkS")
			(hide yes)
			(effects
				(font
					(size 1.27 1.27)
				)
				(justify mirror)
			)
		)
		(property "Value" ""
			(at 0 0 90)
			(layer "B.Fab")
			(effects
				(font
					(size 1.27 1.27)
				)
				(justify mirror)
			)
		)
		(duplicate_pad_numbers_are_jumpers no)
		(fp_line
			(start -0.7874 0.4064)
			(end 0.7874 0.4064)
			(stroke
				(width 0.1524)
				(type default)
			)
			(layer "B.SilkS")
		)
		(fp_line
			(start 0.7874 0.4064)
			(end 0.7874 -0.4064)
			(stroke
				(width 0.1524)
				(type default)
			)
			(layer "B.SilkS")
		)
		(fp_line
			(start -0.7874 -0.4064)
			(end -0.7874 0.4064)
			(stroke
				(width 0.1524)
				(type default)
			)
			(layer "B.SilkS")
		)
		(fp_line
			(start 0.7874 -0.4064)
			(end -0.7874 -0.4064)
			(stroke
				(width 0.1524)
				(type default)
			)
			(layer "B.SilkS")
		)
		(fp_line
			(start -0.67945 0.3048)
			(end -0.120396 0.3048)
			(stroke
				(width 0.1)
				(type default)
			)
			(layer "B.Fab")
		)
		(fp_line
			(start -0.120396 0.3048)
			(end -0.120396 0.2794)
			(stroke
				(width 0.1)
				(type default)
			)
			(layer "B.Fab")
		)
		(fp_line
			(start 0.12065 0.3048)
			(end 0.67945 0.3048)
			(stroke
				(width 0.1)
				(type default)
			)
			(layer "B.Fab")
		)
		(fp_line
			(start 0.67945 0.3048)
			(end 0.67945 -0.305054)
			(stroke
				(width 0.1)
				(type default)
			)
			(layer "B.Fab")
		)
		(fp_line
			(start -0.120396 0.2794)
			(end 0.12065 0.2794)
			(stroke
				(width 0.1)
				(type default)
			)
			(layer "B.Fab")
		)
		(fp_line
			(start 0.12065 0.2794)
			(end 0.12065 0.3048)
			(stroke
				(width 0.1)
				(type default)
			)
			(layer "B.Fab")
		)
		(fp_line
			(start -0.12065 -0.2794)
			(end -0.12065 -0.3048)
			(stroke
				(width 0.1)
				(type default)
			)
			(layer "B.Fab")
		)
		(fp_line
			(start 0.12065 -0.2794)
			(end -0.12065 -0.2794)
			(stroke
				(width 0.1)
				(type default)
			)
			(layer "B.Fab")
		)
		(fp_line
			(start -0.67945 -0.3048)
			(end -0.67945 0.3048)
			(stroke
				(width 0.1)
				(type default)
			)
			(layer "B.Fab")
		)
		(fp_line
			(start -0.12065 -0.3048)
			(end -0.67945 -0.3048)
			(stroke
				(width 0.1)
				(type default)
			)
			(layer "B.Fab")
		)
		(fp_line
			(start 0.12065 -0.305054)
			(end 0.12065 -0.2794)
			(stroke
				(width 0.1)
				(type default)
			)
			(layer "B.Fab")
		)
		(fp_line
			(start 0.67945 -0.305054)
			(end 0.12065 -0.305054)
			(stroke
				(width 0.1)
				(type default)
			)
			(layer "B.Fab")
		)
		(pad "1" smd circle
			(at 0.40005 0 90)
			(size 0 0)
			(layers "B.Cu" "B.Mask" "B.Paste")
			(net "I3C_SPD_DDRABCD_CPU1_BMC_R_SDA")
		)
		(pad "2" smd circle
			(at -0.40005 0 90)
			(size 0 0)
			(layers "B.Cu" "B.Mask" "B.Paste")
			(net "I3C_SPD_DDRABCD_CPU1_BMC_SDA")
		)
	)
	(footprint ""
		(layer "B.Cu")
		(at 359.24998 -212.049614)
		(property "Reference" "C499"
			(at 0 0 0)
			(layer "B.SilkS")
			(hide yes)
			(effects
				(font
					(size 1.27 1.27)
				)
				(justify mirror)
			)
		)
		(property "Value" ""
			(at 0 0 0)
			(layer "B.Fab")
			(effects
				(font
					(size 1.27 1.27)
				)
				(justify mirror)
			)
		)
		(duplicate_pad_numbers_are_jumpers no)
		(fp_line
			(start -1.524 -0.762)
			(end -1.524 0.762)
			(stroke
				(width 0.1524)
				(type default)
			)
			(layer "B.SilkS")
		)
		(fp_line
			(start -1.524 0.762)
			(end 1.524 0.762)
			(stroke
				(width 0.1524)
				(type default)
			)
			(layer "B.SilkS")
		)
		(fp_line
			(start 1.524 -0.762)
			(end -1.524 -0.762)
			(stroke
				(width 0.1524)
				(type default)
			)
			(layer "B.SilkS")
		)
		(fp_line
			(start 1.524 0.762)
			(end 1.524 -0.762)
			(stroke
				(width 0.1524)
				(type default)
			)
			(layer "B.SilkS")
		)
		(fp_line
			(start -1.1049 -0.724916)
			(end 1.1049 -0.724916)
			(stroke
				(width 0.1)
				(type default)
			)
			(layer "B.Fab")
		)
		(fp_line
			(start -1.1049 0.724916)
			(end -1.1049 -0.724916)
			(stroke
				(width 0.1)
				(type default)
			)
			(layer "B.Fab")
		)
		(fp_line
			(start 1.1049 -0.724916)
			(end 1.1049 0.724916)
			(stroke
				(width 0.1)
				(type default)
			)
			(layer "B.Fab")
		)
		(fp_line
			(start 1.1049 0.724916)
			(end -1.1049 0.724916)
			(stroke
				(width 0.1)
				(type default)
			)
			(layer "B.Fab")
		)
		(pad "1" smd rect
			(at 0.889 0)
			(size 1.016 1.27)
			(layers "B.Cu" "B.Mask" "B.Paste")
			(net "PVCCD_HV_CPU0")
		)
		(pad "2" smd rect
			(at -0.889 0)
			(size 1.016 1.27)
			(layers "B.Cu" "B.Mask" "B.Paste")
			(net "GND")
		)
	)
	(footprint ""
		(layer "B.Cu")
		(at 136.60755 -28.598368)
		(property "Reference" "C2325"
			(at 0 0 0)
			(layer "B.SilkS")
			(hide yes)
			(effects
				(font
					(size 1.27 1.27)
				)
				(justify mirror)
			)
		)
		(property "Value" ""
			(at 0 0 0)
			(layer "B.Fab")
			(effects
				(font
					(size 1.27 1.27)
				)
				(justify mirror)
			)
		)
		(duplicate_pad_numbers_are_jumpers no)
		(fp_line
			(start -0.7874 -0.4064)
			(end -0.7874 0.4064)
			(stroke
				(width 0.1524)
				(type default)
			)
			(layer "B.SilkS")
		)
		(fp_line
			(start -0.7874 0.4064)
			(end 0.7874 0.4064)
			(stroke
				(width 0.1524)
				(type default)
			)
			(layer "B.SilkS")
		)
		(fp_line
			(start 0.7874 -0.4064)
			(end -0.7874 -0.4064)
			(stroke
				(width 0.1524)
				(type default)
			)
			(layer "B.SilkS")
		)
		(fp_line
			(start 0.7874 0.4064)
			(end 0.7874 -0.4064)
			(stroke
				(width 0.1524)
				(type default)
			)
			(layer "B.SilkS")
		)
		(fp_line
			(start -0.67945 -0.3048)
			(end -0.67945 0.3048)
			(stroke
				(width 0.1)
				(type default)
			)
			(layer "B.Fab")
		)
		(fp_line
			(start -0.67945 0.3048)
			(end -0.120396 0.3048)
			(stroke
				(width 0.1)
				(type default)
			)
			(layer "B.Fab")
		)
		(fp_line
			(start -0.12065 -0.3048)
			(end -0.67945 -0.3048)
			(stroke
				(width 0.1)
				(type default)
			)
			(layer "B.Fab")
		)
		(fp_line
			(start -0.12065 -0.2794)
			(end -0.12065 -0.3048)
			(stroke
				(width 0.1)
				(type default)
			)
			(layer "B.Fab")
		)
		(fp_line
			(start -0.120396 0.2794)
			(end 0.12065 0.2794)
			(stroke
				(width 0.1)
				(type default)
			)
			(layer "B.Fab")
		)
		(fp_line
			(start -0.120396 0.3048)
			(end -0.120396 0.2794)
			(stroke
				(width 0.1)
				(type default)
			)
			(layer "B.Fab")
		)
		(fp_line
			(start 0.12065 -0.305054)
			(end 0.12065 -0.2794)
			(stroke
				(width 0.1)
				(type default)
			)
			(layer "B.Fab")
		)
		(fp_line
			(start 0.12065 -0.2794)
			(end -0.12065 -0.2794)
			(stroke
				(width 0.1)
				(type default)
			)
			(layer "B.Fab")
		)
		(fp_line
			(start 0.12065 0.2794)
			(end 0.12065 0.3048)
			(stroke
				(width 0.1)
				(type default)
			)
			(layer "B.Fab")
		)
		(fp_line
			(start 0.12065 0.3048)
			(end 0.67945 0.3048)
			(stroke
				(width 0.1)
				(type default)
			)
			(layer "B.Fab")
		)
		(fp_line
			(start 0.67945 -0.305054)
			(end 0.12065 -0.305054)
			(stroke
				(width 0.1)
				(type default)
			)
			(layer "B.Fab")
		)
		(fp_line
			(start 0.67945 0.3048)
			(end 0.67945 -0.305054)
			(stroke
				(width 0.1)
				(type default)
			)
			(layer "B.Fab")
		)
		(pad "1" smd circle
			(at 0.40005 0 180)
			(size 0 0)
			(layers "B.Cu" "B.Mask" "B.Paste")
			(net "PD_USB_HUB_2_VREG")
		)
		(pad "2" smd circle
			(at -0.40005 0 180)
			(size 0 0)
			(layers "B.Cu" "B.Mask" "B.Paste")
			(net "GND")
		)
	)
	(footprint ""
		(layer "B.Cu")
		(at 154.21102 -226.406456 180)
		(property "Reference" "R961"
			(at 0 0 0)
			(layer "B.SilkS")
			(hide yes)
			(effects
				(font
					(size 1.27 1.27)
				)
				(justify mirror)
			)
		)
		(property "Value" ""
			(at 0 0 0)
			(layer "B.Fab")
			(effects
				(font
					(size 1.27 1.27)
				)
				(justify mirror)
			)
		)
		(duplicate_pad_numbers_are_jumpers no)
		(fp_line
			(start 0.7874 0.4064)
			(end 0.7874 -0.4064)
			(stroke
				(width 0.1524)
				(type default)
			)
			(layer "B.SilkS")
		)
		(fp_line
			(start 0.7874 -0.4064)
			(end -0.7874 -0.4064)
			(stroke
				(width 0.1524)
				(type default)
			)
			(layer "B.SilkS")
		)
		(fp_line
			(start -0.7874 0.4064)
			(end 0.7874 0.4064)
			(stroke
				(width 0.1524)
				(type default)
			)
			(layer "B.SilkS")
		)
		(fp_line
			(start -0.7874 -0.4064)
			(end -0.7874 0.4064)
			(stroke
				(width 0.1524)
				(type default)
			)
			(layer "B.SilkS")
		)
		(fp_line
			(start 0.67945 0.3048)
			(end 0.67945 -0.305054)
			(stroke
				(width 0.1)
				(type default)
			)
			(layer "B.Fab")
		)
		(fp_line
			(start 0.67945 -0.305054)
			(end 0.12065 -0.305054)
			(stroke
				(width 0.1)
				(type default)
			)
			(layer "B.Fab")
		)
		(fp_line
			(start 0.12065 0.3048)
			(end 0.67945 0.3048)
			(stroke
				(width 0.1)
				(type default)
			)
			(layer "B.Fab")
		)
		(fp_line
			(start 0.12065 0.2794)
			(end 0.12065 0.3048)
			(stroke
				(width 0.1)
				(type default)
			)
			(layer "B.Fab")
		)
		(fp_line
			(start 0.12065 -0.2794)
			(end -0.12065 -0.2794)
			(stroke
				(width 0.1)
				(type default)
			)
			(layer "B.Fab")
		)
		(fp_line
			(start 0.12065 -0.305054)
			(end 0.12065 -0.2794)
			(stroke
				(width 0.1)
				(type default)
			)
			(layer "B.Fab")
		)
		(fp_line
			(start -0.120396 0.3048)
			(end -0.120396 0.2794)
			(stroke
				(width 0.1)
				(type default)
			)
			(layer "B.Fab")
		)
		(fp_line
			(start -0.120396 0.2794)
			(end 0.12065 0.2794)
			(stroke
				(width 0.1)
				(type default)
			)
			(layer "B.Fab")
		)
		(fp_line
			(start -0.12065 -0.2794)
			(end -0.12065 -0.3048)
			(stroke
				(width 0.1)
				(type default)
			)
			(layer "B.Fab")
		)
		(fp_line
			(start -0.12065 -0.3048)
			(end -0.67945 -0.3048)
			(stroke
				(width 0.1)
				(type default)
			)
			(layer "B.Fab")
		)
		(fp_line
			(start -0.67945 0.3048)
			(end -0.120396 0.3048)
			(stroke
				(width 0.1)
				(type default)
			)
			(layer "B.Fab")
		)
		(fp_line
			(start -0.67945 -0.3048)
			(end -0.67945 0.3048)
			(stroke
				(width 0.1)
				(type default)
			)
			(layer "B.Fab")
		)
		(pad "1" smd circle
			(at 0.40005 0)
			(size 0 0)
			(layers "B.Cu" "B.Mask" "B.Paste")
			(net "SMB_PEHPCPU1_GTL_SCL")
		)
		(pad "2" smd circle
			(at -0.40005 0)
			(size 0 0)
			(layers "B.Cu" "B.Mask" "B.Paste")
			(net "SMB_PEHPCPU1_GTL_R_SCL")
		)
	)
	(footprint ""
		(layer "B.Cu")
		(at 362.7374 -183.373776 180)
		(property "Reference" "R998"
			(at 0 0 0)
			(layer "B.SilkS")
			(hide yes)
			(effects
				(font
					(size 1.27 1.27)
				)
				(justify mirror)
			)
		)
		(property "Value" ""
			(at 0 0 0)
			(layer "B.Fab")
			(effects
				(font
					(size 1.27 1.27)
				)
				(justify mirror)
			)
		)
		(duplicate_pad_numbers_are_jumpers no)
		(fp_line
			(start 0.7874 0.4064)
			(end 0.7874 -0.4064)
			(stroke
				(width 0.1524)
				(type default)
			)
			(layer "B.SilkS")
		)
		(fp_line
			(start 0.7874 -0.4064)
			(end -0.7874 -0.4064)
			(stroke
				(width 0.1524)
				(type default)
			)
			(layer "B.SilkS")
		)
		(fp_line
			(start -0.7874 0.4064)
			(end 0.7874 0.4064)
			(stroke
				(width 0.1524)
				(type default)
			)
			(layer "B.SilkS")
		)
		(fp_line
			(start -0.7874 -0.4064)
			(end -0.7874 0.4064)
			(stroke
				(width 0.1524)
				(type default)
			)
			(layer "B.SilkS")
		)
		(fp_line
			(start 0.67945 0.3048)
			(end 0.67945 -0.305054)
			(stroke
				(width 0.1)
				(type default)
			)
			(layer "B.Fab")
		)
		(fp_line
			(start 0.67945 -0.305054)
			(end 0.12065 -0.305054)
			(stroke
				(width 0.1)
				(type default)
			)
			(layer "B.Fab")
		)
		(fp_line
			(start 0.12065 0.3048)
			(end 0.67945 0.3048)
			(stroke
				(width 0.1)
				(type default)
			)
			(layer "B.Fab")
		)
		(fp_line
			(start 0.12065 0.2794)
			(end 0.12065 0.3048)
			(stroke
				(width 0.1)
				(type default)
			)
			(layer "B.Fab")
		)
		(fp_line
			(start 0.12065 -0.2794)
			(end -0.12065 -0.2794)
			(stroke
				(width 0.1)
				(type default)
			)
			(layer "B.Fab")
		)
		(fp_line
			(start 0.12065 -0.305054)
			(end 0.12065 -0.2794)
			(stroke
				(width 0.1)
				(type default)
			)
			(layer "B.Fab")
		)
		(fp_line
			(start -0.120396 0.3048)
			(end -0.120396 0.2794)
			(stroke
				(width 0.1)
				(type default)
			)
			(layer "B.Fab")
		)
		(fp_line
			(start -0.120396 0.2794)
			(end 0.12065 0.2794)
			(stroke
				(width 0.1)
				(type default)
			)
			(layer "B.Fab")
		)
		(fp_line
			(start -0.12065 -0.2794)
			(end -0.12065 -0.3048)
			(stroke
				(width 0.1)
				(type default)
			)
			(layer "B.Fab")
		)
		(fp_line
			(start -0.12065 -0.3048)
			(end -0.67945 -0.3048)
			(stroke
				(width 0.1)
				(type default)
			)
			(layer "B.Fab")
		)
		(fp_line
			(start -0.67945 0.3048)
			(end -0.120396 0.3048)
			(stroke
				(width 0.1)
				(type default)
			)
			(layer "B.Fab")
		)
		(fp_line
			(start -0.67945 -0.3048)
			(end -0.67945 0.3048)
			(stroke
				(width 0.1)
				(type default)
			)
			(layer "B.Fab")
		)
		(pad "1" smd circle
			(at 0.40005 0)
			(size 0 0)
			(layers "B.Cu" "B.Mask" "B.Paste")
			(net "FM_SMB_PEHPCPU0_PCIE_ALERT_N")
		)
		(pad "2" smd circle
			(at -0.40005 0)
			(size 0 0)
			(layers "B.Cu" "B.Mask" "B.Paste")
			(net "FM_SMB_PEHPCPU0_PCIE_ALERT_R_N")
		)
	)
	(footprint ""
		(layer "B.Cu")
		(at 430.577244 -123.648724 180)
		(property "Reference" "PR1311"
			(at 0 0 0)
			(layer "B.SilkS")
			(hide yes)
			(effects
				(font
					(size 1.27 1.27)
				)
				(justify mirror)
			)
		)
		(property "Value" ""
			(at 0 0 0)
			(layer "B.Fab")
			(effects
				(font
					(size 1.27 1.27)
				)
				(justify mirror)
			)
		)
		(duplicate_pad_numbers_are_jumpers no)
		(fp_line
			(start 0.7874 0.4064)
			(end 0.7874 -0.4064)
			(stroke
				(width 0.1524)
				(type default)
			)
			(layer "B.SilkS")
		)
		(fp_line
			(start 0.7874 -0.4064)
			(end -0.7874 -0.4064)
			(stroke
				(width 0.1524)
				(type default)
			)
			(layer "B.SilkS")
		)
		(fp_line
			(start -0.7874 0.4064)
			(end 0.7874 0.4064)
			(stroke
				(width 0.1524)
				(type default)
			)
			(layer "B.SilkS")
		)
		(fp_line
			(start -0.7874 -0.4064)
			(end -0.7874 0.4064)
			(stroke
				(width 0.1524)
				(type default)
			)
			(layer "B.SilkS")
		)
		(fp_line
			(start 0.67945 0.3048)
			(end 0.67945 -0.305054)
			(stroke
				(width 0.1)
				(type default)
			)
			(layer "B.Fab")
		)
		(fp_line
			(start 0.67945 -0.305054)
			(end 0.12065 -0.305054)
			(stroke
				(width 0.1)
				(type default)
			)
			(layer "B.Fab")
		)
		(fp_line
			(start 0.12065 0.3048)
			(end 0.67945 0.3048)
			(stroke
				(width 0.1)
				(type default)
			)
			(layer "B.Fab")
		)
		(fp_line
			(start 0.12065 0.2794)
			(end 0.12065 0.3048)
			(stroke
				(width 0.1)
				(type default)
			)
			(layer "B.Fab")
		)
		(fp_line
			(start 0.12065 -0.2794)
			(end -0.12065 -0.2794)
			(stroke
				(width 0.1)
				(type default)
			)
			(layer "B.Fab")
		)
		(fp_line
			(start 0.12065 -0.305054)
			(end 0.12065 -0.2794)
			(stroke
				(width 0.1)
				(type default)
			)
			(layer "B.Fab")
		)
		(fp_line
			(start -0.120396 0.3048)
			(end -0.120396 0.2794)
			(stroke
				(width 0.1)
				(type default)
			)
			(layer "B.Fab")
		)
		(fp_line
			(start -0.120396 0.2794)
			(end 0.12065 0.2794)
			(stroke
				(width 0.1)
				(type default)
			)
			(layer "B.Fab")
		)
		(fp_line
			(start -0.12065 -0.2794)
			(end -0.12065 -0.3048)
			(stroke
				(width 0.1)
				(type default)
			)
			(layer "B.Fab")
		)
		(fp_line
			(start -0.12065 -0.3048)
			(end -0.67945 -0.3048)
			(stroke
				(width 0.1)
				(type default)
			)
			(layer "B.Fab")
		)
		(fp_line
			(start -0.67945 0.3048)
			(end -0.120396 0.3048)
			(stroke
				(width 0.1)
				(type default)
			)
			(layer "B.Fab")
		)
		(fp_line
			(start -0.67945 -0.3048)
			(end -0.67945 0.3048)
			(stroke
				(width 0.1)
				(type default)
			)
			(layer "B.Fab")
		)
		(pad "1" smd circle
			(at 0.40005 0)
			(size 0 0)
			(layers "B.Cu" "B.Mask" "B.Paste")
			(net "PVCCD_HV_CPU0_ISYS_R")
		)
		(pad "2" smd circle
			(at -0.40005 0)
			(size 0 0)
			(layers "B.Cu" "B.Mask" "B.Paste")
			(net "GND")
		)
	)
	(footprint ""
		(layer "B.Cu")
		(at 338.422234 -136.479534)
		(property "Reference" "R1015"
			(at 0 0 0)
			(layer "B.SilkS")
			(hide yes)
			(effects
				(font
					(size 1.27 1.27)
				)
				(justify mirror)
			)
		)
		(property "Value" ""
			(at 0 0 0)
			(layer "B.Fab")
			(effects
				(font
					(size 1.27 1.27)
				)
				(justify mirror)
			)
		)
		(duplicate_pad_numbers_are_jumpers no)
		(fp_line
			(start -0.7874 -0.4064)
			(end -0.7874 0.4064)
			(stroke
				(width 0.1524)
				(type default)
			)
			(layer "B.SilkS")
		)
		(fp_line
			(start -0.7874 0.4064)
			(end 0.7874 0.4064)
			(stroke
				(width 0.1524)
				(type default)
			)
			(layer "B.SilkS")
		)
		(fp_line
			(start -0.630174 -0.4064)
			(end -0.7874 -0.4064)
			(stroke
				(width 0.1524)
				(type default)
			)
			(layer "B.SilkS")
		)
		(fp_line
			(start 0.7874 -0.4064)
			(end -0.195834 -0.4064)
			(stroke
				(width 0.1524)
				(type default)
			)
			(layer "B.SilkS")
		)
		(fp_line
			(start 0.7874 -0.208534)
			(end 0.7874 -0.4064)
			(stroke
				(width 0.1524)
				(type default)
			)
			(layer "B.SilkS")
		)
		(fp_line
			(start 0.7874 0.4064)
			(end 0.7874 0.220726)
			(stroke
				(width 0.1524)
				(type default)
			)
			(layer "B.SilkS")
		)
		(fp_line
			(start -0.67945 -0.3048)
			(end -0.67945 0.3048)
			(stroke
				(width 0.1)
				(type default)
			)
			(layer "B.Fab")
		)
		(fp_line
			(start -0.67945 0.3048)
			(end -0.120396 0.3048)
			(stroke
				(width 0.1)
				(type default)
			)
			(layer "B.Fab")
		)
		(fp_line
			(start -0.12065 -0.3048)
			(end -0.67945 -0.3048)
			(stroke
				(width 0.1)
				(type default)
			)
			(layer "B.Fab")
		)
		(fp_line
			(start -0.12065 -0.2794)
			(end -0.12065 -0.3048)
			(stroke
				(width 0.1)
				(type default)
			)
			(layer "B.Fab")
		)
		(fp_line
			(start -0.120396 0.2794)
			(end 0.12065 0.2794)
			(stroke
				(width 0.1)
				(type default)
			)
			(layer "B.Fab")
		)
		(fp_line
			(start -0.120396 0.3048)
			(end -0.120396 0.2794)
			(stroke
				(width 0.1)
				(type default)
			)
			(layer "B.Fab")
		)
		(fp_line
			(start 0.12065 -0.305054)
			(end 0.12065 -0.2794)
			(stroke
				(width 0.1)
				(type default)
			)
			(layer "B.Fab")
		)
		(fp_line
			(start 0.12065 -0.2794)
			(end -0.12065 -0.2794)
			(stroke
				(width 0.1)
				(type default)
			)
			(layer "B.Fab")
		)
		(fp_line
			(start 0.12065 0.2794)
			(end 0.12065 0.3048)
			(stroke
				(width 0.1)
				(type default)
			)
			(layer "B.Fab")
		)
		(fp_line
			(start 0.12065 0.3048)
			(end 0.67945 0.3048)
			(stroke
				(width 0.1)
				(type default)
			)
			(layer "B.Fab")
		)
		(fp_line
			(start 0.67945 -0.305054)
			(end 0.12065 -0.305054)
			(stroke
				(width 0.1)
				(type default)
			)
			(layer "B.Fab")
		)
		(fp_line
			(start 0.67945 0.3048)
			(end 0.67945 -0.305054)
			(stroke
				(width 0.1)
				(type default)
			)
			(layer "B.Fab")
		)
		(pad "1" smd rect
			(at 0.40005 0)
			(size 0.4572 0.508)
			(layers "B.Cu" "B.Mask" "B.Paste")
			(net "CLK_25M_PCH_CPU0_DN")
		)
		(pad "2" smd rect
			(at -0.40005 0)
			(size 0.4572 0.508)
			(layers "B.Cu" "B.Mask" "B.Paste")
			(net "CLK_25M_NSSC_CPU0_DN")
		)
	)
	(footprint ""
		(layer "B.Cu")
		(at 107.457494 -248.49836 -90)
		(property "Reference" "C339"
			(at 0 0 90)
			(layer "B.SilkS")
			(hide yes)
			(effects
				(font
					(size 1.27 1.27)
				)
				(justify mirror)
			)
		)
		(property "Value" ""
			(at 0 0 90)
			(layer "B.Fab")
			(effects
				(font
					(size 1.27 1.27)
				)
				(justify mirror)
			)
		)
		(duplicate_pad_numbers_are_jumpers no)
		(fp_line
			(start -1.524 0.762)
			(end 1.524 0.762)
			(stroke
				(width 0.1524)
				(type default)
			)
			(layer "B.SilkS")
		)
		(fp_line
			(start 1.524 0.762)
			(end 1.524 -0.762)
			(stroke
				(width 0.1524)
				(type default)
			)
			(layer "B.SilkS")
		)
		(fp_line
			(start -1.524 -0.762)
			(end -1.524 0.762)
			(stroke
				(width 0.1524)
				(type default)
			)
			(layer "B.SilkS")
		)
		(fp_line
			(start 1.524 -0.762)
			(end -1.524 -0.762)
			(stroke
				(width 0.1524)
				(type default)
			)
			(layer "B.SilkS")
		)
		(fp_line
			(start -1.1049 0.724916)
			(end -1.1049 -0.724916)
			(stroke
				(width 0.1)
				(type default)
			)
			(layer "B.Fab")
		)
		(fp_line
			(start 1.1049 0.724916)
			(end -1.1049 0.724916)
			(stroke
				(width 0.1)
				(type default)
			)
			(layer "B.Fab")
		)
		(fp_line
			(start -1.1049 -0.724916)
			(end 1.1049 -0.724916)
			(stroke
				(width 0.1)
				(type default)
			)
			(layer "B.Fab")
		)
		(fp_line
			(start 1.1049 -0.724916)
			(end 1.1049 0.724916)
			(stroke
				(width 0.1)
				(type default)
			)
			(layer "B.Fab")
		)
		(pad "1" smd rect
			(at 0.889 0 270)
			(size 1.016 1.27)
			(layers "B.Cu" "B.Mask" "B.Paste")
			(net "PVCCIN_CPU1")
		)
		(pad "2" smd rect
			(at -0.889 0 270)
			(size 1.016 1.27)
			(layers "B.Cu" "B.Mask" "B.Paste")
			(net "GND")
		)
	)
	(footprint ""
		(layer "B.Cu")
		(at 338.045552 -190.756286 -90)
		(property "Reference" "R680"
			(at 0 0 90)
			(layer "B.SilkS")
			(hide yes)
			(effects
				(font
					(size 1.27 1.27)
				)
				(justify mirror)
			)
		)
		(property "Value" ""
			(at 0 0 90)
			(layer "B.Fab")
			(effects
				(font
					(size 1.27 1.27)
				)
				(justify mirror)
			)
		)
		(duplicate_pad_numbers_are_jumpers no)
		(fp_line
			(start -0.7874 0.4064)
			(end 0.7874 0.4064)
			(stroke
				(width 0.1524)
				(type default)
			)
			(layer "B.SilkS")
		)
		(fp_line
			(start 0.7874 0.4064)
			(end 0.7874 -0.4064)
			(stroke
				(width 0.1524)
				(type default)
			)
			(layer "B.SilkS")
		)
		(fp_line
			(start -0.7874 -0.4064)
			(end -0.7874 0.4064)
			(stroke
				(width 0.1524)
				(type default)
			)
			(layer "B.SilkS")
		)
		(fp_line
			(start 0.7874 -0.4064)
			(end -0.7874 -0.4064)
			(stroke
				(width 0.1524)
				(type default)
			)
			(layer "B.SilkS")
		)
		(fp_line
			(start -0.67945 0.3048)
			(end -0.120396 0.3048)
			(stroke
				(width 0.1)
				(type default)
			)
			(layer "B.Fab")
		)
		(fp_line
			(start -0.120396 0.3048)
			(end -0.120396 0.2794)
			(stroke
				(width 0.1)
				(type default)
			)
			(layer "B.Fab")
		)
		(fp_line
			(start 0.12065 0.3048)
			(end 0.67945 0.3048)
			(stroke
				(width 0.1)
				(type default)
			)
			(layer "B.Fab")
		)
		(fp_line
			(start 0.67945 0.3048)
			(end 0.67945 -0.305054)
			(stroke
				(width 0.1)
				(type default)
			)
			(layer "B.Fab")
		)
		(fp_line
			(start -0.120396 0.2794)
			(end 0.12065 0.2794)
			(stroke
				(width 0.1)
				(type default)
			)
			(layer "B.Fab")
		)
		(fp_line
			(start 0.12065 0.2794)
			(end 0.12065 0.3048)
			(stroke
				(width 0.1)
				(type default)
			)
			(layer "B.Fab")
		)
		(fp_line
			(start -0.12065 -0.2794)
			(end -0.12065 -0.3048)
			(stroke
				(width 0.1)
				(type default)
			)
			(layer "B.Fab")
		)
		(fp_line
			(start 0.12065 -0.2794)
			(end -0.12065 -0.2794)
			(stroke
				(width 0.1)
				(type default)
			)
			(layer "B.Fab")
		)
		(fp_line
			(start -0.67945 -0.3048)
			(end -0.67945 0.3048)
			(stroke
				(width 0.1)
				(type default)
			)
			(layer "B.Fab")
		)
		(fp_line
			(start -0.12065 -0.3048)
			(end -0.67945 -0.3048)
			(stroke
				(width 0.1)
				(type default)
			)
			(layer "B.Fab")
		)
		(fp_line
			(start 0.12065 -0.305054)
			(end 0.12065 -0.2794)
			(stroke
				(width 0.1)
				(type default)
			)
			(layer "B.Fab")
		)
		(fp_line
			(start 0.67945 -0.305054)
			(end 0.12065 -0.305054)
			(stroke
				(width 0.1)
				(type default)
			)
			(layer "B.Fab")
		)
		(pad "1" smd circle
			(at 0.40005 0 90)
			(size 0 0)
			(layers "B.Cu" "B.Mask" "B.Paste")
			(net "PVNN_TERM_CPU0")
		)
		(pad "2" smd circle
			(at -0.40005 0 90)
			(size 0 0)
			(layers "B.Cu" "B.Mask" "B.Paste")
			(net "I3C_SPD_DDRABCD_CPU0_SDA")
		)
	)
	(footprint ""
		(layer "B.Cu")
		(at 351.536508 -237.709202 -90)
		(property "Reference" "C1407"
			(at 0 0 90)
			(layer "B.SilkS")
			(hide yes)
			(effects
				(font
					(size 1.27 1.27)
				)
				(justify mirror)
			)
		)
		(property "Value" ""
			(at 0 0 90)
			(layer "B.Fab")
			(effects
				(font
					(size 1.27 1.27)
				)
				(justify mirror)
			)
		)
		(duplicate_pad_numbers_are_jumpers no)
		(fp_line
			(start -1.2954 0.5842)
			(end 1.2954 0.5842)
			(stroke
				(width 0.1524)
				(type default)
			)
			(layer "B.SilkS")
		)
		(fp_line
			(start 1.2954 0.5842)
			(end 1.2954 -0.5842)
			(stroke
				(width 0.1524)
				(type default)
			)
			(layer "B.SilkS")
		)
		(fp_line
			(start -1.2954 -0.5842)
			(end -1.2954 0.5842)
			(stroke
				(width 0.1524)
				(type default)
			)
			(layer "B.SilkS")
		)
		(fp_line
			(start 0 -0.5842)
			(end 0 0.5842)
			(stroke
				(width 0.1524)
				(type default)
			)
			(layer "B.SilkS")
		)
		(fp_line
			(start 1.2954 -0.5842)
			(end -1.2954 -0.5842)
			(stroke
				(width 0.1524)
				(type default)
			)
			(layer "B.SilkS")
		)
		(fp_line
			(start -0.8636 0.4572)
			(end 0.8636 0.4572)
			(stroke
				(width 0.1)
				(type default)
			)
			(layer "B.Fab")
		)
		(fp_line
			(start 0.8636 0.4572)
			(end 0.8636 0.4064)
			(stroke
				(width 0.1)
				(type default)
			)
			(layer "B.Fab")
		)
		(fp_line
			(start -1.1938 0.4064)
			(end -0.8636 0.4064)
			(stroke
				(width 0.1)
				(type default)
			)
			(layer "B.Fab")
		)
		(fp_line
			(start -0.8636 0.4064)
			(end -0.8636 0.4572)
			(stroke
				(width 0.1)
				(type default)
			)
			(layer "B.Fab")
		)
		(fp_line
			(start 0.8636 0.4064)
			(end 1.1938 0.4064)
			(stroke
				(width 0.1)
				(type default)
			)
			(layer "B.Fab")
		)
		(fp_line
			(start 1.1938 0.4064)
			(end 1.1938 -0.4064)
			(stroke
				(width 0.1)
				(type default)
			)
			(layer "B.Fab")
		)
		(fp_line
			(start -1.1938 -0.4064)
			(end -1.1938 0.4064)
			(stroke
				(width 0.1)
				(type default)
			)
			(layer "B.Fab")
		)
		(fp_line
			(start -0.8636 -0.4064)
			(end -1.1938 -0.4064)
			(stroke
				(width 0.1)
				(type default)
			)
			(layer "B.Fab")
		)
		(fp_line
			(start 0.8636 -0.4064)
			(end 0.8636 -0.4572)
			(stroke
				(width 0.1)
				(type default)
			)
			(layer "B.Fab")
		)
		(fp_line
			(start 1.1938 -0.4064)
			(end 0.8636 -0.4064)
			(stroke
				(width 0.1)
				(type default)
			)
			(layer "B.Fab")
		)
		(fp_line
			(start -0.8636 -0.4572)
			(end -0.8636 -0.4064)
			(stroke
				(width 0.1)
				(type default)
			)
			(layer "B.Fab")
		)
		(fp_line
			(start 0.8636 -0.4572)
			(end -0.8636 -0.4572)
			(stroke
				(width 0.1)
				(type default)
			)
			(layer "B.Fab")
		)
		(pad "1" smd rect
			(at 0.7366 0 180)
			(size 0.7112 0.8128)
			(layers "B.Cu" "B.Mask" "B.Paste")
			(net "PVNN_MAIN_CPU0")
		)
		(pad "2" smd rect
			(at -0.7366 0 180)
			(size 0.7112 0.8128)
			(layers "B.Cu" "B.Mask" "B.Paste")
			(net "GND")
		)
	)
	(footprint ""
		(layer "B.Cu")
		(at 25.277064 -175.824642 -90)
		(property "Reference" "R2584"
			(at 0 0 90)
			(layer "B.SilkS")
			(hide yes)
			(effects
				(font
					(size 1.27 1.27)
				)
				(justify mirror)
			)
		)
		(property "Value" ""
			(at 0 0 90)
			(layer "B.Fab")
			(effects
				(font
					(size 1.27 1.27)
				)
				(justify mirror)
			)
		)
		(duplicate_pad_numbers_are_jumpers no)
		(fp_line
			(start -0.7874 0.4064)
			(end 0.7874 0.4064)
			(stroke
				(width 0.1524)
				(type default)
			)
			(layer "B.SilkS")
		)
		(fp_line
			(start 0.7874 0.4064)
			(end 0.7874 -0.4064)
			(stroke
				(width 0.1524)
				(type default)
			)
			(layer "B.SilkS")
		)
		(fp_line
			(start -0.7874 -0.4064)
			(end -0.7874 0.4064)
			(stroke
				(width 0.1524)
				(type default)
			)
			(layer "B.SilkS")
		)
		(fp_line
			(start 0.7874 -0.4064)
			(end -0.7874 -0.4064)
			(stroke
				(width 0.1524)
				(type default)
			)
			(layer "B.SilkS")
		)
		(fp_line
			(start -0.67945 0.3048)
			(end -0.120396 0.3048)
			(stroke
				(width 0.1)
				(type default)
			)
			(layer "B.Fab")
		)
		(fp_line
			(start -0.120396 0.3048)
			(end -0.120396 0.2794)
			(stroke
				(width 0.1)
				(type default)
			)
			(layer "B.Fab")
		)
		(fp_line
			(start 0.12065 0.3048)
			(end 0.67945 0.3048)
			(stroke
				(width 0.1)
				(type default)
			)
			(layer "B.Fab")
		)
		(fp_line
			(start 0.67945 0.3048)
			(end 0.67945 -0.305054)
			(stroke
				(width 0.1)
				(type default)
			)
			(layer "B.Fab")
		)
		(fp_line
			(start -0.120396 0.2794)
			(end 0.12065 0.2794)
			(stroke
				(width 0.1)
				(type default)
			)
			(layer "B.Fab")
		)
		(fp_line
			(start 0.12065 0.2794)
			(end 0.12065 0.3048)
			(stroke
				(width 0.1)
				(type default)
			)
			(layer "B.Fab")
		)
		(fp_line
			(start -0.12065 -0.2794)
			(end -0.12065 -0.3048)
			(stroke
				(width 0.1)
				(type default)
			)
			(layer "B.Fab")
		)
		(fp_line
			(start 0.12065 -0.2794)
			(end -0.12065 -0.2794)
			(stroke
				(width 0.1)
				(type default)
			)
			(layer "B.Fab")
		)
		(fp_line
			(start -0.67945 -0.3048)
			(end -0.67945 0.3048)
			(stroke
				(width 0.1)
				(type default)
			)
			(layer "B.Fab")
		)
		(fp_line
			(start -0.12065 -0.3048)
			(end -0.67945 -0.3048)
			(stroke
				(width 0.1)
				(type default)
			)
			(layer "B.Fab")
		)
		(fp_line
			(start 0.12065 -0.305054)
			(end 0.12065 -0.2794)
			(stroke
				(width 0.1)
				(type default)
			)
			(layer "B.Fab")
		)
		(fp_line
			(start 0.67945 -0.305054)
			(end 0.12065 -0.305054)
			(stroke
				(width 0.1)
				(type default)
			)
			(layer "B.Fab")
		)
		(pad "1" smd circle
			(at 0.40005 0 90)
			(size 0 0)
			(layers "B.Cu" "B.Mask" "B.Paste")
			(net "P3V3_AUX")
		)
		(pad "2" smd circle
			(at -0.40005 0 90)
			(size 0 0)
			(layers "B.Cu" "B.Mask" "B.Paste")
			(net "PWRGD_PVNN_MAIN_CPU1_R")
		)
	)
	(footprint ""
		(layer "B.Cu")
		(at 368.398298 -359.586276 -90)
		(property "Reference" "PJ64"
			(at -3.236722 -3.587242 0)
			(unlocked yes)
			(layer "B.SilkS")
			(effects
				(font
					(size 0.7874 0.5842)
					(thickness 0.1524)
				)
				(justify left mirror)
			)
		)
		(property "Value" ""
			(at 0 0 90)
			(layer "B.Fab")
			(effects
				(font
					(size 1.27 1.27)
				)
				(justify mirror)
			)
		)
		(duplicate_pad_numbers_are_jumpers no)
		(pad "1" smd circle
			(at 0.7493 0)
			(size 0 0)
			(layers "B.Cu" "B.Mask" "B.Paste")
			(net "SH_PVPP_HBM_CPU0_P")
		)
		(pad "2" smd rect
			(at -0.7493 0 180)
			(size 0.7112 0.8128)
			(layers "B.Cu" "B.Mask" "B.Paste")
			(net "PVPP_HBM_CPU0")
		)
		(zone
			(layer "B.Cu")
			(hatch none 0.5)
			(connect_pads
				(clearance 0)
			)
			(min_thickness 0.25)
			(keepout
				(tracks allowed)
				(vias not_allowed)
				(pads allowed)
				(copperpour not_allowed)
				(footprints allowed)
			)
			(placement
				(enabled no)
				(sheetname "")
			)
			(fill
				(thermal_gap 0.5)
				(thermal_bridge_width 0.5)
				(island_removal_mode 0)
			)
			(polygon
				(pts
					(xy 367.987072 -358.405176) (xy 368.804698 -358.405176) (xy 368.804698 -360.792776) (xy 367.987072 -360.792776)
				)
			)
		)
	)
	(footprint ""
		(layer "B.Cu")
		(at 34.014156 -395.918436 -90)
		(property "Reference" "C2356"
			(at 0 0 90)
			(layer "B.SilkS")
			(hide yes)
			(effects
				(font
					(size 1.27 1.27)
				)
				(justify mirror)
			)
		)
		(property "Value" ""
			(at 0 0 90)
			(layer "B.Fab")
			(effects
				(font
					(size 1.27 1.27)
				)
				(justify mirror)
			)
		)
		(duplicate_pad_numbers_are_jumpers no)
		(fp_line
			(start -1.524 0.762)
			(end 1.524 0.762)
			(stroke
				(width 0.1524)
				(type default)
			)
			(layer "B.SilkS")
		)
		(fp_line
			(start 1.524 0.762)
			(end 1.524 -0.762)
			(stroke
				(width 0.1524)
				(type default)
			)
			(layer "B.SilkS")
		)
		(fp_line
			(start -1.524 -0.762)
			(end -1.524 0.762)
			(stroke
				(width 0.1524)
				(type default)
			)
			(layer "B.SilkS")
		)
		(fp_line
			(start 1.524 -0.762)
			(end -1.524 -0.762)
			(stroke
				(width 0.1524)
				(type default)
			)
			(layer "B.SilkS")
		)
		(fp_line
			(start -1.1049 0.724916)
			(end -1.1049 -0.724916)
			(stroke
				(width 0.1)
				(type default)
			)
			(layer "B.Fab")
		)
		(fp_line
			(start 1.1049 0.724916)
			(end -1.1049 0.724916)
			(stroke
				(width 0.1)
				(type default)
			)
			(layer "B.Fab")
		)
		(fp_line
			(start -1.1049 -0.724916)
			(end 1.1049 -0.724916)
			(stroke
				(width 0.1)
				(type default)
			)
			(layer "B.Fab")
		)
		(fp_line
			(start 1.1049 -0.724916)
			(end 1.1049 0.724916)
			(stroke
				(width 0.1)
				(type default)
			)
			(layer "B.Fab")
		)
		(pad "1" smd rect
			(at 0.889 0 270)
			(size 1.016 1.27)
			(layers "B.Cu" "B.Mask" "B.Paste")
			(net "P3V3_AUX")
		)
		(pad "2" smd rect
			(at -0.889 0 270)
			(size 1.016 1.27)
			(layers "B.Cu" "B.Mask" "B.Paste")
			(net "GND")
		)
	)
	(footprint ""
		(layer "B.Cu")
		(at 22.989032 -171.165774 180)
		(property "Reference" "R4595"
			(at 0 0 0)
			(layer "B.SilkS")
			(hide yes)
			(effects
				(font
					(size 1.27 1.27)
				)
				(justify mirror)
			)
		)
		(property "Value" ""
			(at 0 0 0)
			(layer "B.Fab")
			(effects
				(font
					(size 1.27 1.27)
				)
				(justify mirror)
			)
		)
		(duplicate_pad_numbers_are_jumpers no)
		(fp_line
			(start 0.7874 0.4064)
			(end 0.7874 -0.4064)
			(stroke
				(width 0.1524)
				(type default)
			)
			(layer "B.SilkS")
		)
		(fp_line
			(start 0.7874 -0.4064)
			(end -0.7874 -0.4064)
			(stroke
				(width 0.1524)
				(type default)
			)
			(layer "B.SilkS")
		)
		(fp_line
			(start -0.7874 0.4064)
			(end 0.7874 0.4064)
			(stroke
				(width 0.1524)
				(type default)
			)
			(layer "B.SilkS")
		)
		(fp_line
			(start -0.7874 -0.4064)
			(end -0.7874 0.4064)
			(stroke
				(width 0.1524)
				(type default)
			)
			(layer "B.SilkS")
		)
		(fp_line
			(start 0.67945 0.3048)
			(end 0.67945 -0.305054)
			(stroke
				(width 0.1)
				(type default)
			)
			(layer "B.Fab")
		)
		(fp_line
			(start 0.67945 -0.305054)
			(end 0.12065 -0.305054)
			(stroke
				(width 0.1)
				(type default)
			)
			(layer "B.Fab")
		)
		(fp_line
			(start 0.12065 0.3048)
			(end 0.67945 0.3048)
			(stroke
				(width 0.1)
				(type default)
			)
			(layer "B.Fab")
		)
		(fp_line
			(start 0.12065 0.2794)
			(end 0.12065 0.3048)
			(stroke
				(width 0.1)
				(type default)
			)
			(layer "B.Fab")
		)
		(fp_line
			(start 0.12065 -0.2794)
			(end -0.12065 -0.2794)
			(stroke
				(width 0.1)
				(type default)
			)
			(layer "B.Fab")
		)
		(fp_line
			(start 0.12065 -0.305054)
			(end 0.12065 -0.2794)
			(stroke
				(width 0.1)
				(type default)
			)
			(layer "B.Fab")
		)
		(fp_line
			(start -0.120396 0.3048)
			(end -0.120396 0.2794)
			(stroke
				(width 0.1)
				(type default)
			)
			(layer "B.Fab")
		)
		(fp_line
			(start -0.120396 0.2794)
			(end 0.12065 0.2794)
			(stroke
				(width 0.1)
				(type default)
			)
			(layer "B.Fab")
		)
		(fp_line
			(start -0.12065 -0.2794)
			(end -0.12065 -0.3048)
			(stroke
				(width 0.1)
				(type default)
			)
			(layer "B.Fab")
		)
		(fp_line
			(start -0.12065 -0.3048)
			(end -0.67945 -0.3048)
			(stroke
				(width 0.1)
				(type default)
			)
			(layer "B.Fab")
		)
		(fp_line
			(start -0.67945 0.3048)
			(end -0.120396 0.3048)
			(stroke
				(width 0.1)
				(type default)
			)
			(layer "B.Fab")
		)
		(fp_line
			(start -0.67945 -0.3048)
			(end -0.67945 0.3048)
			(stroke
				(width 0.1)
				(type default)
			)
			(layer "B.Fab")
		)
		(pad "1" smd circle
			(at 0.40005 0)
			(size 0 0)
			(layers "B.Cu" "B.Mask" "B.Paste")
			(net "SMB_VR_3V3AUX_SCL_R")
		)
		(pad "2" smd circle
			(at -0.40005 0)
			(size 0 0)
			(layers "B.Cu" "B.Mask" "B.Paste")
			(net "SMB_CLK_PVCCD_HV_CPU1")
		)
	)
	(footprint ""
		(layer "B.Cu")
		(at 338.998814 -190.756286 90)
		(property "Reference" "R688"
			(at 0 0 90)
			(layer "B.SilkS")
			(hide yes)
			(effects
				(font
					(size 1.27 1.27)
				)
				(justify mirror)
			)
		)
		(property "Value" ""
			(at 0 0 90)
			(layer "B.Fab")
			(effects
				(font
					(size 1.27 1.27)
				)
				(justify mirror)
			)
		)
		(duplicate_pad_numbers_are_jumpers no)
		(fp_line
			(start 0.7874 -0.4064)
			(end -0.7874 -0.4064)
			(stroke
				(width 0.1524)
				(type default)
			)
			(layer "B.SilkS")
		)
		(fp_line
			(start -0.7874 -0.4064)
			(end -0.7874 0.4064)
			(stroke
				(width 0.1524)
				(type default)
			)
			(layer "B.SilkS")
		)
		(fp_line
			(start 0.7874 0.4064)
			(end 0.7874 -0.4064)
			(stroke
				(width 0.1524)
				(type default)
			)
			(layer "B.SilkS")
		)
		(fp_line
			(start -0.7874 0.4064)
			(end 0.7874 0.4064)
			(stroke
				(width 0.1524)
				(type default)
			)
			(layer "B.SilkS")
		)
		(fp_line
			(start 0.67945 -0.305054)
			(end 0.12065 -0.305054)
			(stroke
				(width 0.1)
				(type default)
			)
			(layer "B.Fab")
		)
		(fp_line
			(start 0.12065 -0.305054)
			(end 0.12065 -0.2794)
			(stroke
				(width 0.1)
				(type default)
			)
			(layer "B.Fab")
		)
		(fp_line
			(start -0.12065 -0.3048)
			(end -0.67945 -0.3048)
			(stroke
				(width 0.1)
				(type default)
			)
			(layer "B.Fab")
		)
		(fp_line
			(start -0.67945 -0.3048)
			(end -0.67945 0.3048)
			(stroke
				(width 0.1)
				(type default)
			)
			(layer "B.Fab")
		)
		(fp_line
			(start 0.12065 -0.2794)
			(end -0.12065 -0.2794)
			(stroke
				(width 0.1)
				(type default)
			)
			(layer "B.Fab")
		)
		(fp_line
			(start -0.12065 -0.2794)
			(end -0.12065 -0.3048)
			(stroke
				(width 0.1)
				(type default)
			)
			(layer "B.Fab")
		)
		(fp_line
			(start 0.12065 0.2794)
			(end 0.12065 0.3048)
			(stroke
				(width 0.1)
				(type default)
			)
			(layer "B.Fab")
		)
		(fp_line
			(start -0.120396 0.2794)
			(end 0.12065 0.2794)
			(stroke
				(width 0.1)
				(type default)
			)
			(layer "B.Fab")
		)
		(fp_line
			(start 0.67945 0.3048)
			(end 0.67945 -0.305054)
			(stroke
				(width 0.1)
				(type default)
			)
			(layer "B.Fab")
		)
		(fp_line
			(start 0.12065 0.3048)
			(end 0.67945 0.3048)
			(stroke
				(width 0.1)
				(type default)
			)
			(layer "B.Fab")
		)
		(fp_line
			(start -0.120396 0.3048)
			(end -0.120396 0.2794)
			(stroke
				(width 0.1)
				(type default)
			)
			(layer "B.Fab")
		)
		(fp_line
			(start -0.67945 0.3048)
			(end -0.120396 0.3048)
			(stroke
				(width 0.1)
				(type default)
			)
			(layer "B.Fab")
		)
		(pad "1" smd circle
			(at 0.40005 0 270)
			(size 0 0)
			(layers "B.Cu" "B.Mask" "B.Paste")
			(net "I3C_SPD_DDRABCD_CPU0_SDA")
		)
		(pad "2" smd circle
			(at -0.40005 0 270)
			(size 0 0)
			(layers "B.Cu" "B.Mask" "B.Paste")
			(net "I3C_SPD_DDRABCD_CPU0_R_SDA")
		)
	)
	(footprint ""
		(layer "B.Cu")
		(at 98.273108 -190.705232 -90)
		(property "Reference" "R743"
			(at 0 0 90)
			(layer "B.SilkS")
			(hide yes)
			(effects
				(font
					(size 1.27 1.27)
				)
				(justify mirror)
			)
		)
		(property "Value" ""
			(at 0 0 90)
			(layer "B.Fab")
			(effects
				(font
					(size 1.27 1.27)
				)
				(justify mirror)
			)
		)
		(duplicate_pad_numbers_are_jumpers no)
		(fp_line
			(start -0.7874 0.4064)
			(end 0.7874 0.4064)
			(stroke
				(width 0.1524)
				(type default)
			)
			(layer "B.SilkS")
		)
		(fp_line
			(start 0.7874 0.4064)
			(end 0.7874 -0.4064)
			(stroke
				(width 0.1524)
				(type default)
			)
			(layer "B.SilkS")
		)
		(fp_line
			(start -0.7874 -0.4064)
			(end -0.7874 0.4064)
			(stroke
				(width 0.1524)
				(type default)
			)
			(layer "B.SilkS")
		)
		(fp_line
			(start 0.7874 -0.4064)
			(end -0.7874 -0.4064)
			(stroke
				(width 0.1524)
				(type default)
			)
			(layer "B.SilkS")
		)
		(fp_line
			(start -0.67945 0.3048)
			(end -0.120396 0.3048)
			(stroke
				(width 0.1)
				(type default)
			)
			(layer "B.Fab")
		)
		(fp_line
			(start -0.120396 0.3048)
			(end -0.120396 0.2794)
			(stroke
				(width 0.1)
				(type default)
			)
			(layer "B.Fab")
		)
		(fp_line
			(start 0.12065 0.3048)
			(end 0.67945 0.3048)
			(stroke
				(width 0.1)
				(type default)
			)
			(layer "B.Fab")
		)
		(fp_line
			(start 0.67945 0.3048)
			(end 0.67945 -0.305054)
			(stroke
				(width 0.1)
				(type default)
			)
			(layer "B.Fab")
		)
		(fp_line
			(start -0.120396 0.2794)
			(end 0.12065 0.2794)
			(stroke
				(width 0.1)
				(type default)
			)
			(layer "B.Fab")
		)
		(fp_line
			(start 0.12065 0.2794)
			(end 0.12065 0.3048)
			(stroke
				(width 0.1)
				(type default)
			)
			(layer "B.Fab")
		)
		(fp_line
			(start -0.12065 -0.2794)
			(end -0.12065 -0.3048)
			(stroke
				(width 0.1)
				(type default)
			)
			(layer "B.Fab")
		)
		(fp_line
			(start 0.12065 -0.2794)
			(end -0.12065 -0.2794)
			(stroke
				(width 0.1)
				(type default)
			)
			(layer "B.Fab")
		)
		(fp_line
			(start -0.67945 -0.3048)
			(end -0.67945 0.3048)
			(stroke
				(width 0.1)
				(type default)
			)
			(layer "B.Fab")
		)
		(fp_line
			(start -0.12065 -0.3048)
			(end -0.67945 -0.3048)
			(stroke
				(width 0.1)
				(type default)
			)
			(layer "B.Fab")
		)
		(fp_line
			(start 0.12065 -0.305054)
			(end 0.12065 -0.2794)
			(stroke
				(width 0.1)
				(type default)
			)
			(layer "B.Fab")
		)
		(fp_line
			(start 0.67945 -0.305054)
			(end 0.12065 -0.305054)
			(stroke
				(width 0.1)
				(type default)
			)
			(layer "B.Fab")
		)
		(pad "1" smd circle
			(at 0.40005 0 90)
			(size 0 0)
			(layers "B.Cu" "B.Mask" "B.Paste")
			(net "PVNN_TERM_CPU1")
		)
		(pad "2" smd circle
			(at -0.40005 0 90)
			(size 0 0)
			(layers "B.Cu" "B.Mask" "B.Paste")
			(net "JTAG_MUX_CPU1_GTL_TDI")
		)
	)
	(footprint ""
		(layer "B.Cu")
		(at 254.508 -96.738948 180)
		(property "Reference" "R3642"
			(at 0 0 0)
			(layer "B.SilkS")
			(hide yes)
			(effects
				(font
					(size 1.27 1.27)
				)
				(justify mirror)
			)
		)
		(property "Value" ""
			(at 0 0 0)
			(layer "B.Fab")
			(effects
				(font
					(size 1.27 1.27)
				)
				(justify mirror)
			)
		)
		(duplicate_pad_numbers_are_jumpers no)
		(fp_line
			(start 0.7874 0.4064)
			(end 0.7874 -0.4064)
			(stroke
				(width 0.1524)
				(type default)
			)
			(layer "B.SilkS")
		)
		(fp_line
			(start 0.7874 -0.4064)
			(end -0.7874 -0.4064)
			(stroke
				(width 0.1524)
				(type default)
			)
			(layer "B.SilkS")
		)
		(fp_line
			(start -0.7874 0.4064)
			(end 0.7874 0.4064)
			(stroke
				(width 0.1524)
				(type default)
			)
			(layer "B.SilkS")
		)
		(fp_line
			(start -0.7874 -0.4064)
			(end -0.7874 0.4064)
			(stroke
				(width 0.1524)
				(type default)
			)
			(layer "B.SilkS")
		)
		(fp_line
			(start 0.67945 0.3048)
			(end 0.67945 -0.305054)
			(stroke
				(width 0.1)
				(type default)
			)
			(layer "B.Fab")
		)
		(fp_line
			(start 0.67945 -0.305054)
			(end 0.12065 -0.305054)
			(stroke
				(width 0.1)
				(type default)
			)
			(layer "B.Fab")
		)
		(fp_line
			(start 0.12065 0.3048)
			(end 0.67945 0.3048)
			(stroke
				(width 0.1)
				(type default)
			)
			(layer "B.Fab")
		)
		(fp_line
			(start 0.12065 0.2794)
			(end 0.12065 0.3048)
			(stroke
				(width 0.1)
				(type default)
			)
			(layer "B.Fab")
		)
		(fp_line
			(start 0.12065 -0.2794)
			(end -0.12065 -0.2794)
			(stroke
				(width 0.1)
				(type default)
			)
			(layer "B.Fab")
		)
		(fp_line
			(start 0.12065 -0.305054)
			(end 0.12065 -0.2794)
			(stroke
				(width 0.1)
				(type default)
			)
			(layer "B.Fab")
		)
		(fp_line
			(start -0.120396 0.3048)
			(end -0.120396 0.2794)
			(stroke
				(width 0.1)
				(type default)
			)
			(layer "B.Fab")
		)
		(fp_line
			(start -0.120396 0.2794)
			(end 0.12065 0.2794)
			(stroke
				(width 0.1)
				(type default)
			)
			(layer "B.Fab")
		)
		(fp_line
			(start -0.12065 -0.2794)
			(end -0.12065 -0.3048)
			(stroke
				(width 0.1)
				(type default)
			)
			(layer "B.Fab")
		)
		(fp_line
			(start -0.12065 -0.3048)
			(end -0.67945 -0.3048)
			(stroke
				(width 0.1)
				(type default)
			)
			(layer "B.Fab")
		)
		(fp_line
			(start -0.67945 0.3048)
			(end -0.120396 0.3048)
			(stroke
				(width 0.1)
				(type default)
			)
			(layer "B.Fab")
		)
		(fp_line
			(start -0.67945 -0.3048)
			(end -0.67945 0.3048)
			(stroke
				(width 0.1)
				(type default)
			)
			(layer "B.Fab")
		)
		(pad "1" smd circle
			(at 0.40005 0)
			(size 0 0)
			(layers "B.Cu" "B.Mask" "B.Paste")
			(net "P3V3_AUX")
		)
		(pad "2" smd circle
			(at -0.40005 0)
			(size 0 0)
			(layers "B.Cu" "B.Mask" "B.Paste")
			(net "CK440Q_OE_5")
		)
	)
	(footprint ""
		(layer "B.Cu")
		(at 430.586388 -120.798082 180)
		(property "Reference" "PR373"
			(at 0 0 0)
			(layer "B.SilkS")
			(hide yes)
			(effects
				(font
					(size 1.27 1.27)
				)
				(justify mirror)
			)
		)
		(property "Value" ""
			(at 0 0 0)
			(layer "B.Fab")
			(effects
				(font
					(size 1.27 1.27)
				)
				(justify mirror)
			)
		)
		(duplicate_pad_numbers_are_jumpers no)
		(fp_line
			(start 0.7874 0.4064)
			(end 0.7874 -0.4064)
			(stroke
				(width 0.1524)
				(type default)
			)
			(layer "B.SilkS")
		)
		(fp_line
			(start 0.7874 -0.4064)
			(end -0.7874 -0.4064)
			(stroke
				(width 0.1524)
				(type default)
			)
			(layer "B.SilkS")
		)
		(fp_line
			(start -0.7874 0.4064)
			(end 0.7874 0.4064)
			(stroke
				(width 0.1524)
				(type default)
			)
			(layer "B.SilkS")
		)
		(fp_line
			(start -0.7874 -0.4064)
			(end -0.7874 0.4064)
			(stroke
				(width 0.1524)
				(type default)
			)
			(layer "B.SilkS")
		)
		(fp_line
			(start 0.67945 0.3048)
			(end 0.67945 -0.305054)
			(stroke
				(width 0.1)
				(type default)
			)
			(layer "B.Fab")
		)
		(fp_line
			(start 0.67945 -0.305054)
			(end 0.12065 -0.305054)
			(stroke
				(width 0.1)
				(type default)
			)
			(layer "B.Fab")
		)
		(fp_line
			(start 0.12065 0.3048)
			(end 0.67945 0.3048)
			(stroke
				(width 0.1)
				(type default)
			)
			(layer "B.Fab")
		)
		(fp_line
			(start 0.12065 0.2794)
			(end 0.12065 0.3048)
			(stroke
				(width 0.1)
				(type default)
			)
			(layer "B.Fab")
		)
		(fp_line
			(start 0.12065 -0.2794)
			(end -0.12065 -0.2794)
			(stroke
				(width 0.1)
				(type default)
			)
			(layer "B.Fab")
		)
		(fp_line
			(start 0.12065 -0.305054)
			(end 0.12065 -0.2794)
			(stroke
				(width 0.1)
				(type default)
			)
			(layer "B.Fab")
		)
		(fp_line
			(start -0.120396 0.3048)
			(end -0.120396 0.2794)
			(stroke
				(width 0.1)
				(type default)
			)
			(layer "B.Fab")
		)
		(fp_line
			(start -0.120396 0.2794)
			(end 0.12065 0.2794)
			(stroke
				(width 0.1)
				(type default)
			)
			(layer "B.Fab")
		)
		(fp_line
			(start -0.12065 -0.2794)
			(end -0.12065 -0.3048)
			(stroke
				(width 0.1)
				(type default)
			)
			(layer "B.Fab")
		)
		(fp_line
			(start -0.12065 -0.3048)
			(end -0.67945 -0.3048)
			(stroke
				(width 0.1)
				(type default)
			)
			(layer "B.Fab")
		)
		(fp_line
			(start -0.67945 0.3048)
			(end -0.120396 0.3048)
			(stroke
				(width 0.1)
				(type default)
			)
			(layer "B.Fab")
		)
		(fp_line
			(start -0.67945 -0.3048)
			(end -0.67945 0.3048)
			(stroke
				(width 0.1)
				(type default)
			)
			(layer "B.Fab")
		)
		(pad "1" smd circle
			(at 0.40005 0)
			(size 0 0)
			(layers "B.Cu" "B.Mask" "B.Paste")
			(net "PVCCD_HV_CPU0_ISENSE_N")
		)
		(pad "2" smd circle
			(at -0.40005 0)
			(size 0 0)
			(layers "B.Cu" "B.Mask" "B.Paste")
			(net "GND")
		)
	)
	(footprint ""
		(layer "B.Cu")
		(at 328.913998 -190.74511 -90)
		(property "Reference" "R294"
			(at 0 0 90)
			(layer "B.SilkS")
			(hide yes)
			(effects
				(font
					(size 1.27 1.27)
				)
				(justify mirror)
			)
		)
		(property "Value" ""
			(at 0 0 90)
			(layer "B.Fab")
			(effects
				(font
					(size 1.27 1.27)
				)
				(justify mirror)
			)
		)
		(duplicate_pad_numbers_are_jumpers no)
		(fp_line
			(start -0.7874 0.4064)
			(end 0.7874 0.4064)
			(stroke
				(width 0.1524)
				(type default)
			)
			(layer "B.SilkS")
		)
		(fp_line
			(start 0.7874 0.4064)
			(end 0.7874 -0.4064)
			(stroke
				(width 0.1524)
				(type default)
			)
			(layer "B.SilkS")
		)
		(fp_line
			(start -0.7874 -0.4064)
			(end -0.7874 0.4064)
			(stroke
				(width 0.1524)
				(type default)
			)
			(layer "B.SilkS")
		)
		(fp_line
			(start 0.7874 -0.4064)
			(end -0.7874 -0.4064)
			(stroke
				(width 0.1524)
				(type default)
			)
			(layer "B.SilkS")
		)
		(fp_line
			(start -0.67945 0.3048)
			(end -0.120396 0.3048)
			(stroke
				(width 0.1)
				(type default)
			)
			(layer "B.Fab")
		)
		(fp_line
			(start -0.120396 0.3048)
			(end -0.120396 0.2794)
			(stroke
				(width 0.1)
				(type default)
			)
			(layer "B.Fab")
		)
		(fp_line
			(start 0.12065 0.3048)
			(end 0.67945 0.3048)
			(stroke
				(width 0.1)
				(type default)
			)
			(layer "B.Fab")
		)
		(fp_line
			(start 0.67945 0.3048)
			(end 0.67945 -0.305054)
			(stroke
				(width 0.1)
				(type default)
			)
			(layer "B.Fab")
		)
		(fp_line
			(start -0.120396 0.2794)
			(end 0.12065 0.2794)
			(stroke
				(width 0.1)
				(type default)
			)
			(layer "B.Fab")
		)
		(fp_line
			(start 0.12065 0.2794)
			(end 0.12065 0.3048)
			(stroke
				(width 0.1)
				(type default)
			)
			(layer "B.Fab")
		)
		(fp_line
			(start -0.12065 -0.2794)
			(end -0.12065 -0.3048)
			(stroke
				(width 0.1)
				(type default)
			)
			(layer "B.Fab")
		)
		(fp_line
			(start 0.12065 -0.2794)
			(end -0.12065 -0.2794)
			(stroke
				(width 0.1)
				(type default)
			)
			(layer "B.Fab")
		)
		(fp_line
			(start -0.67945 -0.3048)
			(end -0.67945 0.3048)
			(stroke
				(width 0.1)
				(type default)
			)
			(layer "B.Fab")
		)
		(fp_line
			(start -0.12065 -0.3048)
			(end -0.67945 -0.3048)
			(stroke
				(width 0.1)
				(type default)
			)
			(layer "B.Fab")
		)
		(fp_line
			(start 0.12065 -0.305054)
			(end 0.12065 -0.2794)
			(stroke
				(width 0.1)
				(type default)
			)
			(layer "B.Fab")
		)
		(fp_line
			(start 0.67945 -0.305054)
			(end 0.12065 -0.305054)
			(stroke
				(width 0.1)
				(type default)
			)
			(layer "B.Fab")
		)
		(pad "1" smd circle
			(at 0.40005 0 90)
			(size 0 0)
			(layers "B.Cu" "B.Mask" "B.Paste")
			(net "GND")
		)
		(pad "2" smd circle
			(at -0.40005 0 90)
			(size 0 0)
			(layers "B.Cu" "B.Mask" "B.Paste")
			(net "PD_CPU0_DMIMODE_OVERRIDE")
		)
	)
	(footprint ""
		(layer "B.Cu")
		(at 369.49888 -43.144948 180)
		(property "Reference" "R2509"
			(at 0 0 0)
			(layer "B.SilkS")
			(hide yes)
			(effects
				(font
					(size 1.27 1.27)
				)
				(justify mirror)
			)
		)
		(property "Value" ""
			(at 0 0 0)
			(layer "B.Fab")
			(effects
				(font
					(size 1.27 1.27)
				)
				(justify mirror)
			)
		)
		(duplicate_pad_numbers_are_jumpers no)
		(fp_line
			(start 0.7874 0.4064)
			(end 0.7874 -0.4064)
			(stroke
				(width 0.1524)
				(type default)
			)
			(layer "B.SilkS")
		)
		(fp_line
			(start 0.7874 -0.4064)
			(end -0.7874 -0.4064)
			(stroke
				(width 0.1524)
				(type default)
			)
			(layer "B.SilkS")
		)
		(fp_line
			(start -0.7874 0.4064)
			(end 0.7874 0.4064)
			(stroke
				(width 0.1524)
				(type default)
			)
			(layer "B.SilkS")
		)
		(fp_line
			(start -0.7874 -0.4064)
			(end -0.7874 0.4064)
			(stroke
				(width 0.1524)
				(type default)
			)
			(layer "B.SilkS")
		)
		(fp_line
			(start 0.67945 0.3048)
			(end 0.67945 -0.305054)
			(stroke
				(width 0.1)
				(type default)
			)
			(layer "B.Fab")
		)
		(fp_line
			(start 0.67945 -0.305054)
			(end 0.12065 -0.305054)
			(stroke
				(width 0.1)
				(type default)
			)
			(layer "B.Fab")
		)
		(fp_line
			(start 0.12065 0.3048)
			(end 0.67945 0.3048)
			(stroke
				(width 0.1)
				(type default)
			)
			(layer "B.Fab")
		)
		(fp_line
			(start 0.12065 0.2794)
			(end 0.12065 0.3048)
			(stroke
				(width 0.1)
				(type default)
			)
			(layer "B.Fab")
		)
		(fp_line
			(start 0.12065 -0.2794)
			(end -0.12065 -0.2794)
			(stroke
				(width 0.1)
				(type default)
			)
			(layer "B.Fab")
		)
		(fp_line
			(start 0.12065 -0.305054)
			(end 0.12065 -0.2794)
			(stroke
				(width 0.1)
				(type default)
			)
			(layer "B.Fab")
		)
		(fp_line
			(start -0.120396 0.3048)
			(end -0.120396 0.2794)
			(stroke
				(width 0.1)
				(type default)
			)
			(layer "B.Fab")
		)
		(fp_line
			(start -0.120396 0.2794)
			(end 0.12065 0.2794)
			(stroke
				(width 0.1)
				(type default)
			)
			(layer "B.Fab")
		)
		(fp_line
			(start -0.12065 -0.2794)
			(end -0.12065 -0.3048)
			(stroke
				(width 0.1)
				(type default)
			)
			(layer "B.Fab")
		)
		(fp_line
			(start -0.12065 -0.3048)
			(end -0.67945 -0.3048)
			(stroke
				(width 0.1)
				(type default)
			)
			(layer "B.Fab")
		)
		(fp_line
			(start -0.67945 0.3048)
			(end -0.120396 0.3048)
			(stroke
				(width 0.1)
				(type default)
			)
			(layer "B.Fab")
		)
		(fp_line
			(start -0.67945 -0.3048)
			(end -0.67945 0.3048)
			(stroke
				(width 0.1)
				(type default)
			)
			(layer "B.Fab")
		)
		(pad "1" smd circle
			(at 0.40005 0)
			(size 0 0)
			(layers "B.Cu" "B.Mask" "B.Paste")
			(net "FM_M2_SSD0_E7_PEDET")
		)
		(pad "2" smd circle
			(at -0.40005 0)
			(size 0 0)
			(layers "B.Cu" "B.Mask" "B.Paste")
			(net "GND")
		)
	)
	(footprint ""
		(layer "B.Cu")
		(at 292.528498 -400.999452 -90)
		(property "Reference" "PR2527"
			(at 0 0 90)
			(layer "B.SilkS")
			(hide yes)
			(effects
				(font
					(size 1.27 1.27)
				)
				(justify mirror)
			)
		)
		(property "Value" ""
			(at 0 0 90)
			(layer "B.Fab")
			(effects
				(font
					(size 1.27 1.27)
				)
				(justify mirror)
			)
		)
		(duplicate_pad_numbers_are_jumpers no)
		(fp_line
			(start -0.7874 0.4064)
			(end 0.7874 0.4064)
			(stroke
				(width 0.1524)
				(type default)
			)
			(layer "B.SilkS")
		)
		(fp_line
			(start 0.7874 0.4064)
			(end 0.7874 -0.4064)
			(stroke
				(width 0.1524)
				(type default)
			)
			(layer "B.SilkS")
		)
		(fp_line
			(start -0.7874 -0.4064)
			(end -0.7874 0.4064)
			(stroke
				(width 0.1524)
				(type default)
			)
			(layer "B.SilkS")
		)
		(fp_line
			(start 0.7874 -0.4064)
			(end -0.7874 -0.4064)
			(stroke
				(width 0.1524)
				(type default)
			)
			(layer "B.SilkS")
		)
		(fp_line
			(start -0.67945 0.3048)
			(end -0.120396 0.3048)
			(stroke
				(width 0.1)
				(type default)
			)
			(layer "B.Fab")
		)
		(fp_line
			(start -0.120396 0.3048)
			(end -0.120396 0.2794)
			(stroke
				(width 0.1)
				(type default)
			)
			(layer "B.Fab")
		)
		(fp_line
			(start 0.12065 0.3048)
			(end 0.67945 0.3048)
			(stroke
				(width 0.1)
				(type default)
			)
			(layer "B.Fab")
		)
		(fp_line
			(start 0.67945 0.3048)
			(end 0.67945 -0.305054)
			(stroke
				(width 0.1)
				(type default)
			)
			(layer "B.Fab")
		)
		(fp_line
			(start -0.120396 0.2794)
			(end 0.12065 0.2794)
			(stroke
				(width 0.1)
				(type default)
			)
			(layer "B.Fab")
		)
		(fp_line
			(start 0.12065 0.2794)
			(end 0.12065 0.3048)
			(stroke
				(width 0.1)
				(type default)
			)
			(layer "B.Fab")
		)
		(fp_line
			(start -0.12065 -0.2794)
			(end -0.12065 -0.3048)
			(stroke
				(width 0.1)
				(type default)
			)
			(layer "B.Fab")
		)
		(fp_line
			(start 0.12065 -0.2794)
			(end -0.12065 -0.2794)
			(stroke
				(width 0.1)
				(type default)
			)
			(layer "B.Fab")
		)
		(fp_line
			(start -0.67945 -0.3048)
			(end -0.67945 0.3048)
			(stroke
				(width 0.1)
				(type default)
			)
			(layer "B.Fab")
		)
		(fp_line
			(start -0.12065 -0.3048)
			(end -0.67945 -0.3048)
			(stroke
				(width 0.1)
				(type default)
			)
			(layer "B.Fab")
		)
		(fp_line
			(start 0.12065 -0.305054)
			(end 0.12065 -0.2794)
			(stroke
				(width 0.1)
				(type default)
			)
			(layer "B.Fab")
		)
		(fp_line
			(start 0.67945 -0.305054)
			(end 0.12065 -0.305054)
			(stroke
				(width 0.1)
				(type default)
			)
			(layer "B.Fab")
		)
		(pad "1" smd circle
			(at 0.40005 0 90)
			(size 0 0)
			(layers "B.Cu" "B.Mask" "B.Paste")
			(net "P12V_HSC_SENSE2_N")
		)
		(pad "2" smd circle
			(at -0.40005 0 90)
			(size 0 0)
			(layers "B.Cu" "B.Mask" "B.Paste")
			(net "P12V_HSC_SENSE2_R4_N")
		)
	)
	(footprint ""
		(layer "B.Cu")
		(at 355.397308 -255.853946 -90)
		(property "Reference" "C362"
			(at 0 0 90)
			(layer "B.SilkS")
			(hide yes)
			(effects
				(font
					(size 1.27 1.27)
				)
				(justify mirror)
			)
		)
		(property "Value" ""
			(at 0 0 90)
			(layer "B.Fab")
			(effects
				(font
					(size 1.27 1.27)
				)
				(justify mirror)
			)
		)
		(duplicate_pad_numbers_are_jumpers no)
		(fp_line
			(start -1.524 0.762)
			(end 1.524 0.762)
			(stroke
				(width 0.1524)
				(type default)
			)
			(layer "B.SilkS")
		)
		(fp_line
			(start 1.524 0.762)
			(end 1.524 -0.762)
			(stroke
				(width 0.1524)
				(type default)
			)
			(layer "B.SilkS")
		)
		(fp_line
			(start -1.524 -0.762)
			(end -1.524 0.762)
			(stroke
				(width 0.1524)
				(type default)
			)
			(layer "B.SilkS")
		)
		(fp_line
			(start 1.524 -0.762)
			(end -1.524 -0.762)
			(stroke
				(width 0.1524)
				(type default)
			)
			(layer "B.SilkS")
		)
		(fp_line
			(start -1.1049 0.724916)
			(end -1.1049 -0.724916)
			(stroke
				(width 0.1)
				(type default)
			)
			(layer "B.Fab")
		)
		(fp_line
			(start 1.1049 0.724916)
			(end -1.1049 0.724916)
			(stroke
				(width 0.1)
				(type default)
			)
			(layer "B.Fab")
		)
		(fp_line
			(start -1.1049 -0.724916)
			(end 1.1049 -0.724916)
			(stroke
				(width 0.1)
				(type default)
			)
			(layer "B.Fab")
		)
		(fp_line
			(start 1.1049 -0.724916)
			(end 1.1049 0.724916)
			(stroke
				(width 0.1)
				(type default)
			)
			(layer "B.Fab")
		)
		(pad "1" smd rect
			(at 0.889 0 270)
			(size 1.016 1.27)
			(layers "B.Cu" "B.Mask" "B.Paste")
			(net "PVCCIN_CPU0")
		)
		(pad "2" smd rect
			(at -0.889 0 270)
			(size 1.016 1.27)
			(layers "B.Cu" "B.Mask" "B.Paste")
			(net "GND")
		)
	)
	(footprint ""
		(layer "B.Cu")
		(at 114.374676 -360.418126 -90)
		(property "Reference" "PR304"
			(at 0 0 90)
			(layer "B.SilkS")
			(hide yes)
			(effects
				(font
					(size 1.27 1.27)
				)
				(justify mirror)
			)
		)
		(property "Value" ""
			(at 0 0 90)
			(layer "B.Fab")
			(effects
				(font
					(size 1.27 1.27)
				)
				(justify mirror)
			)
		)
		(duplicate_pad_numbers_are_jumpers no)
		(fp_line
			(start -0.7874 0.4064)
			(end 0.7874 0.4064)
			(stroke
				(width 0.1524)
				(type default)
			)
			(layer "B.SilkS")
		)
		(fp_line
			(start 0.7874 0.4064)
			(end 0.7874 -0.4064)
			(stroke
				(width 0.1524)
				(type default)
			)
			(layer "B.SilkS")
		)
		(fp_line
			(start -0.7874 -0.4064)
			(end -0.7874 0.4064)
			(stroke
				(width 0.1524)
				(type default)
			)
			(layer "B.SilkS")
		)
		(fp_line
			(start 0.7874 -0.4064)
			(end -0.7874 -0.4064)
			(stroke
				(width 0.1524)
				(type default)
			)
			(layer "B.SilkS")
		)
		(fp_line
			(start -0.67945 0.3048)
			(end -0.120396 0.3048)
			(stroke
				(width 0.1)
				(type default)
			)
			(layer "B.Fab")
		)
		(fp_line
			(start -0.120396 0.3048)
			(end -0.120396 0.2794)
			(stroke
				(width 0.1)
				(type default)
			)
			(layer "B.Fab")
		)
		(fp_line
			(start 0.12065 0.3048)
			(end 0.67945 0.3048)
			(stroke
				(width 0.1)
				(type default)
			)
			(layer "B.Fab")
		)
		(fp_line
			(start 0.67945 0.3048)
			(end 0.67945 -0.305054)
			(stroke
				(width 0.1)
				(type default)
			)
			(layer "B.Fab")
		)
		(fp_line
			(start -0.120396 0.2794)
			(end 0.12065 0.2794)
			(stroke
				(width 0.1)
				(type default)
			)
			(layer "B.Fab")
		)
		(fp_line
			(start 0.12065 0.2794)
			(end 0.12065 0.3048)
			(stroke
				(width 0.1)
				(type default)
			)
			(layer "B.Fab")
		)
		(fp_line
			(start -0.12065 -0.2794)
			(end -0.12065 -0.3048)
			(stroke
				(width 0.1)
				(type default)
			)
			(layer "B.Fab")
		)
		(fp_line
			(start 0.12065 -0.2794)
			(end -0.12065 -0.2794)
			(stroke
				(width 0.1)
				(type default)
			)
			(layer "B.Fab")
		)
		(fp_line
			(start -0.67945 -0.3048)
			(end -0.67945 0.3048)
			(stroke
				(width 0.1)
				(type default)
			)
			(layer "B.Fab")
		)
		(fp_line
			(start -0.12065 -0.3048)
			(end -0.67945 -0.3048)
			(stroke
				(width 0.1)
				(type default)
			)
			(layer "B.Fab")
		)
		(fp_line
			(start 0.12065 -0.305054)
			(end 0.12065 -0.2794)
			(stroke
				(width 0.1)
				(type default)
			)
			(layer "B.Fab")
		)
		(fp_line
			(start 0.67945 -0.305054)
			(end 0.12065 -0.305054)
			(stroke
				(width 0.1)
				(type default)
			)
			(layer "B.Fab")
		)
		(pad "1" smd circle
			(at 0.40005 0 90)
			(size 0 0)
			(layers "B.Cu" "B.Mask" "B.Paste")
			(net "P12V_AUX")
		)
		(pad "2" smd circle
			(at -0.40005 0 90)
			(size 0 0)
			(layers "B.Cu" "B.Mask" "B.Paste")
			(net "PVCCIN_CPU1_CSPIN")
		)
	)
	(footprint ""
		(layer "B.Cu")
		(at 146.3548 -13.772388 90)
		(property "Reference" "R4087"
			(at 0 0 90)
			(layer "B.SilkS")
			(hide yes)
			(effects
				(font
					(size 1.27 1.27)
				)
				(justify mirror)
			)
		)
		(property "Value" ""
			(at 0 0 90)
			(layer "B.Fab")
			(effects
				(font
					(size 1.27 1.27)
				)
				(justify mirror)
			)
		)
		(duplicate_pad_numbers_are_jumpers no)
		(fp_line
			(start 0.7874 -0.4064)
			(end -0.7874 -0.4064)
			(stroke
				(width 0.1524)
				(type default)
			)
			(layer "B.SilkS")
		)
		(fp_line
			(start -0.7874 -0.4064)
			(end -0.7874 0.4064)
			(stroke
				(width 0.1524)
				(type default)
			)
			(layer "B.SilkS")
		)
		(fp_line
			(start 0.7874 0.4064)
			(end 0.7874 -0.4064)
			(stroke
				(width 0.1524)
				(type default)
			)
			(layer "B.SilkS")
		)
		(fp_line
			(start -0.7874 0.4064)
			(end 0.7874 0.4064)
			(stroke
				(width 0.1524)
				(type default)
			)
			(layer "B.SilkS")
		)
		(fp_line
			(start 0.67945 -0.305054)
			(end 0.12065 -0.305054)
			(stroke
				(width 0.1)
				(type default)
			)
			(layer "B.Fab")
		)
		(fp_line
			(start 0.12065 -0.305054)
			(end 0.12065 -0.2794)
			(stroke
				(width 0.1)
				(type default)
			)
			(layer "B.Fab")
		)
		(fp_line
			(start -0.12065 -0.3048)
			(end -0.67945 -0.3048)
			(stroke
				(width 0.1)
				(type default)
			)
			(layer "B.Fab")
		)
		(fp_line
			(start -0.67945 -0.3048)
			(end -0.67945 0.3048)
			(stroke
				(width 0.1)
				(type default)
			)
			(layer "B.Fab")
		)
		(fp_line
			(start 0.12065 -0.2794)
			(end -0.12065 -0.2794)
			(stroke
				(width 0.1)
				(type default)
			)
			(layer "B.Fab")
		)
		(fp_line
			(start -0.12065 -0.2794)
			(end -0.12065 -0.3048)
			(stroke
				(width 0.1)
				(type default)
			)
			(layer "B.Fab")
		)
		(fp_line
			(start 0.12065 0.2794)
			(end 0.12065 0.3048)
			(stroke
				(width 0.1)
				(type default)
			)
			(layer "B.Fab")
		)
		(fp_line
			(start -0.120396 0.2794)
			(end 0.12065 0.2794)
			(stroke
				(width 0.1)
				(type default)
			)
			(layer "B.Fab")
		)
		(fp_line
			(start 0.67945 0.3048)
			(end 0.67945 -0.305054)
			(stroke
				(width 0.1)
				(type default)
			)
			(layer "B.Fab")
		)
		(fp_line
			(start 0.12065 0.3048)
			(end 0.67945 0.3048)
			(stroke
				(width 0.1)
				(type default)
			)
			(layer "B.Fab")
		)
		(fp_line
			(start -0.120396 0.3048)
			(end -0.120396 0.2794)
			(stroke
				(width 0.1)
				(type default)
			)
			(layer "B.Fab")
		)
		(fp_line
			(start -0.67945 0.3048)
			(end -0.120396 0.3048)
			(stroke
				(width 0.1)
				(type default)
			)
			(layer "B.Fab")
		)
		(pad "1" smd circle
			(at 0.40005 0 270)
			(size 0 0)
			(layers "B.Cu" "B.Mask" "B.Paste")
			(net "FM_JTAG_BMC_MUX_SEL_FROM_BMC_R")
		)
		(pad "2" smd circle
			(at -0.40005 0 270)
			(size 0 0)
			(layers "B.Cu" "B.Mask" "B.Paste")
			(net "FM_JTAG_BMC_MUX_SEL_FROM_BMC_R2")
		)
	)
	(footprint ""
		(layer "B.Cu")
		(at 366.120934 -259.531866 90)
		(property "Reference" "C493"
			(at 0 0 90)
			(layer "B.SilkS")
			(hide yes)
			(effects
				(font
					(size 1.27 1.27)
				)
				(justify mirror)
			)
		)
		(property "Value" ""
			(at 0 0 90)
			(layer "B.Fab")
			(effects
				(font
					(size 1.27 1.27)
				)
				(justify mirror)
			)
		)
		(duplicate_pad_numbers_are_jumpers no)
		(fp_line
			(start 1.524 -0.762)
			(end -1.524 -0.762)
			(stroke
				(width 0.1524)
				(type default)
			)
			(layer "B.SilkS")
		)
		(fp_line
			(start -1.524 -0.762)
			(end -1.524 0.762)
			(stroke
				(width 0.1524)
				(type default)
			)
			(layer "B.SilkS")
		)
		(fp_line
			(start 1.524 0.762)
			(end 1.524 -0.762)
			(stroke
				(width 0.1524)
				(type default)
			)
			(layer "B.SilkS")
		)
		(fp_line
			(start -1.524 0.762)
			(end 1.524 0.762)
			(stroke
				(width 0.1524)
				(type default)
			)
			(layer "B.SilkS")
		)
		(fp_line
			(start 1.1049 -0.724916)
			(end 1.1049 0.724916)
			(stroke
				(width 0.1)
				(type default)
			)
			(layer "B.Fab")
		)
		(fp_line
			(start -1.1049 -0.724916)
			(end 1.1049 -0.724916)
			(stroke
				(width 0.1)
				(type default)
			)
			(layer "B.Fab")
		)
		(fp_line
			(start 1.1049 0.724916)
			(end -1.1049 0.724916)
			(stroke
				(width 0.1)
				(type default)
			)
			(layer "B.Fab")
		)
		(fp_line
			(start -1.1049 0.724916)
			(end -1.1049 -0.724916)
			(stroke
				(width 0.1)
				(type default)
			)
			(layer "B.Fab")
		)
		(pad "1" smd rect
			(at 0.889 0 90)
			(size 1.016 1.27)
			(layers "B.Cu" "B.Mask" "B.Paste")
			(net "PVCCFA_EHV_FIVRA_CPU0")
		)
		(pad "2" smd rect
			(at -0.889 0 90)
			(size 1.016 1.27)
			(layers "B.Cu" "B.Mask" "B.Paste")
			(net "GND")
		)
	)
	(footprint ""
		(layer "B.Cu")
		(at 378.711968 -190.795656 -90)
		(property "Reference" "R686"
			(at 0 0 90)
			(layer "B.SilkS")
			(hide yes)
			(effects
				(font
					(size 1.27 1.27)
				)
				(justify mirror)
			)
		)
		(property "Value" ""
			(at 0 0 90)
			(layer "B.Fab")
			(effects
				(font
					(size 1.27 1.27)
				)
				(justify mirror)
			)
		)
		(duplicate_pad_numbers_are_jumpers no)
		(fp_line
			(start -0.7874 0.4064)
			(end 0.7874 0.4064)
			(stroke
				(width 0.1524)
				(type default)
			)
			(layer "B.SilkS")
		)
		(fp_line
			(start 0.7874 0.4064)
			(end 0.7874 -0.4064)
			(stroke
				(width 0.1524)
				(type default)
			)
			(layer "B.SilkS")
		)
		(fp_line
			(start -0.7874 -0.4064)
			(end -0.7874 0.4064)
			(stroke
				(width 0.1524)
				(type default)
			)
			(layer "B.SilkS")
		)
		(fp_line
			(start 0.7874 -0.4064)
			(end -0.7874 -0.4064)
			(stroke
				(width 0.1524)
				(type default)
			)
			(layer "B.SilkS")
		)
		(fp_line
			(start -0.67945 0.3048)
			(end -0.120396 0.3048)
			(stroke
				(width 0.1)
				(type default)
			)
			(layer "B.Fab")
		)
		(fp_line
			(start -0.120396 0.3048)
			(end -0.120396 0.2794)
			(stroke
				(width 0.1)
				(type default)
			)
			(layer "B.Fab")
		)
		(fp_line
			(start 0.12065 0.3048)
			(end 0.67945 0.3048)
			(stroke
				(width 0.1)
				(type default)
			)
			(layer "B.Fab")
		)
		(fp_line
			(start 0.67945 0.3048)
			(end 0.67945 -0.305054)
			(stroke
				(width 0.1)
				(type default)
			)
			(layer "B.Fab")
		)
		(fp_line
			(start -0.120396 0.2794)
			(end 0.12065 0.2794)
			(stroke
				(width 0.1)
				(type default)
			)
			(layer "B.Fab")
		)
		(fp_line
			(start 0.12065 0.2794)
			(end 0.12065 0.3048)
			(stroke
				(width 0.1)
				(type default)
			)
			(layer "B.Fab")
		)
		(fp_line
			(start -0.12065 -0.2794)
			(end -0.12065 -0.3048)
			(stroke
				(width 0.1)
				(type default)
			)
			(layer "B.Fab")
		)
		(fp_line
			(start 0.12065 -0.2794)
			(end -0.12065 -0.2794)
			(stroke
				(width 0.1)
				(type default)
			)
			(layer "B.Fab")
		)
		(fp_line
			(start -0.67945 -0.3048)
			(end -0.67945 0.3048)
			(stroke
				(width 0.1)
				(type default)
			)
			(layer "B.Fab")
		)
		(fp_line
			(start -0.12065 -0.3048)
			(end -0.67945 -0.3048)
			(stroke
				(width 0.1)
				(type default)
			)
			(layer "B.Fab")
		)
		(fp_line
			(start 0.12065 -0.305054)
			(end 0.12065 -0.2794)
			(stroke
				(width 0.1)
				(type default)
			)
			(layer "B.Fab")
		)
		(fp_line
			(start 0.67945 -0.305054)
			(end 0.12065 -0.305054)
			(stroke
				(width 0.1)
				(type default)
			)
			(layer "B.Fab")
		)
		(pad "1" smd circle
			(at 0.40005 0 90)
			(size 0 0)
			(layers "B.Cu" "B.Mask" "B.Paste")
			(net "PVNN_TERM_CPU0")
		)
		(pad "2" smd circle
			(at -0.40005 0 90)
			(size 0 0)
			(layers "B.Cu" "B.Mask" "B.Paste")
			(net "I3C_SPD_DDREFGH_CPU0_SDA")
		)
	)
	(footprint ""
		(layer "B.Cu")
		(at 364.342934 -244.820186 -90)
		(property "Reference" "C379"
			(at 0 0 90)
			(layer "B.SilkS")
			(hide yes)
			(effects
				(font
					(size 1.27 1.27)
				)
				(justify mirror)
			)
		)
		(property "Value" ""
			(at 0 0 90)
			(layer "B.Fab")
			(effects
				(font
					(size 1.27 1.27)
				)
				(justify mirror)
			)
		)
		(duplicate_pad_numbers_are_jumpers no)
		(fp_line
			(start -1.524 0.762)
			(end 1.524 0.762)
			(stroke
				(width 0.1524)
				(type default)
			)
			(layer "B.SilkS")
		)
		(fp_line
			(start 1.524 0.762)
			(end 1.524 -0.762)
			(stroke
				(width 0.1524)
				(type default)
			)
			(layer "B.SilkS")
		)
		(fp_line
			(start -1.524 -0.762)
			(end -1.524 0.762)
			(stroke
				(width 0.1524)
				(type default)
			)
			(layer "B.SilkS")
		)
		(fp_line
			(start 1.524 -0.762)
			(end -1.524 -0.762)
			(stroke
				(width 0.1524)
				(type default)
			)
			(layer "B.SilkS")
		)
		(fp_line
			(start -1.1049 0.724916)
			(end -1.1049 -0.724916)
			(stroke
				(width 0.1)
				(type default)
			)
			(layer "B.Fab")
		)
		(fp_line
			(start 1.1049 0.724916)
			(end -1.1049 0.724916)
			(stroke
				(width 0.1)
				(type default)
			)
			(layer "B.Fab")
		)
		(fp_line
			(start -1.1049 -0.724916)
			(end 1.1049 -0.724916)
			(stroke
				(width 0.1)
				(type default)
			)
			(layer "B.Fab")
		)
		(fp_line
			(start 1.1049 -0.724916)
			(end 1.1049 0.724916)
			(stroke
				(width 0.1)
				(type default)
			)
			(layer "B.Fab")
		)
		(pad "1" smd rect
			(at 0.889 0 270)
			(size 1.016 1.27)
			(layers "B.Cu" "B.Mask" "B.Paste")
			(net "PVCCIN_CPU0")
		)
		(pad "2" smd rect
			(at -0.889 0 270)
			(size 1.016 1.27)
			(layers "B.Cu" "B.Mask" "B.Paste")
			(net "GND")
		)
	)
	(footprint ""
		(layer "B.Cu")
		(at 436.941214 -321.549776 -90)
		(property "Reference" "C42"
			(at 0 0 90)
			(layer "B.SilkS")
			(hide yes)
			(effects
				(font
					(size 1.27 1.27)
				)
				(justify mirror)
			)
		)
		(property "Value" ""
			(at 0 0 90)
			(layer "B.Fab")
			(effects
				(font
					(size 1.27 1.27)
				)
				(justify mirror)
			)
		)
		(duplicate_pad_numbers_are_jumpers no)
		(fp_line
			(start -1.524 0.762)
			(end 1.524 0.762)
			(stroke
				(width 0.1524)
				(type default)
			)
			(layer "B.SilkS")
		)
		(fp_line
			(start 1.524 0.762)
			(end 1.524 -0.762)
			(stroke
				(width 0.1524)
				(type default)
			)
			(layer "B.SilkS")
		)
		(fp_line
			(start -1.524 -0.762)
			(end -1.524 0.762)
			(stroke
				(width 0.1524)
				(type default)
			)
			(layer "B.SilkS")
		)
		(fp_line
			(start 1.524 -0.762)
			(end -1.524 -0.762)
			(stroke
				(width 0.1524)
				(type default)
			)
			(layer "B.SilkS")
		)
		(fp_line
			(start -1.1049 0.724916)
			(end -1.1049 -0.724916)
			(stroke
				(width 0.1)
				(type default)
			)
			(layer "B.Fab")
		)
		(fp_line
			(start 1.1049 0.724916)
			(end -1.1049 0.724916)
			(stroke
				(width 0.1)
				(type default)
			)
			(layer "B.Fab")
		)
		(fp_line
			(start -1.1049 -0.724916)
			(end 1.1049 -0.724916)
			(stroke
				(width 0.1)
				(type default)
			)
			(layer "B.Fab")
		)
		(fp_line
			(start 1.1049 -0.724916)
			(end 1.1049 0.724916)
			(stroke
				(width 0.1)
				(type default)
			)
			(layer "B.Fab")
		)
		(pad "1" smd rect
			(at 0.889 0 270)
			(size 1.016 1.27)
			(layers "B.Cu" "B.Mask" "B.Paste")
			(net "P12V_S3_AUX_CPU0_NVDIMM")
		)
		(pad "2" smd rect
			(at -0.889 0 270)
			(size 1.016 1.27)
			(layers "B.Cu" "B.Mask" "B.Paste")
			(net "GND")
		)
	)
	(footprint ""
		(layer "B.Cu")
		(at 353.610418 -296.054526)
		(property "Reference" "C388"
			(at 0 0 0)
			(layer "B.SilkS")
			(hide yes)
			(effects
				(font
					(size 1.27 1.27)
				)
				(justify mirror)
			)
		)
		(property "Value" ""
			(at 0 0 0)
			(layer "B.Fab")
			(effects
				(font
					(size 1.27 1.27)
				)
				(justify mirror)
			)
		)
		(duplicate_pad_numbers_are_jumpers no)
		(fp_line
			(start -1.524 -0.762)
			(end -1.524 0.762)
			(stroke
				(width 0.1524)
				(type default)
			)
			(layer "B.SilkS")
		)
		(fp_line
			(start -1.524 0.762)
			(end 1.524 0.762)
			(stroke
				(width 0.1524)
				(type default)
			)
			(layer "B.SilkS")
		)
		(fp_line
			(start 1.524 -0.762)
			(end -1.524 -0.762)
			(stroke
				(width 0.1524)
				(type default)
			)
			(layer "B.SilkS")
		)
		(fp_line
			(start 1.524 0.762)
			(end 1.524 -0.762)
			(stroke
				(width 0.1524)
				(type default)
			)
			(layer "B.SilkS")
		)
		(fp_line
			(start -1.1049 -0.724916)
			(end 1.1049 -0.724916)
			(stroke
				(width 0.1)
				(type default)
			)
			(layer "B.Fab")
		)
		(fp_line
			(start -1.1049 0.724916)
			(end -1.1049 -0.724916)
			(stroke
				(width 0.1)
				(type default)
			)
			(layer "B.Fab")
		)
		(fp_line
			(start 1.1049 -0.724916)
			(end 1.1049 0.724916)
			(stroke
				(width 0.1)
				(type default)
			)
			(layer "B.Fab")
		)
		(fp_line
			(start 1.1049 0.724916)
			(end -1.1049 0.724916)
			(stroke
				(width 0.1)
				(type default)
			)
			(layer "B.Fab")
		)
		(pad "1" smd rect
			(at 0.889 0)
			(size 1.016 1.27)
			(layers "B.Cu" "B.Mask" "B.Paste")
			(net "PVCCIN_CPU0")
		)
		(pad "2" smd rect
			(at -0.889 0)
			(size 1.016 1.27)
			(layers "B.Cu" "B.Mask" "B.Paste")
			(net "GND")
		)
	)
	(footprint ""
		(layer "B.Cu")
		(at 423.799762 -134.19709 180)
		(property "Reference" "PR123"
			(at 0 0 0)
			(layer "B.SilkS")
			(hide yes)
			(effects
				(font
					(size 1.27 1.27)
				)
				(justify mirror)
			)
		)
		(property "Value" ""
			(at 0 0 0)
			(layer "B.Fab")
			(effects
				(font
					(size 1.27 1.27)
				)
				(justify mirror)
			)
		)
		(duplicate_pad_numbers_are_jumpers no)
		(fp_line
			(start 0.7874 0.4064)
			(end 0.7874 -0.4064)
			(stroke
				(width 0.1524)
				(type default)
			)
			(layer "B.SilkS")
		)
		(fp_line
			(start 0.7874 -0.4064)
			(end -0.7874 -0.4064)
			(stroke
				(width 0.1524)
				(type default)
			)
			(layer "B.SilkS")
		)
		(fp_line
			(start -0.7874 0.4064)
			(end 0.7874 0.4064)
			(stroke
				(width 0.1524)
				(type default)
			)
			(layer "B.SilkS")
		)
		(fp_line
			(start -0.7874 -0.4064)
			(end -0.7874 0.4064)
			(stroke
				(width 0.1524)
				(type default)
			)
			(layer "B.SilkS")
		)
		(fp_line
			(start 0.67945 0.3048)
			(end 0.67945 -0.305054)
			(stroke
				(width 0.1)
				(type default)
			)
			(layer "B.Fab")
		)
		(fp_line
			(start 0.67945 -0.305054)
			(end 0.12065 -0.305054)
			(stroke
				(width 0.1)
				(type default)
			)
			(layer "B.Fab")
		)
		(fp_line
			(start 0.12065 0.3048)
			(end 0.67945 0.3048)
			(stroke
				(width 0.1)
				(type default)
			)
			(layer "B.Fab")
		)
		(fp_line
			(start 0.12065 0.2794)
			(end 0.12065 0.3048)
			(stroke
				(width 0.1)
				(type default)
			)
			(layer "B.Fab")
		)
		(fp_line
			(start 0.12065 -0.2794)
			(end -0.12065 -0.2794)
			(stroke
				(width 0.1)
				(type default)
			)
			(layer "B.Fab")
		)
		(fp_line
			(start 0.12065 -0.305054)
			(end 0.12065 -0.2794)
			(stroke
				(width 0.1)
				(type default)
			)
			(layer "B.Fab")
		)
		(fp_line
			(start -0.120396 0.3048)
			(end -0.120396 0.2794)
			(stroke
				(width 0.1)
				(type default)
			)
			(layer "B.Fab")
		)
		(fp_line
			(start -0.120396 0.2794)
			(end 0.12065 0.2794)
			(stroke
				(width 0.1)
				(type default)
			)
			(layer "B.Fab")
		)
		(fp_line
			(start -0.12065 -0.2794)
			(end -0.12065 -0.3048)
			(stroke
				(width 0.1)
				(type default)
			)
			(layer "B.Fab")
		)
		(fp_line
			(start -0.12065 -0.3048)
			(end -0.67945 -0.3048)
			(stroke
				(width 0.1)
				(type default)
			)
			(layer "B.Fab")
		)
		(fp_line
			(start -0.67945 0.3048)
			(end -0.120396 0.3048)
			(stroke
				(width 0.1)
				(type default)
			)
			(layer "B.Fab")
		)
		(fp_line
			(start -0.67945 -0.3048)
			(end -0.67945 0.3048)
			(stroke
				(width 0.1)
				(type default)
			)
			(layer "B.Fab")
		)
		(pad "1" smd circle
			(at 0.40005 0)
			(size 0 0)
			(layers "B.Cu" "B.Mask" "B.Paste")
			(net "PVCCINFAON_CPU0_VIN_CSNIN")
		)
		(pad "2" smd circle
			(at -0.40005 0)
			(size 0 0)
			(layers "B.Cu" "B.Mask" "B.Paste")
			(net "GND")
		)
	)
	(footprint ""
		(layer "B.Cu")
		(at 477.827594 -343.149682)
		(property "Reference" "DB11"
			(at 2.502662 -5.374386 270)
			(unlocked yes)
			(layer "B.SilkS")
			(effects
				(font
					(size 0.7874 0.5842)
					(thickness 0.1524)
				)
				(justify left mirror)
			)
		)
		(property "Value" ""
			(at 0 0 0)
			(layer "B.Fab")
			(effects
				(font
					(size 1.27 1.27)
				)
				(justify mirror)
			)
		)
		(duplicate_pad_numbers_are_jumpers no)
		(fp_line
			(start -3.330702 -4.771136)
			(end 0 4.011168)
			(stroke
				(width 0.1524)
				(type default)
			)
			(layer "B.SilkS")
		)
		(fp_line
			(start 0 4.011168)
			(end 3.330702 -4.771136)
			(stroke
				(width 0.1524)
				(type default)
			)
			(layer "B.SilkS")
		)
		(fp_line
			(start 3.330702 -4.771136)
			(end -3.330702 -4.771136)
			(stroke
				(width 0.1524)
				(type default)
			)
			(layer "B.SilkS")
		)
		(fp_line
			(start -3.330702 -4.771136)
			(end 0 4.011168)
			(stroke
				(width 0.1)
				(type default)
			)
			(layer "B.Fab")
		)
		(fp_line
			(start 0 4.011168)
			(end 3.330702 -4.771136)
			(stroke
				(width 0.1)
				(type default)
			)
			(layer "B.Fab")
		)
		(fp_line
			(start 3.330702 -4.771136)
			(end -3.330702 -4.771136)
			(stroke
				(width 0.1)
				(type default)
			)
			(layer "B.Fab")
		)
		(pad "1" thru_hole circle
			(at 0 0 180)
			(size 2.159 2.159)
			(drill 1.7018)
			(layers "*.Cu" "*.Mask")
			(remove_unused_layers no)
			(net "T1_GND")
			(clearance 0.0254)
			(thermal_gap 0.0254)
		)
		(pad "2" thru_hole circle
			(at 1.27 -3.348736 180)
			(size 2.159 2.159)
			(drill 1.7018)
			(layers "*.Cu" "*.Mask")
			(remove_unused_layers no)
			(net "TDR_SE_50_OHM_IN4")
			(clearance 0.0254)
			(thermal_gap 0.0254)
		)
		(pad "3" thru_hole circle
			(at -1.27 -3.348736 180)
			(size 2.159 2.159)
			(drill 1.7018)
			(layers "*.Cu" "*.Mask")
			(remove_unused_layers no)
			(net "TDR_SE_50_OHM_IN4")
			(clearance 0.0254)
			(thermal_gap 0.0254)
		)
	)
	(footprint ""
		(layer "B.Cu")
		(at 80.763618 -190.83401 90)
		(property "Reference" "R51"
			(at 0 0 90)
			(layer "B.SilkS")
			(hide yes)
			(effects
				(font
					(size 1.27 1.27)
				)
				(justify mirror)
			)
		)
		(property "Value" ""
			(at 0 0 90)
			(layer "B.Fab")
			(effects
				(font
					(size 1.27 1.27)
				)
				(justify mirror)
			)
		)
		(duplicate_pad_numbers_are_jumpers no)
		(fp_line
			(start 0.7874 -0.4064)
			(end -0.7874 -0.4064)
			(stroke
				(width 0.1524)
				(type default)
			)
			(layer "B.SilkS")
		)
		(fp_line
			(start -0.7874 -0.4064)
			(end -0.7874 0.4064)
			(stroke
				(width 0.1524)
				(type default)
			)
			(layer "B.SilkS")
		)
		(fp_line
			(start 0.7874 0.4064)
			(end 0.7874 -0.4064)
			(stroke
				(width 0.1524)
				(type default)
			)
			(layer "B.SilkS")
		)
		(fp_line
			(start -0.7874 0.4064)
			(end 0.7874 0.4064)
			(stroke
				(width 0.1524)
				(type default)
			)
			(layer "B.SilkS")
		)
		(fp_line
			(start 0.67945 -0.305054)
			(end 0.12065 -0.305054)
			(stroke
				(width 0.1)
				(type default)
			)
			(layer "B.Fab")
		)
		(fp_line
			(start 0.12065 -0.305054)
			(end 0.12065 -0.2794)
			(stroke
				(width 0.1)
				(type default)
			)
			(layer "B.Fab")
		)
		(fp_line
			(start -0.12065 -0.3048)
			(end -0.67945 -0.3048)
			(stroke
				(width 0.1)
				(type default)
			)
			(layer "B.Fab")
		)
		(fp_line
			(start -0.67945 -0.3048)
			(end -0.67945 0.3048)
			(stroke
				(width 0.1)
				(type default)
			)
			(layer "B.Fab")
		)
		(fp_line
			(start 0.12065 -0.2794)
			(end -0.12065 -0.2794)
			(stroke
				(width 0.1)
				(type default)
			)
			(layer "B.Fab")
		)
		(fp_line
			(start -0.12065 -0.2794)
			(end -0.12065 -0.3048)
			(stroke
				(width 0.1)
				(type default)
			)
			(layer "B.Fab")
		)
		(fp_line
			(start 0.12065 0.2794)
			(end 0.12065 0.3048)
			(stroke
				(width 0.1)
				(type default)
			)
			(layer "B.Fab")
		)
		(fp_line
			(start -0.120396 0.2794)
			(end 0.12065 0.2794)
			(stroke
				(width 0.1)
				(type default)
			)
			(layer "B.Fab")
		)
		(fp_line
			(start 0.67945 0.3048)
			(end 0.67945 -0.305054)
			(stroke
				(width 0.1)
				(type default)
			)
			(layer "B.Fab")
		)
		(fp_line
			(start 0.12065 0.3048)
			(end 0.67945 0.3048)
			(stroke
				(width 0.1)
				(type default)
			)
			(layer "B.Fab")
		)
		(fp_line
			(start -0.120396 0.3048)
			(end -0.120396 0.2794)
			(stroke
				(width 0.1)
				(type default)
			)
			(layer "B.Fab")
		)
		(fp_line
			(start -0.67945 0.3048)
			(end -0.120396 0.3048)
			(stroke
				(width 0.1)
				(type default)
			)
			(layer "B.Fab")
		)
		(pad "1" smd circle
			(at 0.40005 0 270)
			(size 0 0)
			(layers "B.Cu" "B.Mask" "B.Paste")
			(net "DBP_CPU1_MBP0_GTL_R_N")
		)
		(pad "2" smd circle
			(at -0.40005 0 270)
			(size 0 0)
			(layers "B.Cu" "B.Mask" "B.Paste")
			(net "DBP_CPU_MBP0_GTL_N")
		)
	)
	(footprint ""
		(layer "B.Cu")
		(at 353.619308 -252.176026 -90)
		(property "Reference" "C368"
			(at 0 0 90)
			(layer "B.SilkS")
			(hide yes)
			(effects
				(font
					(size 1.27 1.27)
				)
				(justify mirror)
			)
		)
		(property "Value" ""
			(at 0 0 90)
			(layer "B.Fab")
			(effects
				(font
					(size 1.27 1.27)
				)
				(justify mirror)
			)
		)
		(duplicate_pad_numbers_are_jumpers no)
		(fp_line
			(start -1.524 0.762)
			(end 1.524 0.762)
			(stroke
				(width 0.1524)
				(type default)
			)
			(layer "B.SilkS")
		)
		(fp_line
			(start 1.524 0.762)
			(end 1.524 -0.762)
			(stroke
				(width 0.1524)
				(type default)
			)
			(layer "B.SilkS")
		)
		(fp_line
			(start -1.524 -0.762)
			(end -1.524 0.762)
			(stroke
				(width 0.1524)
				(type default)
			)
			(layer "B.SilkS")
		)
		(fp_line
			(start 1.524 -0.762)
			(end -1.524 -0.762)
			(stroke
				(width 0.1524)
				(type default)
			)
			(layer "B.SilkS")
		)
		(fp_line
			(start -1.1049 0.724916)
			(end -1.1049 -0.724916)
			(stroke
				(width 0.1)
				(type default)
			)
			(layer "B.Fab")
		)
		(fp_line
			(start 1.1049 0.724916)
			(end -1.1049 0.724916)
			(stroke
				(width 0.1)
				(type default)
			)
			(layer "B.Fab")
		)
		(fp_line
			(start -1.1049 -0.724916)
			(end 1.1049 -0.724916)
			(stroke
				(width 0.1)
				(type default)
			)
			(layer "B.Fab")
		)
		(fp_line
			(start 1.1049 -0.724916)
			(end 1.1049 0.724916)
			(stroke
				(width 0.1)
				(type default)
			)
			(layer "B.Fab")
		)
		(pad "1" smd rect
			(at 0.889 0 270)
			(size 1.016 1.27)
			(layers "B.Cu" "B.Mask" "B.Paste")
			(net "PVCCIN_CPU0")
		)
		(pad "2" smd rect
			(at -0.889 0 270)
			(size 1.016 1.27)
			(layers "B.Cu" "B.Mask" "B.Paste")
			(net "GND")
		)
	)
	(footprint ""
		(layer "B.Cu")
		(at 154.26436 -224.814638 -90)
		(property "Reference" "R11"
			(at 0 0 90)
			(layer "B.SilkS")
			(hide yes)
			(effects
				(font
					(size 1.27 1.27)
				)
				(justify mirror)
			)
		)
		(property "Value" ""
			(at 0 0 90)
			(layer "B.Fab")
			(effects
				(font
					(size 1.27 1.27)
				)
				(justify mirror)
			)
		)
		(duplicate_pad_numbers_are_jumpers no)
		(fp_line
			(start -0.7874 0.4064)
			(end 0.7874 0.4064)
			(stroke
				(width 0.1524)
				(type default)
			)
			(layer "B.SilkS")
		)
		(fp_line
			(start 0.7874 0.4064)
			(end 0.7874 -0.4064)
			(stroke
				(width 0.1524)
				(type default)
			)
			(layer "B.SilkS")
		)
		(fp_line
			(start -0.7874 -0.4064)
			(end -0.7874 0.4064)
			(stroke
				(width 0.1524)
				(type default)
			)
			(layer "B.SilkS")
		)
		(fp_line
			(start 0.7874 -0.4064)
			(end -0.7874 -0.4064)
			(stroke
				(width 0.1524)
				(type default)
			)
			(layer "B.SilkS")
		)
		(fp_line
			(start -0.67945 0.3048)
			(end -0.120396 0.3048)
			(stroke
				(width 0.1)
				(type default)
			)
			(layer "B.Fab")
		)
		(fp_line
			(start -0.120396 0.3048)
			(end -0.120396 0.2794)
			(stroke
				(width 0.1)
				(type default)
			)
			(layer "B.Fab")
		)
		(fp_line
			(start 0.12065 0.3048)
			(end 0.67945 0.3048)
			(stroke
				(width 0.1)
				(type default)
			)
			(layer "B.Fab")
		)
		(fp_line
			(start 0.67945 0.3048)
			(end 0.67945 -0.305054)
			(stroke
				(width 0.1)
				(type default)
			)
			(layer "B.Fab")
		)
		(fp_line
			(start -0.120396 0.2794)
			(end 0.12065 0.2794)
			(stroke
				(width 0.1)
				(type default)
			)
			(layer "B.Fab")
		)
		(fp_line
			(start 0.12065 0.2794)
			(end 0.12065 0.3048)
			(stroke
				(width 0.1)
				(type default)
			)
			(layer "B.Fab")
		)
		(fp_line
			(start -0.12065 -0.2794)
			(end -0.12065 -0.3048)
			(stroke
				(width 0.1)
				(type default)
			)
			(layer "B.Fab")
		)
		(fp_line
			(start 0.12065 -0.2794)
			(end -0.12065 -0.2794)
			(stroke
				(width 0.1)
				(type default)
			)
			(layer "B.Fab")
		)
		(fp_line
			(start -0.67945 -0.3048)
			(end -0.67945 0.3048)
			(stroke
				(width 0.1)
				(type default)
			)
			(layer "B.Fab")
		)
		(fp_line
			(start -0.12065 -0.3048)
			(end -0.67945 -0.3048)
			(stroke
				(width 0.1)
				(type default)
			)
			(layer "B.Fab")
		)
		(fp_line
			(start 0.12065 -0.305054)
			(end 0.12065 -0.2794)
			(stroke
				(width 0.1)
				(type default)
			)
			(layer "B.Fab")
		)
		(fp_line
			(start 0.67945 -0.305054)
			(end 0.12065 -0.305054)
			(stroke
				(width 0.1)
				(type default)
			)
			(layer "B.Fab")
		)
		(pad "1" smd circle
			(at 0.40005 0 90)
			(size 0 0)
			(layers "B.Cu" "B.Mask" "B.Paste")
			(net "H_CPU0_PMDOWN_CPU1_R1")
		)
		(pad "2" smd circle
			(at -0.40005 0 90)
			(size 0 0)
			(layers "B.Cu" "B.Mask" "B.Paste")
			(net "H_CPU0_PMDOWN_CPU1")
		)
	)
	(footprint ""
		(layer "B.Cu")
		(at 149.8854 -14.823948 -90)
		(property "Reference" "R4629"
			(at 0 0 90)
			(layer "B.SilkS")
			(hide yes)
			(effects
				(font
					(size 1.27 1.27)
				)
				(justify mirror)
			)
		)
		(property "Value" ""
			(at 0 0 90)
			(layer "B.Fab")
			(effects
				(font
					(size 1.27 1.27)
				)
				(justify mirror)
			)
		)
		(duplicate_pad_numbers_are_jumpers no)
		(fp_line
			(start -0.7874 0.4064)
			(end 0.7874 0.4064)
			(stroke
				(width 0.1524)
				(type default)
			)
			(layer "B.SilkS")
		)
		(fp_line
			(start 0.7874 0.4064)
			(end 0.7874 -0.4064)
			(stroke
				(width 0.1524)
				(type default)
			)
			(layer "B.SilkS")
		)
		(fp_line
			(start -0.7874 -0.4064)
			(end -0.7874 0.4064)
			(stroke
				(width 0.1524)
				(type default)
			)
			(layer "B.SilkS")
		)
		(fp_line
			(start 0.7874 -0.4064)
			(end -0.7874 -0.4064)
			(stroke
				(width 0.1524)
				(type default)
			)
			(layer "B.SilkS")
		)
		(fp_line
			(start -0.67945 0.3048)
			(end -0.120396 0.3048)
			(stroke
				(width 0.1)
				(type default)
			)
			(layer "B.Fab")
		)
		(fp_line
			(start -0.120396 0.3048)
			(end -0.120396 0.2794)
			(stroke
				(width 0.1)
				(type default)
			)
			(layer "B.Fab")
		)
		(fp_line
			(start 0.12065 0.3048)
			(end 0.67945 0.3048)
			(stroke
				(width 0.1)
				(type default)
			)
			(layer "B.Fab")
		)
		(fp_line
			(start 0.67945 0.3048)
			(end 0.67945 -0.305054)
			(stroke
				(width 0.1)
				(type default)
			)
			(layer "B.Fab")
		)
		(fp_line
			(start -0.120396 0.2794)
			(end 0.12065 0.2794)
			(stroke
				(width 0.1)
				(type default)
			)
			(layer "B.Fab")
		)
		(fp_line
			(start 0.12065 0.2794)
			(end 0.12065 0.3048)
			(stroke
				(width 0.1)
				(type default)
			)
			(layer "B.Fab")
		)
		(fp_line
			(start -0.12065 -0.2794)
			(end -0.12065 -0.3048)
			(stroke
				(width 0.1)
				(type default)
			)
			(layer "B.Fab")
		)
		(fp_line
			(start 0.12065 -0.2794)
			(end -0.12065 -0.2794)
			(stroke
				(width 0.1)
				(type default)
			)
			(layer "B.Fab")
		)
		(fp_line
			(start -0.67945 -0.3048)
			(end -0.67945 0.3048)
			(stroke
				(width 0.1)
				(type default)
			)
			(layer "B.Fab")
		)
		(fp_line
			(start -0.12065 -0.3048)
			(end -0.67945 -0.3048)
			(stroke
				(width 0.1)
				(type default)
			)
			(layer "B.Fab")
		)
		(fp_line
			(start 0.12065 -0.305054)
			(end 0.12065 -0.2794)
			(stroke
				(width 0.1)
				(type default)
			)
			(layer "B.Fab")
		)
		(fp_line
			(start 0.67945 -0.305054)
			(end 0.12065 -0.305054)
			(stroke
				(width 0.1)
				(type default)
			)
			(layer "B.Fab")
		)
		(pad "1" smd circle
			(at 0.40005 0 90)
			(size 0 0)
			(layers "B.Cu" "B.Mask" "B.Paste")
			(net "JTAG_BMC_TCK")
		)
		(pad "2" smd circle
			(at -0.40005 0 90)
			(size 0 0)
			(layers "B.Cu" "B.Mask" "B.Paste")
			(net "JTAG_BMC_TCK_R")
		)
	)
	(footprint ""
		(layer "B.Cu")
		(at 53.912516 -162.717226)
		(property "Reference" "PR200"
			(at 0 0 0)
			(layer "B.SilkS")
			(hide yes)
			(effects
				(font
					(size 1.27 1.27)
				)
				(justify mirror)
			)
		)
		(property "Value" ""
			(at 0 0 0)
			(layer "B.Fab")
			(effects
				(font
					(size 1.27 1.27)
				)
				(justify mirror)
			)
		)
		(duplicate_pad_numbers_are_jumpers no)
		(fp_line
			(start -0.7874 -0.4064)
			(end -0.7874 0.4064)
			(stroke
				(width 0.1524)
				(type default)
			)
			(layer "B.SilkS")
		)
		(fp_line
			(start -0.7874 0.4064)
			(end 0.7874 0.4064)
			(stroke
				(width 0.1524)
				(type default)
			)
			(layer "B.SilkS")
		)
		(fp_line
			(start 0.7874 -0.4064)
			(end -0.7874 -0.4064)
			(stroke
				(width 0.1524)
				(type default)
			)
			(layer "B.SilkS")
		)
		(fp_line
			(start 0.7874 0.4064)
			(end 0.7874 -0.4064)
			(stroke
				(width 0.1524)
				(type default)
			)
			(layer "B.SilkS")
		)
		(fp_line
			(start -0.67945 -0.3048)
			(end -0.67945 0.3048)
			(stroke
				(width 0.1)
				(type default)
			)
			(layer "B.Fab")
		)
		(fp_line
			(start -0.67945 0.3048)
			(end -0.120396 0.3048)
			(stroke
				(width 0.1)
				(type default)
			)
			(layer "B.Fab")
		)
		(fp_line
			(start -0.12065 -0.3048)
			(end -0.67945 -0.3048)
			(stroke
				(width 0.1)
				(type default)
			)
			(layer "B.Fab")
		)
		(fp_line
			(start -0.12065 -0.2794)
			(end -0.12065 -0.3048)
			(stroke
				(width 0.1)
				(type default)
			)
			(layer "B.Fab")
		)
		(fp_line
			(start -0.120396 0.2794)
			(end 0.12065 0.2794)
			(stroke
				(width 0.1)
				(type default)
			)
			(layer "B.Fab")
		)
		(fp_line
			(start -0.120396 0.3048)
			(end -0.120396 0.2794)
			(stroke
				(width 0.1)
				(type default)
			)
			(layer "B.Fab")
		)
		(fp_line
			(start 0.12065 -0.305054)
			(end 0.12065 -0.2794)
			(stroke
				(width 0.1)
				(type default)
			)
			(layer "B.Fab")
		)
		(fp_line
			(start 0.12065 -0.2794)
			(end -0.12065 -0.2794)
			(stroke
				(width 0.1)
				(type default)
			)
			(layer "B.Fab")
		)
		(fp_line
			(start 0.12065 0.2794)
			(end 0.12065 0.3048)
			(stroke
				(width 0.1)
				(type default)
			)
			(layer "B.Fab")
		)
		(fp_line
			(start 0.12065 0.3048)
			(end 0.67945 0.3048)
			(stroke
				(width 0.1)
				(type default)
			)
			(layer "B.Fab")
		)
		(fp_line
			(start 0.67945 -0.305054)
			(end 0.12065 -0.305054)
			(stroke
				(width 0.1)
				(type default)
			)
			(layer "B.Fab")
		)
		(fp_line
			(start 0.67945 0.3048)
			(end 0.67945 -0.305054)
			(stroke
				(width 0.1)
				(type default)
			)
			(layer "B.Fab")
		)
		(pad "1" smd circle
			(at 0.40005 0 180)
			(size 0 0)
			(layers "B.Cu" "B.Mask" "B.Paste")
			(net "PVCCFA_EHV_CPU1_PVCC")
		)
		(pad "2" smd circle
			(at -0.40005 0 180)
			(size 0 0)
			(layers "B.Cu" "B.Mask" "B.Paste")
			(net "PVCCD_HV_CPU1_VDD1")
		)
	)
	(footprint ""
		(layer "B.Cu")
		(at 111.31677 -409.467558 90)
		(property "Reference" "C2328"
			(at 0 0 90)
			(layer "B.SilkS")
			(hide yes)
			(effects
				(font
					(size 1.27 1.27)
				)
				(justify mirror)
			)
		)
		(property "Value" ""
			(at 0 0 90)
			(layer "B.Fab")
			(effects
				(font
					(size 1.27 1.27)
				)
				(justify mirror)
			)
		)
		(duplicate_pad_numbers_are_jumpers no)
		(fp_line
			(start 1.2954 -0.5842)
			(end -1.2954 -0.5842)
			(stroke
				(width 0.1524)
				(type default)
			)
			(layer "B.SilkS")
		)
		(fp_line
			(start 0 -0.5842)
			(end 0 0.5842)
			(stroke
				(width 0.1524)
				(type default)
			)
			(layer "B.SilkS")
		)
		(fp_line
			(start -1.2954 -0.5842)
			(end -1.2954 0.5842)
			(stroke
				(width 0.1524)
				(type default)
			)
			(layer "B.SilkS")
		)
		(fp_line
			(start 1.2954 0.5842)
			(end 1.2954 -0.5842)
			(stroke
				(width 0.1524)
				(type default)
			)
			(layer "B.SilkS")
		)
		(fp_line
			(start -1.2954 0.5842)
			(end 1.2954 0.5842)
			(stroke
				(width 0.1524)
				(type default)
			)
			(layer "B.SilkS")
		)
		(fp_line
			(start 0.8636 -0.4572)
			(end -0.8636 -0.4572)
			(stroke
				(width 0.1)
				(type default)
			)
			(layer "B.Fab")
		)
		(fp_line
			(start -0.8636 -0.4572)
			(end -0.8636 -0.4064)
			(stroke
				(width 0.1)
				(type default)
			)
			(layer "B.Fab")
		)
		(fp_line
			(start 1.1938 -0.4064)
			(end 0.8636 -0.4064)
			(stroke
				(width 0.1)
				(type default)
			)
			(layer "B.Fab")
		)
		(fp_line
			(start 0.8636 -0.4064)
			(end 0.8636 -0.4572)
			(stroke
				(width 0.1)
				(type default)
			)
			(layer "B.Fab")
		)
		(fp_line
			(start -0.8636 -0.4064)
			(end -1.1938 -0.4064)
			(stroke
				(width 0.1)
				(type default)
			)
			(layer "B.Fab")
		)
		(fp_line
			(start -1.1938 -0.4064)
			(end -1.1938 0.4064)
			(stroke
				(width 0.1)
				(type default)
			)
			(layer "B.Fab")
		)
		(fp_line
			(start 1.1938 0.4064)
			(end 1.1938 -0.4064)
			(stroke
				(width 0.1)
				(type default)
			)
			(layer "B.Fab")
		)
		(fp_line
			(start 0.8636 0.4064)
			(end 1.1938 0.4064)
			(stroke
				(width 0.1)
				(type default)
			)
			(layer "B.Fab")
		)
		(fp_line
			(start -0.8636 0.4064)
			(end -0.8636 0.4572)
			(stroke
				(width 0.1)
				(type default)
			)
			(layer "B.Fab")
		)
		(fp_line
			(start -1.1938 0.4064)
			(end -0.8636 0.4064)
			(stroke
				(width 0.1)
				(type default)
			)
			(layer "B.Fab")
		)
		(fp_line
			(start 0.8636 0.4572)
			(end 0.8636 0.4064)
			(stroke
				(width 0.1)
				(type default)
			)
			(layer "B.Fab")
		)
		(fp_line
			(start -0.8636 0.4572)
			(end 0.8636 0.4572)
			(stroke
				(width 0.1)
				(type default)
			)
			(layer "B.Fab")
		)
		(pad "1" smd rect
			(at 0.7366 0)
			(size 0.7112 0.8128)
			(layers "B.Cu" "B.Mask" "B.Paste")
			(net "P3V3_9ZXL045_VDD")
		)
		(pad "2" smd rect
			(at -0.7366 0)
			(size 0.7112 0.8128)
			(layers "B.Cu" "B.Mask" "B.Paste")
			(net "GND")
		)
	)
	(footprint ""
		(layer "B.Cu")
		(at 406.766014 -321.549776 -90)
		(property "Reference" "C31"
			(at 0 0 90)
			(layer "B.SilkS")
			(hide yes)
			(effects
				(font
					(size 1.27 1.27)
				)
				(justify mirror)
			)
		)
		(property "Value" ""
			(at 0 0 90)
			(layer "B.Fab")
			(effects
				(font
					(size 1.27 1.27)
				)
				(justify mirror)
			)
		)
		(duplicate_pad_numbers_are_jumpers no)
		(fp_line
			(start -1.524 0.762)
			(end 1.524 0.762)
			(stroke
				(width 0.1524)
				(type default)
			)
			(layer "B.SilkS")
		)
		(fp_line
			(start 1.524 0.762)
			(end 1.524 -0.762)
			(stroke
				(width 0.1524)
				(type default)
			)
			(layer "B.SilkS")
		)
		(fp_line
			(start -1.524 -0.762)
			(end -1.524 0.762)
			(stroke
				(width 0.1524)
				(type default)
			)
			(layer "B.SilkS")
		)
		(fp_line
			(start 1.524 -0.762)
			(end -1.524 -0.762)
			(stroke
				(width 0.1524)
				(type default)
			)
			(layer "B.SilkS")
		)
		(fp_line
			(start -1.1049 0.724916)
			(end -1.1049 -0.724916)
			(stroke
				(width 0.1)
				(type default)
			)
			(layer "B.Fab")
		)
		(fp_line
			(start 1.1049 0.724916)
			(end -1.1049 0.724916)
			(stroke
				(width 0.1)
				(type default)
			)
			(layer "B.Fab")
		)
		(fp_line
			(start -1.1049 -0.724916)
			(end 1.1049 -0.724916)
			(stroke
				(width 0.1)
				(type default)
			)
			(layer "B.Fab")
		)
		(fp_line
			(start 1.1049 -0.724916)
			(end 1.1049 0.724916)
			(stroke
				(width 0.1)
				(type default)
			)
			(layer "B.Fab")
		)
		(pad "1" smd rect
			(at 0.889 0 270)
			(size 1.016 1.27)
			(layers "B.Cu" "B.Mask" "B.Paste")
			(net "P12V_S3_AUX_CPU0_NVDIMM")
		)
		(pad "2" smd rect
			(at -0.889 0 270)
			(size 1.016 1.27)
			(layers "B.Cu" "B.Mask" "B.Paste")
			(net "GND")
		)
	)
	(footprint ""
		(layer "B.Cu")
		(at 180.814218 -13.772388 90)
		(property "Reference" "R2421"
			(at 0 0 90)
			(layer "B.SilkS")
			(hide yes)
			(effects
				(font
					(size 1.27 1.27)
				)
				(justify mirror)
			)
		)
		(property "Value" ""
			(at 0 0 90)
			(layer "B.Fab")
			(effects
				(font
					(size 1.27 1.27)
				)
				(justify mirror)
			)
		)
		(duplicate_pad_numbers_are_jumpers no)
		(fp_line
			(start 0.7874 -0.4064)
			(end -0.7874 -0.4064)
			(stroke
				(width 0.1524)
				(type default)
			)
			(layer "B.SilkS")
		)
		(fp_line
			(start -0.7874 -0.4064)
			(end -0.7874 0.4064)
			(stroke
				(width 0.1524)
				(type default)
			)
			(layer "B.SilkS")
		)
		(fp_line
			(start 0.7874 0.4064)
			(end 0.7874 -0.4064)
			(stroke
				(width 0.1524)
				(type default)
			)
			(layer "B.SilkS")
		)
		(fp_line
			(start -0.7874 0.4064)
			(end 0.7874 0.4064)
			(stroke
				(width 0.1524)
				(type default)
			)
			(layer "B.SilkS")
		)
		(fp_line
			(start 0.67945 -0.305054)
			(end 0.12065 -0.305054)
			(stroke
				(width 0.1)
				(type default)
			)
			(layer "B.Fab")
		)
		(fp_line
			(start 0.12065 -0.305054)
			(end 0.12065 -0.2794)
			(stroke
				(width 0.1)
				(type default)
			)
			(layer "B.Fab")
		)
		(fp_line
			(start -0.12065 -0.3048)
			(end -0.67945 -0.3048)
			(stroke
				(width 0.1)
				(type default)
			)
			(layer "B.Fab")
		)
		(fp_line
			(start -0.67945 -0.3048)
			(end -0.67945 0.3048)
			(stroke
				(width 0.1)
				(type default)
			)
			(layer "B.Fab")
		)
		(fp_line
			(start 0.12065 -0.2794)
			(end -0.12065 -0.2794)
			(stroke
				(width 0.1)
				(type default)
			)
			(layer "B.Fab")
		)
		(fp_line
			(start -0.12065 -0.2794)
			(end -0.12065 -0.3048)
			(stroke
				(width 0.1)
				(type default)
			)
			(layer "B.Fab")
		)
		(fp_line
			(start 0.12065 0.2794)
			(end 0.12065 0.3048)
			(stroke
				(width 0.1)
				(type default)
			)
			(layer "B.Fab")
		)
		(fp_line
			(start -0.120396 0.2794)
			(end 0.12065 0.2794)
			(stroke
				(width 0.1)
				(type default)
			)
			(layer "B.Fab")
		)
		(fp_line
			(start 0.67945 0.3048)
			(end 0.67945 -0.305054)
			(stroke
				(width 0.1)
				(type default)
			)
			(layer "B.Fab")
		)
		(fp_line
			(start 0.12065 0.3048)
			(end 0.67945 0.3048)
			(stroke
				(width 0.1)
				(type default)
			)
			(layer "B.Fab")
		)
		(fp_line
			(start -0.120396 0.3048)
			(end -0.120396 0.2794)
			(stroke
				(width 0.1)
				(type default)
			)
			(layer "B.Fab")
		)
		(fp_line
			(start -0.67945 0.3048)
			(end -0.120396 0.3048)
			(stroke
				(width 0.1)
				(type default)
			)
			(layer "B.Fab")
		)
		(pad "1" smd circle
			(at 0.40005 0 270)
			(size 0 0)
			(layers "B.Cu" "B.Mask" "B.Paste")
			(net "SMB_VR_SENSOR_3V3AUX_SCL")
		)
		(pad "2" smd circle
			(at -0.40005 0 270)
			(size 0 0)
			(layers "B.Cu" "B.Mask" "B.Paste")
			(net "SMB_VR_3V3AUX_SCL_R0")
		)
	)
	(footprint ""
		(layer "B.Cu")
		(at 179.729638 -13.762228 90)
		(property "Reference" "R2422"
			(at 0 0 90)
			(layer "B.SilkS")
			(hide yes)
			(effects
				(font
					(size 1.27 1.27)
				)
				(justify mirror)
			)
		)
		(property "Value" ""
			(at 0 0 90)
			(layer "B.Fab")
			(effects
				(font
					(size 1.27 1.27)
				)
				(justify mirror)
			)
		)
		(duplicate_pad_numbers_are_jumpers no)
		(fp_line
			(start 0.7874 -0.4064)
			(end -0.7874 -0.4064)
			(stroke
				(width 0.1524)
				(type default)
			)
			(layer "B.SilkS")
		)
		(fp_line
			(start -0.7874 -0.4064)
			(end -0.7874 0.4064)
			(stroke
				(width 0.1524)
				(type default)
			)
			(layer "B.SilkS")
		)
		(fp_line
			(start 0.7874 0.4064)
			(end 0.7874 -0.4064)
			(stroke
				(width 0.1524)
				(type default)
			)
			(layer "B.SilkS")
		)
		(fp_line
			(start -0.7874 0.4064)
			(end 0.7874 0.4064)
			(stroke
				(width 0.1524)
				(type default)
			)
			(layer "B.SilkS")
		)
		(fp_line
			(start 0.67945 -0.305054)
			(end 0.12065 -0.305054)
			(stroke
				(width 0.1)
				(type default)
			)
			(layer "B.Fab")
		)
		(fp_line
			(start 0.12065 -0.305054)
			(end 0.12065 -0.2794)
			(stroke
				(width 0.1)
				(type default)
			)
			(layer "B.Fab")
		)
		(fp_line
			(start -0.12065 -0.3048)
			(end -0.67945 -0.3048)
			(stroke
				(width 0.1)
				(type default)
			)
			(layer "B.Fab")
		)
		(fp_line
			(start -0.67945 -0.3048)
			(end -0.67945 0.3048)
			(stroke
				(width 0.1)
				(type default)
			)
			(layer "B.Fab")
		)
		(fp_line
			(start 0.12065 -0.2794)
			(end -0.12065 -0.2794)
			(stroke
				(width 0.1)
				(type default)
			)
			(layer "B.Fab")
		)
		(fp_line
			(start -0.12065 -0.2794)
			(end -0.12065 -0.3048)
			(stroke
				(width 0.1)
				(type default)
			)
			(layer "B.Fab")
		)
		(fp_line
			(start 0.12065 0.2794)
			(end 0.12065 0.3048)
			(stroke
				(width 0.1)
				(type default)
			)
			(layer "B.Fab")
		)
		(fp_line
			(start -0.120396 0.2794)
			(end 0.12065 0.2794)
			(stroke
				(width 0.1)
				(type default)
			)
			(layer "B.Fab")
		)
		(fp_line
			(start 0.67945 0.3048)
			(end 0.67945 -0.305054)
			(stroke
				(width 0.1)
				(type default)
			)
			(layer "B.Fab")
		)
		(fp_line
			(start 0.12065 0.3048)
			(end 0.67945 0.3048)
			(stroke
				(width 0.1)
				(type default)
			)
			(layer "B.Fab")
		)
		(fp_line
			(start -0.120396 0.3048)
			(end -0.120396 0.2794)
			(stroke
				(width 0.1)
				(type default)
			)
			(layer "B.Fab")
		)
		(fp_line
			(start -0.67945 0.3048)
			(end -0.120396 0.3048)
			(stroke
				(width 0.1)
				(type default)
			)
			(layer "B.Fab")
		)
		(pad "1" smd circle
			(at 0.40005 0 270)
			(size 0 0)
			(layers "B.Cu" "B.Mask" "B.Paste")
			(net "SMB_VR_SENSOR_3V3AUX_SDA")
		)
		(pad "2" smd circle
			(at -0.40005 0 270)
			(size 0 0)
			(layers "B.Cu" "B.Mask" "B.Paste")
			(net "SMB_VR_3V3AUX_SDA_R0")
		)
	)
	(footprint ""
		(layer "B.Cu")
		(at 258.953 -98.008948)
		(property "Reference" "C171"
			(at 0 0 0)
			(layer "B.SilkS")
			(hide yes)
			(effects
				(font
					(size 1.27 1.27)
				)
				(justify mirror)
			)
		)
		(property "Value" ""
			(at 0 0 0)
			(layer "B.Fab")
			(effects
				(font
					(size 1.27 1.27)
				)
				(justify mirror)
			)
		)
		(duplicate_pad_numbers_are_jumpers no)
		(fp_line
			(start -0.7874 -0.4064)
			(end -0.7874 0.4064)
			(stroke
				(width 0.1524)
				(type default)
			)
			(layer "B.SilkS")
		)
		(fp_line
			(start -0.7874 0.4064)
			(end 0.7874 0.4064)
			(stroke
				(width 0.1524)
				(type default)
			)
			(layer "B.SilkS")
		)
		(fp_line
			(start 0.7874 -0.4064)
			(end -0.7874 -0.4064)
			(stroke
				(width 0.1524)
				(type default)
			)
			(layer "B.SilkS")
		)
		(fp_line
			(start 0.7874 0.4064)
			(end 0.7874 -0.4064)
			(stroke
				(width 0.1524)
				(type default)
			)
			(layer "B.SilkS")
		)
		(fp_line
			(start -0.67945 -0.3048)
			(end -0.67945 0.3048)
			(stroke
				(width 0.1)
				(type default)
			)
			(layer "B.Fab")
		)
		(fp_line
			(start -0.67945 0.3048)
			(end -0.120396 0.3048)
			(stroke
				(width 0.1)
				(type default)
			)
			(layer "B.Fab")
		)
		(fp_line
			(start -0.12065 -0.3048)
			(end -0.67945 -0.3048)
			(stroke
				(width 0.1)
				(type default)
			)
			(layer "B.Fab")
		)
		(fp_line
			(start -0.12065 -0.2794)
			(end -0.12065 -0.3048)
			(stroke
				(width 0.1)
				(type default)
			)
			(layer "B.Fab")
		)
		(fp_line
			(start -0.120396 0.2794)
			(end 0.12065 0.2794)
			(stroke
				(width 0.1)
				(type default)
			)
			(layer "B.Fab")
		)
		(fp_line
			(start -0.120396 0.3048)
			(end -0.120396 0.2794)
			(stroke
				(width 0.1)
				(type default)
			)
			(layer "B.Fab")
		)
		(fp_line
			(start 0.12065 -0.305054)
			(end 0.12065 -0.2794)
			(stroke
				(width 0.1)
				(type default)
			)
			(layer "B.Fab")
		)
		(fp_line
			(start 0.12065 -0.2794)
			(end -0.12065 -0.2794)
			(stroke
				(width 0.1)
				(type default)
			)
			(layer "B.Fab")
		)
		(fp_line
			(start 0.12065 0.2794)
			(end 0.12065 0.3048)
			(stroke
				(width 0.1)
				(type default)
			)
			(layer "B.Fab")
		)
		(fp_line
			(start 0.12065 0.3048)
			(end 0.67945 0.3048)
			(stroke
				(width 0.1)
				(type default)
			)
			(layer "B.Fab")
		)
		(fp_line
			(start 0.67945 -0.305054)
			(end 0.12065 -0.305054)
			(stroke
				(width 0.1)
				(type default)
			)
			(layer "B.Fab")
		)
		(fp_line
			(start 0.67945 0.3048)
			(end 0.67945 -0.305054)
			(stroke
				(width 0.1)
				(type default)
			)
			(layer "B.Fab")
		)
		(pad "1" smd circle
			(at 0.40005 0 180)
			(size 0 0)
			(layers "B.Cu" "B.Mask" "B.Paste")
			(net "P3V3_AUX_CLK_GEN_VDD_CK440")
		)
		(pad "2" smd circle
			(at -0.40005 0 180)
			(size 0 0)
			(layers "B.Cu" "B.Mask" "B.Paste")
			(net "GND")
		)
	)
	(footprint ""
		(layer "B.Cu")
		(at 203.33208 -36.642548 180)
		(property "Reference" "R3578"
			(at 0 0 0)
			(layer "B.SilkS")
			(hide yes)
			(effects
				(font
					(size 1.27 1.27)
				)
				(justify mirror)
			)
		)
		(property "Value" ""
			(at 0 0 0)
			(layer "B.Fab")
			(effects
				(font
					(size 1.27 1.27)
				)
				(justify mirror)
			)
		)
		(duplicate_pad_numbers_are_jumpers no)
		(fp_line
			(start 0.7874 0.4064)
			(end 0.7874 -0.4064)
			(stroke
				(width 0.1524)
				(type default)
			)
			(layer "B.SilkS")
		)
		(fp_line
			(start 0.7874 -0.4064)
			(end -0.7874 -0.4064)
			(stroke
				(width 0.1524)
				(type default)
			)
			(layer "B.SilkS")
		)
		(fp_line
			(start -0.7874 0.4064)
			(end 0.7874 0.4064)
			(stroke
				(width 0.1524)
				(type default)
			)
			(layer "B.SilkS")
		)
		(fp_line
			(start -0.7874 -0.4064)
			(end -0.7874 0.4064)
			(stroke
				(width 0.1524)
				(type default)
			)
			(layer "B.SilkS")
		)
		(fp_line
			(start 0.67945 0.3048)
			(end 0.67945 -0.305054)
			(stroke
				(width 0.1)
				(type default)
			)
			(layer "B.Fab")
		)
		(fp_line
			(start 0.67945 -0.305054)
			(end 0.12065 -0.305054)
			(stroke
				(width 0.1)
				(type default)
			)
			(layer "B.Fab")
		)
		(fp_line
			(start 0.12065 0.3048)
			(end 0.67945 0.3048)
			(stroke
				(width 0.1)
				(type default)
			)
			(layer "B.Fab")
		)
		(fp_line
			(start 0.12065 0.2794)
			(end 0.12065 0.3048)
			(stroke
				(width 0.1)
				(type default)
			)
			(layer "B.Fab")
		)
		(fp_line
			(start 0.12065 -0.2794)
			(end -0.12065 -0.2794)
			(stroke
				(width 0.1)
				(type default)
			)
			(layer "B.Fab")
		)
		(fp_line
			(start 0.12065 -0.305054)
			(end 0.12065 -0.2794)
			(stroke
				(width 0.1)
				(type default)
			)
			(layer "B.Fab")
		)
		(fp_line
			(start -0.120396 0.3048)
			(end -0.120396 0.2794)
			(stroke
				(width 0.1)
				(type default)
			)
			(layer "B.Fab")
		)
		(fp_line
			(start -0.120396 0.2794)
			(end 0.12065 0.2794)
			(stroke
				(width 0.1)
				(type default)
			)
			(layer "B.Fab")
		)
		(fp_line
			(start -0.12065 -0.2794)
			(end -0.12065 -0.3048)
			(stroke
				(width 0.1)
				(type default)
			)
			(layer "B.Fab")
		)
		(fp_line
			(start -0.12065 -0.3048)
			(end -0.67945 -0.3048)
			(stroke
				(width 0.1)
				(type default)
			)
			(layer "B.Fab")
		)
		(fp_line
			(start -0.67945 0.3048)
			(end -0.120396 0.3048)
			(stroke
				(width 0.1)
				(type default)
			)
			(layer "B.Fab")
		)
		(fp_line
			(start -0.67945 -0.3048)
			(end -0.67945 0.3048)
			(stroke
				(width 0.1)
				(type default)
			)
			(layer "B.Fab")
		)
		(pad "1" smd circle
			(at 0.40005 0)
			(size 0 0)
			(layers "B.Cu" "B.Mask" "B.Paste")
			(net "P12V_SCM_R")
		)
		(pad "2" smd circle
			(at -0.40005 0)
			(size 0 0)
			(layers "B.Cu" "B.Mask" "B.Paste")
			(net "VSENSE_P12V_INA230_5_INP")
		)
	)
	(footprint ""
		(layer "B.Cu")
		(at 109.45114 -356.507288 -90)
		(property "Reference" "PR4239"
			(at 0 0 90)
			(layer "B.SilkS")
			(hide yes)
			(effects
				(font
					(size 1.27 1.27)
				)
				(justify mirror)
			)
		)
		(property "Value" ""
			(at 0 0 90)
			(layer "B.Fab")
			(effects
				(font
					(size 1.27 1.27)
				)
				(justify mirror)
			)
		)
		(duplicate_pad_numbers_are_jumpers no)
		(fp_line
			(start -0.7874 0.4064)
			(end 0.7874 0.4064)
			(stroke
				(width 0.1524)
				(type default)
			)
			(layer "B.SilkS")
		)
		(fp_line
			(start 0.7874 0.4064)
			(end 0.7874 -0.4064)
			(stroke
				(width 0.1524)
				(type default)
			)
			(layer "B.SilkS")
		)
		(fp_line
			(start -0.7874 -0.4064)
			(end -0.7874 0.4064)
			(stroke
				(width 0.1524)
				(type default)
			)
			(layer "B.SilkS")
		)
		(fp_line
			(start 0.7874 -0.4064)
			(end -0.7874 -0.4064)
			(stroke
				(width 0.1524)
				(type default)
			)
			(layer "B.SilkS")
		)
		(fp_line
			(start -0.67945 0.3048)
			(end -0.120396 0.3048)
			(stroke
				(width 0.1)
				(type default)
			)
			(layer "B.Fab")
		)
		(fp_line
			(start -0.120396 0.3048)
			(end -0.120396 0.2794)
			(stroke
				(width 0.1)
				(type default)
			)
			(layer "B.Fab")
		)
		(fp_line
			(start 0.12065 0.3048)
			(end 0.67945 0.3048)
			(stroke
				(width 0.1)
				(type default)
			)
			(layer "B.Fab")
		)
		(fp_line
			(start 0.67945 0.3048)
			(end 0.67945 -0.305054)
			(stroke
				(width 0.1)
				(type default)
			)
			(layer "B.Fab")
		)
		(fp_line
			(start -0.120396 0.2794)
			(end 0.12065 0.2794)
			(stroke
				(width 0.1)
				(type default)
			)
			(layer "B.Fab")
		)
		(fp_line
			(start 0.12065 0.2794)
			(end 0.12065 0.3048)
			(stroke
				(width 0.1)
				(type default)
			)
			(layer "B.Fab")
		)
		(fp_line
			(start -0.12065 -0.2794)
			(end -0.12065 -0.3048)
			(stroke
				(width 0.1)
				(type default)
			)
			(layer "B.Fab")
		)
		(fp_line
			(start 0.12065 -0.2794)
			(end -0.12065 -0.2794)
			(stroke
				(width 0.1)
				(type default)
			)
			(layer "B.Fab")
		)
		(fp_line
			(start -0.67945 -0.3048)
			(end -0.67945 0.3048)
			(stroke
				(width 0.1)
				(type default)
			)
			(layer "B.Fab")
		)
		(fp_line
			(start -0.12065 -0.3048)
			(end -0.67945 -0.3048)
			(stroke
				(width 0.1)
				(type default)
			)
			(layer "B.Fab")
		)
		(fp_line
			(start 0.12065 -0.305054)
			(end 0.12065 -0.2794)
			(stroke
				(width 0.1)
				(type default)
			)
			(layer "B.Fab")
		)
		(fp_line
			(start 0.67945 -0.305054)
			(end 0.12065 -0.305054)
			(stroke
				(width 0.1)
				(type default)
			)
			(layer "B.Fab")
		)
		(pad "1" smd circle
			(at 0.40005 0 90)
			(size 0 0)
			(layers "B.Cu" "B.Mask" "B.Paste")
			(net "PVCCFA_EHV_FIVRA_CPU1_IMON3")
		)
		(pad "2" smd circle
			(at -0.40005 0 90)
			(size 0 0)
			(layers "B.Cu" "B.Mask" "B.Paste")
			(net "GND")
		)
	)
	(footprint ""
		(layer "B.Cu")
		(at 252.222 -97.373948 180)
		(property "Reference" "C111"
			(at 0 0 0)
			(layer "B.SilkS")
			(hide yes)
			(effects
				(font
					(size 1.27 1.27)
				)
				(justify mirror)
			)
		)
		(property "Value" ""
			(at 0 0 0)
			(layer "B.Fab")
			(effects
				(font
					(size 1.27 1.27)
				)
				(justify mirror)
			)
		)
		(duplicate_pad_numbers_are_jumpers no)
		(fp_line
			(start 0.7874 0.4064)
			(end 0.7874 -0.4064)
			(stroke
				(width 0.1524)
				(type default)
			)
			(layer "B.SilkS")
		)
		(fp_line
			(start 0.7874 -0.4064)
			(end -0.7874 -0.4064)
			(stroke
				(width 0.1524)
				(type default)
			)
			(layer "B.SilkS")
		)
		(fp_line
			(start -0.7874 0.4064)
			(end 0.7874 0.4064)
			(stroke
				(width 0.1524)
				(type default)
			)
			(layer "B.SilkS")
		)
		(fp_line
			(start -0.7874 -0.4064)
			(end -0.7874 0.4064)
			(stroke
				(width 0.1524)
				(type default)
			)
			(layer "B.SilkS")
		)
		(fp_line
			(start 0.67945 0.3048)
			(end 0.67945 -0.305054)
			(stroke
				(width 0.1)
				(type default)
			)
			(layer "B.Fab")
		)
		(fp_line
			(start 0.67945 -0.305054)
			(end 0.12065 -0.305054)
			(stroke
				(width 0.1)
				(type default)
			)
			(layer "B.Fab")
		)
		(fp_line
			(start 0.12065 0.3048)
			(end 0.67945 0.3048)
			(stroke
				(width 0.1)
				(type default)
			)
			(layer "B.Fab")
		)
		(fp_line
			(start 0.12065 0.2794)
			(end 0.12065 0.3048)
			(stroke
				(width 0.1)
				(type default)
			)
			(layer "B.Fab")
		)
		(fp_line
			(start 0.12065 -0.2794)
			(end -0.12065 -0.2794)
			(stroke
				(width 0.1)
				(type default)
			)
			(layer "B.Fab")
		)
		(fp_line
			(start 0.12065 -0.305054)
			(end 0.12065 -0.2794)
			(stroke
				(width 0.1)
				(type default)
			)
			(layer "B.Fab")
		)
		(fp_line
			(start -0.120396 0.3048)
			(end -0.120396 0.2794)
			(stroke
				(width 0.1)
				(type default)
			)
			(layer "B.Fab")
		)
		(fp_line
			(start -0.120396 0.2794)
			(end 0.12065 0.2794)
			(stroke
				(width 0.1)
				(type default)
			)
			(layer "B.Fab")
		)
		(fp_line
			(start -0.12065 -0.2794)
			(end -0.12065 -0.3048)
			(stroke
				(width 0.1)
				(type default)
			)
			(layer "B.Fab")
		)
		(fp_line
			(start -0.12065 -0.3048)
			(end -0.67945 -0.3048)
			(stroke
				(width 0.1)
				(type default)
			)
			(layer "B.Fab")
		)
		(fp_line
			(start -0.67945 0.3048)
			(end -0.120396 0.3048)
			(stroke
				(width 0.1)
				(type default)
			)
			(layer "B.Fab")
		)
		(fp_line
			(start -0.67945 -0.3048)
			(end -0.67945 0.3048)
			(stroke
				(width 0.1)
				(type default)
			)
			(layer "B.Fab")
		)
		(pad "1" smd circle
			(at 0.40005 0)
			(size 0 0)
			(layers "B.Cu" "B.Mask" "B.Paste")
			(net "P3V3_AUX_CLK_GEN_VDDXTAL_CK440")
		)
		(pad "2" smd circle
			(at -0.40005 0)
			(size 0 0)
			(layers "B.Cu" "B.Mask" "B.Paste")
			(net "GND")
		)
	)
	(footprint ""
		(layer "B.Cu")
		(at 370.901468 -324.911466 -90)
		(property "Reference" "PC288_P0_4"
			(at 0 0 90)
			(layer "B.SilkS")
			(hide yes)
			(effects
				(font
					(size 1.27 1.27)
				)
				(justify mirror)
			)
		)
		(property "Value" ""
			(at 0 0 90)
			(layer "B.Fab")
			(effects
				(font
					(size 1.27 1.27)
				)
				(justify mirror)
			)
		)
		(duplicate_pad_numbers_are_jumpers no)
		(fp_line
			(start -1.524 0.762)
			(end 1.524 0.762)
			(stroke
				(width 0.1524)
				(type default)
			)
			(layer "B.SilkS")
		)
		(fp_line
			(start 1.524 0.762)
			(end 1.524 -0.762)
			(stroke
				(width 0.1524)
				(type default)
			)
			(layer "B.SilkS")
		)
		(fp_line
			(start -1.524 -0.762)
			(end -1.524 0.762)
			(stroke
				(width 0.1524)
				(type default)
			)
			(layer "B.SilkS")
		)
		(fp_line
			(start 1.524 -0.762)
			(end -1.524 -0.762)
			(stroke
				(width 0.1524)
				(type default)
			)
			(layer "B.SilkS")
		)
		(fp_line
			(start -1.1049 0.724916)
			(end -1.1049 -0.724916)
			(stroke
				(width 0.1)
				(type default)
			)
			(layer "B.Fab")
		)
		(fp_line
			(start 1.1049 0.724916)
			(end -1.1049 0.724916)
			(stroke
				(width 0.1)
				(type default)
			)
			(layer "B.Fab")
		)
		(fp_line
			(start -1.1049 -0.724916)
			(end 1.1049 -0.724916)
			(stroke
				(width 0.1)
				(type default)
			)
			(layer "B.Fab")
		)
		(fp_line
			(start 1.1049 -0.724916)
			(end 1.1049 0.724916)
			(stroke
				(width 0.1)
				(type default)
			)
			(layer "B.Fab")
		)
		(pad "1" smd rect
			(at 0.889 0 270)
			(size 1.016 1.27)
			(layers "B.Cu" "B.Mask" "B.Paste")
			(net "PVCCIN_CPU0")
		)
		(pad "2" smd rect
			(at -0.889 0 270)
			(size 1.016 1.27)
			(layers "B.Cu" "B.Mask" "B.Paste")
			(net "GND")
		)
	)
	(footprint ""
		(layer "B.Cu")
		(at 178.61788 -330.495148)
		(property "Reference" "R1935"
			(at 0 0 0)
			(layer "B.SilkS")
			(hide yes)
			(effects
				(font
					(size 1.27 1.27)
				)
				(justify mirror)
			)
		)
		(property "Value" ""
			(at 0 0 0)
			(layer "B.Fab")
			(effects
				(font
					(size 1.27 1.27)
				)
				(justify mirror)
			)
		)
		(duplicate_pad_numbers_are_jumpers no)
		(fp_line
			(start -0.7874 -0.4064)
			(end -0.7874 0.4064)
			(stroke
				(width 0.1524)
				(type default)
			)
			(layer "B.SilkS")
		)
		(fp_line
			(start -0.7874 0.4064)
			(end 0.7874 0.4064)
			(stroke
				(width 0.1524)
				(type default)
			)
			(layer "B.SilkS")
		)
		(fp_line
			(start 0.7874 -0.4064)
			(end -0.7874 -0.4064)
			(stroke
				(width 0.1524)
				(type default)
			)
			(layer "B.SilkS")
		)
		(fp_line
			(start 0.7874 0.4064)
			(end 0.7874 -0.4064)
			(stroke
				(width 0.1524)
				(type default)
			)
			(layer "B.SilkS")
		)
		(fp_line
			(start -0.67945 -0.3048)
			(end -0.67945 0.3048)
			(stroke
				(width 0.1)
				(type default)
			)
			(layer "B.Fab")
		)
		(fp_line
			(start -0.67945 0.3048)
			(end -0.120396 0.3048)
			(stroke
				(width 0.1)
				(type default)
			)
			(layer "B.Fab")
		)
		(fp_line
			(start -0.12065 -0.3048)
			(end -0.67945 -0.3048)
			(stroke
				(width 0.1)
				(type default)
			)
			(layer "B.Fab")
		)
		(fp_line
			(start -0.12065 -0.2794)
			(end -0.12065 -0.3048)
			(stroke
				(width 0.1)
				(type default)
			)
			(layer "B.Fab")
		)
		(fp_line
			(start -0.120396 0.2794)
			(end 0.12065 0.2794)
			(stroke
				(width 0.1)
				(type default)
			)
			(layer "B.Fab")
		)
		(fp_line
			(start -0.120396 0.3048)
			(end -0.120396 0.2794)
			(stroke
				(width 0.1)
				(type default)
			)
			(layer "B.Fab")
		)
		(fp_line
			(start 0.12065 -0.305054)
			(end 0.12065 -0.2794)
			(stroke
				(width 0.1)
				(type default)
			)
			(layer "B.Fab")
		)
		(fp_line
			(start 0.12065 -0.2794)
			(end -0.12065 -0.2794)
			(stroke
				(width 0.1)
				(type default)
			)
			(layer "B.Fab")
		)
		(fp_line
			(start 0.12065 0.2794)
			(end 0.12065 0.3048)
			(stroke
				(width 0.1)
				(type default)
			)
			(layer "B.Fab")
		)
		(fp_line
			(start 0.12065 0.3048)
			(end 0.67945 0.3048)
			(stroke
				(width 0.1)
				(type default)
			)
			(layer "B.Fab")
		)
		(fp_line
			(start 0.67945 -0.305054)
			(end 0.12065 -0.305054)
			(stroke
				(width 0.1)
				(type default)
			)
			(layer "B.Fab")
		)
		(fp_line
			(start 0.67945 0.3048)
			(end 0.67945 -0.305054)
			(stroke
				(width 0.1)
				(type default)
			)
			(layer "B.Fab")
		)
		(pad "1" smd circle
			(at 0.40005 0 180)
			(size 0 0)
			(layers "B.Cu" "B.Mask" "B.Paste")
			(net "SMB_S3M_CPU1_PIROM_3V3AUX_SDA")
		)
		(pad "2" smd circle
			(at -0.40005 0 180)
			(size 0 0)
			(layers "B.Cu" "B.Mask" "B.Paste")
			(net "SMB_S3M_CPU1_PIROM_3V3AUX_SDA_1")
		)
	)
	(footprint ""
		(layer "B.Cu")
		(at 60.468002 -8.319262 -90)
		(property "Reference" "R3180"
			(at 0 0 90)
			(layer "B.SilkS")
			(hide yes)
			(effects
				(font
					(size 1.27 1.27)
				)
				(justify mirror)
			)
		)
		(property "Value" ""
			(at 0 0 90)
			(layer "B.Fab")
			(effects
				(font
					(size 1.27 1.27)
				)
				(justify mirror)
			)
		)
		(duplicate_pad_numbers_are_jumpers no)
		(fp_line
			(start -0.7874 0.4064)
			(end 0.7874 0.4064)
			(stroke
				(width 0.1524)
				(type default)
			)
			(layer "B.SilkS")
		)
		(fp_line
			(start 0.7874 0.4064)
			(end 0.7874 -0.4064)
			(stroke
				(width 0.1524)
				(type default)
			)
			(layer "B.SilkS")
		)
		(fp_line
			(start -0.7874 -0.4064)
			(end -0.7874 0.4064)
			(stroke
				(width 0.1524)
				(type default)
			)
			(layer "B.SilkS")
		)
		(fp_line
			(start 0.7874 -0.4064)
			(end -0.7874 -0.4064)
			(stroke
				(width 0.1524)
				(type default)
			)
			(layer "B.SilkS")
		)
		(fp_line
			(start -0.67945 0.3048)
			(end -0.120396 0.3048)
			(stroke
				(width 0.1)
				(type default)
			)
			(layer "B.Fab")
		)
		(fp_line
			(start -0.120396 0.3048)
			(end -0.120396 0.2794)
			(stroke
				(width 0.1)
				(type default)
			)
			(layer "B.Fab")
		)
		(fp_line
			(start 0.12065 0.3048)
			(end 0.67945 0.3048)
			(stroke
				(width 0.1)
				(type default)
			)
			(layer "B.Fab")
		)
		(fp_line
			(start 0.67945 0.3048)
			(end 0.67945 -0.305054)
			(stroke
				(width 0.1)
				(type default)
			)
			(layer "B.Fab")
		)
		(fp_line
			(start -0.120396 0.2794)
			(end 0.12065 0.2794)
			(stroke
				(width 0.1)
				(type default)
			)
			(layer "B.Fab")
		)
		(fp_line
			(start 0.12065 0.2794)
			(end 0.12065 0.3048)
			(stroke
				(width 0.1)
				(type default)
			)
			(layer "B.Fab")
		)
		(fp_line
			(start -0.12065 -0.2794)
			(end -0.12065 -0.3048)
			(stroke
				(width 0.1)
				(type default)
			)
			(layer "B.Fab")
		)
		(fp_line
			(start 0.12065 -0.2794)
			(end -0.12065 -0.2794)
			(stroke
				(width 0.1)
				(type default)
			)
			(layer "B.Fab")
		)
		(fp_line
			(start -0.67945 -0.3048)
			(end -0.67945 0.3048)
			(stroke
				(width 0.1)
				(type default)
			)
			(layer "B.Fab")
		)
		(fp_line
			(start -0.12065 -0.3048)
			(end -0.67945 -0.3048)
			(stroke
				(width 0.1)
				(type default)
			)
			(layer "B.Fab")
		)
		(fp_line
			(start 0.12065 -0.305054)
			(end 0.12065 -0.2794)
			(stroke
				(width 0.1)
				(type default)
			)
			(layer "B.Fab")
		)
		(fp_line
			(start 0.67945 -0.305054)
			(end 0.12065 -0.305054)
			(stroke
				(width 0.1)
				(type default)
			)
			(layer "B.Fab")
		)
		(pad "1" smd circle
			(at 0.40005 0 90)
			(size 0 0)
			(layers "B.Cu" "B.Mask" "B.Paste")
			(net "OCP_V3_1_PRSNTA_R_N")
		)
		(pad "2" smd circle
			(at -0.40005 0 90)
			(size 0 0)
			(layers "B.Cu" "B.Mask" "B.Paste")
			(net "GND")
		)
	)
	(footprint ""
		(layer "B.Cu")
		(at 431.546 -24.094948 -90)
		(property "Reference" "R1898"
			(at 0 0 90)
			(layer "B.SilkS")
			(hide yes)
			(effects
				(font
					(size 1.27 1.27)
				)
				(justify mirror)
			)
		)
		(property "Value" ""
			(at 0 0 90)
			(layer "B.Fab")
			(effects
				(font
					(size 1.27 1.27)
				)
				(justify mirror)
			)
		)
		(duplicate_pad_numbers_are_jumpers no)
		(fp_line
			(start -0.7874 0.4064)
			(end 0.7874 0.4064)
			(stroke
				(width 0.1524)
				(type default)
			)
			(layer "B.SilkS")
		)
		(fp_line
			(start 0.7874 0.4064)
			(end 0.7874 -0.4064)
			(stroke
				(width 0.1524)
				(type default)
			)
			(layer "B.SilkS")
		)
		(fp_line
			(start -0.7874 -0.4064)
			(end -0.7874 0.4064)
			(stroke
				(width 0.1524)
				(type default)
			)
			(layer "B.SilkS")
		)
		(fp_line
			(start 0.7874 -0.4064)
			(end -0.7874 -0.4064)
			(stroke
				(width 0.1524)
				(type default)
			)
			(layer "B.SilkS")
		)
		(fp_line
			(start -0.67945 0.3048)
			(end -0.120396 0.3048)
			(stroke
				(width 0.1)
				(type default)
			)
			(layer "B.Fab")
		)
		(fp_line
			(start -0.120396 0.3048)
			(end -0.120396 0.2794)
			(stroke
				(width 0.1)
				(type default)
			)
			(layer "B.Fab")
		)
		(fp_line
			(start 0.12065 0.3048)
			(end 0.67945 0.3048)
			(stroke
				(width 0.1)
				(type default)
			)
			(layer "B.Fab")
		)
		(fp_line
			(start 0.67945 0.3048)
			(end 0.67945 -0.305054)
			(stroke
				(width 0.1)
				(type default)
			)
			(layer "B.Fab")
		)
		(fp_line
			(start -0.120396 0.2794)
			(end 0.12065 0.2794)
			(stroke
				(width 0.1)
				(type default)
			)
			(layer "B.Fab")
		)
		(fp_line
			(start 0.12065 0.2794)
			(end 0.12065 0.3048)
			(stroke
				(width 0.1)
				(type default)
			)
			(layer "B.Fab")
		)
		(fp_line
			(start -0.12065 -0.2794)
			(end -0.12065 -0.3048)
			(stroke
				(width 0.1)
				(type default)
			)
			(layer "B.Fab")
		)
		(fp_line
			(start 0.12065 -0.2794)
			(end -0.12065 -0.2794)
			(stroke
				(width 0.1)
				(type default)
			)
			(layer "B.Fab")
		)
		(fp_line
			(start -0.67945 -0.3048)
			(end -0.67945 0.3048)
			(stroke
				(width 0.1)
				(type default)
			)
			(layer "B.Fab")
		)
		(fp_line
			(start -0.12065 -0.3048)
			(end -0.67945 -0.3048)
			(stroke
				(width 0.1)
				(type default)
			)
			(layer "B.Fab")
		)
		(fp_line
			(start 0.12065 -0.305054)
			(end 0.12065 -0.2794)
			(stroke
				(width 0.1)
				(type default)
			)
			(layer "B.Fab")
		)
		(fp_line
			(start 0.67945 -0.305054)
			(end 0.12065 -0.305054)
			(stroke
				(width 0.1)
				(type default)
			)
			(layer "B.Fab")
		)
		(pad "1" smd circle
			(at 0.40005 0 90)
			(size 0 0)
			(layers "B.Cu" "B.Mask" "B.Paste")
			(net "OCP_SFF_ISO_BIF2_EN")
		)
		(pad "2" smd circle
			(at -0.40005 0 90)
			(size 0 0)
			(layers "B.Cu" "B.Mask" "B.Paste")
			(net "GND")
		)
	)
	(footprint ""
		(layer "B.Cu")
		(at 34.5313 -319.060068 90)
		(property "Reference" "R898"
			(at 0 0 90)
			(layer "B.SilkS")
			(hide yes)
			(effects
				(font
					(size 1.27 1.27)
				)
				(justify mirror)
			)
		)
		(property "Value" ""
			(at 0 0 90)
			(layer "B.Fab")
			(effects
				(font
					(size 1.27 1.27)
				)
				(justify mirror)
			)
		)
		(duplicate_pad_numbers_are_jumpers no)
		(fp_line
			(start 0.7874 -0.4064)
			(end -0.7874 -0.4064)
			(stroke
				(width 0.1524)
				(type default)
			)
			(layer "B.SilkS")
		)
		(fp_line
			(start -0.7874 -0.4064)
			(end -0.7874 0.4064)
			(stroke
				(width 0.1524)
				(type default)
			)
			(layer "B.SilkS")
		)
		(fp_line
			(start 0.7874 0.4064)
			(end 0.7874 -0.4064)
			(stroke
				(width 0.1524)
				(type default)
			)
			(layer "B.SilkS")
		)
		(fp_line
			(start -0.7874 0.4064)
			(end 0.7874 0.4064)
			(stroke
				(width 0.1524)
				(type default)
			)
			(layer "B.SilkS")
		)
		(fp_line
			(start 0.67945 -0.305054)
			(end 0.12065 -0.305054)
			(stroke
				(width 0.1)
				(type default)
			)
			(layer "B.Fab")
		)
		(fp_line
			(start 0.12065 -0.305054)
			(end 0.12065 -0.2794)
			(stroke
				(width 0.1)
				(type default)
			)
			(layer "B.Fab")
		)
		(fp_line
			(start -0.12065 -0.3048)
			(end -0.67945 -0.3048)
			(stroke
				(width 0.1)
				(type default)
			)
			(layer "B.Fab")
		)
		(fp_line
			(start -0.67945 -0.3048)
			(end -0.67945 0.3048)
			(stroke
				(width 0.1)
				(type default)
			)
			(layer "B.Fab")
		)
		(fp_line
			(start 0.12065 -0.2794)
			(end -0.12065 -0.2794)
			(stroke
				(width 0.1)
				(type default)
			)
			(layer "B.Fab")
		)
		(fp_line
			(start -0.12065 -0.2794)
			(end -0.12065 -0.3048)
			(stroke
				(width 0.1)
				(type default)
			)
			(layer "B.Fab")
		)
		(fp_line
			(start 0.12065 0.2794)
			(end 0.12065 0.3048)
			(stroke
				(width 0.1)
				(type default)
			)
			(layer "B.Fab")
		)
		(fp_line
			(start -0.120396 0.2794)
			(end 0.12065 0.2794)
			(stroke
				(width 0.1)
				(type default)
			)
			(layer "B.Fab")
		)
		(fp_line
			(start 0.67945 0.3048)
			(end 0.67945 -0.305054)
			(stroke
				(width 0.1)
				(type default)
			)
			(layer "B.Fab")
		)
		(fp_line
			(start 0.12065 0.3048)
			(end 0.67945 0.3048)
			(stroke
				(width 0.1)
				(type default)
			)
			(layer "B.Fab")
		)
		(fp_line
			(start -0.120396 0.3048)
			(end -0.120396 0.2794)
			(stroke
				(width 0.1)
				(type default)
			)
			(layer "B.Fab")
		)
		(fp_line
			(start -0.67945 0.3048)
			(end -0.120396 0.3048)
			(stroke
				(width 0.1)
				(type default)
			)
			(layer "B.Fab")
		)
		(pad "1" smd circle
			(at 0.40005 0 270)
			(size 0 0)
			(layers "B.Cu" "B.Mask" "B.Paste")
			(net "PWRGD_CHC_CPU1_DIMM2")
		)
		(pad "2" smd circle
			(at -0.40005 0 270)
			(size 0 0)
			(layers "B.Cu" "B.Mask" "B.Paste")
			(net "PWRGD_FAIL_CPU1_CD")
		)
	)
	(footprint ""
		(layer "B.Cu")
		(at 61.62421 -165.11397)
		(property "Reference" "PC1940"
			(at 0 0 0)
			(layer "B.SilkS")
			(hide yes)
			(effects
				(font
					(size 1.27 1.27)
				)
				(justify mirror)
			)
		)
		(property "Value" ""
			(at 0 0 0)
			(layer "B.Fab")
			(effects
				(font
					(size 1.27 1.27)
				)
				(justify mirror)
			)
		)
		(duplicate_pad_numbers_are_jumpers no)
		(fp_line
			(start -4.53898 -2.15011)
			(end -4.53898 2.15011)
			(stroke
				(width 0.1524)
				(type default)
			)
			(layer "B.SilkS")
		)
		(fp_line
			(start -4.53898 2.15011)
			(end 4.53898 2.15011)
			(stroke
				(width 0.1524)
				(type default)
			)
			(layer "B.SilkS")
		)
		(fp_line
			(start 4.53898 -2.150618)
			(end 4.539742 2.152142)
			(stroke
				(width 0.1524)
				(type default)
			)
			(layer "B.SilkS")
		)
		(fp_line
			(start 4.53898 -2.15011)
			(end -4.53898 -2.15011)
			(stroke
				(width 0.1524)
				(type default)
			)
			(layer "B.SilkS")
		)
		(fp_line
			(start 4.53898 2.15011)
			(end 4.53898 -2.15011)
			(stroke
				(width 0.1524)
				(type default)
			)
			(layer "B.SilkS")
		)
		(fp_line
			(start 4.69138 -2.150618)
			(end 4.692396 2.161032)
			(stroke
				(width 0.1524)
				(type default)
			)
			(layer "B.SilkS")
		)
		(fp_line
			(start 4.83108 2.150364)
			(end 4.447794 2.149348)
			(stroke
				(width 0.1524)
				(type default)
			)
			(layer "B.SilkS")
		)
		(fp_line
			(start 4.84378 -2.150618)
			(end 4.53898 -2.150618)
			(stroke
				(width 0.1524)
				(type default)
			)
			(layer "B.SilkS")
		)
		(fp_line
			(start 4.84378 -2.150618)
			(end 4.842256 2.163064)
			(stroke
				(width 0.1524)
				(type default)
			)
			(layer "B.SilkS")
		)
		(fp_line
			(start -3.64998 -2.15011)
			(end -3.64998 2.15011)
			(stroke
				(width 0.1)
				(type default)
			)
			(layer "B.Fab")
		)
		(fp_line
			(start -3.64998 2.15011)
			(end 3.64998 2.15011)
			(stroke
				(width 0.1)
				(type default)
			)
			(layer "B.Fab")
		)
		(fp_line
			(start 3.64998 -2.15011)
			(end -3.64998 -2.15011)
			(stroke
				(width 0.1)
				(type default)
			)
			(layer "B.Fab")
		)
		(fp_line
			(start 3.64998 2.15011)
			(end 3.64998 -2.15011)
			(stroke
				(width 0.1)
				(type default)
			)
			(layer "B.Fab")
		)
		(fp_text user "-"
			(at -4.94157 0.951992 0)
			(unlocked yes)
			(layer "B.SilkS")
			(effects
				(font
					(size 1.905 1.4224)
					(thickness 0.1524)
				)
				(justify left mirror)
			)
		)
		(fp_text user "+"
			(at 6.214872 -0.337058 0)
			(unlocked yes)
			(layer "B.SilkS")
			(effects
				(font
					(size 1.905 1.4224)
					(thickness 0.1524)
				)
				(justify left mirror)
			)
		)
		(fp_text user "-"
			(at -4.313174 -0.094488 0)
			(unlocked yes)
			(layer "B.Fab")
			(effects
				(font
					(size 1.905 1.4224)
					(thickness 0.1524)
				)
				(justify left mirror)
			)
		)
		(fp_text user "+"
			(at 6.214872 -0.337058 0)
			(unlocked yes)
			(layer "B.Fab")
			(effects
				(font
					(size 1.905 1.4224)
					(thickness 0.1524)
				)
				(justify left mirror)
			)
		)
		(pad "1" smd rect
			(at 3.199892 0 180)
			(size 2.413 2.8194)
			(layers "B.Cu" "B.Mask" "B.Paste")
			(net "PVCCD_HV_CPU1")
		)
		(pad "2" smd rect
			(at -3.199892 0 180)
			(size 2.413 2.8194)
			(layers "B.Cu" "B.Mask" "B.Paste")
			(net "GND")
		)
	)
	(footprint ""
		(layer "B.Cu")
		(at 180.514752 -192.699894 -90)
		(property "Reference" "R326"
			(at 0 0 90)
			(layer "B.SilkS")
			(hide yes)
			(effects
				(font
					(size 1.27 1.27)
				)
				(justify mirror)
			)
		)
		(property "Value" ""
			(at 0 0 90)
			(layer "B.Fab")
			(effects
				(font
					(size 1.27 1.27)
				)
				(justify mirror)
			)
		)
		(duplicate_pad_numbers_are_jumpers no)
		(fp_line
			(start -0.7874 0.4064)
			(end 0.7874 0.4064)
			(stroke
				(width 0.1524)
				(type default)
			)
			(layer "B.SilkS")
		)
		(fp_line
			(start 0.7874 0.4064)
			(end 0.7874 -0.4064)
			(stroke
				(width 0.1524)
				(type default)
			)
			(layer "B.SilkS")
		)
		(fp_line
			(start -0.7874 -0.4064)
			(end -0.7874 0.4064)
			(stroke
				(width 0.1524)
				(type default)
			)
			(layer "B.SilkS")
		)
		(fp_line
			(start 0.7874 -0.4064)
			(end -0.7874 -0.4064)
			(stroke
				(width 0.1524)
				(type default)
			)
			(layer "B.SilkS")
		)
		(fp_line
			(start -0.67945 0.3048)
			(end -0.120396 0.3048)
			(stroke
				(width 0.1)
				(type default)
			)
			(layer "B.Fab")
		)
		(fp_line
			(start -0.120396 0.3048)
			(end -0.120396 0.2794)
			(stroke
				(width 0.1)
				(type default)
			)
			(layer "B.Fab")
		)
		(fp_line
			(start 0.12065 0.3048)
			(end 0.67945 0.3048)
			(stroke
				(width 0.1)
				(type default)
			)
			(layer "B.Fab")
		)
		(fp_line
			(start 0.67945 0.3048)
			(end 0.67945 -0.305054)
			(stroke
				(width 0.1)
				(type default)
			)
			(layer "B.Fab")
		)
		(fp_line
			(start -0.120396 0.2794)
			(end 0.12065 0.2794)
			(stroke
				(width 0.1)
				(type default)
			)
			(layer "B.Fab")
		)
		(fp_line
			(start 0.12065 0.2794)
			(end 0.12065 0.3048)
			(stroke
				(width 0.1)
				(type default)
			)
			(layer "B.Fab")
		)
		(fp_line
			(start -0.12065 -0.2794)
			(end -0.12065 -0.3048)
			(stroke
				(width 0.1)
				(type default)
			)
			(layer "B.Fab")
		)
		(fp_line
			(start 0.12065 -0.2794)
			(end -0.12065 -0.2794)
			(stroke
				(width 0.1)
				(type default)
			)
			(layer "B.Fab")
		)
		(fp_line
			(start -0.67945 -0.3048)
			(end -0.67945 0.3048)
			(stroke
				(width 0.1)
				(type default)
			)
			(layer "B.Fab")
		)
		(fp_line
			(start -0.12065 -0.3048)
			(end -0.67945 -0.3048)
			(stroke
				(width 0.1)
				(type default)
			)
			(layer "B.Fab")
		)
		(fp_line
			(start 0.12065 -0.305054)
			(end 0.12065 -0.2794)
			(stroke
				(width 0.1)
				(type default)
			)
			(layer "B.Fab")
		)
		(fp_line
			(start 0.67945 -0.305054)
			(end 0.12065 -0.305054)
			(stroke
				(width 0.1)
				(type default)
			)
			(layer "B.Fab")
		)
		(pad "1" smd circle
			(at 0.40005 0 90)
			(size 0 0)
			(layers "B.Cu" "B.Mask" "B.Paste")
			(net "P3V3_AUX")
		)
		(pad "2" smd circle
			(at -0.40005 0 90)
			(size 0 0)
			(layers "B.Cu" "B.Mask" "B.Paste")
			(net "PU_S3M_CPU1_CPLD_CONFD")
		)
	)
	(footprint ""
		(layer "B.Cu")
		(at 409.284932 -170.821858 180)
		(property "Reference" "PC1575"
			(at 0 0 0)
			(layer "B.SilkS")
			(hide yes)
			(effects
				(font
					(size 1.27 1.27)
				)
				(justify mirror)
			)
		)
		(property "Value" ""
			(at 0 0 0)
			(layer "B.Fab")
			(effects
				(font
					(size 1.27 1.27)
				)
				(justify mirror)
			)
		)
		(duplicate_pad_numbers_are_jumpers no)
		(fp_line
			(start 4.84378 -2.150618)
			(end 4.842256 2.163064)
			(stroke
				(width 0.1524)
				(type default)
			)
			(layer "B.SilkS")
		)
		(fp_line
			(start 4.84378 -2.150618)
			(end 4.53898 -2.150618)
			(stroke
				(width 0.1524)
				(type default)
			)
			(layer "B.SilkS")
		)
		(fp_line
			(start 4.83108 2.150364)
			(end 4.447794 2.149348)
			(stroke
				(width 0.1524)
				(type default)
			)
			(layer "B.SilkS")
		)
		(fp_line
			(start 4.69138 -2.150618)
			(end 4.692396 2.161032)
			(stroke
				(width 0.1524)
				(type default)
			)
			(layer "B.SilkS")
		)
		(fp_line
			(start 4.53898 2.15011)
			(end 4.53898 -2.15011)
			(stroke
				(width 0.1524)
				(type default)
			)
			(layer "B.SilkS")
		)
		(fp_line
			(start 4.53898 -2.15011)
			(end -4.53898 -2.15011)
			(stroke
				(width 0.1524)
				(type default)
			)
			(layer "B.SilkS")
		)
		(fp_line
			(start 4.53898 -2.150618)
			(end 4.539742 2.152142)
			(stroke
				(width 0.1524)
				(type default)
			)
			(layer "B.SilkS")
		)
		(fp_line
			(start -4.53898 2.15011)
			(end 4.53898 2.15011)
			(stroke
				(width 0.1524)
				(type default)
			)
			(layer "B.SilkS")
		)
		(fp_line
			(start -4.53898 -2.15011)
			(end -4.53898 2.15011)
			(stroke
				(width 0.1524)
				(type default)
			)
			(layer "B.SilkS")
		)
		(fp_line
			(start 3.64998 2.15011)
			(end 3.64998 -2.15011)
			(stroke
				(width 0.1)
				(type default)
			)
			(layer "B.Fab")
		)
		(fp_line
			(start 3.64998 -2.15011)
			(end -3.64998 -2.15011)
			(stroke
				(width 0.1)
				(type default)
			)
			(layer "B.Fab")
		)
		(fp_line
			(start -3.64998 2.15011)
			(end 3.64998 2.15011)
			(stroke
				(width 0.1)
				(type default)
			)
			(layer "B.Fab")
		)
		(fp_line
			(start -3.64998 -2.15011)
			(end -3.64998 2.15011)
			(stroke
				(width 0.1)
				(type default)
			)
			(layer "B.Fab")
		)
		(fp_text user "+"
			(at 6.214872 -0.337058 180)
			(unlocked yes)
			(layer "B.SilkS")
			(effects
				(font
					(size 1.905 1.4224)
					(thickness 0.1524)
				)
				(justify left mirror)
			)
		)
		(fp_text user "-"
			(at -5.702808 0.98806 180)
			(unlocked yes)
			(layer "B.SilkS")
			(effects
				(font
					(size 1.905 1.4224)
					(thickness 0.1524)
				)
				(justify left mirror)
			)
		)
		(fp_text user "+"
			(at 6.214872 -0.337058 180)
			(unlocked yes)
			(layer "B.Fab")
			(effects
				(font
					(size 1.905 1.4224)
					(thickness 0.1524)
				)
				(justify left mirror)
			)
		)
		(fp_text user "-"
			(at -4.313174 -0.094488 180)
			(unlocked yes)
			(layer "B.Fab")
			(effects
				(font
					(size 1.905 1.4224)
					(thickness 0.1524)
				)
				(justify left mirror)
			)
		)
		(pad "1" smd rect
			(at 3.199892 0)
			(size 2.413 2.8194)
			(layers "B.Cu" "B.Mask" "B.Paste")
			(net "PVCCINFAON_CPU0")
		)
		(pad "2" smd rect
			(at -3.199892 0)
			(size 2.413 2.8194)
			(layers "B.Cu" "B.Mask" "B.Paste")
			(net "GND")
		)
	)
	(footprint ""
		(layer "B.Cu")
		(at 12.003532 -99.925632 180)
		(property "Reference" "C2033"
			(at 0 0 0)
			(layer "B.SilkS")
			(hide yes)
			(effects
				(font
					(size 1.27 1.27)
				)
				(justify mirror)
			)
		)
		(property "Value" ""
			(at 0 0 0)
			(layer "B.Fab")
			(effects
				(font
					(size 1.27 1.27)
				)
				(justify mirror)
			)
		)
		(duplicate_pad_numbers_are_jumpers no)
		(fp_line
			(start 0.7874 0.4064)
			(end 0.7874 -0.4064)
			(stroke
				(width 0.1524)
				(type default)
			)
			(layer "B.SilkS")
		)
		(fp_line
			(start 0.7874 -0.4064)
			(end -0.7874 -0.4064)
			(stroke
				(width 0.1524)
				(type default)
			)
			(layer "B.SilkS")
		)
		(fp_line
			(start -0.7874 0.4064)
			(end 0.7874 0.4064)
			(stroke
				(width 0.1524)
				(type default)
			)
			(layer "B.SilkS")
		)
		(fp_line
			(start -0.7874 -0.4064)
			(end -0.7874 0.4064)
			(stroke
				(width 0.1524)
				(type default)
			)
			(layer "B.SilkS")
		)
		(fp_line
			(start 0.67945 0.3048)
			(end 0.67945 -0.305054)
			(stroke
				(width 0.1)
				(type default)
			)
			(layer "B.Fab")
		)
		(fp_line
			(start 0.67945 -0.305054)
			(end 0.12065 -0.305054)
			(stroke
				(width 0.1)
				(type default)
			)
			(layer "B.Fab")
		)
		(fp_line
			(start 0.12065 0.3048)
			(end 0.67945 0.3048)
			(stroke
				(width 0.1)
				(type default)
			)
			(layer "B.Fab")
		)
		(fp_line
			(start 0.12065 0.2794)
			(end 0.12065 0.3048)
			(stroke
				(width 0.1)
				(type default)
			)
			(layer "B.Fab")
		)
		(fp_line
			(start 0.12065 -0.2794)
			(end -0.12065 -0.2794)
			(stroke
				(width 0.1)
				(type default)
			)
			(layer "B.Fab")
		)
		(fp_line
			(start 0.12065 -0.305054)
			(end 0.12065 -0.2794)
			(stroke
				(width 0.1)
				(type default)
			)
			(layer "B.Fab")
		)
		(fp_line
			(start -0.120396 0.3048)
			(end -0.120396 0.2794)
			(stroke
				(width 0.1)
				(type default)
			)
			(layer "B.Fab")
		)
		(fp_line
			(start -0.120396 0.2794)
			(end 0.12065 0.2794)
			(stroke
				(width 0.1)
				(type default)
			)
			(layer "B.Fab")
		)
		(fp_line
			(start -0.12065 -0.2794)
			(end -0.12065 -0.3048)
			(stroke
				(width 0.1)
				(type default)
			)
			(layer "B.Fab")
		)
		(fp_line
			(start -0.12065 -0.3048)
			(end -0.67945 -0.3048)
			(stroke
				(width 0.1)
				(type default)
			)
			(layer "B.Fab")
		)
		(fp_line
			(start -0.67945 0.3048)
			(end -0.120396 0.3048)
			(stroke
				(width 0.1)
				(type default)
			)
			(layer "B.Fab")
		)
		(fp_line
			(start -0.67945 -0.3048)
			(end -0.67945 0.3048)
			(stroke
				(width 0.1)
				(type default)
			)
			(layer "B.Fab")
		)
		(pad "1" smd circle
			(at 0.40005 0)
			(size 0 0)
			(layers "B.Cu" "B.Mask" "B.Paste")
			(net "P3V3_AUX_USB_HUB")
		)
		(pad "2" smd circle
			(at -0.40005 0)
			(size 0 0)
			(layers "B.Cu" "B.Mask" "B.Paste")
			(net "GND")
		)
	)
	(footprint ""
		(layer "B.Cu")
		(at 111.506 -96.738948)
		(property "Reference" "R4021"
			(at 0 0 0)
			(layer "B.SilkS")
			(hide yes)
			(effects
				(font
					(size 1.27 1.27)
				)
				(justify mirror)
			)
		)
		(property "Value" ""
			(at 0 0 0)
			(layer "B.Fab")
			(effects
				(font
					(size 1.27 1.27)
				)
				(justify mirror)
			)
		)
		(duplicate_pad_numbers_are_jumpers no)
		(fp_line
			(start -0.7874 -0.4064)
			(end -0.7874 0.4064)
			(stroke
				(width 0.1524)
				(type default)
			)
			(layer "B.SilkS")
		)
		(fp_line
			(start -0.7874 0.4064)
			(end 0.7874 0.4064)
			(stroke
				(width 0.1524)
				(type default)
			)
			(layer "B.SilkS")
		)
		(fp_line
			(start 0.7874 -0.4064)
			(end -0.7874 -0.4064)
			(stroke
				(width 0.1524)
				(type default)
			)
			(layer "B.SilkS")
		)
		(fp_line
			(start 0.7874 0.4064)
			(end 0.7874 -0.4064)
			(stroke
				(width 0.1524)
				(type default)
			)
			(layer "B.SilkS")
		)
		(fp_line
			(start -0.67945 -0.3048)
			(end -0.67945 0.3048)
			(stroke
				(width 0.1)
				(type default)
			)
			(layer "B.Fab")
		)
		(fp_line
			(start -0.67945 0.3048)
			(end -0.120396 0.3048)
			(stroke
				(width 0.1)
				(type default)
			)
			(layer "B.Fab")
		)
		(fp_line
			(start -0.12065 -0.3048)
			(end -0.67945 -0.3048)
			(stroke
				(width 0.1)
				(type default)
			)
			(layer "B.Fab")
		)
		(fp_line
			(start -0.12065 -0.2794)
			(end -0.12065 -0.3048)
			(stroke
				(width 0.1)
				(type default)
			)
			(layer "B.Fab")
		)
		(fp_line
			(start -0.120396 0.2794)
			(end 0.12065 0.2794)
			(stroke
				(width 0.1)
				(type default)
			)
			(layer "B.Fab")
		)
		(fp_line
			(start -0.120396 0.3048)
			(end -0.120396 0.2794)
			(stroke
				(width 0.1)
				(type default)
			)
			(layer "B.Fab")
		)
		(fp_line
			(start 0.12065 -0.305054)
			(end 0.12065 -0.2794)
			(stroke
				(width 0.1)
				(type default)
			)
			(layer "B.Fab")
		)
		(fp_line
			(start 0.12065 -0.2794)
			(end -0.12065 -0.2794)
			(stroke
				(width 0.1)
				(type default)
			)
			(layer "B.Fab")
		)
		(fp_line
			(start 0.12065 0.2794)
			(end 0.12065 0.3048)
			(stroke
				(width 0.1)
				(type default)
			)
			(layer "B.Fab")
		)
		(fp_line
			(start 0.12065 0.3048)
			(end 0.67945 0.3048)
			(stroke
				(width 0.1)
				(type default)
			)
			(layer "B.Fab")
		)
		(fp_line
			(start 0.67945 -0.305054)
			(end 0.12065 -0.305054)
			(stroke
				(width 0.1)
				(type default)
			)
			(layer "B.Fab")
		)
		(fp_line
			(start 0.67945 0.3048)
			(end 0.67945 -0.305054)
			(stroke
				(width 0.1)
				(type default)
			)
			(layer "B.Fab")
		)
		(pad "1" smd circle
			(at 0.40005 0 180)
			(size 0 0)
			(layers "B.Cu" "B.Mask" "B.Paste")
			(net "PWRGD_CPUPWRGD_LVC2_R")
		)
		(pad "2" smd circle
			(at -0.40005 0 180)
			(size 0 0)
			(layers "B.Cu" "B.Mask" "B.Paste")
			(net "PWRGD_CPUPWRGD_LVC2_R1")
		)
	)
	(footprint ""
		(layer "B.Cu")
		(at 501.065038 -342.799924)
		(property "Reference" "DB5"
			(at 2.584704 -5.768848 270)
			(unlocked yes)
			(layer "B.SilkS")
			(effects
				(font
					(size 0.7874 0.5842)
					(thickness 0.1524)
				)
				(justify left mirror)
			)
		)
		(property "Value" ""
			(at 0 0 0)
			(layer "B.Fab")
			(effects
				(font
					(size 1.27 1.27)
				)
				(justify mirror)
			)
		)
		(duplicate_pad_numbers_are_jumpers no)
		(fp_line
			(start -3.330702 -4.771136)
			(end 0 4.011168)
			(stroke
				(width 0.1524)
				(type default)
			)
			(layer "B.SilkS")
		)
		(fp_line
			(start 0 4.011168)
			(end 2.826766 -3.442462)
			(stroke
				(width 0.1524)
				(type default)
			)
			(layer "B.SilkS")
		)
		(fp_line
			(start 3.18389 -4.383786)
			(end 3.330702 -4.771136)
			(stroke
				(width 0.1524)
				(type default)
			)
			(layer "B.SilkS")
		)
		(fp_line
			(start 3.330702 -4.771136)
			(end -3.330702 -4.771136)
			(stroke
				(width 0.1524)
				(type default)
			)
			(layer "B.SilkS")
		)
		(fp_line
			(start -3.330702 -4.771136)
			(end 0 4.011168)
			(stroke
				(width 0.1)
				(type default)
			)
			(layer "B.Fab")
		)
		(fp_line
			(start 0 4.011168)
			(end 3.330702 -4.771136)
			(stroke
				(width 0.1)
				(type default)
			)
			(layer "B.Fab")
		)
		(fp_line
			(start 3.330702 -4.771136)
			(end -3.330702 -4.771136)
			(stroke
				(width 0.1)
				(type default)
			)
			(layer "B.Fab")
		)
		(pad "1" thru_hole circle
			(at 0 0 180)
			(size 2.159 2.159)
			(drill 1.7018)
			(layers "*.Cu" "*.Mask")
			(remove_unused_layers no)
			(net "T1_GND")
			(clearance 0.0254)
			(thermal_gap 0.0254)
		)
		(pad "2" thru_hole circle
			(at 1.27 -3.348736 180)
			(size 2.159 2.159)
			(drill 1.7018)
			(layers "*.Cu" "*.Mask")
			(remove_unused_layers no)
			(net "TDR_SE_40_OHM_IN4")
			(clearance 0.0254)
			(thermal_gap 0.0254)
		)
		(pad "3" thru_hole circle
			(at -1.27 -3.348736 180)
			(size 2.159 2.159)
			(drill 1.7018)
			(layers "*.Cu" "*.Mask")
			(remove_unused_layers no)
			(net "TDR_SE_40_OHM_IN4")
			(clearance 0.0254)
			(thermal_gap 0.0254)
		)
	)
	(footprint ""
		(layer "B.Cu")
		(at 186.345068 -13.60043 -90)
		(property "Reference" "R597"
			(at 0 0 90)
			(layer "B.SilkS")
			(hide yes)
			(effects
				(font
					(size 1.27 1.27)
				)
				(justify mirror)
			)
		)
		(property "Value" ""
			(at 0 0 90)
			(layer "B.Fab")
			(effects
				(font
					(size 1.27 1.27)
				)
				(justify mirror)
			)
		)
		(duplicate_pad_numbers_are_jumpers no)
		(fp_line
			(start -0.7874 0.4064)
			(end 0.7874 0.4064)
			(stroke
				(width 0.1524)
				(type default)
			)
			(layer "B.SilkS")
		)
		(fp_line
			(start 0.7874 0.4064)
			(end 0.7874 -0.4064)
			(stroke
				(width 0.1524)
				(type default)
			)
			(layer "B.SilkS")
		)
		(fp_line
			(start -0.7874 -0.4064)
			(end -0.7874 0.4064)
			(stroke
				(width 0.1524)
				(type default)
			)
			(layer "B.SilkS")
		)
		(fp_line
			(start 0.7874 -0.4064)
			(end -0.7874 -0.4064)
			(stroke
				(width 0.1524)
				(type default)
			)
			(layer "B.SilkS")
		)
		(fp_line
			(start -0.67945 0.3048)
			(end -0.120396 0.3048)
			(stroke
				(width 0.1)
				(type default)
			)
			(layer "B.Fab")
		)
		(fp_line
			(start -0.120396 0.3048)
			(end -0.120396 0.2794)
			(stroke
				(width 0.1)
				(type default)
			)
			(layer "B.Fab")
		)
		(fp_line
			(start 0.12065 0.3048)
			(end 0.67945 0.3048)
			(stroke
				(width 0.1)
				(type default)
			)
			(layer "B.Fab")
		)
		(fp_line
			(start 0.67945 0.3048)
			(end 0.67945 -0.305054)
			(stroke
				(width 0.1)
				(type default)
			)
			(layer "B.Fab")
		)
		(fp_line
			(start -0.120396 0.2794)
			(end 0.12065 0.2794)
			(stroke
				(width 0.1)
				(type default)
			)
			(layer "B.Fab")
		)
		(fp_line
			(start 0.12065 0.2794)
			(end 0.12065 0.3048)
			(stroke
				(width 0.1)
				(type default)
			)
			(layer "B.Fab")
		)
		(fp_line
			(start -0.12065 -0.2794)
			(end -0.12065 -0.3048)
			(stroke
				(width 0.1)
				(type default)
			)
			(layer "B.Fab")
		)
		(fp_line
			(start 0.12065 -0.2794)
			(end -0.12065 -0.2794)
			(stroke
				(width 0.1)
				(type default)
			)
			(layer "B.Fab")
		)
		(fp_line
			(start -0.67945 -0.3048)
			(end -0.67945 0.3048)
			(stroke
				(width 0.1)
				(type default)
			)
			(layer "B.Fab")
		)
		(fp_line
			(start -0.12065 -0.3048)
			(end -0.67945 -0.3048)
			(stroke
				(width 0.1)
				(type default)
			)
			(layer "B.Fab")
		)
		(fp_line
			(start 0.12065 -0.305054)
			(end 0.12065 -0.2794)
			(stroke
				(width 0.1)
				(type default)
			)
			(layer "B.Fab")
		)
		(fp_line
			(start 0.67945 -0.305054)
			(end 0.12065 -0.305054)
			(stroke
				(width 0.1)
				(type default)
			)
			(layer "B.Fab")
		)
		(pad "1" smd circle
			(at 0.40005 0 90)
			(size 0 0)
			(layers "B.Cu" "B.Mask" "B.Paste")
			(net "I3C_SPD_DDRABCD_CPU1_BMC_R_SCL")
		)
		(pad "2" smd circle
			(at -0.40005 0 90)
			(size 0 0)
			(layers "B.Cu" "B.Mask" "B.Paste")
			(net "I3C_SPD_DDRABCD_CPU1_BMC_SCL")
		)
	)
	(footprint ""
		(layer "B.Cu")
		(at 110.866936 -359.47985)
		(property "Reference" "PR305"
			(at 0 0 0)
			(layer "B.SilkS")
			(hide yes)
			(effects
				(font
					(size 1.27 1.27)
				)
				(justify mirror)
			)
		)
		(property "Value" ""
			(at 0 0 0)
			(layer "B.Fab")
			(effects
				(font
					(size 1.27 1.27)
				)
				(justify mirror)
			)
		)
		(duplicate_pad_numbers_are_jumpers no)
		(fp_line
			(start -0.7874 -0.4064)
			(end -0.7874 0.4064)
			(stroke
				(width 0.1524)
				(type default)
			)
			(layer "B.SilkS")
		)
		(fp_line
			(start -0.7874 0.4064)
			(end 0.7874 0.4064)
			(stroke
				(width 0.1524)
				(type default)
			)
			(layer "B.SilkS")
		)
		(fp_line
			(start 0.7874 -0.4064)
			(end -0.7874 -0.4064)
			(stroke
				(width 0.1524)
				(type default)
			)
			(layer "B.SilkS")
		)
		(fp_line
			(start 0.7874 0.4064)
			(end 0.7874 -0.4064)
			(stroke
				(width 0.1524)
				(type default)
			)
			(layer "B.SilkS")
		)
		(fp_line
			(start -0.67945 -0.3048)
			(end -0.67945 0.3048)
			(stroke
				(width 0.1)
				(type default)
			)
			(layer "B.Fab")
		)
		(fp_line
			(start -0.67945 0.3048)
			(end -0.120396 0.3048)
			(stroke
				(width 0.1)
				(type default)
			)
			(layer "B.Fab")
		)
		(fp_line
			(start -0.12065 -0.3048)
			(end -0.67945 -0.3048)
			(stroke
				(width 0.1)
				(type default)
			)
			(layer "B.Fab")
		)
		(fp_line
			(start -0.12065 -0.2794)
			(end -0.12065 -0.3048)
			(stroke
				(width 0.1)
				(type default)
			)
			(layer "B.Fab")
		)
		(fp_line
			(start -0.120396 0.2794)
			(end 0.12065 0.2794)
			(stroke
				(width 0.1)
				(type default)
			)
			(layer "B.Fab")
		)
		(fp_line
			(start -0.120396 0.3048)
			(end -0.120396 0.2794)
			(stroke
				(width 0.1)
				(type default)
			)
			(layer "B.Fab")
		)
		(fp_line
			(start 0.12065 -0.305054)
			(end 0.12065 -0.2794)
			(stroke
				(width 0.1)
				(type default)
			)
			(layer "B.Fab")
		)
		(fp_line
			(start 0.12065 -0.2794)
			(end -0.12065 -0.2794)
			(stroke
				(width 0.1)
				(type default)
			)
			(layer "B.Fab")
		)
		(fp_line
			(start 0.12065 0.2794)
			(end 0.12065 0.3048)
			(stroke
				(width 0.1)
				(type default)
			)
			(layer "B.Fab")
		)
		(fp_line
			(start 0.12065 0.3048)
			(end 0.67945 0.3048)
			(stroke
				(width 0.1)
				(type default)
			)
			(layer "B.Fab")
		)
		(fp_line
			(start 0.67945 -0.305054)
			(end 0.12065 -0.305054)
			(stroke
				(width 0.1)
				(type default)
			)
			(layer "B.Fab")
		)
		(fp_line
			(start 0.67945 0.3048)
			(end 0.67945 -0.305054)
			(stroke
				(width 0.1)
				(type default)
			)
			(layer "B.Fab")
		)
		(pad "1" smd circle
			(at 0.40005 0 180)
			(size 0 0)
			(layers "B.Cu" "B.Mask" "B.Paste")
			(net "PVCCIN_CPU1_CSPIN")
		)
		(pad "2" smd circle
			(at -0.40005 0 180)
			(size 0 0)
			(layers "B.Cu" "B.Mask" "B.Paste")
			(net "GND")
		)
	)
	(footprint ""
		(layer "B.Cu")
		(at 331.155294 -333.896208 -90)
		(property "Reference" "PC243_P0_7"
			(at 0 0 90)
			(layer "B.SilkS")
			(hide yes)
			(effects
				(font
					(size 1.27 1.27)
				)
				(justify mirror)
			)
		)
		(property "Value" ""
			(at 0 0 90)
			(layer "B.Fab")
			(effects
				(font
					(size 1.27 1.27)
				)
				(justify mirror)
			)
		)
		(duplicate_pad_numbers_are_jumpers no)
		(fp_line
			(start -0.7874 0.4064)
			(end 0.7874 0.4064)
			(stroke
				(width 0.1524)
				(type default)
			)
			(layer "B.SilkS")
		)
		(fp_line
			(start 0.7874 0.4064)
			(end 0.7874 -0.4064)
			(stroke
				(width 0.1524)
				(type default)
			)
			(layer "B.SilkS")
		)
		(fp_line
			(start -0.7874 -0.4064)
			(end -0.7874 0.4064)
			(stroke
				(width 0.1524)
				(type default)
			)
			(layer "B.SilkS")
		)
		(fp_line
			(start 0.7874 -0.4064)
			(end -0.7874 -0.4064)
			(stroke
				(width 0.1524)
				(type default)
			)
			(layer "B.SilkS")
		)
		(fp_line
			(start -0.67945 0.3048)
			(end -0.120396 0.3048)
			(stroke
				(width 0.1)
				(type default)
			)
			(layer "B.Fab")
		)
		(fp_line
			(start -0.120396 0.3048)
			(end -0.120396 0.2794)
			(stroke
				(width 0.1)
				(type default)
			)
			(layer "B.Fab")
		)
		(fp_line
			(start 0.12065 0.3048)
			(end 0.67945 0.3048)
			(stroke
				(width 0.1)
				(type default)
			)
			(layer "B.Fab")
		)
		(fp_line
			(start 0.67945 0.3048)
			(end 0.67945 -0.305054)
			(stroke
				(width 0.1)
				(type default)
			)
			(layer "B.Fab")
		)
		(fp_line
			(start -0.120396 0.2794)
			(end 0.12065 0.2794)
			(stroke
				(width 0.1)
				(type default)
			)
			(layer "B.Fab")
		)
		(fp_line
			(start 0.12065 0.2794)
			(end 0.12065 0.3048)
			(stroke
				(width 0.1)
				(type default)
			)
			(layer "B.Fab")
		)
		(fp_line
			(start -0.12065 -0.2794)
			(end -0.12065 -0.3048)
			(stroke
				(width 0.1)
				(type default)
			)
			(layer "B.Fab")
		)
		(fp_line
			(start 0.12065 -0.2794)
			(end -0.12065 -0.2794)
			(stroke
				(width 0.1)
				(type default)
			)
			(layer "B.Fab")
		)
		(fp_line
			(start -0.67945 -0.3048)
			(end -0.67945 0.3048)
			(stroke
				(width 0.1)
				(type default)
			)
			(layer "B.Fab")
		)
		(fp_line
			(start -0.12065 -0.3048)
			(end -0.67945 -0.3048)
			(stroke
				(width 0.1)
				(type default)
			)
			(layer "B.Fab")
		)
		(fp_line
			(start 0.12065 -0.305054)
			(end 0.12065 -0.2794)
			(stroke
				(width 0.1)
				(type default)
			)
			(layer "B.Fab")
		)
		(fp_line
			(start 0.67945 -0.305054)
			(end 0.12065 -0.305054)
			(stroke
				(width 0.1)
				(type default)
			)
			(layer "B.Fab")
		)
		(pad "1" smd circle
			(at 0.40005 0 90)
			(size 0 0)
			(layers "B.Cu" "B.Mask" "B.Paste")
			(net "PVCCIN_CPU0")
		)
		(pad "2" smd circle
			(at -0.40005 0 90)
			(size 0 0)
			(layers "B.Cu" "B.Mask" "B.Paste")
			(net "GND")
		)
	)
	(footprint ""
		(layer "B.Cu")
		(at 178.1556 -114.17554 -90)
		(property "Reference" "C1916"
			(at 0 0 90)
			(layer "B.SilkS")
			(hide yes)
			(effects
				(font
					(size 1.27 1.27)
				)
				(justify mirror)
			)
		)
		(property "Value" ""
			(at 0 0 90)
			(layer "B.Fab")
			(effects
				(font
					(size 1.27 1.27)
				)
				(justify mirror)
			)
		)
		(duplicate_pad_numbers_are_jumpers no)
		(fp_line
			(start -0.69215 0.2921)
			(end 0.69215 0.2921)
			(stroke
				(width 0.1524)
				(type default)
			)
			(layer "B.SilkS")
		)
		(fp_line
			(start 0.69215 0.2921)
			(end 0.69215 -0.2921)
			(stroke
				(width 0.1524)
				(type default)
			)
			(layer "B.SilkS")
		)
		(fp_line
			(start -0.69215 -0.2921)
			(end -0.69215 0.2921)
			(stroke
				(width 0.1524)
				(type default)
			)
			(layer "B.SilkS")
		)
		(fp_line
			(start 0.69215 -0.2921)
			(end -0.69215 -0.2921)
			(stroke
				(width 0.1524)
				(type default)
			)
			(layer "B.SilkS")
		)
		(fp_line
			(start -0.51435 0.2794)
			(end 0.51435 0.2794)
			(stroke
				(width 0.1)
				(type default)
			)
			(layer "B.Fab")
		)
		(fp_line
			(start 0.51435 0.2794)
			(end 0.51435 -0.2794)
			(stroke
				(width 0.1)
				(type default)
			)
			(layer "B.Fab")
		)
		(fp_line
			(start -0.51435 -0.2794)
			(end -0.51435 0.2794)
			(stroke
				(width 0.1)
				(type default)
			)
			(layer "B.Fab")
		)
		(fp_line
			(start 0.51435 -0.2794)
			(end -0.51435 -0.2794)
			(stroke
				(width 0.1)
				(type default)
			)
			(layer "B.Fab")
		)
		(pad "1" smd circle
			(at 0.40005 0 90)
			(size 0 0)
			(layers "B.Cu" "B.Mask" "B.Paste")
			(net "VCC_PLD_CORE")
		)
		(pad "2" smd circle
			(at -0.40005 0 90)
			(size 0 0)
			(layers "B.Cu" "B.Mask" "B.Paste")
			(net "GND")
		)
		(zone
			(layer "B.Cu")
			(hatch none 0.5)
			(connect_pads
				(clearance 0)
			)
			(min_thickness 0.25)
			(keepout
				(tracks not_allowed)
				(vias allowed)
				(pads allowed)
				(copperpour not_allowed)
				(footprints allowed)
			)
			(placement
				(enabled no)
				(sheetname "")
			)
			(fill
				(thermal_gap 0.5)
				(thermal_bridge_width 0.5)
				(island_removal_mode 0)
			)
			(polygon
				(pts
					(xy 178.06797 -113.98504) (xy 178.009804 -114.07648) (xy 178.009804 -114.27587) (xy 178.06797 -114.36604)
					(xy 178.24323 -114.36604) (xy 178.30165 -114.27587) (xy 178.30165 -114.07648) (xy 178.243484 -113.98504)
				)
			)
		)
	)
	(footprint ""
		(layer "B.Cu")
		(at 140.6779 -28.429458 90)
		(property "Reference" "U312"
			(at 2.765298 5.54609 0)
			(unlocked yes)
			(layer "B.SilkS")
			(effects
				(font
					(size 0.7874 0.5842)
					(thickness 0.1524)
				)
				(justify left mirror)
			)
		)
		(property "Value" ""
			(at 0 0 90)
			(layer "B.Fab")
			(effects
				(font
					(size 1.27 1.27)
				)
				(justify mirror)
			)
		)
		(duplicate_pad_numbers_are_jumpers no)
		(fp_line
			(start 1.2446 -1.2446)
			(end 1.2446 -0.4318)
			(stroke
				(width 0.1524)
				(type default)
			)
			(layer "B.SilkS")
		)
		(fp_line
			(start -1.2446 -1.2446)
			(end 1.2446 -1.2446)
			(stroke
				(width 0.1524)
				(type default)
			)
			(layer "B.SilkS")
		)
		(fp_line
			(start -1.2446 -0.56896)
			(end -1.2446 -1.2446)
			(stroke
				(width 0.1524)
				(type default)
			)
			(layer "B.SilkS")
		)
		(fp_line
			(start 1.2446 0.54356)
			(end 1.2446 1.2446)
			(stroke
				(width 0.1524)
				(type default)
			)
			(layer "B.SilkS")
		)
		(fp_line
			(start 1.2446 1.2446)
			(end -1.2446 1.2446)
			(stroke
				(width 0.1524)
				(type default)
			)
			(layer "B.SilkS")
		)
		(fp_line
			(start -1.2446 1.2446)
			(end -1.2446 0.54864)
			(stroke
				(width 0.1524)
				(type default)
			)
			(layer "B.SilkS")
		)
		(fp_poly
			(pts
				(xy 1.377442 -0.400304) (xy 1.649476 -1.21666) (xy 2.193544 -0.672592)
			)
			(stroke
				(width 0)
				(type default)
			)
			(fill yes)
			(layer "B.SilkS")
		)
		(fp_line
			(start 0.824992 -0.824992)
			(end 0.824992 0.824992)
			(stroke
				(width 0.1)
				(type default)
			)
			(layer "B.Fab")
		)
		(fp_line
			(start -0.824992 -0.824992)
			(end 0.824992 -0.824992)
			(stroke
				(width 0.1)
				(type default)
			)
			(layer "B.Fab")
		)
		(fp_line
			(start 0.824992 0.824992)
			(end -0.824992 0.824992)
			(stroke
				(width 0.1)
				(type default)
			)
			(layer "B.Fab")
		)
		(fp_line
			(start -0.824992 0.824992)
			(end -0.824992 -0.824992)
			(stroke
				(width 0.1)
				(type default)
			)
			(layer "B.Fab")
		)
		(fp_poly
			(pts
				(xy 1.389634 -0.199898) (xy 2.159 0.184658) (xy 2.159 -0.584708)
			)
			(stroke
				(width 0)
				(type default)
			)
			(fill yes)
			(layer "B.Fab")
		)
		(pad "1" smd rect
			(at 0.700024 -0.199898)
			(size 0.1778 0.8128)
			(layers "B.Cu" "B.Mask" "B.Paste")
			(net "USB2_HUB_2_BUF_EXT_R_DN")
		)
		(pad "2" smd rect
			(at 0.700024 0.199898)
			(size 0.1778 0.8128)
			(layers "B.Cu" "B.Mask" "B.Paste")
			(net "USB2_HUB_2_BUF_EXT_R_DP")
		)
		(pad "3" smd rect
			(at 0.599948 0.8001 270)
			(size 0.1778 0.6096)
			(layers "B.Cu" "B.Mask" "B.Paste")
			(net "TP_USB_HUB_2_TEST")
		)
		(pad "4" smd rect
			(at 0.199898 0.8001 270)
			(size 0.1778 0.6096)
			(layers "B.Cu" "B.Mask" "B.Paste")
			(net "TP_USB_HUB_2_CD")
		)
		(pad "5" smd rect
			(at -0.199898 0.8001 270)
			(size 0.1778 0.6096)
			(layers "B.Cu" "B.Mask" "B.Paste")
			(net "PD_USB_HUB_2_RSTN")
		)
		(pad "6" smd rect
			(at -0.599948 0.8001 270)
			(size 0.1778 0.6096)
			(layers "B.Cu" "B.Mask" "B.Paste")
			(net "PD_USB_HUB_2_EQ")
		)
		(pad "7" smd rect
			(at -0.700024 0.199898)
			(size 0.1778 0.8128)
			(layers "B.Cu" "B.Mask" "B.Paste")
			(net "USB2_HUB_2_BUF_EXT_R_DP")
		)
		(pad "8" smd rect
			(at -0.700024 -0.199898)
			(size 0.1778 0.8128)
			(layers "B.Cu" "B.Mask" "B.Paste")
			(net "USB2_HUB_2_BUF_EXT_R_DN")
		)
		(pad "9" smd rect
			(at -0.599948 -0.8001 270)
			(size 0.1778 0.6096)
			(layers "B.Cu" "B.Mask" "B.Paste")
			(net "TP_USB_HUB_2_ENA_HS")
		)
		(pad "10" smd rect
			(at -0.199898 -0.8001 270)
			(size 0.1778 0.6096)
			(layers "B.Cu" "B.Mask" "B.Paste")
			(net "GND")
		)
		(pad "11" smd rect
			(at 0.199898 -0.8001 270)
			(size 0.1778 0.6096)
			(layers "B.Cu" "B.Mask" "B.Paste")
			(net "PD_USB_HUB_2_VREG")
		)
		(pad "12" smd rect
			(at 0.599948 -0.8001 270)
			(size 0.1778 0.6096)
			(layers "B.Cu" "B.Mask" "B.Paste")
			(net "P3V3_AUX")
		)
	)
	(footprint ""
		(layer "B.Cu")
		(at 179.506626 -417.030154 180)
		(property "Reference" "R2801"
			(at 0 0 0)
			(layer "B.SilkS")
			(hide yes)
			(effects
				(font
					(size 1.27 1.27)
				)
				(justify mirror)
			)
		)
		(property "Value" ""
			(at 0 0 0)
			(layer "B.Fab")
			(effects
				(font
					(size 1.27 1.27)
				)
				(justify mirror)
			)
		)
		(duplicate_pad_numbers_are_jumpers no)
		(fp_line
			(start 0.7874 0.4064)
			(end 0.7874 -0.4064)
			(stroke
				(width 0.1524)
				(type default)
			)
			(layer "B.SilkS")
		)
		(fp_line
			(start 0.7874 -0.4064)
			(end -0.7874 -0.4064)
			(stroke
				(width 0.1524)
				(type default)
			)
			(layer "B.SilkS")
		)
		(fp_line
			(start -0.7874 0.4064)
			(end 0.7874 0.4064)
			(stroke
				(width 0.1524)
				(type default)
			)
			(layer "B.SilkS")
		)
		(fp_line
			(start -0.7874 -0.4064)
			(end -0.7874 0.4064)
			(stroke
				(width 0.1524)
				(type default)
			)
			(layer "B.SilkS")
		)
		(fp_line
			(start 0.67945 0.3048)
			(end 0.67945 -0.305054)
			(stroke
				(width 0.1)
				(type default)
			)
			(layer "B.Fab")
		)
		(fp_line
			(start 0.67945 -0.305054)
			(end 0.12065 -0.305054)
			(stroke
				(width 0.1)
				(type default)
			)
			(layer "B.Fab")
		)
		(fp_line
			(start 0.12065 0.3048)
			(end 0.67945 0.3048)
			(stroke
				(width 0.1)
				(type default)
			)
			(layer "B.Fab")
		)
		(fp_line
			(start 0.12065 0.2794)
			(end 0.12065 0.3048)
			(stroke
				(width 0.1)
				(type default)
			)
			(layer "B.Fab")
		)
		(fp_line
			(start 0.12065 -0.2794)
			(end -0.12065 -0.2794)
			(stroke
				(width 0.1)
				(type default)
			)
			(layer "B.Fab")
		)
		(fp_line
			(start 0.12065 -0.305054)
			(end 0.12065 -0.2794)
			(stroke
				(width 0.1)
				(type default)
			)
			(layer "B.Fab")
		)
		(fp_line
			(start -0.120396 0.3048)
			(end -0.120396 0.2794)
			(stroke
				(width 0.1)
				(type default)
			)
			(layer "B.Fab")
		)
		(fp_line
			(start -0.120396 0.2794)
			(end 0.12065 0.2794)
			(stroke
				(width 0.1)
				(type default)
			)
			(layer "B.Fab")
		)
		(fp_line
			(start -0.12065 -0.2794)
			(end -0.12065 -0.3048)
			(stroke
				(width 0.1)
				(type default)
			)
			(layer "B.Fab")
		)
		(fp_line
			(start -0.12065 -0.3048)
			(end -0.67945 -0.3048)
			(stroke
				(width 0.1)
				(type default)
			)
			(layer "B.Fab")
		)
		(fp_line
			(start -0.67945 0.3048)
			(end -0.120396 0.3048)
			(stroke
				(width 0.1)
				(type default)
			)
			(layer "B.Fab")
		)
		(fp_line
			(start -0.67945 -0.3048)
			(end -0.67945 0.3048)
			(stroke
				(width 0.1)
				(type default)
			)
			(layer "B.Fab")
		)
		(pad "1" smd circle
			(at 0.40005 0)
			(size 0 0)
			(layers "B.Cu" "B.Mask" "B.Paste")
			(net "SMB_FAN_3V3AUX_R_SDA")
		)
		(pad "2" smd circle
			(at -0.40005 0)
			(size 0 0)
			(layers "B.Cu" "B.Mask" "B.Paste")
			(net "SMB_FAN_3V3AUX_BUF_SDA")
		)
	)
	(footprint ""
		(layer "B.Cu")
		(at 346.026486 -54.487826 90)
		(property "Reference" "C1252"
			(at 0 0 90)
			(layer "B.SilkS")
			(hide yes)
			(effects
				(font
					(size 1.27 1.27)
				)
				(justify mirror)
			)
		)
		(property "Value" ""
			(at 0 0 90)
			(layer "B.Fab")
			(effects
				(font
					(size 1.27 1.27)
				)
				(justify mirror)
			)
		)
		(duplicate_pad_numbers_are_jumpers no)
		(fp_line
			(start 1.125982 -0.5842)
			(end -1.2954 -0.5842)
			(stroke
				(width 0.1524)
				(type default)
			)
			(layer "B.SilkS")
		)
		(fp_line
			(start 0 -0.5842)
			(end 0 0.5842)
			(stroke
				(width 0.1524)
				(type default)
			)
			(layer "B.SilkS")
		)
		(fp_line
			(start -1.2954 -0.5842)
			(end -1.2954 0.5842)
			(stroke
				(width 0.1524)
				(type default)
			)
			(layer "B.SilkS")
		)
		(fp_line
			(start 1.2954 0.5842)
			(end 1.2954 -0.350266)
			(stroke
				(width 0.1524)
				(type default)
			)
			(layer "B.SilkS")
		)
		(fp_line
			(start -1.2954 0.5842)
			(end 1.2954 0.5842)
			(stroke
				(width 0.1524)
				(type default)
			)
			(layer "B.SilkS")
		)
		(fp_line
			(start 0.8636 -0.4572)
			(end -0.8636 -0.4572)
			(stroke
				(width 0.1)
				(type default)
			)
			(layer "B.Fab")
		)
		(fp_line
			(start -0.8636 -0.4572)
			(end -0.8636 -0.4064)
			(stroke
				(width 0.1)
				(type default)
			)
			(layer "B.Fab")
		)
		(fp_line
			(start 1.1938 -0.4064)
			(end 0.8636 -0.4064)
			(stroke
				(width 0.1)
				(type default)
			)
			(layer "B.Fab")
		)
		(fp_line
			(start 0.8636 -0.4064)
			(end 0.8636 -0.4572)
			(stroke
				(width 0.1)
				(type default)
			)
			(layer "B.Fab")
		)
		(fp_line
			(start -0.8636 -0.4064)
			(end -1.1938 -0.4064)
			(stroke
				(width 0.1)
				(type default)
			)
			(layer "B.Fab")
		)
		(fp_line
			(start -1.1938 -0.4064)
			(end -1.1938 0.4064)
			(stroke
				(width 0.1)
				(type default)
			)
			(layer "B.Fab")
		)
		(fp_line
			(start 1.1938 0.4064)
			(end 1.1938 -0.4064)
			(stroke
				(width 0.1)
				(type default)
			)
			(layer "B.Fab")
		)
		(fp_line
			(start 0.8636 0.4064)
			(end 1.1938 0.4064)
			(stroke
				(width 0.1)
				(type default)
			)
			(layer "B.Fab")
		)
		(fp_line
			(start -0.8636 0.4064)
			(end -0.8636 0.4572)
			(stroke
				(width 0.1)
				(type default)
			)
			(layer "B.Fab")
		)
		(fp_line
			(start -1.1938 0.4064)
			(end -0.8636 0.4064)
			(stroke
				(width 0.1)
				(type default)
			)
			(layer "B.Fab")
		)
		(fp_line
			(start 0.8636 0.4572)
			(end 0.8636 0.4064)
			(stroke
				(width 0.1)
				(type default)
			)
			(layer "B.Fab")
		)
		(fp_line
			(start -0.8636 0.4572)
			(end 0.8636 0.4572)
			(stroke
				(width 0.1)
				(type default)
			)
			(layer "B.Fab")
		)
		(pad "1" smd rect
			(at 0.7366 0)
			(size 0.7112 0.8128)
			(layers "B.Cu" "B.Mask" "B.Paste")
			(net "P1V8_PCH_PLL_AUX")
		)
		(pad "2" smd rect
			(at -0.7366 0)
			(size 0.7112 0.8128)
			(layers "B.Cu" "B.Mask" "B.Paste")
			(net "GND")
		)
	)
	(footprint ""
		(layer "B.Cu")
		(at 118.18112 -255.8542 -90)
		(property "Reference" "C332"
			(at 0 0 90)
			(layer "B.SilkS")
			(hide yes)
			(effects
				(font
					(size 1.27 1.27)
				)
				(justify mirror)
			)
		)
		(property "Value" ""
			(at 0 0 90)
			(layer "B.Fab")
			(effects
				(font
					(size 1.27 1.27)
				)
				(justify mirror)
			)
		)
		(duplicate_pad_numbers_are_jumpers no)
		(fp_line
			(start -1.524 0.762)
			(end 1.524 0.762)
			(stroke
				(width 0.1524)
				(type default)
			)
			(layer "B.SilkS")
		)
		(fp_line
			(start 1.524 0.762)
			(end 1.524 -0.762)
			(stroke
				(width 0.1524)
				(type default)
			)
			(layer "B.SilkS")
		)
		(fp_line
			(start -1.524 -0.762)
			(end -1.524 0.762)
			(stroke
				(width 0.1524)
				(type default)
			)
			(layer "B.SilkS")
		)
		(fp_line
			(start 1.524 -0.762)
			(end -1.524 -0.762)
			(stroke
				(width 0.1524)
				(type default)
			)
			(layer "B.SilkS")
		)
		(fp_line
			(start -1.1049 0.724916)
			(end -1.1049 -0.724916)
			(stroke
				(width 0.1)
				(type default)
			)
			(layer "B.Fab")
		)
		(fp_line
			(start 1.1049 0.724916)
			(end -1.1049 0.724916)
			(stroke
				(width 0.1)
				(type default)
			)
			(layer "B.Fab")
		)
		(fp_line
			(start -1.1049 -0.724916)
			(end 1.1049 -0.724916)
			(stroke
				(width 0.1)
				(type default)
			)
			(layer "B.Fab")
		)
		(fp_line
			(start 1.1049 -0.724916)
			(end 1.1049 0.724916)
			(stroke
				(width 0.1)
				(type default)
			)
			(layer "B.Fab")
		)
		(pad "1" smd rect
			(at 0.889 0 270)
			(size 1.016 1.27)
			(layers "B.Cu" "B.Mask" "B.Paste")
			(net "PVCCIN_CPU1")
		)
		(pad "2" smd rect
			(at -0.889 0 270)
			(size 1.016 1.27)
			(layers "B.Cu" "B.Mask" "B.Paste")
			(net "GND")
		)
	)
	(footprint ""
		(layer "B.Cu")
		(at 245.835424 -99.136708)
		(property "Reference" "R953"
			(at 0 0 0)
			(layer "B.SilkS")
			(hide yes)
			(effects
				(font
					(size 1.27 1.27)
				)
				(justify mirror)
			)
		)
		(property "Value" ""
			(at 0 0 0)
			(layer "B.Fab")
			(effects
				(font
					(size 1.27 1.27)
				)
				(justify mirror)
			)
		)
		(duplicate_pad_numbers_are_jumpers no)
		(fp_line
			(start -0.7874 -0.4064)
			(end -0.7874 0.4064)
			(stroke
				(width 0.1524)
				(type default)
			)
			(layer "B.SilkS")
		)
		(fp_line
			(start -0.7874 0.4064)
			(end 0.7874 0.4064)
			(stroke
				(width 0.1524)
				(type default)
			)
			(layer "B.SilkS")
		)
		(fp_line
			(start 0.7874 -0.4064)
			(end -0.7874 -0.4064)
			(stroke
				(width 0.1524)
				(type default)
			)
			(layer "B.SilkS")
		)
		(fp_line
			(start 0.7874 0.4064)
			(end 0.7874 -0.4064)
			(stroke
				(width 0.1524)
				(type default)
			)
			(layer "B.SilkS")
		)
		(fp_line
			(start -0.67945 -0.3048)
			(end -0.67945 0.3048)
			(stroke
				(width 0.1)
				(type default)
			)
			(layer "B.Fab")
		)
		(fp_line
			(start -0.67945 0.3048)
			(end -0.120396 0.3048)
			(stroke
				(width 0.1)
				(type default)
			)
			(layer "B.Fab")
		)
		(fp_line
			(start -0.12065 -0.3048)
			(end -0.67945 -0.3048)
			(stroke
				(width 0.1)
				(type default)
			)
			(layer "B.Fab")
		)
		(fp_line
			(start -0.12065 -0.2794)
			(end -0.12065 -0.3048)
			(stroke
				(width 0.1)
				(type default)
			)
			(layer "B.Fab")
		)
		(fp_line
			(start -0.120396 0.2794)
			(end 0.12065 0.2794)
			(stroke
				(width 0.1)
				(type default)
			)
			(layer "B.Fab")
		)
		(fp_line
			(start -0.120396 0.3048)
			(end -0.120396 0.2794)
			(stroke
				(width 0.1)
				(type default)
			)
			(layer "B.Fab")
		)
		(fp_line
			(start 0.12065 -0.305054)
			(end 0.12065 -0.2794)
			(stroke
				(width 0.1)
				(type default)
			)
			(layer "B.Fab")
		)
		(fp_line
			(start 0.12065 -0.2794)
			(end -0.12065 -0.2794)
			(stroke
				(width 0.1)
				(type default)
			)
			(layer "B.Fab")
		)
		(fp_line
			(start 0.12065 0.2794)
			(end 0.12065 0.3048)
			(stroke
				(width 0.1)
				(type default)
			)
			(layer "B.Fab")
		)
		(fp_line
			(start 0.12065 0.3048)
			(end 0.67945 0.3048)
			(stroke
				(width 0.1)
				(type default)
			)
			(layer "B.Fab")
		)
		(fp_line
			(start 0.67945 -0.305054)
			(end 0.12065 -0.305054)
			(stroke
				(width 0.1)
				(type default)
			)
			(layer "B.Fab")
		)
		(fp_line
			(start 0.67945 0.3048)
			(end 0.67945 -0.305054)
			(stroke
				(width 0.1)
				(type default)
			)
			(layer "B.Fab")
		)
		(pad "1" smd circle
			(at 0.40005 0 180)
			(size 0 0)
			(layers "B.Cu" "B.Mask" "B.Paste")
			(net "CLK_CK440_SMB_ADDR0")
		)
		(pad "2" smd circle
			(at -0.40005 0 180)
			(size 0 0)
			(layers "B.Cu" "B.Mask" "B.Paste")
			(net "GND")
		)
	)
	(footprint ""
		(layer "B.Cu")
		(at 302.218852 -53.018182 180)
		(property "Reference" "C1178"
			(at 0 0 0)
			(layer "B.SilkS")
			(hide yes)
			(effects
				(font
					(size 1.27 1.27)
				)
				(justify mirror)
			)
		)
		(property "Value" ""
			(at 0 0 0)
			(layer "B.Fab")
			(effects
				(font
					(size 1.27 1.27)
				)
				(justify mirror)
			)
		)
		(duplicate_pad_numbers_are_jumpers no)
		(fp_line
			(start 1.2954 0.5842)
			(end 1.2954 -0.5842)
			(stroke
				(width 0.1524)
				(type default)
			)
			(layer "B.SilkS")
		)
		(fp_line
			(start 1.2954 -0.5842)
			(end -1.2954 -0.5842)
			(stroke
				(width 0.1524)
				(type default)
			)
			(layer "B.SilkS")
		)
		(fp_line
			(start 0 -0.5842)
			(end 0 0.5842)
			(stroke
				(width 0.1524)
				(type default)
			)
			(layer "B.SilkS")
		)
		(fp_line
			(start -1.2954 0.5842)
			(end 1.2954 0.5842)
			(stroke
				(width 0.1524)
				(type default)
			)
			(layer "B.SilkS")
		)
		(fp_line
			(start -1.2954 -0.5842)
			(end -1.2954 0.5842)
			(stroke
				(width 0.1524)
				(type default)
			)
			(layer "B.SilkS")
		)
		(fp_line
			(start 1.1938 0.4064)
			(end 1.1938 -0.4064)
			(stroke
				(width 0.1)
				(type default)
			)
			(layer "B.Fab")
		)
		(fp_line
			(start 1.1938 -0.4064)
			(end 0.8636 -0.4064)
			(stroke
				(width 0.1)
				(type default)
			)
			(layer "B.Fab")
		)
		(fp_line
			(start 0.8636 0.4572)
			(end 0.8636 0.4064)
			(stroke
				(width 0.1)
				(type default)
			)
			(layer "B.Fab")
		)
		(fp_line
			(start 0.8636 0.4064)
			(end 1.1938 0.4064)
			(stroke
				(width 0.1)
				(type default)
			)
			(layer "B.Fab")
		)
		(fp_line
			(start 0.8636 -0.4064)
			(end 0.8636 -0.4572)
			(stroke
				(width 0.1)
				(type default)
			)
			(layer "B.Fab")
		)
		(fp_line
			(start 0.8636 -0.4572)
			(end -0.8636 -0.4572)
			(stroke
				(width 0.1)
				(type default)
			)
			(layer "B.Fab")
		)
		(fp_line
			(start -0.8636 0.4572)
			(end 0.8636 0.4572)
			(stroke
				(width 0.1)
				(type default)
			)
			(layer "B.Fab")
		)
		(fp_line
			(start -0.8636 0.4064)
			(end -0.8636 0.4572)
			(stroke
				(width 0.1)
				(type default)
			)
			(layer "B.Fab")
		)
		(fp_line
			(start -0.8636 -0.4064)
			(end -1.1938 -0.4064)
			(stroke
				(width 0.1)
				(type default)
			)
			(layer "B.Fab")
		)
		(fp_line
			(start -0.8636 -0.4572)
			(end -0.8636 -0.4064)
			(stroke
				(width 0.1)
				(type default)
			)
			(layer "B.Fab")
		)
		(fp_line
			(start -1.1938 0.4064)
			(end -0.8636 0.4064)
			(stroke
				(width 0.1)
				(type default)
			)
			(layer "B.Fab")
		)
		(fp_line
			(start -1.1938 -0.4064)
			(end -1.1938 0.4064)
			(stroke
				(width 0.1)
				(type default)
			)
			(layer "B.Fab")
		)
		(pad "1" smd rect
			(at 0.7366 0 90)
			(size 0.7112 0.8128)
			(layers "B.Cu" "B.Mask" "B.Paste")
			(net "P1V05_PCH_AUX")
		)
		(pad "2" smd rect
			(at -0.7366 0 90)
			(size 0.7112 0.8128)
			(layers "B.Cu" "B.Mask" "B.Paste")
			(net "GND")
		)
	)
	(footprint ""
		(layer "B.Cu")
		(at 106.281474 -359.47985 180)
		(property "Reference" "C2860"
			(at 0 0 0)
			(layer "B.SilkS")
			(hide yes)
			(effects
				(font
					(size 1.27 1.27)
				)
				(justify mirror)
			)
		)
		(property "Value" ""
			(at 0 0 0)
			(layer "B.Fab")
			(effects
				(font
					(size 1.27 1.27)
				)
				(justify mirror)
			)
		)
		(duplicate_pad_numbers_are_jumpers no)
		(fp_line
			(start 0.7874 0.4064)
			(end 0.7874 -0.4064)
			(stroke
				(width 0.1524)
				(type default)
			)
			(layer "B.SilkS")
		)
		(fp_line
			(start 0.7874 -0.4064)
			(end -0.7874 -0.4064)
			(stroke
				(width 0.1524)
				(type default)
			)
			(layer "B.SilkS")
		)
		(fp_line
			(start -0.7874 0.4064)
			(end 0.7874 0.4064)
			(stroke
				(width 0.1524)
				(type default)
			)
			(layer "B.SilkS")
		)
		(fp_line
			(start -0.7874 -0.4064)
			(end -0.7874 0.4064)
			(stroke
				(width 0.1524)
				(type default)
			)
			(layer "B.SilkS")
		)
		(fp_line
			(start 0.67945 0.3048)
			(end 0.67945 -0.305054)
			(stroke
				(width 0.1)
				(type default)
			)
			(layer "B.Fab")
		)
		(fp_line
			(start 0.67945 -0.305054)
			(end 0.12065 -0.305054)
			(stroke
				(width 0.1)
				(type default)
			)
			(layer "B.Fab")
		)
		(fp_line
			(start 0.12065 0.3048)
			(end 0.67945 0.3048)
			(stroke
				(width 0.1)
				(type default)
			)
			(layer "B.Fab")
		)
		(fp_line
			(start 0.12065 0.2794)
			(end 0.12065 0.3048)
			(stroke
				(width 0.1)
				(type default)
			)
			(layer "B.Fab")
		)
		(fp_line
			(start 0.12065 -0.2794)
			(end -0.12065 -0.2794)
			(stroke
				(width 0.1)
				(type default)
			)
			(layer "B.Fab")
		)
		(fp_line
			(start 0.12065 -0.305054)
			(end 0.12065 -0.2794)
			(stroke
				(width 0.1)
				(type default)
			)
			(layer "B.Fab")
		)
		(fp_line
			(start -0.120396 0.3048)
			(end -0.120396 0.2794)
			(stroke
				(width 0.1)
				(type default)
			)
			(layer "B.Fab")
		)
		(fp_line
			(start -0.120396 0.2794)
			(end 0.12065 0.2794)
			(stroke
				(width 0.1)
				(type default)
			)
			(layer "B.Fab")
		)
		(fp_line
			(start -0.12065 -0.2794)
			(end -0.12065 -0.3048)
			(stroke
				(width 0.1)
				(type default)
			)
			(layer "B.Fab")
		)
		(fp_line
			(start -0.12065 -0.3048)
			(end -0.67945 -0.3048)
			(stroke
				(width 0.1)
				(type default)
			)
			(layer "B.Fab")
		)
		(fp_line
			(start -0.67945 0.3048)
			(end -0.120396 0.3048)
			(stroke
				(width 0.1)
				(type default)
			)
			(layer "B.Fab")
		)
		(fp_line
			(start -0.67945 -0.3048)
			(end -0.67945 0.3048)
			(stroke
				(width 0.1)
				(type default)
			)
			(layer "B.Fab")
		)
		(pad "1" smd circle
			(at 0.40005 0)
			(size 0 0)
			(layers "B.Cu" "B.Mask" "B.Paste")
			(net "PVCCIN_CPU1_EN_R")
		)
		(pad "2" smd circle
			(at -0.40005 0)
			(size 0 0)
			(layers "B.Cu" "B.Mask" "B.Paste")
			(net "GND")
		)
	)
	(footprint ""
		(layer "B.Cu")
		(at 514.718808 2.286 90)
		(property "Reference" "X17"
			(at 1.35128 3.208782 270)
			(unlocked yes)
			(layer "B.SilkS")
			(effects
				(font
					(size 0.7874 0.5842)
					(thickness 0.1524)
				)
				(justify left mirror)
			)
		)
		(property "Value" ""
			(at 0 0 90)
			(layer "B.Fab")
			(effects
				(font
					(size 1.27 1.27)
				)
				(justify mirror)
			)
		)
		(property "Device Type" "TP_TDR_4P_FTS_TH-TP_TDR_4P_DIPA"
			(at -1.30175 1.27 0)
			(unlocked yes)
			(layer "B.Fab")
			(hide yes)
			(effects
				(font
					(size 0.635 0.4064)
					(thickness 0.1524)
				)
				(justify mirror)
			)
		)
		(property "User Part Number" "N_A"
			(at -1.30175 1.27 0)
			(unlocked yes)
			(layer "Cmts.User")
			(hide yes)
			(effects
				(font
					(size 0.635 0.4064)
					(thickness 0.1524)
				)
				(justify mirror)
			)
		)
		(duplicate_pad_numbers_are_jumpers no)
		(fp_line
			(start 0 -1.27)
			(end 0 -0.635)
			(stroke
				(width 0.1524)
				(type default)
			)
			(layer "B.SilkS")
		)
		(fp_line
			(start -2.54 -1.27)
			(end 0 -1.27)
			(stroke
				(width 0.1524)
				(type default)
			)
			(layer "B.SilkS")
		)
		(fp_line
			(start -2.54 -1.1303)
			(end -2.54 -1.27)
			(stroke
				(width 0.1524)
				(type default)
			)
			(layer "B.SilkS")
		)
		(fp_line
			(start 0 0.635)
			(end 0 1.905)
			(stroke
				(width 0.1524)
				(type default)
			)
			(layer "B.SilkS")
		)
		(fp_line
			(start -2.54 1.4097)
			(end -2.54 1.1303)
			(stroke
				(width 0.1524)
				(type default)
			)
			(layer "B.SilkS")
		)
		(fp_line
			(start 0 3.175)
			(end 0 3.81)
			(stroke
				(width 0.1524)
				(type default)
			)
			(layer "B.SilkS")
		)
		(fp_line
			(start 0 3.81)
			(end -2.54 3.81)
			(stroke
				(width 0.1524)
				(type default)
			)
			(layer "B.SilkS")
		)
		(fp_line
			(start -2.54 3.81)
			(end -2.54 3.6703)
			(stroke
				(width 0.1524)
				(type default)
			)
			(layer "B.SilkS")
		)
		(fp_poly
			(pts
				(xy 2.285746 -0.762) (xy 2.285746 0.762) (xy 0.761746 0)
			)
			(stroke
				(width 0)
				(type default)
			)
			(fill yes)
			(layer "B.SilkS")
		)
		(fp_line
			(start 0 -1.27)
			(end 0 3.81)
			(stroke
				(width 0.1)
				(type default)
			)
			(layer "B.Fab")
		)
		(fp_line
			(start -2.54 -1.27)
			(end 0 -1.27)
			(stroke
				(width 0.1)
				(type default)
			)
			(layer "B.Fab")
		)
		(fp_line
			(start 0 3.81)
			(end -2.54 3.81)
			(stroke
				(width 0.1)
				(type default)
			)
			(layer "B.Fab")
		)
		(fp_line
			(start -2.54 3.81)
			(end -2.54 -1.27)
			(stroke
				(width 0.1)
				(type default)
			)
			(layer "B.Fab")
		)
		(fp_poly
			(pts
				(xy 0.761746 0) (xy 2.285746 -0.762) (xy 2.285746 0.762)
			)
			(stroke
				(width 0)
				(type default)
			)
			(fill yes)
			(layer "B.Fab")
		)
		(pad "1" thru_hole circle
			(at 0 0 270)
			(size 1.0033 1.0033)
			(drill 0.249936)
			(layers "*.Cu" "*.Mask")
			(remove_unused_layers no)
			(net "TDR_DIFF_100_IN4_DP")
			(clearance 0.10795)
			(padstack
				(mode front_inner_back)
				(layer "Inner"
					(shape circle)
					(size 0.8001 0.8001)
					(clearance 0.1524)
				)
				(layer "B.Cu"
					(shape circle)
					(size 1.0033 1.0033)
					(thermal_gap 0.10795)
					(clearance 0.10795)
				)
			)
		)
		(pad "2" thru_hole circle
			(at -2.54 0 270)
			(size 1.9939 1.9939)
			(drill 0.249936)
			(layers "*.Cu" "*.Mask")
			(remove_unused_layers no)
			(net "T1_GND")
			(clearance 0.10795)
			(padstack
				(mode front_inner_back)
				(layer "Inner"
					(shape circle)
					(size 0.8001 0.8001)
					(clearance 0.1524)
				)
				(layer "B.Cu"
					(shape circle)
					(size 1.9939 1.9939)
					(thermal_gap 0.10795)
					(clearance 0.10795)
				)
			)
		)
		(pad "3" thru_hole circle
			(at -2.54 2.54 270)
			(size 1.9939 1.9939)
			(drill 0.249936)
			(layers "*.Cu" "*.Mask")
			(remove_unused_layers no)
			(net "T1_GND")
			(clearance 0.10795)
			(padstack
				(mode front_inner_back)
				(layer "Inner"
					(shape circle)
					(size 0.8001 0.8001)
					(clearance 0.1524)
				)
				(layer "B.Cu"
					(shape circle)
					(size 1.9939 1.9939)
					(thermal_gap 0.10795)
					(clearance 0.10795)
				)
			)
		)
		(pad "4" thru_hole circle
			(at 0 2.54 270)
			(size 1.0033 1.0033)
			(drill 0.249936)
			(layers "*.Cu" "*.Mask")
			(remove_unused_layers no)
			(net "TDR_DIFF_100_IN4_DN")
			(clearance 0.10795)
			(padstack
				(mode front_inner_back)
				(layer "Inner"
					(shape circle)
					(size 0.8001 0.8001)
					(clearance 0.1524)
				)
				(layer "B.Cu"
					(shape circle)
					(size 1.0033 1.0033)
					(thermal_gap 0.10795)
					(clearance 0.10795)
				)
			)
		)
	)
	(footprint ""
		(layer "B.Cu")
		(at 369.485418 -296.054526 180)
		(property "Reference" "C398"
			(at 0 0 0)
			(layer "B.SilkS")
			(hide yes)
			(effects
				(font
					(size 1.27 1.27)
				)
				(justify mirror)
			)
		)
		(property "Value" ""
			(at 0 0 0)
			(layer "B.Fab")
			(effects
				(font
					(size 1.27 1.27)
				)
				(justify mirror)
			)
		)
		(duplicate_pad_numbers_are_jumpers no)
		(fp_line
			(start 1.524 0.762)
			(end 1.524 -0.762)
			(stroke
				(width 0.1524)
				(type default)
			)
			(layer "B.SilkS")
		)
		(fp_line
			(start 1.524 -0.762)
			(end -1.524 -0.762)
			(stroke
				(width 0.1524)
				(type default)
			)
			(layer "B.SilkS")
		)
		(fp_line
			(start -1.524 0.762)
			(end 1.524 0.762)
			(stroke
				(width 0.1524)
				(type default)
			)
			(layer "B.SilkS")
		)
		(fp_line
			(start -1.524 -0.762)
			(end -1.524 0.762)
			(stroke
				(width 0.1524)
				(type default)
			)
			(layer "B.SilkS")
		)
		(fp_line
			(start 1.1049 0.724916)
			(end -1.1049 0.724916)
			(stroke
				(width 0.1)
				(type default)
			)
			(layer "B.Fab")
		)
		(fp_line
			(start 1.1049 -0.724916)
			(end 1.1049 0.724916)
			(stroke
				(width 0.1)
				(type default)
			)
			(layer "B.Fab")
		)
		(fp_line
			(start -1.1049 0.724916)
			(end -1.1049 -0.724916)
			(stroke
				(width 0.1)
				(type default)
			)
			(layer "B.Fab")
		)
		(fp_line
			(start -1.1049 -0.724916)
			(end 1.1049 -0.724916)
			(stroke
				(width 0.1)
				(type default)
			)
			(layer "B.Fab")
		)
		(pad "1" smd rect
			(at 0.889 0 180)
			(size 1.016 1.27)
			(layers "B.Cu" "B.Mask" "B.Paste")
			(net "PVCCIN_CPU0")
		)
		(pad "2" smd rect
			(at -0.889 0 180)
			(size 1.016 1.27)
			(layers "B.Cu" "B.Mask" "B.Paste")
			(net "GND")
		)
	)
	(footprint ""
		(layer "B.Cu")
		(at 312.443622 -34.102548 180)
		(property "Reference" "R494"
			(at 0 0 0)
			(layer "B.SilkS")
			(hide yes)
			(effects
				(font
					(size 1.27 1.27)
				)
				(justify mirror)
			)
		)
		(property "Value" ""
			(at 0 0 0)
			(layer "B.Fab")
			(effects
				(font
					(size 1.27 1.27)
				)
				(justify mirror)
			)
		)
		(duplicate_pad_numbers_are_jumpers no)
		(fp_line
			(start 0.7874 0.4064)
			(end 0.7874 -0.4064)
			(stroke
				(width 0.1524)
				(type default)
			)
			(layer "B.SilkS")
		)
		(fp_line
			(start 0.7874 -0.4064)
			(end -0.7874 -0.4064)
			(stroke
				(width 0.1524)
				(type default)
			)
			(layer "B.SilkS")
		)
		(fp_line
			(start -0.7874 0.4064)
			(end 0.7874 0.4064)
			(stroke
				(width 0.1524)
				(type default)
			)
			(layer "B.SilkS")
		)
		(fp_line
			(start -0.7874 -0.4064)
			(end -0.7874 0.4064)
			(stroke
				(width 0.1524)
				(type default)
			)
			(layer "B.SilkS")
		)
		(fp_line
			(start 0.67945 0.3048)
			(end 0.67945 -0.305054)
			(stroke
				(width 0.1)
				(type default)
			)
			(layer "B.Fab")
		)
		(fp_line
			(start 0.67945 -0.305054)
			(end 0.12065 -0.305054)
			(stroke
				(width 0.1)
				(type default)
			)
			(layer "B.Fab")
		)
		(fp_line
			(start 0.12065 0.3048)
			(end 0.67945 0.3048)
			(stroke
				(width 0.1)
				(type default)
			)
			(layer "B.Fab")
		)
		(fp_line
			(start 0.12065 0.2794)
			(end 0.12065 0.3048)
			(stroke
				(width 0.1)
				(type default)
			)
			(layer "B.Fab")
		)
		(fp_line
			(start 0.12065 -0.2794)
			(end -0.12065 -0.2794)
			(stroke
				(width 0.1)
				(type default)
			)
			(layer "B.Fab")
		)
		(fp_line
			(start 0.12065 -0.305054)
			(end 0.12065 -0.2794)
			(stroke
				(width 0.1)
				(type default)
			)
			(layer "B.Fab")
		)
		(fp_line
			(start -0.120396 0.3048)
			(end -0.120396 0.2794)
			(stroke
				(width 0.1)
				(type default)
			)
			(layer "B.Fab")
		)
		(fp_line
			(start -0.120396 0.2794)
			(end 0.12065 0.2794)
			(stroke
				(width 0.1)
				(type default)
			)
			(layer "B.Fab")
		)
		(fp_line
			(start -0.12065 -0.2794)
			(end -0.12065 -0.3048)
			(stroke
				(width 0.1)
				(type default)
			)
			(layer "B.Fab")
		)
		(fp_line
			(start -0.12065 -0.3048)
			(end -0.67945 -0.3048)
			(stroke
				(width 0.1)
				(type default)
			)
			(layer "B.Fab")
		)
		(fp_line
			(start -0.67945 0.3048)
			(end -0.120396 0.3048)
			(stroke
				(width 0.1)
				(type default)
			)
			(layer "B.Fab")
		)
		(fp_line
			(start -0.67945 -0.3048)
			(end -0.67945 0.3048)
			(stroke
				(width 0.1)
				(type default)
			)
			(layer "B.Fab")
		)
		(pad "1" smd circle
			(at 0.40005 0)
			(size 0 0)
			(layers "B.Cu" "B.Mask" "B.Paste")
			(net "P3V3_AUX")
		)
		(pad "2" smd circle
			(at -0.40005 0)
			(size 0 0)
			(layers "B.Cu" "B.Mask" "B.Paste")
			(net "IRQ_LVC3_WAKE_N")
		)
	)
	(footprint ""
		(layer "B.Cu")
		(at 118.18112 -259.53212 90)
		(property "Reference" "C449"
			(at 0 0 90)
			(layer "B.SilkS")
			(hide yes)
			(effects
				(font
					(size 1.27 1.27)
				)
				(justify mirror)
			)
		)
		(property "Value" ""
			(at 0 0 90)
			(layer "B.Fab")
			(effects
				(font
					(size 1.27 1.27)
				)
				(justify mirror)
			)
		)
		(duplicate_pad_numbers_are_jumpers no)
		(fp_line
			(start 1.524 -0.762)
			(end -1.524 -0.762)
			(stroke
				(width 0.1524)
				(type default)
			)
			(layer "B.SilkS")
		)
		(fp_line
			(start -1.524 -0.762)
			(end -1.524 0.762)
			(stroke
				(width 0.1524)
				(type default)
			)
			(layer "B.SilkS")
		)
		(fp_line
			(start 1.524 0.762)
			(end 1.524 -0.762)
			(stroke
				(width 0.1524)
				(type default)
			)
			(layer "B.SilkS")
		)
		(fp_line
			(start -1.524 0.762)
			(end 1.524 0.762)
			(stroke
				(width 0.1524)
				(type default)
			)
			(layer "B.SilkS")
		)
		(fp_line
			(start 1.1049 -0.724916)
			(end 1.1049 0.724916)
			(stroke
				(width 0.1)
				(type default)
			)
			(layer "B.Fab")
		)
		(fp_line
			(start -1.1049 -0.724916)
			(end 1.1049 -0.724916)
			(stroke
				(width 0.1)
				(type default)
			)
			(layer "B.Fab")
		)
		(fp_line
			(start 1.1049 0.724916)
			(end -1.1049 0.724916)
			(stroke
				(width 0.1)
				(type default)
			)
			(layer "B.Fab")
		)
		(fp_line
			(start -1.1049 0.724916)
			(end -1.1049 -0.724916)
			(stroke
				(width 0.1)
				(type default)
			)
			(layer "B.Fab")
		)
		(pad "1" smd rect
			(at 0.889 0 90)
			(size 1.016 1.27)
			(layers "B.Cu" "B.Mask" "B.Paste")
			(net "PVCCFA_EHV_FIVRA_CPU1")
		)
		(pad "2" smd rect
			(at -0.889 0 90)
			(size 1.016 1.27)
			(layers "B.Cu" "B.Mask" "B.Paste")
			(net "GND")
		)
	)
	(footprint ""
		(layer "B.Cu")
		(at 168.83888 -101.564948 180)
		(property "Reference" "R3346"
			(at 0 0 0)
			(layer "B.SilkS")
			(hide yes)
			(effects
				(font
					(size 1.27 1.27)
				)
				(justify mirror)
			)
		)
		(property "Value" ""
			(at 0 0 0)
			(layer "B.Fab")
			(effects
				(font
					(size 1.27 1.27)
				)
				(justify mirror)
			)
		)
		(duplicate_pad_numbers_are_jumpers no)
		(fp_line
			(start 1.2954 0.5842)
			(end 1.2954 -0.5842)
			(stroke
				(width 0.1524)
				(type default)
			)
			(layer "B.SilkS")
		)
		(fp_line
			(start 1.2954 -0.5842)
			(end -1.2954 -0.5842)
			(stroke
				(width 0.1524)
				(type default)
			)
			(layer "B.SilkS")
		)
		(fp_line
			(start -1.2954 0.5842)
			(end 1.2954 0.5842)
			(stroke
				(width 0.1524)
				(type default)
			)
			(layer "B.SilkS")
		)
		(fp_line
			(start -1.2954 -0.5842)
			(end -1.2954 0.5842)
			(stroke
				(width 0.1524)
				(type default)
			)
			(layer "B.SilkS")
		)
		(fp_line
			(start 1.1938 0.4064)
			(end 1.1938 -0.406654)
			(stroke
				(width 0.1)
				(type default)
			)
			(layer "B.Fab")
		)
		(fp_line
			(start 1.1938 -0.406654)
			(end 0.8636 -0.406654)
			(stroke
				(width 0.1)
				(type default)
			)
			(layer "B.Fab")
		)
		(fp_line
			(start 0.8636 0.4572)
			(end 0.8636 0.4318)
			(stroke
				(width 0.1)
				(type default)
			)
			(layer "B.Fab")
		)
		(fp_line
			(start 0.8636 0.4318)
			(end 0.8636 0.4064)
			(stroke
				(width 0.1)
				(type default)
			)
			(layer "B.Fab")
		)
		(fp_line
			(start 0.8636 0.4064)
			(end 1.1938 0.4064)
			(stroke
				(width 0.1)
				(type default)
			)
			(layer "B.Fab")
		)
		(fp_line
			(start 0.8636 -0.406654)
			(end 0.8636 -0.4572)
			(stroke
				(width 0.1)
				(type default)
			)
			(layer "B.Fab")
		)
		(fp_line
			(start 0.8636 -0.4572)
			(end -0.8636 -0.4572)
			(stroke
				(width 0.1)
				(type default)
			)
			(layer "B.Fab")
		)
		(fp_line
			(start -0.8636 0.4572)
			(end 0.8636 0.4572)
			(stroke
				(width 0.1)
				(type default)
			)
			(layer "B.Fab")
		)
		(fp_line
			(start -0.8636 0.4064)
			(end -0.8636 0.4572)
			(stroke
				(width 0.1)
				(type default)
			)
			(layer "B.Fab")
		)
		(fp_line
			(start -0.8636 -0.406654)
			(end -1.1938 -0.406654)
			(stroke
				(width 0.1)
				(type default)
			)
			(layer "B.Fab")
		)
		(fp_line
			(start -0.8636 -0.4572)
			(end -0.8636 -0.406654)
			(stroke
				(width 0.1)
				(type default)
			)
			(layer "B.Fab")
		)
		(fp_line
			(start -1.1938 0.4064)
			(end -0.8636 0.4064)
			(stroke
				(width 0.1)
				(type default)
			)
			(layer "B.Fab")
		)
		(fp_line
			(start -1.1938 -0.406654)
			(end -1.1938 0.4064)
			(stroke
				(width 0.1)
				(type default)
			)
			(layer "B.Fab")
		)
		(pad "1" smd rect
			(at 0.7366 0 90)
			(size 0.7112 0.8128)
			(layers "B.Cu" "B.Mask" "B.Paste")
			(net "P3V3_AUX")
		)
		(pad "2" smd rect
			(at -0.7366 0 90)
			(size 0.7112 0.8128)
			(layers "B.Cu" "B.Mask" "B.Paste")
			(net "P3V3_AUX_FPGA_VCCIO0")
		)
	)
	(footprint ""
		(layer "B.Cu")
		(at 366.098582 -210.19389)
		(property "Reference" "C530"
			(at 0 0 0)
			(layer "B.SilkS")
			(hide yes)
			(effects
				(font
					(size 1.27 1.27)
				)
				(justify mirror)
			)
		)
		(property "Value" ""
			(at 0 0 0)
			(layer "B.Fab")
			(effects
				(font
					(size 1.27 1.27)
				)
				(justify mirror)
			)
		)
		(duplicate_pad_numbers_are_jumpers no)
		(fp_line
			(start -1.524 -0.762)
			(end -1.524 0.762)
			(stroke
				(width 0.1524)
				(type default)
			)
			(layer "B.SilkS")
		)
		(fp_line
			(start -1.524 0.762)
			(end 1.524 0.762)
			(stroke
				(width 0.1524)
				(type default)
			)
			(layer "B.SilkS")
		)
		(fp_line
			(start 1.524 -0.762)
			(end -1.524 -0.762)
			(stroke
				(width 0.1524)
				(type default)
			)
			(layer "B.SilkS")
		)
		(fp_line
			(start 1.524 0.762)
			(end 1.524 -0.762)
			(stroke
				(width 0.1524)
				(type default)
			)
			(layer "B.SilkS")
		)
		(fp_line
			(start -1.1049 -0.724916)
			(end 1.1049 -0.724916)
			(stroke
				(width 0.1)
				(type default)
			)
			(layer "B.Fab")
		)
		(fp_line
			(start -1.1049 0.724916)
			(end -1.1049 -0.724916)
			(stroke
				(width 0.1)
				(type default)
			)
			(layer "B.Fab")
		)
		(fp_line
			(start 1.1049 -0.724916)
			(end 1.1049 0.724916)
			(stroke
				(width 0.1)
				(type default)
			)
			(layer "B.Fab")
		)
		(fp_line
			(start 1.1049 0.724916)
			(end -1.1049 0.724916)
			(stroke
				(width 0.1)
				(type default)
			)
			(layer "B.Fab")
		)
		(pad "1" smd rect
			(at 0.889 0)
			(size 1.016 1.27)
			(layers "B.Cu" "B.Mask" "B.Paste")
			(net "PVCCINFAON_CPU0")
		)
		(pad "2" smd rect
			(at -0.889 0)
			(size 1.016 1.27)
			(layers "B.Cu" "B.Mask" "B.Paste")
			(net "GND")
		)
	)
	(footprint ""
		(layer "B.Cu")
		(at 56.289702 -358.12349 180)
		(property "Reference" "PC1680"
			(at 0 0 0)
			(layer "B.SilkS")
			(hide yes)
			(effects
				(font
					(size 1.27 1.27)
				)
				(justify mirror)
			)
		)
		(property "Value" ""
			(at 0 0 0)
			(layer "B.Fab")
			(effects
				(font
					(size 1.27 1.27)
				)
				(justify mirror)
			)
		)
		(duplicate_pad_numbers_are_jumpers no)
		(fp_line
			(start 1.524 0.762)
			(end 1.524 -0.762)
			(stroke
				(width 0.1524)
				(type default)
			)
			(layer "B.SilkS")
		)
		(fp_line
			(start 1.524 -0.762)
			(end -1.524 -0.762)
			(stroke
				(width 0.1524)
				(type default)
			)
			(layer "B.SilkS")
		)
		(fp_line
			(start -1.524 0.762)
			(end 1.524 0.762)
			(stroke
				(width 0.1524)
				(type default)
			)
			(layer "B.SilkS")
		)
		(fp_line
			(start -1.524 -0.762)
			(end -1.524 0.762)
			(stroke
				(width 0.1524)
				(type default)
			)
			(layer "B.SilkS")
		)
		(fp_line
			(start 1.1049 0.724916)
			(end -1.1049 0.724916)
			(stroke
				(width 0.1)
				(type default)
			)
			(layer "B.Fab")
		)
		(fp_line
			(start 1.1049 -0.724916)
			(end 1.1049 0.724916)
			(stroke
				(width 0.1)
				(type default)
			)
			(layer "B.Fab")
		)
		(fp_line
			(start -1.1049 0.724916)
			(end -1.1049 -0.724916)
			(stroke
				(width 0.1)
				(type default)
			)
			(layer "B.Fab")
		)
		(fp_line
			(start -1.1049 -0.724916)
			(end 1.1049 -0.724916)
			(stroke
				(width 0.1)
				(type default)
			)
			(layer "B.Fab")
		)
		(pad "1" smd rect
			(at 0.889 0 180)
			(size 1.016 1.27)
			(layers "B.Cu" "B.Mask" "B.Paste")
			(net "SW_P12V_PVCCFA_EHV_FIVRA_CPU1_L")
		)
		(pad "2" smd rect
			(at -0.889 0 180)
			(size 1.016 1.27)
			(layers "B.Cu" "B.Mask" "B.Paste")
			(net "GND")
		)
	)
	(footprint ""
		(layer "B.Cu")
		(at 258.953 -101.183948)
		(property "Reference" "C116"
			(at 0 0 0)
			(layer "B.SilkS")
			(hide yes)
			(effects
				(font
					(size 1.27 1.27)
				)
				(justify mirror)
			)
		)
		(property "Value" ""
			(at 0 0 0)
			(layer "B.Fab")
			(effects
				(font
					(size 1.27 1.27)
				)
				(justify mirror)
			)
		)
		(duplicate_pad_numbers_are_jumpers no)
		(fp_line
			(start -0.7874 -0.4064)
			(end -0.7874 0.4064)
			(stroke
				(width 0.1524)
				(type default)
			)
			(layer "B.SilkS")
		)
		(fp_line
			(start -0.7874 0.4064)
			(end 0.7874 0.4064)
			(stroke
				(width 0.1524)
				(type default)
			)
			(layer "B.SilkS")
		)
		(fp_line
			(start 0.7874 -0.4064)
			(end -0.7874 -0.4064)
			(stroke
				(width 0.1524)
				(type default)
			)
			(layer "B.SilkS")
		)
		(fp_line
			(start 0.7874 0.4064)
			(end 0.7874 -0.4064)
			(stroke
				(width 0.1524)
				(type default)
			)
			(layer "B.SilkS")
		)
		(fp_line
			(start -0.67945 -0.3048)
			(end -0.67945 0.3048)
			(stroke
				(width 0.1)
				(type default)
			)
			(layer "B.Fab")
		)
		(fp_line
			(start -0.67945 0.3048)
			(end -0.120396 0.3048)
			(stroke
				(width 0.1)
				(type default)
			)
			(layer "B.Fab")
		)
		(fp_line
			(start -0.12065 -0.3048)
			(end -0.67945 -0.3048)
			(stroke
				(width 0.1)
				(type default)
			)
			(layer "B.Fab")
		)
		(fp_line
			(start -0.12065 -0.2794)
			(end -0.12065 -0.3048)
			(stroke
				(width 0.1)
				(type default)
			)
			(layer "B.Fab")
		)
		(fp_line
			(start -0.120396 0.2794)
			(end 0.12065 0.2794)
			(stroke
				(width 0.1)
				(type default)
			)
			(layer "B.Fab")
		)
		(fp_line
			(start -0.120396 0.3048)
			(end -0.120396 0.2794)
			(stroke
				(width 0.1)
				(type default)
			)
			(layer "B.Fab")
		)
		(fp_line
			(start 0.12065 -0.305054)
			(end 0.12065 -0.2794)
			(stroke
				(width 0.1)
				(type default)
			)
			(layer "B.Fab")
		)
		(fp_line
			(start 0.12065 -0.2794)
			(end -0.12065 -0.2794)
			(stroke
				(width 0.1)
				(type default)
			)
			(layer "B.Fab")
		)
		(fp_line
			(start 0.12065 0.2794)
			(end 0.12065 0.3048)
			(stroke
				(width 0.1)
				(type default)
			)
			(layer "B.Fab")
		)
		(fp_line
			(start 0.12065 0.3048)
			(end 0.67945 0.3048)
			(stroke
				(width 0.1)
				(type default)
			)
			(layer "B.Fab")
		)
		(fp_line
			(start 0.67945 -0.305054)
			(end 0.12065 -0.305054)
			(stroke
				(width 0.1)
				(type default)
			)
			(layer "B.Fab")
		)
		(fp_line
			(start 0.67945 0.3048)
			(end 0.67945 -0.305054)
			(stroke
				(width 0.1)
				(type default)
			)
			(layer "B.Fab")
		)
		(pad "1" smd circle
			(at 0.40005 0 180)
			(size 0 0)
			(layers "B.Cu" "B.Mask" "B.Paste")
			(net "P3V3_AUX_CLK_GEN_VDDMXCK_CK440")
		)
		(pad "2" smd circle
			(at -0.40005 0 180)
			(size 0 0)
			(layers "B.Cu" "B.Mask" "B.Paste")
			(net "GND")
		)
	)
	(footprint ""
		(layer "B.Cu")
		(at 121.581926 -212.049868 180)
		(property "Reference" "C484"
			(at 0 0 0)
			(layer "B.SilkS")
			(hide yes)
			(effects
				(font
					(size 1.27 1.27)
				)
				(justify mirror)
			)
		)
		(property "Value" ""
			(at 0 0 0)
			(layer "B.Fab")
			(effects
				(font
					(size 1.27 1.27)
				)
				(justify mirror)
			)
		)
		(duplicate_pad_numbers_are_jumpers no)
		(fp_line
			(start 1.524 0.762)
			(end 1.524 -0.762)
			(stroke
				(width 0.1524)
				(type default)
			)
			(layer "B.SilkS")
		)
		(fp_line
			(start 1.524 -0.762)
			(end -1.524 -0.762)
			(stroke
				(width 0.1524)
				(type default)
			)
			(layer "B.SilkS")
		)
		(fp_line
			(start -1.524 0.762)
			(end 1.524 0.762)
			(stroke
				(width 0.1524)
				(type default)
			)
			(layer "B.SilkS")
		)
		(fp_line
			(start -1.524 -0.762)
			(end -1.524 0.762)
			(stroke
				(width 0.1524)
				(type default)
			)
			(layer "B.SilkS")
		)
		(fp_line
			(start 1.1049 0.724916)
			(end -1.1049 0.724916)
			(stroke
				(width 0.1)
				(type default)
			)
			(layer "B.Fab")
		)
		(fp_line
			(start 1.1049 -0.724916)
			(end 1.1049 0.724916)
			(stroke
				(width 0.1)
				(type default)
			)
			(layer "B.Fab")
		)
		(fp_line
			(start -1.1049 0.724916)
			(end -1.1049 -0.724916)
			(stroke
				(width 0.1)
				(type default)
			)
			(layer "B.Fab")
		)
		(fp_line
			(start -1.1049 -0.724916)
			(end 1.1049 -0.724916)
			(stroke
				(width 0.1)
				(type default)
			)
			(layer "B.Fab")
		)
		(pad "1" smd rect
			(at 0.889 0 180)
			(size 1.016 1.27)
			(layers "B.Cu" "B.Mask" "B.Paste")
			(net "PVCCINFAON_CPU1")
		)
		(pad "2" smd rect
			(at -0.889 0 180)
			(size 1.016 1.27)
			(layers "B.Cu" "B.Mask" "B.Paste")
			(net "GND")
		)
	)
	(footprint ""
		(layer "B.Cu")
		(at 89.661238 -179.31511)
		(property "Reference" "R1003"
			(at 0 0 0)
			(layer "B.SilkS")
			(hide yes)
			(effects
				(font
					(size 1.27 1.27)
				)
				(justify mirror)
			)
		)
		(property "Value" ""
			(at 0 0 0)
			(layer "B.Fab")
			(effects
				(font
					(size 1.27 1.27)
				)
				(justify mirror)
			)
		)
		(duplicate_pad_numbers_are_jumpers no)
		(fp_line
			(start -0.7874 -0.4064)
			(end -0.7874 0.4064)
			(stroke
				(width 0.1524)
				(type default)
			)
			(layer "B.SilkS")
		)
		(fp_line
			(start -0.7874 0.4064)
			(end 0.7874 0.4064)
			(stroke
				(width 0.1524)
				(type default)
			)
			(layer "B.SilkS")
		)
		(fp_line
			(start 0.7874 -0.4064)
			(end -0.7874 -0.4064)
			(stroke
				(width 0.1524)
				(type default)
			)
			(layer "B.SilkS")
		)
		(fp_line
			(start 0.7874 0.4064)
			(end 0.7874 -0.4064)
			(stroke
				(width 0.1524)
				(type default)
			)
			(layer "B.SilkS")
		)
		(fp_line
			(start -0.67945 -0.3048)
			(end -0.67945 0.3048)
			(stroke
				(width 0.1)
				(type default)
			)
			(layer "B.Fab")
		)
		(fp_line
			(start -0.67945 0.3048)
			(end -0.120396 0.3048)
			(stroke
				(width 0.1)
				(type default)
			)
			(layer "B.Fab")
		)
		(fp_line
			(start -0.12065 -0.3048)
			(end -0.67945 -0.3048)
			(stroke
				(width 0.1)
				(type default)
			)
			(layer "B.Fab")
		)
		(fp_line
			(start -0.12065 -0.2794)
			(end -0.12065 -0.3048)
			(stroke
				(width 0.1)
				(type default)
			)
			(layer "B.Fab")
		)
		(fp_line
			(start -0.120396 0.2794)
			(end 0.12065 0.2794)
			(stroke
				(width 0.1)
				(type default)
			)
			(layer "B.Fab")
		)
		(fp_line
			(start -0.120396 0.3048)
			(end -0.120396 0.2794)
			(stroke
				(width 0.1)
				(type default)
			)
			(layer "B.Fab")
		)
		(fp_line
			(start 0.12065 -0.305054)
			(end 0.12065 -0.2794)
			(stroke
				(width 0.1)
				(type default)
			)
			(layer "B.Fab")
		)
		(fp_line
			(start 0.12065 -0.2794)
			(end -0.12065 -0.2794)
			(stroke
				(width 0.1)
				(type default)
			)
			(layer "B.Fab")
		)
		(fp_line
			(start 0.12065 0.2794)
			(end 0.12065 0.3048)
			(stroke
				(width 0.1)
				(type default)
			)
			(layer "B.Fab")
		)
		(fp_line
			(start 0.12065 0.3048)
			(end 0.67945 0.3048)
			(stroke
				(width 0.1)
				(type default)
			)
			(layer "B.Fab")
		)
		(fp_line
			(start 0.67945 -0.305054)
			(end 0.12065 -0.305054)
			(stroke
				(width 0.1)
				(type default)
			)
			(layer "B.Fab")
		)
		(fp_line
			(start 0.67945 0.3048)
			(end 0.67945 -0.305054)
			(stroke
				(width 0.1)
				(type default)
			)
			(layer "B.Fab")
		)
		(pad "1" smd circle
			(at 0.40005 0 180)
			(size 0 0)
			(layers "B.Cu" "B.Mask" "B.Paste")
			(net "P3V3")
		)
		(pad "2" smd circle
			(at -0.40005 0 180)
			(size 0 0)
			(layers "B.Cu" "B.Mask" "B.Paste")
			(net "FM_SMB_CPU1_ALERT_R1")
		)
	)
	(footprint ""
		(layer "B.Cu")
		(at 305.181 -317.159386 45)
		(property "Reference" "R3876"
			(at 0 0 45)
			(layer "B.SilkS")
			(hide yes)
			(effects
				(font
					(size 1.27 1.27)
				)
				(justify mirror)
			)
		)
		(property "Value" ""
			(at 0 0 45)
			(layer "B.Fab")
			(effects
				(font
					(size 1.27 1.27)
				)
				(justify mirror)
			)
		)
		(duplicate_pad_numbers_are_jumpers no)
		(fp_line
			(start -0.787389 -0.406267)
			(end -0.787389 0.406267)
			(stroke
				(width 0.1524)
				(type default)
			)
			(layer "B.SilkS")
		)
		(fp_line
			(start -0.787389 0.406267)
			(end 0.787389 0.406267)
			(stroke
				(width 0.1524)
				(type default)
			)
			(layer "B.SilkS")
		)
		(fp_line
			(start 0.787389 -0.406267)
			(end -0.787389 -0.406267)
			(stroke
				(width 0.1524)
				(type default)
			)
			(layer "B.SilkS")
		)
		(fp_line
			(start 0.787389 0.406267)
			(end 0.787389 -0.406267)
			(stroke
				(width 0.1524)
				(type default)
			)
			(layer "B.SilkS")
		)
		(fp_line
			(start -0.679446 -0.30479)
			(end -0.679446 0.30479)
			(stroke
				(width 0.1)
				(type default)
			)
			(layer "B.Fab")
		)
		(fp_line
			(start -0.120515 -0.30479)
			(end -0.679446 -0.30479)
			(stroke
				(width 0.1)
				(type default)
			)
			(layer "B.Fab")
		)
		(fp_line
			(start -0.120695 -0.279466)
			(end -0.120515 -0.30479)
			(stroke
				(width 0.1)
				(type default)
			)
			(layer "B.Fab")
		)
		(fp_line
			(start -0.679446 0.30479)
			(end -0.120515 0.30479)
			(stroke
				(width 0.1)
				(type default)
			)
			(layer "B.Fab")
		)
		(fp_line
			(start 0.120695 -0.304969)
			(end 0.120695 -0.279466)
			(stroke
				(width 0.1)
				(type default)
			)
			(layer "B.Fab")
		)
		(fp_line
			(start 0.120695 -0.279466)
			(end -0.120695 -0.279466)
			(stroke
				(width 0.1)
				(type default)
			)
			(layer "B.Fab")
		)
		(fp_line
			(start -0.120335 0.279466)
			(end 0.120695 0.279466)
			(stroke
				(width 0.1)
				(type default)
			)
			(layer "B.Fab")
		)
		(fp_line
			(start -0.120515 0.30479)
			(end -0.120335 0.279466)
			(stroke
				(width 0.1)
				(type default)
			)
			(layer "B.Fab")
		)
		(fp_line
			(start 0.679446 -0.305149)
			(end 0.120695 -0.304969)
			(stroke
				(width 0.1)
				(type default)
			)
			(layer "B.Fab")
		)
		(fp_line
			(start 0.120695 0.279466)
			(end 0.120515 0.30479)
			(stroke
				(width 0.1)
				(type default)
			)
			(layer "B.Fab")
		)
		(fp_line
			(start 0.120515 0.30479)
			(end 0.679446 0.30479)
			(stroke
				(width 0.1)
				(type default)
			)
			(layer "B.Fab")
		)
		(fp_line
			(start 0.679446 0.30479)
			(end 0.679446 -0.305149)
			(stroke
				(width 0.1)
				(type default)
			)
			(layer "B.Fab")
		)
		(pad "1" smd circle
			(at 0.40005 0 225)
			(size 0 0)
			(layers "B.Cu" "B.Mask" "B.Paste")
			(net "I3C_SPD_DDRABCD_CPU0_LVC1_SCL_1")
		)
		(pad "2" smd circle
			(at -0.40005 0 225)
			(size 0 0)
			(layers "B.Cu" "B.Mask" "B.Paste")
			(net "I3C_SPD_DDRABCD_CPU0_LVC1_SCL")
		)
	)
	(footprint ""
		(layer "B.Cu")
		(at 238.75238 -132.508752 90)
		(property "Reference" "R4502"
			(at 0 0 90)
			(layer "B.SilkS")
			(hide yes)
			(effects
				(font
					(size 1.27 1.27)
				)
				(justify mirror)
			)
		)
		(property "Value" ""
			(at 0 0 90)
			(layer "B.Fab")
			(effects
				(font
					(size 1.27 1.27)
				)
				(justify mirror)
			)
		)
		(duplicate_pad_numbers_are_jumpers no)
		(fp_line
			(start 0.7874 -0.4064)
			(end -0.7874 -0.4064)
			(stroke
				(width 0.1524)
				(type default)
			)
			(layer "B.SilkS")
		)
		(fp_line
			(start -0.7874 -0.4064)
			(end -0.7874 0.4064)
			(stroke
				(width 0.1524)
				(type default)
			)
			(layer "B.SilkS")
		)
		(fp_line
			(start 0.7874 0.4064)
			(end 0.7874 -0.4064)
			(stroke
				(width 0.1524)
				(type default)
			)
			(layer "B.SilkS")
		)
		(fp_line
			(start -0.7874 0.4064)
			(end 0.7874 0.4064)
			(stroke
				(width 0.1524)
				(type default)
			)
			(layer "B.SilkS")
		)
		(fp_line
			(start 0.67945 -0.305054)
			(end 0.12065 -0.305054)
			(stroke
				(width 0.1)
				(type default)
			)
			(layer "B.Fab")
		)
		(fp_line
			(start 0.12065 -0.305054)
			(end 0.12065 -0.2794)
			(stroke
				(width 0.1)
				(type default)
			)
			(layer "B.Fab")
		)
		(fp_line
			(start -0.12065 -0.3048)
			(end -0.67945 -0.3048)
			(stroke
				(width 0.1)
				(type default)
			)
			(layer "B.Fab")
		)
		(fp_line
			(start -0.67945 -0.3048)
			(end -0.67945 0.3048)
			(stroke
				(width 0.1)
				(type default)
			)
			(layer "B.Fab")
		)
		(fp_line
			(start 0.12065 -0.2794)
			(end -0.12065 -0.2794)
			(stroke
				(width 0.1)
				(type default)
			)
			(layer "B.Fab")
		)
		(fp_line
			(start -0.12065 -0.2794)
			(end -0.12065 -0.3048)
			(stroke
				(width 0.1)
				(type default)
			)
			(layer "B.Fab")
		)
		(fp_line
			(start 0.12065 0.2794)
			(end 0.12065 0.3048)
			(stroke
				(width 0.1)
				(type default)
			)
			(layer "B.Fab")
		)
		(fp_line
			(start -0.120396 0.2794)
			(end 0.12065 0.2794)
			(stroke
				(width 0.1)
				(type default)
			)
			(layer "B.Fab")
		)
		(fp_line
			(start 0.67945 0.3048)
			(end 0.67945 -0.305054)
			(stroke
				(width 0.1)
				(type default)
			)
			(layer "B.Fab")
		)
		(fp_line
			(start 0.12065 0.3048)
			(end 0.67945 0.3048)
			(stroke
				(width 0.1)
				(type default)
			)
			(layer "B.Fab")
		)
		(fp_line
			(start -0.120396 0.3048)
			(end -0.120396 0.2794)
			(stroke
				(width 0.1)
				(type default)
			)
			(layer "B.Fab")
		)
		(fp_line
			(start -0.67945 0.3048)
			(end -0.120396 0.3048)
			(stroke
				(width 0.1)
				(type default)
			)
			(layer "B.Fab")
		)
		(pad "1" smd circle
			(at 0.40005 0 270)
			(size 0 0)
			(layers "B.Cu" "B.Mask" "B.Paste")
			(net "SMB_HOST_3V3AUX_SCL_R4")
		)
		(pad "2" smd circle
			(at -0.40005 0 270)
			(size 0 0)
			(layers "B.Cu" "B.Mask" "B.Paste")
			(net "SMB_HOST_3V3AUX_XDP_R_SCL")
		)
	)
	(footprint ""
		(layer "B.Cu")
		(at 137.08888 -9.362948 -90)
		(property "Reference" "R506"
			(at 0 0 90)
			(layer "B.SilkS")
			(hide yes)
			(effects
				(font
					(size 1.27 1.27)
				)
				(justify mirror)
			)
		)
		(property "Value" ""
			(at 0 0 90)
			(layer "B.Fab")
			(effects
				(font
					(size 1.27 1.27)
				)
				(justify mirror)
			)
		)
		(duplicate_pad_numbers_are_jumpers no)
		(fp_line
			(start -0.7874 0.4064)
			(end 0.7874 0.4064)
			(stroke
				(width 0.1524)
				(type default)
			)
			(layer "B.SilkS")
		)
		(fp_line
			(start 0.7874 0.4064)
			(end 0.7874 -0.4064)
			(stroke
				(width 0.1524)
				(type default)
			)
			(layer "B.SilkS")
		)
		(fp_line
			(start -0.7874 -0.4064)
			(end -0.7874 0.4064)
			(stroke
				(width 0.1524)
				(type default)
			)
			(layer "B.SilkS")
		)
		(fp_line
			(start 0.7874 -0.4064)
			(end -0.7874 -0.4064)
			(stroke
				(width 0.1524)
				(type default)
			)
			(layer "B.SilkS")
		)
		(fp_line
			(start -0.67945 0.3048)
			(end -0.120396 0.3048)
			(stroke
				(width 0.1)
				(type default)
			)
			(layer "B.Fab")
		)
		(fp_line
			(start -0.120396 0.3048)
			(end -0.120396 0.2794)
			(stroke
				(width 0.1)
				(type default)
			)
			(layer "B.Fab")
		)
		(fp_line
			(start 0.12065 0.3048)
			(end 0.67945 0.3048)
			(stroke
				(width 0.1)
				(type default)
			)
			(layer "B.Fab")
		)
		(fp_line
			(start 0.67945 0.3048)
			(end 0.67945 -0.305054)
			(stroke
				(width 0.1)
				(type default)
			)
			(layer "B.Fab")
		)
		(fp_line
			(start -0.120396 0.2794)
			(end 0.12065 0.2794)
			(stroke
				(width 0.1)
				(type default)
			)
			(layer "B.Fab")
		)
		(fp_line
			(start 0.12065 0.2794)
			(end 0.12065 0.3048)
			(stroke
				(width 0.1)
				(type default)
			)
			(layer "B.Fab")
		)
		(fp_line
			(start -0.12065 -0.2794)
			(end -0.12065 -0.3048)
			(stroke
				(width 0.1)
				(type default)
			)
			(layer "B.Fab")
		)
		(fp_line
			(start 0.12065 -0.2794)
			(end -0.12065 -0.2794)
			(stroke
				(width 0.1)
				(type default)
			)
			(layer "B.Fab")
		)
		(fp_line
			(start -0.67945 -0.3048)
			(end -0.67945 0.3048)
			(stroke
				(width 0.1)
				(type default)
			)
			(layer "B.Fab")
		)
		(fp_line
			(start -0.12065 -0.3048)
			(end -0.67945 -0.3048)
			(stroke
				(width 0.1)
				(type default)
			)
			(layer "B.Fab")
		)
		(fp_line
			(start 0.12065 -0.305054)
			(end 0.12065 -0.2794)
			(stroke
				(width 0.1)
				(type default)
			)
			(layer "B.Fab")
		)
		(fp_line
			(start 0.67945 -0.305054)
			(end 0.12065 -0.305054)
			(stroke
				(width 0.1)
				(type default)
			)
			(layer "B.Fab")
		)
		(pad "1" smd circle
			(at 0.40005 0 90)
			(size 0 0)
			(layers "B.Cu" "B.Mask" "B.Paste")
			(net "IRQ_SMI_ACTIVE_BMC_N")
		)
		(pad "2" smd circle
			(at -0.40005 0 90)
			(size 0 0)
			(layers "B.Cu" "B.Mask" "B.Paste")
			(net "IRQ0_A57")
		)
	)
	(footprint ""
		(layer "B.Cu")
		(at 407.90368 -184.165748 180)
		(property "Reference" "PR4226"
			(at 0 0 0)
			(layer "B.SilkS")
			(hide yes)
			(effects
				(font
					(size 1.27 1.27)
				)
				(justify mirror)
			)
		)
		(property "Value" ""
			(at 0 0 0)
			(layer "B.Fab")
			(effects
				(font
					(size 1.27 1.27)
				)
				(justify mirror)
			)
		)
		(duplicate_pad_numbers_are_jumpers no)
		(fp_line
			(start 0.7874 0.4064)
			(end 0.7874 -0.4064)
			(stroke
				(width 0.1524)
				(type default)
			)
			(layer "B.SilkS")
		)
		(fp_line
			(start 0.7874 -0.4064)
			(end -0.7874 -0.4064)
			(stroke
				(width 0.1524)
				(type default)
			)
			(layer "B.SilkS")
		)
		(fp_line
			(start -0.7874 0.4064)
			(end 0.7874 0.4064)
			(stroke
				(width 0.1524)
				(type default)
			)
			(layer "B.SilkS")
		)
		(fp_line
			(start -0.7874 -0.4064)
			(end -0.7874 0.4064)
			(stroke
				(width 0.1524)
				(type default)
			)
			(layer "B.SilkS")
		)
		(fp_line
			(start 0.67945 0.3048)
			(end 0.67945 -0.305054)
			(stroke
				(width 0.1)
				(type default)
			)
			(layer "B.Fab")
		)
		(fp_line
			(start 0.67945 -0.305054)
			(end 0.12065 -0.305054)
			(stroke
				(width 0.1)
				(type default)
			)
			(layer "B.Fab")
		)
		(fp_line
			(start 0.12065 0.3048)
			(end 0.67945 0.3048)
			(stroke
				(width 0.1)
				(type default)
			)
			(layer "B.Fab")
		)
		(fp_line
			(start 0.12065 0.2794)
			(end 0.12065 0.3048)
			(stroke
				(width 0.1)
				(type default)
			)
			(layer "B.Fab")
		)
		(fp_line
			(start 0.12065 -0.2794)
			(end -0.12065 -0.2794)
			(stroke
				(width 0.1)
				(type default)
			)
			(layer "B.Fab")
		)
		(fp_line
			(start 0.12065 -0.305054)
			(end 0.12065 -0.2794)
			(stroke
				(width 0.1)
				(type default)
			)
			(layer "B.Fab")
		)
		(fp_line
			(start -0.120396 0.3048)
			(end -0.120396 0.2794)
			(stroke
				(width 0.1)
				(type default)
			)
			(layer "B.Fab")
		)
		(fp_line
			(start -0.120396 0.2794)
			(end 0.12065 0.2794)
			(stroke
				(width 0.1)
				(type default)
			)
			(layer "B.Fab")
		)
		(fp_line
			(start -0.12065 -0.2794)
			(end -0.12065 -0.3048)
			(stroke
				(width 0.1)
				(type default)
			)
			(layer "B.Fab")
		)
		(fp_line
			(start -0.12065 -0.3048)
			(end -0.67945 -0.3048)
			(stroke
				(width 0.1)
				(type default)
			)
			(layer "B.Fab")
		)
		(fp_line
			(start -0.67945 0.3048)
			(end -0.120396 0.3048)
			(stroke
				(width 0.1)
				(type default)
			)
			(layer "B.Fab")
		)
		(fp_line
			(start -0.67945 -0.3048)
			(end -0.67945 0.3048)
			(stroke
				(width 0.1)
				(type default)
			)
			(layer "B.Fab")
		)
		(pad "1" smd circle
			(at 0.40005 0)
			(size 0 0)
			(layers "B.Cu" "B.Mask" "B.Paste")
			(net "PVCCINFAON_CPU0")
		)
		(pad "2" smd circle
			(at -0.40005 0)
			(size 0 0)
			(layers "B.Cu" "B.Mask" "B.Paste")
			(net "GND")
		)
	)
	(footprint ""
		(layer "B.Cu")
		(at 211.85378 -2.159 180)
		(property "Reference" "J74"
			(at 4.23545 -1.143 270)
			(unlocked yes)
			(layer "B.SilkS")
			(effects
				(font
					(size 0.7874 0.5842)
					(thickness 0.1524)
				)
				(justify left mirror)
			)
		)
		(property "Value" ""
			(at 0 0 0)
			(layer "B.Fab")
			(effects
				(font
					(size 1.27 1.27)
				)
				(justify mirror)
			)
		)
		(duplicate_pad_numbers_are_jumpers no)
		(fp_line
			(start 1.2192 2.1082)
			(end 1.2192 -2.1082)
			(stroke
				(width 0.1524)
				(type default)
			)
			(layer "B.SilkS")
		)
		(fp_line
			(start 1.2192 -2.1082)
			(end -1.2192 -2.1082)
			(stroke
				(width 0.1524)
				(type default)
			)
			(layer "B.SilkS")
		)
		(fp_line
			(start -1.2192 2.1082)
			(end 1.2192 2.1082)
			(stroke
				(width 0.1524)
				(type default)
			)
			(layer "B.SilkS")
		)
		(fp_line
			(start -1.2192 -2.1082)
			(end -1.2192 2.1082)
			(stroke
				(width 0.1524)
				(type default)
			)
			(layer "B.SilkS")
		)
		(pad "" np_thru_hole circle
			(at -3.4671 -1.27 90)
			(size 1.0414 1.0414)
			(drill 1.0414)
			(layers "*.Cu" "*.Mask")
			(clearance 0.381)
			(thermal_gap 0.381)
		)
		(pad "" np_thru_hole circle
			(at -3.4671 1.27 90)
			(size 1.0414 1.0414)
			(drill 1.0414)
			(layers "*.Cu" "*.Mask")
			(clearance 0.381)
			(thermal_gap 0.381)
		)
		(pad "" np_thru_hole circle
			(at 2.8829 -1.27 90)
			(size 1.0414 1.0414)
			(drill 1.0414)
			(layers "*.Cu" "*.Mask")
			(clearance 0.381)
			(thermal_gap 0.381)
		)
		(pad "" np_thru_hole circle
			(at 2.8829 1.27 90)
			(size 1.0414 1.0414)
			(drill 1.0414)
			(layers "*.Cu" "*.Mask")
			(clearance 0.381)
			(thermal_gap 0.381)
		)
		(pad "1" smd rect
			(at -0.8255 -0.249936 90)
			(size 0.3048 0.508)
			(layers "B.Cu" "B.Mask" "B.Paste")
			(net "DELTA_L_85_5INCH_IN4_DN")
		)
		(pad "2" smd rect
			(at -0.8255 0.249936 90)
			(size 0.3048 0.508)
			(layers "B.Cu" "B.Mask" "B.Paste")
			(net "DELTA_L_85_5INCH_IN4_DP")
		)
		(pad "3" smd circle
			(at 0 0)
			(size 0 0)
			(layers "B.Cu" "B.Mask" "B.Paste")
			(net "DELTA_L_GND_1")
		)
		(zone
			(layers "F.Cu" "B.Cu" "In1.Cu" "In2.Cu" "In3.Cu" "In4.Cu" "In5.Cu" "In6.Cu"
				"In7.Cu" "In8.Cu" "In9.Cu" "In10.Cu" "In11.Cu" "In12.Cu" "In13.Cu" "In14.Cu"
				"In15.Cu" "In16.Cu"
			)
			(hatch none 0.5)
			(connect_pads
				(clearance 0)
			)
			(min_thickness 0.25)
			(keepout
				(tracks not_allowed)
				(vias allowed)
				(pads allowed)
				(copperpour not_allowed)
				(footprints allowed)
			)
			(placement
				(enabled no)
				(sheetname "")
			)
			(fill
				(thermal_gap 0.5)
				(thermal_bridge_width 0.5)
				(island_removal_mode 0)
			)
			(polygon
				(pts
					(arc
						(start 209.89798 -3.429)
						(mid 208.04378 -3.429)
						(end 209.89798 -3.429)
					)
				)
			)
		)
		(zone
			(layers "F.Cu" "B.Cu" "In1.Cu" "In2.Cu" "In3.Cu" "In4.Cu" "In5.Cu" "In6.Cu"
				"In7.Cu" "In8.Cu" "In9.Cu" "In10.Cu" "In11.Cu" "In12.Cu" "In13.Cu" "In14.Cu"
				"In15.Cu" "In16.Cu"
			)
			(hatch none 0.5)
			(connect_pads
				(clearance 0)
			)
			(min_thickness 0.25)
			(keepout
				(tracks not_allowed)
				(vias allowed)
				(pads allowed)
				(copperpour not_allowed)
				(footprints allowed)
			)
			(placement
				(enabled no)
				(sheetname "")
			)
			(fill
				(thermal_gap 0.5)
				(thermal_bridge_width 0.5)
				(island_removal_mode 0)
			)
			(polygon
				(pts
					(arc
						(start 209.89798 -0.889)
						(mid 208.04378 -0.889)
						(end 209.89798 -0.889)
					)
				)
			)
		)
		(zone
			(layers "F.Cu" "B.Cu" "In1.Cu" "In2.Cu" "In3.Cu" "In4.Cu" "In5.Cu" "In6.Cu"
				"In7.Cu" "In8.Cu" "In9.Cu" "In10.Cu" "In11.Cu" "In12.Cu" "In13.Cu" "In14.Cu"
				"In15.Cu" "In16.Cu"
			)
			(hatch none 0.5)
			(connect_pads
				(clearance 0)
			)
			(min_thickness 0.25)
			(keepout
				(tracks not_allowed)
				(vias allowed)
				(pads allowed)
				(copperpour not_allowed)
				(footprints allowed)
			)
			(placement
				(enabled no)
				(sheetname "")
			)
			(fill
				(thermal_gap 0.5)
				(thermal_bridge_width 0.5)
				(island_removal_mode 0)
			)
			(polygon
				(pts
					(arc
						(start 216.24798 -3.429)
						(mid 214.39378 -3.429)
						(end 216.24798 -3.429)
					)
				)
			)
		)
		(zone
			(layers "F.Cu" "B.Cu" "In1.Cu" "In2.Cu" "In3.Cu" "In4.Cu" "In5.Cu" "In6.Cu"
				"In7.Cu" "In8.Cu" "In9.Cu" "In10.Cu" "In11.Cu" "In12.Cu" "In13.Cu" "In14.Cu"
				"In15.Cu" "In16.Cu"
			)
			(hatch none 0.5)
			(connect_pads
				(clearance 0)
			)
			(min_thickness 0.25)
			(keepout
				(tracks not_allowed)
				(vias allowed)
				(pads allowed)
				(copperpour not_allowed)
				(footprints allowed)
			)
			(placement
				(enabled no)
				(sheetname "")
			)
			(fill
				(thermal_gap 0.5)
				(thermal_bridge_width 0.5)
				(island_removal_mode 0)
			)
			(polygon
				(pts
					(arc
						(start 216.24798 -0.889)
						(mid 214.39378 -0.889)
						(end 216.24798 -0.889)
					)
				)
			)
		)
		(zone
			(layer "B.Cu")
			(hatch none 0.5)
			(connect_pads
				(clearance 0)
			)
			(min_thickness 0.25)
			(keepout
				(tracks not_allowed)
				(vias allowed)
				(pads allowed)
				(copperpour not_allowed)
				(footprints allowed)
			)
			(placement
				(enabled no)
				(sheetname "")
			)
			(fill
				(thermal_gap 0.5)
				(thermal_bridge_width 0.5)
				(island_removal_mode 0)
			)
			(polygon
				(pts
					(xy 212.97138 -1.61036) (xy 212.97138 -1.705864) (xy 212.37448 -1.705864) (xy 212.37448 -2.112264)
					(xy 212.97138 -2.112264) (xy 212.97138 -2.205736) (xy 212.37448 -2.205736) (xy 212.37448 -2.612136)
					(xy 212.97138 -2.612136) (xy 212.97138 -2.70764) (xy 212.27288 -2.70764) (xy 212.27288 -1.61036)
				)
			)
		)
	)
	(footprint ""
		(layer "B.Cu")
		(at 182.68188 -103.723948)
		(property "Reference" "C1842"
			(at 0 0 0)
			(layer "B.SilkS")
			(hide yes)
			(effects
				(font
					(size 1.27 1.27)
				)
				(justify mirror)
			)
		)
		(property "Value" ""
			(at 0 0 0)
			(layer "B.Fab")
			(effects
				(font
					(size 1.27 1.27)
				)
				(justify mirror)
			)
		)
		(duplicate_pad_numbers_are_jumpers no)
		(fp_line
			(start -0.7874 -0.4064)
			(end -0.7874 0.4064)
			(stroke
				(width 0.1524)
				(type default)
			)
			(layer "B.SilkS")
		)
		(fp_line
			(start -0.7874 0.4064)
			(end 0.7874 0.4064)
			(stroke
				(width 0.1524)
				(type default)
			)
			(layer "B.SilkS")
		)
		(fp_line
			(start 0.7874 -0.4064)
			(end -0.7874 -0.4064)
			(stroke
				(width 0.1524)
				(type default)
			)
			(layer "B.SilkS")
		)
		(fp_line
			(start 0.7874 0.4064)
			(end 0.7874 -0.4064)
			(stroke
				(width 0.1524)
				(type default)
			)
			(layer "B.SilkS")
		)
		(fp_line
			(start -0.67945 -0.3048)
			(end -0.67945 0.3048)
			(stroke
				(width 0.1)
				(type default)
			)
			(layer "B.Fab")
		)
		(fp_line
			(start -0.67945 0.3048)
			(end -0.120396 0.3048)
			(stroke
				(width 0.1)
				(type default)
			)
			(layer "B.Fab")
		)
		(fp_line
			(start -0.12065 -0.3048)
			(end -0.67945 -0.3048)
			(stroke
				(width 0.1)
				(type default)
			)
			(layer "B.Fab")
		)
		(fp_line
			(start -0.12065 -0.2794)
			(end -0.12065 -0.3048)
			(stroke
				(width 0.1)
				(type default)
			)
			(layer "B.Fab")
		)
		(fp_line
			(start -0.120396 0.2794)
			(end 0.12065 0.2794)
			(stroke
				(width 0.1)
				(type default)
			)
			(layer "B.Fab")
		)
		(fp_line
			(start -0.120396 0.3048)
			(end -0.120396 0.2794)
			(stroke
				(width 0.1)
				(type default)
			)
			(layer "B.Fab")
		)
		(fp_line
			(start 0.12065 -0.305054)
			(end 0.12065 -0.2794)
			(stroke
				(width 0.1)
				(type default)
			)
			(layer "B.Fab")
		)
		(fp_line
			(start 0.12065 -0.2794)
			(end -0.12065 -0.2794)
			(stroke
				(width 0.1)
				(type default)
			)
			(layer "B.Fab")
		)
		(fp_line
			(start 0.12065 0.2794)
			(end 0.12065 0.3048)
			(stroke
				(width 0.1)
				(type default)
			)
			(layer "B.Fab")
		)
		(fp_line
			(start 0.12065 0.3048)
			(end 0.67945 0.3048)
			(stroke
				(width 0.1)
				(type default)
			)
			(layer "B.Fab")
		)
		(fp_line
			(start 0.67945 -0.305054)
			(end 0.12065 -0.305054)
			(stroke
				(width 0.1)
				(type default)
			)
			(layer "B.Fab")
		)
		(fp_line
			(start 0.67945 0.3048)
			(end 0.67945 -0.305054)
			(stroke
				(width 0.1)
				(type default)
			)
			(layer "B.Fab")
		)
		(pad "1" smd circle
			(at 0.40005 0 180)
			(size 0 0)
			(layers "B.Cu" "B.Mask" "B.Paste")
			(net "P3V3_AUX_FPGA_VCCIO3")
		)
		(pad "2" smd circle
			(at -0.40005 0 180)
			(size 0 0)
			(layers "B.Cu" "B.Mask" "B.Paste")
			(net "GND")
		)
	)
	(footprint ""
		(layer "B.Cu")
		(at 232.692194 -129.673858 -90)
		(property "Reference" "C205"
			(at 0 0 90)
			(layer "B.SilkS")
			(hide yes)
			(effects
				(font
					(size 1.27 1.27)
				)
				(justify mirror)
			)
		)
		(property "Value" ""
			(at 0 0 90)
			(layer "B.Fab")
			(effects
				(font
					(size 1.27 1.27)
				)
				(justify mirror)
			)
		)
		(duplicate_pad_numbers_are_jumpers no)
		(fp_line
			(start -0.7874 0.4064)
			(end 0.7874 0.4064)
			(stroke
				(width 0.1524)
				(type default)
			)
			(layer "B.SilkS")
		)
		(fp_line
			(start 0.7874 0.4064)
			(end 0.7874 -0.4064)
			(stroke
				(width 0.1524)
				(type default)
			)
			(layer "B.SilkS")
		)
		(fp_line
			(start -0.7874 -0.4064)
			(end -0.7874 0.4064)
			(stroke
				(width 0.1524)
				(type default)
			)
			(layer "B.SilkS")
		)
		(fp_line
			(start 0.7874 -0.4064)
			(end -0.7874 -0.4064)
			(stroke
				(width 0.1524)
				(type default)
			)
			(layer "B.SilkS")
		)
		(fp_line
			(start -0.67945 0.3048)
			(end -0.120396 0.3048)
			(stroke
				(width 0.1)
				(type default)
			)
			(layer "B.Fab")
		)
		(fp_line
			(start -0.120396 0.3048)
			(end -0.120396 0.2794)
			(stroke
				(width 0.1)
				(type default)
			)
			(layer "B.Fab")
		)
		(fp_line
			(start 0.12065 0.3048)
			(end 0.67945 0.3048)
			(stroke
				(width 0.1)
				(type default)
			)
			(layer "B.Fab")
		)
		(fp_line
			(start 0.67945 0.3048)
			(end 0.67945 -0.305054)
			(stroke
				(width 0.1)
				(type default)
			)
			(layer "B.Fab")
		)
		(fp_line
			(start -0.120396 0.2794)
			(end 0.12065 0.2794)
			(stroke
				(width 0.1)
				(type default)
			)
			(layer "B.Fab")
		)
		(fp_line
			(start 0.12065 0.2794)
			(end 0.12065 0.3048)
			(stroke
				(width 0.1)
				(type default)
			)
			(layer "B.Fab")
		)
		(fp_line
			(start -0.12065 -0.2794)
			(end -0.12065 -0.3048)
			(stroke
				(width 0.1)
				(type default)
			)
			(layer "B.Fab")
		)
		(fp_line
			(start 0.12065 -0.2794)
			(end -0.12065 -0.2794)
			(stroke
				(width 0.1)
				(type default)
			)
			(layer "B.Fab")
		)
		(fp_line
			(start -0.67945 -0.3048)
			(end -0.67945 0.3048)
			(stroke
				(width 0.1)
				(type default)
			)
			(layer "B.Fab")
		)
		(fp_line
			(start -0.12065 -0.3048)
			(end -0.67945 -0.3048)
			(stroke
				(width 0.1)
				(type default)
			)
			(layer "B.Fab")
		)
		(fp_line
			(start 0.12065 -0.305054)
			(end 0.12065 -0.2794)
			(stroke
				(width 0.1)
				(type default)
			)
			(layer "B.Fab")
		)
		(fp_line
			(start 0.67945 -0.305054)
			(end 0.12065 -0.305054)
			(stroke
				(width 0.1)
				(type default)
			)
			(layer "B.Fab")
		)
		(pad "1" smd circle
			(at 0.40005 0 90)
			(size 0 0)
			(layers "B.Cu" "B.Mask" "B.Paste")
			(net "P3V3_DB2000_VDD")
		)
		(pad "2" smd circle
			(at -0.40005 0 90)
			(size 0 0)
			(layers "B.Cu" "B.Mask" "B.Paste")
			(net "GND")
		)
	)
	(footprint ""
		(layer "B.Cu")
		(at 184.010808 -402.721572 -90)
		(property "Reference" "PC2186"
			(at 0 0 90)
			(layer "B.SilkS")
			(hide yes)
			(effects
				(font
					(size 1.27 1.27)
				)
				(justify mirror)
			)
		)
		(property "Value" ""
			(at 0 0 90)
			(layer "B.Fab")
			(effects
				(font
					(size 1.27 1.27)
				)
				(justify mirror)
			)
		)
		(duplicate_pad_numbers_are_jumpers no)
		(fp_line
			(start -0.7874 0.4064)
			(end 0.7874 0.4064)
			(stroke
				(width 0.1524)
				(type default)
			)
			(layer "B.SilkS")
		)
		(fp_line
			(start 0.7874 0.4064)
			(end 0.7874 -0.4064)
			(stroke
				(width 0.1524)
				(type default)
			)
			(layer "B.SilkS")
		)
		(fp_line
			(start -0.7874 -0.4064)
			(end -0.7874 0.4064)
			(stroke
				(width 0.1524)
				(type default)
			)
			(layer "B.SilkS")
		)
		(fp_line
			(start 0.7874 -0.4064)
			(end -0.7874 -0.4064)
			(stroke
				(width 0.1524)
				(type default)
			)
			(layer "B.SilkS")
		)
		(fp_line
			(start -0.67945 0.3048)
			(end -0.120396 0.3048)
			(stroke
				(width 0.1)
				(type default)
			)
			(layer "B.Fab")
		)
		(fp_line
			(start -0.120396 0.3048)
			(end -0.120396 0.2794)
			(stroke
				(width 0.1)
				(type default)
			)
			(layer "B.Fab")
		)
		(fp_line
			(start 0.12065 0.3048)
			(end 0.67945 0.3048)
			(stroke
				(width 0.1)
				(type default)
			)
			(layer "B.Fab")
		)
		(fp_line
			(start 0.67945 0.3048)
			(end 0.67945 -0.305054)
			(stroke
				(width 0.1)
				(type default)
			)
			(layer "B.Fab")
		)
		(fp_line
			(start -0.120396 0.2794)
			(end 0.12065 0.2794)
			(stroke
				(width 0.1)
				(type default)
			)
			(layer "B.Fab")
		)
		(fp_line
			(start 0.12065 0.2794)
			(end 0.12065 0.3048)
			(stroke
				(width 0.1)
				(type default)
			)
			(layer "B.Fab")
		)
		(fp_line
			(start -0.12065 -0.2794)
			(end -0.12065 -0.3048)
			(stroke
				(width 0.1)
				(type default)
			)
			(layer "B.Fab")
		)
		(fp_line
			(start 0.12065 -0.2794)
			(end -0.12065 -0.2794)
			(stroke
				(width 0.1)
				(type default)
			)
			(layer "B.Fab")
		)
		(fp_line
			(start -0.67945 -0.3048)
			(end -0.67945 0.3048)
			(stroke
				(width 0.1)
				(type default)
			)
			(layer "B.Fab")
		)
		(fp_line
			(start -0.12065 -0.3048)
			(end -0.67945 -0.3048)
			(stroke
				(width 0.1)
				(type default)
			)
			(layer "B.Fab")
		)
		(fp_line
			(start 0.12065 -0.305054)
			(end 0.12065 -0.2794)
			(stroke
				(width 0.1)
				(type default)
			)
			(layer "B.Fab")
		)
		(fp_line
			(start 0.67945 -0.305054)
			(end 0.12065 -0.305054)
			(stroke
				(width 0.1)
				(type default)
			)
			(layer "B.Fab")
		)
		(pad "1" smd circle
			(at 0.40005 0 90)
			(size 0 0)
			(layers "B.Cu" "B.Mask" "B.Paste")
			(net "HSC_VDD_R")
		)
		(pad "2" smd circle
			(at -0.40005 0 90)
			(size 0 0)
			(layers "B.Cu" "B.Mask" "B.Paste")
			(net "AGND_HSC")
		)
	)
	(footprint ""
		(layer "B.Cu")
		(at 257.63982 -49.430686 180)
		(property "Reference" "PR4541"
			(at 0 0 0)
			(layer "B.SilkS")
			(hide yes)
			(effects
				(font
					(size 1.27 1.27)
				)
				(justify mirror)
			)
		)
		(property "Value" ""
			(at 0 0 0)
			(layer "B.Fab")
			(effects
				(font
					(size 1.27 1.27)
				)
				(justify mirror)
			)
		)
		(duplicate_pad_numbers_are_jumpers no)
		(fp_line
			(start 0.7874 0.4064)
			(end 0.7874 -0.4064)
			(stroke
				(width 0.1524)
				(type default)
			)
			(layer "B.SilkS")
		)
		(fp_line
			(start 0.7874 -0.4064)
			(end -0.7874 -0.4064)
			(stroke
				(width 0.1524)
				(type default)
			)
			(layer "B.SilkS")
		)
		(fp_line
			(start -0.7874 0.4064)
			(end 0.7874 0.4064)
			(stroke
				(width 0.1524)
				(type default)
			)
			(layer "B.SilkS")
		)
		(fp_line
			(start -0.7874 -0.4064)
			(end -0.7874 0.4064)
			(stroke
				(width 0.1524)
				(type default)
			)
			(layer "B.SilkS")
		)
		(fp_line
			(start 0.67945 0.3048)
			(end 0.67945 -0.305054)
			(stroke
				(width 0.1)
				(type default)
			)
			(layer "B.Fab")
		)
		(fp_line
			(start 0.67945 -0.305054)
			(end 0.12065 -0.305054)
			(stroke
				(width 0.1)
				(type default)
			)
			(layer "B.Fab")
		)
		(fp_line
			(start 0.12065 0.3048)
			(end 0.67945 0.3048)
			(stroke
				(width 0.1)
				(type default)
			)
			(layer "B.Fab")
		)
		(fp_line
			(start 0.12065 0.2794)
			(end 0.12065 0.3048)
			(stroke
				(width 0.1)
				(type default)
			)
			(layer "B.Fab")
		)
		(fp_line
			(start 0.12065 -0.2794)
			(end -0.12065 -0.2794)
			(stroke
				(width 0.1)
				(type default)
			)
			(layer "B.Fab")
		)
		(fp_line
			(start 0.12065 -0.305054)
			(end 0.12065 -0.2794)
			(stroke
				(width 0.1)
				(type default)
			)
			(layer "B.Fab")
		)
		(fp_line
			(start -0.120396 0.3048)
			(end -0.120396 0.2794)
			(stroke
				(width 0.1)
				(type default)
			)
			(layer "B.Fab")
		)
		(fp_line
			(start -0.120396 0.2794)
			(end 0.12065 0.2794)
			(stroke
				(width 0.1)
				(type default)
			)
			(layer "B.Fab")
		)
		(fp_line
			(start -0.12065 -0.2794)
			(end -0.12065 -0.3048)
			(stroke
				(width 0.1)
				(type default)
			)
			(layer "B.Fab")
		)
		(fp_line
			(start -0.12065 -0.3048)
			(end -0.67945 -0.3048)
			(stroke
				(width 0.1)
				(type default)
			)
			(layer "B.Fab")
		)
		(fp_line
			(start -0.67945 0.3048)
			(end -0.120396 0.3048)
			(stroke
				(width 0.1)
				(type default)
			)
			(layer "B.Fab")
		)
		(fp_line
			(start -0.67945 -0.3048)
			(end -0.67945 0.3048)
			(stroke
				(width 0.1)
				(type default)
			)
			(layer "B.Fab")
		)
		(pad "1" smd circle
			(at 0.40005 0)
			(size 0 0)
			(layers "B.Cu" "B.Mask" "B.Paste")
			(net "P12V_E1S_ISET_0")
		)
		(pad "2" smd circle
			(at -0.40005 0)
			(size 0 0)
			(layers "B.Cu" "B.Mask" "B.Paste")
			(net "P12V_E1S_ISET_0_R")
		)
	)
	(footprint ""
		(layer "B.Cu")
		(at 348.2467 -358.848914 180)
		(property "Reference" "R2377"
			(at 0 0 0)
			(layer "B.SilkS")
			(hide yes)
			(effects
				(font
					(size 1.27 1.27)
				)
				(justify mirror)
			)
		)
		(property "Value" ""
			(at 0 0 0)
			(layer "B.Fab")
			(effects
				(font
					(size 1.27 1.27)
				)
				(justify mirror)
			)
		)
		(duplicate_pad_numbers_are_jumpers no)
		(fp_line
			(start 0.7874 0.4064)
			(end 0.7874 -0.4064)
			(stroke
				(width 0.1524)
				(type default)
			)
			(layer "B.SilkS")
		)
		(fp_line
			(start 0.7874 -0.4064)
			(end -0.7874 -0.4064)
			(stroke
				(width 0.1524)
				(type default)
			)
			(layer "B.SilkS")
		)
		(fp_line
			(start -0.7874 0.4064)
			(end 0.7874 0.4064)
			(stroke
				(width 0.1524)
				(type default)
			)
			(layer "B.SilkS")
		)
		(fp_line
			(start -0.7874 -0.4064)
			(end -0.7874 0.4064)
			(stroke
				(width 0.1524)
				(type default)
			)
			(layer "B.SilkS")
		)
		(fp_line
			(start 0.67945 0.3048)
			(end 0.67945 -0.305054)
			(stroke
				(width 0.1)
				(type default)
			)
			(layer "B.Fab")
		)
		(fp_line
			(start 0.67945 -0.305054)
			(end 0.12065 -0.305054)
			(stroke
				(width 0.1)
				(type default)
			)
			(layer "B.Fab")
		)
		(fp_line
			(start 0.12065 0.3048)
			(end 0.67945 0.3048)
			(stroke
				(width 0.1)
				(type default)
			)
			(layer "B.Fab")
		)
		(fp_line
			(start 0.12065 0.2794)
			(end 0.12065 0.3048)
			(stroke
				(width 0.1)
				(type default)
			)
			(layer "B.Fab")
		)
		(fp_line
			(start 0.12065 -0.2794)
			(end -0.12065 -0.2794)
			(stroke
				(width 0.1)
				(type default)
			)
			(layer "B.Fab")
		)
		(fp_line
			(start 0.12065 -0.305054)
			(end 0.12065 -0.2794)
			(stroke
				(width 0.1)
				(type default)
			)
			(layer "B.Fab")
		)
		(fp_line
			(start -0.120396 0.3048)
			(end -0.120396 0.2794)
			(stroke
				(width 0.1)
				(type default)
			)
			(layer "B.Fab")
		)
		(fp_line
			(start -0.120396 0.2794)
			(end 0.12065 0.2794)
			(stroke
				(width 0.1)
				(type default)
			)
			(layer "B.Fab")
		)
		(fp_line
			(start -0.12065 -0.2794)
			(end -0.12065 -0.3048)
			(stroke
				(width 0.1)
				(type default)
			)
			(layer "B.Fab")
		)
		(fp_line
			(start -0.12065 -0.3048)
			(end -0.67945 -0.3048)
			(stroke
				(width 0.1)
				(type default)
			)
			(layer "B.Fab")
		)
		(fp_line
			(start -0.67945 0.3048)
			(end -0.120396 0.3048)
			(stroke
				(width 0.1)
				(type default)
			)
			(layer "B.Fab")
		)
		(fp_line
			(start -0.67945 -0.3048)
			(end -0.67945 0.3048)
			(stroke
				(width 0.1)
				(type default)
			)
			(layer "B.Fab")
		)
		(pad "1" smd circle
			(at 0.40005 0)
			(size 0 0)
			(layers "B.Cu" "B.Mask" "B.Paste")
			(net "P3V3_AUX")
		)
		(pad "2" smd circle
			(at -0.40005 0)
			(size 0 0)
			(layers "B.Cu" "B.Mask" "B.Paste")
			(net "PWRGD_PVCCFA_EHV_FIVRA_CPU0_R")
		)
	)
	(footprint ""
		(layer "B.Cu")
		(at 278.128984 -193.669666 -90)
		(property "Reference" "R253"
			(at 0 0 90)
			(layer "B.SilkS")
			(hide yes)
			(effects
				(font
					(size 1.27 1.27)
				)
				(justify mirror)
			)
		)
		(property "Value" ""
			(at 0 0 90)
			(layer "B.Fab")
			(effects
				(font
					(size 1.27 1.27)
				)
				(justify mirror)
			)
		)
		(duplicate_pad_numbers_are_jumpers no)
		(fp_line
			(start -0.7874 0.4064)
			(end 0.7874 0.4064)
			(stroke
				(width 0.1524)
				(type default)
			)
			(layer "B.SilkS")
		)
		(fp_line
			(start 0.7874 0.4064)
			(end 0.7874 -0.4064)
			(stroke
				(width 0.1524)
				(type default)
			)
			(layer "B.SilkS")
		)
		(fp_line
			(start -0.7874 -0.4064)
			(end -0.7874 0.4064)
			(stroke
				(width 0.1524)
				(type default)
			)
			(layer "B.SilkS")
		)
		(fp_line
			(start 0.7874 -0.4064)
			(end -0.7874 -0.4064)
			(stroke
				(width 0.1524)
				(type default)
			)
			(layer "B.SilkS")
		)
		(fp_line
			(start -0.67945 0.3048)
			(end -0.120396 0.3048)
			(stroke
				(width 0.1)
				(type default)
			)
			(layer "B.Fab")
		)
		(fp_line
			(start -0.120396 0.3048)
			(end -0.120396 0.2794)
			(stroke
				(width 0.1)
				(type default)
			)
			(layer "B.Fab")
		)
		(fp_line
			(start 0.12065 0.3048)
			(end 0.67945 0.3048)
			(stroke
				(width 0.1)
				(type default)
			)
			(layer "B.Fab")
		)
		(fp_line
			(start 0.67945 0.3048)
			(end 0.67945 -0.305054)
			(stroke
				(width 0.1)
				(type default)
			)
			(layer "B.Fab")
		)
		(fp_line
			(start -0.120396 0.2794)
			(end 0.12065 0.2794)
			(stroke
				(width 0.1)
				(type default)
			)
			(layer "B.Fab")
		)
		(fp_line
			(start 0.12065 0.2794)
			(end 0.12065 0.3048)
			(stroke
				(width 0.1)
				(type default)
			)
			(layer "B.Fab")
		)
		(fp_line
			(start -0.12065 -0.2794)
			(end -0.12065 -0.3048)
			(stroke
				(width 0.1)
				(type default)
			)
			(layer "B.Fab")
		)
		(fp_line
			(start 0.12065 -0.2794)
			(end -0.12065 -0.2794)
			(stroke
				(width 0.1)
				(type default)
			)
			(layer "B.Fab")
		)
		(fp_line
			(start -0.67945 -0.3048)
			(end -0.67945 0.3048)
			(stroke
				(width 0.1)
				(type default)
			)
			(layer "B.Fab")
		)
		(fp_line
			(start -0.12065 -0.3048)
			(end -0.67945 -0.3048)
			(stroke
				(width 0.1)
				(type default)
			)
			(layer "B.Fab")
		)
		(fp_line
			(start 0.12065 -0.305054)
			(end 0.12065 -0.2794)
			(stroke
				(width 0.1)
				(type default)
			)
			(layer "B.Fab")
		)
		(fp_line
			(start 0.67945 -0.305054)
			(end 0.12065 -0.305054)
			(stroke
				(width 0.1)
				(type default)
			)
			(layer "B.Fab")
		)
		(pad "1" smd circle
			(at 0.40005 0 90)
			(size 0 0)
			(layers "B.Cu" "B.Mask" "B.Paste")
			(net "PVNN_TERM_CPU0")
		)
		(pad "2" smd circle
			(at -0.40005 0 90)
			(size 0 0)
			(layers "B.Cu" "B.Mask" "B.Paste")
			(net "FM_S3M_CPU0_LVC1_GPIO_2")
		)
	)
	(footprint ""
		(layer "B.Cu")
		(at 416.121342 -354.903786 -90)
		(property "Reference" "PC2645"
			(at 0 0 90)
			(layer "B.SilkS")
			(hide yes)
			(effects
				(font
					(size 1.27 1.27)
				)
				(justify mirror)
			)
		)
		(property "Value" ""
			(at 0 0 90)
			(layer "B.Fab")
			(effects
				(font
					(size 1.27 1.27)
				)
				(justify mirror)
			)
		)
		(duplicate_pad_numbers_are_jumpers no)
		(fp_line
			(start -4.533392 2.249932)
			(end 4.533392 2.249932)
			(stroke
				(width 0.1524)
				(type default)
			)
			(layer "B.SilkS")
		)
		(fp_line
			(start 4.533392 2.249932)
			(end 4.533392 -2.249932)
			(stroke
				(width 0.1524)
				(type default)
			)
			(layer "B.SilkS")
		)
		(fp_line
			(start -4.533392 -2.249932)
			(end -4.533392 2.249932)
			(stroke
				(width 0.1524)
				(type default)
			)
			(layer "B.SilkS")
		)
		(fp_line
			(start 4.533392 -2.249932)
			(end -4.533392 -2.249932)
			(stroke
				(width 0.1524)
				(type default)
			)
			(layer "B.SilkS")
		)
		(fp_rect
			(start 5.39242 2.326132)
			(end 4.533392 -2.326132)
			(stroke
				(width 0)
				(type default)
			)
			(fill yes)
			(layer "B.SilkS")
		)
		(fp_line
			(start -3.750056 2.249932)
			(end 3.750056 2.249932)
			(stroke
				(width 0.1)
				(type default)
			)
			(layer "B.Fab")
		)
		(fp_line
			(start 3.750056 2.249932)
			(end 3.750056 -2.249932)
			(stroke
				(width 0.1)
				(type default)
			)
			(layer "B.Fab")
		)
		(fp_line
			(start -3.750056 -2.249932)
			(end -3.750056 2.249932)
			(stroke
				(width 0.1)
				(type default)
			)
			(layer "B.Fab")
		)
		(fp_line
			(start 3.750056 -2.249932)
			(end -3.750056 -2.249932)
			(stroke
				(width 0.1)
				(type default)
			)
			(layer "B.Fab")
		)
		(fp_text user "-"
			(at -4.598162 1.848612 270)
			(unlocked yes)
			(layer "B.SilkS")
			(effects
				(font
					(size 1.905 1.4224)
					(thickness 0.1524)
				)
				(justify left mirror)
			)
		)
		(fp_text user "+"
			(at 6.322314 0.786384 180)
			(unlocked yes)
			(layer "B.SilkS")
			(effects
				(font
					(size 1.905 1.4224)
					(thickness 0.1524)
				)
				(justify left mirror)
			)
		)
		(fp_text user "+"
			(at 6.322314 0.786384 180)
			(unlocked yes)
			(layer "B.Fab")
			(effects
				(font
					(size 1.905 1.4224)
					(thickness 0.1524)
				)
				(justify left mirror)
			)
		)
		(fp_text user "-"
			(at -4.8514 -0.14605 270)
			(unlocked yes)
			(layer "B.Fab")
			(effects
				(font
					(size 1.905 1.4224)
					(thickness 0.1524)
				)
				(justify left mirror)
			)
		)
		(pad "1" smd rect
			(at 3.199892 0 90)
			(size 2.413 2.8194)
			(layers "B.Cu" "B.Mask" "B.Paste")
			(net "PVCCFA_EHV_FIVRA_CPU0")
		)
		(pad "2" smd rect
			(at -3.199892 0 90)
			(size 2.413 2.8194)
			(layers "B.Cu" "B.Mask" "B.Paste")
			(net "GND")
		)
	)
	(footprint ""
		(layer "B.Cu")
		(at 366.09782 -212.049614)
		(property "Reference" "C525"
			(at 0 0 0)
			(layer "B.SilkS")
			(hide yes)
			(effects
				(font
					(size 1.27 1.27)
				)
				(justify mirror)
			)
		)
		(property "Value" ""
			(at 0 0 0)
			(layer "B.Fab")
			(effects
				(font
					(size 1.27 1.27)
				)
				(justify mirror)
			)
		)
		(duplicate_pad_numbers_are_jumpers no)
		(fp_line
			(start -1.524 -0.762)
			(end -1.524 0.762)
			(stroke
				(width 0.1524)
				(type default)
			)
			(layer "B.SilkS")
		)
		(fp_line
			(start -1.524 0.762)
			(end 1.524 0.762)
			(stroke
				(width 0.1524)
				(type default)
			)
			(layer "B.SilkS")
		)
		(fp_line
			(start 1.524 -0.762)
			(end -1.524 -0.762)
			(stroke
				(width 0.1524)
				(type default)
			)
			(layer "B.SilkS")
		)
		(fp_line
			(start 1.524 0.762)
			(end 1.524 -0.762)
			(stroke
				(width 0.1524)
				(type default)
			)
			(layer "B.SilkS")
		)
		(fp_line
			(start -1.1049 -0.724916)
			(end 1.1049 -0.724916)
			(stroke
				(width 0.1)
				(type default)
			)
			(layer "B.Fab")
		)
		(fp_line
			(start -1.1049 0.724916)
			(end -1.1049 -0.724916)
			(stroke
				(width 0.1)
				(type default)
			)
			(layer "B.Fab")
		)
		(fp_line
			(start 1.1049 -0.724916)
			(end 1.1049 0.724916)
			(stroke
				(width 0.1)
				(type default)
			)
			(layer "B.Fab")
		)
		(fp_line
			(start 1.1049 0.724916)
			(end -1.1049 0.724916)
			(stroke
				(width 0.1)
				(type default)
			)
			(layer "B.Fab")
		)
		(pad "1" smd rect
			(at 0.889 0)
			(size 1.016 1.27)
			(layers "B.Cu" "B.Mask" "B.Paste")
			(net "PVCCINFAON_CPU0")
		)
		(pad "2" smd rect
			(at -0.889 0)
			(size 1.016 1.27)
			(layers "B.Cu" "B.Mask" "B.Paste")
			(net "GND")
		)
	)
	(footprint ""
		(layer "B.Cu")
		(at 376.618754 -190.703708 90)
		(property "Reference" "R689"
			(at 0 0 90)
			(layer "B.SilkS")
			(hide yes)
			(effects
				(font
					(size 1.27 1.27)
				)
				(justify mirror)
			)
		)
		(property "Value" ""
			(at 0 0 90)
			(layer "B.Fab")
			(effects
				(font
					(size 1.27 1.27)
				)
				(justify mirror)
			)
		)
		(duplicate_pad_numbers_are_jumpers no)
		(fp_line
			(start 0.7874 -0.4064)
			(end -0.7874 -0.4064)
			(stroke
				(width 0.1524)
				(type default)
			)
			(layer "B.SilkS")
		)
		(fp_line
			(start -0.7874 -0.4064)
			(end -0.7874 0.4064)
			(stroke
				(width 0.1524)
				(type default)
			)
			(layer "B.SilkS")
		)
		(fp_line
			(start 0.7874 0.4064)
			(end 0.7874 -0.4064)
			(stroke
				(width 0.1524)
				(type default)
			)
			(layer "B.SilkS")
		)
		(fp_line
			(start -0.7874 0.4064)
			(end 0.7874 0.4064)
			(stroke
				(width 0.1524)
				(type default)
			)
			(layer "B.SilkS")
		)
		(fp_line
			(start 0.67945 -0.305054)
			(end 0.12065 -0.305054)
			(stroke
				(width 0.1)
				(type default)
			)
			(layer "B.Fab")
		)
		(fp_line
			(start 0.12065 -0.305054)
			(end 0.12065 -0.2794)
			(stroke
				(width 0.1)
				(type default)
			)
			(layer "B.Fab")
		)
		(fp_line
			(start -0.12065 -0.3048)
			(end -0.67945 -0.3048)
			(stroke
				(width 0.1)
				(type default)
			)
			(layer "B.Fab")
		)
		(fp_line
			(start -0.67945 -0.3048)
			(end -0.67945 0.3048)
			(stroke
				(width 0.1)
				(type default)
			)
			(layer "B.Fab")
		)
		(fp_line
			(start 0.12065 -0.2794)
			(end -0.12065 -0.2794)
			(stroke
				(width 0.1)
				(type default)
			)
			(layer "B.Fab")
		)
		(fp_line
			(start -0.12065 -0.2794)
			(end -0.12065 -0.3048)
			(stroke
				(width 0.1)
				(type default)
			)
			(layer "B.Fab")
		)
		(fp_line
			(start 0.12065 0.2794)
			(end 0.12065 0.3048)
			(stroke
				(width 0.1)
				(type default)
			)
			(layer "B.Fab")
		)
		(fp_line
			(start -0.120396 0.2794)
			(end 0.12065 0.2794)
			(stroke
				(width 0.1)
				(type default)
			)
			(layer "B.Fab")
		)
		(fp_line
			(start 0.67945 0.3048)
			(end 0.67945 -0.305054)
			(stroke
				(width 0.1)
				(type default)
			)
			(layer "B.Fab")
		)
		(fp_line
			(start 0.12065 0.3048)
			(end 0.67945 0.3048)
			(stroke
				(width 0.1)
				(type default)
			)
			(layer "B.Fab")
		)
		(fp_line
			(start -0.120396 0.3048)
			(end -0.120396 0.2794)
			(stroke
				(width 0.1)
				(type default)
			)
			(layer "B.Fab")
		)
		(fp_line
			(start -0.67945 0.3048)
			(end -0.120396 0.3048)
			(stroke
				(width 0.1)
				(type default)
			)
			(layer "B.Fab")
		)
		(pad "1" smd circle
			(at 0.40005 0 270)
			(size 0 0)
			(layers "B.Cu" "B.Mask" "B.Paste")
			(net "I3C_SPD_DDREFGH_CPU0_SCL")
		)
		(pad "2" smd circle
			(at -0.40005 0 270)
			(size 0 0)
			(layers "B.Cu" "B.Mask" "B.Paste")
			(net "I3C_SPD_DDREFGH_CPU0_R_SCL")
		)
	)
	(footprint ""
		(layer "B.Cu")
		(at 339.042756 -50.678842 90)
		(property "Reference" "C1262"
			(at 0 0 90)
			(layer "B.SilkS")
			(hide yes)
			(effects
				(font
					(size 1.27 1.27)
				)
				(justify mirror)
			)
		)
		(property "Value" ""
			(at 0 0 90)
			(layer "B.Fab")
			(effects
				(font
					(size 1.27 1.27)
				)
				(justify mirror)
			)
		)
		(duplicate_pad_numbers_are_jumpers no)
		(fp_line
			(start 0.7874 -0.4064)
			(end -0.7874 -0.4064)
			(stroke
				(width 0.1524)
				(type default)
			)
			(layer "B.SilkS")
		)
		(fp_line
			(start -0.7874 -0.4064)
			(end -0.7874 0.4064)
			(stroke
				(width 0.1524)
				(type default)
			)
			(layer "B.SilkS")
		)
		(fp_line
			(start 0.7874 0.4064)
			(end 0.7874 -0.4064)
			(stroke
				(width 0.1524)
				(type default)
			)
			(layer "B.SilkS")
		)
		(fp_line
			(start -0.7874 0.4064)
			(end 0.7874 0.4064)
			(stroke
				(width 0.1524)
				(type default)
			)
			(layer "B.SilkS")
		)
		(fp_line
			(start 0.67945 -0.305054)
			(end 0.12065 -0.305054)
			(stroke
				(width 0.1)
				(type default)
			)
			(layer "B.Fab")
		)
		(fp_line
			(start 0.12065 -0.305054)
			(end 0.12065 -0.2794)
			(stroke
				(width 0.1)
				(type default)
			)
			(layer "B.Fab")
		)
		(fp_line
			(start -0.12065 -0.3048)
			(end -0.67945 -0.3048)
			(stroke
				(width 0.1)
				(type default)
			)
			(layer "B.Fab")
		)
		(fp_line
			(start -0.67945 -0.3048)
			(end -0.67945 0.3048)
			(stroke
				(width 0.1)
				(type default)
			)
			(layer "B.Fab")
		)
		(fp_line
			(start 0.12065 -0.2794)
			(end -0.12065 -0.2794)
			(stroke
				(width 0.1)
				(type default)
			)
			(layer "B.Fab")
		)
		(fp_line
			(start -0.12065 -0.2794)
			(end -0.12065 -0.3048)
			(stroke
				(width 0.1)
				(type default)
			)
			(layer "B.Fab")
		)
		(fp_line
			(start 0.12065 0.2794)
			(end 0.12065 0.3048)
			(stroke
				(width 0.1)
				(type default)
			)
			(layer "B.Fab")
		)
		(fp_line
			(start -0.120396 0.2794)
			(end 0.12065 0.2794)
			(stroke
				(width 0.1)
				(type default)
			)
			(layer "B.Fab")
		)
		(fp_line
			(start 0.67945 0.3048)
			(end 0.67945 -0.305054)
			(stroke
				(width 0.1)
				(type default)
			)
			(layer "B.Fab")
		)
		(fp_line
			(start 0.12065 0.3048)
			(end 0.67945 0.3048)
			(stroke
				(width 0.1)
				(type default)
			)
			(layer "B.Fab")
		)
		(fp_line
			(start -0.120396 0.3048)
			(end -0.120396 0.2794)
			(stroke
				(width 0.1)
				(type default)
			)
			(layer "B.Fab")
		)
		(fp_line
			(start -0.67945 0.3048)
			(end -0.120396 0.3048)
			(stroke
				(width 0.1)
				(type default)
			)
			(layer "B.Fab")
		)
		(pad "1" smd circle
			(at 0.40005 0 270)
			(size 0 0)
			(layers "B.Cu" "B.Mask" "B.Paste")
			(net "P1V05_PCH_PLL_AUX")
		)
		(pad "2" smd circle
			(at -0.40005 0 270)
			(size 0 0)
			(layers "B.Cu" "B.Mask" "B.Paste")
			(net "GND")
		)
	)
	(footprint ""
		(layer "B.Cu")
		(at 409.32608 -148.173948 180)
		(property "Reference" "PR4229"
			(at 0 0 0)
			(layer "B.SilkS")
			(hide yes)
			(effects
				(font
					(size 1.27 1.27)
				)
				(justify mirror)
			)
		)
		(property "Value" ""
			(at 0 0 0)
			(layer "B.Fab")
			(effects
				(font
					(size 1.27 1.27)
				)
				(justify mirror)
			)
		)
		(duplicate_pad_numbers_are_jumpers no)
		(fp_line
			(start 0.7874 0.4064)
			(end 0.7874 -0.4064)
			(stroke
				(width 0.1524)
				(type default)
			)
			(layer "B.SilkS")
		)
		(fp_line
			(start 0.7874 -0.4064)
			(end -0.7874 -0.4064)
			(stroke
				(width 0.1524)
				(type default)
			)
			(layer "B.SilkS")
		)
		(fp_line
			(start -0.7874 0.4064)
			(end 0.7874 0.4064)
			(stroke
				(width 0.1524)
				(type default)
			)
			(layer "B.SilkS")
		)
		(fp_line
			(start -0.7874 -0.4064)
			(end -0.7874 0.4064)
			(stroke
				(width 0.1524)
				(type default)
			)
			(layer "B.SilkS")
		)
		(fp_line
			(start 0.67945 0.3048)
			(end 0.67945 -0.305054)
			(stroke
				(width 0.1)
				(type default)
			)
			(layer "B.Fab")
		)
		(fp_line
			(start 0.67945 -0.305054)
			(end 0.12065 -0.305054)
			(stroke
				(width 0.1)
				(type default)
			)
			(layer "B.Fab")
		)
		(fp_line
			(start 0.12065 0.3048)
			(end 0.67945 0.3048)
			(stroke
				(width 0.1)
				(type default)
			)
			(layer "B.Fab")
		)
		(fp_line
			(start 0.12065 0.2794)
			(end 0.12065 0.3048)
			(stroke
				(width 0.1)
				(type default)
			)
			(layer "B.Fab")
		)
		(fp_line
			(start 0.12065 -0.2794)
			(end -0.12065 -0.2794)
			(stroke
				(width 0.1)
				(type default)
			)
			(layer "B.Fab")
		)
		(fp_line
			(start 0.12065 -0.305054)
			(end 0.12065 -0.2794)
			(stroke
				(width 0.1)
				(type default)
			)
			(layer "B.Fab")
		)
		(fp_line
			(start -0.120396 0.3048)
			(end -0.120396 0.2794)
			(stroke
				(width 0.1)
				(type default)
			)
			(layer "B.Fab")
		)
		(fp_line
			(start -0.120396 0.2794)
			(end 0.12065 0.2794)
			(stroke
				(width 0.1)
				(type default)
			)
			(layer "B.Fab")
		)
		(fp_line
			(start -0.12065 -0.2794)
			(end -0.12065 -0.3048)
			(stroke
				(width 0.1)
				(type default)
			)
			(layer "B.Fab")
		)
		(fp_line
			(start -0.12065 -0.3048)
			(end -0.67945 -0.3048)
			(stroke
				(width 0.1)
				(type default)
			)
			(layer "B.Fab")
		)
		(fp_line
			(start -0.67945 0.3048)
			(end -0.120396 0.3048)
			(stroke
				(width 0.1)
				(type default)
			)
			(layer "B.Fab")
		)
		(fp_line
			(start -0.67945 -0.3048)
			(end -0.67945 0.3048)
			(stroke
				(width 0.1)
				(type default)
			)
			(layer "B.Fab")
		)
		(pad "1" smd circle
			(at 0.40005 0)
			(size 0 0)
			(layers "B.Cu" "B.Mask" "B.Paste")
			(net "PVCCFA_EHV_CPU0")
		)
		(pad "2" smd circle
			(at -0.40005 0)
			(size 0 0)
			(layers "B.Cu" "B.Mask" "B.Paste")
			(net "GND")
		)
	)
	(footprint ""
		(layer "B.Cu")
		(at 333.382366 -328.298048 -90)
		(property "Reference" "PC268_P0_6"
			(at 0 0 90)
			(layer "B.SilkS")
			(hide yes)
			(effects
				(font
					(size 1.27 1.27)
				)
				(justify mirror)
			)
		)
		(property "Value" ""
			(at 0 0 90)
			(layer "B.Fab")
			(effects
				(font
					(size 1.27 1.27)
				)
				(justify mirror)
			)
		)
		(duplicate_pad_numbers_are_jumpers no)
		(fp_line
			(start -1.524 0.762)
			(end 1.524 0.762)
			(stroke
				(width 0.1524)
				(type default)
			)
			(layer "B.SilkS")
		)
		(fp_line
			(start 1.524 0.762)
			(end 1.524 -0.762)
			(stroke
				(width 0.1524)
				(type default)
			)
			(layer "B.SilkS")
		)
		(fp_line
			(start -1.524 -0.762)
			(end -1.524 0.762)
			(stroke
				(width 0.1524)
				(type default)
			)
			(layer "B.SilkS")
		)
		(fp_line
			(start 1.524 -0.762)
			(end -1.524 -0.762)
			(stroke
				(width 0.1524)
				(type default)
			)
			(layer "B.SilkS")
		)
		(fp_line
			(start -1.1049 0.724916)
			(end -1.1049 -0.724916)
			(stroke
				(width 0.1)
				(type default)
			)
			(layer "B.Fab")
		)
		(fp_line
			(start 1.1049 0.724916)
			(end -1.1049 0.724916)
			(stroke
				(width 0.1)
				(type default)
			)
			(layer "B.Fab")
		)
		(fp_line
			(start -1.1049 -0.724916)
			(end 1.1049 -0.724916)
			(stroke
				(width 0.1)
				(type default)
			)
			(layer "B.Fab")
		)
		(fp_line
			(start 1.1049 -0.724916)
			(end 1.1049 0.724916)
			(stroke
				(width 0.1)
				(type default)
			)
			(layer "B.Fab")
		)
		(pad "1" smd rect
			(at 0.889 0 270)
			(size 1.016 1.27)
			(layers "B.Cu" "B.Mask" "B.Paste")
			(net "PVCCIN_CPU0")
		)
		(pad "2" smd rect
			(at -0.889 0 270)
			(size 1.016 1.27)
			(layers "B.Cu" "B.Mask" "B.Paste")
			(net "GND")
		)
	)
	(footprint ""
		(layer "B.Cu")
		(at 186.464194 -319.028826 90)
		(property "Reference" "R946"
			(at 0 0 90)
			(layer "B.SilkS")
			(hide yes)
			(effects
				(font
					(size 1.27 1.27)
				)
				(justify mirror)
			)
		)
		(property "Value" ""
			(at 0 0 90)
			(layer "B.Fab")
			(effects
				(font
					(size 1.27 1.27)
				)
				(justify mirror)
			)
		)
		(duplicate_pad_numbers_are_jumpers no)
		(fp_line
			(start 0.7874 -0.4064)
			(end -0.7874 -0.4064)
			(stroke
				(width 0.1524)
				(type default)
			)
			(layer "B.SilkS")
		)
		(fp_line
			(start -0.7874 -0.4064)
			(end -0.7874 0.4064)
			(stroke
				(width 0.1524)
				(type default)
			)
			(layer "B.SilkS")
		)
		(fp_line
			(start 0.7874 0.4064)
			(end 0.7874 -0.4064)
			(stroke
				(width 0.1524)
				(type default)
			)
			(layer "B.SilkS")
		)
		(fp_line
			(start -0.7874 0.4064)
			(end 0.7874 0.4064)
			(stroke
				(width 0.1524)
				(type default)
			)
			(layer "B.SilkS")
		)
		(fp_line
			(start 0.67945 -0.305054)
			(end 0.12065 -0.305054)
			(stroke
				(width 0.1)
				(type default)
			)
			(layer "B.Fab")
		)
		(fp_line
			(start 0.12065 -0.305054)
			(end 0.12065 -0.2794)
			(stroke
				(width 0.1)
				(type default)
			)
			(layer "B.Fab")
		)
		(fp_line
			(start -0.12065 -0.3048)
			(end -0.67945 -0.3048)
			(stroke
				(width 0.1)
				(type default)
			)
			(layer "B.Fab")
		)
		(fp_line
			(start -0.67945 -0.3048)
			(end -0.67945 0.3048)
			(stroke
				(width 0.1)
				(type default)
			)
			(layer "B.Fab")
		)
		(fp_line
			(start 0.12065 -0.2794)
			(end -0.12065 -0.2794)
			(stroke
				(width 0.1)
				(type default)
			)
			(layer "B.Fab")
		)
		(fp_line
			(start -0.12065 -0.2794)
			(end -0.12065 -0.3048)
			(stroke
				(width 0.1)
				(type default)
			)
			(layer "B.Fab")
		)
		(fp_line
			(start 0.12065 0.2794)
			(end 0.12065 0.3048)
			(stroke
				(width 0.1)
				(type default)
			)
			(layer "B.Fab")
		)
		(fp_line
			(start -0.120396 0.2794)
			(end 0.12065 0.2794)
			(stroke
				(width 0.1)
				(type default)
			)
			(layer "B.Fab")
		)
		(fp_line
			(start 0.67945 0.3048)
			(end 0.67945 -0.305054)
			(stroke
				(width 0.1)
				(type default)
			)
			(layer "B.Fab")
		)
		(fp_line
			(start 0.12065 0.3048)
			(end 0.67945 0.3048)
			(stroke
				(width 0.1)
				(type default)
			)
			(layer "B.Fab")
		)
		(fp_line
			(start -0.120396 0.3048)
			(end -0.120396 0.2794)
			(stroke
				(width 0.1)
				(type default)
			)
			(layer "B.Fab")
		)
		(fp_line
			(start -0.67945 0.3048)
			(end -0.120396 0.3048)
			(stroke
				(width 0.1)
				(type default)
			)
			(layer "B.Fab")
		)
		(pad "1" smd circle
			(at 0.40005 0 270)
			(size 0 0)
			(layers "B.Cu" "B.Mask" "B.Paste")
			(net "P3V3_AUX")
		)
		(pad "2" smd circle
			(at -0.40005 0 270)
			(size 0 0)
			(layers "B.Cu" "B.Mask" "B.Paste")
			(net "PWRGD_FAIL_CPU1_EF_R1")
		)
	)
	(footprint ""
		(layer "B.Cu")
		(at 90.340688 -341.017606 -90)
		(property "Reference" "PC513_P1_6"
			(at 0 0 90)
			(layer "B.SilkS")
			(hide yes)
			(effects
				(font
					(size 1.27 1.27)
				)
				(justify mirror)
			)
		)
		(property "Value" ""
			(at 0 0 90)
			(layer "B.Fab")
			(effects
				(font
					(size 1.27 1.27)
				)
				(justify mirror)
			)
		)
		(duplicate_pad_numbers_are_jumpers no)
		(fp_line
			(start -1.524 0.762)
			(end 1.524 0.762)
			(stroke
				(width 0.1524)
				(type default)
			)
			(layer "B.SilkS")
		)
		(fp_line
			(start 1.524 0.762)
			(end 1.524 -0.762)
			(stroke
				(width 0.1524)
				(type default)
			)
			(layer "B.SilkS")
		)
		(fp_line
			(start -1.524 -0.762)
			(end -1.524 0.762)
			(stroke
				(width 0.1524)
				(type default)
			)
			(layer "B.SilkS")
		)
		(fp_line
			(start 1.524 -0.762)
			(end -1.524 -0.762)
			(stroke
				(width 0.1524)
				(type default)
			)
			(layer "B.SilkS")
		)
		(fp_line
			(start -1.1049 0.724916)
			(end -1.1049 -0.724916)
			(stroke
				(width 0.1)
				(type default)
			)
			(layer "B.Fab")
		)
		(fp_line
			(start 1.1049 0.724916)
			(end -1.1049 0.724916)
			(stroke
				(width 0.1)
				(type default)
			)
			(layer "B.Fab")
		)
		(fp_line
			(start -1.1049 -0.724916)
			(end 1.1049 -0.724916)
			(stroke
				(width 0.1)
				(type default)
			)
			(layer "B.Fab")
		)
		(fp_line
			(start 1.1049 -0.724916)
			(end 1.1049 0.724916)
			(stroke
				(width 0.1)
				(type default)
			)
			(layer "B.Fab")
		)
		(pad "1" smd rect
			(at 0.889 0 270)
			(size 1.016 1.27)
			(layers "B.Cu" "B.Mask" "B.Paste")
			(net "SW_P12V_PVCCIN_CPU1_FLT")
		)
		(pad "2" smd rect
			(at -0.889 0 270)
			(size 1.016 1.27)
			(layers "B.Cu" "B.Mask" "B.Paste")
			(net "GND")
		)
	)
	(footprint ""
		(layer "B.Cu")
		(at 286.0294 -367.355628 -90)
		(property "Reference" "PR4217"
			(at 0 0 90)
			(layer "B.SilkS")
			(hide yes)
			(effects
				(font
					(size 1.27 1.27)
				)
				(justify mirror)
			)
		)
		(property "Value" ""
			(at 0 0 90)
			(layer "B.Fab")
			(effects
				(font
					(size 1.27 1.27)
				)
				(justify mirror)
			)
		)
		(duplicate_pad_numbers_are_jumpers no)
		(fp_line
			(start -0.7874 0.4064)
			(end 0.7874 0.4064)
			(stroke
				(width 0.1524)
				(type default)
			)
			(layer "B.SilkS")
		)
		(fp_line
			(start 0.7874 0.4064)
			(end 0.7874 -0.4064)
			(stroke
				(width 0.1524)
				(type default)
			)
			(layer "B.SilkS")
		)
		(fp_line
			(start -0.7874 -0.4064)
			(end -0.7874 0.4064)
			(stroke
				(width 0.1524)
				(type default)
			)
			(layer "B.SilkS")
		)
		(fp_line
			(start 0.7874 -0.4064)
			(end -0.7874 -0.4064)
			(stroke
				(width 0.1524)
				(type default)
			)
			(layer "B.SilkS")
		)
		(fp_line
			(start -0.67945 0.3048)
			(end -0.120396 0.3048)
			(stroke
				(width 0.1)
				(type default)
			)
			(layer "B.Fab")
		)
		(fp_line
			(start -0.120396 0.3048)
			(end -0.120396 0.2794)
			(stroke
				(width 0.1)
				(type default)
			)
			(layer "B.Fab")
		)
		(fp_line
			(start 0.12065 0.3048)
			(end 0.67945 0.3048)
			(stroke
				(width 0.1)
				(type default)
			)
			(layer "B.Fab")
		)
		(fp_line
			(start 0.67945 0.3048)
			(end 0.67945 -0.305054)
			(stroke
				(width 0.1)
				(type default)
			)
			(layer "B.Fab")
		)
		(fp_line
			(start -0.120396 0.2794)
			(end 0.12065 0.2794)
			(stroke
				(width 0.1)
				(type default)
			)
			(layer "B.Fab")
		)
		(fp_line
			(start 0.12065 0.2794)
			(end 0.12065 0.3048)
			(stroke
				(width 0.1)
				(type default)
			)
			(layer "B.Fab")
		)
		(fp_line
			(start -0.12065 -0.2794)
			(end -0.12065 -0.3048)
			(stroke
				(width 0.1)
				(type default)
			)
			(layer "B.Fab")
		)
		(fp_line
			(start 0.12065 -0.2794)
			(end -0.12065 -0.2794)
			(stroke
				(width 0.1)
				(type default)
			)
			(layer "B.Fab")
		)
		(fp_line
			(start -0.67945 -0.3048)
			(end -0.67945 0.3048)
			(stroke
				(width 0.1)
				(type default)
			)
			(layer "B.Fab")
		)
		(fp_line
			(start -0.12065 -0.3048)
			(end -0.67945 -0.3048)
			(stroke
				(width 0.1)
				(type default)
			)
			(layer "B.Fab")
		)
		(fp_line
			(start 0.12065 -0.305054)
			(end 0.12065 -0.2794)
			(stroke
				(width 0.1)
				(type default)
			)
			(layer "B.Fab")
		)
		(fp_line
			(start 0.67945 -0.305054)
			(end 0.12065 -0.305054)
			(stroke
				(width 0.1)
				(type default)
			)
			(layer "B.Fab")
		)
		(pad "1" smd circle
			(at 0.40005 0 90)
			(size 0 0)
			(layers "B.Cu" "B.Mask" "B.Paste")
			(net "PVCCFA_EHV_FIVRA_CPU0_IMON4")
		)
		(pad "2" smd circle
			(at -0.40005 0 90)
			(size 0 0)
			(layers "B.Cu" "B.Mask" "B.Paste")
			(net "GND")
		)
	)
	(footprint ""
		(layer "B.Cu")
		(at 419.417246 -362.107226 90)
		(property "Reference" "PC608_P0_1"
			(at 0 0 90)
			(layer "B.SilkS")
			(hide yes)
			(effects
				(font
					(size 1.27 1.27)
				)
				(justify mirror)
			)
		)
		(property "Value" ""
			(at 0 0 90)
			(layer "B.Fab")
			(effects
				(font
					(size 1.27 1.27)
				)
				(justify mirror)
			)
		)
		(duplicate_pad_numbers_are_jumpers no)
		(fp_line
			(start 1.524 -0.762)
			(end -1.524 -0.762)
			(stroke
				(width 0.1524)
				(type default)
			)
			(layer "B.SilkS")
		)
		(fp_line
			(start -1.524 -0.762)
			(end -1.524 0.762)
			(stroke
				(width 0.1524)
				(type default)
			)
			(layer "B.SilkS")
		)
		(fp_line
			(start 1.524 0.762)
			(end 1.524 -0.762)
			(stroke
				(width 0.1524)
				(type default)
			)
			(layer "B.SilkS")
		)
		(fp_line
			(start -1.524 0.762)
			(end 1.524 0.762)
			(stroke
				(width 0.1524)
				(type default)
			)
			(layer "B.SilkS")
		)
		(fp_line
			(start 1.1049 -0.724916)
			(end 1.1049 0.724916)
			(stroke
				(width 0.1)
				(type default)
			)
			(layer "B.Fab")
		)
		(fp_line
			(start -1.1049 -0.724916)
			(end 1.1049 -0.724916)
			(stroke
				(width 0.1)
				(type default)
			)
			(layer "B.Fab")
		)
		(fp_line
			(start 1.1049 0.724916)
			(end -1.1049 0.724916)
			(stroke
				(width 0.1)
				(type default)
			)
			(layer "B.Fab")
		)
		(fp_line
			(start -1.1049 0.724916)
			(end -1.1049 -0.724916)
			(stroke
				(width 0.1)
				(type default)
			)
			(layer "B.Fab")
		)
		(pad "1" smd rect
			(at 0.889 0 90)
			(size 1.016 1.27)
			(layers "B.Cu" "B.Mask" "B.Paste")
			(net "SW_P12V_PVCCFA_EHV_FIVRA_CPU0_R")
		)
		(pad "2" smd rect
			(at -0.889 0 90)
			(size 1.016 1.27)
			(layers "B.Cu" "B.Mask" "B.Paste")
			(net "GND")
		)
	)
	(footprint ""
		(layer "B.Cu")
		(at 55.87492 -344.650314 -90)
		(property "Reference" "PC411_P1_2"
			(at 0 0 90)
			(layer "B.SilkS")
			(hide yes)
			(effects
				(font
					(size 1.27 1.27)
				)
				(justify mirror)
			)
		)
		(property "Value" ""
			(at 0 0 90)
			(layer "B.Fab")
			(effects
				(font
					(size 1.27 1.27)
				)
				(justify mirror)
			)
		)
		(duplicate_pad_numbers_are_jumpers no)
		(fp_line
			(start -1.524 0.762)
			(end 1.524 0.762)
			(stroke
				(width 0.1524)
				(type default)
			)
			(layer "B.SilkS")
		)
		(fp_line
			(start 1.524 0.762)
			(end 1.524 -0.762)
			(stroke
				(width 0.1524)
				(type default)
			)
			(layer "B.SilkS")
		)
		(fp_line
			(start -1.524 -0.762)
			(end -1.524 0.762)
			(stroke
				(width 0.1524)
				(type default)
			)
			(layer "B.SilkS")
		)
		(fp_line
			(start 1.524 -0.762)
			(end -1.524 -0.762)
			(stroke
				(width 0.1524)
				(type default)
			)
			(layer "B.SilkS")
		)
		(fp_line
			(start -1.1049 0.724916)
			(end -1.1049 -0.724916)
			(stroke
				(width 0.1)
				(type default)
			)
			(layer "B.Fab")
		)
		(fp_line
			(start 1.1049 0.724916)
			(end -1.1049 0.724916)
			(stroke
				(width 0.1)
				(type default)
			)
			(layer "B.Fab")
		)
		(fp_line
			(start -1.1049 -0.724916)
			(end 1.1049 -0.724916)
			(stroke
				(width 0.1)
				(type default)
			)
			(layer "B.Fab")
		)
		(fp_line
			(start 1.1049 -0.724916)
			(end 1.1049 0.724916)
			(stroke
				(width 0.1)
				(type default)
			)
			(layer "B.Fab")
		)
		(pad "1" smd rect
			(at 0.889 0 270)
			(size 1.016 1.27)
			(layers "B.Cu" "B.Mask" "B.Paste")
			(net "PVCCFA_EHV_FIVRA_CPU1")
		)
		(pad "2" smd rect
			(at -0.889 0 270)
			(size 1.016 1.27)
			(layers "B.Cu" "B.Mask" "B.Paste")
			(net "GND")
		)
	)
	(footprint ""
		(layer "B.Cu")
		(at 180.155596 -113.77549 180)
		(property "Reference" "C1897"
			(at 0 0 0)
			(layer "B.SilkS")
			(hide yes)
			(effects
				(font
					(size 1.27 1.27)
				)
				(justify mirror)
			)
		)
		(property "Value" ""
			(at 0 0 0)
			(layer "B.Fab")
			(effects
				(font
					(size 1.27 1.27)
				)
				(justify mirror)
			)
		)
		(duplicate_pad_numbers_are_jumpers no)
		(fp_line
			(start 0.69215 0.2921)
			(end 0.69215 -0.2921)
			(stroke
				(width 0.1524)
				(type default)
			)
			(layer "B.SilkS")
		)
		(fp_line
			(start 0.69215 -0.2921)
			(end -0.69215 -0.2921)
			(stroke
				(width 0.1524)
				(type default)
			)
			(layer "B.SilkS")
		)
		(fp_line
			(start -0.69215 0.2921)
			(end 0.69215 0.2921)
			(stroke
				(width 0.1524)
				(type default)
			)
			(layer "B.SilkS")
		)
		(fp_line
			(start -0.69215 -0.2921)
			(end -0.69215 0.2921)
			(stroke
				(width 0.1524)
				(type default)
			)
			(layer "B.SilkS")
		)
		(fp_line
			(start 0.51435 0.2794)
			(end 0.51435 -0.2794)
			(stroke
				(width 0.1)
				(type default)
			)
			(layer "B.Fab")
		)
		(fp_line
			(start 0.51435 -0.2794)
			(end -0.51435 -0.2794)
			(stroke
				(width 0.1)
				(type default)
			)
			(layer "B.Fab")
		)
		(fp_line
			(start -0.51435 0.2794)
			(end 0.51435 0.2794)
			(stroke
				(width 0.1)
				(type default)
			)
			(layer "B.Fab")
		)
		(fp_line
			(start -0.51435 -0.2794)
			(end -0.51435 0.2794)
			(stroke
				(width 0.1)
				(type default)
			)
			(layer "B.Fab")
		)
		(pad "1" smd circle
			(at 0.40005 0)
			(size 0 0)
			(layers "B.Cu" "B.Mask" "B.Paste")
			(net "VCC_PLD_CORE")
		)
		(pad "2" smd circle
			(at -0.40005 0)
			(size 0 0)
			(layers "B.Cu" "B.Mask" "B.Paste")
			(net "GND")
		)
		(zone
			(layer "B.Cu")
			(hatch none 0.5)
			(connect_pads
				(clearance 0)
			)
			(min_thickness 0.25)
			(keepout
				(tracks not_allowed)
				(vias allowed)
				(pads allowed)
				(copperpour not_allowed)
				(footprints allowed)
			)
			(placement
				(enabled no)
				(sheetname "")
			)
			(fill
				(thermal_gap 0.5)
				(thermal_bridge_width 0.5)
				(island_removal_mode 0)
			)
			(polygon
				(pts
					(xy 179.965096 -113.86312) (xy 180.056536 -113.921286) (xy 180.255926 -113.921286) (xy 180.346096 -113.86312)
					(xy 180.346096 -113.68786) (xy 180.255926 -113.62944) (xy 180.056536 -113.62944) (xy 179.965096 -113.687606)
				)
			)
		)
	)
	(footprint ""
		(layer "B.Cu")
		(at 14.407388 -111.004604 90)
		(property "Reference" "C5229"
			(at 0 0 90)
			(layer "B.SilkS")
			(hide yes)
			(effects
				(font
					(size 1.27 1.27)
				)
				(justify mirror)
			)
		)
		(property "Value" ""
			(at 0 0 90)
			(layer "B.Fab")
			(effects
				(font
					(size 1.27 1.27)
				)
				(justify mirror)
			)
		)
		(duplicate_pad_numbers_are_jumpers no)
		(fp_line
			(start 0.7874 -0.4064)
			(end -0.7874 -0.4064)
			(stroke
				(width 0.1524)
				(type default)
			)
			(layer "B.SilkS")
		)
		(fp_line
			(start -0.7874 -0.4064)
			(end -0.7874 0.4064)
			(stroke
				(width 0.1524)
				(type default)
			)
			(layer "B.SilkS")
		)
		(fp_line
			(start 0.7874 0.4064)
			(end 0.7874 -0.4064)
			(stroke
				(width 0.1524)
				(type default)
			)
			(layer "B.SilkS")
		)
		(fp_line
			(start -0.7874 0.4064)
			(end 0.7874 0.4064)
			(stroke
				(width 0.1524)
				(type default)
			)
			(layer "B.SilkS")
		)
		(fp_line
			(start 0.67945 -0.305054)
			(end 0.12065 -0.305054)
			(stroke
				(width 0.1)
				(type default)
			)
			(layer "B.Fab")
		)
		(fp_line
			(start 0.12065 -0.305054)
			(end 0.12065 -0.2794)
			(stroke
				(width 0.1)
				(type default)
			)
			(layer "B.Fab")
		)
		(fp_line
			(start -0.12065 -0.3048)
			(end -0.67945 -0.3048)
			(stroke
				(width 0.1)
				(type default)
			)
			(layer "B.Fab")
		)
		(fp_line
			(start -0.67945 -0.3048)
			(end -0.67945 0.3048)
			(stroke
				(width 0.1)
				(type default)
			)
			(layer "B.Fab")
		)
		(fp_line
			(start 0.12065 -0.2794)
			(end -0.12065 -0.2794)
			(stroke
				(width 0.1)
				(type default)
			)
			(layer "B.Fab")
		)
		(fp_line
			(start -0.12065 -0.2794)
			(end -0.12065 -0.3048)
			(stroke
				(width 0.1)
				(type default)
			)
			(layer "B.Fab")
		)
		(fp_line
			(start 0.12065 0.2794)
			(end 0.12065 0.3048)
			(stroke
				(width 0.1)
				(type default)
			)
			(layer "B.Fab")
		)
		(fp_line
			(start -0.120396 0.2794)
			(end 0.12065 0.2794)
			(stroke
				(width 0.1)
				(type default)
			)
			(layer "B.Fab")
		)
		(fp_line
			(start 0.67945 0.3048)
			(end 0.67945 -0.305054)
			(stroke
				(width 0.1)
				(type default)
			)
			(layer "B.Fab")
		)
		(fp_line
			(start 0.12065 0.3048)
			(end 0.67945 0.3048)
			(stroke
				(width 0.1)
				(type default)
			)
			(layer "B.Fab")
		)
		(fp_line
			(start -0.120396 0.3048)
			(end -0.120396 0.2794)
			(stroke
				(width 0.1)
				(type default)
			)
			(layer "B.Fab")
		)
		(fp_line
			(start -0.67945 0.3048)
			(end -0.120396 0.3048)
			(stroke
				(width 0.1)
				(type default)
			)
			(layer "B.Fab")
		)
		(pad "1" smd circle
			(at 0.40005 0 270)
			(size 0 0)
			(layers "B.Cu" "B.Mask" "B.Paste")
			(net "P3V3_AUX")
		)
		(pad "2" smd circle
			(at -0.40005 0 270)
			(size 0 0)
			(layers "B.Cu" "B.Mask" "B.Paste")
			(net "GND")
		)
	)
	(footprint ""
		(layer "B.Cu")
		(at 328.092816 -26.601674 90)
		(property "Reference" "R1459"
			(at 0 0 90)
			(layer "B.SilkS")
			(hide yes)
			(effects
				(font
					(size 1.27 1.27)
				)
				(justify mirror)
			)
		)
		(property "Value" ""
			(at 0 0 90)
			(layer "B.Fab")
			(effects
				(font
					(size 1.27 1.27)
				)
				(justify mirror)
			)
		)
		(duplicate_pad_numbers_are_jumpers no)
		(fp_line
			(start 0.7874 -0.4064)
			(end -0.7874 -0.4064)
			(stroke
				(width 0.1524)
				(type default)
			)
			(layer "B.SilkS")
		)
		(fp_line
			(start -0.7874 -0.4064)
			(end -0.7874 0.4064)
			(stroke
				(width 0.1524)
				(type default)
			)
			(layer "B.SilkS")
		)
		(fp_line
			(start 0.7874 0.4064)
			(end 0.7874 -0.4064)
			(stroke
				(width 0.1524)
				(type default)
			)
			(layer "B.SilkS")
		)
		(fp_line
			(start -0.7874 0.4064)
			(end 0.7874 0.4064)
			(stroke
				(width 0.1524)
				(type default)
			)
			(layer "B.SilkS")
		)
		(fp_line
			(start 0.67945 -0.305054)
			(end 0.12065 -0.305054)
			(stroke
				(width 0.1)
				(type default)
			)
			(layer "B.Fab")
		)
		(fp_line
			(start 0.12065 -0.305054)
			(end 0.12065 -0.2794)
			(stroke
				(width 0.1)
				(type default)
			)
			(layer "B.Fab")
		)
		(fp_line
			(start -0.12065 -0.3048)
			(end -0.67945 -0.3048)
			(stroke
				(width 0.1)
				(type default)
			)
			(layer "B.Fab")
		)
		(fp_line
			(start -0.67945 -0.3048)
			(end -0.67945 0.3048)
			(stroke
				(width 0.1)
				(type default)
			)
			(layer "B.Fab")
		)
		(fp_line
			(start 0.12065 -0.2794)
			(end -0.12065 -0.2794)
			(stroke
				(width 0.1)
				(type default)
			)
			(layer "B.Fab")
		)
		(fp_line
			(start -0.12065 -0.2794)
			(end -0.12065 -0.3048)
			(stroke
				(width 0.1)
				(type default)
			)
			(layer "B.Fab")
		)
		(fp_line
			(start 0.12065 0.2794)
			(end 0.12065 0.3048)
			(stroke
				(width 0.1)
				(type default)
			)
			(layer "B.Fab")
		)
		(fp_line
			(start -0.120396 0.2794)
			(end 0.12065 0.2794)
			(stroke
				(width 0.1)
				(type default)
			)
			(layer "B.Fab")
		)
		(fp_line
			(start 0.67945 0.3048)
			(end 0.67945 -0.305054)
			(stroke
				(width 0.1)
				(type default)
			)
			(layer "B.Fab")
		)
		(fp_line
			(start 0.12065 0.3048)
			(end 0.67945 0.3048)
			(stroke
				(width 0.1)
				(type default)
			)
			(layer "B.Fab")
		)
		(fp_line
			(start -0.120396 0.3048)
			(end -0.120396 0.2794)
			(stroke
				(width 0.1)
				(type default)
			)
			(layer "B.Fab")
		)
		(fp_line
			(start -0.67945 0.3048)
			(end -0.120396 0.3048)
			(stroke
				(width 0.1)
				(type default)
			)
			(layer "B.Fab")
		)
		(pad "1" smd circle
			(at 0.40005 0 270)
			(size 0 0)
			(layers "B.Cu" "B.Mask" "B.Paste")
			(net "P3V3_AUX")
		)
		(pad "2" smd circle
			(at -0.40005 0 270)
			(size 0 0)
			(layers "B.Cu" "B.Mask" "B.Paste")
			(net "IRQ_PCH_CPU_NMI_EVENT_R_N")
		)
	)
	(footprint ""
		(layer "B.Cu")
		(at 420.682166 -135.146034 180)
		(property "Reference" "PR108"
			(at 0 0 0)
			(layer "B.SilkS")
			(hide yes)
			(effects
				(font
					(size 1.27 1.27)
				)
				(justify mirror)
			)
		)
		(property "Value" ""
			(at 0 0 0)
			(layer "B.Fab")
			(effects
				(font
					(size 1.27 1.27)
				)
				(justify mirror)
			)
		)
		(duplicate_pad_numbers_are_jumpers no)
		(fp_line
			(start 0.7874 0.4064)
			(end 0.7874 -0.4064)
			(stroke
				(width 0.1524)
				(type default)
			)
			(layer "B.SilkS")
		)
		(fp_line
			(start 0.7874 -0.4064)
			(end -0.7874 -0.4064)
			(stroke
				(width 0.1524)
				(type default)
			)
			(layer "B.SilkS")
		)
		(fp_line
			(start -0.7874 0.4064)
			(end 0.7874 0.4064)
			(stroke
				(width 0.1524)
				(type default)
			)
			(layer "B.SilkS")
		)
		(fp_line
			(start -0.7874 -0.4064)
			(end -0.7874 0.4064)
			(stroke
				(width 0.1524)
				(type default)
			)
			(layer "B.SilkS")
		)
		(fp_line
			(start 0.67945 0.3048)
			(end 0.67945 -0.305054)
			(stroke
				(width 0.1)
				(type default)
			)
			(layer "B.Fab")
		)
		(fp_line
			(start 0.67945 -0.305054)
			(end 0.12065 -0.305054)
			(stroke
				(width 0.1)
				(type default)
			)
			(layer "B.Fab")
		)
		(fp_line
			(start 0.12065 0.3048)
			(end 0.67945 0.3048)
			(stroke
				(width 0.1)
				(type default)
			)
			(layer "B.Fab")
		)
		(fp_line
			(start 0.12065 0.2794)
			(end 0.12065 0.3048)
			(stroke
				(width 0.1)
				(type default)
			)
			(layer "B.Fab")
		)
		(fp_line
			(start 0.12065 -0.2794)
			(end -0.12065 -0.2794)
			(stroke
				(width 0.1)
				(type default)
			)
			(layer "B.Fab")
		)
		(fp_line
			(start 0.12065 -0.305054)
			(end 0.12065 -0.2794)
			(stroke
				(width 0.1)
				(type default)
			)
			(layer "B.Fab")
		)
		(fp_line
			(start -0.120396 0.3048)
			(end -0.120396 0.2794)
			(stroke
				(width 0.1)
				(type default)
			)
			(layer "B.Fab")
		)
		(fp_line
			(start -0.120396 0.2794)
			(end 0.12065 0.2794)
			(stroke
				(width 0.1)
				(type default)
			)
			(layer "B.Fab")
		)
		(fp_line
			(start -0.12065 -0.2794)
			(end -0.12065 -0.3048)
			(stroke
				(width 0.1)
				(type default)
			)
			(layer "B.Fab")
		)
		(fp_line
			(start -0.12065 -0.3048)
			(end -0.67945 -0.3048)
			(stroke
				(width 0.1)
				(type default)
			)
			(layer "B.Fab")
		)
		(fp_line
			(start -0.67945 0.3048)
			(end -0.120396 0.3048)
			(stroke
				(width 0.1)
				(type default)
			)
			(layer "B.Fab")
		)
		(fp_line
			(start -0.67945 -0.3048)
			(end -0.67945 0.3048)
			(stroke
				(width 0.1)
				(type default)
			)
			(layer "B.Fab")
		)
		(pad "1" smd circle
			(at 0.40005 0)
			(size 0 0)
			(layers "B.Cu" "B.Mask" "B.Paste")
			(net "P12V_AUX")
		)
		(pad "2" smd circle
			(at -0.40005 0)
			(size 0 0)
			(layers "B.Cu" "B.Mask" "B.Paste")
			(net "PVCCINFAON_CPU0_VIN_CSNIN")
		)
	)
	(footprint ""
		(layer "B.Cu")
		(at 369.756436 -354.93833 -90)
		(property "Reference" "R2406"
			(at 0 0 90)
			(layer "B.SilkS")
			(hide yes)
			(effects
				(font
					(size 1.27 1.27)
				)
				(justify mirror)
			)
		)
		(property "Value" ""
			(at 0 0 90)
			(layer "B.Fab")
			(effects
				(font
					(size 1.27 1.27)
				)
				(justify mirror)
			)
		)
		(duplicate_pad_numbers_are_jumpers no)
		(fp_line
			(start -0.7874 0.4064)
			(end 0.7874 0.4064)
			(stroke
				(width 0.1524)
				(type default)
			)
			(layer "B.SilkS")
		)
		(fp_line
			(start 0.7874 0.4064)
			(end 0.7874 -0.4064)
			(stroke
				(width 0.1524)
				(type default)
			)
			(layer "B.SilkS")
		)
		(fp_line
			(start -0.7874 -0.4064)
			(end -0.7874 0.4064)
			(stroke
				(width 0.1524)
				(type default)
			)
			(layer "B.SilkS")
		)
		(fp_line
			(start 0.7874 -0.4064)
			(end -0.7874 -0.4064)
			(stroke
				(width 0.1524)
				(type default)
			)
			(layer "B.SilkS")
		)
		(fp_line
			(start -0.67945 0.3048)
			(end -0.120396 0.3048)
			(stroke
				(width 0.1)
				(type default)
			)
			(layer "B.Fab")
		)
		(fp_line
			(start -0.120396 0.3048)
			(end -0.120396 0.2794)
			(stroke
				(width 0.1)
				(type default)
			)
			(layer "B.Fab")
		)
		(fp_line
			(start 0.12065 0.3048)
			(end 0.67945 0.3048)
			(stroke
				(width 0.1)
				(type default)
			)
			(layer "B.Fab")
		)
		(fp_line
			(start 0.67945 0.3048)
			(end 0.67945 -0.305054)
			(stroke
				(width 0.1)
				(type default)
			)
			(layer "B.Fab")
		)
		(fp_line
			(start -0.120396 0.2794)
			(end 0.12065 0.2794)
			(stroke
				(width 0.1)
				(type default)
			)
			(layer "B.Fab")
		)
		(fp_line
			(start 0.12065 0.2794)
			(end 0.12065 0.3048)
			(stroke
				(width 0.1)
				(type default)
			)
			(layer "B.Fab")
		)
		(fp_line
			(start -0.12065 -0.2794)
			(end -0.12065 -0.3048)
			(stroke
				(width 0.1)
				(type default)
			)
			(layer "B.Fab")
		)
		(fp_line
			(start 0.12065 -0.2794)
			(end -0.12065 -0.2794)
			(stroke
				(width 0.1)
				(type default)
			)
			(layer "B.Fab")
		)
		(fp_line
			(start -0.67945 -0.3048)
			(end -0.67945 0.3048)
			(stroke
				(width 0.1)
				(type default)
			)
			(layer "B.Fab")
		)
		(fp_line
			(start -0.12065 -0.3048)
			(end -0.67945 -0.3048)
			(stroke
				(width 0.1)
				(type default)
			)
			(layer "B.Fab")
		)
		(fp_line
			(start 0.12065 -0.305054)
			(end 0.12065 -0.2794)
			(stroke
				(width 0.1)
				(type default)
			)
			(layer "B.Fab")
		)
		(fp_line
			(start 0.67945 -0.305054)
			(end 0.12065 -0.305054)
			(stroke
				(width 0.1)
				(type default)
			)
			(layer "B.Fab")
		)
		(pad "1" smd circle
			(at 0.40005 0 90)
			(size 0 0)
			(layers "B.Cu" "B.Mask" "B.Paste")
			(net "P3V3_AUX")
		)
		(pad "2" smd circle
			(at -0.40005 0 90)
			(size 0 0)
			(layers "B.Cu" "B.Mask" "B.Paste")
			(net "FM_PVPP_HBM_CPU0_EN")
		)
	)
	(footprint ""
		(layer "B.Cu")
		(at 168.83888 -102.707948)
		(property "Reference" "C1938"
			(at 0 0 0)
			(layer "B.SilkS")
			(hide yes)
			(effects
				(font
					(size 1.27 1.27)
				)
				(justify mirror)
			)
		)
		(property "Value" ""
			(at 0 0 0)
			(layer "B.Fab")
			(effects
				(font
					(size 1.27 1.27)
				)
				(justify mirror)
			)
		)
		(duplicate_pad_numbers_are_jumpers no)
		(fp_line
			(start -0.7874 -0.4064)
			(end -0.7874 0.4064)
			(stroke
				(width 0.1524)
				(type default)
			)
			(layer "B.SilkS")
		)
		(fp_line
			(start -0.7874 0.4064)
			(end 0.7874 0.4064)
			(stroke
				(width 0.1524)
				(type default)
			)
			(layer "B.SilkS")
		)
		(fp_line
			(start 0.7874 -0.4064)
			(end -0.7874 -0.4064)
			(stroke
				(width 0.1524)
				(type default)
			)
			(layer "B.SilkS")
		)
		(fp_line
			(start 0.7874 0.4064)
			(end 0.7874 -0.4064)
			(stroke
				(width 0.1524)
				(type default)
			)
			(layer "B.SilkS")
		)
		(fp_line
			(start -0.67945 -0.3048)
			(end -0.67945 0.3048)
			(stroke
				(width 0.1)
				(type default)
			)
			(layer "B.Fab")
		)
		(fp_line
			(start -0.67945 0.3048)
			(end -0.120396 0.3048)
			(stroke
				(width 0.1)
				(type default)
			)
			(layer "B.Fab")
		)
		(fp_line
			(start -0.12065 -0.3048)
			(end -0.67945 -0.3048)
			(stroke
				(width 0.1)
				(type default)
			)
			(layer "B.Fab")
		)
		(fp_line
			(start -0.12065 -0.2794)
			(end -0.12065 -0.3048)
			(stroke
				(width 0.1)
				(type default)
			)
			(layer "B.Fab")
		)
		(fp_line
			(start -0.120396 0.2794)
			(end 0.12065 0.2794)
			(stroke
				(width 0.1)
				(type default)
			)
			(layer "B.Fab")
		)
		(fp_line
			(start -0.120396 0.3048)
			(end -0.120396 0.2794)
			(stroke
				(width 0.1)
				(type default)
			)
			(layer "B.Fab")
		)
		(fp_line
			(start 0.12065 -0.305054)
			(end 0.12065 -0.2794)
			(stroke
				(width 0.1)
				(type default)
			)
			(layer "B.Fab")
		)
		(fp_line
			(start 0.12065 -0.2794)
			(end -0.12065 -0.2794)
			(stroke
				(width 0.1)
				(type default)
			)
			(layer "B.Fab")
		)
		(fp_line
			(start 0.12065 0.2794)
			(end 0.12065 0.3048)
			(stroke
				(width 0.1)
				(type default)
			)
			(layer "B.Fab")
		)
		(fp_line
			(start 0.12065 0.3048)
			(end 0.67945 0.3048)
			(stroke
				(width 0.1)
				(type default)
			)
			(layer "B.Fab")
		)
		(fp_line
			(start 0.67945 -0.305054)
			(end 0.12065 -0.305054)
			(stroke
				(width 0.1)
				(type default)
			)
			(layer "B.Fab")
		)
		(fp_line
			(start 0.67945 0.3048)
			(end 0.67945 -0.305054)
			(stroke
				(width 0.1)
				(type default)
			)
			(layer "B.Fab")
		)
		(pad "1" smd circle
			(at 0.40005 0 180)
			(size 0 0)
			(layers "B.Cu" "B.Mask" "B.Paste")
			(net "P3V3_AUX_FPGA_VCCIO0")
		)
		(pad "2" smd circle
			(at -0.40005 0 180)
			(size 0 0)
			(layers "B.Cu" "B.Mask" "B.Paste")
			(net "GND")
		)
	)
	(footprint ""
		(layer "B.Cu")
		(at 342.453214 -52.202334 -90)
		(property "Reference" "C1257"
			(at 0 0 90)
			(layer "B.SilkS")
			(hide yes)
			(effects
				(font
					(size 1.27 1.27)
				)
				(justify mirror)
			)
		)
		(property "Value" ""
			(at 0 0 90)
			(layer "B.Fab")
			(effects
				(font
					(size 1.27 1.27)
				)
				(justify mirror)
			)
		)
		(duplicate_pad_numbers_are_jumpers no)
		(fp_line
			(start -0.7874 0.4064)
			(end 0.7874 0.4064)
			(stroke
				(width 0.1524)
				(type default)
			)
			(layer "B.SilkS")
		)
		(fp_line
			(start 0.7874 0.4064)
			(end 0.7874 -0.4064)
			(stroke
				(width 0.1524)
				(type default)
			)
			(layer "B.SilkS")
		)
		(fp_line
			(start -0.7874 -0.4064)
			(end -0.7874 0.4064)
			(stroke
				(width 0.1524)
				(type default)
			)
			(layer "B.SilkS")
		)
		(fp_line
			(start 0.7874 -0.4064)
			(end -0.7874 -0.4064)
			(stroke
				(width 0.1524)
				(type default)
			)
			(layer "B.SilkS")
		)
		(fp_line
			(start -0.67945 0.3048)
			(end -0.120396 0.3048)
			(stroke
				(width 0.1)
				(type default)
			)
			(layer "B.Fab")
		)
		(fp_line
			(start -0.120396 0.3048)
			(end -0.120396 0.2794)
			(stroke
				(width 0.1)
				(type default)
			)
			(layer "B.Fab")
		)
		(fp_line
			(start 0.12065 0.3048)
			(end 0.67945 0.3048)
			(stroke
				(width 0.1)
				(type default)
			)
			(layer "B.Fab")
		)
		(fp_line
			(start 0.67945 0.3048)
			(end 0.67945 -0.305054)
			(stroke
				(width 0.1)
				(type default)
			)
			(layer "B.Fab")
		)
		(fp_line
			(start -0.120396 0.2794)
			(end 0.12065 0.2794)
			(stroke
				(width 0.1)
				(type default)
			)
			(layer "B.Fab")
		)
		(fp_line
			(start 0.12065 0.2794)
			(end 0.12065 0.3048)
			(stroke
				(width 0.1)
				(type default)
			)
			(layer "B.Fab")
		)
		(fp_line
			(start -0.12065 -0.2794)
			(end -0.12065 -0.3048)
			(stroke
				(width 0.1)
				(type default)
			)
			(layer "B.Fab")
		)
		(fp_line
			(start 0.12065 -0.2794)
			(end -0.12065 -0.2794)
			(stroke
				(width 0.1)
				(type default)
			)
			(layer "B.Fab")
		)
		(fp_line
			(start -0.67945 -0.3048)
			(end -0.67945 0.3048)
			(stroke
				(width 0.1)
				(type default)
			)
			(layer "B.Fab")
		)
		(fp_line
			(start -0.12065 -0.3048)
			(end -0.67945 -0.3048)
			(stroke
				(width 0.1)
				(type default)
			)
			(layer "B.Fab")
		)
		(fp_line
			(start 0.12065 -0.305054)
			(end 0.12065 -0.2794)
			(stroke
				(width 0.1)
				(type default)
			)
			(layer "B.Fab")
		)
		(fp_line
			(start 0.67945 -0.305054)
			(end 0.12065 -0.305054)
			(stroke
				(width 0.1)
				(type default)
			)
			(layer "B.Fab")
		)
		(pad "1" smd circle
			(at 0.40005 0 90)
			(size 0 0)
			(layers "B.Cu" "B.Mask" "B.Paste")
			(net "P1V8_PCH_PLL_AUX")
		)
		(pad "2" smd circle
			(at -0.40005 0 90)
			(size 0 0)
			(layers "B.Cu" "B.Mask" "B.Paste")
			(net "GND")
		)
	)
	(footprint ""
		(layer "B.Cu")
		(at 204.088746 -321.554856 -90)
		(property "Reference" "C74"
			(at 0 0 90)
			(layer "B.SilkS")
			(hide yes)
			(effects
				(font
					(size 1.27 1.27)
				)
				(justify mirror)
			)
		)
		(property "Value" ""
			(at 0 0 90)
			(layer "B.Fab")
			(effects
				(font
					(size 1.27 1.27)
				)
				(justify mirror)
			)
		)
		(duplicate_pad_numbers_are_jumpers no)
		(fp_line
			(start -1.524 0.762)
			(end 1.524 0.762)
			(stroke
				(width 0.1524)
				(type default)
			)
			(layer "B.SilkS")
		)
		(fp_line
			(start 1.524 0.762)
			(end 1.524 -0.762)
			(stroke
				(width 0.1524)
				(type default)
			)
			(layer "B.SilkS")
		)
		(fp_line
			(start -1.524 -0.762)
			(end -1.524 0.762)
			(stroke
				(width 0.1524)
				(type default)
			)
			(layer "B.SilkS")
		)
		(fp_line
			(start 1.524 -0.762)
			(end -1.524 -0.762)
			(stroke
				(width 0.1524)
				(type default)
			)
			(layer "B.SilkS")
		)
		(fp_line
			(start -1.1049 0.724916)
			(end -1.1049 -0.724916)
			(stroke
				(width 0.1)
				(type default)
			)
			(layer "B.Fab")
		)
		(fp_line
			(start 1.1049 0.724916)
			(end -1.1049 0.724916)
			(stroke
				(width 0.1)
				(type default)
			)
			(layer "B.Fab")
		)
		(fp_line
			(start -1.1049 -0.724916)
			(end 1.1049 -0.724916)
			(stroke
				(width 0.1)
				(type default)
			)
			(layer "B.Fab")
		)
		(fp_line
			(start 1.1049 -0.724916)
			(end 1.1049 0.724916)
			(stroke
				(width 0.1)
				(type default)
			)
			(layer "B.Fab")
		)
		(pad "1" smd rect
			(at 0.889 0 270)
			(size 1.016 1.27)
			(layers "B.Cu" "B.Mask" "B.Paste")
			(net "P12V_S3_AUX_CPU1_NVDIMM")
		)
		(pad "2" smd rect
			(at -0.889 0 270)
			(size 1.016 1.27)
			(layers "B.Cu" "B.Mask" "B.Paste")
			(net "GND")
		)
	)
	(footprint ""
		(layer "B.Cu")
		(at 433.61864 -52.2478 -90)
		(property "Reference" "R1655"
			(at 0 0 90)
			(layer "B.SilkS")
			(hide yes)
			(effects
				(font
					(size 1.27 1.27)
				)
				(justify mirror)
			)
		)
		(property "Value" ""
			(at 0 0 90)
			(layer "B.Fab")
			(effects
				(font
					(size 1.27 1.27)
				)
				(justify mirror)
			)
		)
		(duplicate_pad_numbers_are_jumpers no)
		(fp_line
			(start -0.7874 0.4064)
			(end 0.7874 0.4064)
			(stroke
				(width 0.1524)
				(type default)
			)
			(layer "B.SilkS")
		)
		(fp_line
			(start 0.7874 0.4064)
			(end 0.7874 -0.4064)
			(stroke
				(width 0.1524)
				(type default)
			)
			(layer "B.SilkS")
		)
		(fp_line
			(start -0.7874 -0.4064)
			(end -0.7874 0.4064)
			(stroke
				(width 0.1524)
				(type default)
			)
			(layer "B.SilkS")
		)
		(fp_line
			(start 0.7874 -0.4064)
			(end -0.7874 -0.4064)
			(stroke
				(width 0.1524)
				(type default)
			)
			(layer "B.SilkS")
		)
		(fp_line
			(start -0.67945 0.3048)
			(end -0.120396 0.3048)
			(stroke
				(width 0.1)
				(type default)
			)
			(layer "B.Fab")
		)
		(fp_line
			(start -0.120396 0.3048)
			(end -0.120396 0.2794)
			(stroke
				(width 0.1)
				(type default)
			)
			(layer "B.Fab")
		)
		(fp_line
			(start 0.12065 0.3048)
			(end 0.67945 0.3048)
			(stroke
				(width 0.1)
				(type default)
			)
			(layer "B.Fab")
		)
		(fp_line
			(start 0.67945 0.3048)
			(end 0.67945 -0.305054)
			(stroke
				(width 0.1)
				(type default)
			)
			(layer "B.Fab")
		)
		(fp_line
			(start -0.120396 0.2794)
			(end 0.12065 0.2794)
			(stroke
				(width 0.1)
				(type default)
			)
			(layer "B.Fab")
		)
		(fp_line
			(start 0.12065 0.2794)
			(end 0.12065 0.3048)
			(stroke
				(width 0.1)
				(type default)
			)
			(layer "B.Fab")
		)
		(fp_line
			(start -0.12065 -0.2794)
			(end -0.12065 -0.3048)
			(stroke
				(width 0.1)
				(type default)
			)
			(layer "B.Fab")
		)
		(fp_line
			(start 0.12065 -0.2794)
			(end -0.12065 -0.2794)
			(stroke
				(width 0.1)
				(type default)
			)
			(layer "B.Fab")
		)
		(fp_line
			(start -0.67945 -0.3048)
			(end -0.67945 0.3048)
			(stroke
				(width 0.1)
				(type default)
			)
			(layer "B.Fab")
		)
		(fp_line
			(start -0.12065 -0.3048)
			(end -0.67945 -0.3048)
			(stroke
				(width 0.1)
				(type default)
			)
			(layer "B.Fab")
		)
		(fp_line
			(start 0.12065 -0.305054)
			(end 0.12065 -0.2794)
			(stroke
				(width 0.1)
				(type default)
			)
			(layer "B.Fab")
		)
		(fp_line
			(start 0.67945 -0.305054)
			(end 0.12065 -0.305054)
			(stroke
				(width 0.1)
				(type default)
			)
			(layer "B.Fab")
		)
		(pad "1" smd circle
			(at 0.40005 0 90)
			(size 0 0)
			(layers "B.Cu" "B.Mask" "B.Paste")
			(net "P12V_AUX")
		)
		(pad "2" smd circle
			(at -0.40005 0 90)
			(size 0 0)
			(layers "B.Cu" "B.Mask" "B.Paste")
			(net "PWRGD_P5V_ISO_R")
		)
	)
	(footprint ""
		(layer "B.Cu")
		(at 178.9557 -114.17554 -90)
		(property "Reference" "C1919"
			(at 0 0 90)
			(layer "B.SilkS")
			(hide yes)
			(effects
				(font
					(size 1.27 1.27)
				)
				(justify mirror)
			)
		)
		(property "Value" ""
			(at 0 0 90)
			(layer "B.Fab")
			(effects
				(font
					(size 1.27 1.27)
				)
				(justify mirror)
			)
		)
		(duplicate_pad_numbers_are_jumpers no)
		(fp_line
			(start -0.69215 0.2921)
			(end 0.69215 0.2921)
			(stroke
				(width 0.1524)
				(type default)
			)
			(layer "B.SilkS")
		)
		(fp_line
			(start 0.69215 0.2921)
			(end 0.69215 -0.2921)
			(stroke
				(width 0.1524)
				(type default)
			)
			(layer "B.SilkS")
		)
		(fp_line
			(start -0.69215 -0.2921)
			(end -0.69215 0.2921)
			(stroke
				(width 0.1524)
				(type default)
			)
			(layer "B.SilkS")
		)
		(fp_line
			(start 0.69215 -0.2921)
			(end -0.69215 -0.2921)
			(stroke
				(width 0.1524)
				(type default)
			)
			(layer "B.SilkS")
		)
		(fp_line
			(start -0.51435 0.2794)
			(end 0.51435 0.2794)
			(stroke
				(width 0.1)
				(type default)
			)
			(layer "B.Fab")
		)
		(fp_line
			(start 0.51435 0.2794)
			(end 0.51435 -0.2794)
			(stroke
				(width 0.1)
				(type default)
			)
			(layer "B.Fab")
		)
		(fp_line
			(start -0.51435 -0.2794)
			(end -0.51435 0.2794)
			(stroke
				(width 0.1)
				(type default)
			)
			(layer "B.Fab")
		)
		(fp_line
			(start 0.51435 -0.2794)
			(end -0.51435 -0.2794)
			(stroke
				(width 0.1)
				(type default)
			)
			(layer "B.Fab")
		)
		(pad "1" smd circle
			(at 0.40005 0 90)
			(size 0 0)
			(layers "B.Cu" "B.Mask" "B.Paste")
			(net "VCC_PLD_CORE")
		)
		(pad "2" smd circle
			(at -0.40005 0 90)
			(size 0 0)
			(layers "B.Cu" "B.Mask" "B.Paste")
			(net "GND")
		)
		(zone
			(layer "B.Cu")
			(hatch none 0.5)
			(connect_pads
				(clearance 0)
			)
			(min_thickness 0.25)
			(keepout
				(tracks not_allowed)
				(vias allowed)
				(pads allowed)
				(copperpour not_allowed)
				(footprints allowed)
			)
			(placement
				(enabled no)
				(sheetname "")
			)
			(fill
				(thermal_gap 0.5)
				(thermal_bridge_width 0.5)
				(island_removal_mode 0)
			)
			(polygon
				(pts
					(xy 178.86807 -113.98504) (xy 178.809904 -114.07648) (xy 178.809904 -114.27587) (xy 178.86807 -114.36604)
					(xy 179.04333 -114.36604) (xy 179.10175 -114.27587) (xy 179.10175 -114.07648) (xy 179.043584 -113.98504)
				)
			)
		)
	)
	(footprint ""
		(layer "B.Cu")
		(at 307.984398 -190.45047 90)
		(property "Reference" "R556"
			(at 0 0 90)
			(layer "B.SilkS")
			(hide yes)
			(effects
				(font
					(size 1.27 1.27)
				)
				(justify mirror)
			)
		)
		(property "Value" ""
			(at 0 0 90)
			(layer "B.Fab")
			(effects
				(font
					(size 1.27 1.27)
				)
				(justify mirror)
			)
		)
		(duplicate_pad_numbers_are_jumpers no)
		(fp_line
			(start 0.7874 -0.4064)
			(end -0.7874 -0.4064)
			(stroke
				(width 0.1524)
				(type default)
			)
			(layer "B.SilkS")
		)
		(fp_line
			(start -0.7874 -0.4064)
			(end -0.7874 0.4064)
			(stroke
				(width 0.1524)
				(type default)
			)
			(layer "B.SilkS")
		)
		(fp_line
			(start 0.7874 0.4064)
			(end 0.7874 -0.4064)
			(stroke
				(width 0.1524)
				(type default)
			)
			(layer "B.SilkS")
		)
		(fp_line
			(start -0.7874 0.4064)
			(end 0.7874 0.4064)
			(stroke
				(width 0.1524)
				(type default)
			)
			(layer "B.SilkS")
		)
		(fp_line
			(start 0.67945 -0.305054)
			(end 0.12065 -0.305054)
			(stroke
				(width 0.1)
				(type default)
			)
			(layer "B.Fab")
		)
		(fp_line
			(start 0.12065 -0.305054)
			(end 0.12065 -0.2794)
			(stroke
				(width 0.1)
				(type default)
			)
			(layer "B.Fab")
		)
		(fp_line
			(start -0.12065 -0.3048)
			(end -0.67945 -0.3048)
			(stroke
				(width 0.1)
				(type default)
			)
			(layer "B.Fab")
		)
		(fp_line
			(start -0.67945 -0.3048)
			(end -0.67945 0.3048)
			(stroke
				(width 0.1)
				(type default)
			)
			(layer "B.Fab")
		)
		(fp_line
			(start 0.12065 -0.2794)
			(end -0.12065 -0.2794)
			(stroke
				(width 0.1)
				(type default)
			)
			(layer "B.Fab")
		)
		(fp_line
			(start -0.12065 -0.2794)
			(end -0.12065 -0.3048)
			(stroke
				(width 0.1)
				(type default)
			)
			(layer "B.Fab")
		)
		(fp_line
			(start 0.12065 0.2794)
			(end 0.12065 0.3048)
			(stroke
				(width 0.1)
				(type default)
			)
			(layer "B.Fab")
		)
		(fp_line
			(start -0.120396 0.2794)
			(end 0.12065 0.2794)
			(stroke
				(width 0.1)
				(type default)
			)
			(layer "B.Fab")
		)
		(fp_line
			(start 0.67945 0.3048)
			(end 0.67945 -0.305054)
			(stroke
				(width 0.1)
				(type default)
			)
			(layer "B.Fab")
		)
		(fp_line
			(start 0.12065 0.3048)
			(end 0.67945 0.3048)
			(stroke
				(width 0.1)
				(type default)
			)
			(layer "B.Fab")
		)
		(fp_line
			(start -0.120396 0.3048)
			(end -0.120396 0.2794)
			(stroke
				(width 0.1)
				(type default)
			)
			(layer "B.Fab")
		)
		(fp_line
			(start -0.67945 0.3048)
			(end -0.120396 0.3048)
			(stroke
				(width 0.1)
				(type default)
			)
			(layer "B.Fab")
		)
		(pad "1" smd circle
			(at 0.40005 0 270)
			(size 0 0)
			(layers "B.Cu" "B.Mask" "B.Paste")
			(net "SVID_ALERT1_CPU0_R_N")
		)
		(pad "2" smd circle
			(at -0.40005 0 270)
			(size 0 0)
			(layers "B.Cu" "B.Mask" "B.Paste")
			(net "PVNN_TERM_CPU0")
		)
	)
	(footprint ""
		(layer "B.Cu")
		(at 175.355758 -112.97539 180)
		(property "Reference" "C1917"
			(at 0 0 0)
			(layer "B.SilkS")
			(hide yes)
			(effects
				(font
					(size 1.27 1.27)
				)
				(justify mirror)
			)
		)
		(property "Value" ""
			(at 0 0 0)
			(layer "B.Fab")
			(effects
				(font
					(size 1.27 1.27)
				)
				(justify mirror)
			)
		)
		(duplicate_pad_numbers_are_jumpers no)
		(fp_line
			(start 0.69215 0.2921)
			(end 0.69215 -0.2921)
			(stroke
				(width 0.1524)
				(type default)
			)
			(layer "B.SilkS")
		)
		(fp_line
			(start 0.69215 -0.2921)
			(end -0.69215 -0.2921)
			(stroke
				(width 0.1524)
				(type default)
			)
			(layer "B.SilkS")
		)
		(fp_line
			(start -0.69215 0.2921)
			(end 0.69215 0.2921)
			(stroke
				(width 0.1524)
				(type default)
			)
			(layer "B.SilkS")
		)
		(fp_line
			(start -0.69215 -0.2921)
			(end -0.69215 0.2921)
			(stroke
				(width 0.1524)
				(type default)
			)
			(layer "B.SilkS")
		)
		(fp_line
			(start 0.51435 0.2794)
			(end 0.51435 -0.2794)
			(stroke
				(width 0.1)
				(type default)
			)
			(layer "B.Fab")
		)
		(fp_line
			(start 0.51435 -0.2794)
			(end -0.51435 -0.2794)
			(stroke
				(width 0.1)
				(type default)
			)
			(layer "B.Fab")
		)
		(fp_line
			(start -0.51435 0.2794)
			(end 0.51435 0.2794)
			(stroke
				(width 0.1)
				(type default)
			)
			(layer "B.Fab")
		)
		(fp_line
			(start -0.51435 -0.2794)
			(end -0.51435 0.2794)
			(stroke
				(width 0.1)
				(type default)
			)
			(layer "B.Fab")
		)
		(pad "1" smd circle
			(at 0.40005 0)
			(size 0 0)
			(layers "B.Cu" "B.Mask" "B.Paste")
			(net "P3V3_AUX_FPGA_VCCIO0")
		)
		(pad "2" smd circle
			(at -0.40005 0)
			(size 0 0)
			(layers "B.Cu" "B.Mask" "B.Paste")
			(net "GND")
		)
		(zone
			(layer "B.Cu")
			(hatch none 0.5)
			(connect_pads
				(clearance 0)
			)
			(min_thickness 0.25)
			(keepout
				(tracks not_allowed)
				(vias allowed)
				(pads allowed)
				(copperpour not_allowed)
				(footprints allowed)
			)
			(placement
				(enabled no)
				(sheetname "")
			)
			(fill
				(thermal_gap 0.5)
				(thermal_bridge_width 0.5)
				(island_removal_mode 0)
			)
			(polygon
				(pts
					(xy 175.165258 -113.06302) (xy 175.256698 -113.121186) (xy 175.456088 -113.121186) (xy 175.546258 -113.06302)
					(xy 175.546258 -112.88776) (xy 175.456088 -112.82934) (xy 175.256698 -112.82934) (xy 175.165258 -112.887506)
				)
			)
		)
	)
	(footprint ""
		(layer "B.Cu")
		(at 263.637014 -321.549776 -90)
		(property "Reference" "C25"
			(at 0 0 90)
			(layer "B.SilkS")
			(hide yes)
			(effects
				(font
					(size 1.27 1.27)
				)
				(justify mirror)
			)
		)
		(property "Value" ""
			(at 0 0 90)
			(layer "B.Fab")
			(effects
				(font
					(size 1.27 1.27)
				)
				(justify mirror)
			)
		)
		(duplicate_pad_numbers_are_jumpers no)
		(fp_line
			(start -1.524 0.762)
			(end 1.524 0.762)
			(stroke
				(width 0.1524)
				(type default)
			)
			(layer "B.SilkS")
		)
		(fp_line
			(start 1.524 0.762)
			(end 1.524 -0.762)
			(stroke
				(width 0.1524)
				(type default)
			)
			(layer "B.SilkS")
		)
		(fp_line
			(start -1.524 -0.762)
			(end -1.524 0.762)
			(stroke
				(width 0.1524)
				(type default)
			)
			(layer "B.SilkS")
		)
		(fp_line
			(start 1.524 -0.762)
			(end -1.524 -0.762)
			(stroke
				(width 0.1524)
				(type default)
			)
			(layer "B.SilkS")
		)
		(fp_line
			(start -1.1049 0.724916)
			(end -1.1049 -0.724916)
			(stroke
				(width 0.1)
				(type default)
			)
			(layer "B.Fab")
		)
		(fp_line
			(start 1.1049 0.724916)
			(end -1.1049 0.724916)
			(stroke
				(width 0.1)
				(type default)
			)
			(layer "B.Fab")
		)
		(fp_line
			(start -1.1049 -0.724916)
			(end 1.1049 -0.724916)
			(stroke
				(width 0.1)
				(type default)
			)
			(layer "B.Fab")
		)
		(fp_line
			(start 1.1049 -0.724916)
			(end 1.1049 0.724916)
			(stroke
				(width 0.1)
				(type default)
			)
			(layer "B.Fab")
		)
		(pad "1" smd rect
			(at 0.889 0 270)
			(size 1.016 1.27)
			(layers "B.Cu" "B.Mask" "B.Paste")
			(net "P12V_S3_AUX_CPU0_NVDIMM")
		)
		(pad "2" smd rect
			(at -0.889 0 270)
			(size 1.016 1.27)
			(layers "B.Cu" "B.Mask" "B.Paste")
			(net "GND")
		)
	)
	(footprint ""
		(layer "B.Cu")
		(at 185.755788 -116.975382 180)
		(property "Reference" "C1894"
			(at 0 0 0)
			(layer "B.SilkS")
			(hide yes)
			(effects
				(font
					(size 1.27 1.27)
				)
				(justify mirror)
			)
		)
		(property "Value" ""
			(at 0 0 0)
			(layer "B.Fab")
			(effects
				(font
					(size 1.27 1.27)
				)
				(justify mirror)
			)
		)
		(duplicate_pad_numbers_are_jumpers no)
		(fp_line
			(start 0.69215 0.2921)
			(end 0.69215 -0.2921)
			(stroke
				(width 0.1524)
				(type default)
			)
			(layer "B.SilkS")
		)
		(fp_line
			(start 0.69215 -0.2921)
			(end -0.69215 -0.2921)
			(stroke
				(width 0.1524)
				(type default)
			)
			(layer "B.SilkS")
		)
		(fp_line
			(start -0.69215 0.2921)
			(end 0.69215 0.2921)
			(stroke
				(width 0.1524)
				(type default)
			)
			(layer "B.SilkS")
		)
		(fp_line
			(start -0.69215 -0.2921)
			(end -0.69215 0.2921)
			(stroke
				(width 0.1524)
				(type default)
			)
			(layer "B.SilkS")
		)
		(fp_line
			(start 0.51435 0.2794)
			(end 0.51435 -0.2794)
			(stroke
				(width 0.1)
				(type default)
			)
			(layer "B.Fab")
		)
		(fp_line
			(start 0.51435 -0.2794)
			(end -0.51435 -0.2794)
			(stroke
				(width 0.1)
				(type default)
			)
			(layer "B.Fab")
		)
		(fp_line
			(start -0.51435 0.2794)
			(end 0.51435 0.2794)
			(stroke
				(width 0.1)
				(type default)
			)
			(layer "B.Fab")
		)
		(fp_line
			(start -0.51435 -0.2794)
			(end -0.51435 0.2794)
			(stroke
				(width 0.1)
				(type default)
			)
			(layer "B.Fab")
		)
		(pad "1" smd circle
			(at 0.40005 0)
			(size 0 0)
			(layers "B.Cu" "B.Mask" "B.Paste")
			(net "P3V3_AUX_FPGA_VCCIO2")
		)
		(pad "2" smd circle
			(at -0.40005 0)
			(size 0 0)
			(layers "B.Cu" "B.Mask" "B.Paste")
			(net "GND")
		)
		(zone
			(layer "B.Cu")
			(hatch none 0.5)
			(connect_pads
				(clearance 0)
			)
			(min_thickness 0.25)
			(keepout
				(tracks not_allowed)
				(vias allowed)
				(pads allowed)
				(copperpour not_allowed)
				(footprints allowed)
			)
			(placement
				(enabled no)
				(sheetname "")
			)
			(fill
				(thermal_gap 0.5)
				(thermal_bridge_width 0.5)
				(island_removal_mode 0)
			)
			(polygon
				(pts
					(xy 185.565288 -117.063012) (xy 185.656728 -117.121178) (xy 185.856118 -117.121178) (xy 185.946288 -117.063012)
					(xy 185.946288 -116.887752) (xy 185.856118 -116.829332) (xy 185.656728 -116.829332) (xy 185.565288 -116.887498)
				)
			)
		)
	)
	(footprint ""
		(layer "B.Cu")
		(at 371.665246 -354.93833 90)
		(property "Reference" "C1300"
			(at 0 0 90)
			(layer "B.SilkS")
			(hide yes)
			(effects
				(font
					(size 1.27 1.27)
				)
				(justify mirror)
			)
		)
		(property "Value" ""
			(at 0 0 90)
			(layer "B.Fab")
			(effects
				(font
					(size 1.27 1.27)
				)
				(justify mirror)
			)
		)
		(duplicate_pad_numbers_are_jumpers no)
		(fp_line
			(start 0.7874 -0.4064)
			(end -0.7874 -0.4064)
			(stroke
				(width 0.1524)
				(type default)
			)
			(layer "B.SilkS")
		)
		(fp_line
			(start -0.7874 -0.4064)
			(end -0.7874 0.4064)
			(stroke
				(width 0.1524)
				(type default)
			)
			(layer "B.SilkS")
		)
		(fp_line
			(start 0.7874 0.4064)
			(end 0.7874 -0.4064)
			(stroke
				(width 0.1524)
				(type default)
			)
			(layer "B.SilkS")
		)
		(fp_line
			(start -0.7874 0.4064)
			(end 0.7874 0.4064)
			(stroke
				(width 0.1524)
				(type default)
			)
			(layer "B.SilkS")
		)
		(fp_line
			(start 0.67945 -0.305054)
			(end 0.12065 -0.305054)
			(stroke
				(width 0.1)
				(type default)
			)
			(layer "B.Fab")
		)
		(fp_line
			(start 0.12065 -0.305054)
			(end 0.12065 -0.2794)
			(stroke
				(width 0.1)
				(type default)
			)
			(layer "B.Fab")
		)
		(fp_line
			(start -0.12065 -0.3048)
			(end -0.67945 -0.3048)
			(stroke
				(width 0.1)
				(type default)
			)
			(layer "B.Fab")
		)
		(fp_line
			(start -0.67945 -0.3048)
			(end -0.67945 0.3048)
			(stroke
				(width 0.1)
				(type default)
			)
			(layer "B.Fab")
		)
		(fp_line
			(start 0.12065 -0.2794)
			(end -0.12065 -0.2794)
			(stroke
				(width 0.1)
				(type default)
			)
			(layer "B.Fab")
		)
		(fp_line
			(start -0.12065 -0.2794)
			(end -0.12065 -0.3048)
			(stroke
				(width 0.1)
				(type default)
			)
			(layer "B.Fab")
		)
		(fp_line
			(start 0.12065 0.2794)
			(end 0.12065 0.3048)
			(stroke
				(width 0.1)
				(type default)
			)
			(layer "B.Fab")
		)
		(fp_line
			(start -0.120396 0.2794)
			(end 0.12065 0.2794)
			(stroke
				(width 0.1)
				(type default)
			)
			(layer "B.Fab")
		)
		(fp_line
			(start 0.67945 0.3048)
			(end 0.67945 -0.305054)
			(stroke
				(width 0.1)
				(type default)
			)
			(layer "B.Fab")
		)
		(fp_line
			(start 0.12065 0.3048)
			(end 0.67945 0.3048)
			(stroke
				(width 0.1)
				(type default)
			)
			(layer "B.Fab")
		)
		(fp_line
			(start -0.120396 0.3048)
			(end -0.120396 0.2794)
			(stroke
				(width 0.1)
				(type default)
			)
			(layer "B.Fab")
		)
		(fp_line
			(start -0.67945 0.3048)
			(end -0.120396 0.3048)
			(stroke
				(width 0.1)
				(type default)
			)
			(layer "B.Fab")
		)
		(pad "1" smd circle
			(at 0.40005 0 270)
			(size 0 0)
			(layers "B.Cu" "B.Mask" "B.Paste")
			(net "FM_PVPP_HBM_CPU0_EN")
		)
		(pad "2" smd circle
			(at -0.40005 0 270)
			(size 0 0)
			(layers "B.Cu" "B.Mask" "B.Paste")
			(net "GND")
		)
	)
	(footprint ""
		(layer "B.Cu")
		(at 52.730908 -193.25971 -90)
		(property "Reference" "R1394"
			(at 0 0 90)
			(layer "B.SilkS")
			(hide yes)
			(effects
				(font
					(size 1.27 1.27)
				)
				(justify mirror)
			)
		)
		(property "Value" ""
			(at 0 0 90)
			(layer "B.Fab")
			(effects
				(font
					(size 1.27 1.27)
				)
				(justify mirror)
			)
		)
		(duplicate_pad_numbers_are_jumpers no)
		(fp_line
			(start -0.7874 0.4064)
			(end 0.7874 0.4064)
			(stroke
				(width 0.1524)
				(type default)
			)
			(layer "B.SilkS")
		)
		(fp_line
			(start 0.7874 0.4064)
			(end 0.7874 -0.4064)
			(stroke
				(width 0.1524)
				(type default)
			)
			(layer "B.SilkS")
		)
		(fp_line
			(start -0.7874 -0.4064)
			(end -0.7874 0.4064)
			(stroke
				(width 0.1524)
				(type default)
			)
			(layer "B.SilkS")
		)
		(fp_line
			(start 0.7874 -0.4064)
			(end -0.7874 -0.4064)
			(stroke
				(width 0.1524)
				(type default)
			)
			(layer "B.SilkS")
		)
		(fp_line
			(start -0.67945 0.3048)
			(end -0.120396 0.3048)
			(stroke
				(width 0.1)
				(type default)
			)
			(layer "B.Fab")
		)
		(fp_line
			(start -0.120396 0.3048)
			(end -0.120396 0.2794)
			(stroke
				(width 0.1)
				(type default)
			)
			(layer "B.Fab")
		)
		(fp_line
			(start 0.12065 0.3048)
			(end 0.67945 0.3048)
			(stroke
				(width 0.1)
				(type default)
			)
			(layer "B.Fab")
		)
		(fp_line
			(start 0.67945 0.3048)
			(end 0.67945 -0.305054)
			(stroke
				(width 0.1)
				(type default)
			)
			(layer "B.Fab")
		)
		(fp_line
			(start -0.120396 0.2794)
			(end 0.12065 0.2794)
			(stroke
				(width 0.1)
				(type default)
			)
			(layer "B.Fab")
		)
		(fp_line
			(start 0.12065 0.2794)
			(end 0.12065 0.3048)
			(stroke
				(width 0.1)
				(type default)
			)
			(layer "B.Fab")
		)
		(fp_line
			(start -0.12065 -0.2794)
			(end -0.12065 -0.3048)
			(stroke
				(width 0.1)
				(type default)
			)
			(layer "B.Fab")
		)
		(fp_line
			(start 0.12065 -0.2794)
			(end -0.12065 -0.2794)
			(stroke
				(width 0.1)
				(type default)
			)
			(layer "B.Fab")
		)
		(fp_line
			(start -0.67945 -0.3048)
			(end -0.67945 0.3048)
			(stroke
				(width 0.1)
				(type default)
			)
			(layer "B.Fab")
		)
		(fp_line
			(start -0.12065 -0.3048)
			(end -0.67945 -0.3048)
			(stroke
				(width 0.1)
				(type default)
			)
			(layer "B.Fab")
		)
		(fp_line
			(start 0.12065 -0.305054)
			(end 0.12065 -0.2794)
			(stroke
				(width 0.1)
				(type default)
			)
			(layer "B.Fab")
		)
		(fp_line
			(start 0.67945 -0.305054)
			(end 0.12065 -0.305054)
			(stroke
				(width 0.1)
				(type default)
			)
			(layer "B.Fab")
		)
		(pad "1" smd circle
			(at 0.40005 0 90)
			(size 0 0)
			(layers "B.Cu" "B.Mask" "B.Paste")
			(net "GND")
		)
		(pad "2" smd circle
			(at -0.40005 0 90)
			(size 0 0)
			(layers "B.Cu" "B.Mask" "B.Paste")
			(net "FM_S3M_CPU1_LVC1_GPIO_3")
		)
	)
	(footprint ""
		(layer "B.Cu")
		(at 178.26482 -356.41153 -90)
		(property "Reference" "PR1333"
			(at 0 0 90)
			(layer "B.SilkS")
			(hide yes)
			(effects
				(font
					(size 1.27 1.27)
				)
				(justify mirror)
			)
		)
		(property "Value" ""
			(at 0 0 90)
			(layer "B.Fab")
			(effects
				(font
					(size 1.27 1.27)
				)
				(justify mirror)
			)
		)
		(duplicate_pad_numbers_are_jumpers no)
		(fp_line
			(start -0.7874 0.4064)
			(end 0.7874 0.4064)
			(stroke
				(width 0.1524)
				(type default)
			)
			(layer "B.SilkS")
		)
		(fp_line
			(start 0.7874 0.4064)
			(end 0.7874 -0.4064)
			(stroke
				(width 0.1524)
				(type default)
			)
			(layer "B.SilkS")
		)
		(fp_line
			(start -0.7874 -0.4064)
			(end -0.7874 0.4064)
			(stroke
				(width 0.1524)
				(type default)
			)
			(layer "B.SilkS")
		)
		(fp_line
			(start 0.7874 -0.4064)
			(end -0.7874 -0.4064)
			(stroke
				(width 0.1524)
				(type default)
			)
			(layer "B.SilkS")
		)
		(fp_line
			(start -0.67945 0.3048)
			(end -0.120396 0.3048)
			(stroke
				(width 0.1)
				(type default)
			)
			(layer "B.Fab")
		)
		(fp_line
			(start -0.120396 0.3048)
			(end -0.120396 0.2794)
			(stroke
				(width 0.1)
				(type default)
			)
			(layer "B.Fab")
		)
		(fp_line
			(start 0.12065 0.3048)
			(end 0.67945 0.3048)
			(stroke
				(width 0.1)
				(type default)
			)
			(layer "B.Fab")
		)
		(fp_line
			(start 0.67945 0.3048)
			(end 0.67945 -0.305054)
			(stroke
				(width 0.1)
				(type default)
			)
			(layer "B.Fab")
		)
		(fp_line
			(start -0.120396 0.2794)
			(end 0.12065 0.2794)
			(stroke
				(width 0.1)
				(type default)
			)
			(layer "B.Fab")
		)
		(fp_line
			(start 0.12065 0.2794)
			(end 0.12065 0.3048)
			(stroke
				(width 0.1)
				(type default)
			)
			(layer "B.Fab")
		)
		(fp_line
			(start -0.12065 -0.2794)
			(end -0.12065 -0.3048)
			(stroke
				(width 0.1)
				(type default)
			)
			(layer "B.Fab")
		)
		(fp_line
			(start 0.12065 -0.2794)
			(end -0.12065 -0.2794)
			(stroke
				(width 0.1)
				(type default)
			)
			(layer "B.Fab")
		)
		(fp_line
			(start -0.67945 -0.3048)
			(end -0.67945 0.3048)
			(stroke
				(width 0.1)
				(type default)
			)
			(layer "B.Fab")
		)
		(fp_line
			(start -0.12065 -0.3048)
			(end -0.67945 -0.3048)
			(stroke
				(width 0.1)
				(type default)
			)
			(layer "B.Fab")
		)
		(fp_line
			(start 0.12065 -0.305054)
			(end 0.12065 -0.2794)
			(stroke
				(width 0.1)
				(type default)
			)
			(layer "B.Fab")
		)
		(fp_line
			(start 0.67945 -0.305054)
			(end 0.12065 -0.305054)
			(stroke
				(width 0.1)
				(type default)
			)
			(layer "B.Fab")
		)
		(pad "1" smd circle
			(at 0.40005 0 90)
			(size 0 0)
			(layers "B.Cu" "B.Mask" "B.Paste")
			(net "PVCCFA_EHV_FIVRA_CPU1_VOS3")
		)
		(pad "2" smd circle
			(at -0.40005 0 90)
			(size 0 0)
			(layers "B.Cu" "B.Mask" "B.Paste")
			(net "PVCCFA_EHV_FIVRA_CPU1")
		)
	)
	(footprint ""
		(layer "B.Cu")
		(at 118.370604 -296.05478)
		(property "Reference" "C352"
			(at 0 0 0)
			(layer "B.SilkS")
			(hide yes)
			(effects
				(font
					(size 1.27 1.27)
				)
				(justify mirror)
			)
		)
		(property "Value" ""
			(at 0 0 0)
			(layer "B.Fab")
			(effects
				(font
					(size 1.27 1.27)
				)
				(justify mirror)
			)
		)
		(duplicate_pad_numbers_are_jumpers no)
		(fp_line
			(start -1.524 -0.762)
			(end -1.524 0.762)
			(stroke
				(width 0.1524)
				(type default)
			)
			(layer "B.SilkS")
		)
		(fp_line
			(start -1.524 0.762)
			(end 1.524 0.762)
			(stroke
				(width 0.1524)
				(type default)
			)
			(layer "B.SilkS")
		)
		(fp_line
			(start 1.524 -0.762)
			(end -1.524 -0.762)
			(stroke
				(width 0.1524)
				(type default)
			)
			(layer "B.SilkS")
		)
		(fp_line
			(start 1.524 0.762)
			(end 1.524 -0.762)
			(stroke
				(width 0.1524)
				(type default)
			)
			(layer "B.SilkS")
		)
		(fp_line
			(start -1.1049 -0.724916)
			(end 1.1049 -0.724916)
			(stroke
				(width 0.1)
				(type default)
			)
			(layer "B.Fab")
		)
		(fp_line
			(start -1.1049 0.724916)
			(end -1.1049 -0.724916)
			(stroke
				(width 0.1)
				(type default)
			)
			(layer "B.Fab")
		)
		(fp_line
			(start 1.1049 -0.724916)
			(end 1.1049 0.724916)
			(stroke
				(width 0.1)
				(type default)
			)
			(layer "B.Fab")
		)
		(fp_line
			(start 1.1049 0.724916)
			(end -1.1049 0.724916)
			(stroke
				(width 0.1)
				(type default)
			)
			(layer "B.Fab")
		)
		(pad "1" smd rect
			(at 0.889 0)
			(size 1.016 1.27)
			(layers "B.Cu" "B.Mask" "B.Paste")
			(net "PVCCIN_CPU1")
		)
		(pad "2" smd rect
			(at -0.889 0)
			(size 1.016 1.27)
			(layers "B.Cu" "B.Mask" "B.Paste")
			(net "GND")
		)
	)
	(footprint ""
		(layer "B.Cu")
		(at 381.608584 -186.138058 90)
		(property "Reference" "R293"
			(at 0 0 90)
			(layer "B.SilkS")
			(hide yes)
			(effects
				(font
					(size 1.27 1.27)
				)
				(justify mirror)
			)
		)
		(property "Value" ""
			(at 0 0 90)
			(layer "B.Fab")
			(effects
				(font
					(size 1.27 1.27)
				)
				(justify mirror)
			)
		)
		(duplicate_pad_numbers_are_jumpers no)
		(fp_line
			(start 0.7874 -0.4064)
			(end -0.7874 -0.4064)
			(stroke
				(width 0.1524)
				(type default)
			)
			(layer "B.SilkS")
		)
		(fp_line
			(start -0.7874 -0.4064)
			(end -0.7874 0.4064)
			(stroke
				(width 0.1524)
				(type default)
			)
			(layer "B.SilkS")
		)
		(fp_line
			(start 0.7874 0.4064)
			(end 0.7874 -0.4064)
			(stroke
				(width 0.1524)
				(type default)
			)
			(layer "B.SilkS")
		)
		(fp_line
			(start -0.7874 0.4064)
			(end 0.7874 0.4064)
			(stroke
				(width 0.1524)
				(type default)
			)
			(layer "B.SilkS")
		)
		(fp_line
			(start 0.67945 -0.305054)
			(end 0.12065 -0.305054)
			(stroke
				(width 0.1)
				(type default)
			)
			(layer "B.Fab")
		)
		(fp_line
			(start 0.12065 -0.305054)
			(end 0.12065 -0.2794)
			(stroke
				(width 0.1)
				(type default)
			)
			(layer "B.Fab")
		)
		(fp_line
			(start -0.12065 -0.3048)
			(end -0.67945 -0.3048)
			(stroke
				(width 0.1)
				(type default)
			)
			(layer "B.Fab")
		)
		(fp_line
			(start -0.67945 -0.3048)
			(end -0.67945 0.3048)
			(stroke
				(width 0.1)
				(type default)
			)
			(layer "B.Fab")
		)
		(fp_line
			(start 0.12065 -0.2794)
			(end -0.12065 -0.2794)
			(stroke
				(width 0.1)
				(type default)
			)
			(layer "B.Fab")
		)
		(fp_line
			(start -0.12065 -0.2794)
			(end -0.12065 -0.3048)
			(stroke
				(width 0.1)
				(type default)
			)
			(layer "B.Fab")
		)
		(fp_line
			(start 0.12065 0.2794)
			(end 0.12065 0.3048)
			(stroke
				(width 0.1)
				(type default)
			)
			(layer "B.Fab")
		)
		(fp_line
			(start -0.120396 0.2794)
			(end 0.12065 0.2794)
			(stroke
				(width 0.1)
				(type default)
			)
			(layer "B.Fab")
		)
		(fp_line
			(start 0.67945 0.3048)
			(end 0.67945 -0.305054)
			(stroke
				(width 0.1)
				(type default)
			)
			(layer "B.Fab")
		)
		(fp_line
			(start 0.12065 0.3048)
			(end 0.67945 0.3048)
			(stroke
				(width 0.1)
				(type default)
			)
			(layer "B.Fab")
		)
		(fp_line
			(start -0.120396 0.3048)
			(end -0.120396 0.2794)
			(stroke
				(width 0.1)
				(type default)
			)
			(layer "B.Fab")
		)
		(fp_line
			(start -0.67945 0.3048)
			(end -0.120396 0.3048)
			(stroke
				(width 0.1)
				(type default)
			)
			(layer "B.Fab")
		)
		(pad "1" smd circle
			(at 0.40005 0 270)
			(size 0 0)
			(layers "B.Cu" "B.Mask" "B.Paste")
			(net "PD_CPU0_TXT_PLTEN")
		)
		(pad "2" smd circle
			(at -0.40005 0 270)
			(size 0 0)
			(layers "B.Cu" "B.Mask" "B.Paste")
			(net "GND")
		)
	)
	(footprint ""
		(layer "B.Cu")
		(at 82.180176 -346.808298 -90)
		(property "Reference" "PC490_P1_7"
			(at 0 0 90)
			(layer "B.SilkS")
			(hide yes)
			(effects
				(font
					(size 1.27 1.27)
				)
				(justify mirror)
			)
		)
		(property "Value" ""
			(at 0 0 90)
			(layer "B.Fab")
			(effects
				(font
					(size 1.27 1.27)
				)
				(justify mirror)
			)
		)
		(duplicate_pad_numbers_are_jumpers no)
		(fp_line
			(start -1.524 0.762)
			(end 1.524 0.762)
			(stroke
				(width 0.1524)
				(type default)
			)
			(layer "B.SilkS")
		)
		(fp_line
			(start 1.524 0.762)
			(end 1.524 -0.762)
			(stroke
				(width 0.1524)
				(type default)
			)
			(layer "B.SilkS")
		)
		(fp_line
			(start -1.524 -0.762)
			(end -1.524 0.762)
			(stroke
				(width 0.1524)
				(type default)
			)
			(layer "B.SilkS")
		)
		(fp_line
			(start 1.524 -0.762)
			(end -1.524 -0.762)
			(stroke
				(width 0.1524)
				(type default)
			)
			(layer "B.SilkS")
		)
		(fp_line
			(start -1.1049 0.724916)
			(end -1.1049 -0.724916)
			(stroke
				(width 0.1)
				(type default)
			)
			(layer "B.Fab")
		)
		(fp_line
			(start 1.1049 0.724916)
			(end -1.1049 0.724916)
			(stroke
				(width 0.1)
				(type default)
			)
			(layer "B.Fab")
		)
		(fp_line
			(start -1.1049 -0.724916)
			(end 1.1049 -0.724916)
			(stroke
				(width 0.1)
				(type default)
			)
			(layer "B.Fab")
		)
		(fp_line
			(start 1.1049 -0.724916)
			(end 1.1049 0.724916)
			(stroke
				(width 0.1)
				(type default)
			)
			(layer "B.Fab")
		)
		(pad "1" smd rect
			(at 0.889 0 270)
			(size 1.016 1.27)
			(layers "B.Cu" "B.Mask" "B.Paste")
			(net "SW_P12V_PVCCIN_CPU1_FLT")
		)
		(pad "2" smd rect
			(at -0.889 0 270)
			(size 1.016 1.27)
			(layers "B.Cu" "B.Mask" "B.Paste")
			(net "GND")
		)
	)
	(footprint ""
		(layer "B.Cu")
		(at 459.574646 -315.26099 -90)
		(property "Reference" "D45"
			(at 3.189732 1.218946 0)
			(unlocked yes)
			(layer "B.SilkS")
			(effects
				(font
					(size 0.7874 0.5842)
					(thickness 0.1524)
				)
				(justify left mirror)
			)
		)
		(property "Value" ""
			(at 0 0 90)
			(layer "B.Fab")
			(effects
				(font
					(size 1.27 1.27)
				)
				(justify mirror)
			)
		)
		(duplicate_pad_numbers_are_jumpers no)
		(fp_line
			(start -2.050796 0.700024)
			(end 2.050796 0.700024)
			(stroke
				(width 0.1524)
				(type default)
			)
			(layer "B.SilkS")
		)
		(fp_line
			(start 2.050796 0.700024)
			(end 2.050796 -0.700024)
			(stroke
				(width 0.1524)
				(type default)
			)
			(layer "B.SilkS")
		)
		(fp_line
			(start -2.343404 0.6985)
			(end -2.216404 0.6985)
			(stroke
				(width 0.1524)
				(type default)
			)
			(layer "B.SilkS")
		)
		(fp_line
			(start -2.229104 0.6985)
			(end -2.051304 0.6985)
			(stroke
				(width 0.1524)
				(type default)
			)
			(layer "B.SilkS")
		)
		(fp_line
			(start -2.051304 0.6985)
			(end -2.051304 0.635)
			(stroke
				(width 0.1524)
				(type default)
			)
			(layer "B.SilkS")
		)
		(fp_line
			(start -2.152904 0.635)
			(end -2.152904 -0.6985)
			(stroke
				(width 0.1524)
				(type default)
			)
			(layer "B.SilkS")
		)
		(fp_line
			(start -2.051304 0.635)
			(end -2.152904 0.635)
			(stroke
				(width 0.1524)
				(type default)
			)
			(layer "B.SilkS")
		)
		(fp_line
			(start 0.30607 0.500126)
			(end -0.193802 0)
			(stroke
				(width 0.1524)
				(type default)
			)
			(layer "B.SilkS")
		)
		(fp_line
			(start -0.193802 0)
			(end 0.30607 -0.500126)
			(stroke
				(width 0.1524)
				(type default)
			)
			(layer "B.SilkS")
		)
		(fp_line
			(start -0.293878 -0.500126)
			(end -0.293878 0.500126)
			(stroke
				(width 0.1524)
				(type default)
			)
			(layer "B.SilkS")
		)
		(fp_line
			(start 0.30607 -0.500126)
			(end 0.30607 0.500126)
			(stroke
				(width 0.1524)
				(type default)
			)
			(layer "B.SilkS")
		)
		(fp_line
			(start -2.064004 -0.6731)
			(end -2.064004 -0.6985)
			(stroke
				(width 0.1524)
				(type default)
			)
			(layer "B.SilkS")
		)
		(fp_line
			(start -2.343404 -0.6985)
			(end -2.343404 0.6985)
			(stroke
				(width 0.1524)
				(type default)
			)
			(layer "B.SilkS")
		)
		(fp_line
			(start -2.229104 -0.6985)
			(end -2.229104 0.6985)
			(stroke
				(width 0.1524)
				(type default)
			)
			(layer "B.SilkS")
		)
		(fp_line
			(start -2.152904 -0.6985)
			(end -2.343404 -0.6985)
			(stroke
				(width 0.1524)
				(type default)
			)
			(layer "B.SilkS")
		)
		(fp_line
			(start -2.064004 -0.6985)
			(end -2.229104 -0.6985)
			(stroke
				(width 0.1524)
				(type default)
			)
			(layer "B.SilkS")
		)
		(fp_line
			(start -2.050796 -0.700024)
			(end -2.050796 0.700024)
			(stroke
				(width 0.1524)
				(type default)
			)
			(layer "B.SilkS")
		)
		(fp_line
			(start 2.050796 -0.700024)
			(end -2.050796 -0.700024)
			(stroke
				(width 0.1524)
				(type default)
			)
			(layer "B.SilkS")
		)
		(fp_line
			(start -0.899922 0.700024)
			(end 0.899922 0.700024)
			(stroke
				(width 0.1)
				(type default)
			)
			(layer "B.Fab")
		)
		(fp_line
			(start 0.899922 0.700024)
			(end 0.899922 -0.700024)
			(stroke
				(width 0.1)
				(type default)
			)
			(layer "B.Fab")
		)
		(fp_line
			(start -0.899922 -0.700024)
			(end -0.899922 0.700024)
			(stroke
				(width 0.1)
				(type default)
			)
			(layer "B.Fab")
		)
		(fp_line
			(start 0.899922 -0.700024)
			(end -0.899922 -0.700024)
			(stroke
				(width 0.1)
				(type default)
			)
			(layer "B.Fab")
		)
		(fp_text user "+"
			(at 3.123946 0.762 180)
			(unlocked yes)
			(layer "B.SilkS")
			(effects
				(font
					(size 1.905 1.4224)
					(thickness 0.1524)
				)
				(justify left mirror)
			)
		)
		(fp_text user "-"
			(at -2.003298 -3.303524 90)
			(unlocked yes)
			(layer "B.SilkS")
			(effects
				(font
					(size 1.905 1.4224)
					(thickness 0.1524)
				)
				(justify left mirror)
			)
		)
		(fp_text user "+"
			(at 3.123946 0.762 180)
			(unlocked yes)
			(layer "B.Fab")
			(effects
				(font
					(size 1.905 1.4224)
					(thickness 0.1524)
				)
				(justify left mirror)
			)
		)
		(fp_text user "-"
			(at -3.880104 0.23495 90)
			(unlocked yes)
			(layer "B.Fab")
			(effects
				(font
					(size 1.905 1.4224)
					(thickness 0.1524)
				)
				(justify left mirror)
			)
		)
		(pad "1" smd rect
			(at 1.199896 0 180)
			(size 0.6604 1.3716)
			(layers "B.Cu" "B.Mask" "B.Paste")
			(net "PWRGD_FAIL_CPU0_GH_R1")
		)
		(pad "2" smd rect
			(at -1.199896 0)
			(size 0.6604 1.3716)
			(layers "B.Cu" "B.Mask" "B.Paste")
			(net "P3V3_AUX")
		)
	)
	(footprint ""
		(layer "B.Cu")
		(at 372.41988 -36.921948 180)
		(property "Reference" "R2511"
			(at 0 0 0)
			(layer "B.SilkS")
			(hide yes)
			(effects
				(font
					(size 1.27 1.27)
				)
				(justify mirror)
			)
		)
		(property "Value" ""
			(at 0 0 0)
			(layer "B.Fab")
			(effects
				(font
					(size 1.27 1.27)
				)
				(justify mirror)
			)
		)
		(duplicate_pad_numbers_are_jumpers no)
		(fp_line
			(start 0.7874 0.4064)
			(end 0.7874 -0.4064)
			(stroke
				(width 0.1524)
				(type default)
			)
			(layer "B.SilkS")
		)
		(fp_line
			(start 0.7874 -0.4064)
			(end -0.7874 -0.4064)
			(stroke
				(width 0.1524)
				(type default)
			)
			(layer "B.SilkS")
		)
		(fp_line
			(start -0.7874 0.4064)
			(end 0.7874 0.4064)
			(stroke
				(width 0.1524)
				(type default)
			)
			(layer "B.SilkS")
		)
		(fp_line
			(start -0.7874 -0.4064)
			(end -0.7874 0.4064)
			(stroke
				(width 0.1524)
				(type default)
			)
			(layer "B.SilkS")
		)
		(fp_line
			(start 0.67945 0.3048)
			(end 0.67945 -0.305054)
			(stroke
				(width 0.1)
				(type default)
			)
			(layer "B.Fab")
		)
		(fp_line
			(start 0.67945 -0.305054)
			(end 0.12065 -0.305054)
			(stroke
				(width 0.1)
				(type default)
			)
			(layer "B.Fab")
		)
		(fp_line
			(start 0.12065 0.3048)
			(end 0.67945 0.3048)
			(stroke
				(width 0.1)
				(type default)
			)
			(layer "B.Fab")
		)
		(fp_line
			(start 0.12065 0.2794)
			(end 0.12065 0.3048)
			(stroke
				(width 0.1)
				(type default)
			)
			(layer "B.Fab")
		)
		(fp_line
			(start 0.12065 -0.2794)
			(end -0.12065 -0.2794)
			(stroke
				(width 0.1)
				(type default)
			)
			(layer "B.Fab")
		)
		(fp_line
			(start 0.12065 -0.305054)
			(end 0.12065 -0.2794)
			(stroke
				(width 0.1)
				(type default)
			)
			(layer "B.Fab")
		)
		(fp_line
			(start -0.120396 0.3048)
			(end -0.120396 0.2794)
			(stroke
				(width 0.1)
				(type default)
			)
			(layer "B.Fab")
		)
		(fp_line
			(start -0.120396 0.2794)
			(end 0.12065 0.2794)
			(stroke
				(width 0.1)
				(type default)
			)
			(layer "B.Fab")
		)
		(fp_line
			(start -0.12065 -0.2794)
			(end -0.12065 -0.3048)
			(stroke
				(width 0.1)
				(type default)
			)
			(layer "B.Fab")
		)
		(fp_line
			(start -0.12065 -0.3048)
			(end -0.67945 -0.3048)
			(stroke
				(width 0.1)
				(type default)
			)
			(layer "B.Fab")
		)
		(fp_line
			(start -0.67945 0.3048)
			(end -0.120396 0.3048)
			(stroke
				(width 0.1)
				(type default)
			)
			(layer "B.Fab")
		)
		(fp_line
			(start -0.67945 -0.3048)
			(end -0.67945 0.3048)
			(stroke
				(width 0.1)
				(type default)
			)
			(layer "B.Fab")
		)
		(pad "1" smd circle
			(at 0.40005 0)
			(size 0 0)
			(layers "B.Cu" "B.Mask" "B.Paste")
			(net "FM_M2_E1S_E6_PEDET")
		)
		(pad "2" smd circle
			(at -0.40005 0)
			(size 0 0)
			(layers "B.Cu" "B.Mask" "B.Paste")
			(net "GND")
		)
	)
	(footprint ""
		(layer "B.Cu")
		(at 287.899094 -317.876682 180)
		(property "Reference" "R3877"
			(at 0 0 0)
			(layer "B.SilkS")
			(hide yes)
			(effects
				(font
					(size 1.27 1.27)
				)
				(justify mirror)
			)
		)
		(property "Value" ""
			(at 0 0 0)
			(layer "B.Fab")
			(effects
				(font
					(size 1.27 1.27)
				)
				(justify mirror)
			)
		)
		(duplicate_pad_numbers_are_jumpers no)
		(fp_line
			(start 0.7874 0.4064)
			(end 0.7874 -0.4064)
			(stroke
				(width 0.1524)
				(type default)
			)
			(layer "B.SilkS")
		)
		(fp_line
			(start 0.7874 -0.4064)
			(end -0.7874 -0.4064)
			(stroke
				(width 0.1524)
				(type default)
			)
			(layer "B.SilkS")
		)
		(fp_line
			(start -0.7874 0.4064)
			(end 0.7874 0.4064)
			(stroke
				(width 0.1524)
				(type default)
			)
			(layer "B.SilkS")
		)
		(fp_line
			(start -0.7874 -0.4064)
			(end -0.7874 0.4064)
			(stroke
				(width 0.1524)
				(type default)
			)
			(layer "B.SilkS")
		)
		(fp_line
			(start 0.67945 0.3048)
			(end 0.67945 -0.305054)
			(stroke
				(width 0.1)
				(type default)
			)
			(layer "B.Fab")
		)
		(fp_line
			(start 0.67945 -0.305054)
			(end 0.12065 -0.305054)
			(stroke
				(width 0.1)
				(type default)
			)
			(layer "B.Fab")
		)
		(fp_line
			(start 0.12065 0.3048)
			(end 0.67945 0.3048)
			(stroke
				(width 0.1)
				(type default)
			)
			(layer "B.Fab")
		)
		(fp_line
			(start 0.12065 0.2794)
			(end 0.12065 0.3048)
			(stroke
				(width 0.1)
				(type default)
			)
			(layer "B.Fab")
		)
		(fp_line
			(start 0.12065 -0.2794)
			(end -0.12065 -0.2794)
			(stroke
				(width 0.1)
				(type default)
			)
			(layer "B.Fab")
		)
		(fp_line
			(start 0.12065 -0.305054)
			(end 0.12065 -0.2794)
			(stroke
				(width 0.1)
				(type default)
			)
			(layer "B.Fab")
		)
		(fp_line
			(start -0.120396 0.3048)
			(end -0.120396 0.2794)
			(stroke
				(width 0.1)
				(type default)
			)
			(layer "B.Fab")
		)
		(fp_line
			(start -0.120396 0.2794)
			(end 0.12065 0.2794)
			(stroke
				(width 0.1)
				(type default)
			)
			(layer "B.Fab")
		)
		(fp_line
			(start -0.12065 -0.2794)
			(end -0.12065 -0.3048)
			(stroke
				(width 0.1)
				(type default)
			)
			(layer "B.Fab")
		)
		(fp_line
			(start -0.12065 -0.3048)
			(end -0.67945 -0.3048)
			(stroke
				(width 0.1)
				(type default)
			)
			(layer "B.Fab")
		)
		(fp_line
			(start -0.67945 0.3048)
			(end -0.120396 0.3048)
			(stroke
				(width 0.1)
				(type default)
			)
			(layer "B.Fab")
		)
		(fp_line
			(start -0.67945 -0.3048)
			(end -0.67945 0.3048)
			(stroke
				(width 0.1)
				(type default)
			)
			(layer "B.Fab")
		)
		(pad "1" smd circle
			(at 0.40005 0)
			(size 0 0)
			(layers "B.Cu" "B.Mask" "B.Paste")
			(net "I3C_SPD_DDRABCD_CPU0_LVC1_SCL_2")
		)
		(pad "2" smd circle
			(at -0.40005 0)
			(size 0 0)
			(layers "B.Cu" "B.Mask" "B.Paste")
			(net "I3C_SPD_DDRABCD_CPU0_LVC1_SCL")
		)
	)
	(footprint ""
		(layer "B.Cu")
		(at 166.369746 -321.554856 -90)
		(property "Reference" "C94"
			(at 0 0 90)
			(layer "B.SilkS")
			(hide yes)
			(effects
				(font
					(size 1.27 1.27)
				)
				(justify mirror)
			)
		)
		(property "Value" ""
			(at 0 0 90)
			(layer "B.Fab")
			(effects
				(font
					(size 1.27 1.27)
				)
				(justify mirror)
			)
		)
		(duplicate_pad_numbers_are_jumpers no)
		(fp_line
			(start -1.524 0.762)
			(end 1.524 0.762)
			(stroke
				(width 0.1524)
				(type default)
			)
			(layer "B.SilkS")
		)
		(fp_line
			(start 1.524 0.762)
			(end 1.524 -0.762)
			(stroke
				(width 0.1524)
				(type default)
			)
			(layer "B.SilkS")
		)
		(fp_line
			(start -1.524 -0.762)
			(end -1.524 0.762)
			(stroke
				(width 0.1524)
				(type default)
			)
			(layer "B.SilkS")
		)
		(fp_line
			(start 1.524 -0.762)
			(end -1.524 -0.762)
			(stroke
				(width 0.1524)
				(type default)
			)
			(layer "B.SilkS")
		)
		(fp_line
			(start -1.1049 0.724916)
			(end -1.1049 -0.724916)
			(stroke
				(width 0.1)
				(type default)
			)
			(layer "B.Fab")
		)
		(fp_line
			(start 1.1049 0.724916)
			(end -1.1049 0.724916)
			(stroke
				(width 0.1)
				(type default)
			)
			(layer "B.Fab")
		)
		(fp_line
			(start -1.1049 -0.724916)
			(end 1.1049 -0.724916)
			(stroke
				(width 0.1)
				(type default)
			)
			(layer "B.Fab")
		)
		(fp_line
			(start 1.1049 -0.724916)
			(end 1.1049 0.724916)
			(stroke
				(width 0.1)
				(type default)
			)
			(layer "B.Fab")
		)
		(pad "1" smd rect
			(at 0.889 0 270)
			(size 1.016 1.27)
			(layers "B.Cu" "B.Mask" "B.Paste")
			(net "P12V_S3_AUX_CPU1_NVDIMM")
		)
		(pad "2" smd rect
			(at -0.889 0 270)
			(size 1.016 1.27)
			(layers "B.Cu" "B.Mask" "B.Paste")
			(net "GND")
		)
	)
	(footprint ""
		(layer "B.Cu")
		(at 116.40312 -244.82044 -90)
		(property "Reference" "C320"
			(at 0 0 90)
			(layer "B.SilkS")
			(hide yes)
			(effects
				(font
					(size 1.27 1.27)
				)
				(justify mirror)
			)
		)
		(property "Value" ""
			(at 0 0 90)
			(layer "B.Fab")
			(effects
				(font
					(size 1.27 1.27)
				)
				(justify mirror)
			)
		)
		(duplicate_pad_numbers_are_jumpers no)
		(fp_line
			(start -1.524 0.762)
			(end 1.524 0.762)
			(stroke
				(width 0.1524)
				(type default)
			)
			(layer "B.SilkS")
		)
		(fp_line
			(start 1.524 0.762)
			(end 1.524 -0.762)
			(stroke
				(width 0.1524)
				(type default)
			)
			(layer "B.SilkS")
		)
		(fp_line
			(start -1.524 -0.762)
			(end -1.524 0.762)
			(stroke
				(width 0.1524)
				(type default)
			)
			(layer "B.SilkS")
		)
		(fp_line
			(start 1.524 -0.762)
			(end -1.524 -0.762)
			(stroke
				(width 0.1524)
				(type default)
			)
			(layer "B.SilkS")
		)
		(fp_line
			(start -1.1049 0.724916)
			(end -1.1049 -0.724916)
			(stroke
				(width 0.1)
				(type default)
			)
			(layer "B.Fab")
		)
		(fp_line
			(start 1.1049 0.724916)
			(end -1.1049 0.724916)
			(stroke
				(width 0.1)
				(type default)
			)
			(layer "B.Fab")
		)
		(fp_line
			(start -1.1049 -0.724916)
			(end 1.1049 -0.724916)
			(stroke
				(width 0.1)
				(type default)
			)
			(layer "B.Fab")
		)
		(fp_line
			(start 1.1049 -0.724916)
			(end 1.1049 0.724916)
			(stroke
				(width 0.1)
				(type default)
			)
			(layer "B.Fab")
		)
		(pad "1" smd rect
			(at 0.889 0 270)
			(size 1.016 1.27)
			(layers "B.Cu" "B.Mask" "B.Paste")
			(net "PVCCIN_CPU1")
		)
		(pad "2" smd rect
			(at -0.889 0 270)
			(size 1.016 1.27)
			(layers "B.Cu" "B.Mask" "B.Paste")
			(net "GND")
		)
	)
	(footprint ""
		(layer "B.Cu")
		(at 23.240746 -321.554856 -90)
		(property "Reference" "C64"
			(at 0 0 90)
			(layer "B.SilkS")
			(hide yes)
			(effects
				(font
					(size 1.27 1.27)
				)
				(justify mirror)
			)
		)
		(property "Value" ""
			(at 0 0 90)
			(layer "B.Fab")
			(effects
				(font
					(size 1.27 1.27)
				)
				(justify mirror)
			)
		)
		(duplicate_pad_numbers_are_jumpers no)
		(fp_line
			(start -1.524 0.762)
			(end 1.524 0.762)
			(stroke
				(width 0.1524)
				(type default)
			)
			(layer "B.SilkS")
		)
		(fp_line
			(start 1.524 0.762)
			(end 1.524 -0.762)
			(stroke
				(width 0.1524)
				(type default)
			)
			(layer "B.SilkS")
		)
		(fp_line
			(start -1.524 -0.762)
			(end -1.524 0.762)
			(stroke
				(width 0.1524)
				(type default)
			)
			(layer "B.SilkS")
		)
		(fp_line
			(start 1.524 -0.762)
			(end -1.524 -0.762)
			(stroke
				(width 0.1524)
				(type default)
			)
			(layer "B.SilkS")
		)
		(fp_line
			(start -1.1049 0.724916)
			(end -1.1049 -0.724916)
			(stroke
				(width 0.1)
				(type default)
			)
			(layer "B.Fab")
		)
		(fp_line
			(start 1.1049 0.724916)
			(end -1.1049 0.724916)
			(stroke
				(width 0.1)
				(type default)
			)
			(layer "B.Fab")
		)
		(fp_line
			(start -1.1049 -0.724916)
			(end 1.1049 -0.724916)
			(stroke
				(width 0.1)
				(type default)
			)
			(layer "B.Fab")
		)
		(fp_line
			(start 1.1049 -0.724916)
			(end 1.1049 0.724916)
			(stroke
				(width 0.1)
				(type default)
			)
			(layer "B.Fab")
		)
		(pad "1" smd rect
			(at 0.889 0 270)
			(size 1.016 1.27)
			(layers "B.Cu" "B.Mask" "B.Paste")
			(net "P12V_S3_AUX_CPU1_NVDIMM")
		)
		(pad "2" smd rect
			(at -0.889 0 270)
			(size 1.016 1.27)
			(layers "B.Cu" "B.Mask" "B.Paste")
			(net "GND")
		)
	)
	(footprint ""
		(layer "B.Cu")
		(at 329.240388 8.003794)
		(property "Reference" "J120"
			(at 4.361942 1.648206 270)
			(unlocked yes)
			(layer "B.SilkS")
			(effects
				(font
					(size 0.7874 0.5842)
					(thickness 0.1524)
				)
				(justify left mirror)
			)
		)
		(property "Value" ""
			(at 0 0 0)
			(layer "B.Fab")
			(effects
				(font
					(size 1.27 1.27)
				)
				(justify mirror)
			)
		)
		(duplicate_pad_numbers_are_jumpers no)
		(fp_line
			(start -1.2192 -2.1082)
			(end -1.2192 2.1082)
			(stroke
				(width 0.1524)
				(type default)
			)
			(layer "B.SilkS")
		)
		(fp_line
			(start -1.2192 2.1082)
			(end 1.2192 2.1082)
			(stroke
				(width 0.1524)
				(type default)
			)
			(layer "B.SilkS")
		)
		(fp_line
			(start 1.2192 -2.1082)
			(end -1.2192 -2.1082)
			(stroke
				(width 0.1524)
				(type default)
			)
			(layer "B.SilkS")
		)
		(fp_line
			(start 1.2192 2.1082)
			(end 1.2192 -2.1082)
			(stroke
				(width 0.1524)
				(type default)
			)
			(layer "B.SilkS")
		)
		(pad "" np_thru_hole circle
			(at -3.4671 -1.27 270)
			(size 1.0414 1.0414)
			(drill 1.0414)
			(layers "*.Cu" "*.Mask")
			(clearance 0.381)
			(thermal_gap 0.381)
		)
		(pad "" np_thru_hole circle
			(at -3.4671 1.27 270)
			(size 1.0414 1.0414)
			(drill 1.0414)
			(layers "*.Cu" "*.Mask")
			(clearance 0.381)
			(thermal_gap 0.381)
		)
		(pad "" np_thru_hole circle
			(at 2.8829 -1.27 270)
			(size 1.0414 1.0414)
			(drill 1.0414)
			(layers "*.Cu" "*.Mask")
			(clearance 0.381)
			(thermal_gap 0.381)
		)
		(pad "" np_thru_hole circle
			(at 2.8829 1.27 270)
			(size 1.0414 1.0414)
			(drill 1.0414)
			(layers "*.Cu" "*.Mask")
			(clearance 0.381)
			(thermal_gap 0.381)
		)
		(pad "1" smd rect
			(at -0.8255 -0.249936 270)
			(size 0.3048 0.508)
			(layers "B.Cu" "B.Mask" "B.Paste")
			(net "DELTA_L_85_10INCH_IN5_DN")
		)
		(pad "2" smd rect
			(at -0.8255 0.249936 270)
			(size 0.3048 0.508)
			(layers "B.Cu" "B.Mask" "B.Paste")
			(net "DELTA_L_85_10INCH_IN5_DP")
		)
		(pad "3" smd circle
			(at 0 0 180)
			(size 0 0)
			(layers "B.Cu" "B.Mask" "B.Paste")
			(net "DELTA_L_GND_1")
		)
		(zone
			(layers "F.Cu" "B.Cu" "In1.Cu" "In2.Cu" "In3.Cu" "In4.Cu" "In5.Cu" "In6.Cu"
				"In7.Cu" "In8.Cu" "In9.Cu" "In10.Cu" "In11.Cu" "In12.Cu" "In13.Cu" "In14.Cu"
				"In15.Cu" "In16.Cu"
			)
			(hatch none 0.5)
			(connect_pads
				(clearance 0)
			)
			(min_thickness 0.25)
			(keepout
				(tracks not_allowed)
				(vias allowed)
				(pads allowed)
				(copperpour not_allowed)
				(footprints allowed)
			)
			(placement
				(enabled no)
				(sheetname "")
			)
			(fill
				(thermal_gap 0.5)
				(thermal_bridge_width 0.5)
				(island_removal_mode 0)
			)
			(polygon
				(pts
					(arc
						(start 326.700388 6.733794)
						(mid 324.846188 6.733794)
						(end 326.700388 6.733794)
					)
				)
			)
		)
		(zone
			(layers "F.Cu" "B.Cu" "In1.Cu" "In2.Cu" "In3.Cu" "In4.Cu" "In5.Cu" "In6.Cu"
				"In7.Cu" "In8.Cu" "In9.Cu" "In10.Cu" "In11.Cu" "In12.Cu" "In13.Cu" "In14.Cu"
				"In15.Cu" "In16.Cu"
			)
			(hatch none 0.5)
			(connect_pads
				(clearance 0)
			)
			(min_thickness 0.25)
			(keepout
				(tracks not_allowed)
				(vias allowed)
				(pads allowed)
				(copperpour not_allowed)
				(footprints allowed)
			)
			(placement
				(enabled no)
				(sheetname "")
			)
			(fill
				(thermal_gap 0.5)
				(thermal_bridge_width 0.5)
				(island_removal_mode 0)
			)
			(polygon
				(pts
					(arc
						(start 326.700388 9.273794)
						(mid 324.846188 9.273794)
						(end 326.700388 9.273794)
					)
				)
			)
		)
		(zone
			(layers "F.Cu" "B.Cu" "In1.Cu" "In2.Cu" "In3.Cu" "In4.Cu" "In5.Cu" "In6.Cu"
				"In7.Cu" "In8.Cu" "In9.Cu" "In10.Cu" "In11.Cu" "In12.Cu" "In13.Cu" "In14.Cu"
				"In15.Cu" "In16.Cu"
			)
			(hatch none 0.5)
			(connect_pads
				(clearance 0)
			)
			(min_thickness 0.25)
			(keepout
				(tracks not_allowed)
				(vias allowed)
				(pads allowed)
				(copperpour not_allowed)
				(footprints allowed)
			)
			(placement
				(enabled no)
				(sheetname "")
			)
			(fill
				(thermal_gap 0.5)
				(thermal_bridge_width 0.5)
				(island_removal_mode 0)
			)
			(polygon
				(pts
					(arc
						(start 333.050388 6.733794)
						(mid 331.196188 6.733794)
						(end 333.050388 6.733794)
					)
				)
			)
		)
		(zone
			(layers "F.Cu" "B.Cu" "In1.Cu" "In2.Cu" "In3.Cu" "In4.Cu" "In5.Cu" "In6.Cu"
				"In7.Cu" "In8.Cu" "In9.Cu" "In10.Cu" "In11.Cu" "In12.Cu" "In13.Cu" "In14.Cu"
				"In15.Cu" "In16.Cu"
			)
			(hatch none 0.5)
			(connect_pads
				(clearance 0)
			)
			(min_thickness 0.25)
			(keepout
				(tracks not_allowed)
				(vias allowed)
				(pads allowed)
				(copperpour not_allowed)
				(footprints allowed)
			)
			(placement
				(enabled no)
				(sheetname "")
			)
			(fill
				(thermal_gap 0.5)
				(thermal_bridge_width 0.5)
				(island_removal_mode 0)
			)
			(polygon
				(pts
					(arc
						(start 333.050388 9.273794)
						(mid 331.196188 9.273794)
						(end 333.050388 9.273794)
					)
				)
			)
		)
		(zone
			(layer "B.Cu")
			(hatch none 0.5)
			(connect_pads
				(clearance 0)
			)
			(min_thickness 0.25)
			(keepout
				(tracks not_allowed)
				(vias allowed)
				(pads allowed)
				(copperpour not_allowed)
				(footprints allowed)
			)
			(placement
				(enabled no)
				(sheetname "")
			)
			(fill
				(thermal_gap 0.5)
				(thermal_bridge_width 0.5)
				(island_removal_mode 0)
			)
			(polygon
				(pts
					(xy 328.122788 7.455154) (xy 328.122788 7.550658) (xy 328.719688 7.550658) (xy 328.719688 7.957058)
					(xy 328.122788 7.957058) (xy 328.122788 8.05053) (xy 328.719688 8.05053) (xy 328.719688 8.45693)
					(xy 328.122788 8.45693) (xy 328.122788 8.552434) (xy 328.821288 8.552434) (xy 328.821288 7.455154)
				)
			)
		)
	)
	(footprint ""
		(layer "B.Cu")
		(at 416.996626 -181.854602 180)
		(property "Reference" "PR102"
			(at 0 0 0)
			(layer "B.SilkS")
			(hide yes)
			(effects
				(font
					(size 1.27 1.27)
				)
				(justify mirror)
			)
		)
		(property "Value" ""
			(at 0 0 0)
			(layer "B.Fab")
			(effects
				(font
					(size 1.27 1.27)
				)
				(justify mirror)
			)
		)
		(duplicate_pad_numbers_are_jumpers no)
		(fp_line
			(start 0.7874 0.4064)
			(end 0.7874 -0.4064)
			(stroke
				(width 0.1524)
				(type default)
			)
			(layer "B.SilkS")
		)
		(fp_line
			(start 0.7874 -0.4064)
			(end -0.7874 -0.4064)
			(stroke
				(width 0.1524)
				(type default)
			)
			(layer "B.SilkS")
		)
		(fp_line
			(start -0.7874 0.4064)
			(end 0.7874 0.4064)
			(stroke
				(width 0.1524)
				(type default)
			)
			(layer "B.SilkS")
		)
		(fp_line
			(start -0.7874 -0.4064)
			(end -0.7874 0.4064)
			(stroke
				(width 0.1524)
				(type default)
			)
			(layer "B.SilkS")
		)
		(fp_line
			(start 0.67945 0.3048)
			(end 0.67945 -0.305054)
			(stroke
				(width 0.1)
				(type default)
			)
			(layer "B.Fab")
		)
		(fp_line
			(start 0.67945 -0.305054)
			(end 0.12065 -0.305054)
			(stroke
				(width 0.1)
				(type default)
			)
			(layer "B.Fab")
		)
		(fp_line
			(start 0.12065 0.3048)
			(end 0.67945 0.3048)
			(stroke
				(width 0.1)
				(type default)
			)
			(layer "B.Fab")
		)
		(fp_line
			(start 0.12065 0.2794)
			(end 0.12065 0.3048)
			(stroke
				(width 0.1)
				(type default)
			)
			(layer "B.Fab")
		)
		(fp_line
			(start 0.12065 -0.2794)
			(end -0.12065 -0.2794)
			(stroke
				(width 0.1)
				(type default)
			)
			(layer "B.Fab")
		)
		(fp_line
			(start 0.12065 -0.305054)
			(end 0.12065 -0.2794)
			(stroke
				(width 0.1)
				(type default)
			)
			(layer "B.Fab")
		)
		(fp_line
			(start -0.120396 0.3048)
			(end -0.120396 0.2794)
			(stroke
				(width 0.1)
				(type default)
			)
			(layer "B.Fab")
		)
		(fp_line
			(start -0.120396 0.2794)
			(end 0.12065 0.2794)
			(stroke
				(width 0.1)
				(type default)
			)
			(layer "B.Fab")
		)
		(fp_line
			(start -0.12065 -0.2794)
			(end -0.12065 -0.3048)
			(stroke
				(width 0.1)
				(type default)
			)
			(layer "B.Fab")
		)
		(fp_line
			(start -0.12065 -0.3048)
			(end -0.67945 -0.3048)
			(stroke
				(width 0.1)
				(type default)
			)
			(layer "B.Fab")
		)
		(fp_line
			(start -0.67945 0.3048)
			(end -0.120396 0.3048)
			(stroke
				(width 0.1)
				(type default)
			)
			(layer "B.Fab")
		)
		(fp_line
			(start -0.67945 -0.3048)
			(end -0.67945 0.3048)
			(stroke
				(width 0.1)
				(type default)
			)
			(layer "B.Fab")
		)
		(pad "1" smd circle
			(at 0.40005 0)
			(size 0 0)
			(layers "B.Cu" "B.Mask" "B.Paste")
			(net "PVCCFA_EHV_CPU0_PVCC")
		)
		(pad "2" smd circle
			(at -0.40005 0)
			(size 0 0)
			(layers "B.Cu" "B.Mask" "B.Paste")
			(net "PVCCINFAON_CPU0_VDD2")
		)
	)
	(footprint ""
		(layer "B.Cu")
		(at 243.001038 -102.528624 180)
		(property "Reference" "R1526"
			(at 0 0 0)
			(layer "B.SilkS")
			(hide yes)
			(effects
				(font
					(size 1.27 1.27)
				)
				(justify mirror)
			)
		)
		(property "Value" ""
			(at 0 0 0)
			(layer "B.Fab")
			(effects
				(font
					(size 1.27 1.27)
				)
				(justify mirror)
			)
		)
		(duplicate_pad_numbers_are_jumpers no)
		(fp_line
			(start 0.7874 0.4064)
			(end 0.7874 -0.4064)
			(stroke
				(width 0.1524)
				(type default)
			)
			(layer "B.SilkS")
		)
		(fp_line
			(start 0.7874 -0.4064)
			(end -0.7874 -0.4064)
			(stroke
				(width 0.1524)
				(type default)
			)
			(layer "B.SilkS")
		)
		(fp_line
			(start -0.7874 0.4064)
			(end 0.7874 0.4064)
			(stroke
				(width 0.1524)
				(type default)
			)
			(layer "B.SilkS")
		)
		(fp_line
			(start -0.7874 -0.4064)
			(end -0.7874 0.4064)
			(stroke
				(width 0.1524)
				(type default)
			)
			(layer "B.SilkS")
		)
		(fp_line
			(start 0.67945 0.3048)
			(end 0.67945 -0.305054)
			(stroke
				(width 0.1)
				(type default)
			)
			(layer "B.Fab")
		)
		(fp_line
			(start 0.67945 -0.305054)
			(end 0.12065 -0.305054)
			(stroke
				(width 0.1)
				(type default)
			)
			(layer "B.Fab")
		)
		(fp_line
			(start 0.12065 0.3048)
			(end 0.67945 0.3048)
			(stroke
				(width 0.1)
				(type default)
			)
			(layer "B.Fab")
		)
		(fp_line
			(start 0.12065 0.2794)
			(end 0.12065 0.3048)
			(stroke
				(width 0.1)
				(type default)
			)
			(layer "B.Fab")
		)
		(fp_line
			(start 0.12065 -0.2794)
			(end -0.12065 -0.2794)
			(stroke
				(width 0.1)
				(type default)
			)
			(layer "B.Fab")
		)
		(fp_line
			(start 0.12065 -0.305054)
			(end 0.12065 -0.2794)
			(stroke
				(width 0.1)
				(type default)
			)
			(layer "B.Fab")
		)
		(fp_line
			(start -0.120396 0.3048)
			(end -0.120396 0.2794)
			(stroke
				(width 0.1)
				(type default)
			)
			(layer "B.Fab")
		)
		(fp_line
			(start -0.120396 0.2794)
			(end 0.12065 0.2794)
			(stroke
				(width 0.1)
				(type default)
			)
			(layer "B.Fab")
		)
		(fp_line
			(start -0.12065 -0.2794)
			(end -0.12065 -0.3048)
			(stroke
				(width 0.1)
				(type default)
			)
			(layer "B.Fab")
		)
		(fp_line
			(start -0.12065 -0.3048)
			(end -0.67945 -0.3048)
			(stroke
				(width 0.1)
				(type default)
			)
			(layer "B.Fab")
		)
		(fp_line
			(start -0.67945 0.3048)
			(end -0.120396 0.3048)
			(stroke
				(width 0.1)
				(type default)
			)
			(layer "B.Fab")
		)
		(fp_line
			(start -0.67945 -0.3048)
			(end -0.67945 0.3048)
			(stroke
				(width 0.1)
				(type default)
			)
			(layer "B.Fab")
		)
		(pad "1" smd circle
			(at 0.40005 0)
			(size 0 0)
			(layers "B.Cu" "B.Mask" "B.Paste")
			(net "SMB_HOST_3V3AUX_SDA_R")
		)
		(pad "2" smd circle
			(at -0.40005 0)
			(size 0 0)
			(layers "B.Cu" "B.Mask" "B.Paste")
			(net "SMB_HOST_CLK_3V3AUX_SDA")
		)
	)
	(footprint ""
		(layer "B.Cu")
		(at 370.734082 -337.546442 -90)
		(property "Reference" "PC282_P0_4"
			(at 0 0 90)
			(layer "B.SilkS")
			(hide yes)
			(effects
				(font
					(size 1.27 1.27)
				)
				(justify mirror)
			)
		)
		(property "Value" ""
			(at 0 0 90)
			(layer "B.Fab")
			(effects
				(font
					(size 1.27 1.27)
				)
				(justify mirror)
			)
		)
		(duplicate_pad_numbers_are_jumpers no)
		(fp_line
			(start -1.524 0.762)
			(end 1.524 0.762)
			(stroke
				(width 0.1524)
				(type default)
			)
			(layer "B.SilkS")
		)
		(fp_line
			(start 1.524 0.762)
			(end 1.524 -0.762)
			(stroke
				(width 0.1524)
				(type default)
			)
			(layer "B.SilkS")
		)
		(fp_line
			(start -1.524 -0.762)
			(end -1.524 0.762)
			(stroke
				(width 0.1524)
				(type default)
			)
			(layer "B.SilkS")
		)
		(fp_line
			(start 1.524 -0.762)
			(end -1.524 -0.762)
			(stroke
				(width 0.1524)
				(type default)
			)
			(layer "B.SilkS")
		)
		(fp_line
			(start -1.1049 0.724916)
			(end -1.1049 -0.724916)
			(stroke
				(width 0.1)
				(type default)
			)
			(layer "B.Fab")
		)
		(fp_line
			(start 1.1049 0.724916)
			(end -1.1049 0.724916)
			(stroke
				(width 0.1)
				(type default)
			)
			(layer "B.Fab")
		)
		(fp_line
			(start -1.1049 -0.724916)
			(end 1.1049 -0.724916)
			(stroke
				(width 0.1)
				(type default)
			)
			(layer "B.Fab")
		)
		(fp_line
			(start 1.1049 -0.724916)
			(end 1.1049 0.724916)
			(stroke
				(width 0.1)
				(type default)
			)
			(layer "B.Fab")
		)
		(pad "1" smd rect
			(at 0.889 0 270)
			(size 1.016 1.27)
			(layers "B.Cu" "B.Mask" "B.Paste")
			(net "SW_P12V_PVCCIN_CPU0_FLT")
		)
		(pad "2" smd rect
			(at -0.889 0 270)
			(size 1.016 1.27)
			(layers "B.Cu" "B.Mask" "B.Paste")
			(net "GND")
		)
	)
	(footprint ""
		(layer "B.Cu")
		(at 178.145948 -192.699894 -90)
		(property "Reference" "R267"
			(at 0 0 90)
			(layer "B.SilkS")
			(hide yes)
			(effects
				(font
					(size 1.27 1.27)
				)
				(justify mirror)
			)
		)
		(property "Value" ""
			(at 0 0 90)
			(layer "B.Fab")
			(effects
				(font
					(size 1.27 1.27)
				)
				(justify mirror)
			)
		)
		(duplicate_pad_numbers_are_jumpers no)
		(fp_line
			(start -0.7874 0.4064)
			(end 0.7874 0.4064)
			(stroke
				(width 0.1524)
				(type default)
			)
			(layer "B.SilkS")
		)
		(fp_line
			(start 0.7874 0.4064)
			(end 0.7874 -0.4064)
			(stroke
				(width 0.1524)
				(type default)
			)
			(layer "B.SilkS")
		)
		(fp_line
			(start -0.7874 -0.4064)
			(end -0.7874 0.4064)
			(stroke
				(width 0.1524)
				(type default)
			)
			(layer "B.SilkS")
		)
		(fp_line
			(start 0.7874 -0.4064)
			(end -0.7874 -0.4064)
			(stroke
				(width 0.1524)
				(type default)
			)
			(layer "B.SilkS")
		)
		(fp_line
			(start -0.67945 0.3048)
			(end -0.120396 0.3048)
			(stroke
				(width 0.1)
				(type default)
			)
			(layer "B.Fab")
		)
		(fp_line
			(start -0.120396 0.3048)
			(end -0.120396 0.2794)
			(stroke
				(width 0.1)
				(type default)
			)
			(layer "B.Fab")
		)
		(fp_line
			(start 0.12065 0.3048)
			(end 0.67945 0.3048)
			(stroke
				(width 0.1)
				(type default)
			)
			(layer "B.Fab")
		)
		(fp_line
			(start 0.67945 0.3048)
			(end 0.67945 -0.305054)
			(stroke
				(width 0.1)
				(type default)
			)
			(layer "B.Fab")
		)
		(fp_line
			(start -0.120396 0.2794)
			(end 0.12065 0.2794)
			(stroke
				(width 0.1)
				(type default)
			)
			(layer "B.Fab")
		)
		(fp_line
			(start 0.12065 0.2794)
			(end 0.12065 0.3048)
			(stroke
				(width 0.1)
				(type default)
			)
			(layer "B.Fab")
		)
		(fp_line
			(start -0.12065 -0.2794)
			(end -0.12065 -0.3048)
			(stroke
				(width 0.1)
				(type default)
			)
			(layer "B.Fab")
		)
		(fp_line
			(start 0.12065 -0.2794)
			(end -0.12065 -0.2794)
			(stroke
				(width 0.1)
				(type default)
			)
			(layer "B.Fab")
		)
		(fp_line
			(start -0.67945 -0.3048)
			(end -0.67945 0.3048)
			(stroke
				(width 0.1)
				(type default)
			)
			(layer "B.Fab")
		)
		(fp_line
			(start -0.12065 -0.3048)
			(end -0.67945 -0.3048)
			(stroke
				(width 0.1)
				(type default)
			)
			(layer "B.Fab")
		)
		(fp_line
			(start 0.12065 -0.305054)
			(end 0.12065 -0.2794)
			(stroke
				(width 0.1)
				(type default)
			)
			(layer "B.Fab")
		)
		(fp_line
			(start 0.67945 -0.305054)
			(end 0.12065 -0.305054)
			(stroke
				(width 0.1)
				(type default)
			)
			(layer "B.Fab")
		)
		(pad "1" smd circle
			(at 0.40005 0 90)
			(size 0 0)
			(layers "B.Cu" "B.Mask" "B.Paste")
			(net "PVNN_TERM_CPU1")
		)
		(pad "2" smd circle
			(at -0.40005 0 90)
			(size 0 0)
			(layers "B.Cu" "B.Mask" "B.Paste")
			(net "PU_CPU1_SOCKET_ID2")
		)
	)
	(footprint ""
		(layer "B.Cu")
		(at 337.641692 -137.832338 180)
		(property "Reference" "R1020"
			(at 0 0 0)
			(layer "B.SilkS")
			(hide yes)
			(effects
				(font
					(size 1.27 1.27)
				)
				(justify mirror)
			)
		)
		(property "Value" ""
			(at 0 0 0)
			(layer "B.Fab")
			(effects
				(font
					(size 1.27 1.27)
				)
				(justify mirror)
			)
		)
		(duplicate_pad_numbers_are_jumpers no)
		(fp_line
			(start 0.7874 0.4064)
			(end 0.7874 0.05207)
			(stroke
				(width 0.1524)
				(type default)
			)
			(layer "B.SilkS")
		)
		(fp_line
			(start 0.515112 -0.4064)
			(end -0.518668 -0.4064)
			(stroke
				(width 0.1524)
				(type default)
			)
			(layer "B.SilkS")
		)
		(fp_line
			(start -0.7874 0.4064)
			(end 0.7874 0.4064)
			(stroke
				(width 0.1524)
				(type default)
			)
			(layer "B.SilkS")
		)
		(fp_line
			(start -0.7874 -0.09017)
			(end -0.7874 0.4064)
			(stroke
				(width 0.1524)
				(type default)
			)
			(layer "B.SilkS")
		)
		(fp_line
			(start 0.67945 0.3048)
			(end 0.67945 -0.305054)
			(stroke
				(width 0.1)
				(type default)
			)
			(layer "B.Fab")
		)
		(fp_line
			(start 0.67945 -0.305054)
			(end 0.12065 -0.305054)
			(stroke
				(width 0.1)
				(type default)
			)
			(layer "B.Fab")
		)
		(fp_line
			(start 0.12065 0.3048)
			(end 0.67945 0.3048)
			(stroke
				(width 0.1)
				(type default)
			)
			(layer "B.Fab")
		)
		(fp_line
			(start 0.12065 0.2794)
			(end 0.12065 0.3048)
			(stroke
				(width 0.1)
				(type default)
			)
			(layer "B.Fab")
		)
		(fp_line
			(start 0.12065 -0.2794)
			(end -0.12065 -0.2794)
			(stroke
				(width 0.1)
				(type default)
			)
			(layer "B.Fab")
		)
		(fp_line
			(start 0.12065 -0.305054)
			(end 0.12065 -0.2794)
			(stroke
				(width 0.1)
				(type default)
			)
			(layer "B.Fab")
		)
		(fp_line
			(start -0.120396 0.3048)
			(end -0.120396 0.2794)
			(stroke
				(width 0.1)
				(type default)
			)
			(layer "B.Fab")
		)
		(fp_line
			(start -0.120396 0.2794)
			(end 0.12065 0.2794)
			(stroke
				(width 0.1)
				(type default)
			)
			(layer "B.Fab")
		)
		(fp_line
			(start -0.12065 -0.2794)
			(end -0.12065 -0.3048)
			(stroke
				(width 0.1)
				(type default)
			)
			(layer "B.Fab")
		)
		(fp_line
			(start -0.12065 -0.3048)
			(end -0.67945 -0.3048)
			(stroke
				(width 0.1)
				(type default)
			)
			(layer "B.Fab")
		)
		(fp_line
			(start -0.67945 0.3048)
			(end -0.120396 0.3048)
			(stroke
				(width 0.1)
				(type default)
			)
			(layer "B.Fab")
		)
		(fp_line
			(start -0.67945 -0.3048)
			(end -0.67945 0.3048)
			(stroke
				(width 0.1)
				(type default)
			)
			(layer "B.Fab")
		)
		(pad "1" smd rect
			(at 0.40005 0 180)
			(size 0.4572 0.508)
			(layers "B.Cu" "B.Mask" "B.Paste")
			(net "CLK_25M_CK440_CPU0_R_DP")
		)
		(pad "2" smd rect
			(at -0.40005 0 180)
			(size 0.4572 0.508)
			(layers "B.Cu" "B.Mask" "B.Paste")
			(net "CLK_25M_NSSC_CPU0_DP")
		)
	)
	(footprint ""
		(layer "B.Cu")
		(at 259.097526 -76.558902 -90)
		(property "Reference" "PR1649"
			(at 0 0 90)
			(layer "B.SilkS")
			(hide yes)
			(effects
				(font
					(size 1.27 1.27)
				)
				(justify mirror)
			)
		)
		(property "Value" ""
			(at 0 0 90)
			(layer "B.Fab")
			(effects
				(font
					(size 1.27 1.27)
				)
				(justify mirror)
			)
		)
		(duplicate_pad_numbers_are_jumpers no)
		(fp_line
			(start -0.7874 0.4064)
			(end 0.7874 0.4064)
			(stroke
				(width 0.1524)
				(type default)
			)
			(layer "B.SilkS")
		)
		(fp_line
			(start 0.7874 0.4064)
			(end 0.7874 -0.4064)
			(stroke
				(width 0.1524)
				(type default)
			)
			(layer "B.SilkS")
		)
		(fp_line
			(start -0.7874 -0.4064)
			(end -0.7874 0.4064)
			(stroke
				(width 0.1524)
				(type default)
			)
			(layer "B.SilkS")
		)
		(fp_line
			(start 0.7874 -0.4064)
			(end -0.7874 -0.4064)
			(stroke
				(width 0.1524)
				(type default)
			)
			(layer "B.SilkS")
		)
		(fp_line
			(start -0.67945 0.3048)
			(end -0.120396 0.3048)
			(stroke
				(width 0.1)
				(type default)
			)
			(layer "B.Fab")
		)
		(fp_line
			(start -0.120396 0.3048)
			(end -0.120396 0.2794)
			(stroke
				(width 0.1)
				(type default)
			)
			(layer "B.Fab")
		)
		(fp_line
			(start 0.12065 0.3048)
			(end 0.67945 0.3048)
			(stroke
				(width 0.1)
				(type default)
			)
			(layer "B.Fab")
		)
		(fp_line
			(start 0.67945 0.3048)
			(end 0.67945 -0.305054)
			(stroke
				(width 0.1)
				(type default)
			)
			(layer "B.Fab")
		)
		(fp_line
			(start -0.120396 0.2794)
			(end 0.12065 0.2794)
			(stroke
				(width 0.1)
				(type default)
			)
			(layer "B.Fab")
		)
		(fp_line
			(start 0.12065 0.2794)
			(end 0.12065 0.3048)
			(stroke
				(width 0.1)
				(type default)
			)
			(layer "B.Fab")
		)
		(fp_line
			(start -0.12065 -0.2794)
			(end -0.12065 -0.3048)
			(stroke
				(width 0.1)
				(type default)
			)
			(layer "B.Fab")
		)
		(fp_line
			(start 0.12065 -0.2794)
			(end -0.12065 -0.2794)
			(stroke
				(width 0.1)
				(type default)
			)
			(layer "B.Fab")
		)
		(fp_line
			(start -0.67945 -0.3048)
			(end -0.67945 0.3048)
			(stroke
				(width 0.1)
				(type default)
			)
			(layer "B.Fab")
		)
		(fp_line
			(start -0.12065 -0.3048)
			(end -0.67945 -0.3048)
			(stroke
				(width 0.1)
				(type default)
			)
			(layer "B.Fab")
		)
		(fp_line
			(start 0.12065 -0.305054)
			(end 0.12065 -0.2794)
			(stroke
				(width 0.1)
				(type default)
			)
			(layer "B.Fab")
		)
		(fp_line
			(start 0.67945 -0.305054)
			(end 0.12065 -0.305054)
			(stroke
				(width 0.1)
				(type default)
			)
			(layer "B.Fab")
		)
		(pad "1" smd circle
			(at 0.40005 0 90)
			(size 0 0)
			(layers "B.Cu" "B.Mask" "B.Paste")
			(net "FM_P1V05_PCH_AUX_R_EN")
		)
		(pad "2" smd circle
			(at -0.40005 0 90)
			(size 0 0)
			(layers "B.Cu" "B.Mask" "B.Paste")
			(net "GND")
		)
	)
	(footprint ""
		(layer "B.Cu")
		(at 266.065 -98.008948 -90)
		(property "Reference" "C107"
			(at 0 0 90)
			(layer "B.SilkS")
			(hide yes)
			(effects
				(font
					(size 1.27 1.27)
				)
				(justify mirror)
			)
		)
		(property "Value" ""
			(at 0 0 90)
			(layer "B.Fab")
			(effects
				(font
					(size 1.27 1.27)
				)
				(justify mirror)
			)
		)
		(duplicate_pad_numbers_are_jumpers no)
		(fp_line
			(start -0.7874 0.4064)
			(end 0.7874 0.4064)
			(stroke
				(width 0.1524)
				(type default)
			)
			(layer "B.SilkS")
		)
		(fp_line
			(start 0.7874 0.4064)
			(end 0.7874 -0.4064)
			(stroke
				(width 0.1524)
				(type default)
			)
			(layer "B.SilkS")
		)
		(fp_line
			(start -0.7874 -0.4064)
			(end -0.7874 0.4064)
			(stroke
				(width 0.1524)
				(type default)
			)
			(layer "B.SilkS")
		)
		(fp_line
			(start 0.7874 -0.4064)
			(end -0.7874 -0.4064)
			(stroke
				(width 0.1524)
				(type default)
			)
			(layer "B.SilkS")
		)
		(fp_line
			(start -0.67945 0.3048)
			(end -0.120396 0.3048)
			(stroke
				(width 0.1)
				(type default)
			)
			(layer "B.Fab")
		)
		(fp_line
			(start -0.120396 0.3048)
			(end -0.120396 0.2794)
			(stroke
				(width 0.1)
				(type default)
			)
			(layer "B.Fab")
		)
		(fp_line
			(start 0.12065 0.3048)
			(end 0.67945 0.3048)
			(stroke
				(width 0.1)
				(type default)
			)
			(layer "B.Fab")
		)
		(fp_line
			(start 0.67945 0.3048)
			(end 0.67945 -0.305054)
			(stroke
				(width 0.1)
				(type default)
			)
			(layer "B.Fab")
		)
		(fp_line
			(start -0.120396 0.2794)
			(end 0.12065 0.2794)
			(stroke
				(width 0.1)
				(type default)
			)
			(layer "B.Fab")
		)
		(fp_line
			(start 0.12065 0.2794)
			(end 0.12065 0.3048)
			(stroke
				(width 0.1)
				(type default)
			)
			(layer "B.Fab")
		)
		(fp_line
			(start -0.12065 -0.2794)
			(end -0.12065 -0.3048)
			(stroke
				(width 0.1)
				(type default)
			)
			(layer "B.Fab")
		)
		(fp_line
			(start 0.12065 -0.2794)
			(end -0.12065 -0.2794)
			(stroke
				(width 0.1)
				(type default)
			)
			(layer "B.Fab")
		)
		(fp_line
			(start -0.67945 -0.3048)
			(end -0.67945 0.3048)
			(stroke
				(width 0.1)
				(type default)
			)
			(layer "B.Fab")
		)
		(fp_line
			(start -0.12065 -0.3048)
			(end -0.67945 -0.3048)
			(stroke
				(width 0.1)
				(type default)
			)
			(layer "B.Fab")
		)
		(fp_line
			(start 0.12065 -0.305054)
			(end 0.12065 -0.2794)
			(stroke
				(width 0.1)
				(type default)
			)
			(layer "B.Fab")
		)
		(fp_line
			(start 0.67945 -0.305054)
			(end 0.12065 -0.305054)
			(stroke
				(width 0.1)
				(type default)
			)
			(layer "B.Fab")
		)
		(pad "1" smd circle
			(at 0.40005 0 90)
			(size 0 0)
			(layers "B.Cu" "B.Mask" "B.Paste")
			(net "P3V3_AUX_CLK_GEN_VDD_CK440")
		)
		(pad "2" smd circle
			(at -0.40005 0 90)
			(size 0 0)
			(layers "B.Cu" "B.Mask" "B.Paste")
			(net "GND")
		)
	)
	(footprint ""
		(layer "B.Cu")
		(at 236.201712 -135.401558 180)
		(property "Reference" "R1023"
			(at 0 0 0)
			(layer "B.SilkS")
			(hide yes)
			(effects
				(font
					(size 1.27 1.27)
				)
				(justify mirror)
			)
		)
		(property "Value" ""
			(at 0 0 0)
			(layer "B.Fab")
			(effects
				(font
					(size 1.27 1.27)
				)
				(justify mirror)
			)
		)
		(duplicate_pad_numbers_are_jumpers no)
		(fp_line
			(start 0.7874 0.4064)
			(end 0.7874 -0.04191)
			(stroke
				(width 0.1524)
				(type default)
			)
			(layer "B.SilkS")
		)
		(fp_line
			(start 0.652272 -0.4064)
			(end -0.455168 -0.4064)
			(stroke
				(width 0.1524)
				(type default)
			)
			(layer "B.SilkS")
		)
		(fp_line
			(start -0.7874 0.4064)
			(end 0.7874 0.4064)
			(stroke
				(width 0.1524)
				(type default)
			)
			(layer "B.SilkS")
		)
		(fp_line
			(start -0.7874 -0.20955)
			(end -0.7874 0.4064)
			(stroke
				(width 0.1524)
				(type default)
			)
			(layer "B.SilkS")
		)
		(fp_line
			(start 0.67945 0.3048)
			(end 0.67945 -0.305054)
			(stroke
				(width 0.1)
				(type default)
			)
			(layer "B.Fab")
		)
		(fp_line
			(start 0.67945 -0.305054)
			(end 0.12065 -0.305054)
			(stroke
				(width 0.1)
				(type default)
			)
			(layer "B.Fab")
		)
		(fp_line
			(start 0.12065 0.3048)
			(end 0.67945 0.3048)
			(stroke
				(width 0.1)
				(type default)
			)
			(layer "B.Fab")
		)
		(fp_line
			(start 0.12065 0.2794)
			(end 0.12065 0.3048)
			(stroke
				(width 0.1)
				(type default)
			)
			(layer "B.Fab")
		)
		(fp_line
			(start 0.12065 -0.2794)
			(end -0.12065 -0.2794)
			(stroke
				(width 0.1)
				(type default)
			)
			(layer "B.Fab")
		)
		(fp_line
			(start 0.12065 -0.305054)
			(end 0.12065 -0.2794)
			(stroke
				(width 0.1)
				(type default)
			)
			(layer "B.Fab")
		)
		(fp_line
			(start -0.120396 0.3048)
			(end -0.120396 0.2794)
			(stroke
				(width 0.1)
				(type default)
			)
			(layer "B.Fab")
		)
		(fp_line
			(start -0.120396 0.2794)
			(end 0.12065 0.2794)
			(stroke
				(width 0.1)
				(type default)
			)
			(layer "B.Fab")
		)
		(fp_line
			(start -0.12065 -0.2794)
			(end -0.12065 -0.3048)
			(stroke
				(width 0.1)
				(type default)
			)
			(layer "B.Fab")
		)
		(fp_line
			(start -0.12065 -0.3048)
			(end -0.67945 -0.3048)
			(stroke
				(width 0.1)
				(type default)
			)
			(layer "B.Fab")
		)
		(fp_line
			(start -0.67945 0.3048)
			(end -0.120396 0.3048)
			(stroke
				(width 0.1)
				(type default)
			)
			(layer "B.Fab")
		)
		(fp_line
			(start -0.67945 -0.3048)
			(end -0.67945 0.3048)
			(stroke
				(width 0.1)
				(type default)
			)
			(layer "B.Fab")
		)
		(pad "1" smd rect
			(at 0.40005 0 180)
			(size 0.4572 0.508)
			(layers "B.Cu" "B.Mask" "B.Paste")
			(net "CLK_25M_CK440_CPU1_R_DN")
		)
		(pad "2" smd rect
			(at -0.40005 0 180)
			(size 0.4572 0.508)
			(layers "B.Cu" "B.Mask" "B.Paste")
			(net "CLK_25M_NSSC_CPU1_DN")
		)
	)
	(footprint ""
		(layer "B.Cu")
		(at 155.356052 -196.776848 180)
		(property "Reference" "R1227"
			(at 0 0 0)
			(layer "B.SilkS")
			(hide yes)
			(effects
				(font
					(size 1.27 1.27)
				)
				(justify mirror)
			)
		)
		(property "Value" ""
			(at 0 0 0)
			(layer "B.Fab")
			(effects
				(font
					(size 1.27 1.27)
				)
				(justify mirror)
			)
		)
		(duplicate_pad_numbers_are_jumpers no)
		(fp_line
			(start 0.7874 0.4064)
			(end 0.7874 -0.4064)
			(stroke
				(width 0.1524)
				(type default)
			)
			(layer "B.SilkS")
		)
		(fp_line
			(start 0.7874 -0.4064)
			(end -0.7874 -0.4064)
			(stroke
				(width 0.1524)
				(type default)
			)
			(layer "B.SilkS")
		)
		(fp_line
			(start -0.7874 0.4064)
			(end 0.7874 0.4064)
			(stroke
				(width 0.1524)
				(type default)
			)
			(layer "B.SilkS")
		)
		(fp_line
			(start -0.7874 -0.4064)
			(end -0.7874 0.4064)
			(stroke
				(width 0.1524)
				(type default)
			)
			(layer "B.SilkS")
		)
		(fp_line
			(start 0.67945 0.3048)
			(end 0.67945 -0.305054)
			(stroke
				(width 0.1)
				(type default)
			)
			(layer "B.Fab")
		)
		(fp_line
			(start 0.67945 -0.305054)
			(end 0.12065 -0.305054)
			(stroke
				(width 0.1)
				(type default)
			)
			(layer "B.Fab")
		)
		(fp_line
			(start 0.12065 0.3048)
			(end 0.67945 0.3048)
			(stroke
				(width 0.1)
				(type default)
			)
			(layer "B.Fab")
		)
		(fp_line
			(start 0.12065 0.2794)
			(end 0.12065 0.3048)
			(stroke
				(width 0.1)
				(type default)
			)
			(layer "B.Fab")
		)
		(fp_line
			(start 0.12065 -0.2794)
			(end -0.12065 -0.2794)
			(stroke
				(width 0.1)
				(type default)
			)
			(layer "B.Fab")
		)
		(fp_line
			(start 0.12065 -0.305054)
			(end 0.12065 -0.2794)
			(stroke
				(width 0.1)
				(type default)
			)
			(layer "B.Fab")
		)
		(fp_line
			(start -0.120396 0.3048)
			(end -0.120396 0.2794)
			(stroke
				(width 0.1)
				(type default)
			)
			(layer "B.Fab")
		)
		(fp_line
			(start -0.120396 0.2794)
			(end 0.12065 0.2794)
			(stroke
				(width 0.1)
				(type default)
			)
			(layer "B.Fab")
		)
		(fp_line
			(start -0.12065 -0.2794)
			(end -0.12065 -0.3048)
			(stroke
				(width 0.1)
				(type default)
			)
			(layer "B.Fab")
		)
		(fp_line
			(start -0.12065 -0.3048)
			(end -0.67945 -0.3048)
			(stroke
				(width 0.1)
				(type default)
			)
			(layer "B.Fab")
		)
		(fp_line
			(start -0.67945 0.3048)
			(end -0.120396 0.3048)
			(stroke
				(width 0.1)
				(type default)
			)
			(layer "B.Fab")
		)
		(fp_line
			(start -0.67945 -0.3048)
			(end -0.67945 0.3048)
			(stroke
				(width 0.1)
				(type default)
			)
			(layer "B.Fab")
		)
		(pad "1" smd circle
			(at 0.40005 0)
			(size 0 0)
			(layers "B.Cu" "B.Mask" "B.Paste")
			(net "PD_JTAG_CPU1_PLD_TCK")
		)
		(pad "2" smd circle
			(at -0.40005 0)
			(size 0 0)
			(layers "B.Cu" "B.Mask" "B.Paste")
			(net "GND")
		)
	)
	(footprint ""
		(layer "B.Cu")
		(at 340.036658 -354.92817 90)
		(property "Reference" "PR2554"
			(at 0 0 90)
			(layer "B.SilkS")
			(hide yes)
			(effects
				(font
					(size 1.27 1.27)
				)
				(justify mirror)
			)
		)
		(property "Value" ""
			(at 0 0 90)
			(layer "B.Fab")
			(effects
				(font
					(size 1.27 1.27)
				)
				(justify mirror)
			)
		)
		(duplicate_pad_numbers_are_jumpers no)
		(fp_line
			(start 4.0386 -1.7526)
			(end -4.0386 -1.7526)
			(stroke
				(width 0.1524)
				(type default)
			)
			(layer "B.SilkS")
		)
		(fp_line
			(start -4.0386 -1.7526)
			(end -4.0386 1.7526)
			(stroke
				(width 0.1524)
				(type default)
			)
			(layer "B.SilkS")
		)
		(fp_line
			(start 4.0386 1.7526)
			(end 4.0386 -1.7526)
			(stroke
				(width 0.1524)
				(type default)
			)
			(layer "B.SilkS")
		)
		(fp_line
			(start -4.0386 1.7526)
			(end 4.0386 1.7526)
			(stroke
				(width 0.1524)
				(type default)
			)
			(layer "B.SilkS")
		)
		(fp_line
			(start 4.0386 -1.7526)
			(end -4.0386 -1.7526)
			(stroke
				(width 0.1)
				(type default)
			)
			(layer "B.Fab")
		)
		(fp_line
			(start -4.0386 -1.7526)
			(end -4.0386 1.7526)
			(stroke
				(width 0.1)
				(type default)
			)
			(layer "B.Fab")
		)
		(fp_line
			(start 4.0386 1.7526)
			(end 4.0386 -1.7526)
			(stroke
				(width 0.1)
				(type default)
			)
			(layer "B.Fab")
		)
		(fp_line
			(start -4.0386 1.7526)
			(end 4.0386 1.7526)
			(stroke
				(width 0.1)
				(type default)
			)
			(layer "B.Fab")
		)
		(pad "1" smd rect
			(at 3.1115 0 270)
			(size 1.524 3.2004)
			(layers "B.Cu" "B.Mask" "B.Paste")
			(net "P12V_AUX")
		)
		(pad "2" smd rect
			(at -3.1115 0 270)
			(size 1.524 3.2004)
			(layers "B.Cu" "B.Mask" "B.Paste")
			(net "SW_P12V_PVCCIN_CPU0_FLT")
		)
	)
	(footprint ""
		(layer "B.Cu")
		(at 407.108152 -193.08953 -90)
		(property "Reference" "R282"
			(at 0 0 90)
			(layer "B.SilkS")
			(hide yes)
			(effects
				(font
					(size 1.27 1.27)
				)
				(justify mirror)
			)
		)
		(property "Value" ""
			(at 0 0 90)
			(layer "B.Fab")
			(effects
				(font
					(size 1.27 1.27)
				)
				(justify mirror)
			)
		)
		(duplicate_pad_numbers_are_jumpers no)
		(fp_line
			(start -0.7874 0.4064)
			(end 0.7874 0.4064)
			(stroke
				(width 0.1524)
				(type default)
			)
			(layer "B.SilkS")
		)
		(fp_line
			(start 0.7874 0.4064)
			(end 0.7874 -0.4064)
			(stroke
				(width 0.1524)
				(type default)
			)
			(layer "B.SilkS")
		)
		(fp_line
			(start -0.7874 -0.4064)
			(end -0.7874 0.4064)
			(stroke
				(width 0.1524)
				(type default)
			)
			(layer "B.SilkS")
		)
		(fp_line
			(start 0.7874 -0.4064)
			(end -0.7874 -0.4064)
			(stroke
				(width 0.1524)
				(type default)
			)
			(layer "B.SilkS")
		)
		(fp_line
			(start -0.67945 0.3048)
			(end -0.120396 0.3048)
			(stroke
				(width 0.1)
				(type default)
			)
			(layer "B.Fab")
		)
		(fp_line
			(start -0.120396 0.3048)
			(end -0.120396 0.2794)
			(stroke
				(width 0.1)
				(type default)
			)
			(layer "B.Fab")
		)
		(fp_line
			(start 0.12065 0.3048)
			(end 0.67945 0.3048)
			(stroke
				(width 0.1)
				(type default)
			)
			(layer "B.Fab")
		)
		(fp_line
			(start 0.67945 0.3048)
			(end 0.67945 -0.305054)
			(stroke
				(width 0.1)
				(type default)
			)
			(layer "B.Fab")
		)
		(fp_line
			(start -0.120396 0.2794)
			(end 0.12065 0.2794)
			(stroke
				(width 0.1)
				(type default)
			)
			(layer "B.Fab")
		)
		(fp_line
			(start 0.12065 0.2794)
			(end 0.12065 0.3048)
			(stroke
				(width 0.1)
				(type default)
			)
			(layer "B.Fab")
		)
		(fp_line
			(start -0.12065 -0.2794)
			(end -0.12065 -0.3048)
			(stroke
				(width 0.1)
				(type default)
			)
			(layer "B.Fab")
		)
		(fp_line
			(start 0.12065 -0.2794)
			(end -0.12065 -0.2794)
			(stroke
				(width 0.1)
				(type default)
			)
			(layer "B.Fab")
		)
		(fp_line
			(start -0.67945 -0.3048)
			(end -0.67945 0.3048)
			(stroke
				(width 0.1)
				(type default)
			)
			(layer "B.Fab")
		)
		(fp_line
			(start -0.12065 -0.3048)
			(end -0.67945 -0.3048)
			(stroke
				(width 0.1)
				(type default)
			)
			(layer "B.Fab")
		)
		(fp_line
			(start 0.12065 -0.305054)
			(end 0.12065 -0.2794)
			(stroke
				(width 0.1)
				(type default)
			)
			(layer "B.Fab")
		)
		(fp_line
			(start 0.67945 -0.305054)
			(end 0.12065 -0.305054)
			(stroke
				(width 0.1)
				(type default)
			)
			(layer "B.Fab")
		)
		(pad "1" smd circle
			(at 0.40005 0 90)
			(size 0 0)
			(layers "B.Cu" "B.Mask" "B.Paste")
			(net "PVNN_TERM_CPU0")
		)
		(pad "2" smd circle
			(at -0.40005 0 90)
			(size 0 0)
			(layers "B.Cu" "B.Mask" "B.Paste")
			(net "PU_CPU0_LEGACY_SKT")
		)
	)
	(footprint ""
		(layer "B.Cu")
		(at 75.87488 -11.267948 -90)
		(property "Reference" "R3165"
			(at 0 0 90)
			(layer "B.SilkS")
			(hide yes)
			(effects
				(font
					(size 1.27 1.27)
				)
				(justify mirror)
			)
		)
		(property "Value" ""
			(at 0 0 90)
			(layer "B.Fab")
			(effects
				(font
					(size 1.27 1.27)
				)
				(justify mirror)
			)
		)
		(duplicate_pad_numbers_are_jumpers no)
		(fp_line
			(start -0.7874 0.4064)
			(end 0.7874 0.4064)
			(stroke
				(width 0.1524)
				(type default)
			)
			(layer "B.SilkS")
		)
		(fp_line
			(start 0.7874 0.4064)
			(end 0.7874 -0.4064)
			(stroke
				(width 0.1524)
				(type default)
			)
			(layer "B.SilkS")
		)
		(fp_line
			(start -0.7874 -0.4064)
			(end -0.7874 0.4064)
			(stroke
				(width 0.1524)
				(type default)
			)
			(layer "B.SilkS")
		)
		(fp_line
			(start 0.7874 -0.4064)
			(end -0.7874 -0.4064)
			(stroke
				(width 0.1524)
				(type default)
			)
			(layer "B.SilkS")
		)
		(fp_line
			(start -0.67945 0.3048)
			(end -0.120396 0.3048)
			(stroke
				(width 0.1)
				(type default)
			)
			(layer "B.Fab")
		)
		(fp_line
			(start -0.120396 0.3048)
			(end -0.120396 0.2794)
			(stroke
				(width 0.1)
				(type default)
			)
			(layer "B.Fab")
		)
		(fp_line
			(start 0.12065 0.3048)
			(end 0.67945 0.3048)
			(stroke
				(width 0.1)
				(type default)
			)
			(layer "B.Fab")
		)
		(fp_line
			(start 0.67945 0.3048)
			(end 0.67945 -0.305054)
			(stroke
				(width 0.1)
				(type default)
			)
			(layer "B.Fab")
		)
		(fp_line
			(start -0.120396 0.2794)
			(end 0.12065 0.2794)
			(stroke
				(width 0.1)
				(type default)
			)
			(layer "B.Fab")
		)
		(fp_line
			(start 0.12065 0.2794)
			(end 0.12065 0.3048)
			(stroke
				(width 0.1)
				(type default)
			)
			(layer "B.Fab")
		)
		(fp_line
			(start -0.12065 -0.2794)
			(end -0.12065 -0.3048)
			(stroke
				(width 0.1)
				(type default)
			)
			(layer "B.Fab")
		)
		(fp_line
			(start 0.12065 -0.2794)
			(end -0.12065 -0.2794)
			(stroke
				(width 0.1)
				(type default)
			)
			(layer "B.Fab")
		)
		(fp_line
			(start -0.67945 -0.3048)
			(end -0.67945 0.3048)
			(stroke
				(width 0.1)
				(type default)
			)
			(layer "B.Fab")
		)
		(fp_line
			(start -0.12065 -0.3048)
			(end -0.67945 -0.3048)
			(stroke
				(width 0.1)
				(type default)
			)
			(layer "B.Fab")
		)
		(fp_line
			(start 0.12065 -0.305054)
			(end 0.12065 -0.2794)
			(stroke
				(width 0.1)
				(type default)
			)
			(layer "B.Fab")
		)
		(fp_line
			(start 0.67945 -0.305054)
			(end 0.12065 -0.305054)
			(stroke
				(width 0.1)
				(type default)
			)
			(layer "B.Fab")
		)
		(pad "1" smd circle
			(at 0.40005 0 90)
			(size 0 0)
			(layers "B.Cu" "B.Mask" "B.Paste")
			(net "GND")
		)
		(pad "2" smd circle
			(at -0.40005 0 90)
			(size 0 0)
			(layers "B.Cu" "B.Mask" "B.Paste")
			(net "OCP_V3_2_MAIN_PWR_EN")
		)
	)
	(footprint ""
		(layer "B.Cu")
		(at 414.309814 -319.263776 180)
		(property "Reference" "C26"
			(at 0 0 0)
			(layer "B.SilkS")
			(hide yes)
			(effects
				(font
					(size 1.27 1.27)
				)
				(justify mirror)
			)
		)
		(property "Value" ""
			(at 0 0 0)
			(layer "B.Fab")
			(effects
				(font
					(size 1.27 1.27)
				)
				(justify mirror)
			)
		)
		(duplicate_pad_numbers_are_jumpers no)
		(fp_line
			(start 0.7874 0.4064)
			(end 0.7874 -0.4064)
			(stroke
				(width 0.1524)
				(type default)
			)
			(layer "B.SilkS")
		)
		(fp_line
			(start 0.7874 -0.4064)
			(end -0.7874 -0.4064)
			(stroke
				(width 0.1524)
				(type default)
			)
			(layer "B.SilkS")
		)
		(fp_line
			(start -0.7874 0.4064)
			(end 0.7874 0.4064)
			(stroke
				(width 0.1524)
				(type default)
			)
			(layer "B.SilkS")
		)
		(fp_line
			(start -0.7874 -0.4064)
			(end -0.7874 0.4064)
			(stroke
				(width 0.1524)
				(type default)
			)
			(layer "B.SilkS")
		)
		(fp_line
			(start 0.67945 0.3048)
			(end 0.67945 -0.305054)
			(stroke
				(width 0.1)
				(type default)
			)
			(layer "B.Fab")
		)
		(fp_line
			(start 0.67945 -0.305054)
			(end 0.12065 -0.305054)
			(stroke
				(width 0.1)
				(type default)
			)
			(layer "B.Fab")
		)
		(fp_line
			(start 0.12065 0.3048)
			(end 0.67945 0.3048)
			(stroke
				(width 0.1)
				(type default)
			)
			(layer "B.Fab")
		)
		(fp_line
			(start 0.12065 0.2794)
			(end 0.12065 0.3048)
			(stroke
				(width 0.1)
				(type default)
			)
			(layer "B.Fab")
		)
		(fp_line
			(start 0.12065 -0.2794)
			(end -0.12065 -0.2794)
			(stroke
				(width 0.1)
				(type default)
			)
			(layer "B.Fab")
		)
		(fp_line
			(start 0.12065 -0.305054)
			(end 0.12065 -0.2794)
			(stroke
				(width 0.1)
				(type default)
			)
			(layer "B.Fab")
		)
		(fp_line
			(start -0.120396 0.3048)
			(end -0.120396 0.2794)
			(stroke
				(width 0.1)
				(type default)
			)
			(layer "B.Fab")
		)
		(fp_line
			(start -0.120396 0.2794)
			(end 0.12065 0.2794)
			(stroke
				(width 0.1)
				(type default)
			)
			(layer "B.Fab")
		)
		(fp_line
			(start -0.12065 -0.2794)
			(end -0.12065 -0.3048)
			(stroke
				(width 0.1)
				(type default)
			)
			(layer "B.Fab")
		)
		(fp_line
			(start -0.12065 -0.3048)
			(end -0.67945 -0.3048)
			(stroke
				(width 0.1)
				(type default)
			)
			(layer "B.Fab")
		)
		(fp_line
			(start -0.67945 0.3048)
			(end -0.120396 0.3048)
			(stroke
				(width 0.1)
				(type default)
			)
			(layer "B.Fab")
		)
		(fp_line
			(start -0.67945 -0.3048)
			(end -0.67945 0.3048)
			(stroke
				(width 0.1)
				(type default)
			)
			(layer "B.Fab")
		)
		(pad "1" smd circle
			(at 0.40005 0)
			(size 0 0)
			(layers "B.Cu" "B.Mask" "B.Paste")
			(net "P3V3_AUX")
		)
		(pad "2" smd circle
			(at -0.40005 0)
			(size 0 0)
			(layers "B.Cu" "B.Mask" "B.Paste")
			(net "GND")
		)
	)
	(footprint ""
		(layer "B.Cu")
		(at 447.56705 -10.594086 90)
		(property "Reference" "R410"
			(at 0 0 90)
			(layer "B.SilkS")
			(hide yes)
			(effects
				(font
					(size 1.27 1.27)
				)
				(justify mirror)
			)
		)
		(property "Value" ""
			(at 0 0 90)
			(layer "B.Fab")
			(effects
				(font
					(size 1.27 1.27)
				)
				(justify mirror)
			)
		)
		(duplicate_pad_numbers_are_jumpers no)
		(fp_line
			(start 0.7874 -0.4064)
			(end -0.7874 -0.4064)
			(stroke
				(width 0.1524)
				(type default)
			)
			(layer "B.SilkS")
		)
		(fp_line
			(start -0.7874 -0.4064)
			(end -0.7874 0.4064)
			(stroke
				(width 0.1524)
				(type default)
			)
			(layer "B.SilkS")
		)
		(fp_line
			(start 0.7874 0.4064)
			(end 0.7874 -0.4064)
			(stroke
				(width 0.1524)
				(type default)
			)
			(layer "B.SilkS")
		)
		(fp_line
			(start -0.7874 0.4064)
			(end 0.7874 0.4064)
			(stroke
				(width 0.1524)
				(type default)
			)
			(layer "B.SilkS")
		)
		(fp_line
			(start 0.67945 -0.305054)
			(end 0.12065 -0.305054)
			(stroke
				(width 0.1)
				(type default)
			)
			(layer "B.Fab")
		)
		(fp_line
			(start 0.12065 -0.305054)
			(end 0.12065 -0.2794)
			(stroke
				(width 0.1)
				(type default)
			)
			(layer "B.Fab")
		)
		(fp_line
			(start -0.12065 -0.3048)
			(end -0.67945 -0.3048)
			(stroke
				(width 0.1)
				(type default)
			)
			(layer "B.Fab")
		)
		(fp_line
			(start -0.67945 -0.3048)
			(end -0.67945 0.3048)
			(stroke
				(width 0.1)
				(type default)
			)
			(layer "B.Fab")
		)
		(fp_line
			(start 0.12065 -0.2794)
			(end -0.12065 -0.2794)
			(stroke
				(width 0.1)
				(type default)
			)
			(layer "B.Fab")
		)
		(fp_line
			(start -0.12065 -0.2794)
			(end -0.12065 -0.3048)
			(stroke
				(width 0.1)
				(type default)
			)
			(layer "B.Fab")
		)
		(fp_line
			(start 0.12065 0.2794)
			(end 0.12065 0.3048)
			(stroke
				(width 0.1)
				(type default)
			)
			(layer "B.Fab")
		)
		(fp_line
			(start -0.120396 0.2794)
			(end 0.12065 0.2794)
			(stroke
				(width 0.1)
				(type default)
			)
			(layer "B.Fab")
		)
		(fp_line
			(start 0.67945 0.3048)
			(end 0.67945 -0.305054)
			(stroke
				(width 0.1)
				(type default)
			)
			(layer "B.Fab")
		)
		(fp_line
			(start 0.12065 0.3048)
			(end 0.67945 0.3048)
			(stroke
				(width 0.1)
				(type default)
			)
			(layer "B.Fab")
		)
		(fp_line
			(start -0.120396 0.3048)
			(end -0.120396 0.2794)
			(stroke
				(width 0.1)
				(type default)
			)
			(layer "B.Fab")
		)
		(fp_line
			(start -0.67945 0.3048)
			(end -0.120396 0.3048)
			(stroke
				(width 0.1)
				(type default)
			)
			(layer "B.Fab")
		)
		(pad "1" smd circle
			(at 0.40005 0 270)
			(size 0 0)
			(layers "B.Cu" "B.Mask" "B.Paste")
			(net "OCP_SFF_ID0")
		)
		(pad "2" smd circle
			(at -0.40005 0 270)
			(size 0 0)
			(layers "B.Cu" "B.Mask" "B.Paste")
			(net "GND")
		)
	)
	(footprint ""
		(layer "B.Cu")
		(at 71.65848 -183.278018 -90)
		(property "Reference" "R264"
			(at 0 0 90)
			(layer "B.SilkS")
			(hide yes)
			(effects
				(font
					(size 1.27 1.27)
				)
				(justify mirror)
			)
		)
		(property "Value" ""
			(at 0 0 90)
			(layer "B.Fab")
			(effects
				(font
					(size 1.27 1.27)
				)
				(justify mirror)
			)
		)
		(duplicate_pad_numbers_are_jumpers no)
		(fp_line
			(start -0.7874 0.4064)
			(end 0.7874 0.4064)
			(stroke
				(width 0.1524)
				(type default)
			)
			(layer "B.SilkS")
		)
		(fp_line
			(start 0.7874 0.4064)
			(end 0.7874 -0.4064)
			(stroke
				(width 0.1524)
				(type default)
			)
			(layer "B.SilkS")
		)
		(fp_line
			(start -0.7874 -0.4064)
			(end -0.7874 0.4064)
			(stroke
				(width 0.1524)
				(type default)
			)
			(layer "B.SilkS")
		)
		(fp_line
			(start 0.7874 -0.4064)
			(end -0.7874 -0.4064)
			(stroke
				(width 0.1524)
				(type default)
			)
			(layer "B.SilkS")
		)
		(fp_line
			(start -0.67945 0.3048)
			(end -0.120396 0.3048)
			(stroke
				(width 0.1)
				(type default)
			)
			(layer "B.Fab")
		)
		(fp_line
			(start -0.120396 0.3048)
			(end -0.120396 0.2794)
			(stroke
				(width 0.1)
				(type default)
			)
			(layer "B.Fab")
		)
		(fp_line
			(start 0.12065 0.3048)
			(end 0.67945 0.3048)
			(stroke
				(width 0.1)
				(type default)
			)
			(layer "B.Fab")
		)
		(fp_line
			(start 0.67945 0.3048)
			(end 0.67945 -0.305054)
			(stroke
				(width 0.1)
				(type default)
			)
			(layer "B.Fab")
		)
		(fp_line
			(start -0.120396 0.2794)
			(end 0.12065 0.2794)
			(stroke
				(width 0.1)
				(type default)
			)
			(layer "B.Fab")
		)
		(fp_line
			(start 0.12065 0.2794)
			(end 0.12065 0.3048)
			(stroke
				(width 0.1)
				(type default)
			)
			(layer "B.Fab")
		)
		(fp_line
			(start -0.12065 -0.2794)
			(end -0.12065 -0.3048)
			(stroke
				(width 0.1)
				(type default)
			)
			(layer "B.Fab")
		)
		(fp_line
			(start 0.12065 -0.2794)
			(end -0.12065 -0.2794)
			(stroke
				(width 0.1)
				(type default)
			)
			(layer "B.Fab")
		)
		(fp_line
			(start -0.67945 -0.3048)
			(end -0.67945 0.3048)
			(stroke
				(width 0.1)
				(type default)
			)
			(layer "B.Fab")
		)
		(fp_line
			(start -0.12065 -0.3048)
			(end -0.67945 -0.3048)
			(stroke
				(width 0.1)
				(type default)
			)
			(layer "B.Fab")
		)
		(fp_line
			(start 0.12065 -0.305054)
			(end 0.12065 -0.2794)
			(stroke
				(width 0.1)
				(type default)
			)
			(layer "B.Fab")
		)
		(fp_line
			(start 0.67945 -0.305054)
			(end 0.12065 -0.305054)
			(stroke
				(width 0.1)
				(type default)
			)
			(layer "B.Fab")
		)
		(pad "1" smd circle
			(at 0.40005 0 90)
			(size 0 0)
			(layers "B.Cu" "B.Mask" "B.Paste")
			(net "PVNN_TERM_CPU1")
		)
		(pad "2" smd circle
			(at -0.40005 0 90)
			(size 0 0)
			(layers "B.Cu" "B.Mask" "B.Paste")
			(net "H_CPU1_BMCINIT_LVC1")
		)
	)
	(footprint ""
		(layer "B.Cu")
		(at 271.180814 -321.549776 -90)
		(property "Reference" "C16"
			(at 0 0 90)
			(layer "B.SilkS")
			(hide yes)
			(effects
				(font
					(size 1.27 1.27)
				)
				(justify mirror)
			)
		)
		(property "Value" ""
			(at 0 0 90)
			(layer "B.Fab")
			(effects
				(font
					(size 1.27 1.27)
				)
				(justify mirror)
			)
		)
		(duplicate_pad_numbers_are_jumpers no)
		(fp_line
			(start -1.524 0.762)
			(end 1.524 0.762)
			(stroke
				(width 0.1524)
				(type default)
			)
			(layer "B.SilkS")
		)
		(fp_line
			(start 1.524 0.762)
			(end 1.524 -0.762)
			(stroke
				(width 0.1524)
				(type default)
			)
			(layer "B.SilkS")
		)
		(fp_line
			(start -1.524 -0.762)
			(end -1.524 0.762)
			(stroke
				(width 0.1524)
				(type default)
			)
			(layer "B.SilkS")
		)
		(fp_line
			(start 1.524 -0.762)
			(end -1.524 -0.762)
			(stroke
				(width 0.1524)
				(type default)
			)
			(layer "B.SilkS")
		)
		(fp_line
			(start -1.1049 0.724916)
			(end -1.1049 -0.724916)
			(stroke
				(width 0.1)
				(type default)
			)
			(layer "B.Fab")
		)
		(fp_line
			(start 1.1049 0.724916)
			(end -1.1049 0.724916)
			(stroke
				(width 0.1)
				(type default)
			)
			(layer "B.Fab")
		)
		(fp_line
			(start -1.1049 -0.724916)
			(end 1.1049 -0.724916)
			(stroke
				(width 0.1)
				(type default)
			)
			(layer "B.Fab")
		)
		(fp_line
			(start 1.1049 -0.724916)
			(end 1.1049 0.724916)
			(stroke
				(width 0.1)
				(type default)
			)
			(layer "B.Fab")
		)
		(pad "1" smd rect
			(at 0.889 0 270)
			(size 1.016 1.27)
			(layers "B.Cu" "B.Mask" "B.Paste")
			(net "P12V_S3_AUX_CPU0_NVDIMM")
		)
		(pad "2" smd rect
			(at -0.889 0 270)
			(size 1.016 1.27)
			(layers "B.Cu" "B.Mask" "B.Paste")
			(net "GND")
		)
	)
	(footprint ""
		(layer "B.Cu")
		(at 373.143018 -186.14517 -90)
		(property "Reference" "R911"
			(at 0 0 90)
			(layer "B.SilkS")
			(hide yes)
			(effects
				(font
					(size 1.27 1.27)
				)
				(justify mirror)
			)
		)
		(property "Value" ""
			(at 0 0 90)
			(layer "B.Fab")
			(effects
				(font
					(size 1.27 1.27)
				)
				(justify mirror)
			)
		)
		(duplicate_pad_numbers_are_jumpers no)
		(fp_line
			(start -0.7874 0.4064)
			(end 0.7874 0.4064)
			(stroke
				(width 0.1524)
				(type default)
			)
			(layer "B.SilkS")
		)
		(fp_line
			(start 0.7874 0.4064)
			(end 0.7874 -0.4064)
			(stroke
				(width 0.1524)
				(type default)
			)
			(layer "B.SilkS")
		)
		(fp_line
			(start -0.7874 -0.4064)
			(end -0.7874 0.4064)
			(stroke
				(width 0.1524)
				(type default)
			)
			(layer "B.SilkS")
		)
		(fp_line
			(start 0.7874 -0.4064)
			(end -0.7874 -0.4064)
			(stroke
				(width 0.1524)
				(type default)
			)
			(layer "B.SilkS")
		)
		(fp_line
			(start -0.67945 0.3048)
			(end -0.120396 0.3048)
			(stroke
				(width 0.1)
				(type default)
			)
			(layer "B.Fab")
		)
		(fp_line
			(start -0.120396 0.3048)
			(end -0.120396 0.2794)
			(stroke
				(width 0.1)
				(type default)
			)
			(layer "B.Fab")
		)
		(fp_line
			(start 0.12065 0.3048)
			(end 0.67945 0.3048)
			(stroke
				(width 0.1)
				(type default)
			)
			(layer "B.Fab")
		)
		(fp_line
			(start 0.67945 0.3048)
			(end 0.67945 -0.305054)
			(stroke
				(width 0.1)
				(type default)
			)
			(layer "B.Fab")
		)
		(fp_line
			(start -0.120396 0.2794)
			(end 0.12065 0.2794)
			(stroke
				(width 0.1)
				(type default)
			)
			(layer "B.Fab")
		)
		(fp_line
			(start 0.12065 0.2794)
			(end 0.12065 0.3048)
			(stroke
				(width 0.1)
				(type default)
			)
			(layer "B.Fab")
		)
		(fp_line
			(start -0.12065 -0.2794)
			(end -0.12065 -0.3048)
			(stroke
				(width 0.1)
				(type default)
			)
			(layer "B.Fab")
		)
		(fp_line
			(start 0.12065 -0.2794)
			(end -0.12065 -0.2794)
			(stroke
				(width 0.1)
				(type default)
			)
			(layer "B.Fab")
		)
		(fp_line
			(start -0.67945 -0.3048)
			(end -0.67945 0.3048)
			(stroke
				(width 0.1)
				(type default)
			)
			(layer "B.Fab")
		)
		(fp_line
			(start -0.12065 -0.3048)
			(end -0.67945 -0.3048)
			(stroke
				(width 0.1)
				(type default)
			)
			(layer "B.Fab")
		)
		(fp_line
			(start 0.12065 -0.305054)
			(end 0.12065 -0.2794)
			(stroke
				(width 0.1)
				(type default)
			)
			(layer "B.Fab")
		)
		(fp_line
			(start 0.67945 -0.305054)
			(end 0.12065 -0.305054)
			(stroke
				(width 0.1)
				(type default)
			)
			(layer "B.Fab")
		)
		(pad "1" smd circle
			(at 0.40005 0 90)
			(size 0 0)
			(layers "B.Cu" "B.Mask" "B.Paste")
			(net "PVNN_TERM_CPU0")
		)
		(pad "2" smd circle
			(at -0.40005 0 90)
			(size 0 0)
			(layers "B.Cu" "B.Mask" "B.Paste")
			(net "SMB_PEHPCPU0_GTL_R_SDA")
		)
	)
	(footprint ""
		(layer "B.Cu")
		(at 350.849438 -334.845152 -90)
		(property "Reference" "PR152"
			(at 0 0 90)
			(layer "B.SilkS")
			(hide yes)
			(effects
				(font
					(size 1.27 1.27)
				)
				(justify mirror)
			)
		)
		(property "Value" ""
			(at 0 0 90)
			(layer "B.Fab")
			(effects
				(font
					(size 1.27 1.27)
				)
				(justify mirror)
			)
		)
		(duplicate_pad_numbers_are_jumpers no)
		(fp_line
			(start -0.7874 0.4064)
			(end 0.7874 0.4064)
			(stroke
				(width 0.1524)
				(type default)
			)
			(layer "B.SilkS")
		)
		(fp_line
			(start 0.7874 0.4064)
			(end 0.7874 -0.4064)
			(stroke
				(width 0.1524)
				(type default)
			)
			(layer "B.SilkS")
		)
		(fp_line
			(start -0.7874 -0.4064)
			(end -0.7874 0.4064)
			(stroke
				(width 0.1524)
				(type default)
			)
			(layer "B.SilkS")
		)
		(fp_line
			(start 0.7874 -0.4064)
			(end -0.7874 -0.4064)
			(stroke
				(width 0.1524)
				(type default)
			)
			(layer "B.SilkS")
		)
		(fp_line
			(start -0.67945 0.3048)
			(end -0.120396 0.3048)
			(stroke
				(width 0.1)
				(type default)
			)
			(layer "B.Fab")
		)
		(fp_line
			(start -0.120396 0.3048)
			(end -0.120396 0.2794)
			(stroke
				(width 0.1)
				(type default)
			)
			(layer "B.Fab")
		)
		(fp_line
			(start 0.12065 0.3048)
			(end 0.67945 0.3048)
			(stroke
				(width 0.1)
				(type default)
			)
			(layer "B.Fab")
		)
		(fp_line
			(start 0.67945 0.3048)
			(end 0.67945 -0.305054)
			(stroke
				(width 0.1)
				(type default)
			)
			(layer "B.Fab")
		)
		(fp_line
			(start -0.120396 0.2794)
			(end 0.12065 0.2794)
			(stroke
				(width 0.1)
				(type default)
			)
			(layer "B.Fab")
		)
		(fp_line
			(start 0.12065 0.2794)
			(end 0.12065 0.3048)
			(stroke
				(width 0.1)
				(type default)
			)
			(layer "B.Fab")
		)
		(fp_line
			(start -0.12065 -0.2794)
			(end -0.12065 -0.3048)
			(stroke
				(width 0.1)
				(type default)
			)
			(layer "B.Fab")
		)
		(fp_line
			(start 0.12065 -0.2794)
			(end -0.12065 -0.2794)
			(stroke
				(width 0.1)
				(type default)
			)
			(layer "B.Fab")
		)
		(fp_line
			(start -0.67945 -0.3048)
			(end -0.67945 0.3048)
			(stroke
				(width 0.1)
				(type default)
			)
			(layer "B.Fab")
		)
		(fp_line
			(start -0.12065 -0.3048)
			(end -0.67945 -0.3048)
			(stroke
				(width 0.1)
				(type default)
			)
			(layer "B.Fab")
		)
		(fp_line
			(start 0.12065 -0.305054)
			(end 0.12065 -0.2794)
			(stroke
				(width 0.1)
				(type default)
			)
			(layer "B.Fab")
		)
		(fp_line
			(start 0.67945 -0.305054)
			(end 0.12065 -0.305054)
			(stroke
				(width 0.1)
				(type default)
			)
			(layer "B.Fab")
		)
		(pad "1" smd circle
			(at 0.40005 0 90)
			(size 0 0)
			(layers "B.Cu" "B.Mask" "B.Paste")
			(net "PVCCIN_CPU0_PVCC")
		)
		(pad "2" smd circle
			(at -0.40005 0 90)
			(size 0 0)
			(layers "B.Cu" "B.Mask" "B.Paste")
			(net "PVCCIN_CPU0_VDD2")
		)
	)
	(footprint ""
		(layer "B.Cu")
		(at 120.145302 -262.032496 -90)
		(property "Reference" "C490"
			(at 0 0 90)
			(layer "B.SilkS")
			(hide yes)
			(effects
				(font
					(size 1.27 1.27)
				)
				(justify mirror)
			)
		)
		(property "Value" ""
			(at 0 0 90)
			(layer "B.Fab")
			(effects
				(font
					(size 1.27 1.27)
				)
				(justify mirror)
			)
		)
		(duplicate_pad_numbers_are_jumpers no)
		(fp_line
			(start -0.7874 0.4064)
			(end 0.7874 0.4064)
			(stroke
				(width 0.1524)
				(type default)
			)
			(layer "B.SilkS")
		)
		(fp_line
			(start 0.7874 0.4064)
			(end 0.7874 -0.4064)
			(stroke
				(width 0.1524)
				(type default)
			)
			(layer "B.SilkS")
		)
		(fp_line
			(start -0.7874 -0.4064)
			(end -0.7874 0.4064)
			(stroke
				(width 0.1524)
				(type default)
			)
			(layer "B.SilkS")
		)
		(fp_line
			(start 0.7874 -0.4064)
			(end -0.7874 -0.4064)
			(stroke
				(width 0.1524)
				(type default)
			)
			(layer "B.SilkS")
		)
		(fp_line
			(start -0.67945 0.3048)
			(end -0.120396 0.3048)
			(stroke
				(width 0.1)
				(type default)
			)
			(layer "B.Fab")
		)
		(fp_line
			(start -0.120396 0.3048)
			(end -0.120396 0.2794)
			(stroke
				(width 0.1)
				(type default)
			)
			(layer "B.Fab")
		)
		(fp_line
			(start 0.12065 0.3048)
			(end 0.67945 0.3048)
			(stroke
				(width 0.1)
				(type default)
			)
			(layer "B.Fab")
		)
		(fp_line
			(start 0.67945 0.3048)
			(end 0.67945 -0.305054)
			(stroke
				(width 0.1)
				(type default)
			)
			(layer "B.Fab")
		)
		(fp_line
			(start -0.120396 0.2794)
			(end 0.12065 0.2794)
			(stroke
				(width 0.1)
				(type default)
			)
			(layer "B.Fab")
		)
		(fp_line
			(start 0.12065 0.2794)
			(end 0.12065 0.3048)
			(stroke
				(width 0.1)
				(type default)
			)
			(layer "B.Fab")
		)
		(fp_line
			(start -0.12065 -0.2794)
			(end -0.12065 -0.3048)
			(stroke
				(width 0.1)
				(type default)
			)
			(layer "B.Fab")
		)
		(fp_line
			(start 0.12065 -0.2794)
			(end -0.12065 -0.2794)
			(stroke
				(width 0.1)
				(type default)
			)
			(layer "B.Fab")
		)
		(fp_line
			(start -0.67945 -0.3048)
			(end -0.67945 0.3048)
			(stroke
				(width 0.1)
				(type default)
			)
			(layer "B.Fab")
		)
		(fp_line
			(start -0.12065 -0.3048)
			(end -0.67945 -0.3048)
			(stroke
				(width 0.1)
				(type default)
			)
			(layer "B.Fab")
		)
		(fp_line
			(start 0.12065 -0.305054)
			(end 0.12065 -0.2794)
			(stroke
				(width 0.1)
				(type default)
			)
			(layer "B.Fab")
		)
		(fp_line
			(start 0.67945 -0.305054)
			(end 0.12065 -0.305054)
			(stroke
				(width 0.1)
				(type default)
			)
			(layer "B.Fab")
		)
		(pad "1" smd circle
			(at 0.40005 0 90)
			(size 0 0)
			(layers "B.Cu" "B.Mask" "B.Paste")
			(net "PVCCINFAON_CPU1")
		)
		(pad "2" smd circle
			(at -0.40005 0 90)
			(size 0 0)
			(layers "B.Cu" "B.Mask" "B.Paste")
			(net "GND")
		)
	)
	(footprint ""
		(layer "B.Cu")
		(at 431.72888 -124.932948 90)
		(property "Reference" "PR4234"
			(at 0 0 90)
			(layer "B.SilkS")
			(hide yes)
			(effects
				(font
					(size 1.27 1.27)
				)
				(justify mirror)
			)
		)
		(property "Value" ""
			(at 0 0 90)
			(layer "B.Fab")
			(effects
				(font
					(size 1.27 1.27)
				)
				(justify mirror)
			)
		)
		(duplicate_pad_numbers_are_jumpers no)
		(fp_line
			(start 0.7874 -0.4064)
			(end -0.7874 -0.4064)
			(stroke
				(width 0.1524)
				(type default)
			)
			(layer "B.SilkS")
		)
		(fp_line
			(start -0.7874 -0.4064)
			(end -0.7874 0.4064)
			(stroke
				(width 0.1524)
				(type default)
			)
			(layer "B.SilkS")
		)
		(fp_line
			(start 0.7874 0.4064)
			(end 0.7874 -0.4064)
			(stroke
				(width 0.1524)
				(type default)
			)
			(layer "B.SilkS")
		)
		(fp_line
			(start -0.7874 0.4064)
			(end 0.7874 0.4064)
			(stroke
				(width 0.1524)
				(type default)
			)
			(layer "B.SilkS")
		)
		(fp_line
			(start 0.67945 -0.305054)
			(end 0.12065 -0.305054)
			(stroke
				(width 0.1)
				(type default)
			)
			(layer "B.Fab")
		)
		(fp_line
			(start 0.12065 -0.305054)
			(end 0.12065 -0.2794)
			(stroke
				(width 0.1)
				(type default)
			)
			(layer "B.Fab")
		)
		(fp_line
			(start -0.12065 -0.3048)
			(end -0.67945 -0.3048)
			(stroke
				(width 0.1)
				(type default)
			)
			(layer "B.Fab")
		)
		(fp_line
			(start -0.67945 -0.3048)
			(end -0.67945 0.3048)
			(stroke
				(width 0.1)
				(type default)
			)
			(layer "B.Fab")
		)
		(fp_line
			(start 0.12065 -0.2794)
			(end -0.12065 -0.2794)
			(stroke
				(width 0.1)
				(type default)
			)
			(layer "B.Fab")
		)
		(fp_line
			(start -0.12065 -0.2794)
			(end -0.12065 -0.3048)
			(stroke
				(width 0.1)
				(type default)
			)
			(layer "B.Fab")
		)
		(fp_line
			(start 0.12065 0.2794)
			(end 0.12065 0.3048)
			(stroke
				(width 0.1)
				(type default)
			)
			(layer "B.Fab")
		)
		(fp_line
			(start -0.120396 0.2794)
			(end 0.12065 0.2794)
			(stroke
				(width 0.1)
				(type default)
			)
			(layer "B.Fab")
		)
		(fp_line
			(start 0.67945 0.3048)
			(end 0.67945 -0.305054)
			(stroke
				(width 0.1)
				(type default)
			)
			(layer "B.Fab")
		)
		(fp_line
			(start 0.12065 0.3048)
			(end 0.67945 0.3048)
			(stroke
				(width 0.1)
				(type default)
			)
			(layer "B.Fab")
		)
		(fp_line
			(start -0.120396 0.3048)
			(end -0.120396 0.2794)
			(stroke
				(width 0.1)
				(type default)
			)
			(layer "B.Fab")
		)
		(fp_line
			(start -0.67945 0.3048)
			(end -0.120396 0.3048)
			(stroke
				(width 0.1)
				(type default)
			)
			(layer "B.Fab")
		)
		(pad "1" smd circle
			(at 0.40005 0 270)
			(size 0 0)
			(layers "B.Cu" "B.Mask" "B.Paste")
			(net "NC_PVCCD_HV_CPU0_ACSP6")
		)
		(pad "2" smd circle
			(at -0.40005 0 270)
			(size 0 0)
			(layers "B.Cu" "B.Mask" "B.Paste")
			(net "GND")
		)
	)
	(footprint ""
		(layer "B.Cu")
		(at 432.523392 -193.565272 -90)
		(property "Reference" "C621"
			(at 0 0 90)
			(layer "B.SilkS")
			(hide yes)
			(effects
				(font
					(size 1.27 1.27)
				)
				(justify mirror)
			)
		)
		(property "Value" ""
			(at 0 0 90)
			(layer "B.Fab")
			(effects
				(font
					(size 1.27 1.27)
				)
				(justify mirror)
			)
		)
		(duplicate_pad_numbers_are_jumpers no)
		(fp_line
			(start -0.7874 0.4064)
			(end 0.7874 0.4064)
			(stroke
				(width 0.1524)
				(type default)
			)
			(layer "B.SilkS")
		)
		(fp_line
			(start 0.7874 0.4064)
			(end 0.7874 -0.4064)
			(stroke
				(width 0.1524)
				(type default)
			)
			(layer "B.SilkS")
		)
		(fp_line
			(start -0.7874 -0.4064)
			(end -0.7874 0.4064)
			(stroke
				(width 0.1524)
				(type default)
			)
			(layer "B.SilkS")
		)
		(fp_line
			(start 0.7874 -0.4064)
			(end -0.7874 -0.4064)
			(stroke
				(width 0.1524)
				(type default)
			)
			(layer "B.SilkS")
		)
		(fp_line
			(start -0.67945 0.3048)
			(end -0.120396 0.3048)
			(stroke
				(width 0.1)
				(type default)
			)
			(layer "B.Fab")
		)
		(fp_line
			(start -0.120396 0.3048)
			(end -0.120396 0.2794)
			(stroke
				(width 0.1)
				(type default)
			)
			(layer "B.Fab")
		)
		(fp_line
			(start 0.12065 0.3048)
			(end 0.67945 0.3048)
			(stroke
				(width 0.1)
				(type default)
			)
			(layer "B.Fab")
		)
		(fp_line
			(start 0.67945 0.3048)
			(end 0.67945 -0.305054)
			(stroke
				(width 0.1)
				(type default)
			)
			(layer "B.Fab")
		)
		(fp_line
			(start -0.120396 0.2794)
			(end 0.12065 0.2794)
			(stroke
				(width 0.1)
				(type default)
			)
			(layer "B.Fab")
		)
		(fp_line
			(start 0.12065 0.2794)
			(end 0.12065 0.3048)
			(stroke
				(width 0.1)
				(type default)
			)
			(layer "B.Fab")
		)
		(fp_line
			(start -0.12065 -0.2794)
			(end -0.12065 -0.3048)
			(stroke
				(width 0.1)
				(type default)
			)
			(layer "B.Fab")
		)
		(fp_line
			(start 0.12065 -0.2794)
			(end -0.12065 -0.2794)
			(stroke
				(width 0.1)
				(type default)
			)
			(layer "B.Fab")
		)
		(fp_line
			(start -0.67945 -0.3048)
			(end -0.67945 0.3048)
			(stroke
				(width 0.1)
				(type default)
			)
			(layer "B.Fab")
		)
		(fp_line
			(start -0.12065 -0.3048)
			(end -0.67945 -0.3048)
			(stroke
				(width 0.1)
				(type default)
			)
			(layer "B.Fab")
		)
		(fp_line
			(start 0.12065 -0.305054)
			(end 0.12065 -0.2794)
			(stroke
				(width 0.1)
				(type default)
			)
			(layer "B.Fab")
		)
		(fp_line
			(start 0.67945 -0.305054)
			(end 0.12065 -0.305054)
			(stroke
				(width 0.1)
				(type default)
			)
			(layer "B.Fab")
		)
		(pad "1" smd circle
			(at 0.40005 0 90)
			(size 0 0)
			(layers "B.Cu" "B.Mask" "B.Paste")
			(net "RST_PLD_CPU0_DRAM_GH_N")
		)
		(pad "2" smd circle
			(at -0.40005 0 90)
			(size 0 0)
			(layers "B.Cu" "B.Mask" "B.Paste")
			(net "GND")
		)
	)
	(footprint ""
		(layer "B.Cu")
		(at 410.156152 -193.08953 -90)
		(property "Reference" "R281"
			(at 0 0 90)
			(layer "B.SilkS")
			(hide yes)
			(effects
				(font
					(size 1.27 1.27)
				)
				(justify mirror)
			)
		)
		(property "Value" ""
			(at 0 0 90)
			(layer "B.Fab")
			(effects
				(font
					(size 1.27 1.27)
				)
				(justify mirror)
			)
		)
		(duplicate_pad_numbers_are_jumpers no)
		(fp_line
			(start -0.7874 0.4064)
			(end 0.7874 0.4064)
			(stroke
				(width 0.1524)
				(type default)
			)
			(layer "B.SilkS")
		)
		(fp_line
			(start 0.7874 0.4064)
			(end 0.7874 -0.4064)
			(stroke
				(width 0.1524)
				(type default)
			)
			(layer "B.SilkS")
		)
		(fp_line
			(start -0.7874 -0.4064)
			(end -0.7874 0.4064)
			(stroke
				(width 0.1524)
				(type default)
			)
			(layer "B.SilkS")
		)
		(fp_line
			(start 0.7874 -0.4064)
			(end -0.7874 -0.4064)
			(stroke
				(width 0.1524)
				(type default)
			)
			(layer "B.SilkS")
		)
		(fp_line
			(start -0.67945 0.3048)
			(end -0.120396 0.3048)
			(stroke
				(width 0.1)
				(type default)
			)
			(layer "B.Fab")
		)
		(fp_line
			(start -0.120396 0.3048)
			(end -0.120396 0.2794)
			(stroke
				(width 0.1)
				(type default)
			)
			(layer "B.Fab")
		)
		(fp_line
			(start 0.12065 0.3048)
			(end 0.67945 0.3048)
			(stroke
				(width 0.1)
				(type default)
			)
			(layer "B.Fab")
		)
		(fp_line
			(start 0.67945 0.3048)
			(end 0.67945 -0.305054)
			(stroke
				(width 0.1)
				(type default)
			)
			(layer "B.Fab")
		)
		(fp_line
			(start -0.120396 0.2794)
			(end 0.12065 0.2794)
			(stroke
				(width 0.1)
				(type default)
			)
			(layer "B.Fab")
		)
		(fp_line
			(start 0.12065 0.2794)
			(end 0.12065 0.3048)
			(stroke
				(width 0.1)
				(type default)
			)
			(layer "B.Fab")
		)
		(fp_line
			(start -0.12065 -0.2794)
			(end -0.12065 -0.3048)
			(stroke
				(width 0.1)
				(type default)
			)
			(layer "B.Fab")
		)
		(fp_line
			(start 0.12065 -0.2794)
			(end -0.12065 -0.2794)
			(stroke
				(width 0.1)
				(type default)
			)
			(layer "B.Fab")
		)
		(fp_line
			(start -0.67945 -0.3048)
			(end -0.67945 0.3048)
			(stroke
				(width 0.1)
				(type default)
			)
			(layer "B.Fab")
		)
		(fp_line
			(start -0.12065 -0.3048)
			(end -0.67945 -0.3048)
			(stroke
				(width 0.1)
				(type default)
			)
			(layer "B.Fab")
		)
		(fp_line
			(start 0.12065 -0.305054)
			(end 0.12065 -0.2794)
			(stroke
				(width 0.1)
				(type default)
			)
			(layer "B.Fab")
		)
		(fp_line
			(start 0.67945 -0.305054)
			(end 0.12065 -0.305054)
			(stroke
				(width 0.1)
				(type default)
			)
			(layer "B.Fab")
		)
		(pad "1" smd circle
			(at 0.40005 0 90)
			(size 0 0)
			(layers "B.Cu" "B.Mask" "B.Paste")
			(net "PVNN_TERM_CPU0")
		)
		(pad "2" smd circle
			(at -0.40005 0 90)
			(size 0 0)
			(layers "B.Cu" "B.Mask" "B.Paste")
			(net "PU_CPU0_SOCKET_ID2")
		)
	)
	(footprint ""
		(layer "B.Cu")
		(at 157.02788 -112.486948 180)
		(property "Reference" "R3479"
			(at 0 0 0)
			(layer "B.SilkS")
			(hide yes)
			(effects
				(font
					(size 1.27 1.27)
				)
				(justify mirror)
			)
		)
		(property "Value" ""
			(at 0 0 0)
			(layer "B.Fab")
			(effects
				(font
					(size 1.27 1.27)
				)
				(justify mirror)
			)
		)
		(duplicate_pad_numbers_are_jumpers no)
		(fp_line
			(start 0.7874 0.4064)
			(end 0.7874 -0.4064)
			(stroke
				(width 0.1524)
				(type default)
			)
			(layer "B.SilkS")
		)
		(fp_line
			(start 0.7874 -0.4064)
			(end -0.7874 -0.4064)
			(stroke
				(width 0.1524)
				(type default)
			)
			(layer "B.SilkS")
		)
		(fp_line
			(start -0.7874 0.4064)
			(end 0.7874 0.4064)
			(stroke
				(width 0.1524)
				(type default)
			)
			(layer "B.SilkS")
		)
		(fp_line
			(start -0.7874 -0.4064)
			(end -0.7874 0.4064)
			(stroke
				(width 0.1524)
				(type default)
			)
			(layer "B.SilkS")
		)
		(fp_line
			(start 0.67945 0.3048)
			(end 0.67945 -0.305054)
			(stroke
				(width 0.1)
				(type default)
			)
			(layer "B.Fab")
		)
		(fp_line
			(start 0.67945 -0.305054)
			(end 0.12065 -0.305054)
			(stroke
				(width 0.1)
				(type default)
			)
			(layer "B.Fab")
		)
		(fp_line
			(start 0.12065 0.3048)
			(end 0.67945 0.3048)
			(stroke
				(width 0.1)
				(type default)
			)
			(layer "B.Fab")
		)
		(fp_line
			(start 0.12065 0.2794)
			(end 0.12065 0.3048)
			(stroke
				(width 0.1)
				(type default)
			)
			(layer "B.Fab")
		)
		(fp_line
			(start 0.12065 -0.2794)
			(end -0.12065 -0.2794)
			(stroke
				(width 0.1)
				(type default)
			)
			(layer "B.Fab")
		)
		(fp_line
			(start 0.12065 -0.305054)
			(end 0.12065 -0.2794)
			(stroke
				(width 0.1)
				(type default)
			)
			(layer "B.Fab")
		)
		(fp_line
			(start -0.120396 0.3048)
			(end -0.120396 0.2794)
			(stroke
				(width 0.1)
				(type default)
			)
			(layer "B.Fab")
		)
		(fp_line
			(start -0.120396 0.2794)
			(end 0.12065 0.2794)
			(stroke
				(width 0.1)
				(type default)
			)
			(layer "B.Fab")
		)
		(fp_line
			(start -0.12065 -0.2794)
			(end -0.12065 -0.3048)
			(stroke
				(width 0.1)
				(type default)
			)
			(layer "B.Fab")
		)
		(fp_line
			(start -0.12065 -0.3048)
			(end -0.67945 -0.3048)
			(stroke
				(width 0.1)
				(type default)
			)
			(layer "B.Fab")
		)
		(fp_line
			(start -0.67945 0.3048)
			(end -0.120396 0.3048)
			(stroke
				(width 0.1)
				(type default)
			)
			(layer "B.Fab")
		)
		(fp_line
			(start -0.67945 -0.3048)
			(end -0.67945 0.3048)
			(stroke
				(width 0.1)
				(type default)
			)
			(layer "B.Fab")
		)
		(pad "1" smd circle
			(at 0.40005 0)
			(size 0 0)
			(layers "B.Cu" "B.Mask" "B.Paste")
			(net "GPU_BASE_STBY_EN")
		)
		(pad "2" smd circle
			(at -0.40005 0)
			(size 0 0)
			(layers "B.Cu" "B.Mask" "B.Paste")
			(net "GPU_BASE_STBY_EN_R")
		)
	)
	(footprint ""
		(layer "B.Cu")
		(at 374.00484 -339.602572 -90)
		(property "Reference" "PR143"
			(at 0 0 90)
			(layer "B.SilkS")
			(hide yes)
			(effects
				(font
					(size 1.27 1.27)
				)
				(justify mirror)
			)
		)
		(property "Value" ""
			(at 0 0 90)
			(layer "B.Fab")
			(effects
				(font
					(size 1.27 1.27)
				)
				(justify mirror)
			)
		)
		(duplicate_pad_numbers_are_jumpers no)
		(fp_line
			(start -0.7874 0.4064)
			(end 0.7874 0.4064)
			(stroke
				(width 0.1524)
				(type default)
			)
			(layer "B.SilkS")
		)
		(fp_line
			(start 0.7874 0.4064)
			(end 0.7874 -0.4064)
			(stroke
				(width 0.1524)
				(type default)
			)
			(layer "B.SilkS")
		)
		(fp_line
			(start -0.7874 -0.4064)
			(end -0.7874 0.4064)
			(stroke
				(width 0.1524)
				(type default)
			)
			(layer "B.SilkS")
		)
		(fp_line
			(start 0.7874 -0.4064)
			(end -0.7874 -0.4064)
			(stroke
				(width 0.1524)
				(type default)
			)
			(layer "B.SilkS")
		)
		(fp_line
			(start -0.67945 0.3048)
			(end -0.120396 0.3048)
			(stroke
				(width 0.1)
				(type default)
			)
			(layer "B.Fab")
		)
		(fp_line
			(start -0.120396 0.3048)
			(end -0.120396 0.2794)
			(stroke
				(width 0.1)
				(type default)
			)
			(layer "B.Fab")
		)
		(fp_line
			(start 0.12065 0.3048)
			(end 0.67945 0.3048)
			(stroke
				(width 0.1)
				(type default)
			)
			(layer "B.Fab")
		)
		(fp_line
			(start 0.67945 0.3048)
			(end 0.67945 -0.305054)
			(stroke
				(width 0.1)
				(type default)
			)
			(layer "B.Fab")
		)
		(fp_line
			(start -0.120396 0.2794)
			(end 0.12065 0.2794)
			(stroke
				(width 0.1)
				(type default)
			)
			(layer "B.Fab")
		)
		(fp_line
			(start 0.12065 0.2794)
			(end 0.12065 0.3048)
			(stroke
				(width 0.1)
				(type default)
			)
			(layer "B.Fab")
		)
		(fp_line
			(start -0.12065 -0.2794)
			(end -0.12065 -0.3048)
			(stroke
				(width 0.1)
				(type default)
			)
			(layer "B.Fab")
		)
		(fp_line
			(start 0.12065 -0.2794)
			(end -0.12065 -0.2794)
			(stroke
				(width 0.1)
				(type default)
			)
			(layer "B.Fab")
		)
		(fp_line
			(start -0.67945 -0.3048)
			(end -0.67945 0.3048)
			(stroke
				(width 0.1)
				(type default)
			)
			(layer "B.Fab")
		)
		(fp_line
			(start -0.12065 -0.3048)
			(end -0.67945 -0.3048)
			(stroke
				(width 0.1)
				(type default)
			)
			(layer "B.Fab")
		)
		(fp_line
			(start 0.12065 -0.305054)
			(end 0.12065 -0.2794)
			(stroke
				(width 0.1)
				(type default)
			)
			(layer "B.Fab")
		)
		(fp_line
			(start 0.67945 -0.305054)
			(end 0.12065 -0.305054)
			(stroke
				(width 0.1)
				(type default)
			)
			(layer "B.Fab")
		)
		(pad "1" smd circle
			(at 0.40005 0 90)
			(size 0 0)
			(layers "B.Cu" "B.Mask" "B.Paste")
			(net "PVCCIN_CPU0_VOS5")
		)
		(pad "2" smd circle
			(at -0.40005 0 90)
			(size 0 0)
			(layers "B.Cu" "B.Mask" "B.Paste")
			(net "PVCCIN_CPU0")
		)
	)
	(footprint ""
		(layer "B.Cu")
		(at 284.925262 -365.653066 -90)
		(property "Reference" "PR1325"
			(at 0 0 90)
			(layer "B.SilkS")
			(hide yes)
			(effects
				(font
					(size 1.27 1.27)
				)
				(justify mirror)
			)
		)
		(property "Value" ""
			(at 0 0 90)
			(layer "B.Fab")
			(effects
				(font
					(size 1.27 1.27)
				)
				(justify mirror)
			)
		)
		(duplicate_pad_numbers_are_jumpers no)
		(fp_line
			(start -0.7874 0.4064)
			(end 0.7874 0.4064)
			(stroke
				(width 0.1524)
				(type default)
			)
			(layer "B.SilkS")
		)
		(fp_line
			(start 0.7874 0.4064)
			(end 0.7874 -0.4064)
			(stroke
				(width 0.1524)
				(type default)
			)
			(layer "B.SilkS")
		)
		(fp_line
			(start -0.7874 -0.4064)
			(end -0.7874 0.4064)
			(stroke
				(width 0.1524)
				(type default)
			)
			(layer "B.SilkS")
		)
		(fp_line
			(start 0.7874 -0.4064)
			(end -0.7874 -0.4064)
			(stroke
				(width 0.1524)
				(type default)
			)
			(layer "B.SilkS")
		)
		(fp_line
			(start -0.67945 0.3048)
			(end -0.120396 0.3048)
			(stroke
				(width 0.1)
				(type default)
			)
			(layer "B.Fab")
		)
		(fp_line
			(start -0.120396 0.3048)
			(end -0.120396 0.2794)
			(stroke
				(width 0.1)
				(type default)
			)
			(layer "B.Fab")
		)
		(fp_line
			(start 0.12065 0.3048)
			(end 0.67945 0.3048)
			(stroke
				(width 0.1)
				(type default)
			)
			(layer "B.Fab")
		)
		(fp_line
			(start 0.67945 0.3048)
			(end 0.67945 -0.305054)
			(stroke
				(width 0.1)
				(type default)
			)
			(layer "B.Fab")
		)
		(fp_line
			(start -0.120396 0.2794)
			(end 0.12065 0.2794)
			(stroke
				(width 0.1)
				(type default)
			)
			(layer "B.Fab")
		)
		(fp_line
			(start 0.12065 0.2794)
			(end 0.12065 0.3048)
			(stroke
				(width 0.1)
				(type default)
			)
			(layer "B.Fab")
		)
		(fp_line
			(start -0.12065 -0.2794)
			(end -0.12065 -0.3048)
			(stroke
				(width 0.1)
				(type default)
			)
			(layer "B.Fab")
		)
		(fp_line
			(start 0.12065 -0.2794)
			(end -0.12065 -0.2794)
			(stroke
				(width 0.1)
				(type default)
			)
			(layer "B.Fab")
		)
		(fp_line
			(start -0.67945 -0.3048)
			(end -0.67945 0.3048)
			(stroke
				(width 0.1)
				(type default)
			)
			(layer "B.Fab")
		)
		(fp_line
			(start -0.12065 -0.3048)
			(end -0.67945 -0.3048)
			(stroke
				(width 0.1)
				(type default)
			)
			(layer "B.Fab")
		)
		(fp_line
			(start 0.12065 -0.305054)
			(end 0.12065 -0.2794)
			(stroke
				(width 0.1)
				(type default)
			)
			(layer "B.Fab")
		)
		(fp_line
			(start 0.67945 -0.305054)
			(end 0.12065 -0.305054)
			(stroke
				(width 0.1)
				(type default)
			)
			(layer "B.Fab")
		)
		(pad "1" smd circle
			(at 0.40005 0 90)
			(size 0 0)
			(layers "B.Cu" "B.Mask" "B.Paste")
			(net "PVCCFA_EHV_FIVRA_CPU0_VOS4")
		)
		(pad "2" smd circle
			(at -0.40005 0 90)
			(size 0 0)
			(layers "B.Cu" "B.Mask" "B.Paste")
			(net "PVCCFA_EHV_FIVRA_CPU0")
		)
	)
	(footprint ""
		(layer "B.Cu")
		(at 295.93413 -400.999452 -90)
		(property "Reference" "PR2522"
			(at 0 0 90)
			(layer "B.SilkS")
			(hide yes)
			(effects
				(font
					(size 1.27 1.27)
				)
				(justify mirror)
			)
		)
		(property "Value" ""
			(at 0 0 90)
			(layer "B.Fab")
			(effects
				(font
					(size 1.27 1.27)
				)
				(justify mirror)
			)
		)
		(duplicate_pad_numbers_are_jumpers no)
		(fp_line
			(start -0.7874 0.4064)
			(end 0.7874 0.4064)
			(stroke
				(width 0.1524)
				(type default)
			)
			(layer "B.SilkS")
		)
		(fp_line
			(start 0.7874 0.4064)
			(end 0.7874 -0.4064)
			(stroke
				(width 0.1524)
				(type default)
			)
			(layer "B.SilkS")
		)
		(fp_line
			(start -0.7874 -0.4064)
			(end -0.7874 0.4064)
			(stroke
				(width 0.1524)
				(type default)
			)
			(layer "B.SilkS")
		)
		(fp_line
			(start 0.7874 -0.4064)
			(end -0.7874 -0.4064)
			(stroke
				(width 0.1524)
				(type default)
			)
			(layer "B.SilkS")
		)
		(fp_line
			(start -0.67945 0.3048)
			(end -0.120396 0.3048)
			(stroke
				(width 0.1)
				(type default)
			)
			(layer "B.Fab")
		)
		(fp_line
			(start -0.120396 0.3048)
			(end -0.120396 0.2794)
			(stroke
				(width 0.1)
				(type default)
			)
			(layer "B.Fab")
		)
		(fp_line
			(start 0.12065 0.3048)
			(end 0.67945 0.3048)
			(stroke
				(width 0.1)
				(type default)
			)
			(layer "B.Fab")
		)
		(fp_line
			(start 0.67945 0.3048)
			(end 0.67945 -0.305054)
			(stroke
				(width 0.1)
				(type default)
			)
			(layer "B.Fab")
		)
		(fp_line
			(start -0.120396 0.2794)
			(end 0.12065 0.2794)
			(stroke
				(width 0.1)
				(type default)
			)
			(layer "B.Fab")
		)
		(fp_line
			(start 0.12065 0.2794)
			(end 0.12065 0.3048)
			(stroke
				(width 0.1)
				(type default)
			)
			(layer "B.Fab")
		)
		(fp_line
			(start -0.12065 -0.2794)
			(end -0.12065 -0.3048)
			(stroke
				(width 0.1)
				(type default)
			)
			(layer "B.Fab")
		)
		(fp_line
			(start 0.12065 -0.2794)
			(end -0.12065 -0.2794)
			(stroke
				(width 0.1)
				(type default)
			)
			(layer "B.Fab")
		)
		(fp_line
			(start -0.67945 -0.3048)
			(end -0.67945 0.3048)
			(stroke
				(width 0.1)
				(type default)
			)
			(layer "B.Fab")
		)
		(fp_line
			(start -0.12065 -0.3048)
			(end -0.67945 -0.3048)
			(stroke
				(width 0.1)
				(type default)
			)
			(layer "B.Fab")
		)
		(fp_line
			(start 0.12065 -0.305054)
			(end 0.12065 -0.2794)
			(stroke
				(width 0.1)
				(type default)
			)
			(layer "B.Fab")
		)
		(fp_line
			(start 0.67945 -0.305054)
			(end 0.12065 -0.305054)
			(stroke
				(width 0.1)
				(type default)
			)
			(layer "B.Fab")
		)
		(pad "1" smd circle
			(at 0.40005 0 90)
			(size 0 0)
			(layers "B.Cu" "B.Mask" "B.Paste")
			(net "P12V_HSC_SENSE2_P")
		)
		(pad "2" smd circle
			(at -0.40005 0 90)
			(size 0 0)
			(layers "B.Cu" "B.Mask" "B.Paste")
			(net "P12V_HSC_SENSE2_R3_P")
		)
	)
	(footprint ""
		(layer "B.Cu")
		(at 100.306886 -359.788714 180)
		(property "Reference" "R2551"
			(at 0 0 0)
			(layer "B.SilkS")
			(hide yes)
			(effects
				(font
					(size 1.27 1.27)
				)
				(justify mirror)
			)
		)
		(property "Value" ""
			(at 0 0 0)
			(layer "B.Fab")
			(effects
				(font
					(size 1.27 1.27)
				)
				(justify mirror)
			)
		)
		(duplicate_pad_numbers_are_jumpers no)
		(fp_line
			(start 0.7874 0.4064)
			(end 0.7874 -0.4064)
			(stroke
				(width 0.1524)
				(type default)
			)
			(layer "B.SilkS")
		)
		(fp_line
			(start 0.7874 -0.4064)
			(end -0.7874 -0.4064)
			(stroke
				(width 0.1524)
				(type default)
			)
			(layer "B.SilkS")
		)
		(fp_line
			(start -0.7874 0.4064)
			(end 0.7874 0.4064)
			(stroke
				(width 0.1524)
				(type default)
			)
			(layer "B.SilkS")
		)
		(fp_line
			(start -0.7874 -0.4064)
			(end -0.7874 0.4064)
			(stroke
				(width 0.1524)
				(type default)
			)
			(layer "B.SilkS")
		)
		(fp_line
			(start 0.67945 0.3048)
			(end 0.67945 -0.305054)
			(stroke
				(width 0.1)
				(type default)
			)
			(layer "B.Fab")
		)
		(fp_line
			(start 0.67945 -0.305054)
			(end 0.12065 -0.305054)
			(stroke
				(width 0.1)
				(type default)
			)
			(layer "B.Fab")
		)
		(fp_line
			(start 0.12065 0.3048)
			(end 0.67945 0.3048)
			(stroke
				(width 0.1)
				(type default)
			)
			(layer "B.Fab")
		)
		(fp_line
			(start 0.12065 0.2794)
			(end 0.12065 0.3048)
			(stroke
				(width 0.1)
				(type default)
			)
			(layer "B.Fab")
		)
		(fp_line
			(start 0.12065 -0.2794)
			(end -0.12065 -0.2794)
			(stroke
				(width 0.1)
				(type default)
			)
			(layer "B.Fab")
		)
		(fp_line
			(start 0.12065 -0.305054)
			(end 0.12065 -0.2794)
			(stroke
				(width 0.1)
				(type default)
			)
			(layer "B.Fab")
		)
		(fp_line
			(start -0.120396 0.3048)
			(end -0.120396 0.2794)
			(stroke
				(width 0.1)
				(type default)
			)
			(layer "B.Fab")
		)
		(fp_line
			(start -0.120396 0.2794)
			(end 0.12065 0.2794)
			(stroke
				(width 0.1)
				(type default)
			)
			(layer "B.Fab")
		)
		(fp_line
			(start -0.12065 -0.2794)
			(end -0.12065 -0.3048)
			(stroke
				(width 0.1)
				(type default)
			)
			(layer "B.Fab")
		)
		(fp_line
			(start -0.12065 -0.3048)
			(end -0.67945 -0.3048)
			(stroke
				(width 0.1)
				(type default)
			)
			(layer "B.Fab")
		)
		(fp_line
			(start -0.67945 0.3048)
			(end -0.120396 0.3048)
			(stroke
				(width 0.1)
				(type default)
			)
			(layer "B.Fab")
		)
		(fp_line
			(start -0.67945 -0.3048)
			(end -0.67945 0.3048)
			(stroke
				(width 0.1)
				(type default)
			)
			(layer "B.Fab")
		)
		(pad "1" smd circle
			(at 0.40005 0)
			(size 0 0)
			(layers "B.Cu" "B.Mask" "B.Paste")
			(net "P3V3_AUX")
		)
		(pad "2" smd circle
			(at -0.40005 0)
			(size 0 0)
			(layers "B.Cu" "B.Mask" "B.Paste")
			(net "PWRGD_PVCCFA_EHV_FIVRA_CPU1_R")
		)
	)
	(footprint ""
		(layer "B.Cu")
		(at 238.161322 -130.3909 -90)
		(property "Reference" "R578"
			(at 0 0 90)
			(layer "B.SilkS")
			(hide yes)
			(effects
				(font
					(size 1.27 1.27)
				)
				(justify mirror)
			)
		)
		(property "Value" ""
			(at 0 0 90)
			(layer "B.Fab")
			(effects
				(font
					(size 1.27 1.27)
				)
				(justify mirror)
			)
		)
		(duplicate_pad_numbers_are_jumpers no)
		(fp_line
			(start -0.7874 0.4064)
			(end 0.7874 0.4064)
			(stroke
				(width 0.1524)
				(type default)
			)
			(layer "B.SilkS")
		)
		(fp_line
			(start 0.7874 0.4064)
			(end 0.7874 -0.4064)
			(stroke
				(width 0.1524)
				(type default)
			)
			(layer "B.SilkS")
		)
		(fp_line
			(start -0.7874 -0.4064)
			(end -0.7874 0.4064)
			(stroke
				(width 0.1524)
				(type default)
			)
			(layer "B.SilkS")
		)
		(fp_line
			(start 0.7874 -0.4064)
			(end -0.7874 -0.4064)
			(stroke
				(width 0.1524)
				(type default)
			)
			(layer "B.SilkS")
		)
		(fp_line
			(start -0.67945 0.3048)
			(end -0.120396 0.3048)
			(stroke
				(width 0.1)
				(type default)
			)
			(layer "B.Fab")
		)
		(fp_line
			(start -0.120396 0.3048)
			(end -0.120396 0.2794)
			(stroke
				(width 0.1)
				(type default)
			)
			(layer "B.Fab")
		)
		(fp_line
			(start 0.12065 0.3048)
			(end 0.67945 0.3048)
			(stroke
				(width 0.1)
				(type default)
			)
			(layer "B.Fab")
		)
		(fp_line
			(start 0.67945 0.3048)
			(end 0.67945 -0.305054)
			(stroke
				(width 0.1)
				(type default)
			)
			(layer "B.Fab")
		)
		(fp_line
			(start -0.120396 0.2794)
			(end 0.12065 0.2794)
			(stroke
				(width 0.1)
				(type default)
			)
			(layer "B.Fab")
		)
		(fp_line
			(start 0.12065 0.2794)
			(end 0.12065 0.3048)
			(stroke
				(width 0.1)
				(type default)
			)
			(layer "B.Fab")
		)
		(fp_line
			(start -0.12065 -0.2794)
			(end -0.12065 -0.3048)
			(stroke
				(width 0.1)
				(type default)
			)
			(layer "B.Fab")
		)
		(fp_line
			(start 0.12065 -0.2794)
			(end -0.12065 -0.2794)
			(stroke
				(width 0.1)
				(type default)
			)
			(layer "B.Fab")
		)
		(fp_line
			(start -0.67945 -0.3048)
			(end -0.67945 0.3048)
			(stroke
				(width 0.1)
				(type default)
			)
			(layer "B.Fab")
		)
		(fp_line
			(start -0.12065 -0.3048)
			(end -0.67945 -0.3048)
			(stroke
				(width 0.1)
				(type default)
			)
			(layer "B.Fab")
		)
		(fp_line
			(start 0.12065 -0.305054)
			(end 0.12065 -0.2794)
			(stroke
				(width 0.1)
				(type default)
			)
			(layer "B.Fab")
		)
		(fp_line
			(start 0.67945 -0.305054)
			(end 0.12065 -0.305054)
			(stroke
				(width 0.1)
				(type default)
			)
			(layer "B.Fab")
		)
		(pad "1" smd circle
			(at 0.40005 0 90)
			(size 0 0)
			(layers "B.Cu" "B.Mask" "B.Paste")
			(net "SMB_HOST_3V3AUX_SDA_R4")
		)
		(pad "2" smd circle
			(at -0.40005 0 90)
			(size 0 0)
			(layers "B.Cu" "B.Mask" "B.Paste")
			(net "SMB_HOST_3V3AUX_SDA_R")
		)
	)
	(footprint ""
		(layer "B.Cu")
		(at 175.281082 -353.726242 90)
		(property "Reference" "PC405_P1_1"
			(at 0 0 90)
			(layer "B.SilkS")
			(hide yes)
			(effects
				(font
					(size 1.27 1.27)
				)
				(justify mirror)
			)
		)
		(property "Value" ""
			(at 0 0 90)
			(layer "B.Fab")
			(effects
				(font
					(size 1.27 1.27)
				)
				(justify mirror)
			)
		)
		(duplicate_pad_numbers_are_jumpers no)
		(fp_line
			(start 1.524 -0.762)
			(end -1.524 -0.762)
			(stroke
				(width 0.1524)
				(type default)
			)
			(layer "B.SilkS")
		)
		(fp_line
			(start -1.524 -0.762)
			(end -1.524 0.762)
			(stroke
				(width 0.1524)
				(type default)
			)
			(layer "B.SilkS")
		)
		(fp_line
			(start 1.524 0.762)
			(end 1.524 -0.762)
			(stroke
				(width 0.1524)
				(type default)
			)
			(layer "B.SilkS")
		)
		(fp_line
			(start -1.524 0.762)
			(end 1.524 0.762)
			(stroke
				(width 0.1524)
				(type default)
			)
			(layer "B.SilkS")
		)
		(fp_line
			(start 1.1049 -0.724916)
			(end 1.1049 0.724916)
			(stroke
				(width 0.1)
				(type default)
			)
			(layer "B.Fab")
		)
		(fp_line
			(start -1.1049 -0.724916)
			(end 1.1049 -0.724916)
			(stroke
				(width 0.1)
				(type default)
			)
			(layer "B.Fab")
		)
		(fp_line
			(start 1.1049 0.724916)
			(end -1.1049 0.724916)
			(stroke
				(width 0.1)
				(type default)
			)
			(layer "B.Fab")
		)
		(fp_line
			(start -1.1049 0.724916)
			(end -1.1049 -0.724916)
			(stroke
				(width 0.1)
				(type default)
			)
			(layer "B.Fab")
		)
		(pad "1" smd rect
			(at 0.889 0 90)
			(size 1.016 1.27)
			(layers "B.Cu" "B.Mask" "B.Paste")
			(net "SW_P12V_PVCCFA_EHV_FIVRA_CPU1_R")
		)
		(pad "2" smd rect
			(at -0.889 0 90)
			(size 1.016 1.27)
			(layers "B.Cu" "B.Mask" "B.Paste")
			(net "GND")
		)
	)
	(footprint ""
		(layer "B.Cu")
		(at 105.13314 -415.323528 180)
		(property "Reference" "L20"
			(at 0 0 0)
			(layer "B.SilkS")
			(hide yes)
			(effects
				(font
					(size 1.27 1.27)
				)
				(justify mirror)
			)
		)
		(property "Value" ""
			(at 0 0 0)
			(layer "B.Fab")
			(effects
				(font
					(size 1.27 1.27)
				)
				(justify mirror)
			)
		)
		(duplicate_pad_numbers_are_jumpers no)
		(fp_line
			(start 1.63576 -0.8128)
			(end 1.63576 0.8128)
			(stroke
				(width 0.1524)
				(type default)
			)
			(layer "B.SilkS")
		)
		(fp_line
			(start 1.63576 -0.8128)
			(end -1.63576 -0.8128)
			(stroke
				(width 0.1524)
				(type default)
			)
			(layer "B.SilkS")
		)
		(fp_line
			(start -1.63576 0.8128)
			(end 1.63576 0.8128)
			(stroke
				(width 0.1524)
				(type default)
			)
			(layer "B.SilkS")
		)
		(fp_line
			(start -1.63576 -0.8128)
			(end -1.63576 0.8128)
			(stroke
				(width 0.1524)
				(type default)
			)
			(layer "B.SilkS")
		)
		(fp_line
			(start 1.56083 0.7366)
			(end 1.524 0.7366)
			(stroke
				(width 0.1)
				(type default)
			)
			(layer "B.Fab")
		)
		(fp_line
			(start 1.56083 -0.738632)
			(end 1.56083 0.7366)
			(stroke
				(width 0.1)
				(type default)
			)
			(layer "B.Fab")
		)
		(fp_line
			(start 1.524 0.7366)
			(end -1.524 0.7366)
			(stroke
				(width 0.1)
				(type default)
			)
			(layer "B.Fab")
		)
		(fp_line
			(start -1.524 0.7366)
			(end -1.560576 0.7366)
			(stroke
				(width 0.1)
				(type default)
			)
			(layer "B.Fab")
		)
		(fp_line
			(start -1.560576 0.7366)
			(end -1.560576 -0.738632)
			(stroke
				(width 0.1)
				(type default)
			)
			(layer "B.Fab")
		)
		(fp_line
			(start -1.560576 -0.738632)
			(end 1.56083 -0.738632)
			(stroke
				(width 0.1)
				(type default)
			)
			(layer "B.Fab")
		)
		(pad "1" smd rect
			(at 0.94996 0 180)
			(size 1.1176 1.3716)
			(layers "B.Cu" "B.Mask" "B.Paste")
			(net "P3V3")
		)
		(pad "2" smd rect
			(at -0.94996 0 180)
			(size 1.1176 1.3716)
			(layers "B.Cu" "B.Mask" "B.Paste")
			(net "P3V3_9ZXL045_VDD")
		)
	)
	(footprint ""
		(layer "B.Cu")
		(at 250.65482 -2.159)
		(property "Reference" "J68"
			(at 4.20751 1.143 270)
			(unlocked yes)
			(layer "B.SilkS")
			(effects
				(font
					(size 0.7874 0.5842)
					(thickness 0.1524)
				)
				(justify left mirror)
			)
		)
		(property "Value" ""
			(at 0 0 0)
			(layer "B.Fab")
			(effects
				(font
					(size 1.27 1.27)
				)
				(justify mirror)
			)
		)
		(duplicate_pad_numbers_are_jumpers no)
		(fp_line
			(start -1.2192 -2.1082)
			(end -1.2192 2.1082)
			(stroke
				(width 0.1524)
				(type default)
			)
			(layer "B.SilkS")
		)
		(fp_line
			(start -1.2192 2.1082)
			(end 1.2192 2.1082)
			(stroke
				(width 0.1524)
				(type default)
			)
			(layer "B.SilkS")
		)
		(fp_line
			(start 1.2192 -2.1082)
			(end -1.2192 -2.1082)
			(stroke
				(width 0.1524)
				(type default)
			)
			(layer "B.SilkS")
		)
		(fp_line
			(start 1.2192 2.1082)
			(end 1.2192 -2.1082)
			(stroke
				(width 0.1524)
				(type default)
			)
			(layer "B.SilkS")
		)
		(pad "" np_thru_hole circle
			(at -3.4671 -1.27 270)
			(size 1.0414 1.0414)
			(drill 1.0414)
			(layers "*.Cu" "*.Mask")
			(clearance 0.381)
			(thermal_gap 0.381)
		)
		(pad "" np_thru_hole circle
			(at -3.4671 1.27 270)
			(size 1.0414 1.0414)
			(drill 1.0414)
			(layers "*.Cu" "*.Mask")
			(clearance 0.381)
			(thermal_gap 0.381)
		)
		(pad "" np_thru_hole circle
			(at 2.8829 -1.27 270)
			(size 1.0414 1.0414)
			(drill 1.0414)
			(layers "*.Cu" "*.Mask")
			(clearance 0.381)
			(thermal_gap 0.381)
		)
		(pad "" np_thru_hole circle
			(at 2.8829 1.27 270)
			(size 1.0414 1.0414)
			(drill 1.0414)
			(layers "*.Cu" "*.Mask")
			(clearance 0.381)
			(thermal_gap 0.381)
		)
		(pad "1" smd rect
			(at -0.8255 -0.249936 270)
			(size 0.3048 0.508)
			(layers "B.Cu" "B.Mask" "B.Paste")
			(net "DELTA_L_85_5INCH_IN4_DP")
		)
		(pad "2" smd rect
			(at -0.8255 0.249936 270)
			(size 0.3048 0.508)
			(layers "B.Cu" "B.Mask" "B.Paste")
			(net "DELTA_L_85_5INCH_IN4_DN")
		)
		(pad "3" smd circle
			(at 0 0 180)
			(size 0 0)
			(layers "B.Cu" "B.Mask" "B.Paste")
			(net "DELTA_L_GND_1")
		)
		(zone
			(layers "F.Cu" "B.Cu" "In1.Cu" "In2.Cu" "In3.Cu" "In4.Cu" "In5.Cu" "In6.Cu"
				"In7.Cu" "In8.Cu" "In9.Cu" "In10.Cu" "In11.Cu" "In12.Cu" "In13.Cu" "In14.Cu"
				"In15.Cu" "In16.Cu"
			)
			(hatch none 0.5)
			(connect_pads
				(clearance 0)
			)
			(min_thickness 0.25)
			(keepout
				(tracks not_allowed)
				(vias allowed)
				(pads allowed)
				(copperpour not_allowed)
				(footprints allowed)
			)
			(placement
				(enabled no)
				(sheetname "")
			)
			(fill
				(thermal_gap 0.5)
				(thermal_bridge_width 0.5)
				(island_removal_mode 0)
			)
			(polygon
				(pts
					(arc
						(start 248.11482 -3.429)
						(mid 246.26062 -3.429)
						(end 248.11482 -3.429)
					)
				)
			)
		)
		(zone
			(layers "F.Cu" "B.Cu" "In1.Cu" "In2.Cu" "In3.Cu" "In4.Cu" "In5.Cu" "In6.Cu"
				"In7.Cu" "In8.Cu" "In9.Cu" "In10.Cu" "In11.Cu" "In12.Cu" "In13.Cu" "In14.Cu"
				"In15.Cu" "In16.Cu"
			)
			(hatch none 0.5)
			(connect_pads
				(clearance 0)
			)
			(min_thickness 0.25)
			(keepout
				(tracks not_allowed)
				(vias allowed)
				(pads allowed)
				(copperpour not_allowed)
				(footprints allowed)
			)
			(placement
				(enabled no)
				(sheetname "")
			)
			(fill
				(thermal_gap 0.5)
				(thermal_bridge_width 0.5)
				(island_removal_mode 0)
			)
			(polygon
				(pts
					(arc
						(start 248.11482 -0.889)
						(mid 246.26062 -0.889)
						(end 248.11482 -0.889)
					)
				)
			)
		)
		(zone
			(layers "F.Cu" "B.Cu" "In1.Cu" "In2.Cu" "In3.Cu" "In4.Cu" "In5.Cu" "In6.Cu"
				"In7.Cu" "In8.Cu" "In9.Cu" "In10.Cu" "In11.Cu" "In12.Cu" "In13.Cu" "In14.Cu"
				"In15.Cu" "In16.Cu"
			)
			(hatch none 0.5)
			(connect_pads
				(clearance 0)
			)
			(min_thickness 0.25)
			(keepout
				(tracks not_allowed)
				(vias allowed)
				(pads allowed)
				(copperpour not_allowed)
				(footprints allowed)
			)
			(placement
				(enabled no)
				(sheetname "")
			)
			(fill
				(thermal_gap 0.5)
				(thermal_bridge_width 0.5)
				(island_removal_mode 0)
			)
			(polygon
				(pts
					(arc
						(start 254.46482 -3.429)
						(mid 252.61062 -3.429)
						(end 254.46482 -3.429)
					)
				)
			)
		)
		(zone
			(layers "F.Cu" "B.Cu" "In1.Cu" "In2.Cu" "In3.Cu" "In4.Cu" "In5.Cu" "In6.Cu"
				"In7.Cu" "In8.Cu" "In9.Cu" "In10.Cu" "In11.Cu" "In12.Cu" "In13.Cu" "In14.Cu"
				"In15.Cu" "In16.Cu"
			)
			(hatch none 0.5)
			(connect_pads
				(clearance 0)
			)
			(min_thickness 0.25)
			(keepout
				(tracks not_allowed)
				(vias allowed)
				(pads allowed)
				(copperpour not_allowed)
				(footprints allowed)
			)
			(placement
				(enabled no)
				(sheetname "")
			)
			(fill
				(thermal_gap 0.5)
				(thermal_bridge_width 0.5)
				(island_removal_mode 0)
			)
			(polygon
				(pts
					(arc
						(start 254.46482 -0.889)
						(mid 252.61062 -0.889)
						(end 254.46482 -0.889)
					)
				)
			)
		)
		(zone
			(layer "B.Cu")
			(hatch none 0.5)
			(connect_pads
				(clearance 0)
			)
			(min_thickness 0.25)
			(keepout
				(tracks not_allowed)
				(vias allowed)
				(pads allowed)
				(copperpour not_allowed)
				(footprints allowed)
			)
			(placement
				(enabled no)
				(sheetname "")
			)
			(fill
				(thermal_gap 0.5)
				(thermal_bridge_width 0.5)
				(island_removal_mode 0)
			)
			(polygon
				(pts
					(xy 249.53722 -2.70764) (xy 249.53722 -2.612136) (xy 250.13412 -2.612136) (xy 250.13412 -2.205736)
					(xy 249.53722 -2.205736) (xy 249.53722 -2.112264) (xy 250.13412 -2.112264) (xy 250.13412 -1.705864)
					(xy 249.53722 -1.705864) (xy 249.53722 -1.61036) (xy 250.23572 -1.61036) (xy 250.23572 -2.70764)
				)
			)
		)
	)
	(footprint ""
		(layer "B.Cu")
		(at 263.064752 -99.450398 -90)
		(property "Reference" "R1527"
			(at 0 0 90)
			(layer "B.SilkS")
			(hide yes)
			(effects
				(font
					(size 1.27 1.27)
				)
				(justify mirror)
			)
		)
		(property "Value" ""
			(at 0 0 90)
			(layer "B.Fab")
			(effects
				(font
					(size 1.27 1.27)
				)
				(justify mirror)
			)
		)
		(duplicate_pad_numbers_are_jumpers no)
		(fp_line
			(start -0.7874 0.4064)
			(end 0.7874 0.4064)
			(stroke
				(width 0.1524)
				(type default)
			)
			(layer "B.SilkS")
		)
		(fp_line
			(start 0.7874 0.4064)
			(end 0.7874 -0.4064)
			(stroke
				(width 0.1524)
				(type default)
			)
			(layer "B.SilkS")
		)
		(fp_line
			(start -0.7874 -0.4064)
			(end -0.7874 0.4064)
			(stroke
				(width 0.1524)
				(type default)
			)
			(layer "B.SilkS")
		)
		(fp_line
			(start 0.7874 -0.4064)
			(end -0.7874 -0.4064)
			(stroke
				(width 0.1524)
				(type default)
			)
			(layer "B.SilkS")
		)
		(fp_line
			(start -0.67945 0.3048)
			(end -0.120396 0.3048)
			(stroke
				(width 0.1)
				(type default)
			)
			(layer "B.Fab")
		)
		(fp_line
			(start -0.120396 0.3048)
			(end -0.120396 0.2794)
			(stroke
				(width 0.1)
				(type default)
			)
			(layer "B.Fab")
		)
		(fp_line
			(start 0.12065 0.3048)
			(end 0.67945 0.3048)
			(stroke
				(width 0.1)
				(type default)
			)
			(layer "B.Fab")
		)
		(fp_line
			(start 0.67945 0.3048)
			(end 0.67945 -0.305054)
			(stroke
				(width 0.1)
				(type default)
			)
			(layer "B.Fab")
		)
		(fp_line
			(start -0.120396 0.2794)
			(end 0.12065 0.2794)
			(stroke
				(width 0.1)
				(type default)
			)
			(layer "B.Fab")
		)
		(fp_line
			(start 0.12065 0.2794)
			(end 0.12065 0.3048)
			(stroke
				(width 0.1)
				(type default)
			)
			(layer "B.Fab")
		)
		(fp_line
			(start -0.12065 -0.2794)
			(end -0.12065 -0.3048)
			(stroke
				(width 0.1)
				(type default)
			)
			(layer "B.Fab")
		)
		(fp_line
			(start 0.12065 -0.2794)
			(end -0.12065 -0.2794)
			(stroke
				(width 0.1)
				(type default)
			)
			(layer "B.Fab")
		)
		(fp_line
			(start -0.67945 -0.3048)
			(end -0.67945 0.3048)
			(stroke
				(width 0.1)
				(type default)
			)
			(layer "B.Fab")
		)
		(fp_line
			(start -0.12065 -0.3048)
			(end -0.67945 -0.3048)
			(stroke
				(width 0.1)
				(type default)
			)
			(layer "B.Fab")
		)
		(fp_line
			(start 0.12065 -0.305054)
			(end 0.12065 -0.2794)
			(stroke
				(width 0.1)
				(type default)
			)
			(layer "B.Fab")
		)
		(fp_line
			(start 0.67945 -0.305054)
			(end 0.12065 -0.305054)
			(stroke
				(width 0.1)
				(type default)
			)
			(layer "B.Fab")
		)
		(pad "1" smd circle
			(at 0.40005 0 90)
			(size 0 0)
			(layers "B.Cu" "B.Mask" "B.Paste")
			(net "FM_CLK_GEN1_OE0_N")
		)
		(pad "2" smd circle
			(at -0.40005 0 90)
			(size 0 0)
			(layers "B.Cu" "B.Mask" "B.Paste")
			(net "GND")
		)
	)
	(footprint ""
		(layer "B.Cu")
		(at 292.998398 -153.546048 -90)
		(property "Reference" "R683"
			(at 0 0 90)
			(layer "B.SilkS")
			(hide yes)
			(effects
				(font
					(size 1.27 1.27)
				)
				(justify mirror)
			)
		)
		(property "Value" ""
			(at 0 0 90)
			(layer "B.Fab")
			(effects
				(font
					(size 1.27 1.27)
				)
				(justify mirror)
			)
		)
		(duplicate_pad_numbers_are_jumpers no)
		(fp_line
			(start -0.7874 0.4064)
			(end 0.7874 0.4064)
			(stroke
				(width 0.1524)
				(type default)
			)
			(layer "B.SilkS")
		)
		(fp_line
			(start 0.7874 0.4064)
			(end 0.7874 -0.4064)
			(stroke
				(width 0.1524)
				(type default)
			)
			(layer "B.SilkS")
		)
		(fp_line
			(start -0.7874 -0.4064)
			(end -0.7874 0.4064)
			(stroke
				(width 0.1524)
				(type default)
			)
			(layer "B.SilkS")
		)
		(fp_line
			(start 0.7874 -0.4064)
			(end -0.7874 -0.4064)
			(stroke
				(width 0.1524)
				(type default)
			)
			(layer "B.SilkS")
		)
		(fp_line
			(start -0.67945 0.3048)
			(end -0.120396 0.3048)
			(stroke
				(width 0.1)
				(type default)
			)
			(layer "B.Fab")
		)
		(fp_line
			(start -0.120396 0.3048)
			(end -0.120396 0.2794)
			(stroke
				(width 0.1)
				(type default)
			)
			(layer "B.Fab")
		)
		(fp_line
			(start 0.12065 0.3048)
			(end 0.67945 0.3048)
			(stroke
				(width 0.1)
				(type default)
			)
			(layer "B.Fab")
		)
		(fp_line
			(start 0.67945 0.3048)
			(end 0.67945 -0.305054)
			(stroke
				(width 0.1)
				(type default)
			)
			(layer "B.Fab")
		)
		(fp_line
			(start -0.120396 0.2794)
			(end 0.12065 0.2794)
			(stroke
				(width 0.1)
				(type default)
			)
			(layer "B.Fab")
		)
		(fp_line
			(start 0.12065 0.2794)
			(end 0.12065 0.3048)
			(stroke
				(width 0.1)
				(type default)
			)
			(layer "B.Fab")
		)
		(fp_line
			(start -0.12065 -0.2794)
			(end -0.12065 -0.3048)
			(stroke
				(width 0.1)
				(type default)
			)
			(layer "B.Fab")
		)
		(fp_line
			(start 0.12065 -0.2794)
			(end -0.12065 -0.2794)
			(stroke
				(width 0.1)
				(type default)
			)
			(layer "B.Fab")
		)
		(fp_line
			(start -0.67945 -0.3048)
			(end -0.67945 0.3048)
			(stroke
				(width 0.1)
				(type default)
			)
			(layer "B.Fab")
		)
		(fp_line
			(start -0.12065 -0.3048)
			(end -0.67945 -0.3048)
			(stroke
				(width 0.1)
				(type default)
			)
			(layer "B.Fab")
		)
		(fp_line
			(start 0.12065 -0.305054)
			(end 0.12065 -0.2794)
			(stroke
				(width 0.1)
				(type default)
			)
			(layer "B.Fab")
		)
		(fp_line
			(start 0.67945 -0.305054)
			(end 0.12065 -0.305054)
			(stroke
				(width 0.1)
				(type default)
			)
			(layer "B.Fab")
		)
		(pad "1" smd circle
			(at 0.40005 0 90)
			(size 0 0)
			(layers "B.Cu" "B.Mask" "B.Paste")
			(net "I3C_SPD_DDRABCD_CPU0_R_SDA")
		)
		(pad "2" smd circle
			(at -0.40005 0 90)
			(size 0 0)
			(layers "B.Cu" "B.Mask" "B.Paste")
			(net "I3C_SPD_DDRABCD_CPU0_LVC1_R_SDA")
		)
	)
	(footprint ""
		(layer "B.Cu")
		(at 369.49888 -45.176948 180)
		(property "Reference" "R4113"
			(at 0 0 0)
			(layer "B.SilkS")
			(hide yes)
			(effects
				(font
					(size 1.27 1.27)
				)
				(justify mirror)
			)
		)
		(property "Value" ""
			(at 0 0 0)
			(layer "B.Fab")
			(effects
				(font
					(size 1.27 1.27)
				)
				(justify mirror)
			)
		)
		(duplicate_pad_numbers_are_jumpers no)
		(fp_line
			(start 0.7874 0.4064)
			(end 0.7874 -0.4064)
			(stroke
				(width 0.1524)
				(type default)
			)
			(layer "B.SilkS")
		)
		(fp_line
			(start 0.7874 -0.4064)
			(end -0.7874 -0.4064)
			(stroke
				(width 0.1524)
				(type default)
			)
			(layer "B.SilkS")
		)
		(fp_line
			(start -0.7874 0.4064)
			(end 0.7874 0.4064)
			(stroke
				(width 0.1524)
				(type default)
			)
			(layer "B.SilkS")
		)
		(fp_line
			(start -0.7874 -0.4064)
			(end -0.7874 0.4064)
			(stroke
				(width 0.1524)
				(type default)
			)
			(layer "B.SilkS")
		)
		(fp_line
			(start 0.67945 0.3048)
			(end 0.67945 -0.305054)
			(stroke
				(width 0.1)
				(type default)
			)
			(layer "B.Fab")
		)
		(fp_line
			(start 0.67945 -0.305054)
			(end 0.12065 -0.305054)
			(stroke
				(width 0.1)
				(type default)
			)
			(layer "B.Fab")
		)
		(fp_line
			(start 0.12065 0.3048)
			(end 0.67945 0.3048)
			(stroke
				(width 0.1)
				(type default)
			)
			(layer "B.Fab")
		)
		(fp_line
			(start 0.12065 0.2794)
			(end 0.12065 0.3048)
			(stroke
				(width 0.1)
				(type default)
			)
			(layer "B.Fab")
		)
		(fp_line
			(start 0.12065 -0.2794)
			(end -0.12065 -0.2794)
			(stroke
				(width 0.1)
				(type default)
			)
			(layer "B.Fab")
		)
		(fp_line
			(start 0.12065 -0.305054)
			(end 0.12065 -0.2794)
			(stroke
				(width 0.1)
				(type default)
			)
			(layer "B.Fab")
		)
		(fp_line
			(start -0.120396 0.3048)
			(end -0.120396 0.2794)
			(stroke
				(width 0.1)
				(type default)
			)
			(layer "B.Fab")
		)
		(fp_line
			(start -0.120396 0.2794)
			(end 0.12065 0.2794)
			(stroke
				(width 0.1)
				(type default)
			)
			(layer "B.Fab")
		)
		(fp_line
			(start -0.12065 -0.2794)
			(end -0.12065 -0.3048)
			(stroke
				(width 0.1)
				(type default)
			)
			(layer "B.Fab")
		)
		(fp_line
			(start -0.12065 -0.3048)
			(end -0.67945 -0.3048)
			(stroke
				(width 0.1)
				(type default)
			)
			(layer "B.Fab")
		)
		(fp_line
			(start -0.67945 0.3048)
			(end -0.120396 0.3048)
			(stroke
				(width 0.1)
				(type default)
			)
			(layer "B.Fab")
		)
		(fp_line
			(start -0.67945 -0.3048)
			(end -0.67945 0.3048)
			(stroke
				(width 0.1)
				(type default)
			)
			(layer "B.Fab")
		)
		(pad "1" smd circle
			(at 0.40005 0)
			(size 0 0)
			(layers "B.Cu" "B.Mask" "B.Paste")
			(net "PD_PCH_GPP_E_11")
		)
		(pad "2" smd circle
			(at -0.40005 0)
			(size 0 0)
			(layers "B.Cu" "B.Mask" "B.Paste")
			(net "GND")
		)
	)
	(footprint ""
		(layer "B.Cu")
		(at 385.46405 -188.70422 -90)
		(property "Reference" "R67"
			(at 0 0 90)
			(layer "B.SilkS")
			(hide yes)
			(effects
				(font
					(size 1.27 1.27)
				)
				(justify mirror)
			)
		)
		(property "Value" ""
			(at 0 0 90)
			(layer "B.Fab")
			(effects
				(font
					(size 1.27 1.27)
				)
				(justify mirror)
			)
		)
		(duplicate_pad_numbers_are_jumpers no)
		(fp_line
			(start -0.7874 0.4064)
			(end 0.7874 0.4064)
			(stroke
				(width 0.1524)
				(type default)
			)
			(layer "B.SilkS")
		)
		(fp_line
			(start 0.7874 0.4064)
			(end 0.7874 -0.4064)
			(stroke
				(width 0.1524)
				(type default)
			)
			(layer "B.SilkS")
		)
		(fp_line
			(start -0.7874 -0.4064)
			(end -0.7874 0.4064)
			(stroke
				(width 0.1524)
				(type default)
			)
			(layer "B.SilkS")
		)
		(fp_line
			(start 0.7874 -0.4064)
			(end -0.7874 -0.4064)
			(stroke
				(width 0.1524)
				(type default)
			)
			(layer "B.SilkS")
		)
		(fp_line
			(start -0.67945 0.3048)
			(end -0.120396 0.3048)
			(stroke
				(width 0.1)
				(type default)
			)
			(layer "B.Fab")
		)
		(fp_line
			(start -0.120396 0.3048)
			(end -0.120396 0.2794)
			(stroke
				(width 0.1)
				(type default)
			)
			(layer "B.Fab")
		)
		(fp_line
			(start 0.12065 0.3048)
			(end 0.67945 0.3048)
			(stroke
				(width 0.1)
				(type default)
			)
			(layer "B.Fab")
		)
		(fp_line
			(start 0.67945 0.3048)
			(end 0.67945 -0.305054)
			(stroke
				(width 0.1)
				(type default)
			)
			(layer "B.Fab")
		)
		(fp_line
			(start -0.120396 0.2794)
			(end 0.12065 0.2794)
			(stroke
				(width 0.1)
				(type default)
			)
			(layer "B.Fab")
		)
		(fp_line
			(start 0.12065 0.2794)
			(end 0.12065 0.3048)
			(stroke
				(width 0.1)
				(type default)
			)
			(layer "B.Fab")
		)
		(fp_line
			(start -0.12065 -0.2794)
			(end -0.12065 -0.3048)
			(stroke
				(width 0.1)
				(type default)
			)
			(layer "B.Fab")
		)
		(fp_line
			(start 0.12065 -0.2794)
			(end -0.12065 -0.2794)
			(stroke
				(width 0.1)
				(type default)
			)
			(layer "B.Fab")
		)
		(fp_line
			(start -0.67945 -0.3048)
			(end -0.67945 0.3048)
			(stroke
				(width 0.1)
				(type default)
			)
			(layer "B.Fab")
		)
		(fp_line
			(start -0.12065 -0.3048)
			(end -0.67945 -0.3048)
			(stroke
				(width 0.1)
				(type default)
			)
			(layer "B.Fab")
		)
		(fp_line
			(start 0.12065 -0.305054)
			(end 0.12065 -0.2794)
			(stroke
				(width 0.1)
				(type default)
			)
			(layer "B.Fab")
		)
		(fp_line
			(start 0.67945 -0.305054)
			(end 0.12065 -0.305054)
			(stroke
				(width 0.1)
				(type default)
			)
			(layer "B.Fab")
		)
		(pad "1" smd circle
			(at 0.40005 0 90)
			(size 0 0)
			(layers "B.Cu" "B.Mask" "B.Paste")
			(net "PWRGD_PLT_AUX_CPU0_LVT3_R")
		)
		(pad "2" smd circle
			(at -0.40005 0 90)
			(size 0 0)
			(layers "B.Cu" "B.Mask" "B.Paste")
			(net "PWRGD_PLT_AUX_CPU0_LVT3")
		)
	)
	(footprint ""
		(layer "B.Cu")
		(at 181.755542 -113.77549)
		(property "Reference" "C1146"
			(at 0 0 0)
			(layer "B.SilkS")
			(hide yes)
			(effects
				(font
					(size 1.27 1.27)
				)
				(justify mirror)
			)
		)
		(property "Value" ""
			(at 0 0 0)
			(layer "B.Fab")
			(effects
				(font
					(size 1.27 1.27)
				)
				(justify mirror)
			)
		)
		(duplicate_pad_numbers_are_jumpers no)
		(fp_line
			(start -0.69215 -0.2921)
			(end -0.69215 0.2921)
			(stroke
				(width 0.1524)
				(type default)
			)
			(layer "B.SilkS")
		)
		(fp_line
			(start -0.69215 0.2921)
			(end 0.69215 0.2921)
			(stroke
				(width 0.1524)
				(type default)
			)
			(layer "B.SilkS")
		)
		(fp_line
			(start 0.69215 -0.2921)
			(end -0.69215 -0.2921)
			(stroke
				(width 0.1524)
				(type default)
			)
			(layer "B.SilkS")
		)
		(fp_line
			(start 0.69215 0.2921)
			(end 0.69215 -0.2921)
			(stroke
				(width 0.1524)
				(type default)
			)
			(layer "B.SilkS")
		)
		(fp_line
			(start -0.51435 -0.2794)
			(end -0.51435 0.2794)
			(stroke
				(width 0.1)
				(type default)
			)
			(layer "B.Fab")
		)
		(fp_line
			(start -0.51435 0.2794)
			(end 0.51435 0.2794)
			(stroke
				(width 0.1)
				(type default)
			)
			(layer "B.Fab")
		)
		(fp_line
			(start 0.51435 -0.2794)
			(end -0.51435 -0.2794)
			(stroke
				(width 0.1)
				(type default)
			)
			(layer "B.Fab")
		)
		(fp_line
			(start 0.51435 0.2794)
			(end 0.51435 -0.2794)
			(stroke
				(width 0.1)
				(type default)
			)
			(layer "B.Fab")
		)
		(pad "1" smd circle
			(at 0.40005 0 180)
			(size 0 0)
			(layers "B.Cu" "B.Mask" "B.Paste")
			(net "P3V3_AUX_FPGA_VCCIO2")
		)
		(pad "2" smd circle
			(at -0.40005 0 180)
			(size 0 0)
			(layers "B.Cu" "B.Mask" "B.Paste")
			(net "GND")
		)
		(zone
			(layer "B.Cu")
			(hatch none 0.5)
			(connect_pads
				(clearance 0)
			)
			(min_thickness 0.25)
			(keepout
				(tracks not_allowed)
				(vias allowed)
				(pads allowed)
				(copperpour not_allowed)
				(footprints allowed)
			)
			(placement
				(enabled no)
				(sheetname "")
			)
			(fill
				(thermal_gap 0.5)
				(thermal_bridge_width 0.5)
				(island_removal_mode 0)
			)
			(polygon
				(pts
					(xy 181.946042 -113.68786) (xy 181.854602 -113.629694) (xy 181.655212 -113.629694) (xy 181.565042 -113.68786)
					(xy 181.565042 -113.86312) (xy 181.655212 -113.92154) (xy 181.854602 -113.92154) (xy 181.946042 -113.863374)
				)
			)
		)
	)
	(footprint ""
		(layer "B.Cu")
		(at 191.264286 -193.615056 -90)
		(property "Reference" "C613"
			(at 0 0 90)
			(layer "B.SilkS")
			(hide yes)
			(effects
				(font
					(size 1.27 1.27)
				)
				(justify mirror)
			)
		)
		(property "Value" ""
			(at 0 0 90)
			(layer "B.Fab")
			(effects
				(font
					(size 1.27 1.27)
				)
				(justify mirror)
			)
		)
		(duplicate_pad_numbers_are_jumpers no)
		(fp_line
			(start -0.7874 0.4064)
			(end 0.7874 0.4064)
			(stroke
				(width 0.1524)
				(type default)
			)
			(layer "B.SilkS")
		)
		(fp_line
			(start 0.7874 0.4064)
			(end 0.7874 -0.4064)
			(stroke
				(width 0.1524)
				(type default)
			)
			(layer "B.SilkS")
		)
		(fp_line
			(start -0.7874 -0.4064)
			(end -0.7874 0.4064)
			(stroke
				(width 0.1524)
				(type default)
			)
			(layer "B.SilkS")
		)
		(fp_line
			(start 0.7874 -0.4064)
			(end -0.7874 -0.4064)
			(stroke
				(width 0.1524)
				(type default)
			)
			(layer "B.SilkS")
		)
		(fp_line
			(start -0.67945 0.3048)
			(end -0.120396 0.3048)
			(stroke
				(width 0.1)
				(type default)
			)
			(layer "B.Fab")
		)
		(fp_line
			(start -0.120396 0.3048)
			(end -0.120396 0.2794)
			(stroke
				(width 0.1)
				(type default)
			)
			(layer "B.Fab")
		)
		(fp_line
			(start 0.12065 0.3048)
			(end 0.67945 0.3048)
			(stroke
				(width 0.1)
				(type default)
			)
			(layer "B.Fab")
		)
		(fp_line
			(start 0.67945 0.3048)
			(end 0.67945 -0.305054)
			(stroke
				(width 0.1)
				(type default)
			)
			(layer "B.Fab")
		)
		(fp_line
			(start -0.120396 0.2794)
			(end 0.12065 0.2794)
			(stroke
				(width 0.1)
				(type default)
			)
			(layer "B.Fab")
		)
		(fp_line
			(start 0.12065 0.2794)
			(end 0.12065 0.3048)
			(stroke
				(width 0.1)
				(type default)
			)
			(layer "B.Fab")
		)
		(fp_line
			(start -0.12065 -0.2794)
			(end -0.12065 -0.3048)
			(stroke
				(width 0.1)
				(type default)
			)
			(layer "B.Fab")
		)
		(fp_line
			(start 0.12065 -0.2794)
			(end -0.12065 -0.2794)
			(stroke
				(width 0.1)
				(type default)
			)
			(layer "B.Fab")
		)
		(fp_line
			(start -0.67945 -0.3048)
			(end -0.67945 0.3048)
			(stroke
				(width 0.1)
				(type default)
			)
			(layer "B.Fab")
		)
		(fp_line
			(start -0.12065 -0.3048)
			(end -0.67945 -0.3048)
			(stroke
				(width 0.1)
				(type default)
			)
			(layer "B.Fab")
		)
		(fp_line
			(start 0.12065 -0.305054)
			(end 0.12065 -0.2794)
			(stroke
				(width 0.1)
				(type default)
			)
			(layer "B.Fab")
		)
		(fp_line
			(start 0.67945 -0.305054)
			(end 0.12065 -0.305054)
			(stroke
				(width 0.1)
				(type default)
			)
			(layer "B.Fab")
		)
		(pad "1" smd circle
			(at 0.40005 0 90)
			(size 0 0)
			(layers "B.Cu" "B.Mask" "B.Paste")
			(net "RST_PLD_CPU1_DRAM_GH_N")
		)
		(pad "2" smd circle
			(at -0.40005 0 90)
			(size 0 0)
			(layers "B.Cu" "B.Mask" "B.Paste")
			(net "GND")
		)
	)
	(footprint ""
		(layer "B.Cu")
		(at 366.992408 -325.110094 -90)
		(property "Reference" "PC308_P0_1"
			(at 0 0 90)
			(layer "B.SilkS")
			(hide yes)
			(effects
				(font
					(size 1.27 1.27)
				)
				(justify mirror)
			)
		)
		(property "Value" ""
			(at 0 0 90)
			(layer "B.Fab")
			(effects
				(font
					(size 1.27 1.27)
				)
				(justify mirror)
			)
		)
		(duplicate_pad_numbers_are_jumpers no)
		(fp_line
			(start -0.7874 0.4064)
			(end 0.7874 0.4064)
			(stroke
				(width 0.1524)
				(type default)
			)
			(layer "B.SilkS")
		)
		(fp_line
			(start 0.7874 0.4064)
			(end 0.7874 -0.4064)
			(stroke
				(width 0.1524)
				(type default)
			)
			(layer "B.SilkS")
		)
		(fp_line
			(start -0.7874 -0.4064)
			(end -0.7874 0.4064)
			(stroke
				(width 0.1524)
				(type default)
			)
			(layer "B.SilkS")
		)
		(fp_line
			(start 0.7874 -0.4064)
			(end -0.7874 -0.4064)
			(stroke
				(width 0.1524)
				(type default)
			)
			(layer "B.SilkS")
		)
		(fp_line
			(start -0.67945 0.3048)
			(end -0.120396 0.3048)
			(stroke
				(width 0.1)
				(type default)
			)
			(layer "B.Fab")
		)
		(fp_line
			(start -0.120396 0.3048)
			(end -0.120396 0.2794)
			(stroke
				(width 0.1)
				(type default)
			)
			(layer "B.Fab")
		)
		(fp_line
			(start 0.12065 0.3048)
			(end 0.67945 0.3048)
			(stroke
				(width 0.1)
				(type default)
			)
			(layer "B.Fab")
		)
		(fp_line
			(start 0.67945 0.3048)
			(end 0.67945 -0.305054)
			(stroke
				(width 0.1)
				(type default)
			)
			(layer "B.Fab")
		)
		(fp_line
			(start -0.120396 0.2794)
			(end 0.12065 0.2794)
			(stroke
				(width 0.1)
				(type default)
			)
			(layer "B.Fab")
		)
		(fp_line
			(start 0.12065 0.2794)
			(end 0.12065 0.3048)
			(stroke
				(width 0.1)
				(type default)
			)
			(layer "B.Fab")
		)
		(fp_line
			(start -0.12065 -0.2794)
			(end -0.12065 -0.3048)
			(stroke
				(width 0.1)
				(type default)
			)
			(layer "B.Fab")
		)
		(fp_line
			(start 0.12065 -0.2794)
			(end -0.12065 -0.2794)
			(stroke
				(width 0.1)
				(type default)
			)
			(layer "B.Fab")
		)
		(fp_line
			(start -0.67945 -0.3048)
			(end -0.67945 0.3048)
			(stroke
				(width 0.1)
				(type default)
			)
			(layer "B.Fab")
		)
		(fp_line
			(start -0.12065 -0.3048)
			(end -0.67945 -0.3048)
			(stroke
				(width 0.1)
				(type default)
			)
			(layer "B.Fab")
		)
		(fp_line
			(start 0.12065 -0.305054)
			(end 0.12065 -0.2794)
			(stroke
				(width 0.1)
				(type default)
			)
			(layer "B.Fab")
		)
		(fp_line
			(start 0.67945 -0.305054)
			(end 0.12065 -0.305054)
			(stroke
				(width 0.1)
				(type default)
			)
			(layer "B.Fab")
		)
		(pad "1" smd circle
			(at 0.40005 0 90)
			(size 0 0)
			(layers "B.Cu" "B.Mask" "B.Paste")
			(net "PVCCIN_CPU0")
		)
		(pad "2" smd circle
			(at -0.40005 0 90)
			(size 0 0)
			(layers "B.Cu" "B.Mask" "B.Paste")
			(net "GND")
		)
	)
	(footprint ""
		(layer "B.Cu")
		(at 331.146912 -32.71266 90)
		(property "Reference" "R375"
			(at 0 0 90)
			(layer "B.SilkS")
			(hide yes)
			(effects
				(font
					(size 1.27 1.27)
				)
				(justify mirror)
			)
		)
		(property "Value" ""
			(at 0 0 90)
			(layer "B.Fab")
			(effects
				(font
					(size 1.27 1.27)
				)
				(justify mirror)
			)
		)
		(duplicate_pad_numbers_are_jumpers no)
		(fp_line
			(start 0.7874 -0.4064)
			(end -0.7874 -0.4064)
			(stroke
				(width 0.1524)
				(type default)
			)
			(layer "B.SilkS")
		)
		(fp_line
			(start -0.7874 -0.4064)
			(end -0.7874 0.4064)
			(stroke
				(width 0.1524)
				(type default)
			)
			(layer "B.SilkS")
		)
		(fp_line
			(start 0.7874 0.4064)
			(end 0.7874 -0.4064)
			(stroke
				(width 0.1524)
				(type default)
			)
			(layer "B.SilkS")
		)
		(fp_line
			(start -0.7874 0.4064)
			(end 0.7874 0.4064)
			(stroke
				(width 0.1524)
				(type default)
			)
			(layer "B.SilkS")
		)
		(fp_line
			(start 0.67945 -0.305054)
			(end 0.12065 -0.305054)
			(stroke
				(width 0.1)
				(type default)
			)
			(layer "B.Fab")
		)
		(fp_line
			(start 0.12065 -0.305054)
			(end 0.12065 -0.2794)
			(stroke
				(width 0.1)
				(type default)
			)
			(layer "B.Fab")
		)
		(fp_line
			(start -0.12065 -0.3048)
			(end -0.67945 -0.3048)
			(stroke
				(width 0.1)
				(type default)
			)
			(layer "B.Fab")
		)
		(fp_line
			(start -0.67945 -0.3048)
			(end -0.67945 0.3048)
			(stroke
				(width 0.1)
				(type default)
			)
			(layer "B.Fab")
		)
		(fp_line
			(start 0.12065 -0.2794)
			(end -0.12065 -0.2794)
			(stroke
				(width 0.1)
				(type default)
			)
			(layer "B.Fab")
		)
		(fp_line
			(start -0.12065 -0.2794)
			(end -0.12065 -0.3048)
			(stroke
				(width 0.1)
				(type default)
			)
			(layer "B.Fab")
		)
		(fp_line
			(start 0.12065 0.2794)
			(end 0.12065 0.3048)
			(stroke
				(width 0.1)
				(type default)
			)
			(layer "B.Fab")
		)
		(fp_line
			(start -0.120396 0.2794)
			(end 0.12065 0.2794)
			(stroke
				(width 0.1)
				(type default)
			)
			(layer "B.Fab")
		)
		(fp_line
			(start 0.67945 0.3048)
			(end 0.67945 -0.305054)
			(stroke
				(width 0.1)
				(type default)
			)
			(layer "B.Fab")
		)
		(fp_line
			(start 0.12065 0.3048)
			(end 0.67945 0.3048)
			(stroke
				(width 0.1)
				(type default)
			)
			(layer "B.Fab")
		)
		(fp_line
			(start -0.120396 0.3048)
			(end -0.120396 0.2794)
			(stroke
				(width 0.1)
				(type default)
			)
			(layer "B.Fab")
		)
		(fp_line
			(start -0.67945 0.3048)
			(end -0.120396 0.3048)
			(stroke
				(width 0.1)
				(type default)
			)
			(layer "B.Fab")
		)
		(pad "1" smd circle
			(at 0.40005 0 270)
			(size 0 0)
			(layers "B.Cu" "B.Mask" "B.Paste")
			(net "FM_SPI_3V3_1V8_VOLTAGE")
		)
		(pad "2" smd circle
			(at -0.40005 0 270)
			(size 0 0)
			(layers "B.Cu" "B.Mask" "B.Paste")
			(net "GND")
		)
	)
	(footprint ""
		(layer "B.Cu")
		(at 152.339802 -190.359284 -90)
		(property "Reference" "R669"
			(at 0 0 90)
			(layer "B.SilkS")
			(hide yes)
			(effects
				(font
					(size 1.27 1.27)
				)
				(justify mirror)
			)
		)
		(property "Value" ""
			(at 0 0 90)
			(layer "B.Fab")
			(effects
				(font
					(size 1.27 1.27)
				)
				(justify mirror)
			)
		)
		(duplicate_pad_numbers_are_jumpers no)
		(fp_line
			(start -0.7874 0.4064)
			(end 0.7874 0.4064)
			(stroke
				(width 0.1524)
				(type default)
			)
			(layer "B.SilkS")
		)
		(fp_line
			(start 0.7874 0.4064)
			(end 0.7874 -0.4064)
			(stroke
				(width 0.1524)
				(type default)
			)
			(layer "B.SilkS")
		)
		(fp_line
			(start -0.7874 -0.4064)
			(end -0.7874 0.4064)
			(stroke
				(width 0.1524)
				(type default)
			)
			(layer "B.SilkS")
		)
		(fp_line
			(start 0.7874 -0.4064)
			(end -0.7874 -0.4064)
			(stroke
				(width 0.1524)
				(type default)
			)
			(layer "B.SilkS")
		)
		(fp_line
			(start -0.67945 0.3048)
			(end -0.120396 0.3048)
			(stroke
				(width 0.1)
				(type default)
			)
			(layer "B.Fab")
		)
		(fp_line
			(start -0.120396 0.3048)
			(end -0.120396 0.2794)
			(stroke
				(width 0.1)
				(type default)
			)
			(layer "B.Fab")
		)
		(fp_line
			(start 0.12065 0.3048)
			(end 0.67945 0.3048)
			(stroke
				(width 0.1)
				(type default)
			)
			(layer "B.Fab")
		)
		(fp_line
			(start 0.67945 0.3048)
			(end 0.67945 -0.305054)
			(stroke
				(width 0.1)
				(type default)
			)
			(layer "B.Fab")
		)
		(fp_line
			(start -0.120396 0.2794)
			(end 0.12065 0.2794)
			(stroke
				(width 0.1)
				(type default)
			)
			(layer "B.Fab")
		)
		(fp_line
			(start 0.12065 0.2794)
			(end 0.12065 0.3048)
			(stroke
				(width 0.1)
				(type default)
			)
			(layer "B.Fab")
		)
		(fp_line
			(start -0.12065 -0.2794)
			(end -0.12065 -0.3048)
			(stroke
				(width 0.1)
				(type default)
			)
			(layer "B.Fab")
		)
		(fp_line
			(start 0.12065 -0.2794)
			(end -0.12065 -0.2794)
			(stroke
				(width 0.1)
				(type default)
			)
			(layer "B.Fab")
		)
		(fp_line
			(start -0.67945 -0.3048)
			(end -0.67945 0.3048)
			(stroke
				(width 0.1)
				(type default)
			)
			(layer "B.Fab")
		)
		(fp_line
			(start -0.12065 -0.3048)
			(end -0.67945 -0.3048)
			(stroke
				(width 0.1)
				(type default)
			)
			(layer "B.Fab")
		)
		(fp_line
			(start 0.12065 -0.305054)
			(end 0.12065 -0.2794)
			(stroke
				(width 0.1)
				(type default)
			)
			(layer "B.Fab")
		)
		(fp_line
			(start 0.67945 -0.305054)
			(end 0.12065 -0.305054)
			(stroke
				(width 0.1)
				(type default)
			)
			(layer "B.Fab")
		)
		(pad "1" smd circle
			(at 0.40005 0 90)
			(size 0 0)
			(layers "B.Cu" "B.Mask" "B.Paste")
			(net "PVNN_TERM_CPU1")
		)
		(pad "2" smd circle
			(at -0.40005 0 90)
			(size 0 0)
			(layers "B.Cu" "B.Mask" "B.Paste")
			(net "I3C_SPD_DDREFGH_CPU1_SDA")
		)
	)
	(footprint ""
		(layer "B.Cu")
		(at 183.960008 -404.853902 180)
		(property "Reference" "R3924"
			(at 0 0 0)
			(layer "B.SilkS")
			(hide yes)
			(effects
				(font
					(size 1.27 1.27)
				)
				(justify mirror)
			)
		)
		(property "Value" ""
			(at 0 0 0)
			(layer "B.Fab")
			(effects
				(font
					(size 1.27 1.27)
				)
				(justify mirror)
			)
		)
		(duplicate_pad_numbers_are_jumpers no)
		(fp_line
			(start 0.7874 0.4064)
			(end 0.7874 -0.4064)
			(stroke
				(width 0.1524)
				(type default)
			)
			(layer "B.SilkS")
		)
		(fp_line
			(start 0.7874 -0.4064)
			(end -0.7874 -0.4064)
			(stroke
				(width 0.1524)
				(type default)
			)
			(layer "B.SilkS")
		)
		(fp_line
			(start -0.7874 0.4064)
			(end 0.7874 0.4064)
			(stroke
				(width 0.1524)
				(type default)
			)
			(layer "B.SilkS")
		)
		(fp_line
			(start -0.7874 -0.4064)
			(end -0.7874 0.4064)
			(stroke
				(width 0.1524)
				(type default)
			)
			(layer "B.SilkS")
		)
		(fp_line
			(start 0.67945 0.3048)
			(end 0.67945 -0.305054)
			(stroke
				(width 0.1)
				(type default)
			)
			(layer "B.Fab")
		)
		(fp_line
			(start 0.67945 -0.305054)
			(end 0.12065 -0.305054)
			(stroke
				(width 0.1)
				(type default)
			)
			(layer "B.Fab")
		)
		(fp_line
			(start 0.12065 0.3048)
			(end 0.67945 0.3048)
			(stroke
				(width 0.1)
				(type default)
			)
			(layer "B.Fab")
		)
		(fp_line
			(start 0.12065 0.2794)
			(end 0.12065 0.3048)
			(stroke
				(width 0.1)
				(type default)
			)
			(layer "B.Fab")
		)
		(fp_line
			(start 0.12065 -0.2794)
			(end -0.12065 -0.2794)
			(stroke
				(width 0.1)
				(type default)
			)
			(layer "B.Fab")
		)
		(fp_line
			(start 0.12065 -0.305054)
			(end 0.12065 -0.2794)
			(stroke
				(width 0.1)
				(type default)
			)
			(layer "B.Fab")
		)
		(fp_line
			(start -0.120396 0.3048)
			(end -0.120396 0.2794)
			(stroke
				(width 0.1)
				(type default)
			)
			(layer "B.Fab")
		)
		(fp_line
			(start -0.120396 0.2794)
			(end 0.12065 0.2794)
			(stroke
				(width 0.1)
				(type default)
			)
			(layer "B.Fab")
		)
		(fp_line
			(start -0.12065 -0.2794)
			(end -0.12065 -0.3048)
			(stroke
				(width 0.1)
				(type default)
			)
			(layer "B.Fab")
		)
		(fp_line
			(start -0.12065 -0.3048)
			(end -0.67945 -0.3048)
			(stroke
				(width 0.1)
				(type default)
			)
			(layer "B.Fab")
		)
		(fp_line
			(start -0.67945 0.3048)
			(end -0.120396 0.3048)
			(stroke
				(width 0.1)
				(type default)
			)
			(layer "B.Fab")
		)
		(fp_line
			(start -0.67945 -0.3048)
			(end -0.67945 0.3048)
			(stroke
				(width 0.1)
				(type default)
			)
			(layer "B.Fab")
		)
		(pad "1" smd circle
			(at 0.40005 0)
			(size 0 0)
			(layers "B.Cu" "B.Mask" "B.Paste")
			(net "IRQ_SML1_PMBUS_ALERT_N")
		)
		(pad "2" smd circle
			(at -0.40005 0)
			(size 0 0)
			(layers "B.Cu" "B.Mask" "B.Paste")
			(net "IRQ_SML1_PMBUS_ALERT")
		)
	)
	(footprint ""
		(layer "B.Cu")
		(at 352.402902 -212.049614)
		(property "Reference" "C512"
			(at 0 0 0)
			(layer "B.SilkS")
			(hide yes)
			(effects
				(font
					(size 1.27 1.27)
				)
				(justify mirror)
			)
		)
		(property "Value" ""
			(at 0 0 0)
			(layer "B.Fab")
			(effects
				(font
					(size 1.27 1.27)
				)
				(justify mirror)
			)
		)
		(duplicate_pad_numbers_are_jumpers no)
		(fp_line
			(start -1.524 -0.762)
			(end -1.524 0.762)
			(stroke
				(width 0.1524)
				(type default)
			)
			(layer "B.SilkS")
		)
		(fp_line
			(start -1.524 0.762)
			(end 1.524 0.762)
			(stroke
				(width 0.1524)
				(type default)
			)
			(layer "B.SilkS")
		)
		(fp_line
			(start 1.524 -0.762)
			(end -1.524 -0.762)
			(stroke
				(width 0.1524)
				(type default)
			)
			(layer "B.SilkS")
		)
		(fp_line
			(start 1.524 0.762)
			(end 1.524 -0.762)
			(stroke
				(width 0.1524)
				(type default)
			)
			(layer "B.SilkS")
		)
		(fp_line
			(start -1.1049 -0.724916)
			(end 1.1049 -0.724916)
			(stroke
				(width 0.1)
				(type default)
			)
			(layer "B.Fab")
		)
		(fp_line
			(start -1.1049 0.724916)
			(end -1.1049 -0.724916)
			(stroke
				(width 0.1)
				(type default)
			)
			(layer "B.Fab")
		)
		(fp_line
			(start 1.1049 -0.724916)
			(end 1.1049 0.724916)
			(stroke
				(width 0.1)
				(type default)
			)
			(layer "B.Fab")
		)
		(fp_line
			(start 1.1049 0.724916)
			(end -1.1049 0.724916)
			(stroke
				(width 0.1)
				(type default)
			)
			(layer "B.Fab")
		)
		(pad "1" smd rect
			(at 0.889 0)
			(size 1.016 1.27)
			(layers "B.Cu" "B.Mask" "B.Paste")
			(net "PVCCFA_EHV_CPU0")
		)
		(pad "2" smd rect
			(at -0.889 0)
			(size 1.016 1.27)
			(layers "B.Cu" "B.Mask" "B.Paste")
			(net "GND")
		)
	)
	(footprint ""
		(layer "B.Cu")
		(at 85.457284 -190.705232 -90)
		(property "Reference" "R261"
			(at 0 0 90)
			(layer "B.SilkS")
			(hide yes)
			(effects
				(font
					(size 1.27 1.27)
				)
				(justify mirror)
			)
		)
		(property "Value" ""
			(at 0 0 90)
			(layer "B.Fab")
			(effects
				(font
					(size 1.27 1.27)
				)
				(justify mirror)
			)
		)
		(duplicate_pad_numbers_are_jumpers no)
		(fp_line
			(start -0.7874 0.4064)
			(end 0.7874 0.4064)
			(stroke
				(width 0.1524)
				(type default)
			)
			(layer "B.SilkS")
		)
		(fp_line
			(start 0.7874 0.4064)
			(end 0.7874 -0.4064)
			(stroke
				(width 0.1524)
				(type default)
			)
			(layer "B.SilkS")
		)
		(fp_line
			(start -0.7874 -0.4064)
			(end -0.7874 0.4064)
			(stroke
				(width 0.1524)
				(type default)
			)
			(layer "B.SilkS")
		)
		(fp_line
			(start 0.7874 -0.4064)
			(end -0.7874 -0.4064)
			(stroke
				(width 0.1524)
				(type default)
			)
			(layer "B.SilkS")
		)
		(fp_line
			(start -0.67945 0.3048)
			(end -0.120396 0.3048)
			(stroke
				(width 0.1)
				(type default)
			)
			(layer "B.Fab")
		)
		(fp_line
			(start -0.120396 0.3048)
			(end -0.120396 0.2794)
			(stroke
				(width 0.1)
				(type default)
			)
			(layer "B.Fab")
		)
		(fp_line
			(start 0.12065 0.3048)
			(end 0.67945 0.3048)
			(stroke
				(width 0.1)
				(type default)
			)
			(layer "B.Fab")
		)
		(fp_line
			(start 0.67945 0.3048)
			(end 0.67945 -0.305054)
			(stroke
				(width 0.1)
				(type default)
			)
			(layer "B.Fab")
		)
		(fp_line
			(start -0.120396 0.2794)
			(end 0.12065 0.2794)
			(stroke
				(width 0.1)
				(type default)
			)
			(layer "B.Fab")
		)
		(fp_line
			(start 0.12065 0.2794)
			(end 0.12065 0.3048)
			(stroke
				(width 0.1)
				(type default)
			)
			(layer "B.Fab")
		)
		(fp_line
			(start -0.12065 -0.2794)
			(end -0.12065 -0.3048)
			(stroke
				(width 0.1)
				(type default)
			)
			(layer "B.Fab")
		)
		(fp_line
			(start 0.12065 -0.2794)
			(end -0.12065 -0.2794)
			(stroke
				(width 0.1)
				(type default)
			)
			(layer "B.Fab")
		)
		(fp_line
			(start -0.67945 -0.3048)
			(end -0.67945 0.3048)
			(stroke
				(width 0.1)
				(type default)
			)
			(layer "B.Fab")
		)
		(fp_line
			(start -0.12065 -0.3048)
			(end -0.67945 -0.3048)
			(stroke
				(width 0.1)
				(type default)
			)
			(layer "B.Fab")
		)
		(fp_line
			(start 0.12065 -0.305054)
			(end 0.12065 -0.2794)
			(stroke
				(width 0.1)
				(type default)
			)
			(layer "B.Fab")
		)
		(fp_line
			(start 0.67945 -0.305054)
			(end 0.12065 -0.305054)
			(stroke
				(width 0.1)
				(type default)
			)
			(layer "B.Fab")
		)
		(pad "1" smd circle
			(at 0.40005 0 90)
			(size 0 0)
			(layers "B.Cu" "B.Mask" "B.Paste")
			(net "PVNN_TERM_CPU1")
		)
		(pad "2" smd circle
			(at -0.40005 0 90)
			(size 0 0)
			(layers "B.Cu" "B.Mask" "B.Paste")
			(net "PU_CPU1_TXT_AGENT")
		)
	)
	(footprint ""
		(layer "B.Cu")
		(at 373.810276 -366.755426 90)
		(property "Reference" "PC1256"
			(at 0 0 90)
			(layer "B.SilkS")
			(hide yes)
			(effects
				(font
					(size 1.27 1.27)
				)
				(justify mirror)
			)
		)
		(property "Value" ""
			(at 0 0 90)
			(layer "B.Fab")
			(effects
				(font
					(size 1.27 1.27)
				)
				(justify mirror)
			)
		)
		(duplicate_pad_numbers_are_jumpers no)
		(fp_line
			(start 1.524 -0.762)
			(end -1.524 -0.762)
			(stroke
				(width 0.1524)
				(type default)
			)
			(layer "B.SilkS")
		)
		(fp_line
			(start -1.524 -0.762)
			(end -1.524 0.762)
			(stroke
				(width 0.1524)
				(type default)
			)
			(layer "B.SilkS")
		)
		(fp_line
			(start 1.524 0.762)
			(end 1.524 -0.762)
			(stroke
				(width 0.1524)
				(type default)
			)
			(layer "B.SilkS")
		)
		(fp_line
			(start -1.524 0.762)
			(end 1.524 0.762)
			(stroke
				(width 0.1524)
				(type default)
			)
			(layer "B.SilkS")
		)
		(fp_line
			(start 1.1049 -0.724916)
			(end 1.1049 0.724916)
			(stroke
				(width 0.1)
				(type default)
			)
			(layer "B.Fab")
		)
		(fp_line
			(start -1.1049 -0.724916)
			(end 1.1049 -0.724916)
			(stroke
				(width 0.1)
				(type default)
			)
			(layer "B.Fab")
		)
		(fp_line
			(start 1.1049 0.724916)
			(end -1.1049 0.724916)
			(stroke
				(width 0.1)
				(type default)
			)
			(layer "B.Fab")
		)
		(fp_line
			(start -1.1049 0.724916)
			(end -1.1049 -0.724916)
			(stroke
				(width 0.1)
				(type default)
			)
			(layer "B.Fab")
		)
		(pad "1" smd rect
			(at 0.889 0 90)
			(size 1.016 1.27)
			(layers "B.Cu" "B.Mask" "B.Paste")
			(net "PVPP_HBM_CPU0")
		)
		(pad "2" smd rect
			(at -0.889 0 90)
			(size 1.016 1.27)
			(layers "B.Cu" "B.Mask" "B.Paste")
			(net "GND")
		)
	)
	(footprint ""
		(layer "B.Cu")
		(at 440.137804 -18.27022)
		(property "Reference" "C1232"
			(at 0 0 0)
			(layer "B.SilkS")
			(hide yes)
			(effects
				(font
					(size 1.27 1.27)
				)
				(justify mirror)
			)
		)
		(property "Value" ""
			(at 0 0 0)
			(layer "B.Fab")
			(effects
				(font
					(size 1.27 1.27)
				)
				(justify mirror)
			)
		)
		(duplicate_pad_numbers_are_jumpers no)
		(fp_line
			(start -1.524 -0.762)
			(end -1.524 0.762)
			(stroke
				(width 0.1524)
				(type default)
			)
			(layer "B.SilkS")
		)
		(fp_line
			(start -1.524 0.762)
			(end 1.524 0.762)
			(stroke
				(width 0.1524)
				(type default)
			)
			(layer "B.SilkS")
		)
		(fp_line
			(start 1.524 -0.762)
			(end -1.524 -0.762)
			(stroke
				(width 0.1524)
				(type default)
			)
			(layer "B.SilkS")
		)
		(fp_line
			(start 1.524 0.762)
			(end 1.524 -0.762)
			(stroke
				(width 0.1524)
				(type default)
			)
			(layer "B.SilkS")
		)
		(fp_line
			(start -1.1049 -0.724916)
			(end 1.1049 -0.724916)
			(stroke
				(width 0.1)
				(type default)
			)
			(layer "B.Fab")
		)
		(fp_line
			(start -1.1049 0.724916)
			(end -1.1049 -0.724916)
			(stroke
				(width 0.1)
				(type default)
			)
			(layer "B.Fab")
		)
		(fp_line
			(start 1.1049 -0.724916)
			(end 1.1049 0.724916)
			(stroke
				(width 0.1)
				(type default)
			)
			(layer "B.Fab")
		)
		(fp_line
			(start 1.1049 0.724916)
			(end -1.1049 0.724916)
			(stroke
				(width 0.1)
				(type default)
			)
			(layer "B.Fab")
		)
		(pad "1" smd rect
			(at 0.889 0)
			(size 1.016 1.27)
			(layers "B.Cu" "B.Mask" "B.Paste")
			(net "P12V_OCP_SFF")
		)
		(pad "2" smd rect
			(at -0.889 0)
			(size 1.016 1.27)
			(layers "B.Cu" "B.Mask" "B.Paste")
			(net "GND")
		)
	)
	(footprint ""
		(layer "B.Cu")
		(at 179.360068 -397.188182)
		(property "Reference" "PR3929"
			(at 0 0 0)
			(layer "B.SilkS")
			(hide yes)
			(effects
				(font
					(size 1.27 1.27)
				)
				(justify mirror)
			)
		)
		(property "Value" ""
			(at 0 0 0)
			(layer "B.Fab")
			(effects
				(font
					(size 1.27 1.27)
				)
				(justify mirror)
			)
		)
		(duplicate_pad_numbers_are_jumpers no)
		(fp_line
			(start -0.7874 -0.4064)
			(end -0.7874 0.4064)
			(stroke
				(width 0.1524)
				(type default)
			)
			(layer "B.SilkS")
		)
		(fp_line
			(start -0.7874 0.4064)
			(end 0.7874 0.4064)
			(stroke
				(width 0.1524)
				(type default)
			)
			(layer "B.SilkS")
		)
		(fp_line
			(start 0.7874 -0.4064)
			(end -0.7874 -0.4064)
			(stroke
				(width 0.1524)
				(type default)
			)
			(layer "B.SilkS")
		)
		(fp_line
			(start 0.7874 0.4064)
			(end 0.7874 -0.4064)
			(stroke
				(width 0.1524)
				(type default)
			)
			(layer "B.SilkS")
		)
		(fp_line
			(start -0.67945 -0.3048)
			(end -0.67945 0.3048)
			(stroke
				(width 0.1)
				(type default)
			)
			(layer "B.Fab")
		)
		(fp_line
			(start -0.67945 0.3048)
			(end -0.120396 0.3048)
			(stroke
				(width 0.1)
				(type default)
			)
			(layer "B.Fab")
		)
		(fp_line
			(start -0.12065 -0.3048)
			(end -0.67945 -0.3048)
			(stroke
				(width 0.1)
				(type default)
			)
			(layer "B.Fab")
		)
		(fp_line
			(start -0.12065 -0.2794)
			(end -0.12065 -0.3048)
			(stroke
				(width 0.1)
				(type default)
			)
			(layer "B.Fab")
		)
		(fp_line
			(start -0.120396 0.2794)
			(end 0.12065 0.2794)
			(stroke
				(width 0.1)
				(type default)
			)
			(layer "B.Fab")
		)
		(fp_line
			(start -0.120396 0.3048)
			(end -0.120396 0.2794)
			(stroke
				(width 0.1)
				(type default)
			)
			(layer "B.Fab")
		)
		(fp_line
			(start 0.12065 -0.305054)
			(end 0.12065 -0.2794)
			(stroke
				(width 0.1)
				(type default)
			)
			(layer "B.Fab")
		)
		(fp_line
			(start 0.12065 -0.2794)
			(end -0.12065 -0.2794)
			(stroke
				(width 0.1)
				(type default)
			)
			(layer "B.Fab")
		)
		(fp_line
			(start 0.12065 0.2794)
			(end 0.12065 0.3048)
			(stroke
				(width 0.1)
				(type default)
			)
			(layer "B.Fab")
		)
		(fp_line
			(start 0.12065 0.3048)
			(end 0.67945 0.3048)
			(stroke
				(width 0.1)
				(type default)
			)
			(layer "B.Fab")
		)
		(fp_line
			(start 0.67945 -0.305054)
			(end 0.12065 -0.305054)
			(stroke
				(width 0.1)
				(type default)
			)
			(layer "B.Fab")
		)
		(fp_line
			(start 0.67945 0.3048)
			(end 0.67945 -0.305054)
			(stroke
				(width 0.1)
				(type default)
			)
			(layer "B.Fab")
		)
		(pad "1" smd circle
			(at 0.40005 0 180)
			(size 0 0)
			(layers "B.Cu" "B.Mask" "B.Paste")
			(net "HSC_ADDR")
		)
		(pad "2" smd circle
			(at -0.40005 0 180)
			(size 0 0)
			(layers "B.Cu" "B.Mask" "B.Paste")
			(net "HSC_VDD18")
		)
	)
	(footprint ""
		(layer "B.Cu")
		(at 418.540692 -166.050214 180)
		(property "Reference" "PR1785"
			(at 0 0 0)
			(layer "B.SilkS")
			(hide yes)
			(effects
				(font
					(size 1.27 1.27)
				)
				(justify mirror)
			)
		)
		(property "Value" ""
			(at 0 0 0)
			(layer "B.Fab")
			(effects
				(font
					(size 1.27 1.27)
				)
				(justify mirror)
			)
		)
		(duplicate_pad_numbers_are_jumpers no)
		(fp_line
			(start 0.7874 0.4064)
			(end 0.7874 -0.4064)
			(stroke
				(width 0.1524)
				(type default)
			)
			(layer "B.SilkS")
		)
		(fp_line
			(start 0.7874 -0.4064)
			(end -0.7874 -0.4064)
			(stroke
				(width 0.1524)
				(type default)
			)
			(layer "B.SilkS")
		)
		(fp_line
			(start -0.7874 0.4064)
			(end 0.7874 0.4064)
			(stroke
				(width 0.1524)
				(type default)
			)
			(layer "B.SilkS")
		)
		(fp_line
			(start -0.7874 -0.4064)
			(end -0.7874 0.4064)
			(stroke
				(width 0.1524)
				(type default)
			)
			(layer "B.SilkS")
		)
		(fp_line
			(start 0.67945 0.3048)
			(end 0.67945 -0.305054)
			(stroke
				(width 0.1)
				(type default)
			)
			(layer "B.Fab")
		)
		(fp_line
			(start 0.67945 -0.305054)
			(end 0.12065 -0.305054)
			(stroke
				(width 0.1)
				(type default)
			)
			(layer "B.Fab")
		)
		(fp_line
			(start 0.12065 0.3048)
			(end 0.67945 0.3048)
			(stroke
				(width 0.1)
				(type default)
			)
			(layer "B.Fab")
		)
		(fp_line
			(start 0.12065 0.2794)
			(end 0.12065 0.3048)
			(stroke
				(width 0.1)
				(type default)
			)
			(layer "B.Fab")
		)
		(fp_line
			(start 0.12065 -0.2794)
			(end -0.12065 -0.2794)
			(stroke
				(width 0.1)
				(type default)
			)
			(layer "B.Fab")
		)
		(fp_line
			(start 0.12065 -0.305054)
			(end 0.12065 -0.2794)
			(stroke
				(width 0.1)
				(type default)
			)
			(layer "B.Fab")
		)
		(fp_line
			(start -0.120396 0.3048)
			(end -0.120396 0.2794)
			(stroke
				(width 0.1)
				(type default)
			)
			(layer "B.Fab")
		)
		(fp_line
			(start -0.120396 0.2794)
			(end 0.12065 0.2794)
			(stroke
				(width 0.1)
				(type default)
			)
			(layer "B.Fab")
		)
		(fp_line
			(start -0.12065 -0.2794)
			(end -0.12065 -0.3048)
			(stroke
				(width 0.1)
				(type default)
			)
			(layer "B.Fab")
		)
		(fp_line
			(start -0.12065 -0.3048)
			(end -0.67945 -0.3048)
			(stroke
				(width 0.1)
				(type default)
			)
			(layer "B.Fab")
		)
		(fp_line
			(start -0.67945 0.3048)
			(end -0.120396 0.3048)
			(stroke
				(width 0.1)
				(type default)
			)
			(layer "B.Fab")
		)
		(fp_line
			(start -0.67945 -0.3048)
			(end -0.67945 0.3048)
			(stroke
				(width 0.1)
				(type default)
			)
			(layer "B.Fab")
		)
		(pad "1" smd circle
			(at 0.40005 0)
			(size 0 0)
			(layers "B.Cu" "B.Mask" "B.Paste")
			(net "PVCCD_HV_CPU0_VOS")
		)
		(pad "2" smd circle
			(at -0.40005 0)
			(size 0 0)
			(layers "B.Cu" "B.Mask" "B.Paste")
			(net "PVCCD_HV_CPU0")
		)
	)
	(footprint ""
		(layer "B.Cu")
		(at 76.89088 -11.267948 90)
		(property "Reference" "R3168"
			(at 0 0 90)
			(layer "B.SilkS")
			(hide yes)
			(effects
				(font
					(size 1.27 1.27)
				)
				(justify mirror)
			)
		)
		(property "Value" ""
			(at 0 0 90)
			(layer "B.Fab")
			(effects
				(font
					(size 1.27 1.27)
				)
				(justify mirror)
			)
		)
		(duplicate_pad_numbers_are_jumpers no)
		(fp_line
			(start 0.7874 -0.4064)
			(end -0.7874 -0.4064)
			(stroke
				(width 0.1524)
				(type default)
			)
			(layer "B.SilkS")
		)
		(fp_line
			(start -0.7874 -0.4064)
			(end -0.7874 0.4064)
			(stroke
				(width 0.1524)
				(type default)
			)
			(layer "B.SilkS")
		)
		(fp_line
			(start 0.7874 0.4064)
			(end 0.7874 -0.4064)
			(stroke
				(width 0.1524)
				(type default)
			)
			(layer "B.SilkS")
		)
		(fp_line
			(start -0.7874 0.4064)
			(end 0.7874 0.4064)
			(stroke
				(width 0.1524)
				(type default)
			)
			(layer "B.SilkS")
		)
		(fp_line
			(start 0.67945 -0.305054)
			(end 0.12065 -0.305054)
			(stroke
				(width 0.1)
				(type default)
			)
			(layer "B.Fab")
		)
		(fp_line
			(start 0.12065 -0.305054)
			(end 0.12065 -0.2794)
			(stroke
				(width 0.1)
				(type default)
			)
			(layer "B.Fab")
		)
		(fp_line
			(start -0.12065 -0.3048)
			(end -0.67945 -0.3048)
			(stroke
				(width 0.1)
				(type default)
			)
			(layer "B.Fab")
		)
		(fp_line
			(start -0.67945 -0.3048)
			(end -0.67945 0.3048)
			(stroke
				(width 0.1)
				(type default)
			)
			(layer "B.Fab")
		)
		(fp_line
			(start 0.12065 -0.2794)
			(end -0.12065 -0.2794)
			(stroke
				(width 0.1)
				(type default)
			)
			(layer "B.Fab")
		)
		(fp_line
			(start -0.12065 -0.2794)
			(end -0.12065 -0.3048)
			(stroke
				(width 0.1)
				(type default)
			)
			(layer "B.Fab")
		)
		(fp_line
			(start 0.12065 0.2794)
			(end 0.12065 0.3048)
			(stroke
				(width 0.1)
				(type default)
			)
			(layer "B.Fab")
		)
		(fp_line
			(start -0.120396 0.2794)
			(end 0.12065 0.2794)
			(stroke
				(width 0.1)
				(type default)
			)
			(layer "B.Fab")
		)
		(fp_line
			(start 0.67945 0.3048)
			(end 0.67945 -0.305054)
			(stroke
				(width 0.1)
				(type default)
			)
			(layer "B.Fab")
		)
		(fp_line
			(start 0.12065 0.3048)
			(end 0.67945 0.3048)
			(stroke
				(width 0.1)
				(type default)
			)
			(layer "B.Fab")
		)
		(fp_line
			(start -0.120396 0.3048)
			(end -0.120396 0.2794)
			(stroke
				(width 0.1)
				(type default)
			)
			(layer "B.Fab")
		)
		(fp_line
			(start -0.67945 0.3048)
			(end -0.120396 0.3048)
			(stroke
				(width 0.1)
				(type default)
			)
			(layer "B.Fab")
		)
		(pad "1" smd circle
			(at 0.40005 0 270)
			(size 0 0)
			(layers "B.Cu" "B.Mask" "B.Paste")
			(net "OCP_V3_2_MAIN_PWR_EN")
		)
		(pad "2" smd circle
			(at -0.40005 0 270)
			(size 0 0)
			(layers "B.Cu" "B.Mask" "B.Paste")
			(net "OCP_V3_2_MAIN_PWR_EN_R")
		)
	)
	(footprint ""
		(layer "B.Cu")
		(at 434.34635 -5.052568 -90)
		(property "Reference" "R435"
			(at 0 0 90)
			(layer "B.SilkS")
			(hide yes)
			(effects
				(font
					(size 1.27 1.27)
				)
				(justify mirror)
			)
		)
		(property "Value" ""
			(at 0 0 90)
			(layer "B.Fab")
			(effects
				(font
					(size 1.27 1.27)
				)
				(justify mirror)
			)
		)
		(duplicate_pad_numbers_are_jumpers no)
		(fp_line
			(start -0.7874 0.4064)
			(end 0.7874 0.4064)
			(stroke
				(width 0.1524)
				(type default)
			)
			(layer "B.SilkS")
		)
		(fp_line
			(start 0.7874 0.4064)
			(end 0.7874 -0.4064)
			(stroke
				(width 0.1524)
				(type default)
			)
			(layer "B.SilkS")
		)
		(fp_line
			(start -0.7874 -0.4064)
			(end -0.7874 0.4064)
			(stroke
				(width 0.1524)
				(type default)
			)
			(layer "B.SilkS")
		)
		(fp_line
			(start 0.7874 -0.4064)
			(end -0.7874 -0.4064)
			(stroke
				(width 0.1524)
				(type default)
			)
			(layer "B.SilkS")
		)
		(fp_line
			(start -0.67945 0.3048)
			(end -0.120396 0.3048)
			(stroke
				(width 0.1)
				(type default)
			)
			(layer "B.Fab")
		)
		(fp_line
			(start -0.120396 0.3048)
			(end -0.120396 0.2794)
			(stroke
				(width 0.1)
				(type default)
			)
			(layer "B.Fab")
		)
		(fp_line
			(start 0.12065 0.3048)
			(end 0.67945 0.3048)
			(stroke
				(width 0.1)
				(type default)
			)
			(layer "B.Fab")
		)
		(fp_line
			(start 0.67945 0.3048)
			(end 0.67945 -0.305054)
			(stroke
				(width 0.1)
				(type default)
			)
			(layer "B.Fab")
		)
		(fp_line
			(start -0.120396 0.2794)
			(end 0.12065 0.2794)
			(stroke
				(width 0.1)
				(type default)
			)
			(layer "B.Fab")
		)
		(fp_line
			(start 0.12065 0.2794)
			(end 0.12065 0.3048)
			(stroke
				(width 0.1)
				(type default)
			)
			(layer "B.Fab")
		)
		(fp_line
			(start -0.12065 -0.2794)
			(end -0.12065 -0.3048)
			(stroke
				(width 0.1)
				(type default)
			)
			(layer "B.Fab")
		)
		(fp_line
			(start 0.12065 -0.2794)
			(end -0.12065 -0.2794)
			(stroke
				(width 0.1)
				(type default)
			)
			(layer "B.Fab")
		)
		(fp_line
			(start -0.67945 -0.3048)
			(end -0.67945 0.3048)
			(stroke
				(width 0.1)
				(type default)
			)
			(layer "B.Fab")
		)
		(fp_line
			(start -0.12065 -0.3048)
			(end -0.67945 -0.3048)
			(stroke
				(width 0.1)
				(type default)
			)
			(layer "B.Fab")
		)
		(fp_line
			(start 0.12065 -0.305054)
			(end 0.12065 -0.2794)
			(stroke
				(width 0.1)
				(type default)
			)
			(layer "B.Fab")
		)
		(fp_line
			(start 0.67945 -0.305054)
			(end 0.12065 -0.305054)
			(stroke
				(width 0.1)
				(type default)
			)
			(layer "B.Fab")
		)
		(pad "1" smd circle
			(at 0.40005 0 90)
			(size 0 0)
			(layers "B.Cu" "B.Mask" "B.Paste")
			(net "RST_OCP_V3_1_BUF_N")
		)
		(pad "2" smd circle
			(at -0.40005 0 90)
			(size 0 0)
			(layers "B.Cu" "B.Mask" "B.Paste")
			(net "RST_PERST1_OCP_SFF_N")
		)
	)
	(footprint ""
		(layer "B.Cu")
		(at 132.89661 -337.145884 90)
		(property "Reference" "PC516_P1_5"
			(at 0 0 90)
			(layer "B.SilkS")
			(hide yes)
			(effects
				(font
					(size 1.27 1.27)
				)
				(justify mirror)
			)
		)
		(property "Value" ""
			(at 0 0 90)
			(layer "B.Fab")
			(effects
				(font
					(size 1.27 1.27)
				)
				(justify mirror)
			)
		)
		(duplicate_pad_numbers_are_jumpers no)
		(fp_line
			(start 1.524 -0.762)
			(end -1.524 -0.762)
			(stroke
				(width 0.1524)
				(type default)
			)
			(layer "B.SilkS")
		)
		(fp_line
			(start -1.524 -0.762)
			(end -1.524 0.762)
			(stroke
				(width 0.1524)
				(type default)
			)
			(layer "B.SilkS")
		)
		(fp_line
			(start 1.524 0.762)
			(end 1.524 -0.762)
			(stroke
				(width 0.1524)
				(type default)
			)
			(layer "B.SilkS")
		)
		(fp_line
			(start -1.524 0.762)
			(end 1.524 0.762)
			(stroke
				(width 0.1524)
				(type default)
			)
			(layer "B.SilkS")
		)
		(fp_line
			(start 1.1049 -0.724916)
			(end 1.1049 0.724916)
			(stroke
				(width 0.1)
				(type default)
			)
			(layer "B.Fab")
		)
		(fp_line
			(start -1.1049 -0.724916)
			(end 1.1049 -0.724916)
			(stroke
				(width 0.1)
				(type default)
			)
			(layer "B.Fab")
		)
		(fp_line
			(start 1.1049 0.724916)
			(end -1.1049 0.724916)
			(stroke
				(width 0.1)
				(type default)
			)
			(layer "B.Fab")
		)
		(fp_line
			(start -1.1049 0.724916)
			(end -1.1049 -0.724916)
			(stroke
				(width 0.1)
				(type default)
			)
			(layer "B.Fab")
		)
		(pad "1" smd rect
			(at 0.889 0 90)
			(size 1.016 1.27)
			(layers "B.Cu" "B.Mask" "B.Paste")
			(net "SW_P12V_PVCCIN_CPU1_FLT")
		)
		(pad "2" smd rect
			(at -0.889 0 90)
			(size 1.016 1.27)
			(layers "B.Cu" "B.Mask" "B.Paste")
			(net "GND")
		)
	)
	(footprint ""
		(layer "B.Cu")
		(at 88.837262 -329.970384 -90)
		(property "Reference" "PC189"
			(at 0 0 90)
			(layer "B.SilkS")
			(hide yes)
			(effects
				(font
					(size 1.27 1.27)
				)
				(justify mirror)
			)
		)
		(property "Value" ""
			(at 0 0 90)
			(layer "B.Fab")
			(effects
				(font
					(size 1.27 1.27)
				)
				(justify mirror)
			)
		)
		(duplicate_pad_numbers_are_jumpers no)
		(fp_line
			(start -4.533392 2.249932)
			(end 4.533392 2.249932)
			(stroke
				(width 0.1524)
				(type default)
			)
			(layer "B.SilkS")
		)
		(fp_line
			(start 4.533392 2.249932)
			(end 4.533392 -2.249932)
			(stroke
				(width 0.1524)
				(type default)
			)
			(layer "B.SilkS")
		)
		(fp_line
			(start -4.533392 -2.249932)
			(end -4.533392 2.249932)
			(stroke
				(width 0.1524)
				(type default)
			)
			(layer "B.SilkS")
		)
		(fp_line
			(start 4.533392 -2.249932)
			(end -4.533392 -2.249932)
			(stroke
				(width 0.1524)
				(type default)
			)
			(layer "B.SilkS")
		)
		(fp_rect
			(start 5.39242 2.326132)
			(end 4.533392 -2.326132)
			(stroke
				(width 0)
				(type default)
			)
			(fill yes)
			(layer "B.SilkS")
		)
		(fp_line
			(start -3.750056 2.249932)
			(end 3.750056 2.249932)
			(stroke
				(width 0.1)
				(type default)
			)
			(layer "B.Fab")
		)
		(fp_line
			(start 3.750056 2.249932)
			(end 3.750056 -2.249932)
			(stroke
				(width 0.1)
				(type default)
			)
			(layer "B.Fab")
		)
		(fp_line
			(start -3.750056 -2.249932)
			(end -3.750056 2.249932)
			(stroke
				(width 0.1)
				(type default)
			)
			(layer "B.Fab")
		)
		(fp_line
			(start 3.750056 -2.249932)
			(end -3.750056 -2.249932)
			(stroke
				(width 0.1)
				(type default)
			)
			(layer "B.Fab")
		)
		(fp_text user "-"
			(at -4.634484 0.883412 270)
			(unlocked yes)
			(layer "B.SilkS")
			(effects
				(font
					(size 1.905 1.4224)
					(thickness 0.1524)
				)
				(justify left mirror)
			)
		)
		(fp_text user "+"
			(at 6.322314 0.786384 180)
			(unlocked yes)
			(layer "B.SilkS")
			(effects
				(font
					(size 1.905 1.4224)
					(thickness 0.1524)
				)
				(justify left mirror)
			)
		)
		(fp_text user "+"
			(at 6.322314 0.786384 180)
			(unlocked yes)
			(layer "B.Fab")
			(effects
				(font
					(size 1.905 1.4224)
					(thickness 0.1524)
				)
				(justify left mirror)
			)
		)
		(fp_text user "-"
			(at -4.8514 -0.14605 270)
			(unlocked yes)
			(layer "B.Fab")
			(effects
				(font
					(size 1.905 1.4224)
					(thickness 0.1524)
				)
				(justify left mirror)
			)
		)
		(pad "1" smd rect
			(at 3.199892 0 90)
			(size 2.413 2.8194)
			(layers "B.Cu" "B.Mask" "B.Paste")
			(net "PVCCIN_CPU1")
		)
		(pad "2" smd rect
			(at -3.199892 0 90)
			(size 2.413 2.8194)
			(layers "B.Cu" "B.Mask" "B.Paste")
			(net "GND")
		)
	)
	(footprint ""
		(layer "B.Cu")
		(at 70.369684 -185.791856 90)
		(property "Reference" "R54"
			(at 0 0 90)
			(layer "B.SilkS")
			(hide yes)
			(effects
				(font
					(size 1.27 1.27)
				)
				(justify mirror)
			)
		)
		(property "Value" ""
			(at 0 0 90)
			(layer "B.Fab")
			(effects
				(font
					(size 1.27 1.27)
				)
				(justify mirror)
			)
		)
		(duplicate_pad_numbers_are_jumpers no)
		(fp_line
			(start 0.7874 -0.4064)
			(end -0.7874 -0.4064)
			(stroke
				(width 0.1524)
				(type default)
			)
			(layer "B.SilkS")
		)
		(fp_line
			(start -0.7874 -0.4064)
			(end -0.7874 0.4064)
			(stroke
				(width 0.1524)
				(type default)
			)
			(layer "B.SilkS")
		)
		(fp_line
			(start 0.7874 0.4064)
			(end 0.7874 -0.4064)
			(stroke
				(width 0.1524)
				(type default)
			)
			(layer "B.SilkS")
		)
		(fp_line
			(start -0.7874 0.4064)
			(end 0.7874 0.4064)
			(stroke
				(width 0.1524)
				(type default)
			)
			(layer "B.SilkS")
		)
		(fp_line
			(start 0.67945 -0.305054)
			(end 0.12065 -0.305054)
			(stroke
				(width 0.1)
				(type default)
			)
			(layer "B.Fab")
		)
		(fp_line
			(start 0.12065 -0.305054)
			(end 0.12065 -0.2794)
			(stroke
				(width 0.1)
				(type default)
			)
			(layer "B.Fab")
		)
		(fp_line
			(start -0.12065 -0.3048)
			(end -0.67945 -0.3048)
			(stroke
				(width 0.1)
				(type default)
			)
			(layer "B.Fab")
		)
		(fp_line
			(start -0.67945 -0.3048)
			(end -0.67945 0.3048)
			(stroke
				(width 0.1)
				(type default)
			)
			(layer "B.Fab")
		)
		(fp_line
			(start 0.12065 -0.2794)
			(end -0.12065 -0.2794)
			(stroke
				(width 0.1)
				(type default)
			)
			(layer "B.Fab")
		)
		(fp_line
			(start -0.12065 -0.2794)
			(end -0.12065 -0.3048)
			(stroke
				(width 0.1)
				(type default)
			)
			(layer "B.Fab")
		)
		(fp_line
			(start 0.12065 0.2794)
			(end 0.12065 0.3048)
			(stroke
				(width 0.1)
				(type default)
			)
			(layer "B.Fab")
		)
		(fp_line
			(start -0.120396 0.2794)
			(end 0.12065 0.2794)
			(stroke
				(width 0.1)
				(type default)
			)
			(layer "B.Fab")
		)
		(fp_line
			(start 0.67945 0.3048)
			(end 0.67945 -0.305054)
			(stroke
				(width 0.1)
				(type default)
			)
			(layer "B.Fab")
		)
		(fp_line
			(start 0.12065 0.3048)
			(end 0.67945 0.3048)
			(stroke
				(width 0.1)
				(type default)
			)
			(layer "B.Fab")
		)
		(fp_line
			(start -0.120396 0.3048)
			(end -0.120396 0.2794)
			(stroke
				(width 0.1)
				(type default)
			)
			(layer "B.Fab")
		)
		(fp_line
			(start -0.67945 0.3048)
			(end -0.120396 0.3048)
			(stroke
				(width 0.1)
				(type default)
			)
			(layer "B.Fab")
		)
		(pad "1" smd circle
			(at 0.40005 0 270)
			(size 0 0)
			(layers "B.Cu" "B.Mask" "B.Paste")
			(net "DBP_CPU1_HOOK9_MBP3_GTL_QS_R_N")
		)
		(pad "2" smd circle
			(at -0.40005 0 270)
			(size 0 0)
			(layers "B.Cu" "B.Mask" "B.Paste")
			(net "DBP_CPU_HOOK9_MBP3_GTL_QS_N")
		)
	)
	(footprint ""
		(layer "B.Cu")
		(at 335.909158 -45.129704 90)
		(property "Reference" "C1214"
			(at 0 0 90)
			(layer "B.SilkS")
			(hide yes)
			(effects
				(font
					(size 1.27 1.27)
				)
				(justify mirror)
			)
		)
		(property "Value" ""
			(at 0 0 90)
			(layer "B.Fab")
			(effects
				(font
					(size 1.27 1.27)
				)
				(justify mirror)
			)
		)
		(duplicate_pad_numbers_are_jumpers no)
		(fp_line
			(start 0.7874 -0.4064)
			(end -0.7874 -0.4064)
			(stroke
				(width 0.1524)
				(type default)
			)
			(layer "B.SilkS")
		)
		(fp_line
			(start -0.7874 -0.4064)
			(end -0.7874 0.4064)
			(stroke
				(width 0.1524)
				(type default)
			)
			(layer "B.SilkS")
		)
		(fp_line
			(start 0.7874 0.4064)
			(end 0.7874 -0.4064)
			(stroke
				(width 0.1524)
				(type default)
			)
			(layer "B.SilkS")
		)
		(fp_line
			(start -0.7874 0.4064)
			(end 0.7874 0.4064)
			(stroke
				(width 0.1524)
				(type default)
			)
			(layer "B.SilkS")
		)
		(fp_line
			(start 0.67945 -0.305054)
			(end 0.12065 -0.305054)
			(stroke
				(width 0.1)
				(type default)
			)
			(layer "B.Fab")
		)
		(fp_line
			(start 0.12065 -0.305054)
			(end 0.12065 -0.2794)
			(stroke
				(width 0.1)
				(type default)
			)
			(layer "B.Fab")
		)
		(fp_line
			(start -0.12065 -0.3048)
			(end -0.67945 -0.3048)
			(stroke
				(width 0.1)
				(type default)
			)
			(layer "B.Fab")
		)
		(fp_line
			(start -0.67945 -0.3048)
			(end -0.67945 0.3048)
			(stroke
				(width 0.1)
				(type default)
			)
			(layer "B.Fab")
		)
		(fp_line
			(start 0.12065 -0.2794)
			(end -0.12065 -0.2794)
			(stroke
				(width 0.1)
				(type default)
			)
			(layer "B.Fab")
		)
		(fp_line
			(start -0.12065 -0.2794)
			(end -0.12065 -0.3048)
			(stroke
				(width 0.1)
				(type default)
			)
			(layer "B.Fab")
		)
		(fp_line
			(start 0.12065 0.2794)
			(end 0.12065 0.3048)
			(stroke
				(width 0.1)
				(type default)
			)
			(layer "B.Fab")
		)
		(fp_line
			(start -0.120396 0.2794)
			(end 0.12065 0.2794)
			(stroke
				(width 0.1)
				(type default)
			)
			(layer "B.Fab")
		)
		(fp_line
			(start 0.67945 0.3048)
			(end 0.67945 -0.305054)
			(stroke
				(width 0.1)
				(type default)
			)
			(layer "B.Fab")
		)
		(fp_line
			(start 0.12065 0.3048)
			(end 0.67945 0.3048)
			(stroke
				(width 0.1)
				(type default)
			)
			(layer "B.Fab")
		)
		(fp_line
			(start -0.120396 0.3048)
			(end -0.120396 0.2794)
			(stroke
				(width 0.1)
				(type default)
			)
			(layer "B.Fab")
		)
		(fp_line
			(start -0.67945 0.3048)
			(end -0.120396 0.3048)
			(stroke
				(width 0.1)
				(type default)
			)
			(layer "B.Fab")
		)
		(pad "1" smd circle
			(at 0.40005 0 270)
			(size 0 0)
			(layers "B.Cu" "B.Mask" "B.Paste")
			(net "P1V05_PCH_AUX")
		)
		(pad "2" smd circle
			(at -0.40005 0 270)
			(size 0 0)
			(layers "B.Cu" "B.Mask" "B.Paste")
			(net "GND")
		)
	)
	(footprint ""
		(layer "B.Cu")
		(at 81.681574 -331.58938 -90)
		(property "Reference" "PC500_P1_7"
			(at 0 0 90)
			(layer "B.SilkS")
			(hide yes)
			(effects
				(font
					(size 1.27 1.27)
				)
				(justify mirror)
			)
		)
		(property "Value" ""
			(at 0 0 90)
			(layer "B.Fab")
			(effects
				(font
					(size 1.27 1.27)
				)
				(justify mirror)
			)
		)
		(duplicate_pad_numbers_are_jumpers no)
		(fp_line
			(start -1.524 0.762)
			(end 1.524 0.762)
			(stroke
				(width 0.1524)
				(type default)
			)
			(layer "B.SilkS")
		)
		(fp_line
			(start 1.524 0.762)
			(end 1.524 -0.762)
			(stroke
				(width 0.1524)
				(type default)
			)
			(layer "B.SilkS")
		)
		(fp_line
			(start -1.524 -0.762)
			(end -1.524 0.762)
			(stroke
				(width 0.1524)
				(type default)
			)
			(layer "B.SilkS")
		)
		(fp_line
			(start 1.524 -0.762)
			(end -1.524 -0.762)
			(stroke
				(width 0.1524)
				(type default)
			)
			(layer "B.SilkS")
		)
		(fp_line
			(start -1.1049 0.724916)
			(end -1.1049 -0.724916)
			(stroke
				(width 0.1)
				(type default)
			)
			(layer "B.Fab")
		)
		(fp_line
			(start 1.1049 0.724916)
			(end -1.1049 0.724916)
			(stroke
				(width 0.1)
				(type default)
			)
			(layer "B.Fab")
		)
		(fp_line
			(start -1.1049 -0.724916)
			(end 1.1049 -0.724916)
			(stroke
				(width 0.1)
				(type default)
			)
			(layer "B.Fab")
		)
		(fp_line
			(start 1.1049 -0.724916)
			(end 1.1049 0.724916)
			(stroke
				(width 0.1)
				(type default)
			)
			(layer "B.Fab")
		)
		(pad "1" smd rect
			(at 0.889 0 270)
			(size 1.016 1.27)
			(layers "B.Cu" "B.Mask" "B.Paste")
			(net "PVCCIN_CPU1")
		)
		(pad "2" smd rect
			(at -0.889 0 270)
			(size 1.016 1.27)
			(layers "B.Cu" "B.Mask" "B.Paste")
			(net "GND")
		)
	)
	(footprint ""
		(layer "B.Cu")
		(at 257.91287 -318.582802)
		(property "Reference" "R32"
			(at 0 0 0)
			(layer "B.SilkS")
			(hide yes)
			(effects
				(font
					(size 1.27 1.27)
				)
				(justify mirror)
			)
		)
		(property "Value" ""
			(at 0 0 0)
			(layer "B.Fab")
			(effects
				(font
					(size 1.27 1.27)
				)
				(justify mirror)
			)
		)
		(duplicate_pad_numbers_are_jumpers no)
		(fp_line
			(start -0.7874 -0.4064)
			(end -0.7874 0.4064)
			(stroke
				(width 0.1524)
				(type default)
			)
			(layer "B.SilkS")
		)
		(fp_line
			(start -0.7874 0.4064)
			(end 0.7874 0.4064)
			(stroke
				(width 0.1524)
				(type default)
			)
			(layer "B.SilkS")
		)
		(fp_line
			(start 0.7874 -0.4064)
			(end -0.7874 -0.4064)
			(stroke
				(width 0.1524)
				(type default)
			)
			(layer "B.SilkS")
		)
		(fp_line
			(start 0.7874 0.4064)
			(end 0.7874 -0.4064)
			(stroke
				(width 0.1524)
				(type default)
			)
			(layer "B.SilkS")
		)
		(fp_line
			(start -0.67945 -0.3048)
			(end -0.67945 0.3048)
			(stroke
				(width 0.1)
				(type default)
			)
			(layer "B.Fab")
		)
		(fp_line
			(start -0.67945 0.3048)
			(end -0.120396 0.3048)
			(stroke
				(width 0.1)
				(type default)
			)
			(layer "B.Fab")
		)
		(fp_line
			(start -0.12065 -0.3048)
			(end -0.67945 -0.3048)
			(stroke
				(width 0.1)
				(type default)
			)
			(layer "B.Fab")
		)
		(fp_line
			(start -0.12065 -0.2794)
			(end -0.12065 -0.3048)
			(stroke
				(width 0.1)
				(type default)
			)
			(layer "B.Fab")
		)
		(fp_line
			(start -0.120396 0.2794)
			(end 0.12065 0.2794)
			(stroke
				(width 0.1)
				(type default)
			)
			(layer "B.Fab")
		)
		(fp_line
			(start -0.120396 0.3048)
			(end -0.120396 0.2794)
			(stroke
				(width 0.1)
				(type default)
			)
			(layer "B.Fab")
		)
		(fp_line
			(start 0.12065 -0.305054)
			(end 0.12065 -0.2794)
			(stroke
				(width 0.1)
				(type default)
			)
			(layer "B.Fab")
		)
		(fp_line
			(start 0.12065 -0.2794)
			(end -0.12065 -0.2794)
			(stroke
				(width 0.1)
				(type default)
			)
			(layer "B.Fab")
		)
		(fp_line
			(start 0.12065 0.2794)
			(end 0.12065 0.3048)
			(stroke
				(width 0.1)
				(type default)
			)
			(layer "B.Fab")
		)
		(fp_line
			(start 0.12065 0.3048)
			(end 0.67945 0.3048)
			(stroke
				(width 0.1)
				(type default)
			)
			(layer "B.Fab")
		)
		(fp_line
			(start 0.67945 -0.305054)
			(end 0.12065 -0.305054)
			(stroke
				(width 0.1)
				(type default)
			)
			(layer "B.Fab")
		)
		(fp_line
			(start 0.67945 0.3048)
			(end 0.67945 -0.305054)
			(stroke
				(width 0.1)
				(type default)
			)
			(layer "B.Fab")
		)
		(pad "1" smd circle
			(at 0.40005 0 180)
			(size 0 0)
			(layers "B.Cu" "B.Mask" "B.Paste")
			(net "PD_CHD_CPU0_DIMM1_SAA")
		)
		(pad "2" smd circle
			(at -0.40005 0 180)
			(size 0 0)
			(layers "B.Cu" "B.Mask" "B.Paste")
			(net "GND")
		)
	)
	(footprint ""
		(layer "B.Cu")
		(at 62.702186 -15.769844 90)
		(property "Reference" "R3216"
			(at 0 0 90)
			(layer "B.SilkS")
			(hide yes)
			(effects
				(font
					(size 1.27 1.27)
				)
				(justify mirror)
			)
		)
		(property "Value" ""
			(at 0 0 90)
			(layer "B.Fab")
			(effects
				(font
					(size 1.27 1.27)
				)
				(justify mirror)
			)
		)
		(duplicate_pad_numbers_are_jumpers no)
		(fp_line
			(start 0.7874 -0.4064)
			(end -0.7874 -0.4064)
			(stroke
				(width 0.1524)
				(type default)
			)
			(layer "B.SilkS")
		)
		(fp_line
			(start -0.7874 -0.4064)
			(end -0.7874 0.4064)
			(stroke
				(width 0.1524)
				(type default)
			)
			(layer "B.SilkS")
		)
		(fp_line
			(start 0.7874 0.4064)
			(end 0.7874 -0.4064)
			(stroke
				(width 0.1524)
				(type default)
			)
			(layer "B.SilkS")
		)
		(fp_line
			(start -0.7874 0.4064)
			(end 0.7874 0.4064)
			(stroke
				(width 0.1524)
				(type default)
			)
			(layer "B.SilkS")
		)
		(fp_line
			(start 0.67945 -0.305054)
			(end 0.12065 -0.305054)
			(stroke
				(width 0.1)
				(type default)
			)
			(layer "B.Fab")
		)
		(fp_line
			(start 0.12065 -0.305054)
			(end 0.12065 -0.2794)
			(stroke
				(width 0.1)
				(type default)
			)
			(layer "B.Fab")
		)
		(fp_line
			(start -0.12065 -0.3048)
			(end -0.67945 -0.3048)
			(stroke
				(width 0.1)
				(type default)
			)
			(layer "B.Fab")
		)
		(fp_line
			(start -0.67945 -0.3048)
			(end -0.67945 0.3048)
			(stroke
				(width 0.1)
				(type default)
			)
			(layer "B.Fab")
		)
		(fp_line
			(start 0.12065 -0.2794)
			(end -0.12065 -0.2794)
			(stroke
				(width 0.1)
				(type default)
			)
			(layer "B.Fab")
		)
		(fp_line
			(start -0.12065 -0.2794)
			(end -0.12065 -0.3048)
			(stroke
				(width 0.1)
				(type default)
			)
			(layer "B.Fab")
		)
		(fp_line
			(start 0.12065 0.2794)
			(end 0.12065 0.3048)
			(stroke
				(width 0.1)
				(type default)
			)
			(layer "B.Fab")
		)
		(fp_line
			(start -0.120396 0.2794)
			(end 0.12065 0.2794)
			(stroke
				(width 0.1)
				(type default)
			)
			(layer "B.Fab")
		)
		(fp_line
			(start 0.67945 0.3048)
			(end 0.67945 -0.305054)
			(stroke
				(width 0.1)
				(type default)
			)
			(layer "B.Fab")
		)
		(fp_line
			(start 0.12065 0.3048)
			(end 0.67945 0.3048)
			(stroke
				(width 0.1)
				(type default)
			)
			(layer "B.Fab")
		)
		(fp_line
			(start -0.120396 0.3048)
			(end -0.120396 0.2794)
			(stroke
				(width 0.1)
				(type default)
			)
			(layer "B.Fab")
		)
		(fp_line
			(start -0.67945 0.3048)
			(end -0.120396 0.3048)
			(stroke
				(width 0.1)
				(type default)
			)
			(layer "B.Fab")
		)
		(pad "1" smd circle
			(at 0.40005 0 270)
			(size 0 0)
			(layers "B.Cu" "B.Mask" "B.Paste")
			(net "OCP_V3_2_ISO_BIF1_EN")
		)
		(pad "2" smd circle
			(at -0.40005 0 270)
			(size 0 0)
			(layers "B.Cu" "B.Mask" "B.Paste")
			(net "GND")
		)
	)
	(footprint ""
		(layer "B.Cu")
		(at 111.490506 -358.522016)
		(property "Reference" "PR453"
			(at 0 0 0)
			(layer "B.SilkS")
			(hide yes)
			(effects
				(font
					(size 1.27 1.27)
				)
				(justify mirror)
			)
		)
		(property "Value" ""
			(at 0 0 0)
			(layer "B.Fab")
			(effects
				(font
					(size 1.27 1.27)
				)
				(justify mirror)
			)
		)
		(duplicate_pad_numbers_are_jumpers no)
		(fp_line
			(start -0.7874 -0.4064)
			(end -0.7874 0.4064)
			(stroke
				(width 0.1524)
				(type default)
			)
			(layer "B.SilkS")
		)
		(fp_line
			(start -0.7874 0.4064)
			(end 0.7874 0.4064)
			(stroke
				(width 0.1524)
				(type default)
			)
			(layer "B.SilkS")
		)
		(fp_line
			(start 0.7874 -0.4064)
			(end -0.7874 -0.4064)
			(stroke
				(width 0.1524)
				(type default)
			)
			(layer "B.SilkS")
		)
		(fp_line
			(start 0.7874 0.4064)
			(end 0.7874 -0.4064)
			(stroke
				(width 0.1524)
				(type default)
			)
			(layer "B.SilkS")
		)
		(fp_line
			(start -0.67945 -0.3048)
			(end -0.67945 0.3048)
			(stroke
				(width 0.1)
				(type default)
			)
			(layer "B.Fab")
		)
		(fp_line
			(start -0.67945 0.3048)
			(end -0.120396 0.3048)
			(stroke
				(width 0.1)
				(type default)
			)
			(layer "B.Fab")
		)
		(fp_line
			(start -0.12065 -0.3048)
			(end -0.67945 -0.3048)
			(stroke
				(width 0.1)
				(type default)
			)
			(layer "B.Fab")
		)
		(fp_line
			(start -0.12065 -0.2794)
			(end -0.12065 -0.3048)
			(stroke
				(width 0.1)
				(type default)
			)
			(layer "B.Fab")
		)
		(fp_line
			(start -0.120396 0.2794)
			(end 0.12065 0.2794)
			(stroke
				(width 0.1)
				(type default)
			)
			(layer "B.Fab")
		)
		(fp_line
			(start -0.120396 0.3048)
			(end -0.120396 0.2794)
			(stroke
				(width 0.1)
				(type default)
			)
			(layer "B.Fab")
		)
		(fp_line
			(start 0.12065 -0.305054)
			(end 0.12065 -0.2794)
			(stroke
				(width 0.1)
				(type default)
			)
			(layer "B.Fab")
		)
		(fp_line
			(start 0.12065 -0.2794)
			(end -0.12065 -0.2794)
			(stroke
				(width 0.1)
				(type default)
			)
			(layer "B.Fab")
		)
		(fp_line
			(start 0.12065 0.2794)
			(end 0.12065 0.3048)
			(stroke
				(width 0.1)
				(type default)
			)
			(layer "B.Fab")
		)
		(fp_line
			(start 0.12065 0.3048)
			(end 0.67945 0.3048)
			(stroke
				(width 0.1)
				(type default)
			)
			(layer "B.Fab")
		)
		(fp_line
			(start 0.67945 -0.305054)
			(end 0.12065 -0.305054)
			(stroke
				(width 0.1)
				(type default)
			)
			(layer "B.Fab")
		)
		(fp_line
			(start 0.67945 0.3048)
			(end 0.67945 -0.305054)
			(stroke
				(width 0.1)
				(type default)
			)
			(layer "B.Fab")
		)
		(pad "1" smd circle
			(at 0.40005 0 180)
			(size 0 0)
			(layers "B.Cu" "B.Mask" "B.Paste")
			(net "PVCCFA_EHV_FIVRA_CPU1_BTSEN")
		)
		(pad "2" smd circle
			(at -0.40005 0 180)
			(size 0 0)
			(layers "B.Cu" "B.Mask" "B.Paste")
			(net "GND")
		)
	)
	(footprint ""
		(layer "B.Cu")
		(at 298.47413 -403.031452 90)
		(property "Reference" "PR2510"
			(at 0 0 90)
			(layer "B.SilkS")
			(hide yes)
			(effects
				(font
					(size 1.27 1.27)
				)
				(justify mirror)
			)
		)
		(property "Value" ""
			(at 0 0 90)
			(layer "B.Fab")
			(effects
				(font
					(size 1.27 1.27)
				)
				(justify mirror)
			)
		)
		(duplicate_pad_numbers_are_jumpers no)
		(fp_line
			(start 0.7874 -0.4064)
			(end -0.7874 -0.4064)
			(stroke
				(width 0.1524)
				(type default)
			)
			(layer "B.SilkS")
		)
		(fp_line
			(start -0.7874 -0.4064)
			(end -0.7874 0.4064)
			(stroke
				(width 0.1524)
				(type default)
			)
			(layer "B.SilkS")
		)
		(fp_line
			(start 0.7874 0.4064)
			(end 0.7874 -0.4064)
			(stroke
				(width 0.1524)
				(type default)
			)
			(layer "B.SilkS")
		)
		(fp_line
			(start -0.7874 0.4064)
			(end 0.7874 0.4064)
			(stroke
				(width 0.1524)
				(type default)
			)
			(layer "B.SilkS")
		)
		(fp_line
			(start 0.67945 -0.305054)
			(end 0.12065 -0.305054)
			(stroke
				(width 0.1)
				(type default)
			)
			(layer "B.Fab")
		)
		(fp_line
			(start 0.12065 -0.305054)
			(end 0.12065 -0.2794)
			(stroke
				(width 0.1)
				(type default)
			)
			(layer "B.Fab")
		)
		(fp_line
			(start -0.12065 -0.3048)
			(end -0.67945 -0.3048)
			(stroke
				(width 0.1)
				(type default)
			)
			(layer "B.Fab")
		)
		(fp_line
			(start -0.67945 -0.3048)
			(end -0.67945 0.3048)
			(stroke
				(width 0.1)
				(type default)
			)
			(layer "B.Fab")
		)
		(fp_line
			(start 0.12065 -0.2794)
			(end -0.12065 -0.2794)
			(stroke
				(width 0.1)
				(type default)
			)
			(layer "B.Fab")
		)
		(fp_line
			(start -0.12065 -0.2794)
			(end -0.12065 -0.3048)
			(stroke
				(width 0.1)
				(type default)
			)
			(layer "B.Fab")
		)
		(fp_line
			(start 0.12065 0.2794)
			(end 0.12065 0.3048)
			(stroke
				(width 0.1)
				(type default)
			)
			(layer "B.Fab")
		)
		(fp_line
			(start -0.120396 0.2794)
			(end 0.12065 0.2794)
			(stroke
				(width 0.1)
				(type default)
			)
			(layer "B.Fab")
		)
		(fp_line
			(start 0.67945 0.3048)
			(end 0.67945 -0.305054)
			(stroke
				(width 0.1)
				(type default)
			)
			(layer "B.Fab")
		)
		(fp_line
			(start 0.12065 0.3048)
			(end 0.67945 0.3048)
			(stroke
				(width 0.1)
				(type default)
			)
			(layer "B.Fab")
		)
		(fp_line
			(start -0.120396 0.3048)
			(end -0.120396 0.2794)
			(stroke
				(width 0.1)
				(type default)
			)
			(layer "B.Fab")
		)
		(fp_line
			(start -0.67945 0.3048)
			(end -0.120396 0.3048)
			(stroke
				(width 0.1)
				(type default)
			)
			(layer "B.Fab")
		)
		(pad "1" smd circle
			(at 0.40005 0 270)
			(size 0 0)
			(layers "B.Cu" "B.Mask" "B.Paste")
			(net "P12V_HSC_ADC_P")
		)
		(pad "2" smd circle
			(at -0.40005 0 270)
			(size 0 0)
			(layers "B.Cu" "B.Mask" "B.Paste")
			(net "P12V_HSC_SENSE2_R1_P")
		)
	)
	(footprint ""
		(layer "B.Cu")
		(at 355.397308 -237.967266 -90)
		(property "Reference" "C395"
			(at 0 0 90)
			(layer "B.SilkS")
			(hide yes)
			(effects
				(font
					(size 1.27 1.27)
				)
				(justify mirror)
			)
		)
		(property "Value" ""
			(at 0 0 90)
			(layer "B.Fab")
			(effects
				(font
					(size 1.27 1.27)
				)
				(justify mirror)
			)
		)
		(duplicate_pad_numbers_are_jumpers no)
		(fp_line
			(start -1.524 0.762)
			(end 1.524 0.762)
			(stroke
				(width 0.1524)
				(type default)
			)
			(layer "B.SilkS")
		)
		(fp_line
			(start 1.524 0.762)
			(end 1.524 -0.762)
			(stroke
				(width 0.1524)
				(type default)
			)
			(layer "B.SilkS")
		)
		(fp_line
			(start -1.524 -0.762)
			(end -1.524 0.762)
			(stroke
				(width 0.1524)
				(type default)
			)
			(layer "B.SilkS")
		)
		(fp_line
			(start 1.524 -0.762)
			(end -1.524 -0.762)
			(stroke
				(width 0.1524)
				(type default)
			)
			(layer "B.SilkS")
		)
		(fp_line
			(start -1.1049 0.724916)
			(end -1.1049 -0.724916)
			(stroke
				(width 0.1)
				(type default)
			)
			(layer "B.Fab")
		)
		(fp_line
			(start 1.1049 0.724916)
			(end -1.1049 0.724916)
			(stroke
				(width 0.1)
				(type default)
			)
			(layer "B.Fab")
		)
		(fp_line
			(start -1.1049 -0.724916)
			(end 1.1049 -0.724916)
			(stroke
				(width 0.1)
				(type default)
			)
			(layer "B.Fab")
		)
		(fp_line
			(start 1.1049 -0.724916)
			(end 1.1049 0.724916)
			(stroke
				(width 0.1)
				(type default)
			)
			(layer "B.Fab")
		)
		(pad "1" smd rect
			(at 0.889 0 270)
			(size 1.016 1.27)
			(layers "B.Cu" "B.Mask" "B.Paste")
			(net "PVNN_MAIN_CPU0")
		)
		(pad "2" smd rect
			(at -0.889 0 270)
			(size 1.016 1.27)
			(layers "B.Cu" "B.Mask" "B.Paste")
			(net "GND")
		)
	)
	(footprint ""
		(layer "B.Cu")
		(at 320.886582 -66.955924 -90)
		(property "Reference" "C1243"
			(at 0 0 90)
			(layer "B.SilkS")
			(hide yes)
			(effects
				(font
					(size 1.27 1.27)
				)
				(justify mirror)
			)
		)
		(property "Value" ""
			(at 0 0 90)
			(layer "B.Fab")
			(effects
				(font
					(size 1.27 1.27)
				)
				(justify mirror)
			)
		)
		(duplicate_pad_numbers_are_jumpers no)
		(fp_line
			(start -1.524 0.762)
			(end 1.524 0.762)
			(stroke
				(width 0.1524)
				(type default)
			)
			(layer "B.SilkS")
		)
		(fp_line
			(start 1.524 0.762)
			(end 1.524 -0.762)
			(stroke
				(width 0.1524)
				(type default)
			)
			(layer "B.SilkS")
		)
		(fp_line
			(start -1.524 -0.762)
			(end -1.524 0.762)
			(stroke
				(width 0.1524)
				(type default)
			)
			(layer "B.SilkS")
		)
		(fp_line
			(start 1.524 -0.762)
			(end -1.524 -0.762)
			(stroke
				(width 0.1524)
				(type default)
			)
			(layer "B.SilkS")
		)
		(fp_line
			(start -1.1049 0.724916)
			(end -1.1049 -0.724916)
			(stroke
				(width 0.1)
				(type default)
			)
			(layer "B.Fab")
		)
		(fp_line
			(start 1.1049 0.724916)
			(end -1.1049 0.724916)
			(stroke
				(width 0.1)
				(type default)
			)
			(layer "B.Fab")
		)
		(fp_line
			(start -1.1049 -0.724916)
			(end 1.1049 -0.724916)
			(stroke
				(width 0.1)
				(type default)
			)
			(layer "B.Fab")
		)
		(fp_line
			(start 1.1049 -0.724916)
			(end 1.1049 0.724916)
			(stroke
				(width 0.1)
				(type default)
			)
			(layer "B.Fab")
		)
		(pad "1" smd rect
			(at 0.889 0 270)
			(size 1.016 1.27)
			(layers "B.Cu" "B.Mask" "B.Paste")
			(net "P3V3_AUX")
		)
		(pad "2" smd rect
			(at -0.889 0 270)
			(size 1.016 1.27)
			(layers "B.Cu" "B.Mask" "B.Paste")
			(net "GND")
		)
	)
	(footprint ""
		(layer "B.Cu")
		(at 339.244686 -45.481748 180)
		(property "Reference" "C1256"
			(at 0 0 0)
			(layer "B.SilkS")
			(hide yes)
			(effects
				(font
					(size 1.27 1.27)
				)
				(justify mirror)
			)
		)
		(property "Value" ""
			(at 0 0 0)
			(layer "B.Fab")
			(effects
				(font
					(size 1.27 1.27)
				)
				(justify mirror)
			)
		)
		(duplicate_pad_numbers_are_jumpers no)
		(fp_line
			(start 0.7874 0.4064)
			(end 0.7874 -0.4064)
			(stroke
				(width 0.1524)
				(type default)
			)
			(layer "B.SilkS")
		)
		(fp_line
			(start 0.7874 -0.4064)
			(end -0.7874 -0.4064)
			(stroke
				(width 0.1524)
				(type default)
			)
			(layer "B.SilkS")
		)
		(fp_line
			(start -0.7874 0.4064)
			(end 0.7874 0.4064)
			(stroke
				(width 0.1524)
				(type default)
			)
			(layer "B.SilkS")
		)
		(fp_line
			(start -0.7874 -0.4064)
			(end -0.7874 0.4064)
			(stroke
				(width 0.1524)
				(type default)
			)
			(layer "B.SilkS")
		)
		(fp_line
			(start 0.67945 0.3048)
			(end 0.67945 -0.305054)
			(stroke
				(width 0.1)
				(type default)
			)
			(layer "B.Fab")
		)
		(fp_line
			(start 0.67945 -0.305054)
			(end 0.12065 -0.305054)
			(stroke
				(width 0.1)
				(type default)
			)
			(layer "B.Fab")
		)
		(fp_line
			(start 0.12065 0.3048)
			(end 0.67945 0.3048)
			(stroke
				(width 0.1)
				(type default)
			)
			(layer "B.Fab")
		)
		(fp_line
			(start 0.12065 0.2794)
			(end 0.12065 0.3048)
			(stroke
				(width 0.1)
				(type default)
			)
			(layer "B.Fab")
		)
		(fp_line
			(start 0.12065 -0.2794)
			(end -0.12065 -0.2794)
			(stroke
				(width 0.1)
				(type default)
			)
			(layer "B.Fab")
		)
		(fp_line
			(start 0.12065 -0.305054)
			(end 0.12065 -0.2794)
			(stroke
				(width 0.1)
				(type default)
			)
			(layer "B.Fab")
		)
		(fp_line
			(start -0.120396 0.3048)
			(end -0.120396 0.2794)
			(stroke
				(width 0.1)
				(type default)
			)
			(layer "B.Fab")
		)
		(fp_line
			(start -0.120396 0.2794)
			(end 0.12065 0.2794)
			(stroke
				(width 0.1)
				(type default)
			)
			(layer "B.Fab")
		)
		(fp_line
			(start -0.12065 -0.2794)
			(end -0.12065 -0.3048)
			(stroke
				(width 0.1)
				(type default)
			)
			(layer "B.Fab")
		)
		(fp_line
			(start -0.12065 -0.3048)
			(end -0.67945 -0.3048)
			(stroke
				(width 0.1)
				(type default)
			)
			(layer "B.Fab")
		)
		(fp_line
			(start -0.67945 0.3048)
			(end -0.120396 0.3048)
			(stroke
				(width 0.1)
				(type default)
			)
			(layer "B.Fab")
		)
		(fp_line
			(start -0.67945 -0.3048)
			(end -0.67945 0.3048)
			(stroke
				(width 0.1)
				(type default)
			)
			(layer "B.Fab")
		)
		(pad "1" smd circle
			(at 0.40005 0)
			(size 0 0)
			(layers "B.Cu" "B.Mask" "B.Paste")
			(net "P1V05_PCH_PLL_AUX")
		)
		(pad "2" smd circle
			(at -0.40005 0)
			(size 0 0)
			(layers "B.Cu" "B.Mask" "B.Paste")
			(net "GND")
		)
	)
	(footprint ""
		(layer "B.Cu")
		(at 429.40224 -108.867448 90)
		(property "Reference" "R3785"
			(at 0 0 90)
			(layer "B.SilkS")
			(hide yes)
			(effects
				(font
					(size 1.27 1.27)
				)
				(justify mirror)
			)
		)
		(property "Value" ""
			(at 0 0 90)
			(layer "B.Fab")
			(effects
				(font
					(size 1.27 1.27)
				)
				(justify mirror)
			)
		)
		(duplicate_pad_numbers_are_jumpers no)
		(fp_line
			(start 0.7874 -0.4064)
			(end -0.7874 -0.4064)
			(stroke
				(width 0.1524)
				(type default)
			)
			(layer "B.SilkS")
		)
		(fp_line
			(start -0.7874 -0.4064)
			(end -0.7874 0.4064)
			(stroke
				(width 0.1524)
				(type default)
			)
			(layer "B.SilkS")
		)
		(fp_line
			(start 0.7874 0.4064)
			(end 0.7874 -0.4064)
			(stroke
				(width 0.1524)
				(type default)
			)
			(layer "B.SilkS")
		)
		(fp_line
			(start -0.7874 0.4064)
			(end 0.7874 0.4064)
			(stroke
				(width 0.1524)
				(type default)
			)
			(layer "B.SilkS")
		)
		(fp_line
			(start 0.67945 -0.305054)
			(end 0.12065 -0.305054)
			(stroke
				(width 0.1)
				(type default)
			)
			(layer "B.Fab")
		)
		(fp_line
			(start 0.12065 -0.305054)
			(end 0.12065 -0.2794)
			(stroke
				(width 0.1)
				(type default)
			)
			(layer "B.Fab")
		)
		(fp_line
			(start -0.12065 -0.3048)
			(end -0.67945 -0.3048)
			(stroke
				(width 0.1)
				(type default)
			)
			(layer "B.Fab")
		)
		(fp_line
			(start -0.67945 -0.3048)
			(end -0.67945 0.3048)
			(stroke
				(width 0.1)
				(type default)
			)
			(layer "B.Fab")
		)
		(fp_line
			(start 0.12065 -0.2794)
			(end -0.12065 -0.2794)
			(stroke
				(width 0.1)
				(type default)
			)
			(layer "B.Fab")
		)
		(fp_line
			(start -0.12065 -0.2794)
			(end -0.12065 -0.3048)
			(stroke
				(width 0.1)
				(type default)
			)
			(layer "B.Fab")
		)
		(fp_line
			(start 0.12065 0.2794)
			(end 0.12065 0.3048)
			(stroke
				(width 0.1)
				(type default)
			)
			(layer "B.Fab")
		)
		(fp_line
			(start -0.120396 0.2794)
			(end 0.12065 0.2794)
			(stroke
				(width 0.1)
				(type default)
			)
			(layer "B.Fab")
		)
		(fp_line
			(start 0.67945 0.3048)
			(end 0.67945 -0.305054)
			(stroke
				(width 0.1)
				(type default)
			)
			(layer "B.Fab")
		)
		(fp_line
			(start 0.12065 0.3048)
			(end 0.67945 0.3048)
			(stroke
				(width 0.1)
				(type default)
			)
			(layer "B.Fab")
		)
		(fp_line
			(start -0.120396 0.3048)
			(end -0.120396 0.2794)
			(stroke
				(width 0.1)
				(type default)
			)
			(layer "B.Fab")
		)
		(fp_line
			(start -0.67945 0.3048)
			(end -0.120396 0.3048)
			(stroke
				(width 0.1)
				(type default)
			)
			(layer "B.Fab")
		)
		(pad "1" smd circle
			(at 0.40005 0 270)
			(size 0 0)
			(layers "B.Cu" "B.Mask" "B.Paste")
			(net "P3V3_OCP_UV_1_R1")
		)
		(pad "2" smd circle
			(at -0.40005 0 270)
			(size 0 0)
			(layers "B.Cu" "B.Mask" "B.Paste")
			(net "P3V3_OCP_UV_1")
		)
	)
	(footprint ""
		(layer "B.Cu")
		(at 236.182154 -134.048754 180)
		(property "Reference" "R1022"
			(at 0 0 0)
			(layer "B.SilkS")
			(hide yes)
			(effects
				(font
					(size 1.27 1.27)
				)
				(justify mirror)
			)
		)
		(property "Value" ""
			(at 0 0 0)
			(layer "B.Fab")
			(effects
				(font
					(size 1.27 1.27)
				)
				(justify mirror)
			)
		)
		(duplicate_pad_numbers_are_jumpers no)
		(fp_line
			(start 0.7874 -0.154686)
			(end 0.7874 -0.4064)
			(stroke
				(width 0.1524)
				(type default)
			)
			(layer "B.SilkS")
		)
		(fp_line
			(start 0.7874 -0.4064)
			(end -0.7874 -0.4064)
			(stroke
				(width 0.1524)
				(type default)
			)
			(layer "B.SilkS")
		)
		(fp_line
			(start -0.241046 0.4064)
			(end 0.632714 0.4064)
			(stroke
				(width 0.1524)
				(type default)
			)
			(layer "B.SilkS")
		)
		(fp_line
			(start -0.7874 0.4064)
			(end -0.576326 0.4064)
			(stroke
				(width 0.1524)
				(type default)
			)
			(layer "B.SilkS")
		)
		(fp_line
			(start -0.7874 -0.4064)
			(end -0.7874 0.4064)
			(stroke
				(width 0.1524)
				(type default)
			)
			(layer "B.SilkS")
		)
		(fp_line
			(start 0.67945 0.3048)
			(end 0.67945 -0.305054)
			(stroke
				(width 0.1)
				(type default)
			)
			(layer "B.Fab")
		)
		(fp_line
			(start 0.67945 -0.305054)
			(end 0.12065 -0.305054)
			(stroke
				(width 0.1)
				(type default)
			)
			(layer "B.Fab")
		)
		(fp_line
			(start 0.12065 0.3048)
			(end 0.67945 0.3048)
			(stroke
				(width 0.1)
				(type default)
			)
			(layer "B.Fab")
		)
		(fp_line
			(start 0.12065 0.2794)
			(end 0.12065 0.3048)
			(stroke
				(width 0.1)
				(type default)
			)
			(layer "B.Fab")
		)
		(fp_line
			(start 0.12065 -0.2794)
			(end -0.12065 -0.2794)
			(stroke
				(width 0.1)
				(type default)
			)
			(layer "B.Fab")
		)
		(fp_line
			(start 0.12065 -0.305054)
			(end 0.12065 -0.2794)
			(stroke
				(width 0.1)
				(type default)
			)
			(layer "B.Fab")
		)
		(fp_line
			(start -0.120396 0.3048)
			(end -0.120396 0.2794)
			(stroke
				(width 0.1)
				(type default)
			)
			(layer "B.Fab")
		)
		(fp_line
			(start -0.120396 0.2794)
			(end 0.12065 0.2794)
			(stroke
				(width 0.1)
				(type default)
			)
			(layer "B.Fab")
		)
		(fp_line
			(start -0.12065 -0.2794)
			(end -0.12065 -0.3048)
			(stroke
				(width 0.1)
				(type default)
			)
			(layer "B.Fab")
		)
		(fp_line
			(start -0.12065 -0.3048)
			(end -0.67945 -0.3048)
			(stroke
				(width 0.1)
				(type default)
			)
			(layer "B.Fab")
		)
		(fp_line
			(start -0.67945 0.3048)
			(end -0.120396 0.3048)
			(stroke
				(width 0.1)
				(type default)
			)
			(layer "B.Fab")
		)
		(fp_line
			(start -0.67945 -0.3048)
			(end -0.67945 0.3048)
			(stroke
				(width 0.1)
				(type default)
			)
			(layer "B.Fab")
		)
		(pad "1" smd rect
			(at 0.40005 0 180)
			(size 0.4572 0.508)
			(layers "B.Cu" "B.Mask" "B.Paste")
			(net "CLK_25M_CK440_CPU1_R_DP")
		)
		(pad "2" smd rect
			(at -0.40005 0 180)
			(size 0.4572 0.508)
			(layers "B.Cu" "B.Mask" "B.Paste")
			(net "CLK_25M_NSSC_CPU1_DP")
		)
	)
	(footprint ""
		(layer "B.Cu")
		(at 258.953 -96.738948)
		(property "Reference" "C110"
			(at 0 0 0)
			(layer "B.SilkS")
			(hide yes)
			(effects
				(font
					(size 1.27 1.27)
				)
				(justify mirror)
			)
		)
		(property "Value" ""
			(at 0 0 0)
			(layer "B.Fab")
			(effects
				(font
					(size 1.27 1.27)
				)
				(justify mirror)
			)
		)
		(duplicate_pad_numbers_are_jumpers no)
		(fp_line
			(start -0.7874 -0.4064)
			(end -0.7874 0.4064)
			(stroke
				(width 0.1524)
				(type default)
			)
			(layer "B.SilkS")
		)
		(fp_line
			(start -0.7874 0.4064)
			(end 0.7874 0.4064)
			(stroke
				(width 0.1524)
				(type default)
			)
			(layer "B.SilkS")
		)
		(fp_line
			(start 0.7874 -0.4064)
			(end -0.7874 -0.4064)
			(stroke
				(width 0.1524)
				(type default)
			)
			(layer "B.SilkS")
		)
		(fp_line
			(start 0.7874 0.4064)
			(end 0.7874 -0.4064)
			(stroke
				(width 0.1524)
				(type default)
			)
			(layer "B.SilkS")
		)
		(fp_line
			(start -0.67945 -0.3048)
			(end -0.67945 0.3048)
			(stroke
				(width 0.1)
				(type default)
			)
			(layer "B.Fab")
		)
		(fp_line
			(start -0.67945 0.3048)
			(end -0.120396 0.3048)
			(stroke
				(width 0.1)
				(type default)
			)
			(layer "B.Fab")
		)
		(fp_line
			(start -0.12065 -0.3048)
			(end -0.67945 -0.3048)
			(stroke
				(width 0.1)
				(type default)
			)
			(layer "B.Fab")
		)
		(fp_line
			(start -0.12065 -0.2794)
			(end -0.12065 -0.3048)
			(stroke
				(width 0.1)
				(type default)
			)
			(layer "B.Fab")
		)
		(fp_line
			(start -0.120396 0.2794)
			(end 0.12065 0.2794)
			(stroke
				(width 0.1)
				(type default)
			)
			(layer "B.Fab")
		)
		(fp_line
			(start -0.120396 0.3048)
			(end -0.120396 0.2794)
			(stroke
				(width 0.1)
				(type default)
			)
			(layer "B.Fab")
		)
		(fp_line
			(start 0.12065 -0.305054)
			(end 0.12065 -0.2794)
			(stroke
				(width 0.1)
				(type default)
			)
			(layer "B.Fab")
		)
		(fp_line
			(start 0.12065 -0.2794)
			(end -0.12065 -0.2794)
			(stroke
				(width 0.1)
				(type default)
			)
			(layer "B.Fab")
		)
		(fp_line
			(start 0.12065 0.2794)
			(end 0.12065 0.3048)
			(stroke
				(width 0.1)
				(type default)
			)
			(layer "B.Fab")
		)
		(fp_line
			(start 0.12065 0.3048)
			(end 0.67945 0.3048)
			(stroke
				(width 0.1)
				(type default)
			)
			(layer "B.Fab")
		)
		(fp_line
			(start 0.67945 -0.305054)
			(end 0.12065 -0.305054)
			(stroke
				(width 0.1)
				(type default)
			)
			(layer "B.Fab")
		)
		(fp_line
			(start 0.67945 0.3048)
			(end 0.67945 -0.305054)
			(stroke
				(width 0.1)
				(type default)
			)
			(layer "B.Fab")
		)
		(pad "1" smd circle
			(at 0.40005 0 180)
			(size 0 0)
			(layers "B.Cu" "B.Mask" "B.Paste")
			(net "P3V3_AUX_CLK_GEN_VDD_CK440")
		)
		(pad "2" smd circle
			(at -0.40005 0 180)
			(size 0 0)
			(layers "B.Cu" "B.Mask" "B.Paste")
			(net "GND")
		)
	)
	(footprint ""
		(layer "B.Cu")
		(at 355.826822 -210.19389 180)
		(property "Reference" "C508"
			(at 0 0 0)
			(layer "B.SilkS")
			(hide yes)
			(effects
				(font
					(size 1.27 1.27)
				)
				(justify mirror)
			)
		)
		(property "Value" ""
			(at 0 0 0)
			(layer "B.Fab")
			(effects
				(font
					(size 1.27 1.27)
				)
				(justify mirror)
			)
		)
		(duplicate_pad_numbers_are_jumpers no)
		(fp_line
			(start 1.524 0.762)
			(end 1.524 -0.762)
			(stroke
				(width 0.1524)
				(type default)
			)
			(layer "B.SilkS")
		)
		(fp_line
			(start 1.524 -0.762)
			(end -1.524 -0.762)
			(stroke
				(width 0.1524)
				(type default)
			)
			(layer "B.SilkS")
		)
		(fp_line
			(start -1.524 0.762)
			(end 1.524 0.762)
			(stroke
				(width 0.1524)
				(type default)
			)
			(layer "B.SilkS")
		)
		(fp_line
			(start -1.524 -0.762)
			(end -1.524 0.762)
			(stroke
				(width 0.1524)
				(type default)
			)
			(layer "B.SilkS")
		)
		(fp_line
			(start 1.1049 0.724916)
			(end -1.1049 0.724916)
			(stroke
				(width 0.1)
				(type default)
			)
			(layer "B.Fab")
		)
		(fp_line
			(start 1.1049 -0.724916)
			(end 1.1049 0.724916)
			(stroke
				(width 0.1)
				(type default)
			)
			(layer "B.Fab")
		)
		(fp_line
			(start -1.1049 0.724916)
			(end -1.1049 -0.724916)
			(stroke
				(width 0.1)
				(type default)
			)
			(layer "B.Fab")
		)
		(fp_line
			(start -1.1049 -0.724916)
			(end 1.1049 -0.724916)
			(stroke
				(width 0.1)
				(type default)
			)
			(layer "B.Fab")
		)
		(pad "1" smd rect
			(at 0.889 0 180)
			(size 1.016 1.27)
			(layers "B.Cu" "B.Mask" "B.Paste")
			(net "PVCCFA_EHV_CPU0")
		)
		(pad "2" smd rect
			(at -0.889 0 180)
			(size 1.016 1.27)
			(layers "B.Cu" "B.Mask" "B.Paste")
			(net "GND")
		)
	)
	(footprint ""
		(layer "B.Cu")
		(at 237.844076 -126.513082 180)
		(property "Reference" "R574"
			(at 0 0 0)
			(layer "B.SilkS")
			(hide yes)
			(effects
				(font
					(size 1.27 1.27)
				)
				(justify mirror)
			)
		)
		(property "Value" ""
			(at 0 0 0)
			(layer "B.Fab")
			(effects
				(font
					(size 1.27 1.27)
				)
				(justify mirror)
			)
		)
		(duplicate_pad_numbers_are_jumpers no)
		(fp_line
			(start 0.7874 0.4064)
			(end 0.7874 -0.4064)
			(stroke
				(width 0.1524)
				(type default)
			)
			(layer "B.SilkS")
		)
		(fp_line
			(start 0.7874 -0.4064)
			(end -0.7874 -0.4064)
			(stroke
				(width 0.1524)
				(type default)
			)
			(layer "B.SilkS")
		)
		(fp_line
			(start -0.7874 0.4064)
			(end 0.7874 0.4064)
			(stroke
				(width 0.1524)
				(type default)
			)
			(layer "B.SilkS")
		)
		(fp_line
			(start -0.7874 -0.4064)
			(end -0.7874 0.4064)
			(stroke
				(width 0.1524)
				(type default)
			)
			(layer "B.SilkS")
		)
		(fp_line
			(start 0.67945 0.3048)
			(end 0.67945 -0.305054)
			(stroke
				(width 0.1)
				(type default)
			)
			(layer "B.Fab")
		)
		(fp_line
			(start 0.67945 -0.305054)
			(end 0.12065 -0.305054)
			(stroke
				(width 0.1)
				(type default)
			)
			(layer "B.Fab")
		)
		(fp_line
			(start 0.12065 0.3048)
			(end 0.67945 0.3048)
			(stroke
				(width 0.1)
				(type default)
			)
			(layer "B.Fab")
		)
		(fp_line
			(start 0.12065 0.2794)
			(end 0.12065 0.3048)
			(stroke
				(width 0.1)
				(type default)
			)
			(layer "B.Fab")
		)
		(fp_line
			(start 0.12065 -0.2794)
			(end -0.12065 -0.2794)
			(stroke
				(width 0.1)
				(type default)
			)
			(layer "B.Fab")
		)
		(fp_line
			(start 0.12065 -0.305054)
			(end 0.12065 -0.2794)
			(stroke
				(width 0.1)
				(type default)
			)
			(layer "B.Fab")
		)
		(fp_line
			(start -0.120396 0.3048)
			(end -0.120396 0.2794)
			(stroke
				(width 0.1)
				(type default)
			)
			(layer "B.Fab")
		)
		(fp_line
			(start -0.120396 0.2794)
			(end 0.12065 0.2794)
			(stroke
				(width 0.1)
				(type default)
			)
			(layer "B.Fab")
		)
		(fp_line
			(start -0.12065 -0.2794)
			(end -0.12065 -0.3048)
			(stroke
				(width 0.1)
				(type default)
			)
			(layer "B.Fab")
		)
		(fp_line
			(start -0.12065 -0.3048)
			(end -0.67945 -0.3048)
			(stroke
				(width 0.1)
				(type default)
			)
			(layer "B.Fab")
		)
		(fp_line
			(start -0.67945 0.3048)
			(end -0.120396 0.3048)
			(stroke
				(width 0.1)
				(type default)
			)
			(layer "B.Fab")
		)
		(fp_line
			(start -0.67945 -0.3048)
			(end -0.67945 0.3048)
			(stroke
				(width 0.1)
				(type default)
			)
			(layer "B.Fab")
		)
		(pad "1" smd circle
			(at 0.40005 0)
			(size 0 0)
			(layers "B.Cu" "B.Mask" "B.Paste")
			(net "FM_DB2000_VSBEN")
		)
		(pad "2" smd circle
			(at -0.40005 0)
			(size 0 0)
			(layers "B.Cu" "B.Mask" "B.Paste")
			(net "GND")
		)
	)
	(footprint ""
		(layer "B.Cu")
		(at 340.877398 -50.681636 180)
		(property "Reference" "C1266"
			(at 0 0 0)
			(layer "B.SilkS")
			(hide yes)
			(effects
				(font
					(size 1.27 1.27)
				)
				(justify mirror)
			)
		)
		(property "Value" ""
			(at 0 0 0)
			(layer "B.Fab")
			(effects
				(font
					(size 1.27 1.27)
				)
				(justify mirror)
			)
		)
		(duplicate_pad_numbers_are_jumpers no)
		(fp_line
			(start 0.7874 0.4064)
			(end 0.7874 -0.4064)
			(stroke
				(width 0.1524)
				(type default)
			)
			(layer "B.SilkS")
		)
		(fp_line
			(start 0.7874 -0.4064)
			(end -0.7874 -0.4064)
			(stroke
				(width 0.1524)
				(type default)
			)
			(layer "B.SilkS")
		)
		(fp_line
			(start -0.7874 0.4064)
			(end 0.7874 0.4064)
			(stroke
				(width 0.1524)
				(type default)
			)
			(layer "B.SilkS")
		)
		(fp_line
			(start -0.7874 -0.4064)
			(end -0.7874 0.4064)
			(stroke
				(width 0.1524)
				(type default)
			)
			(layer "B.SilkS")
		)
		(fp_line
			(start 0.67945 0.3048)
			(end 0.67945 -0.305054)
			(stroke
				(width 0.1)
				(type default)
			)
			(layer "B.Fab")
		)
		(fp_line
			(start 0.67945 -0.305054)
			(end 0.12065 -0.305054)
			(stroke
				(width 0.1)
				(type default)
			)
			(layer "B.Fab")
		)
		(fp_line
			(start 0.12065 0.3048)
			(end 0.67945 0.3048)
			(stroke
				(width 0.1)
				(type default)
			)
			(layer "B.Fab")
		)
		(fp_line
			(start 0.12065 0.2794)
			(end 0.12065 0.3048)
			(stroke
				(width 0.1)
				(type default)
			)
			(layer "B.Fab")
		)
		(fp_line
			(start 0.12065 -0.2794)
			(end -0.12065 -0.2794)
			(stroke
				(width 0.1)
				(type default)
			)
			(layer "B.Fab")
		)
		(fp_line
			(start 0.12065 -0.305054)
			(end 0.12065 -0.2794)
			(stroke
				(width 0.1)
				(type default)
			)
			(layer "B.Fab")
		)
		(fp_line
			(start -0.120396 0.3048)
			(end -0.120396 0.2794)
			(stroke
				(width 0.1)
				(type default)
			)
			(layer "B.Fab")
		)
		(fp_line
			(start -0.120396 0.2794)
			(end 0.12065 0.2794)
			(stroke
				(width 0.1)
				(type default)
			)
			(layer "B.Fab")
		)
		(fp_line
			(start -0.12065 -0.2794)
			(end -0.12065 -0.3048)
			(stroke
				(width 0.1)
				(type default)
			)
			(layer "B.Fab")
		)
		(fp_line
			(start -0.12065 -0.3048)
			(end -0.67945 -0.3048)
			(stroke
				(width 0.1)
				(type default)
			)
			(layer "B.Fab")
		)
		(fp_line
			(start -0.67945 0.3048)
			(end -0.120396 0.3048)
			(stroke
				(width 0.1)
				(type default)
			)
			(layer "B.Fab")
		)
		(fp_line
			(start -0.67945 -0.3048)
			(end -0.67945 0.3048)
			(stroke
				(width 0.1)
				(type default)
			)
			(layer "B.Fab")
		)
		(pad "1" smd circle
			(at 0.40005 0)
			(size 0 0)
			(layers "B.Cu" "B.Mask" "B.Paste")
			(net "P1V8_PCH_PLL_AUX")
		)
		(pad "2" smd circle
			(at -0.40005 0)
			(size 0 0)
			(layers "B.Cu" "B.Mask" "B.Paste")
			(net "GND")
		)
	)
	(footprint ""
		(layer "B.Cu")
		(at 22.960584 -176.253902 -90)
		(property "Reference" "C1297"
			(at 0 0 90)
			(layer "B.SilkS")
			(hide yes)
			(effects
				(font
					(size 1.27 1.27)
				)
				(justify mirror)
			)
		)
		(property "Value" ""
			(at 0 0 90)
			(layer "B.Fab")
			(effects
				(font
					(size 1.27 1.27)
				)
				(justify mirror)
			)
		)
		(duplicate_pad_numbers_are_jumpers no)
		(fp_line
			(start -0.7874 0.4064)
			(end 0.7874 0.4064)
			(stroke
				(width 0.1524)
				(type default)
			)
			(layer "B.SilkS")
		)
		(fp_line
			(start 0.7874 0.4064)
			(end 0.7874 -0.4064)
			(stroke
				(width 0.1524)
				(type default)
			)
			(layer "B.SilkS")
		)
		(fp_line
			(start -0.7874 -0.4064)
			(end -0.7874 0.4064)
			(stroke
				(width 0.1524)
				(type default)
			)
			(layer "B.SilkS")
		)
		(fp_line
			(start 0.7874 -0.4064)
			(end -0.7874 -0.4064)
			(stroke
				(width 0.1524)
				(type default)
			)
			(layer "B.SilkS")
		)
		(fp_line
			(start -0.67945 0.3048)
			(end -0.120396 0.3048)
			(stroke
				(width 0.1)
				(type default)
			)
			(layer "B.Fab")
		)
		(fp_line
			(start -0.120396 0.3048)
			(end -0.120396 0.2794)
			(stroke
				(width 0.1)
				(type default)
			)
			(layer "B.Fab")
		)
		(fp_line
			(start 0.12065 0.3048)
			(end 0.67945 0.3048)
			(stroke
				(width 0.1)
				(type default)
			)
			(layer "B.Fab")
		)
		(fp_line
			(start 0.67945 0.3048)
			(end 0.67945 -0.305054)
			(stroke
				(width 0.1)
				(type default)
			)
			(layer "B.Fab")
		)
		(fp_line
			(start -0.120396 0.2794)
			(end 0.12065 0.2794)
			(stroke
				(width 0.1)
				(type default)
			)
			(layer "B.Fab")
		)
		(fp_line
			(start 0.12065 0.2794)
			(end 0.12065 0.3048)
			(stroke
				(width 0.1)
				(type default)
			)
			(layer "B.Fab")
		)
		(fp_line
			(start -0.12065 -0.2794)
			(end -0.12065 -0.3048)
			(stroke
				(width 0.1)
				(type default)
			)
			(layer "B.Fab")
		)
		(fp_line
			(start 0.12065 -0.2794)
			(end -0.12065 -0.2794)
			(stroke
				(width 0.1)
				(type default)
			)
			(layer "B.Fab")
		)
		(fp_line
			(start -0.67945 -0.3048)
			(end -0.67945 0.3048)
			(stroke
				(width 0.1)
				(type default)
			)
			(layer "B.Fab")
		)
		(fp_line
			(start -0.12065 -0.3048)
			(end -0.67945 -0.3048)
			(stroke
				(width 0.1)
				(type default)
			)
			(layer "B.Fab")
		)
		(fp_line
			(start 0.12065 -0.305054)
			(end 0.12065 -0.2794)
			(stroke
				(width 0.1)
				(type default)
			)
			(layer "B.Fab")
		)
		(fp_line
			(start 0.67945 -0.305054)
			(end 0.12065 -0.305054)
			(stroke
				(width 0.1)
				(type default)
			)
			(layer "B.Fab")
		)
		(pad "1" smd circle
			(at 0.40005 0 90)
			(size 0 0)
			(layers "B.Cu" "B.Mask" "B.Paste")
			(net "PWRGD_PVNN_MAIN_CPU1")
		)
		(pad "2" smd circle
			(at -0.40005 0 90)
			(size 0 0)
			(layers "B.Cu" "B.Mask" "B.Paste")
			(net "GND")
		)
	)
	(footprint ""
		(layer "B.Cu")
		(at 307.148738 -194.71767 90)
		(property "Reference" "R16"
			(at 0 0 90)
			(layer "B.SilkS")
			(hide yes)
			(effects
				(font
					(size 1.27 1.27)
				)
				(justify mirror)
			)
		)
		(property "Value" ""
			(at 0 0 90)
			(layer "B.Fab")
			(effects
				(font
					(size 1.27 1.27)
				)
				(justify mirror)
			)
		)
		(duplicate_pad_numbers_are_jumpers no)
		(fp_line
			(start 0.7874 -0.4064)
			(end -0.7874 -0.4064)
			(stroke
				(width 0.1524)
				(type default)
			)
			(layer "B.SilkS")
		)
		(fp_line
			(start -0.7874 -0.4064)
			(end -0.7874 0.4064)
			(stroke
				(width 0.1524)
				(type default)
			)
			(layer "B.SilkS")
		)
		(fp_line
			(start 0.7874 0.4064)
			(end 0.7874 -0.4064)
			(stroke
				(width 0.1524)
				(type default)
			)
			(layer "B.SilkS")
		)
		(fp_line
			(start -0.7874 0.4064)
			(end 0.7874 0.4064)
			(stroke
				(width 0.1524)
				(type default)
			)
			(layer "B.SilkS")
		)
		(fp_line
			(start 0.67945 -0.305054)
			(end 0.12065 -0.305054)
			(stroke
				(width 0.1)
				(type default)
			)
			(layer "B.Fab")
		)
		(fp_line
			(start 0.12065 -0.305054)
			(end 0.12065 -0.2794)
			(stroke
				(width 0.1)
				(type default)
			)
			(layer "B.Fab")
		)
		(fp_line
			(start -0.12065 -0.3048)
			(end -0.67945 -0.3048)
			(stroke
				(width 0.1)
				(type default)
			)
			(layer "B.Fab")
		)
		(fp_line
			(start -0.67945 -0.3048)
			(end -0.67945 0.3048)
			(stroke
				(width 0.1)
				(type default)
			)
			(layer "B.Fab")
		)
		(fp_line
			(start 0.12065 -0.2794)
			(end -0.12065 -0.2794)
			(stroke
				(width 0.1)
				(type default)
			)
			(layer "B.Fab")
		)
		(fp_line
			(start -0.12065 -0.2794)
			(end -0.12065 -0.3048)
			(stroke
				(width 0.1)
				(type default)
			)
			(layer "B.Fab")
		)
		(fp_line
			(start 0.12065 0.2794)
			(end 0.12065 0.3048)
			(stroke
				(width 0.1)
				(type default)
			)
			(layer "B.Fab")
		)
		(fp_line
			(start -0.120396 0.2794)
			(end 0.12065 0.2794)
			(stroke
				(width 0.1)
				(type default)
			)
			(layer "B.Fab")
		)
		(fp_line
			(start 0.67945 0.3048)
			(end 0.67945 -0.305054)
			(stroke
				(width 0.1)
				(type default)
			)
			(layer "B.Fab")
		)
		(fp_line
			(start 0.12065 0.3048)
			(end 0.67945 0.3048)
			(stroke
				(width 0.1)
				(type default)
			)
			(layer "B.Fab")
		)
		(fp_line
			(start -0.120396 0.3048)
			(end -0.120396 0.2794)
			(stroke
				(width 0.1)
				(type default)
			)
			(layer "B.Fab")
		)
		(fp_line
			(start -0.67945 0.3048)
			(end -0.120396 0.3048)
			(stroke
				(width 0.1)
				(type default)
			)
			(layer "B.Fab")
		)
		(pad "1" smd circle
			(at 0.40005 0 270)
			(size 0 0)
			(layers "B.Cu" "B.Mask" "B.Paste")
			(net "SVID_CLK1_CPU0")
		)
		(pad "2" smd circle
			(at -0.40005 0 270)
			(size 0 0)
			(layers "B.Cu" "B.Mask" "B.Paste")
			(net "SVID_CLK1_CPU0_R")
		)
	)
	(footprint ""
		(layer "B.Cu")
		(at 412.548324 -256.636266 -90)
		(property "Reference" "C510"
			(at 0 0 90)
			(layer "B.SilkS")
			(hide yes)
			(effects
				(font
					(size 1.27 1.27)
				)
				(justify mirror)
			)
		)
		(property "Value" ""
			(at 0 0 90)
			(layer "B.Fab")
			(effects
				(font
					(size 1.27 1.27)
				)
				(justify mirror)
			)
		)
		(duplicate_pad_numbers_are_jumpers no)
		(fp_line
			(start -1.524 0.762)
			(end 1.524 0.762)
			(stroke
				(width 0.1524)
				(type default)
			)
			(layer "B.SilkS")
		)
		(fp_line
			(start 1.524 0.762)
			(end 1.524 -0.762)
			(stroke
				(width 0.1524)
				(type default)
			)
			(layer "B.SilkS")
		)
		(fp_line
			(start -1.524 -0.762)
			(end -1.524 0.762)
			(stroke
				(width 0.1524)
				(type default)
			)
			(layer "B.SilkS")
		)
		(fp_line
			(start 1.524 -0.762)
			(end -1.524 -0.762)
			(stroke
				(width 0.1524)
				(type default)
			)
			(layer "B.SilkS")
		)
		(fp_line
			(start -1.1049 0.724916)
			(end -1.1049 -0.724916)
			(stroke
				(width 0.1)
				(type default)
			)
			(layer "B.Fab")
		)
		(fp_line
			(start 1.1049 0.724916)
			(end -1.1049 0.724916)
			(stroke
				(width 0.1)
				(type default)
			)
			(layer "B.Fab")
		)
		(fp_line
			(start -1.1049 -0.724916)
			(end 1.1049 -0.724916)
			(stroke
				(width 0.1)
				(type default)
			)
			(layer "B.Fab")
		)
		(fp_line
			(start 1.1049 -0.724916)
			(end 1.1049 0.724916)
			(stroke
				(width 0.1)
				(type default)
			)
			(layer "B.Fab")
		)
		(pad "1" smd rect
			(at 0.889 0 270)
			(size 1.016 1.27)
			(layers "B.Cu" "B.Mask" "B.Paste")
			(net "PVCCFA_EHV_FIVRA_CPU0")
		)
		(pad "2" smd rect
			(at -0.889 0 270)
			(size 1.016 1.27)
			(layers "B.Cu" "B.Mask" "B.Paste")
			(net "GND")
		)
	)
	(footprint ""
		(layer "B.Cu")
		(at 297.44416 -50.226468)
		(property "Reference" "C1187"
			(at 0 0 0)
			(layer "B.SilkS")
			(hide yes)
			(effects
				(font
					(size 1.27 1.27)
				)
				(justify mirror)
			)
		)
		(property "Value" ""
			(at 0 0 0)
			(layer "B.Fab")
			(effects
				(font
					(size 1.27 1.27)
				)
				(justify mirror)
			)
		)
		(duplicate_pad_numbers_are_jumpers no)
		(fp_line
			(start -1.2954 -0.5842)
			(end -1.2954 0.5842)
			(stroke
				(width 0.1524)
				(type default)
			)
			(layer "B.SilkS")
		)
		(fp_line
			(start -1.2954 0.5842)
			(end 1.2954 0.5842)
			(stroke
				(width 0.1524)
				(type default)
			)
			(layer "B.SilkS")
		)
		(fp_line
			(start 0 -0.5842)
			(end 0 0.5842)
			(stroke
				(width 0.1524)
				(type default)
			)
			(layer "B.SilkS")
		)
		(fp_line
			(start 1.2954 -0.5842)
			(end -1.2954 -0.5842)
			(stroke
				(width 0.1524)
				(type default)
			)
			(layer "B.SilkS")
		)
		(fp_line
			(start 1.2954 0.5842)
			(end 1.2954 -0.5842)
			(stroke
				(width 0.1524)
				(type default)
			)
			(layer "B.SilkS")
		)
		(fp_line
			(start -1.1938 -0.4064)
			(end -1.1938 0.4064)
			(stroke
				(width 0.1)
				(type default)
			)
			(layer "B.Fab")
		)
		(fp_line
			(start -1.1938 0.4064)
			(end -0.8636 0.4064)
			(stroke
				(width 0.1)
				(type default)
			)
			(layer "B.Fab")
		)
		(fp_line
			(start -0.8636 -0.4572)
			(end -0.8636 -0.4064)
			(stroke
				(width 0.1)
				(type default)
			)
			(layer "B.Fab")
		)
		(fp_line
			(start -0.8636 -0.4064)
			(end -1.1938 -0.4064)
			(stroke
				(width 0.1)
				(type default)
			)
			(layer "B.Fab")
		)
		(fp_line
			(start -0.8636 0.4064)
			(end -0.8636 0.4572)
			(stroke
				(width 0.1)
				(type default)
			)
			(layer "B.Fab")
		)
		(fp_line
			(start -0.8636 0.4572)
			(end 0.8636 0.4572)
			(stroke
				(width 0.1)
				(type default)
			)
			(layer "B.Fab")
		)
		(fp_line
			(start 0.8636 -0.4572)
			(end -0.8636 -0.4572)
			(stroke
				(width 0.1)
				(type default)
			)
			(layer "B.Fab")
		)
		(fp_line
			(start 0.8636 -0.4064)
			(end 0.8636 -0.4572)
			(stroke
				(width 0.1)
				(type default)
			)
			(layer "B.Fab")
		)
		(fp_line
			(start 0.8636 0.4064)
			(end 1.1938 0.4064)
			(stroke
				(width 0.1)
				(type default)
			)
			(layer "B.Fab")
		)
		(fp_line
			(start 0.8636 0.4572)
			(end 0.8636 0.4064)
			(stroke
				(width 0.1)
				(type default)
			)
			(layer "B.Fab")
		)
		(fp_line
			(start 1.1938 -0.4064)
			(end 0.8636 -0.4064)
			(stroke
				(width 0.1)
				(type default)
			)
			(layer "B.Fab")
		)
		(fp_line
			(start 1.1938 0.4064)
			(end 1.1938 -0.4064)
			(stroke
				(width 0.1)
				(type default)
			)
			(layer "B.Fab")
		)
		(pad "1" smd rect
			(at 0.7366 0 270)
			(size 0.7112 0.8128)
			(layers "B.Cu" "B.Mask" "B.Paste")
			(net "P1V05_PCH_AUX")
		)
		(pad "2" smd rect
			(at -0.7366 0 270)
			(size 0.7112 0.8128)
			(layers "B.Cu" "B.Mask" "B.Paste")
			(net "GND")
		)
	)
	(footprint ""
		(layer "B.Cu")
		(at 319.58153 -32.470598 -90)
		(property "Reference" "R1744"
			(at 0 0 90)
			(layer "B.SilkS")
			(hide yes)
			(effects
				(font
					(size 1.27 1.27)
				)
				(justify mirror)
			)
		)
		(property "Value" ""
			(at 0 0 90)
			(layer "B.Fab")
			(effects
				(font
					(size 1.27 1.27)
				)
				(justify mirror)
			)
		)
		(duplicate_pad_numbers_are_jumpers no)
		(fp_line
			(start -0.7874 0.4064)
			(end 0.7874 0.4064)
			(stroke
				(width 0.1524)
				(type default)
			)
			(layer "B.SilkS")
		)
		(fp_line
			(start 0.7874 0.4064)
			(end 0.7874 -0.4064)
			(stroke
				(width 0.1524)
				(type default)
			)
			(layer "B.SilkS")
		)
		(fp_line
			(start -0.7874 -0.4064)
			(end -0.7874 0.4064)
			(stroke
				(width 0.1524)
				(type default)
			)
			(layer "B.SilkS")
		)
		(fp_line
			(start 0.7874 -0.4064)
			(end -0.7874 -0.4064)
			(stroke
				(width 0.1524)
				(type default)
			)
			(layer "B.SilkS")
		)
		(fp_line
			(start -0.67945 0.3048)
			(end -0.120396 0.3048)
			(stroke
				(width 0.1)
				(type default)
			)
			(layer "B.Fab")
		)
		(fp_line
			(start -0.120396 0.3048)
			(end -0.120396 0.2794)
			(stroke
				(width 0.1)
				(type default)
			)
			(layer "B.Fab")
		)
		(fp_line
			(start 0.12065 0.3048)
			(end 0.67945 0.3048)
			(stroke
				(width 0.1)
				(type default)
			)
			(layer "B.Fab")
		)
		(fp_line
			(start 0.67945 0.3048)
			(end 0.67945 -0.305054)
			(stroke
				(width 0.1)
				(type default)
			)
			(layer "B.Fab")
		)
		(fp_line
			(start -0.120396 0.2794)
			(end 0.12065 0.2794)
			(stroke
				(width 0.1)
				(type default)
			)
			(layer "B.Fab")
		)
		(fp_line
			(start 0.12065 0.2794)
			(end 0.12065 0.3048)
			(stroke
				(width 0.1)
				(type default)
			)
			(layer "B.Fab")
		)
		(fp_line
			(start -0.12065 -0.2794)
			(end -0.12065 -0.3048)
			(stroke
				(width 0.1)
				(type default)
			)
			(layer "B.Fab")
		)
		(fp_line
			(start 0.12065 -0.2794)
			(end -0.12065 -0.2794)
			(stroke
				(width 0.1)
				(type default)
			)
			(layer "B.Fab")
		)
		(fp_line
			(start -0.67945 -0.3048)
			(end -0.67945 0.3048)
			(stroke
				(width 0.1)
				(type default)
			)
			(layer "B.Fab")
		)
		(fp_line
			(start -0.12065 -0.3048)
			(end -0.67945 -0.3048)
			(stroke
				(width 0.1)
				(type default)
			)
			(layer "B.Fab")
		)
		(fp_line
			(start 0.12065 -0.305054)
			(end 0.12065 -0.2794)
			(stroke
				(width 0.1)
				(type default)
			)
			(layer "B.Fab")
		)
		(fp_line
			(start 0.67945 -0.305054)
			(end 0.12065 -0.305054)
			(stroke
				(width 0.1)
				(type default)
			)
			(layer "B.Fab")
		)
		(pad "1" smd circle
			(at 0.40005 0 90)
			(size 0 0)
			(layers "B.Cu" "B.Mask" "B.Paste")
			(net "FM_BMC_PWRBTN_OUT_N")
		)
		(pad "2" smd circle
			(at -0.40005 0 90)
			(size 0 0)
			(layers "B.Cu" "B.Mask" "B.Paste")
			(net "FM_BMC_PWRBTN_N")
		)
	)
	(footprint ""
		(layer "B.Cu")
		(at 381.213868 -189.29096)
		(property "Reference" "R1242"
			(at 0 0 0)
			(layer "B.SilkS")
			(hide yes)
			(effects
				(font
					(size 1.27 1.27)
				)
				(justify mirror)
			)
		)
		(property "Value" ""
			(at 0 0 0)
			(layer "B.Fab")
			(effects
				(font
					(size 1.27 1.27)
				)
				(justify mirror)
			)
		)
		(duplicate_pad_numbers_are_jumpers no)
		(fp_line
			(start -0.7874 -0.4064)
			(end -0.7874 0.4064)
			(stroke
				(width 0.1524)
				(type default)
			)
			(layer "B.SilkS")
		)
		(fp_line
			(start -0.7874 0.4064)
			(end 0.7874 0.4064)
			(stroke
				(width 0.1524)
				(type default)
			)
			(layer "B.SilkS")
		)
		(fp_line
			(start 0.7874 -0.4064)
			(end -0.7874 -0.4064)
			(stroke
				(width 0.1524)
				(type default)
			)
			(layer "B.SilkS")
		)
		(fp_line
			(start 0.7874 0.4064)
			(end 0.7874 -0.4064)
			(stroke
				(width 0.1524)
				(type default)
			)
			(layer "B.SilkS")
		)
		(fp_line
			(start -0.67945 -0.3048)
			(end -0.67945 0.3048)
			(stroke
				(width 0.1)
				(type default)
			)
			(layer "B.Fab")
		)
		(fp_line
			(start -0.67945 0.3048)
			(end -0.120396 0.3048)
			(stroke
				(width 0.1)
				(type default)
			)
			(layer "B.Fab")
		)
		(fp_line
			(start -0.12065 -0.3048)
			(end -0.67945 -0.3048)
			(stroke
				(width 0.1)
				(type default)
			)
			(layer "B.Fab")
		)
		(fp_line
			(start -0.12065 -0.2794)
			(end -0.12065 -0.3048)
			(stroke
				(width 0.1)
				(type default)
			)
			(layer "B.Fab")
		)
		(fp_line
			(start -0.120396 0.2794)
			(end 0.12065 0.2794)
			(stroke
				(width 0.1)
				(type default)
			)
			(layer "B.Fab")
		)
		(fp_line
			(start -0.120396 0.3048)
			(end -0.120396 0.2794)
			(stroke
				(width 0.1)
				(type default)
			)
			(layer "B.Fab")
		)
		(fp_line
			(start 0.12065 -0.305054)
			(end 0.12065 -0.2794)
			(stroke
				(width 0.1)
				(type default)
			)
			(layer "B.Fab")
		)
		(fp_line
			(start 0.12065 -0.2794)
			(end -0.12065 -0.2794)
			(stroke
				(width 0.1)
				(type default)
			)
			(layer "B.Fab")
		)
		(fp_line
			(start 0.12065 0.2794)
			(end 0.12065 0.3048)
			(stroke
				(width 0.1)
				(type default)
			)
			(layer "B.Fab")
		)
		(fp_line
			(start 0.12065 0.3048)
			(end 0.67945 0.3048)
			(stroke
				(width 0.1)
				(type default)
			)
			(layer "B.Fab")
		)
		(fp_line
			(start 0.67945 -0.305054)
			(end 0.12065 -0.305054)
			(stroke
				(width 0.1)
				(type default)
			)
			(layer "B.Fab")
		)
		(fp_line
			(start 0.67945 0.3048)
			(end 0.67945 -0.305054)
			(stroke
				(width 0.1)
				(type default)
			)
			(layer "B.Fab")
		)
		(pad "1" smd circle
			(at 0.40005 0 180)
			(size 0 0)
			(layers "B.Cu" "B.Mask" "B.Paste")
			(net "PVNN_TERM_CPU0")
		)
		(pad "2" smd circle
			(at -0.40005 0 180)
			(size 0 0)
			(layers "B.Cu" "B.Mask" "B.Paste")
			(net "H_CPU_PM_FAST_WAKE_N")
		)
	)
	(footprint ""
		(layer "B.Cu")
		(at 490.57433 -303.547272 -90)
		(property "Reference" "X12"
			(at 3.322828 3.706876 270)
			(unlocked yes)
			(layer "B.SilkS")
			(effects
				(font
					(size 0.7874 0.5842)
					(thickness 0.1524)
				)
				(justify left mirror)
			)
		)
		(property "Value" ""
			(at 0 0 90)
			(layer "B.Fab")
			(effects
				(font
					(size 1.27 1.27)
				)
				(justify mirror)
			)
		)
		(property "Device Type" "TP_TDR_4P_FTS_MPKT4_H025P0200_I"
			(at -1.30175 1.27 180)
			(unlocked yes)
			(layer "B.Fab")
			(hide yes)
			(effects
				(font
					(size 0.635 0.4064)
					(thickness 0.1524)
				)
				(justify mirror)
			)
		)
		(property "User Part Number" "TP15"
			(at -1.30175 1.27 180)
			(unlocked yes)
			(layer "Cmts.User")
			(hide yes)
			(effects
				(font
					(size 0.635 0.4064)
					(thickness 0.1524)
				)
				(justify mirror)
			)
		)
		(duplicate_pad_numbers_are_jumpers no)
		(fp_line
			(start -2.54 3.81)
			(end -2.54 3.6703)
			(stroke
				(width 0.1524)
				(type default)
			)
			(layer "B.SilkS")
		)
		(fp_line
			(start 0 3.81)
			(end -2.54 3.81)
			(stroke
				(width 0.1524)
				(type default)
			)
			(layer "B.SilkS")
		)
		(fp_line
			(start 0 3.175)
			(end 0 3.81)
			(stroke
				(width 0.1524)
				(type default)
			)
			(layer "B.SilkS")
		)
		(fp_line
			(start -2.54 1.4097)
			(end -2.54 1.1303)
			(stroke
				(width 0.1524)
				(type default)
			)
			(layer "B.SilkS")
		)
		(fp_line
			(start 0 0.635)
			(end 0 1.905)
			(stroke
				(width 0.1524)
				(type default)
			)
			(layer "B.SilkS")
		)
		(fp_line
			(start -2.54 -1.1303)
			(end -2.54 -1.27)
			(stroke
				(width 0.1524)
				(type default)
			)
			(layer "B.SilkS")
		)
		(fp_line
			(start -2.54 -1.27)
			(end 0 -1.27)
			(stroke
				(width 0.1524)
				(type default)
			)
			(layer "B.SilkS")
		)
		(fp_line
			(start 0 -1.27)
			(end 0 -0.635)
			(stroke
				(width 0.1524)
				(type default)
			)
			(layer "B.SilkS")
		)
		(fp_poly
			(pts
				(xy 2.853944 -0.825246) (xy 2.853944 0.698754) (xy 1.329944 -0.063246)
			)
			(stroke
				(width 0)
				(type default)
			)
			(fill yes)
			(layer "B.SilkS")
		)
		(fp_line
			(start -2.54 3.81)
			(end -2.54 -1.27)
			(stroke
				(width 0.1)
				(type default)
			)
			(layer "B.Fab")
		)
		(fp_line
			(start 0 3.81)
			(end -2.54 3.81)
			(stroke
				(width 0.1)
				(type default)
			)
			(layer "B.Fab")
		)
		(fp_line
			(start -2.54 -1.27)
			(end 0 -1.27)
			(stroke
				(width 0.1)
				(type default)
			)
			(layer "B.Fab")
		)
		(fp_line
			(start 0 -1.27)
			(end 0 3.81)
			(stroke
				(width 0.1)
				(type default)
			)
			(layer "B.Fab")
		)
		(fp_poly
			(pts
				(xy 0.761746 0) (xy 2.285746 -0.762) (xy 2.285746 0.762)
			)
			(stroke
				(width 0)
				(type default)
			)
			(fill yes)
			(layer "B.Fab")
		)
		(pad "1" thru_hole circle
			(at 0 0 90)
			(size 1.0033 1.0033)
			(drill 0.249936)
			(layers "*.Cu" "*.Mask")
			(remove_unused_layers no)
			(net "TDR_DIFF_85_BOT_DN")
			(clearance 0.10795)
			(padstack
				(mode front_inner_back)
				(layer "Inner"
					(shape circle)
					(size 0.8001 0.8001)
					(clearance 0.1524)
				)
				(layer "B.Cu"
					(shape circle)
					(size 1.0033 1.0033)
					(thermal_gap 0.10795)
					(clearance 0.10795)
				)
			)
		)
		(pad "2" thru_hole circle
			(at -2.54 0 90)
			(size 1.9939 1.9939)
			(drill 0.249936)
			(layers "*.Cu" "*.Mask")
			(remove_unused_layers no)
			(net "T1_GND")
			(clearance 0.10795)
			(padstack
				(mode front_inner_back)
				(layer "Inner"
					(shape circle)
					(size 0.8001 0.8001)
					(clearance 0.1524)
				)
				(layer "B.Cu"
					(shape circle)
					(size 1.9939 1.9939)
					(thermal_gap 0.10795)
					(clearance 0.10795)
				)
			)
		)
		(pad "3" thru_hole circle
			(at -2.54 2.54 90)
			(size 1.9939 1.9939)
			(drill 0.249936)
			(layers "*.Cu" "*.Mask")
			(remove_unused_layers no)
			(net "T1_GND")
			(clearance 0.10795)
			(padstack
				(mode front_inner_back)
				(layer "Inner"
					(shape circle)
					(size 0.8001 0.8001)
					(clearance 0.1524)
				)
				(layer "B.Cu"
					(shape circle)
					(size 1.9939 1.9939)
					(thermal_gap 0.10795)
					(clearance 0.10795)
				)
			)
		)
		(pad "4" thru_hole circle
			(at 0 2.54 90)
			(size 1.0033 1.0033)
			(drill 0.249936)
			(layers "*.Cu" "*.Mask")
			(remove_unused_layers no)
			(net "TDR_DIFF_85_BOT_DP")
			(clearance 0.10795)
			(padstack
				(mode front_inner_back)
				(layer "Inner"
					(shape circle)
					(size 0.8001 0.8001)
					(clearance 0.1524)
				)
				(layer "B.Cu"
					(shape circle)
					(size 1.0033 1.0033)
					(thermal_gap 0.10795)
					(clearance 0.10795)
				)
			)
		)
	)
	(footprint ""
		(layer "B.Cu")
		(at 98.511868 -404.486618 -90)
		(property "Reference" "C2074"
			(at 0 0 90)
			(layer "B.SilkS")
			(hide yes)
			(effects
				(font
					(size 1.27 1.27)
				)
				(justify mirror)
			)
		)
		(property "Value" ""
			(at 0 0 90)
			(layer "B.Fab")
			(effects
				(font
					(size 1.27 1.27)
				)
				(justify mirror)
			)
		)
		(duplicate_pad_numbers_are_jumpers no)
		(fp_line
			(start -0.299974 0.150114)
			(end 0.299974 0.150114)
			(stroke
				(width 0.1)
				(type default)
			)
			(layer "B.Fab")
		)
		(fp_line
			(start 0.299974 0.150114)
			(end 0.299974 -0.150114)
			(stroke
				(width 0.1)
				(type default)
			)
			(layer "B.Fab")
		)
		(fp_line
			(start -0.299974 -0.150114)
			(end -0.299974 0.150114)
			(stroke
				(width 0.1)
				(type default)
			)
			(layer "B.Fab")
		)
		(fp_line
			(start 0.299974 -0.150114)
			(end -0.299974 -0.150114)
			(stroke
				(width 0.1)
				(type default)
			)
			(layer "B.Fab")
		)
		(pad "1" smd rect
			(at 0.2667 0 90)
			(size 0.3048 0.381)
			(layers "B.Cu" "B.Mask" "B.Paste")
			(net "P3E_PCH_NVS_TX_DN<1>")
		)
		(pad "2" smd rect
			(at -0.2667 0 90)
			(size 0.3048 0.381)
			(layers "B.Cu" "B.Mask" "B.Paste")
			(net "P3E_PCH_NVS_TX_C_DN<1>")
		)
		(zone
			(layer "In16.Cu")
			(hatch none 0.5)
			(connect_pads
				(clearance 0)
			)
			(min_thickness 0.25)
			(keepout
				(tracks not_allowed)
				(vias allowed)
				(pads allowed)
				(copperpour not_allowed)
				(footprints allowed)
			)
			(placement
				(enabled no)
				(sheetname "")
			)
			(fill
				(thermal_gap 0.5)
				(thermal_bridge_width 0.5)
				(island_removal_mode 0)
			)
			(polygon
				(pts
					(arc
						(start 98.270568 -404.626318)
						(mid 98.292886 -404.572436)
						(end 98.346768 -404.550118)
					)
					(arc
						(start 98.676968 -404.550118)
						(mid 98.73085 -404.572436)
						(end 98.753168 -404.626318)
					)
					(arc
						(start 98.753168 -404.880318)
						(mid 98.73085 -404.9342)
						(end 98.676968 -404.956518)
					)
					(arc
						(start 98.346768 -404.956518)
						(mid 98.292886 -404.9342)
						(end 98.270568 -404.880318)
					)
				)
			)
		)
		(zone
			(layer "In16.Cu")
			(hatch none 0.5)
			(connect_pads
				(clearance 0)
			)
			(min_thickness 0.25)
			(keepout
				(tracks not_allowed)
				(vias allowed)
				(pads allowed)
				(copperpour not_allowed)
				(footprints allowed)
			)
			(placement
				(enabled no)
				(sheetname "")
			)
			(fill
				(thermal_gap 0.5)
				(thermal_bridge_width 0.5)
				(island_removal_mode 0)
			)
			(polygon
				(pts
					(arc
						(start 98.270568 -404.092918)
						(mid 98.292886 -404.039036)
						(end 98.346768 -404.016718)
					)
					(arc
						(start 98.676968 -404.016718)
						(mid 98.73085 -404.039036)
						(end 98.753168 -404.092918)
					)
					(arc
						(start 98.753168 -404.346918)
						(mid 98.73085 -404.4008)
						(end 98.676968 -404.423118)
					)
					(arc
						(start 98.346768 -404.423118)
						(mid 98.292886 -404.4008)
						(end 98.270568 -404.346918)
					)
				)
			)
		)
	)
	(footprint ""
		(layer "B.Cu")
		(at 366.120934 -248.498106 -90)
		(property "Reference" "C376"
			(at 0 0 90)
			(layer "B.SilkS")
			(hide yes)
			(effects
				(font
					(size 1.27 1.27)
				)
				(justify mirror)
			)
		)
		(property "Value" ""
			(at 0 0 90)
			(layer "B.Fab")
			(effects
				(font
					(size 1.27 1.27)
				)
				(justify mirror)
			)
		)
		(duplicate_pad_numbers_are_jumpers no)
		(fp_line
			(start -1.524 0.762)
			(end 1.524 0.762)
			(stroke
				(width 0.1524)
				(type default)
			)
			(layer "B.SilkS")
		)
		(fp_line
			(start 1.524 0.762)
			(end 1.524 -0.762)
			(stroke
				(width 0.1524)
				(type default)
			)
			(layer "B.SilkS")
		)
		(fp_line
			(start -1.524 -0.762)
			(end -1.524 0.762)
			(stroke
				(width 0.1524)
				(type default)
			)
			(layer "B.SilkS")
		)
		(fp_line
			(start 1.524 -0.762)
			(end -1.524 -0.762)
			(stroke
				(width 0.1524)
				(type default)
			)
			(layer "B.SilkS")
		)
		(fp_line
			(start -1.1049 0.724916)
			(end -1.1049 -0.724916)
			(stroke
				(width 0.1)
				(type default)
			)
			(layer "B.Fab")
		)
		(fp_line
			(start 1.1049 0.724916)
			(end -1.1049 0.724916)
			(stroke
				(width 0.1)
				(type default)
			)
			(layer "B.Fab")
		)
		(fp_line
			(start -1.1049 -0.724916)
			(end 1.1049 -0.724916)
			(stroke
				(width 0.1)
				(type default)
			)
			(layer "B.Fab")
		)
		(fp_line
			(start 1.1049 -0.724916)
			(end 1.1049 0.724916)
			(stroke
				(width 0.1)
				(type default)
			)
			(layer "B.Fab")
		)
		(pad "1" smd rect
			(at 0.889 0 270)
			(size 1.016 1.27)
			(layers "B.Cu" "B.Mask" "B.Paste")
			(net "PVCCIN_CPU0")
		)
		(pad "2" smd rect
			(at -0.889 0 270)
			(size 1.016 1.27)
			(layers "B.Cu" "B.Mask" "B.Paste")
			(net "GND")
		)
	)
	(footprint ""
		(layer "B.Cu")
		(at 427.466252 -124.025152)
		(property "Reference" "PR409"
			(at 0 0 0)
			(layer "B.SilkS")
			(hide yes)
			(effects
				(font
					(size 1.27 1.27)
				)
				(justify mirror)
			)
		)
		(property "Value" ""
			(at 0 0 0)
			(layer "B.Fab")
			(effects
				(font
					(size 1.27 1.27)
				)
				(justify mirror)
			)
		)
		(duplicate_pad_numbers_are_jumpers no)
		(fp_line
			(start -0.7874 -0.4064)
			(end -0.7874 0.4064)
			(stroke
				(width 0.1524)
				(type default)
			)
			(layer "B.SilkS")
		)
		(fp_line
			(start -0.7874 0.4064)
			(end 0.7874 0.4064)
			(stroke
				(width 0.1524)
				(type default)
			)
			(layer "B.SilkS")
		)
		(fp_line
			(start 0.7874 -0.4064)
			(end -0.7874 -0.4064)
			(stroke
				(width 0.1524)
				(type default)
			)
			(layer "B.SilkS")
		)
		(fp_line
			(start 0.7874 0.4064)
			(end 0.7874 -0.4064)
			(stroke
				(width 0.1524)
				(type default)
			)
			(layer "B.SilkS")
		)
		(fp_line
			(start -0.67945 -0.3048)
			(end -0.67945 0.3048)
			(stroke
				(width 0.1)
				(type default)
			)
			(layer "B.Fab")
		)
		(fp_line
			(start -0.67945 0.3048)
			(end -0.120396 0.3048)
			(stroke
				(width 0.1)
				(type default)
			)
			(layer "B.Fab")
		)
		(fp_line
			(start -0.12065 -0.3048)
			(end -0.67945 -0.3048)
			(stroke
				(width 0.1)
				(type default)
			)
			(layer "B.Fab")
		)
		(fp_line
			(start -0.12065 -0.2794)
			(end -0.12065 -0.3048)
			(stroke
				(width 0.1)
				(type default)
			)
			(layer "B.Fab")
		)
		(fp_line
			(start -0.120396 0.2794)
			(end 0.12065 0.2794)
			(stroke
				(width 0.1)
				(type default)
			)
			(layer "B.Fab")
		)
		(fp_line
			(start -0.120396 0.3048)
			(end -0.120396 0.2794)
			(stroke
				(width 0.1)
				(type default)
			)
			(layer "B.Fab")
		)
		(fp_line
			(start 0.12065 -0.305054)
			(end 0.12065 -0.2794)
			(stroke
				(width 0.1)
				(type default)
			)
			(layer "B.Fab")
		)
		(fp_line
			(start 0.12065 -0.2794)
			(end -0.12065 -0.2794)
			(stroke
				(width 0.1)
				(type default)
			)
			(layer "B.Fab")
		)
		(fp_line
			(start 0.12065 0.2794)
			(end 0.12065 0.3048)
			(stroke
				(width 0.1)
				(type default)
			)
			(layer "B.Fab")
		)
		(fp_line
			(start 0.12065 0.3048)
			(end 0.67945 0.3048)
			(stroke
				(width 0.1)
				(type default)
			)
			(layer "B.Fab")
		)
		(fp_line
			(start 0.67945 -0.305054)
			(end 0.12065 -0.305054)
			(stroke
				(width 0.1)
				(type default)
			)
			(layer "B.Fab")
		)
		(fp_line
			(start 0.67945 0.3048)
			(end 0.67945 -0.305054)
			(stroke
				(width 0.1)
				(type default)
			)
			(layer "B.Fab")
		)
		(pad "1" smd circle
			(at 0.40005 0 180)
			(size 0 0)
			(layers "B.Cu" "B.Mask" "B.Paste")
			(net "PVCCD_HV_CPU0_ISYS_R")
		)
		(pad "2" smd circle
			(at -0.40005 0 180)
			(size 0 0)
			(layers "B.Cu" "B.Mask" "B.Paste")
			(net "PVCCD_HV_CPU0_NVDIMM_ISENSE")
		)
	)
	(footprint ""
		(layer "B.Cu")
		(at 284.446726 -193.691256 -90)
		(property "Reference" "R706"
			(at 0 0 90)
			(layer "B.SilkS")
			(hide yes)
			(effects
				(font
					(size 1.27 1.27)
				)
				(justify mirror)
			)
		)
		(property "Value" ""
			(at 0 0 90)
			(layer "B.Fab")
			(effects
				(font
					(size 1.27 1.27)
				)
				(justify mirror)
			)
		)
		(duplicate_pad_numbers_are_jumpers no)
		(fp_line
			(start -0.7874 0.4064)
			(end 0.7874 0.4064)
			(stroke
				(width 0.1524)
				(type default)
			)
			(layer "B.SilkS")
		)
		(fp_line
			(start 0.7874 0.4064)
			(end 0.7874 -0.4064)
			(stroke
				(width 0.1524)
				(type default)
			)
			(layer "B.SilkS")
		)
		(fp_line
			(start -0.7874 -0.4064)
			(end -0.7874 0.4064)
			(stroke
				(width 0.1524)
				(type default)
			)
			(layer "B.SilkS")
		)
		(fp_line
			(start 0.7874 -0.4064)
			(end -0.7874 -0.4064)
			(stroke
				(width 0.1524)
				(type default)
			)
			(layer "B.SilkS")
		)
		(fp_line
			(start -0.67945 0.3048)
			(end -0.120396 0.3048)
			(stroke
				(width 0.1)
				(type default)
			)
			(layer "B.Fab")
		)
		(fp_line
			(start -0.120396 0.3048)
			(end -0.120396 0.2794)
			(stroke
				(width 0.1)
				(type default)
			)
			(layer "B.Fab")
		)
		(fp_line
			(start 0.12065 0.3048)
			(end 0.67945 0.3048)
			(stroke
				(width 0.1)
				(type default)
			)
			(layer "B.Fab")
		)
		(fp_line
			(start 0.67945 0.3048)
			(end 0.67945 -0.305054)
			(stroke
				(width 0.1)
				(type default)
			)
			(layer "B.Fab")
		)
		(fp_line
			(start -0.120396 0.2794)
			(end 0.12065 0.2794)
			(stroke
				(width 0.1)
				(type default)
			)
			(layer "B.Fab")
		)
		(fp_line
			(start 0.12065 0.2794)
			(end 0.12065 0.3048)
			(stroke
				(width 0.1)
				(type default)
			)
			(layer "B.Fab")
		)
		(fp_line
			(start -0.12065 -0.2794)
			(end -0.12065 -0.3048)
			(stroke
				(width 0.1)
				(type default)
			)
			(layer "B.Fab")
		)
		(fp_line
			(start 0.12065 -0.2794)
			(end -0.12065 -0.2794)
			(stroke
				(width 0.1)
				(type default)
			)
			(layer "B.Fab")
		)
		(fp_line
			(start -0.67945 -0.3048)
			(end -0.67945 0.3048)
			(stroke
				(width 0.1)
				(type default)
			)
			(layer "B.Fab")
		)
		(fp_line
			(start -0.12065 -0.3048)
			(end -0.67945 -0.3048)
			(stroke
				(width 0.1)
				(type default)
			)
			(layer "B.Fab")
		)
		(fp_line
			(start 0.12065 -0.305054)
			(end 0.12065 -0.2794)
			(stroke
				(width 0.1)
				(type default)
			)
			(layer "B.Fab")
		)
		(fp_line
			(start 0.67945 -0.305054)
			(end 0.12065 -0.305054)
			(stroke
				(width 0.1)
				(type default)
			)
			(layer "B.Fab")
		)
		(pad "1" smd circle
			(at 0.40005 0 90)
			(size 0 0)
			(layers "B.Cu" "B.Mask" "B.Paste")
			(net "RST_PLD_CPU0_DRAM_AB_N")
		)
		(pad "2" smd circle
			(at -0.40005 0 90)
			(size 0 0)
			(layers "B.Cu" "B.Mask" "B.Paste")
			(net "GND")
		)
	)
	(footprint ""
		(layer "B.Cu")
		(at 57.88152 -315.539882)
		(property "Reference" "R3892"
			(at 0 0 0)
			(layer "B.SilkS")
			(hide yes)
			(effects
				(font
					(size 1.27 1.27)
				)
				(justify mirror)
			)
		)
		(property "Value" ""
			(at 0 0 0)
			(layer "B.Fab")
			(effects
				(font
					(size 1.27 1.27)
				)
				(justify mirror)
			)
		)
		(duplicate_pad_numbers_are_jumpers no)
		(fp_line
			(start -0.7874 -0.4064)
			(end -0.7874 0.4064)
			(stroke
				(width 0.1524)
				(type default)
			)
			(layer "B.SilkS")
		)
		(fp_line
			(start -0.7874 0.4064)
			(end 0.7874 0.4064)
			(stroke
				(width 0.1524)
				(type default)
			)
			(layer "B.SilkS")
		)
		(fp_line
			(start 0.7874 -0.4064)
			(end -0.7874 -0.4064)
			(stroke
				(width 0.1524)
				(type default)
			)
			(layer "B.SilkS")
		)
		(fp_line
			(start 0.7874 0.4064)
			(end 0.7874 -0.4064)
			(stroke
				(width 0.1524)
				(type default)
			)
			(layer "B.SilkS")
		)
		(fp_line
			(start -0.67945 -0.3048)
			(end -0.67945 0.3048)
			(stroke
				(width 0.1)
				(type default)
			)
			(layer "B.Fab")
		)
		(fp_line
			(start -0.67945 0.3048)
			(end -0.120396 0.3048)
			(stroke
				(width 0.1)
				(type default)
			)
			(layer "B.Fab")
		)
		(fp_line
			(start -0.12065 -0.3048)
			(end -0.67945 -0.3048)
			(stroke
				(width 0.1)
				(type default)
			)
			(layer "B.Fab")
		)
		(fp_line
			(start -0.12065 -0.2794)
			(end -0.12065 -0.3048)
			(stroke
				(width 0.1)
				(type default)
			)
			(layer "B.Fab")
		)
		(fp_line
			(start -0.120396 0.2794)
			(end 0.12065 0.2794)
			(stroke
				(width 0.1)
				(type default)
			)
			(layer "B.Fab")
		)
		(fp_line
			(start -0.120396 0.3048)
			(end -0.120396 0.2794)
			(stroke
				(width 0.1)
				(type default)
			)
			(layer "B.Fab")
		)
		(fp_line
			(start 0.12065 -0.305054)
			(end 0.12065 -0.2794)
			(stroke
				(width 0.1)
				(type default)
			)
			(layer "B.Fab")
		)
		(fp_line
			(start 0.12065 -0.2794)
			(end -0.12065 -0.2794)
			(stroke
				(width 0.1)
				(type default)
			)
			(layer "B.Fab")
		)
		(fp_line
			(start 0.12065 0.2794)
			(end 0.12065 0.3048)
			(stroke
				(width 0.1)
				(type default)
			)
			(layer "B.Fab")
		)
		(fp_line
			(start 0.12065 0.3048)
			(end 0.67945 0.3048)
			(stroke
				(width 0.1)
				(type default)
			)
			(layer "B.Fab")
		)
		(fp_line
			(start 0.67945 -0.305054)
			(end 0.12065 -0.305054)
			(stroke
				(width 0.1)
				(type default)
			)
			(layer "B.Fab")
		)
		(fp_line
			(start 0.67945 0.3048)
			(end 0.67945 -0.305054)
			(stroke
				(width 0.1)
				(type default)
			)
			(layer "B.Fab")
		)
		(pad "1" smd circle
			(at 0.40005 0 180)
			(size 0 0)
			(layers "B.Cu" "B.Mask" "B.Paste")
			(net "I3C_SPD_DDRABCD_CPU1_LVC1_SCL_1")
		)
		(pad "2" smd circle
			(at -0.40005 0 180)
			(size 0 0)
			(layers "B.Cu" "B.Mask" "B.Paste")
			(net "I3C_SPD_DDRABCD_CPU1_LVC1_SCL")
		)
	)
	(footprint ""
		(layer "B.Cu")
		(at 83.933538 -342.936576 90)
		(property "Reference" "PC492_P1_7"
			(at 0 0 90)
			(layer "B.SilkS")
			(hide yes)
			(effects
				(font
					(size 1.27 1.27)
				)
				(justify mirror)
			)
		)
		(property "Value" ""
			(at 0 0 90)
			(layer "B.Fab")
			(effects
				(font
					(size 1.27 1.27)
				)
				(justify mirror)
			)
		)
		(duplicate_pad_numbers_are_jumpers no)
		(fp_line
			(start 1.524 -0.762)
			(end -1.524 -0.762)
			(stroke
				(width 0.1524)
				(type default)
			)
			(layer "B.SilkS")
		)
		(fp_line
			(start -1.524 -0.762)
			(end -1.524 0.762)
			(stroke
				(width 0.1524)
				(type default)
			)
			(layer "B.SilkS")
		)
		(fp_line
			(start 1.524 0.762)
			(end 1.524 -0.762)
			(stroke
				(width 0.1524)
				(type default)
			)
			(layer "B.SilkS")
		)
		(fp_line
			(start -1.524 0.762)
			(end 1.524 0.762)
			(stroke
				(width 0.1524)
				(type default)
			)
			(layer "B.SilkS")
		)
		(fp_line
			(start 1.1049 -0.724916)
			(end 1.1049 0.724916)
			(stroke
				(width 0.1)
				(type default)
			)
			(layer "B.Fab")
		)
		(fp_line
			(start -1.1049 -0.724916)
			(end 1.1049 -0.724916)
			(stroke
				(width 0.1)
				(type default)
			)
			(layer "B.Fab")
		)
		(fp_line
			(start 1.1049 0.724916)
			(end -1.1049 0.724916)
			(stroke
				(width 0.1)
				(type default)
			)
			(layer "B.Fab")
		)
		(fp_line
			(start -1.1049 0.724916)
			(end -1.1049 -0.724916)
			(stroke
				(width 0.1)
				(type default)
			)
			(layer "B.Fab")
		)
		(pad "1" smd rect
			(at 0.889 0 90)
			(size 1.016 1.27)
			(layers "B.Cu" "B.Mask" "B.Paste")
			(net "SW_P12V_PVCCIN_CPU1_FLT")
		)
		(pad "2" smd rect
			(at -0.889 0 90)
			(size 1.016 1.27)
			(layers "B.Cu" "B.Mask" "B.Paste")
			(net "GND")
		)
	)
	(footprint ""
		(layer "B.Cu")
		(at 416.02914 -176.20107)
		(property "Reference" "PC196_P0_2"
			(at 0 0 0)
			(layer "B.SilkS")
			(hide yes)
			(effects
				(font
					(size 1.27 1.27)
				)
				(justify mirror)
			)
		)
		(property "Value" ""
			(at 0 0 0)
			(layer "B.Fab")
			(effects
				(font
					(size 1.27 1.27)
				)
				(justify mirror)
			)
		)
		(duplicate_pad_numbers_are_jumpers no)
		(fp_line
			(start -1.524 -0.762)
			(end -1.524 0.762)
			(stroke
				(width 0.1524)
				(type default)
			)
			(layer "B.SilkS")
		)
		(fp_line
			(start -1.524 0.762)
			(end 1.524 0.762)
			(stroke
				(width 0.1524)
				(type default)
			)
			(layer "B.SilkS")
		)
		(fp_line
			(start 1.524 -0.762)
			(end -1.524 -0.762)
			(stroke
				(width 0.1524)
				(type default)
			)
			(layer "B.SilkS")
		)
		(fp_line
			(start 1.524 0.762)
			(end 1.524 -0.762)
			(stroke
				(width 0.1524)
				(type default)
			)
			(layer "B.SilkS")
		)
		(fp_line
			(start -1.1049 -0.724916)
			(end 1.1049 -0.724916)
			(stroke
				(width 0.1)
				(type default)
			)
			(layer "B.Fab")
		)
		(fp_line
			(start -1.1049 0.724916)
			(end -1.1049 -0.724916)
			(stroke
				(width 0.1)
				(type default)
			)
			(layer "B.Fab")
		)
		(fp_line
			(start 1.1049 -0.724916)
			(end 1.1049 0.724916)
			(stroke
				(width 0.1)
				(type default)
			)
			(layer "B.Fab")
		)
		(fp_line
			(start 1.1049 0.724916)
			(end -1.1049 0.724916)
			(stroke
				(width 0.1)
				(type default)
			)
			(layer "B.Fab")
		)
		(pad "1" smd rect
			(at 0.889 0)
			(size 1.016 1.27)
			(layers "B.Cu" "B.Mask" "B.Paste")
			(net "SW_P12V_PVCCINFAON_CPU0_FLT")
		)
		(pad "2" smd rect
			(at -0.889 0)
			(size 1.016 1.27)
			(layers "B.Cu" "B.Mask" "B.Paste")
			(net "GND")
		)
	)
	(footprint ""
		(layer "B.Cu")
		(at 337.89874 -337.145884 90)
		(property "Reference" "PC262_P0_6"
			(at 0 0 90)
			(layer "B.SilkS")
			(hide yes)
			(effects
				(font
					(size 1.27 1.27)
				)
				(justify mirror)
			)
		)
		(property "Value" ""
			(at 0 0 90)
			(layer "B.Fab")
			(effects
				(font
					(size 1.27 1.27)
				)
				(justify mirror)
			)
		)
		(duplicate_pad_numbers_are_jumpers no)
		(fp_line
			(start 1.524 -0.762)
			(end -1.524 -0.762)
			(stroke
				(width 0.1524)
				(type default)
			)
			(layer "B.SilkS")
		)
		(fp_line
			(start -1.524 -0.762)
			(end -1.524 0.762)
			(stroke
				(width 0.1524)
				(type default)
			)
			(layer "B.SilkS")
		)
		(fp_line
			(start 1.524 0.762)
			(end 1.524 -0.762)
			(stroke
				(width 0.1524)
				(type default)
			)
			(layer "B.SilkS")
		)
		(fp_line
			(start -1.524 0.762)
			(end 1.524 0.762)
			(stroke
				(width 0.1524)
				(type default)
			)
			(layer "B.SilkS")
		)
		(fp_line
			(start 1.1049 -0.724916)
			(end 1.1049 0.724916)
			(stroke
				(width 0.1)
				(type default)
			)
			(layer "B.Fab")
		)
		(fp_line
			(start -1.1049 -0.724916)
			(end 1.1049 -0.724916)
			(stroke
				(width 0.1)
				(type default)
			)
			(layer "B.Fab")
		)
		(fp_line
			(start 1.1049 0.724916)
			(end -1.1049 0.724916)
			(stroke
				(width 0.1)
				(type default)
			)
			(layer "B.Fab")
		)
		(fp_line
			(start -1.1049 0.724916)
			(end -1.1049 -0.724916)
			(stroke
				(width 0.1)
				(type default)
			)
			(layer "B.Fab")
		)
		(pad "1" smd rect
			(at 0.889 0 90)
			(size 1.016 1.27)
			(layers "B.Cu" "B.Mask" "B.Paste")
			(net "SW_P12V_PVCCIN_CPU0_FLT")
		)
		(pad "2" smd rect
			(at -0.889 0 90)
			(size 1.016 1.27)
			(layers "B.Cu" "B.Mask" "B.Paste")
			(net "GND")
		)
	)
	(footprint ""
		(layer "B.Cu")
		(at 181.457346 -319.268856 180)
		(property "Reference" "C87"
			(at 0 0 0)
			(layer "B.SilkS")
			(hide yes)
			(effects
				(font
					(size 1.27 1.27)
				)
				(justify mirror)
			)
		)
		(property "Value" ""
			(at 0 0 0)
			(layer "B.Fab")
			(effects
				(font
					(size 1.27 1.27)
				)
				(justify mirror)
			)
		)
		(duplicate_pad_numbers_are_jumpers no)
		(fp_line
			(start 0.7874 0.4064)
			(end 0.7874 -0.4064)
			(stroke
				(width 0.1524)
				(type default)
			)
			(layer "B.SilkS")
		)
		(fp_line
			(start 0.7874 -0.4064)
			(end -0.7874 -0.4064)
			(stroke
				(width 0.1524)
				(type default)
			)
			(layer "B.SilkS")
		)
		(fp_line
			(start -0.7874 0.4064)
			(end 0.7874 0.4064)
			(stroke
				(width 0.1524)
				(type default)
			)
			(layer "B.SilkS")
		)
		(fp_line
			(start -0.7874 -0.4064)
			(end -0.7874 0.4064)
			(stroke
				(width 0.1524)
				(type default)
			)
			(layer "B.SilkS")
		)
		(fp_line
			(start 0.67945 0.3048)
			(end 0.67945 -0.305054)
			(stroke
				(width 0.1)
				(type default)
			)
			(layer "B.Fab")
		)
		(fp_line
			(start 0.67945 -0.305054)
			(end 0.12065 -0.305054)
			(stroke
				(width 0.1)
				(type default)
			)
			(layer "B.Fab")
		)
		(fp_line
			(start 0.12065 0.3048)
			(end 0.67945 0.3048)
			(stroke
				(width 0.1)
				(type default)
			)
			(layer "B.Fab")
		)
		(fp_line
			(start 0.12065 0.2794)
			(end 0.12065 0.3048)
			(stroke
				(width 0.1)
				(type default)
			)
			(layer "B.Fab")
		)
		(fp_line
			(start 0.12065 -0.2794)
			(end -0.12065 -0.2794)
			(stroke
				(width 0.1)
				(type default)
			)
			(layer "B.Fab")
		)
		(fp_line
			(start 0.12065 -0.305054)
			(end 0.12065 -0.2794)
			(stroke
				(width 0.1)
				(type default)
			)
			(layer "B.Fab")
		)
		(fp_line
			(start -0.120396 0.3048)
			(end -0.120396 0.2794)
			(stroke
				(width 0.1)
				(type default)
			)
			(layer "B.Fab")
		)
		(fp_line
			(start -0.120396 0.2794)
			(end 0.12065 0.2794)
			(stroke
				(width 0.1)
				(type default)
			)
			(layer "B.Fab")
		)
		(fp_line
			(start -0.12065 -0.2794)
			(end -0.12065 -0.3048)
			(stroke
				(width 0.1)
				(type default)
			)
			(layer "B.Fab")
		)
		(fp_line
			(start -0.12065 -0.3048)
			(end -0.67945 -0.3048)
			(stroke
				(width 0.1)
				(type default)
			)
			(layer "B.Fab")
		)
		(fp_line
			(start -0.67945 0.3048)
			(end -0.120396 0.3048)
			(stroke
				(width 0.1)
				(type default)
			)
			(layer "B.Fab")
		)
		(fp_line
			(start -0.67945 -0.3048)
			(end -0.67945 0.3048)
			(stroke
				(width 0.1)
				(type default)
			)
			(layer "B.Fab")
		)
		(pad "1" smd circle
			(at 0.40005 0)
			(size 0 0)
			(layers "B.Cu" "B.Mask" "B.Paste")
			(net "P3V3_AUX")
		)
		(pad "2" smd circle
			(at -0.40005 0)
			(size 0 0)
			(layers "B.Cu" "B.Mask" "B.Paste")
			(net "GND")
		)
	)
	(footprint ""
		(layer "B.Cu")
		(at 409.284932 -162.185858 180)
		(property "Reference" "PC1910"
			(at 0 0 0)
			(layer "B.SilkS")
			(hide yes)
			(effects
				(font
					(size 1.27 1.27)
				)
				(justify mirror)
			)
		)
		(property "Value" ""
			(at 0 0 0)
			(layer "B.Fab")
			(effects
				(font
					(size 1.27 1.27)
				)
				(justify mirror)
			)
		)
		(duplicate_pad_numbers_are_jumpers no)
		(fp_line
			(start 4.84378 -2.150618)
			(end 4.842256 2.163064)
			(stroke
				(width 0.1524)
				(type default)
			)
			(layer "B.SilkS")
		)
		(fp_line
			(start 4.84378 -2.150618)
			(end 4.53898 -2.150618)
			(stroke
				(width 0.1524)
				(type default)
			)
			(layer "B.SilkS")
		)
		(fp_line
			(start 4.83108 2.150364)
			(end 4.447794 2.149348)
			(stroke
				(width 0.1524)
				(type default)
			)
			(layer "B.SilkS")
		)
		(fp_line
			(start 4.69138 -2.150618)
			(end 4.692396 2.161032)
			(stroke
				(width 0.1524)
				(type default)
			)
			(layer "B.SilkS")
		)
		(fp_line
			(start 4.53898 2.15011)
			(end 4.53898 -2.15011)
			(stroke
				(width 0.1524)
				(type default)
			)
			(layer "B.SilkS")
		)
		(fp_line
			(start 4.53898 -2.15011)
			(end -4.53898 -2.15011)
			(stroke
				(width 0.1524)
				(type default)
			)
			(layer "B.SilkS")
		)
		(fp_line
			(start 4.53898 -2.150618)
			(end 4.539742 2.152142)
			(stroke
				(width 0.1524)
				(type default)
			)
			(layer "B.SilkS")
		)
		(fp_line
			(start -4.53898 2.15011)
			(end 4.53898 2.15011)
			(stroke
				(width 0.1524)
				(type default)
			)
			(layer "B.SilkS")
		)
		(fp_line
			(start -4.53898 -2.15011)
			(end -4.53898 2.15011)
			(stroke
				(width 0.1524)
				(type default)
			)
			(layer "B.SilkS")
		)
		(fp_line
			(start 3.64998 2.15011)
			(end 3.64998 -2.15011)
			(stroke
				(width 0.1)
				(type default)
			)
			(layer "B.Fab")
		)
		(fp_line
			(start 3.64998 -2.15011)
			(end -3.64998 -2.15011)
			(stroke
				(width 0.1)
				(type default)
			)
			(layer "B.Fab")
		)
		(fp_line
			(start -3.64998 2.15011)
			(end 3.64998 2.15011)
			(stroke
				(width 0.1)
				(type default)
			)
			(layer "B.Fab")
		)
		(fp_line
			(start -3.64998 -2.15011)
			(end -3.64998 2.15011)
			(stroke
				(width 0.1)
				(type default)
			)
			(layer "B.Fab")
		)
		(fp_text user "+"
			(at 6.214872 -0.337058 180)
			(unlocked yes)
			(layer "B.SilkS")
			(effects
				(font
					(size 1.905 1.4224)
					(thickness 0.1524)
				)
				(justify left mirror)
			)
		)
		(fp_text user "-"
			(at -5.646928 0.98552 180)
			(unlocked yes)
			(layer "B.SilkS")
			(effects
				(font
					(size 1.905 1.4224)
					(thickness 0.1524)
				)
				(justify left mirror)
			)
		)
		(fp_text user "+"
			(at 6.214872 -0.337058 180)
			(unlocked yes)
			(layer "B.Fab")
			(effects
				(font
					(size 1.905 1.4224)
					(thickness 0.1524)
				)
				(justify left mirror)
			)
		)
		(fp_text user "-"
			(at -4.313174 -0.094488 180)
			(unlocked yes)
			(layer "B.Fab")
			(effects
				(font
					(size 1.905 1.4224)
					(thickness 0.1524)
				)
				(justify left mirror)
			)
		)
		(pad "1" smd rect
			(at 3.199892 0)
			(size 2.413 2.8194)
			(layers "B.Cu" "B.Mask" "B.Paste")
			(net "PVCCD_HV_CPU0")
		)
		(pad "2" smd rect
			(at -3.199892 0)
			(size 2.413 2.8194)
			(layers "B.Cu" "B.Mask" "B.Paste")
			(net "GND")
		)
	)
	(footprint ""
		(layer "B.Cu")
		(at 175.31588 -13.762228 -90)
		(property "Reference" "R1336"
			(at 0 0 90)
			(layer "B.SilkS")
			(hide yes)
			(effects
				(font
					(size 1.27 1.27)
				)
				(justify mirror)
			)
		)
		(property "Value" ""
			(at 0 0 90)
			(layer "B.Fab")
			(effects
				(font
					(size 1.27 1.27)
				)
				(justify mirror)
			)
		)
		(duplicate_pad_numbers_are_jumpers no)
		(fp_line
			(start -0.7874 0.4064)
			(end 0.7874 0.4064)
			(stroke
				(width 0.1524)
				(type default)
			)
			(layer "B.SilkS")
		)
		(fp_line
			(start 0.7874 0.4064)
			(end 0.7874 -0.4064)
			(stroke
				(width 0.1524)
				(type default)
			)
			(layer "B.SilkS")
		)
		(fp_line
			(start -0.7874 -0.4064)
			(end -0.7874 0.4064)
			(stroke
				(width 0.1524)
				(type default)
			)
			(layer "B.SilkS")
		)
		(fp_line
			(start 0.7874 -0.4064)
			(end -0.7874 -0.4064)
			(stroke
				(width 0.1524)
				(type default)
			)
			(layer "B.SilkS")
		)
		(fp_line
			(start -0.67945 0.3048)
			(end -0.120396 0.3048)
			(stroke
				(width 0.1)
				(type default)
			)
			(layer "B.Fab")
		)
		(fp_line
			(start -0.120396 0.3048)
			(end -0.120396 0.2794)
			(stroke
				(width 0.1)
				(type default)
			)
			(layer "B.Fab")
		)
		(fp_line
			(start 0.12065 0.3048)
			(end 0.67945 0.3048)
			(stroke
				(width 0.1)
				(type default)
			)
			(layer "B.Fab")
		)
		(fp_line
			(start 0.67945 0.3048)
			(end 0.67945 -0.305054)
			(stroke
				(width 0.1)
				(type default)
			)
			(layer "B.Fab")
		)
		(fp_line
			(start -0.120396 0.2794)
			(end 0.12065 0.2794)
			(stroke
				(width 0.1)
				(type default)
			)
			(layer "B.Fab")
		)
		(fp_line
			(start 0.12065 0.2794)
			(end 0.12065 0.3048)
			(stroke
				(width 0.1)
				(type default)
			)
			(layer "B.Fab")
		)
		(fp_line
			(start -0.12065 -0.2794)
			(end -0.12065 -0.3048)
			(stroke
				(width 0.1)
				(type default)
			)
			(layer "B.Fab")
		)
		(fp_line
			(start 0.12065 -0.2794)
			(end -0.12065 -0.2794)
			(stroke
				(width 0.1)
				(type default)
			)
			(layer "B.Fab")
		)
		(fp_line
			(start -0.67945 -0.3048)
			(end -0.67945 0.3048)
			(stroke
				(width 0.1)
				(type default)
			)
			(layer "B.Fab")
		)
		(fp_line
			(start -0.12065 -0.3048)
			(end -0.67945 -0.3048)
			(stroke
				(width 0.1)
				(type default)
			)
			(layer "B.Fab")
		)
		(fp_line
			(start 0.12065 -0.305054)
			(end 0.12065 -0.2794)
			(stroke
				(width 0.1)
				(type default)
			)
			(layer "B.Fab")
		)
		(fp_line
			(start 0.67945 -0.305054)
			(end 0.12065 -0.305054)
			(stroke
				(width 0.1)
				(type default)
			)
			(layer "B.Fab")
		)
		(pad "1" smd circle
			(at 0.40005 0 90)
			(size 0 0)
			(layers "B.Cu" "B.Mask" "B.Paste")
			(net "I3C_BMC_SWB_SCL")
		)
		(pad "2" smd circle
			(at -0.40005 0 90)
			(size 0 0)
			(layers "B.Cu" "B.Mask" "B.Paste")
			(net "P3V3_AUX")
		)
	)
	(footprint ""
		(layer "B.Cu")
		(at 107.457494 -255.8542 -90)
		(property "Reference" "C324"
			(at 0 0 90)
			(layer "B.SilkS")
			(hide yes)
			(effects
				(font
					(size 1.27 1.27)
				)
				(justify mirror)
			)
		)
		(property "Value" ""
			(at 0 0 90)
			(layer "B.Fab")
			(effects
				(font
					(size 1.27 1.27)
				)
				(justify mirror)
			)
		)
		(duplicate_pad_numbers_are_jumpers no)
		(fp_line
			(start -1.524 0.762)
			(end 1.524 0.762)
			(stroke
				(width 0.1524)
				(type default)
			)
			(layer "B.SilkS")
		)
		(fp_line
			(start 1.524 0.762)
			(end 1.524 -0.762)
			(stroke
				(width 0.1524)
				(type default)
			)
			(layer "B.SilkS")
		)
		(fp_line
			(start -1.524 -0.762)
			(end -1.524 0.762)
			(stroke
				(width 0.1524)
				(type default)
			)
			(layer "B.SilkS")
		)
		(fp_line
			(start 1.524 -0.762)
			(end -1.524 -0.762)
			(stroke
				(width 0.1524)
				(type default)
			)
			(layer "B.SilkS")
		)
		(fp_line
			(start -1.1049 0.724916)
			(end -1.1049 -0.724916)
			(stroke
				(width 0.1)
				(type default)
			)
			(layer "B.Fab")
		)
		(fp_line
			(start 1.1049 0.724916)
			(end -1.1049 0.724916)
			(stroke
				(width 0.1)
				(type default)
			)
			(layer "B.Fab")
		)
		(fp_line
			(start -1.1049 -0.724916)
			(end 1.1049 -0.724916)
			(stroke
				(width 0.1)
				(type default)
			)
			(layer "B.Fab")
		)
		(fp_line
			(start 1.1049 -0.724916)
			(end 1.1049 0.724916)
			(stroke
				(width 0.1)
				(type default)
			)
			(layer "B.Fab")
		)
		(pad "1" smd rect
			(at 0.889 0 270)
			(size 1.016 1.27)
			(layers "B.Cu" "B.Mask" "B.Paste")
			(net "PVCCIN_CPU1")
		)
		(pad "2" smd rect
			(at -0.889 0 270)
			(size 1.016 1.27)
			(layers "B.Cu" "B.Mask" "B.Paste")
			(net "GND")
		)
	)
	(footprint ""
		(layer "B.Cu")
		(at 498.693948 -153.16454 90)
		(property "Reference" "X28"
			(at 1.46177 2.60096 270)
			(unlocked yes)
			(layer "B.SilkS")
			(effects
				(font
					(size 0.7874 0.5842)
					(thickness 0.1524)
				)
				(justify left mirror)
			)
		)
		(property "Value" ""
			(at 0 0 90)
			(layer "B.Fab")
			(effects
				(font
					(size 1.27 1.27)
				)
				(justify mirror)
			)
		)
		(property "Device Type" "TP_TDR_4P_FTS_TH-TP_TDR_4P_DIPA"
			(at -1.30175 1.27 0)
			(unlocked yes)
			(layer "B.Fab")
			(hide yes)
			(effects
				(font
					(size 0.635 0.4064)
					(thickness 0.1524)
				)
				(justify mirror)
			)
		)
		(property "User Part Number" "N_A"
			(at -1.30175 1.27 0)
			(unlocked yes)
			(layer "Cmts.User")
			(hide yes)
			(effects
				(font
					(size 0.635 0.4064)
					(thickness 0.1524)
				)
				(justify mirror)
			)
		)
		(duplicate_pad_numbers_are_jumpers no)
		(fp_line
			(start 0 -1.27)
			(end 0 -0.635)
			(stroke
				(width 0.1524)
				(type default)
			)
			(layer "B.SilkS")
		)
		(fp_line
			(start -2.54 -1.27)
			(end 0 -1.27)
			(stroke
				(width 0.1524)
				(type default)
			)
			(layer "B.SilkS")
		)
		(fp_line
			(start -2.54 -1.1303)
			(end -2.54 -1.27)
			(stroke
				(width 0.1524)
				(type default)
			)
			(layer "B.SilkS")
		)
		(fp_line
			(start 0 0.635)
			(end 0 1.905)
			(stroke
				(width 0.1524)
				(type default)
			)
			(layer "B.SilkS")
		)
		(fp_line
			(start -2.54 1.4097)
			(end -2.54 1.1303)
			(stroke
				(width 0.1524)
				(type default)
			)
			(layer "B.SilkS")
		)
		(fp_line
			(start 0 3.175)
			(end 0 3.81)
			(stroke
				(width 0.1524)
				(type default)
			)
			(layer "B.SilkS")
		)
		(fp_line
			(start 0 3.81)
			(end -2.54 3.81)
			(stroke
				(width 0.1524)
				(type default)
			)
			(layer "B.SilkS")
		)
		(fp_line
			(start -2.54 3.81)
			(end -2.54 3.6703)
			(stroke
				(width 0.1524)
				(type default)
			)
			(layer "B.SilkS")
		)
		(fp_poly
			(pts
				(xy 2.790952 -0.930402) (xy 2.790952 0.593598) (xy 1.266952 -0.168402)
			)
			(stroke
				(width 0)
				(type default)
			)
			(fill yes)
			(layer "B.SilkS")
		)
		(fp_line
			(start 0 -1.27)
			(end 0 3.81)
			(stroke
				(width 0.1)
				(type default)
			)
			(layer "B.Fab")
		)
		(fp_line
			(start -2.54 -1.27)
			(end 0 -1.27)
			(stroke
				(width 0.1)
				(type default)
			)
			(layer "B.Fab")
		)
		(fp_line
			(start 0 3.81)
			(end -2.54 3.81)
			(stroke
				(width 0.1)
				(type default)
			)
			(layer "B.Fab")
		)
		(fp_line
			(start -2.54 3.81)
			(end -2.54 -1.27)
			(stroke
				(width 0.1)
				(type default)
			)
			(layer "B.Fab")
		)
		(fp_poly
			(pts
				(xy 0.761746 0) (xy 2.285746 -0.762) (xy 2.285746 0.762)
			)
			(stroke
				(width 0)
				(type default)
			)
			(fill yes)
			(layer "B.Fab")
		)
		(pad "1" thru_hole circle
			(at 0 0 270)
			(size 1.0033 1.0033)
			(drill 0.249936)
			(layers "*.Cu" "*.Mask")
			(remove_unused_layers no)
			(net "TDR_DIFF_85_IN6_DN")
			(clearance 0.10795)
			(padstack
				(mode front_inner_back)
				(layer "Inner"
					(shape circle)
					(size 0.8001 0.8001)
					(clearance 0.1524)
				)
				(layer "B.Cu"
					(shape circle)
					(size 1.0033 1.0033)
					(thermal_gap 0.10795)
					(clearance 0.10795)
				)
			)
		)
		(pad "2" thru_hole circle
			(at -2.54 0 270)
			(size 1.9939 1.9939)
			(drill 0.249936)
			(layers "*.Cu" "*.Mask")
			(remove_unused_layers no)
			(net "T1_GND")
			(clearance 0.10795)
			(padstack
				(mode front_inner_back)
				(layer "Inner"
					(shape circle)
					(size 0.8001 0.8001)
					(clearance 0.1524)
				)
				(layer "B.Cu"
					(shape circle)
					(size 1.9939 1.9939)
					(thermal_gap 0.10795)
					(clearance 0.10795)
				)
			)
		)
		(pad "3" thru_hole circle
			(at -2.54 2.54 270)
			(size 1.9939 1.9939)
			(drill 0.249936)
			(layers "*.Cu" "*.Mask")
			(remove_unused_layers no)
			(net "T1_GND")
			(clearance 0.10795)
			(padstack
				(mode front_inner_back)
				(layer "Inner"
					(shape circle)
					(size 0.8001 0.8001)
					(clearance 0.1524)
				)
				(layer "B.Cu"
					(shape circle)
					(size 1.9939 1.9939)
					(thermal_gap 0.10795)
					(clearance 0.10795)
				)
			)
		)
		(pad "4" thru_hole circle
			(at 0 2.54 270)
			(size 1.0033 1.0033)
			(drill 0.249936)
			(layers "*.Cu" "*.Mask")
			(remove_unused_layers no)
			(net "TDR_DIFF_85_IN6_DP")
			(clearance 0.10795)
			(padstack
				(mode front_inner_back)
				(layer "Inner"
					(shape circle)
					(size 0.8001 0.8001)
					(clearance 0.1524)
				)
				(layer "B.Cu"
					(shape circle)
					(size 1.0033 1.0033)
					(thermal_gap 0.10795)
					(clearance 0.10795)
				)
			)
		)
	)
	(footprint ""
		(layer "B.Cu")
		(at 174.29988 -123.916948 90)
		(property "Reference" "R3348"
			(at 0 0 90)
			(layer "B.SilkS")
			(hide yes)
			(effects
				(font
					(size 1.27 1.27)
				)
				(justify mirror)
			)
		)
		(property "Value" ""
			(at 0 0 90)
			(layer "B.Fab")
			(effects
				(font
					(size 1.27 1.27)
				)
				(justify mirror)
			)
		)
		(duplicate_pad_numbers_are_jumpers no)
		(fp_line
			(start 1.2954 -0.5842)
			(end -1.2954 -0.5842)
			(stroke
				(width 0.1524)
				(type default)
			)
			(layer "B.SilkS")
		)
		(fp_line
			(start -1.2954 -0.5842)
			(end -1.2954 0.5842)
			(stroke
				(width 0.1524)
				(type default)
			)
			(layer "B.SilkS")
		)
		(fp_line
			(start 1.2954 0.5842)
			(end 1.2954 -0.5842)
			(stroke
				(width 0.1524)
				(type default)
			)
			(layer "B.SilkS")
		)
		(fp_line
			(start -1.2954 0.5842)
			(end 1.2954 0.5842)
			(stroke
				(width 0.1524)
				(type default)
			)
			(layer "B.SilkS")
		)
		(fp_line
			(start 0.8636 -0.4572)
			(end -0.8636 -0.4572)
			(stroke
				(width 0.1)
				(type default)
			)
			(layer "B.Fab")
		)
		(fp_line
			(start -0.8636 -0.4572)
			(end -0.8636 -0.406654)
			(stroke
				(width 0.1)
				(type default)
			)
			(layer "B.Fab")
		)
		(fp_line
			(start 1.1938 -0.406654)
			(end 0.8636 -0.406654)
			(stroke
				(width 0.1)
				(type default)
			)
			(layer "B.Fab")
		)
		(fp_line
			(start 0.8636 -0.406654)
			(end 0.8636 -0.4572)
			(stroke
				(width 0.1)
				(type default)
			)
			(layer "B.Fab")
		)
		(fp_line
			(start -0.8636 -0.406654)
			(end -1.1938 -0.406654)
			(stroke
				(width 0.1)
				(type default)
			)
			(layer "B.Fab")
		)
		(fp_line
			(start -1.1938 -0.406654)
			(end -1.1938 0.4064)
			(stroke
				(width 0.1)
				(type default)
			)
			(layer "B.Fab")
		)
		(fp_line
			(start 1.1938 0.4064)
			(end 1.1938 -0.406654)
			(stroke
				(width 0.1)
				(type default)
			)
			(layer "B.Fab")
		)
		(fp_line
			(start 0.8636 0.4064)
			(end 1.1938 0.4064)
			(stroke
				(width 0.1)
				(type default)
			)
			(layer "B.Fab")
		)
		(fp_line
			(start -0.8636 0.4064)
			(end -0.8636 0.4572)
			(stroke
				(width 0.1)
				(type default)
			)
			(layer "B.Fab")
		)
		(fp_line
			(start -1.1938 0.4064)
			(end -0.8636 0.4064)
			(stroke
				(width 0.1)
				(type default)
			)
			(layer "B.Fab")
		)
		(fp_line
			(start 0.8636 0.4318)
			(end 0.8636 0.4064)
			(stroke
				(width 0.1)
				(type default)
			)
			(layer "B.Fab")
		)
		(fp_line
			(start 0.8636 0.4572)
			(end 0.8636 0.4318)
			(stroke
				(width 0.1)
				(type default)
			)
			(layer "B.Fab")
		)
		(fp_line
			(start -0.8636 0.4572)
			(end 0.8636 0.4572)
			(stroke
				(width 0.1)
				(type default)
			)
			(layer "B.Fab")
		)
		(pad "1" smd rect
			(at 0.7366 0)
			(size 0.7112 0.8128)
			(layers "B.Cu" "B.Mask" "B.Paste")
			(net "P3V3_AUX")
		)
		(pad "2" smd rect
			(at -0.7366 0)
			(size 0.7112 0.8128)
			(layers "B.Cu" "B.Mask" "B.Paste")
			(net "P3V3_AUX_FPGA_VCCIO1")
		)
	)
	(footprint ""
		(layer "B.Cu")
		(at 211.632546 -319.268856 180)
		(property "Reference" "C75"
			(at 0 0 0)
			(layer "B.SilkS")
			(hide yes)
			(effects
				(font
					(size 1.27 1.27)
				)
				(justify mirror)
			)
		)
		(property "Value" ""
			(at 0 0 0)
			(layer "B.Fab")
			(effects
				(font
					(size 1.27 1.27)
				)
				(justify mirror)
			)
		)
		(duplicate_pad_numbers_are_jumpers no)
		(fp_line
			(start 0.7874 0.4064)
			(end 0.7874 -0.4064)
			(stroke
				(width 0.1524)
				(type default)
			)
			(layer "B.SilkS")
		)
		(fp_line
			(start 0.7874 -0.4064)
			(end -0.7874 -0.4064)
			(stroke
				(width 0.1524)
				(type default)
			)
			(layer "B.SilkS")
		)
		(fp_line
			(start -0.7874 0.4064)
			(end 0.7874 0.4064)
			(stroke
				(width 0.1524)
				(type default)
			)
			(layer "B.SilkS")
		)
		(fp_line
			(start -0.7874 -0.4064)
			(end -0.7874 0.4064)
			(stroke
				(width 0.1524)
				(type default)
			)
			(layer "B.SilkS")
		)
		(fp_line
			(start 0.67945 0.3048)
			(end 0.67945 -0.305054)
			(stroke
				(width 0.1)
				(type default)
			)
			(layer "B.Fab")
		)
		(fp_line
			(start 0.67945 -0.305054)
			(end 0.12065 -0.305054)
			(stroke
				(width 0.1)
				(type default)
			)
			(layer "B.Fab")
		)
		(fp_line
			(start 0.12065 0.3048)
			(end 0.67945 0.3048)
			(stroke
				(width 0.1)
				(type default)
			)
			(layer "B.Fab")
		)
		(fp_line
			(start 0.12065 0.2794)
			(end 0.12065 0.3048)
			(stroke
				(width 0.1)
				(type default)
			)
			(layer "B.Fab")
		)
		(fp_line
			(start 0.12065 -0.2794)
			(end -0.12065 -0.2794)
			(stroke
				(width 0.1)
				(type default)
			)
			(layer "B.Fab")
		)
		(fp_line
			(start 0.12065 -0.305054)
			(end 0.12065 -0.2794)
			(stroke
				(width 0.1)
				(type default)
			)
			(layer "B.Fab")
		)
		(fp_line
			(start -0.120396 0.3048)
			(end -0.120396 0.2794)
			(stroke
				(width 0.1)
				(type default)
			)
			(layer "B.Fab")
		)
		(fp_line
			(start -0.120396 0.2794)
			(end 0.12065 0.2794)
			(stroke
				(width 0.1)
				(type default)
			)
			(layer "B.Fab")
		)
		(fp_line
			(start -0.12065 -0.2794)
			(end -0.12065 -0.3048)
			(stroke
				(width 0.1)
				(type default)
			)
			(layer "B.Fab")
		)
		(fp_line
			(start -0.12065 -0.3048)
			(end -0.67945 -0.3048)
			(stroke
				(width 0.1)
				(type default)
			)
			(layer "B.Fab")
		)
		(fp_line
			(start -0.67945 0.3048)
			(end -0.120396 0.3048)
			(stroke
				(width 0.1)
				(type default)
			)
			(layer "B.Fab")
		)
		(fp_line
			(start -0.67945 -0.3048)
			(end -0.67945 0.3048)
			(stroke
				(width 0.1)
				(type default)
			)
			(layer "B.Fab")
		)
		(pad "1" smd circle
			(at 0.40005 0)
			(size 0 0)
			(layers "B.Cu" "B.Mask" "B.Paste")
			(net "P3V3_AUX")
		)
		(pad "2" smd circle
			(at -0.40005 0)
			(size 0 0)
			(layers "B.Cu" "B.Mask" "B.Paste")
			(net "GND")
		)
	)
	(footprint ""
		(layer "B.Cu")
		(at 357.368602 -356.50043 -90)
		(property "Reference" "PR4218"
			(at 0 0 90)
			(layer "B.SilkS")
			(hide yes)
			(effects
				(font
					(size 1.27 1.27)
				)
				(justify mirror)
			)
		)
		(property "Value" ""
			(at 0 0 90)
			(layer "B.Fab")
			(effects
				(font
					(size 1.27 1.27)
				)
				(justify mirror)
			)
		)
		(duplicate_pad_numbers_are_jumpers no)
		(fp_line
			(start -0.7874 0.4064)
			(end 0.7874 0.4064)
			(stroke
				(width 0.1524)
				(type default)
			)
			(layer "B.SilkS")
		)
		(fp_line
			(start 0.7874 0.4064)
			(end 0.7874 -0.4064)
			(stroke
				(width 0.1524)
				(type default)
			)
			(layer "B.SilkS")
		)
		(fp_line
			(start -0.7874 -0.4064)
			(end -0.7874 0.4064)
			(stroke
				(width 0.1524)
				(type default)
			)
			(layer "B.SilkS")
		)
		(fp_line
			(start 0.7874 -0.4064)
			(end -0.7874 -0.4064)
			(stroke
				(width 0.1524)
				(type default)
			)
			(layer "B.SilkS")
		)
		(fp_line
			(start -0.67945 0.3048)
			(end -0.120396 0.3048)
			(stroke
				(width 0.1)
				(type default)
			)
			(layer "B.Fab")
		)
		(fp_line
			(start -0.120396 0.3048)
			(end -0.120396 0.2794)
			(stroke
				(width 0.1)
				(type default)
			)
			(layer "B.Fab")
		)
		(fp_line
			(start 0.12065 0.3048)
			(end 0.67945 0.3048)
			(stroke
				(width 0.1)
				(type default)
			)
			(layer "B.Fab")
		)
		(fp_line
			(start 0.67945 0.3048)
			(end 0.67945 -0.305054)
			(stroke
				(width 0.1)
				(type default)
			)
			(layer "B.Fab")
		)
		(fp_line
			(start -0.120396 0.2794)
			(end 0.12065 0.2794)
			(stroke
				(width 0.1)
				(type default)
			)
			(layer "B.Fab")
		)
		(fp_line
			(start 0.12065 0.2794)
			(end 0.12065 0.3048)
			(stroke
				(width 0.1)
				(type default)
			)
			(layer "B.Fab")
		)
		(fp_line
			(start -0.12065 -0.2794)
			(end -0.12065 -0.3048)
			(stroke
				(width 0.1)
				(type default)
			)
			(layer "B.Fab")
		)
		(fp_line
			(start 0.12065 -0.2794)
			(end -0.12065 -0.2794)
			(stroke
				(width 0.1)
				(type default)
			)
			(layer "B.Fab")
		)
		(fp_line
			(start -0.67945 -0.3048)
			(end -0.67945 0.3048)
			(stroke
				(width 0.1)
				(type default)
			)
			(layer "B.Fab")
		)
		(fp_line
			(start -0.12065 -0.3048)
			(end -0.67945 -0.3048)
			(stroke
				(width 0.1)
				(type default)
			)
			(layer "B.Fab")
		)
		(fp_line
			(start 0.12065 -0.305054)
			(end 0.12065 -0.2794)
			(stroke
				(width 0.1)
				(type default)
			)
			(layer "B.Fab")
		)
		(fp_line
			(start 0.67945 -0.305054)
			(end 0.12065 -0.305054)
			(stroke
				(width 0.1)
				(type default)
			)
			(layer "B.Fab")
		)
		(pad "1" smd circle
			(at 0.40005 0 90)
			(size 0 0)
			(layers "B.Cu" "B.Mask" "B.Paste")
			(net "PVCCFA_EHV_FIVRA_CPU0_IMON3")
		)
		(pad "2" smd circle
			(at -0.40005 0 90)
			(size 0 0)
			(layers "B.Cu" "B.Mask" "B.Paste")
			(net "GND")
		)
	)
	(footprint ""
		(layer "B.Cu")
		(at 181.755542 -112.175544)
		(property "Reference" "C1142"
			(at 0 0 0)
			(layer "B.SilkS")
			(hide yes)
			(effects
				(font
					(size 1.27 1.27)
				)
				(justify mirror)
			)
		)
		(property "Value" ""
			(at 0 0 0)
			(layer "B.Fab")
			(effects
				(font
					(size 1.27 1.27)
				)
				(justify mirror)
			)
		)
		(duplicate_pad_numbers_are_jumpers no)
		(fp_line
			(start -0.69215 -0.2921)
			(end -0.69215 0.2921)
			(stroke
				(width 0.1524)
				(type default)
			)
			(layer "B.SilkS")
		)
		(fp_line
			(start -0.69215 0.2921)
			(end 0.69215 0.2921)
			(stroke
				(width 0.1524)
				(type default)
			)
			(layer "B.SilkS")
		)
		(fp_line
			(start 0.69215 -0.2921)
			(end -0.69215 -0.2921)
			(stroke
				(width 0.1524)
				(type default)
			)
			(layer "B.SilkS")
		)
		(fp_line
			(start 0.69215 0.2921)
			(end 0.69215 -0.2921)
			(stroke
				(width 0.1524)
				(type default)
			)
			(layer "B.SilkS")
		)
		(fp_line
			(start -0.51435 -0.2794)
			(end -0.51435 0.2794)
			(stroke
				(width 0.1)
				(type default)
			)
			(layer "B.Fab")
		)
		(fp_line
			(start -0.51435 0.2794)
			(end 0.51435 0.2794)
			(stroke
				(width 0.1)
				(type default)
			)
			(layer "B.Fab")
		)
		(fp_line
			(start 0.51435 -0.2794)
			(end -0.51435 -0.2794)
			(stroke
				(width 0.1)
				(type default)
			)
			(layer "B.Fab")
		)
		(fp_line
			(start 0.51435 0.2794)
			(end 0.51435 -0.2794)
			(stroke
				(width 0.1)
				(type default)
			)
			(layer "B.Fab")
		)
		(pad "1" smd circle
			(at 0.40005 0 180)
			(size 0 0)
			(layers "B.Cu" "B.Mask" "B.Paste")
			(net "P3V3_AUX_FPGA_VCCIO2")
		)
		(pad "2" smd circle
			(at -0.40005 0 180)
			(size 0 0)
			(layers "B.Cu" "B.Mask" "B.Paste")
			(net "GND")
		)
		(zone
			(layer "B.Cu")
			(hatch none 0.5)
			(connect_pads
				(clearance 0)
			)
			(min_thickness 0.25)
			(keepout
				(tracks not_allowed)
				(vias allowed)
				(pads allowed)
				(copperpour not_allowed)
				(footprints allowed)
			)
			(placement
				(enabled no)
				(sheetname "")
			)
			(fill
				(thermal_gap 0.5)
				(thermal_bridge_width 0.5)
				(island_removal_mode 0)
			)
			(polygon
				(pts
					(xy 181.946042 -112.087914) (xy 181.854602 -112.029748) (xy 181.655212 -112.029748) (xy 181.565042 -112.087914)
					(xy 181.565042 -112.263174) (xy 181.655212 -112.321594) (xy 181.854602 -112.321594) (xy 181.946042 -112.263428)
				)
			)
		)
	)
	(footprint ""
		(layer "B.Cu")
		(at 119.07266 -334.693514 -90)
		(property "Reference" "PR299"
			(at 0 0 90)
			(layer "B.SilkS")
			(hide yes)
			(effects
				(font
					(size 1.27 1.27)
				)
				(justify mirror)
			)
		)
		(property "Value" ""
			(at 0 0 90)
			(layer "B.Fab")
			(effects
				(font
					(size 1.27 1.27)
				)
				(justify mirror)
			)
		)
		(duplicate_pad_numbers_are_jumpers no)
		(fp_line
			(start -0.7874 0.4064)
			(end 0.7874 0.4064)
			(stroke
				(width 0.1524)
				(type default)
			)
			(layer "B.SilkS")
		)
		(fp_line
			(start 0.7874 0.4064)
			(end 0.7874 -0.4064)
			(stroke
				(width 0.1524)
				(type default)
			)
			(layer "B.SilkS")
		)
		(fp_line
			(start -0.7874 -0.4064)
			(end -0.7874 0.4064)
			(stroke
				(width 0.1524)
				(type default)
			)
			(layer "B.SilkS")
		)
		(fp_line
			(start 0.7874 -0.4064)
			(end -0.7874 -0.4064)
			(stroke
				(width 0.1524)
				(type default)
			)
			(layer "B.SilkS")
		)
		(fp_line
			(start -0.67945 0.3048)
			(end -0.120396 0.3048)
			(stroke
				(width 0.1)
				(type default)
			)
			(layer "B.Fab")
		)
		(fp_line
			(start -0.120396 0.3048)
			(end -0.120396 0.2794)
			(stroke
				(width 0.1)
				(type default)
			)
			(layer "B.Fab")
		)
		(fp_line
			(start 0.12065 0.3048)
			(end 0.67945 0.3048)
			(stroke
				(width 0.1)
				(type default)
			)
			(layer "B.Fab")
		)
		(fp_line
			(start 0.67945 0.3048)
			(end 0.67945 -0.305054)
			(stroke
				(width 0.1)
				(type default)
			)
			(layer "B.Fab")
		)
		(fp_line
			(start -0.120396 0.2794)
			(end 0.12065 0.2794)
			(stroke
				(width 0.1)
				(type default)
			)
			(layer "B.Fab")
		)
		(fp_line
			(start 0.12065 0.2794)
			(end 0.12065 0.3048)
			(stroke
				(width 0.1)
				(type default)
			)
			(layer "B.Fab")
		)
		(fp_line
			(start -0.12065 -0.2794)
			(end -0.12065 -0.3048)
			(stroke
				(width 0.1)
				(type default)
			)
			(layer "B.Fab")
		)
		(fp_line
			(start 0.12065 -0.2794)
			(end -0.12065 -0.2794)
			(stroke
				(width 0.1)
				(type default)
			)
			(layer "B.Fab")
		)
		(fp_line
			(start -0.67945 -0.3048)
			(end -0.67945 0.3048)
			(stroke
				(width 0.1)
				(type default)
			)
			(layer "B.Fab")
		)
		(fp_line
			(start -0.12065 -0.3048)
			(end -0.67945 -0.3048)
			(stroke
				(width 0.1)
				(type default)
			)
			(layer "B.Fab")
		)
		(fp_line
			(start 0.12065 -0.305054)
			(end 0.12065 -0.2794)
			(stroke
				(width 0.1)
				(type default)
			)
			(layer "B.Fab")
		)
		(fp_line
			(start 0.67945 -0.305054)
			(end 0.12065 -0.305054)
			(stroke
				(width 0.1)
				(type default)
			)
			(layer "B.Fab")
		)
		(pad "1" smd circle
			(at 0.40005 0 90)
			(size 0 0)
			(layers "B.Cu" "B.Mask" "B.Paste")
			(net "PVCCIN_CPU1_PVCC")
		)
		(pad "2" smd circle
			(at -0.40005 0 90)
			(size 0 0)
			(layers "B.Cu" "B.Mask" "B.Paste")
			(net "PVCCIN_CPU1_VDD4")
		)
	)
	(footprint ""
		(layer "B.Cu")
		(at 422.50487 -353.25939 -90)
		(property "Reference" "PC1187_P0_3"
			(at 0 0 90)
			(layer "B.SilkS")
			(hide yes)
			(effects
				(font
					(size 1.27 1.27)
				)
				(justify mirror)
			)
		)
		(property "Value" ""
			(at 0 0 90)
			(layer "B.Fab")
			(effects
				(font
					(size 1.27 1.27)
				)
				(justify mirror)
			)
		)
		(duplicate_pad_numbers_are_jumpers no)
		(fp_line
			(start -1.524 0.762)
			(end 1.524 0.762)
			(stroke
				(width 0.1524)
				(type default)
			)
			(layer "B.SilkS")
		)
		(fp_line
			(start 1.524 0.762)
			(end 1.524 -0.762)
			(stroke
				(width 0.1524)
				(type default)
			)
			(layer "B.SilkS")
		)
		(fp_line
			(start -1.524 -0.762)
			(end -1.524 0.762)
			(stroke
				(width 0.1524)
				(type default)
			)
			(layer "B.SilkS")
		)
		(fp_line
			(start 1.524 -0.762)
			(end -1.524 -0.762)
			(stroke
				(width 0.1524)
				(type default)
			)
			(layer "B.SilkS")
		)
		(fp_line
			(start -1.1049 0.724916)
			(end -1.1049 -0.724916)
			(stroke
				(width 0.1)
				(type default)
			)
			(layer "B.Fab")
		)
		(fp_line
			(start 1.1049 0.724916)
			(end -1.1049 0.724916)
			(stroke
				(width 0.1)
				(type default)
			)
			(layer "B.Fab")
		)
		(fp_line
			(start -1.1049 -0.724916)
			(end 1.1049 -0.724916)
			(stroke
				(width 0.1)
				(type default)
			)
			(layer "B.Fab")
		)
		(fp_line
			(start 1.1049 -0.724916)
			(end 1.1049 0.724916)
			(stroke
				(width 0.1)
				(type default)
			)
			(layer "B.Fab")
		)
		(pad "1" smd rect
			(at 0.889 0 270)
			(size 1.016 1.27)
			(layers "B.Cu" "B.Mask" "B.Paste")
			(net "PVCCFA_EHV_FIVRA_CPU0")
		)
		(pad "2" smd rect
			(at -0.889 0 270)
			(size 1.016 1.27)
			(layers "B.Cu" "B.Mask" "B.Paste")
			(net "GND")
		)
	)
	(footprint ""
		(layer "B.Cu")
		(at 328.142092 -66.244724 45)
		(property "Reference" "C1260"
			(at 0 0 45)
			(layer "B.SilkS")
			(hide yes)
			(effects
				(font
					(size 1.27 1.27)
				)
				(justify mirror)
			)
		)
		(property "Value" ""
			(at 0 0 45)
			(layer "B.Fab")
			(effects
				(font
					(size 1.27 1.27)
				)
				(justify mirror)
			)
		)
		(duplicate_pad_numbers_are_jumpers no)
		(fp_line
			(start -1.295492 -0.584255)
			(end -1.295492 0.584255)
			(stroke
				(width 0.1524)
				(type default)
			)
			(layer "B.SilkS")
		)
		(fp_line
			(start -1.295492 0.584255)
			(end 1.295492 0.584255)
			(stroke
				(width 0.1524)
				(type default)
			)
			(layer "B.SilkS")
		)
		(fp_line
			(start 0 -0.584076)
			(end 0 0.584076)
			(stroke
				(width 0.1524)
				(type default)
			)
			(layer "B.SilkS")
		)
		(fp_line
			(start 1.295492 -0.584255)
			(end -1.295492 -0.584255)
			(stroke
				(width 0.1524)
				(type default)
			)
			(layer "B.SilkS")
		)
		(fp_line
			(start 1.295492 0.584255)
			(end 1.295492 -0.584255)
			(stroke
				(width 0.1524)
				(type default)
			)
			(layer "B.SilkS")
		)
		(fp_line
			(start -1.193835 -0.406446)
			(end -1.193835 0.406446)
			(stroke
				(width 0.1)
				(type default)
			)
			(layer "B.Fab")
		)
		(fp_line
			(start -0.863541 -0.457275)
			(end -0.863721 -0.406446)
			(stroke
				(width 0.1)
				(type default)
			)
			(layer "B.Fab")
		)
		(fp_line
			(start -0.863721 -0.406446)
			(end -1.193835 -0.406446)
			(stroke
				(width 0.1)
				(type default)
			)
			(layer "B.Fab")
		)
		(fp_line
			(start -1.193835 0.406446)
			(end -0.863721 0.406446)
			(stroke
				(width 0.1)
				(type default)
			)
			(layer "B.Fab")
		)
		(fp_line
			(start -0.863721 0.406446)
			(end -0.863541 0.457275)
			(stroke
				(width 0.1)
				(type default)
			)
			(layer "B.Fab")
		)
		(fp_line
			(start -0.863541 0.457275)
			(end 0.863541 0.457275)
			(stroke
				(width 0.1)
				(type default)
			)
			(layer "B.Fab")
		)
		(fp_line
			(start 0.863541 -0.457275)
			(end -0.863541 -0.457275)
			(stroke
				(width 0.1)
				(type default)
			)
			(layer "B.Fab")
		)
		(fp_line
			(start 0.863721 -0.406446)
			(end 0.863541 -0.457275)
			(stroke
				(width 0.1)
				(type default)
			)
			(layer "B.Fab")
		)
		(fp_line
			(start 1.193835 -0.406446)
			(end 0.863721 -0.406446)
			(stroke
				(width 0.1)
				(type default)
			)
			(layer "B.Fab")
		)
		(fp_line
			(start 0.863721 0.406446)
			(end 1.193835 0.406446)
			(stroke
				(width 0.1)
				(type default)
			)
			(layer "B.Fab")
		)
		(fp_line
			(start 0.863541 0.457275)
			(end 0.863721 0.406446)
			(stroke
				(width 0.1)
				(type default)
			)
			(layer "B.Fab")
		)
		(fp_line
			(start 1.193835 0.406446)
			(end 1.193835 -0.406446)
			(stroke
				(width 0.1)
				(type default)
			)
			(layer "B.Fab")
		)
		(pad "1" smd rect
			(at 0.7366 0 315)
			(size 0.7112 0.8128)
			(layers "B.Cu" "B.Mask" "B.Paste")
			(net "P1V05_PCH_PLL_AUX")
		)
		(pad "2" smd rect
			(at -0.7366 0 315)
			(size 0.7112 0.8128)
			(layers "B.Cu" "B.Mask" "B.Paste")
			(net "GND")
		)
	)
	(footprint ""
		(layer "B.Cu")
		(at 448.186556 -318.908176 90)
		(property "Reference" "R889"
			(at 0 0 90)
			(layer "B.SilkS")
			(hide yes)
			(effects
				(font
					(size 1.27 1.27)
				)
				(justify mirror)
			)
		)
		(property "Value" ""
			(at 0 0 90)
			(layer "B.Fab")
			(effects
				(font
					(size 1.27 1.27)
				)
				(justify mirror)
			)
		)
		(duplicate_pad_numbers_are_jumpers no)
		(fp_line
			(start 0.7874 -0.4064)
			(end -0.7874 -0.4064)
			(stroke
				(width 0.1524)
				(type default)
			)
			(layer "B.SilkS")
		)
		(fp_line
			(start -0.7874 -0.4064)
			(end -0.7874 0.4064)
			(stroke
				(width 0.1524)
				(type default)
			)
			(layer "B.SilkS")
		)
		(fp_line
			(start 0.7874 0.4064)
			(end 0.7874 -0.4064)
			(stroke
				(width 0.1524)
				(type default)
			)
			(layer "B.SilkS")
		)
		(fp_line
			(start -0.7874 0.4064)
			(end 0.7874 0.4064)
			(stroke
				(width 0.1524)
				(type default)
			)
			(layer "B.SilkS")
		)
		(fp_line
			(start 0.67945 -0.305054)
			(end 0.12065 -0.305054)
			(stroke
				(width 0.1)
				(type default)
			)
			(layer "B.Fab")
		)
		(fp_line
			(start 0.12065 -0.305054)
			(end 0.12065 -0.2794)
			(stroke
				(width 0.1)
				(type default)
			)
			(layer "B.Fab")
		)
		(fp_line
			(start -0.12065 -0.3048)
			(end -0.67945 -0.3048)
			(stroke
				(width 0.1)
				(type default)
			)
			(layer "B.Fab")
		)
		(fp_line
			(start -0.67945 -0.3048)
			(end -0.67945 0.3048)
			(stroke
				(width 0.1)
				(type default)
			)
			(layer "B.Fab")
		)
		(fp_line
			(start 0.12065 -0.2794)
			(end -0.12065 -0.2794)
			(stroke
				(width 0.1)
				(type default)
			)
			(layer "B.Fab")
		)
		(fp_line
			(start -0.12065 -0.2794)
			(end -0.12065 -0.3048)
			(stroke
				(width 0.1)
				(type default)
			)
			(layer "B.Fab")
		)
		(fp_line
			(start 0.12065 0.2794)
			(end 0.12065 0.3048)
			(stroke
				(width 0.1)
				(type default)
			)
			(layer "B.Fab")
		)
		(fp_line
			(start -0.120396 0.2794)
			(end 0.12065 0.2794)
			(stroke
				(width 0.1)
				(type default)
			)
			(layer "B.Fab")
		)
		(fp_line
			(start 0.67945 0.3048)
			(end 0.67945 -0.305054)
			(stroke
				(width 0.1)
				(type default)
			)
			(layer "B.Fab")
		)
		(fp_line
			(start 0.12065 0.3048)
			(end 0.67945 0.3048)
			(stroke
				(width 0.1)
				(type default)
			)
			(layer "B.Fab")
		)
		(fp_line
			(start -0.120396 0.3048)
			(end -0.120396 0.2794)
			(stroke
				(width 0.1)
				(type default)
			)
			(layer "B.Fab")
		)
		(fp_line
			(start -0.67945 0.3048)
			(end -0.120396 0.3048)
			(stroke
				(width 0.1)
				(type default)
			)
			(layer "B.Fab")
		)
		(pad "1" smd circle
			(at 0.40005 0 270)
			(size 0 0)
			(layers "B.Cu" "B.Mask" "B.Paste")
			(net "PWRGD_CHG_CPU0_DIMM1")
		)
		(pad "2" smd circle
			(at -0.40005 0 270)
			(size 0 0)
			(layers "B.Cu" "B.Mask" "B.Paste")
			(net "PWRGD_FAIL_CPU0_GH")
		)
	)
	(footprint ""
		(layer "B.Cu")
		(at 337.31708 -45.141134 -90)
		(property "Reference" "C1242"
			(at 0 0 90)
			(layer "B.SilkS")
			(hide yes)
			(effects
				(font
					(size 1.27 1.27)
				)
				(justify mirror)
			)
		)
		(property "Value" ""
			(at 0 0 90)
			(layer "B.Fab")
			(effects
				(font
					(size 1.27 1.27)
				)
				(justify mirror)
			)
		)
		(duplicate_pad_numbers_are_jumpers no)
		(fp_line
			(start -0.7874 0.4064)
			(end 0.7874 0.4064)
			(stroke
				(width 0.1524)
				(type default)
			)
			(layer "B.SilkS")
		)
		(fp_line
			(start 0.7874 0.4064)
			(end 0.7874 -0.4064)
			(stroke
				(width 0.1524)
				(type default)
			)
			(layer "B.SilkS")
		)
		(fp_line
			(start -0.7874 -0.4064)
			(end -0.7874 0.4064)
			(stroke
				(width 0.1524)
				(type default)
			)
			(layer "B.SilkS")
		)
		(fp_line
			(start 0.7874 -0.4064)
			(end -0.7874 -0.4064)
			(stroke
				(width 0.1524)
				(type default)
			)
			(layer "B.SilkS")
		)
		(fp_line
			(start -0.67945 0.3048)
			(end -0.120396 0.3048)
			(stroke
				(width 0.1)
				(type default)
			)
			(layer "B.Fab")
		)
		(fp_line
			(start -0.120396 0.3048)
			(end -0.120396 0.2794)
			(stroke
				(width 0.1)
				(type default)
			)
			(layer "B.Fab")
		)
		(fp_line
			(start 0.12065 0.3048)
			(end 0.67945 0.3048)
			(stroke
				(width 0.1)
				(type default)
			)
			(layer "B.Fab")
		)
		(fp_line
			(start 0.67945 0.3048)
			(end 0.67945 -0.305054)
			(stroke
				(width 0.1)
				(type default)
			)
			(layer "B.Fab")
		)
		(fp_line
			(start -0.120396 0.2794)
			(end 0.12065 0.2794)
			(stroke
				(width 0.1)
				(type default)
			)
			(layer "B.Fab")
		)
		(fp_line
			(start 0.12065 0.2794)
			(end 0.12065 0.3048)
			(stroke
				(width 0.1)
				(type default)
			)
			(layer "B.Fab")
		)
		(fp_line
			(start -0.12065 -0.2794)
			(end -0.12065 -0.3048)
			(stroke
				(width 0.1)
				(type default)
			)
			(layer "B.Fab")
		)
		(fp_line
			(start 0.12065 -0.2794)
			(end -0.12065 -0.2794)
			(stroke
				(width 0.1)
				(type default)
			)
			(layer "B.Fab")
		)
		(fp_line
			(start -0.67945 -0.3048)
			(end -0.67945 0.3048)
			(stroke
				(width 0.1)
				(type default)
			)
			(layer "B.Fab")
		)
		(fp_line
			(start -0.12065 -0.3048)
			(end -0.67945 -0.3048)
			(stroke
				(width 0.1)
				(type default)
			)
			(layer "B.Fab")
		)
		(fp_line
			(start 0.12065 -0.305054)
			(end 0.12065 -0.2794)
			(stroke
				(width 0.1)
				(type default)
			)
			(layer "B.Fab")
		)
		(fp_line
			(start 0.67945 -0.305054)
			(end 0.12065 -0.305054)
			(stroke
				(width 0.1)
				(type default)
			)
			(layer "B.Fab")
		)
		(pad "1" smd circle
			(at 0.40005 0 90)
			(size 0 0)
			(layers "B.Cu" "B.Mask" "B.Paste")
			(net "P1V05_PCH_AUX")
		)
		(pad "2" smd circle
			(at -0.40005 0 90)
			(size 0 0)
			(layers "B.Cu" "B.Mask" "B.Paste")
			(net "GND")
		)
	)
	(footprint ""
		(layer "B.Cu")
		(at 281.100784 -193.669666 -90)
		(property "Reference" "R254"
			(at 0 0 90)
			(layer "B.SilkS")
			(hide yes)
			(effects
				(font
					(size 1.27 1.27)
				)
				(justify mirror)
			)
		)
		(property "Value" ""
			(at 0 0 90)
			(layer "B.Fab")
			(effects
				(font
					(size 1.27 1.27)
				)
				(justify mirror)
			)
		)
		(duplicate_pad_numbers_are_jumpers no)
		(fp_line
			(start -0.7874 0.4064)
			(end 0.7874 0.4064)
			(stroke
				(width 0.1524)
				(type default)
			)
			(layer "B.SilkS")
		)
		(fp_line
			(start 0.7874 0.4064)
			(end 0.7874 -0.4064)
			(stroke
				(width 0.1524)
				(type default)
			)
			(layer "B.SilkS")
		)
		(fp_line
			(start -0.7874 -0.4064)
			(end -0.7874 0.4064)
			(stroke
				(width 0.1524)
				(type default)
			)
			(layer "B.SilkS")
		)
		(fp_line
			(start 0.7874 -0.4064)
			(end -0.7874 -0.4064)
			(stroke
				(width 0.1524)
				(type default)
			)
			(layer "B.SilkS")
		)
		(fp_line
			(start -0.67945 0.3048)
			(end -0.120396 0.3048)
			(stroke
				(width 0.1)
				(type default)
			)
			(layer "B.Fab")
		)
		(fp_line
			(start -0.120396 0.3048)
			(end -0.120396 0.2794)
			(stroke
				(width 0.1)
				(type default)
			)
			(layer "B.Fab")
		)
		(fp_line
			(start 0.12065 0.3048)
			(end 0.67945 0.3048)
			(stroke
				(width 0.1)
				(type default)
			)
			(layer "B.Fab")
		)
		(fp_line
			(start 0.67945 0.3048)
			(end 0.67945 -0.305054)
			(stroke
				(width 0.1)
				(type default)
			)
			(layer "B.Fab")
		)
		(fp_line
			(start -0.120396 0.2794)
			(end 0.12065 0.2794)
			(stroke
				(width 0.1)
				(type default)
			)
			(layer "B.Fab")
		)
		(fp_line
			(start 0.12065 0.2794)
			(end 0.12065 0.3048)
			(stroke
				(width 0.1)
				(type default)
			)
			(layer "B.Fab")
		)
		(fp_line
			(start -0.12065 -0.2794)
			(end -0.12065 -0.3048)
			(stroke
				(width 0.1)
				(type default)
			)
			(layer "B.Fab")
		)
		(fp_line
			(start 0.12065 -0.2794)
			(end -0.12065 -0.2794)
			(stroke
				(width 0.1)
				(type default)
			)
			(layer "B.Fab")
		)
		(fp_line
			(start -0.67945 -0.3048)
			(end -0.67945 0.3048)
			(stroke
				(width 0.1)
				(type default)
			)
			(layer "B.Fab")
		)
		(fp_line
			(start -0.12065 -0.3048)
			(end -0.67945 -0.3048)
			(stroke
				(width 0.1)
				(type default)
			)
			(layer "B.Fab")
		)
		(fp_line
			(start 0.12065 -0.305054)
			(end 0.12065 -0.2794)
			(stroke
				(width 0.1)
				(type default)
			)
			(layer "B.Fab")
		)
		(fp_line
			(start 0.67945 -0.305054)
			(end 0.12065 -0.305054)
			(stroke
				(width 0.1)
				(type default)
			)
			(layer "B.Fab")
		)
		(pad "1" smd circle
			(at 0.40005 0 90)
			(size 0 0)
			(layers "B.Cu" "B.Mask" "B.Paste")
			(net "PVNN_TERM_CPU0")
		)
		(pad "2" smd circle
			(at -0.40005 0 90)
			(size 0 0)
			(layers "B.Cu" "B.Mask" "B.Paste")
			(net "FM_S3M_CPU0_LVC1_GPIO_3")
		)
	)
	(footprint ""
		(layer "B.Cu")
		(at 100.306886 -358.899714 180)
		(property "Reference" "R2552"
			(at 0 0 0)
			(layer "B.SilkS")
			(hide yes)
			(effects
				(font
					(size 1.27 1.27)
				)
				(justify mirror)
			)
		)
		(property "Value" ""
			(at 0 0 0)
			(layer "B.Fab")
			(effects
				(font
					(size 1.27 1.27)
				)
				(justify mirror)
			)
		)
		(duplicate_pad_numbers_are_jumpers no)
		(fp_line
			(start 0.7874 0.4064)
			(end 0.7874 -0.4064)
			(stroke
				(width 0.1524)
				(type default)
			)
			(layer "B.SilkS")
		)
		(fp_line
			(start 0.7874 -0.4064)
			(end -0.7874 -0.4064)
			(stroke
				(width 0.1524)
				(type default)
			)
			(layer "B.SilkS")
		)
		(fp_line
			(start -0.7874 0.4064)
			(end 0.7874 0.4064)
			(stroke
				(width 0.1524)
				(type default)
			)
			(layer "B.SilkS")
		)
		(fp_line
			(start -0.7874 -0.4064)
			(end -0.7874 0.4064)
			(stroke
				(width 0.1524)
				(type default)
			)
			(layer "B.SilkS")
		)
		(fp_line
			(start 0.67945 0.3048)
			(end 0.67945 -0.305054)
			(stroke
				(width 0.1)
				(type default)
			)
			(layer "B.Fab")
		)
		(fp_line
			(start 0.67945 -0.305054)
			(end 0.12065 -0.305054)
			(stroke
				(width 0.1)
				(type default)
			)
			(layer "B.Fab")
		)
		(fp_line
			(start 0.12065 0.3048)
			(end 0.67945 0.3048)
			(stroke
				(width 0.1)
				(type default)
			)
			(layer "B.Fab")
		)
		(fp_line
			(start 0.12065 0.2794)
			(end 0.12065 0.3048)
			(stroke
				(width 0.1)
				(type default)
			)
			(layer "B.Fab")
		)
		(fp_line
			(start 0.12065 -0.2794)
			(end -0.12065 -0.2794)
			(stroke
				(width 0.1)
				(type default)
			)
			(layer "B.Fab")
		)
		(fp_line
			(start 0.12065 -0.305054)
			(end 0.12065 -0.2794)
			(stroke
				(width 0.1)
				(type default)
			)
			(layer "B.Fab")
		)
		(fp_line
			(start -0.120396 0.3048)
			(end -0.120396 0.2794)
			(stroke
				(width 0.1)
				(type default)
			)
			(layer "B.Fab")
		)
		(fp_line
			(start -0.120396 0.2794)
			(end 0.12065 0.2794)
			(stroke
				(width 0.1)
				(type default)
			)
			(layer "B.Fab")
		)
		(fp_line
			(start -0.12065 -0.2794)
			(end -0.12065 -0.3048)
			(stroke
				(width 0.1)
				(type default)
			)
			(layer "B.Fab")
		)
		(fp_line
			(start -0.12065 -0.3048)
			(end -0.67945 -0.3048)
			(stroke
				(width 0.1)
				(type default)
			)
			(layer "B.Fab")
		)
		(fp_line
			(start -0.67945 0.3048)
			(end -0.120396 0.3048)
			(stroke
				(width 0.1)
				(type default)
			)
			(layer "B.Fab")
		)
		(fp_line
			(start -0.67945 -0.3048)
			(end -0.67945 0.3048)
			(stroke
				(width 0.1)
				(type default)
			)
			(layer "B.Fab")
		)
		(pad "1" smd circle
			(at 0.40005 0)
			(size 0 0)
			(layers "B.Cu" "B.Mask" "B.Paste")
			(net "PWRGD_PVCCFA_EHV_FIVRA_CPU1")
		)
		(pad "2" smd circle
			(at -0.40005 0)
			(size 0 0)
			(layers "B.Cu" "B.Mask" "B.Paste")
			(net "PWRGD_PVCCFA_EHV_FIVRA_CPU1_R")
		)
	)
	(footprint ""
		(layer "B.Cu")
		(at 311.84088 -55.336948)
		(property "Reference" "R4104"
			(at 0 0 0)
			(layer "B.SilkS")
			(hide yes)
			(effects
				(font
					(size 1.27 1.27)
				)
				(justify mirror)
			)
		)
		(property "Value" ""
			(at 0 0 0)
			(layer "B.Fab")
			(effects
				(font
					(size 1.27 1.27)
				)
				(justify mirror)
			)
		)
		(duplicate_pad_numbers_are_jumpers no)
		(fp_line
			(start -0.7874 -0.4064)
			(end -0.7874 0.4064)
			(stroke
				(width 0.1524)
				(type default)
			)
			(layer "B.SilkS")
		)
		(fp_line
			(start -0.7874 0.4064)
			(end 0.7874 0.4064)
			(stroke
				(width 0.1524)
				(type default)
			)
			(layer "B.SilkS")
		)
		(fp_line
			(start 0.7874 -0.4064)
			(end -0.7874 -0.4064)
			(stroke
				(width 0.1524)
				(type default)
			)
			(layer "B.SilkS")
		)
		(fp_line
			(start 0.7874 0.4064)
			(end 0.7874 -0.4064)
			(stroke
				(width 0.1524)
				(type default)
			)
			(layer "B.SilkS")
		)
		(fp_line
			(start -0.67945 -0.3048)
			(end -0.67945 0.3048)
			(stroke
				(width 0.1)
				(type default)
			)
			(layer "B.Fab")
		)
		(fp_line
			(start -0.67945 0.3048)
			(end -0.120396 0.3048)
			(stroke
				(width 0.1)
				(type default)
			)
			(layer "B.Fab")
		)
		(fp_line
			(start -0.12065 -0.3048)
			(end -0.67945 -0.3048)
			(stroke
				(width 0.1)
				(type default)
			)
			(layer "B.Fab")
		)
		(fp_line
			(start -0.12065 -0.2794)
			(end -0.12065 -0.3048)
			(stroke
				(width 0.1)
				(type default)
			)
			(layer "B.Fab")
		)
		(fp_line
			(start -0.120396 0.2794)
			(end 0.12065 0.2794)
			(stroke
				(width 0.1)
				(type default)
			)
			(layer "B.Fab")
		)
		(fp_line
			(start -0.120396 0.3048)
			(end -0.120396 0.2794)
			(stroke
				(width 0.1)
				(type default)
			)
			(layer "B.Fab")
		)
		(fp_line
			(start 0.12065 -0.305054)
			(end 0.12065 -0.2794)
			(stroke
				(width 0.1)
				(type default)
			)
			(layer "B.Fab")
		)
		(fp_line
			(start 0.12065 -0.2794)
			(end -0.12065 -0.2794)
			(stroke
				(width 0.1)
				(type default)
			)
			(layer "B.Fab")
		)
		(fp_line
			(start 0.12065 0.2794)
			(end 0.12065 0.3048)
			(stroke
				(width 0.1)
				(type default)
			)
			(layer "B.Fab")
		)
		(fp_line
			(start 0.12065 0.3048)
			(end 0.67945 0.3048)
			(stroke
				(width 0.1)
				(type default)
			)
			(layer "B.Fab")
		)
		(fp_line
			(start 0.67945 -0.305054)
			(end 0.12065 -0.305054)
			(stroke
				(width 0.1)
				(type default)
			)
			(layer "B.Fab")
		)
		(fp_line
			(start 0.67945 0.3048)
			(end 0.67945 -0.305054)
			(stroke
				(width 0.1)
				(type default)
			)
			(layer "B.Fab")
		)
		(pad "1" smd circle
			(at 0.40005 0 180)
			(size 0 0)
			(layers "B.Cu" "B.Mask" "B.Paste")
			(net "PD_GPP_M_16")
		)
		(pad "2" smd circle
			(at -0.40005 0 180)
			(size 0 0)
			(layers "B.Cu" "B.Mask" "B.Paste")
			(net "GND")
		)
	)
	(footprint ""
		(layer "B.Cu")
		(at 160.952942 -318.705992 -90)
		(property "Reference" "R78"
			(at 0 0 90)
			(layer "B.SilkS")
			(hide yes)
			(effects
				(font
					(size 1.27 1.27)
				)
				(justify mirror)
			)
		)
		(property "Value" ""
			(at 0 0 90)
			(layer "B.Fab")
			(effects
				(font
					(size 1.27 1.27)
				)
				(justify mirror)
			)
		)
		(duplicate_pad_numbers_are_jumpers no)
		(fp_line
			(start -0.7874 0.4064)
			(end 0.7874 0.4064)
			(stroke
				(width 0.1524)
				(type default)
			)
			(layer "B.SilkS")
		)
		(fp_line
			(start 0.7874 0.4064)
			(end 0.7874 -0.4064)
			(stroke
				(width 0.1524)
				(type default)
			)
			(layer "B.SilkS")
		)
		(fp_line
			(start -0.7874 -0.4064)
			(end -0.7874 0.4064)
			(stroke
				(width 0.1524)
				(type default)
			)
			(layer "B.SilkS")
		)
		(fp_line
			(start 0.7874 -0.4064)
			(end -0.7874 -0.4064)
			(stroke
				(width 0.1524)
				(type default)
			)
			(layer "B.SilkS")
		)
		(fp_line
			(start -0.67945 0.3048)
			(end -0.120396 0.3048)
			(stroke
				(width 0.1)
				(type default)
			)
			(layer "B.Fab")
		)
		(fp_line
			(start -0.120396 0.3048)
			(end -0.120396 0.2794)
			(stroke
				(width 0.1)
				(type default)
			)
			(layer "B.Fab")
		)
		(fp_line
			(start 0.12065 0.3048)
			(end 0.67945 0.3048)
			(stroke
				(width 0.1)
				(type default)
			)
			(layer "B.Fab")
		)
		(fp_line
			(start 0.67945 0.3048)
			(end 0.67945 -0.305054)
			(stroke
				(width 0.1)
				(type default)
			)
			(layer "B.Fab")
		)
		(fp_line
			(start -0.120396 0.2794)
			(end 0.12065 0.2794)
			(stroke
				(width 0.1)
				(type default)
			)
			(layer "B.Fab")
		)
		(fp_line
			(start 0.12065 0.2794)
			(end 0.12065 0.3048)
			(stroke
				(width 0.1)
				(type default)
			)
			(layer "B.Fab")
		)
		(fp_line
			(start -0.12065 -0.2794)
			(end -0.12065 -0.3048)
			(stroke
				(width 0.1)
				(type default)
			)
			(layer "B.Fab")
		)
		(fp_line
			(start 0.12065 -0.2794)
			(end -0.12065 -0.2794)
			(stroke
				(width 0.1)
				(type default)
			)
			(layer "B.Fab")
		)
		(fp_line
			(start -0.67945 -0.3048)
			(end -0.67945 0.3048)
			(stroke
				(width 0.1)
				(type default)
			)
			(layer "B.Fab")
		)
		(fp_line
			(start -0.12065 -0.3048)
			(end -0.67945 -0.3048)
			(stroke
				(width 0.1)
				(type default)
			)
			(layer "B.Fab")
		)
		(fp_line
			(start 0.12065 -0.305054)
			(end 0.12065 -0.2794)
			(stroke
				(width 0.1)
				(type default)
			)
			(layer "B.Fab")
		)
		(fp_line
			(start 0.67945 -0.305054)
			(end 0.12065 -0.305054)
			(stroke
				(width 0.1)
				(type default)
			)
			(layer "B.Fab")
		)
		(pad "1" smd circle
			(at 0.40005 0 90)
			(size 0 0)
			(layers "B.Cu" "B.Mask" "B.Paste")
			(net "PD_CHE_CPU1_DIMM2_SAA")
		)
		(pad "2" smd circle
			(at -0.40005 0 90)
			(size 0 0)
			(layers "B.Cu" "B.Mask" "B.Paste")
			(net "GND")
		)
	)
	(footprint ""
		(layer "B.Cu")
		(at 342.037416 -37.574728 -90)
		(property "Reference" "R71"
			(at 0 0 90)
			(layer "B.SilkS")
			(hide yes)
			(effects
				(font
					(size 1.27 1.27)
				)
				(justify mirror)
			)
		)
		(property "Value" ""
			(at 0 0 90)
			(layer "B.Fab")
			(effects
				(font
					(size 1.27 1.27)
				)
				(justify mirror)
			)
		)
		(duplicate_pad_numbers_are_jumpers no)
		(fp_line
			(start -0.7874 0.4064)
			(end 0.7874 0.4064)
			(stroke
				(width 0.1524)
				(type default)
			)
			(layer "B.SilkS")
		)
		(fp_line
			(start 0.7874 0.4064)
			(end 0.7874 -0.4064)
			(stroke
				(width 0.1524)
				(type default)
			)
			(layer "B.SilkS")
		)
		(fp_line
			(start -0.7874 -0.4064)
			(end -0.7874 0.4064)
			(stroke
				(width 0.1524)
				(type default)
			)
			(layer "B.SilkS")
		)
		(fp_line
			(start 0.7874 -0.4064)
			(end -0.7874 -0.4064)
			(stroke
				(width 0.1524)
				(type default)
			)
			(layer "B.SilkS")
		)
		(fp_line
			(start -0.67945 0.3048)
			(end -0.120396 0.3048)
			(stroke
				(width 0.1)
				(type default)
			)
			(layer "B.Fab")
		)
		(fp_line
			(start -0.120396 0.3048)
			(end -0.120396 0.2794)
			(stroke
				(width 0.1)
				(type default)
			)
			(layer "B.Fab")
		)
		(fp_line
			(start 0.12065 0.3048)
			(end 0.67945 0.3048)
			(stroke
				(width 0.1)
				(type default)
			)
			(layer "B.Fab")
		)
		(fp_line
			(start 0.67945 0.3048)
			(end 0.67945 -0.305054)
			(stroke
				(width 0.1)
				(type default)
			)
			(layer "B.Fab")
		)
		(fp_line
			(start -0.120396 0.2794)
			(end 0.12065 0.2794)
			(stroke
				(width 0.1)
				(type default)
			)
			(layer "B.Fab")
		)
		(fp_line
			(start 0.12065 0.2794)
			(end 0.12065 0.3048)
			(stroke
				(width 0.1)
				(type default)
			)
			(layer "B.Fab")
		)
		(fp_line
			(start -0.12065 -0.2794)
			(end -0.12065 -0.3048)
			(stroke
				(width 0.1)
				(type default)
			)
			(layer "B.Fab")
		)
		(fp_line
			(start 0.12065 -0.2794)
			(end -0.12065 -0.2794)
			(stroke
				(width 0.1)
				(type default)
			)
			(layer "B.Fab")
		)
		(fp_line
			(start -0.67945 -0.3048)
			(end -0.67945 0.3048)
			(stroke
				(width 0.1)
				(type default)
			)
			(layer "B.Fab")
		)
		(fp_line
			(start -0.12065 -0.3048)
			(end -0.67945 -0.3048)
			(stroke
				(width 0.1)
				(type default)
			)
			(layer "B.Fab")
		)
		(fp_line
			(start 0.12065 -0.305054)
			(end 0.12065 -0.2794)
			(stroke
				(width 0.1)
				(type default)
			)
			(layer "B.Fab")
		)
		(fp_line
			(start 0.67945 -0.305054)
			(end 0.12065 -0.305054)
			(stroke
				(width 0.1)
				(type default)
			)
			(layer "B.Fab")
		)
		(pad "1" smd circle
			(at 0.40005 0 90)
			(size 0 0)
			(layers "B.Cu" "B.Mask" "B.Paste")
			(net "P3V3_AUX")
		)
		(pad "2" smd circle
			(at -0.40005 0 90)
			(size 0 0)
			(layers "B.Cu" "B.Mask" "B.Paste")
			(net "FM_ME_BT_DONE")
		)
	)
	(footprint ""
		(layer "B.Cu")
		(at 295.130474 -354.163376 -90)
		(property "Reference" "PC616_P0_2"
			(at 0 0 90)
			(layer "B.SilkS")
			(hide yes)
			(effects
				(font
					(size 1.27 1.27)
				)
				(justify mirror)
			)
		)
		(property "Value" ""
			(at 0 0 90)
			(layer "B.Fab")
			(effects
				(font
					(size 1.27 1.27)
				)
				(justify mirror)
			)
		)
		(duplicate_pad_numbers_are_jumpers no)
		(fp_line
			(start -1.524 0.762)
			(end 1.524 0.762)
			(stroke
				(width 0.1524)
				(type default)
			)
			(layer "B.SilkS")
		)
		(fp_line
			(start 1.524 0.762)
			(end 1.524 -0.762)
			(stroke
				(width 0.1524)
				(type default)
			)
			(layer "B.SilkS")
		)
		(fp_line
			(start -1.524 -0.762)
			(end -1.524 0.762)
			(stroke
				(width 0.1524)
				(type default)
			)
			(layer "B.SilkS")
		)
		(fp_line
			(start 1.524 -0.762)
			(end -1.524 -0.762)
			(stroke
				(width 0.1524)
				(type default)
			)
			(layer "B.SilkS")
		)
		(fp_line
			(start -1.1049 0.724916)
			(end -1.1049 -0.724916)
			(stroke
				(width 0.1)
				(type default)
			)
			(layer "B.Fab")
		)
		(fp_line
			(start 1.1049 0.724916)
			(end -1.1049 0.724916)
			(stroke
				(width 0.1)
				(type default)
			)
			(layer "B.Fab")
		)
		(fp_line
			(start -1.1049 -0.724916)
			(end 1.1049 -0.724916)
			(stroke
				(width 0.1)
				(type default)
			)
			(layer "B.Fab")
		)
		(fp_line
			(start 1.1049 -0.724916)
			(end 1.1049 0.724916)
			(stroke
				(width 0.1)
				(type default)
			)
			(layer "B.Fab")
		)
		(pad "1" smd rect
			(at 0.889 0 270)
			(size 1.016 1.27)
			(layers "B.Cu" "B.Mask" "B.Paste")
			(net "PVCCFA_EHV_FIVRA_CPU0")
		)
		(pad "2" smd rect
			(at -0.889 0 270)
			(size 1.016 1.27)
			(layers "B.Cu" "B.Mask" "B.Paste")
			(net "GND")
		)
	)
	(footprint ""
		(layer "B.Cu")
		(at 116.84 -86.705948 180)
		(property "Reference" "R4023"
			(at 0 0 0)
			(layer "B.SilkS")
			(hide yes)
			(effects
				(font
					(size 1.27 1.27)
				)
				(justify mirror)
			)
		)
		(property "Value" ""
			(at 0 0 0)
			(layer "B.Fab")
			(effects
				(font
					(size 1.27 1.27)
				)
				(justify mirror)
			)
		)
		(duplicate_pad_numbers_are_jumpers no)
		(fp_line
			(start 0.7874 0.4064)
			(end 0.7874 -0.4064)
			(stroke
				(width 0.1524)
				(type default)
			)
			(layer "B.SilkS")
		)
		(fp_line
			(start 0.7874 -0.4064)
			(end -0.7874 -0.4064)
			(stroke
				(width 0.1524)
				(type default)
			)
			(layer "B.SilkS")
		)
		(fp_line
			(start -0.7874 0.4064)
			(end 0.7874 0.4064)
			(stroke
				(width 0.1524)
				(type default)
			)
			(layer "B.SilkS")
		)
		(fp_line
			(start -0.7874 -0.4064)
			(end -0.7874 0.4064)
			(stroke
				(width 0.1524)
				(type default)
			)
			(layer "B.SilkS")
		)
		(fp_line
			(start 0.67945 0.3048)
			(end 0.67945 -0.305054)
			(stroke
				(width 0.1)
				(type default)
			)
			(layer "B.Fab")
		)
		(fp_line
			(start 0.67945 -0.305054)
			(end 0.12065 -0.305054)
			(stroke
				(width 0.1)
				(type default)
			)
			(layer "B.Fab")
		)
		(fp_line
			(start 0.12065 0.3048)
			(end 0.67945 0.3048)
			(stroke
				(width 0.1)
				(type default)
			)
			(layer "B.Fab")
		)
		(fp_line
			(start 0.12065 0.2794)
			(end 0.12065 0.3048)
			(stroke
				(width 0.1)
				(type default)
			)
			(layer "B.Fab")
		)
		(fp_line
			(start 0.12065 -0.2794)
			(end -0.12065 -0.2794)
			(stroke
				(width 0.1)
				(type default)
			)
			(layer "B.Fab")
		)
		(fp_line
			(start 0.12065 -0.305054)
			(end 0.12065 -0.2794)
			(stroke
				(width 0.1)
				(type default)
			)
			(layer "B.Fab")
		)
		(fp_line
			(start -0.120396 0.3048)
			(end -0.120396 0.2794)
			(stroke
				(width 0.1)
				(type default)
			)
			(layer "B.Fab")
		)
		(fp_line
			(start -0.120396 0.2794)
			(end 0.12065 0.2794)
			(stroke
				(width 0.1)
				(type default)
			)
			(layer "B.Fab")
		)
		(fp_line
			(start -0.12065 -0.2794)
			(end -0.12065 -0.3048)
			(stroke
				(width 0.1)
				(type default)
			)
			(layer "B.Fab")
		)
		(fp_line
			(start -0.12065 -0.3048)
			(end -0.67945 -0.3048)
			(stroke
				(width 0.1)
				(type default)
			)
			(layer "B.Fab")
		)
		(fp_line
			(start -0.67945 0.3048)
			(end -0.120396 0.3048)
			(stroke
				(width 0.1)
				(type default)
			)
			(layer "B.Fab")
		)
		(fp_line
			(start -0.67945 -0.3048)
			(end -0.67945 0.3048)
			(stroke
				(width 0.1)
				(type default)
			)
			(layer "B.Fab")
		)
		(pad "1" smd circle
			(at 0.40005 0)
			(size 0 0)
			(layers "B.Cu" "B.Mask" "B.Paste")
			(net "H_CPU_CATERR_LVC2_R1_N")
		)
		(pad "2" smd circle
			(at -0.40005 0)
			(size 0 0)
			(layers "B.Cu" "B.Mask" "B.Paste")
			(net "H_CPU_CATERR_LVC2_R2_N")
		)
	)
	(footprint ""
		(layer "B.Cu")
		(at 99.53752 -422.145968 90)
		(property "Reference" "R4556"
			(at 0 0 90)
			(layer "B.SilkS")
			(hide yes)
			(effects
				(font
					(size 1.27 1.27)
				)
				(justify mirror)
			)
		)
		(property "Value" ""
			(at 0 0 90)
			(layer "B.Fab")
			(effects
				(font
					(size 1.27 1.27)
				)
				(justify mirror)
			)
		)
		(duplicate_pad_numbers_are_jumpers no)
		(fp_line
			(start 0.7874 -0.4064)
			(end -0.7874 -0.4064)
			(stroke
				(width 0.1524)
				(type default)
			)
			(layer "B.SilkS")
		)
		(fp_line
			(start -0.7874 -0.4064)
			(end -0.7874 0.4064)
			(stroke
				(width 0.1524)
				(type default)
			)
			(layer "B.SilkS")
		)
		(fp_line
			(start 0.7874 0.4064)
			(end 0.7874 -0.4064)
			(stroke
				(width 0.1524)
				(type default)
			)
			(layer "B.SilkS")
		)
		(fp_line
			(start -0.7874 0.4064)
			(end 0.7874 0.4064)
			(stroke
				(width 0.1524)
				(type default)
			)
			(layer "B.SilkS")
		)
		(fp_line
			(start 0.67945 -0.305054)
			(end 0.12065 -0.305054)
			(stroke
				(width 0.1)
				(type default)
			)
			(layer "B.Fab")
		)
		(fp_line
			(start 0.12065 -0.305054)
			(end 0.12065 -0.2794)
			(stroke
				(width 0.1)
				(type default)
			)
			(layer "B.Fab")
		)
		(fp_line
			(start -0.12065 -0.3048)
			(end -0.67945 -0.3048)
			(stroke
				(width 0.1)
				(type default)
			)
			(layer "B.Fab")
		)
		(fp_line
			(start -0.67945 -0.3048)
			(end -0.67945 0.3048)
			(stroke
				(width 0.1)
				(type default)
			)
			(layer "B.Fab")
		)
		(fp_line
			(start 0.12065 -0.2794)
			(end -0.12065 -0.2794)
			(stroke
				(width 0.1)
				(type default)
			)
			(layer "B.Fab")
		)
		(fp_line
			(start -0.12065 -0.2794)
			(end -0.12065 -0.3048)
			(stroke
				(width 0.1)
				(type default)
			)
			(layer "B.Fab")
		)
		(fp_line
			(start 0.12065 0.2794)
			(end 0.12065 0.3048)
			(stroke
				(width 0.1)
				(type default)
			)
			(layer "B.Fab")
		)
		(fp_line
			(start -0.120396 0.2794)
			(end 0.12065 0.2794)
			(stroke
				(width 0.1)
				(type default)
			)
			(layer "B.Fab")
		)
		(fp_line
			(start 0.67945 0.3048)
			(end 0.67945 -0.305054)
			(stroke
				(width 0.1)
				(type default)
			)
			(layer "B.Fab")
		)
		(fp_line
			(start 0.12065 0.3048)
			(end 0.67945 0.3048)
			(stroke
				(width 0.1)
				(type default)
			)
			(layer "B.Fab")
		)
		(fp_line
			(start -0.120396 0.3048)
			(end -0.120396 0.2794)
			(stroke
				(width 0.1)
				(type default)
			)
			(layer "B.Fab")
		)
		(fp_line
			(start -0.67945 0.3048)
			(end -0.120396 0.3048)
			(stroke
				(width 0.1)
				(type default)
			)
			(layer "B.Fab")
		)
		(pad "1" smd circle
			(at 0.40005 0 270)
			(size 0 0)
			(layers "B.Cu" "B.Mask" "B.Paste")
			(net "HGX_DETECT_N_R")
		)
		(pad "2" smd circle
			(at -0.40005 0 270)
			(size 0 0)
			(layers "B.Cu" "B.Mask" "B.Paste")
			(net "HGX_DETECT_N")
		)
	)
	(footprint ""
		(layer "B.Cu")
		(at 237.230666 -422.993058 90)
		(property "Reference" "R2906"
			(at 0 0 90)
			(layer "B.SilkS")
			(hide yes)
			(effects
				(font
					(size 1.27 1.27)
				)
				(justify mirror)
			)
		)
		(property "Value" ""
			(at 0 0 90)
			(layer "B.Fab")
			(effects
				(font
					(size 1.27 1.27)
				)
				(justify mirror)
			)
		)
		(duplicate_pad_numbers_are_jumpers no)
		(fp_line
			(start 0.7874 -0.4064)
			(end -0.7874 -0.4064)
			(stroke
				(width 0.1524)
				(type default)
			)
			(layer "B.SilkS")
		)
		(fp_line
			(start -0.7874 -0.4064)
			(end -0.7874 0.4064)
			(stroke
				(width 0.1524)
				(type default)
			)
			(layer "B.SilkS")
		)
		(fp_line
			(start 0.7874 0.4064)
			(end 0.7874 -0.4064)
			(stroke
				(width 0.1524)
				(type default)
			)
			(layer "B.SilkS")
		)
		(fp_line
			(start -0.7874 0.4064)
			(end 0.7874 0.4064)
			(stroke
				(width 0.1524)
				(type default)
			)
			(layer "B.SilkS")
		)
		(fp_line
			(start 0.67945 -0.305054)
			(end 0.12065 -0.305054)
			(stroke
				(width 0.1)
				(type default)
			)
			(layer "B.Fab")
		)
		(fp_line
			(start 0.12065 -0.305054)
			(end 0.12065 -0.2794)
			(stroke
				(width 0.1)
				(type default)
			)
			(layer "B.Fab")
		)
		(fp_line
			(start -0.12065 -0.3048)
			(end -0.67945 -0.3048)
			(stroke
				(width 0.1)
				(type default)
			)
			(layer "B.Fab")
		)
		(fp_line
			(start -0.67945 -0.3048)
			(end -0.67945 0.3048)
			(stroke
				(width 0.1)
				(type default)
			)
			(layer "B.Fab")
		)
		(fp_line
			(start 0.12065 -0.2794)
			(end -0.12065 -0.2794)
			(stroke
				(width 0.1)
				(type default)
			)
			(layer "B.Fab")
		)
		(fp_line
			(start -0.12065 -0.2794)
			(end -0.12065 -0.3048)
			(stroke
				(width 0.1)
				(type default)
			)
			(layer "B.Fab")
		)
		(fp_line
			(start 0.12065 0.2794)
			(end 0.12065 0.3048)
			(stroke
				(width 0.1)
				(type default)
			)
			(layer "B.Fab")
		)
		(fp_line
			(start -0.120396 0.2794)
			(end 0.12065 0.2794)
			(stroke
				(width 0.1)
				(type default)
			)
			(layer "B.Fab")
		)
		(fp_line
			(start 0.67945 0.3048)
			(end 0.67945 -0.305054)
			(stroke
				(width 0.1)
				(type default)
			)
			(layer "B.Fab")
		)
		(fp_line
			(start 0.12065 0.3048)
			(end 0.67945 0.3048)
			(stroke
				(width 0.1)
				(type default)
			)
			(layer "B.Fab")
		)
		(fp_line
			(start -0.120396 0.3048)
			(end -0.120396 0.2794)
			(stroke
				(width 0.1)
				(type default)
			)
			(layer "B.Fab")
		)
		(fp_line
			(start -0.67945 0.3048)
			(end -0.120396 0.3048)
			(stroke
				(width 0.1)
				(type default)
			)
			(layer "B.Fab")
		)
		(pad "1" smd circle
			(at 0.40005 0 270)
			(size 0 0)
			(layers "B.Cu" "B.Mask" "B.Paste")
			(net "FM_GPU_HSC_EN_BUF_R1")
		)
		(pad "2" smd circle
			(at -0.40005 0 270)
			(size 0 0)
			(layers "B.Cu" "B.Mask" "B.Paste")
			(net "FM_GPU_HSC_EN_BUF")
		)
	)
	(footprint ""
		(layer "B.Cu")
		(at 84.494624 -184.096152 90)
		(property "Reference" "R759"
			(at 0 0 90)
			(layer "B.SilkS")
			(hide yes)
			(effects
				(font
					(size 1.27 1.27)
				)
				(justify mirror)
			)
		)
		(property "Value" ""
			(at 0 0 90)
			(layer "B.Fab")
			(effects
				(font
					(size 1.27 1.27)
				)
				(justify mirror)
			)
		)
		(duplicate_pad_numbers_are_jumpers no)
		(fp_line
			(start 0.7874 -0.4064)
			(end -0.7874 -0.4064)
			(stroke
				(width 0.1524)
				(type default)
			)
			(layer "B.SilkS")
		)
		(fp_line
			(start -0.7874 -0.4064)
			(end -0.7874 0.4064)
			(stroke
				(width 0.1524)
				(type default)
			)
			(layer "B.SilkS")
		)
		(fp_line
			(start 0.7874 0.4064)
			(end 0.7874 -0.4064)
			(stroke
				(width 0.1524)
				(type default)
			)
			(layer "B.SilkS")
		)
		(fp_line
			(start -0.7874 0.4064)
			(end 0.7874 0.4064)
			(stroke
				(width 0.1524)
				(type default)
			)
			(layer "B.SilkS")
		)
		(fp_line
			(start 0.67945 -0.305054)
			(end 0.12065 -0.305054)
			(stroke
				(width 0.1)
				(type default)
			)
			(layer "B.Fab")
		)
		(fp_line
			(start 0.12065 -0.305054)
			(end 0.12065 -0.2794)
			(stroke
				(width 0.1)
				(type default)
			)
			(layer "B.Fab")
		)
		(fp_line
			(start -0.12065 -0.3048)
			(end -0.67945 -0.3048)
			(stroke
				(width 0.1)
				(type default)
			)
			(layer "B.Fab")
		)
		(fp_line
			(start -0.67945 -0.3048)
			(end -0.67945 0.3048)
			(stroke
				(width 0.1)
				(type default)
			)
			(layer "B.Fab")
		)
		(fp_line
			(start 0.12065 -0.2794)
			(end -0.12065 -0.2794)
			(stroke
				(width 0.1)
				(type default)
			)
			(layer "B.Fab")
		)
		(fp_line
			(start -0.12065 -0.2794)
			(end -0.12065 -0.3048)
			(stroke
				(width 0.1)
				(type default)
			)
			(layer "B.Fab")
		)
		(fp_line
			(start 0.12065 0.2794)
			(end 0.12065 0.3048)
			(stroke
				(width 0.1)
				(type default)
			)
			(layer "B.Fab")
		)
		(fp_line
			(start -0.120396 0.2794)
			(end 0.12065 0.2794)
			(stroke
				(width 0.1)
				(type default)
			)
			(layer "B.Fab")
		)
		(fp_line
			(start 0.67945 0.3048)
			(end 0.67945 -0.305054)
			(stroke
				(width 0.1)
				(type default)
			)
			(layer "B.Fab")
		)
		(fp_line
			(start 0.12065 0.3048)
			(end 0.67945 0.3048)
			(stroke
				(width 0.1)
				(type default)
			)
			(layer "B.Fab")
		)
		(fp_line
			(start -0.120396 0.3048)
			(end -0.120396 0.2794)
			(stroke
				(width 0.1)
				(type default)
			)
			(layer "B.Fab")
		)
		(fp_line
			(start -0.67945 0.3048)
			(end -0.120396 0.3048)
			(stroke
				(width 0.1)
				(type default)
			)
			(layer "B.Fab")
		)
		(pad "1" smd circle
			(at 0.40005 0 270)
			(size 0 0)
			(layers "B.Cu" "B.Mask" "B.Paste")
			(net "PVNN_TERM_CPU0")
		)
		(pad "2" smd circle
			(at -0.40005 0 270)
			(size 0 0)
			(layers "B.Cu" "B.Mask" "B.Paste")
			(net "H_CPU_PRDY_QS_GTL_N")
		)
	)
	(footprint ""
		(layer "B.Cu")
		(at 461.419448 -318.79159 90)
		(property "Reference" "R40"
			(at 0 0 90)
			(layer "B.SilkS")
			(hide yes)
			(effects
				(font
					(size 1.27 1.27)
				)
				(justify mirror)
			)
		)
		(property "Value" ""
			(at 0 0 90)
			(layer "B.Fab")
			(effects
				(font
					(size 1.27 1.27)
				)
				(justify mirror)
			)
		)
		(duplicate_pad_numbers_are_jumpers no)
		(fp_line
			(start 0.7874 -0.4064)
			(end -0.7874 -0.4064)
			(stroke
				(width 0.1524)
				(type default)
			)
			(layer "B.SilkS")
		)
		(fp_line
			(start -0.7874 -0.4064)
			(end -0.7874 0.4064)
			(stroke
				(width 0.1524)
				(type default)
			)
			(layer "B.SilkS")
		)
		(fp_line
			(start 0.7874 0.4064)
			(end 0.7874 -0.4064)
			(stroke
				(width 0.1524)
				(type default)
			)
			(layer "B.SilkS")
		)
		(fp_line
			(start -0.7874 0.4064)
			(end 0.7874 0.4064)
			(stroke
				(width 0.1524)
				(type default)
			)
			(layer "B.SilkS")
		)
		(fp_line
			(start 0.67945 -0.305054)
			(end 0.12065 -0.305054)
			(stroke
				(width 0.1)
				(type default)
			)
			(layer "B.Fab")
		)
		(fp_line
			(start 0.12065 -0.305054)
			(end 0.12065 -0.2794)
			(stroke
				(width 0.1)
				(type default)
			)
			(layer "B.Fab")
		)
		(fp_line
			(start -0.12065 -0.3048)
			(end -0.67945 -0.3048)
			(stroke
				(width 0.1)
				(type default)
			)
			(layer "B.Fab")
		)
		(fp_line
			(start -0.67945 -0.3048)
			(end -0.67945 0.3048)
			(stroke
				(width 0.1)
				(type default)
			)
			(layer "B.Fab")
		)
		(fp_line
			(start 0.12065 -0.2794)
			(end -0.12065 -0.2794)
			(stroke
				(width 0.1)
				(type default)
			)
			(layer "B.Fab")
		)
		(fp_line
			(start -0.12065 -0.2794)
			(end -0.12065 -0.3048)
			(stroke
				(width 0.1)
				(type default)
			)
			(layer "B.Fab")
		)
		(fp_line
			(start 0.12065 0.2794)
			(end 0.12065 0.3048)
			(stroke
				(width 0.1)
				(type default)
			)
			(layer "B.Fab")
		)
		(fp_line
			(start -0.120396 0.2794)
			(end 0.12065 0.2794)
			(stroke
				(width 0.1)
				(type default)
			)
			(layer "B.Fab")
		)
		(fp_line
			(start 0.67945 0.3048)
			(end 0.67945 -0.305054)
			(stroke
				(width 0.1)
				(type default)
			)
			(layer "B.Fab")
		)
		(fp_line
			(start 0.12065 0.3048)
			(end 0.67945 0.3048)
			(stroke
				(width 0.1)
				(type default)
			)
			(layer "B.Fab")
		)
		(fp_line
			(start -0.120396 0.3048)
			(end -0.120396 0.2794)
			(stroke
				(width 0.1)
				(type default)
			)
			(layer "B.Fab")
		)
		(fp_line
			(start -0.67945 0.3048)
			(end -0.120396 0.3048)
			(stroke
				(width 0.1)
				(type default)
			)
			(layer "B.Fab")
		)
		(pad "1" smd circle
			(at 0.40005 0 270)
			(size 0 0)
			(layers "B.Cu" "B.Mask" "B.Paste")
			(net "PD_CHH_CPU0_DIMM1_SAA")
		)
		(pad "2" smd circle
			(at -0.40005 0 270)
			(size 0 0)
			(layers "B.Cu" "B.Mask" "B.Paste")
			(net "GND")
		)
	)
	(footprint ""
		(layer "B.Cu")
		(at 381.92583 -190.82131 -90)
		(property "Reference" "R95"
			(at 0 0 90)
			(layer "B.SilkS")
			(hide yes)
			(effects
				(font
					(size 1.27 1.27)
				)
				(justify mirror)
			)
		)
		(property "Value" ""
			(at 0 0 90)
			(layer "B.Fab")
			(effects
				(font
					(size 1.27 1.27)
				)
				(justify mirror)
			)
		)
		(duplicate_pad_numbers_are_jumpers no)
		(fp_line
			(start -0.7874 0.4064)
			(end 0.7874 0.4064)
			(stroke
				(width 0.1524)
				(type default)
			)
			(layer "B.SilkS")
		)
		(fp_line
			(start 0.7874 0.4064)
			(end 0.7874 -0.4064)
			(stroke
				(width 0.1524)
				(type default)
			)
			(layer "B.SilkS")
		)
		(fp_line
			(start -0.7874 -0.4064)
			(end -0.7874 0.4064)
			(stroke
				(width 0.1524)
				(type default)
			)
			(layer "B.SilkS")
		)
		(fp_line
			(start 0.7874 -0.4064)
			(end -0.7874 -0.4064)
			(stroke
				(width 0.1524)
				(type default)
			)
			(layer "B.SilkS")
		)
		(fp_line
			(start -0.67945 0.3048)
			(end -0.120396 0.3048)
			(stroke
				(width 0.1)
				(type default)
			)
			(layer "B.Fab")
		)
		(fp_line
			(start -0.120396 0.3048)
			(end -0.120396 0.2794)
			(stroke
				(width 0.1)
				(type default)
			)
			(layer "B.Fab")
		)
		(fp_line
			(start 0.12065 0.3048)
			(end 0.67945 0.3048)
			(stroke
				(width 0.1)
				(type default)
			)
			(layer "B.Fab")
		)
		(fp_line
			(start 0.67945 0.3048)
			(end 0.67945 -0.305054)
			(stroke
				(width 0.1)
				(type default)
			)
			(layer "B.Fab")
		)
		(fp_line
			(start -0.120396 0.2794)
			(end 0.12065 0.2794)
			(stroke
				(width 0.1)
				(type default)
			)
			(layer "B.Fab")
		)
		(fp_line
			(start 0.12065 0.2794)
			(end 0.12065 0.3048)
			(stroke
				(width 0.1)
				(type default)
			)
			(layer "B.Fab")
		)
		(fp_line
			(start -0.12065 -0.2794)
			(end -0.12065 -0.3048)
			(stroke
				(width 0.1)
				(type default)
			)
			(layer "B.Fab")
		)
		(fp_line
			(start 0.12065 -0.2794)
			(end -0.12065 -0.2794)
			(stroke
				(width 0.1)
				(type default)
			)
			(layer "B.Fab")
		)
		(fp_line
			(start -0.67945 -0.3048)
			(end -0.67945 0.3048)
			(stroke
				(width 0.1)
				(type default)
			)
			(layer "B.Fab")
		)
		(fp_line
			(start -0.12065 -0.3048)
			(end -0.67945 -0.3048)
			(stroke
				(width 0.1)
				(type default)
			)
			(layer "B.Fab")
		)
		(fp_line
			(start 0.12065 -0.305054)
			(end 0.12065 -0.2794)
			(stroke
				(width 0.1)
				(type default)
			)
			(layer "B.Fab")
		)
		(fp_line
			(start 0.67945 -0.305054)
			(end 0.12065 -0.305054)
			(stroke
				(width 0.1)
				(type default)
			)
			(layer "B.Fab")
		)
		(pad "1" smd circle
			(at 0.40005 0 90)
			(size 0 0)
			(layers "B.Cu" "B.Mask" "B.Paste")
			(net "PVNN_TERM_CPU0")
		)
		(pad "2" smd circle
			(at -0.40005 0 90)
			(size 0 0)
			(layers "B.Cu" "B.Mask" "B.Paste")
			(net "PU_CPU0_UPI1_AC_COUPLING")
		)
	)
	(footprint ""
		(layer "B.Cu")
		(at 20.566634 -176.423574 -90)
		(property "Reference" "C1308"
			(at 0 0 90)
			(layer "B.SilkS")
			(hide yes)
			(effects
				(font
					(size 1.27 1.27)
				)
				(justify mirror)
			)
		)
		(property "Value" ""
			(at 0 0 90)
			(layer "B.Fab")
			(effects
				(font
					(size 1.27 1.27)
				)
				(justify mirror)
			)
		)
		(duplicate_pad_numbers_are_jumpers no)
		(fp_line
			(start -0.7874 0.4064)
			(end 0.7874 0.4064)
			(stroke
				(width 0.1524)
				(type default)
			)
			(layer "B.SilkS")
		)
		(fp_line
			(start 0.7874 0.4064)
			(end 0.7874 -0.4064)
			(stroke
				(width 0.1524)
				(type default)
			)
			(layer "B.SilkS")
		)
		(fp_line
			(start -0.7874 -0.4064)
			(end -0.7874 0.4064)
			(stroke
				(width 0.1524)
				(type default)
			)
			(layer "B.SilkS")
		)
		(fp_line
			(start 0.7874 -0.4064)
			(end -0.7874 -0.4064)
			(stroke
				(width 0.1524)
				(type default)
			)
			(layer "B.SilkS")
		)
		(fp_line
			(start -0.67945 0.3048)
			(end -0.120396 0.3048)
			(stroke
				(width 0.1)
				(type default)
			)
			(layer "B.Fab")
		)
		(fp_line
			(start -0.120396 0.3048)
			(end -0.120396 0.2794)
			(stroke
				(width 0.1)
				(type default)
			)
			(layer "B.Fab")
		)
		(fp_line
			(start 0.12065 0.3048)
			(end 0.67945 0.3048)
			(stroke
				(width 0.1)
				(type default)
			)
			(layer "B.Fab")
		)
		(fp_line
			(start 0.67945 0.3048)
			(end 0.67945 -0.305054)
			(stroke
				(width 0.1)
				(type default)
			)
			(layer "B.Fab")
		)
		(fp_line
			(start -0.120396 0.2794)
			(end 0.12065 0.2794)
			(stroke
				(width 0.1)
				(type default)
			)
			(layer "B.Fab")
		)
		(fp_line
			(start 0.12065 0.2794)
			(end 0.12065 0.3048)
			(stroke
				(width 0.1)
				(type default)
			)
			(layer "B.Fab")
		)
		(fp_line
			(start -0.12065 -0.2794)
			(end -0.12065 -0.3048)
			(stroke
				(width 0.1)
				(type default)
			)
			(layer "B.Fab")
		)
		(fp_line
			(start 0.12065 -0.2794)
			(end -0.12065 -0.2794)
			(stroke
				(width 0.1)
				(type default)
			)
			(layer "B.Fab")
		)
		(fp_line
			(start -0.67945 -0.3048)
			(end -0.67945 0.3048)
			(stroke
				(width 0.1)
				(type default)
			)
			(layer "B.Fab")
		)
		(fp_line
			(start -0.12065 -0.3048)
			(end -0.67945 -0.3048)
			(stroke
				(width 0.1)
				(type default)
			)
			(layer "B.Fab")
		)
		(fp_line
			(start 0.12065 -0.305054)
			(end 0.12065 -0.2794)
			(stroke
				(width 0.1)
				(type default)
			)
			(layer "B.Fab")
		)
		(fp_line
			(start 0.67945 -0.305054)
			(end 0.12065 -0.305054)
			(stroke
				(width 0.1)
				(type default)
			)
			(layer "B.Fab")
		)
		(pad "1" smd circle
			(at 0.40005 0 90)
			(size 0 0)
			(layers "B.Cu" "B.Mask" "B.Paste")
			(net "FM_PVNN_MAIN_CPU1_EN")
		)
		(pad "2" smd circle
			(at -0.40005 0 90)
			(size 0 0)
			(layers "B.Cu" "B.Mask" "B.Paste")
			(net "GND")
		)
	)
	(footprint ""
		(layer "B.Cu")
		(at 413.6644 -363.125258 -90)
		(property "Reference" "PR355"
			(at 0 0 90)
			(layer "B.SilkS")
			(hide yes)
			(effects
				(font
					(size 1.27 1.27)
				)
				(justify mirror)
			)
		)
		(property "Value" ""
			(at 0 0 90)
			(layer "B.Fab")
			(effects
				(font
					(size 1.27 1.27)
				)
				(justify mirror)
			)
		)
		(duplicate_pad_numbers_are_jumpers no)
		(fp_line
			(start -0.7874 0.4064)
			(end 0.7874 0.4064)
			(stroke
				(width 0.1524)
				(type default)
			)
			(layer "B.SilkS")
		)
		(fp_line
			(start 0.7874 0.4064)
			(end 0.7874 -0.4064)
			(stroke
				(width 0.1524)
				(type default)
			)
			(layer "B.SilkS")
		)
		(fp_line
			(start -0.7874 -0.4064)
			(end -0.7874 0.4064)
			(stroke
				(width 0.1524)
				(type default)
			)
			(layer "B.SilkS")
		)
		(fp_line
			(start 0.7874 -0.4064)
			(end -0.7874 -0.4064)
			(stroke
				(width 0.1524)
				(type default)
			)
			(layer "B.SilkS")
		)
		(fp_line
			(start -0.67945 0.3048)
			(end -0.120396 0.3048)
			(stroke
				(width 0.1)
				(type default)
			)
			(layer "B.Fab")
		)
		(fp_line
			(start -0.120396 0.3048)
			(end -0.120396 0.2794)
			(stroke
				(width 0.1)
				(type default)
			)
			(layer "B.Fab")
		)
		(fp_line
			(start 0.12065 0.3048)
			(end 0.67945 0.3048)
			(stroke
				(width 0.1)
				(type default)
			)
			(layer "B.Fab")
		)
		(fp_line
			(start 0.67945 0.3048)
			(end 0.67945 -0.305054)
			(stroke
				(width 0.1)
				(type default)
			)
			(layer "B.Fab")
		)
		(fp_line
			(start -0.120396 0.2794)
			(end 0.12065 0.2794)
			(stroke
				(width 0.1)
				(type default)
			)
			(layer "B.Fab")
		)
		(fp_line
			(start 0.12065 0.2794)
			(end 0.12065 0.3048)
			(stroke
				(width 0.1)
				(type default)
			)
			(layer "B.Fab")
		)
		(fp_line
			(start -0.12065 -0.2794)
			(end -0.12065 -0.3048)
			(stroke
				(width 0.1)
				(type default)
			)
			(layer "B.Fab")
		)
		(fp_line
			(start 0.12065 -0.2794)
			(end -0.12065 -0.2794)
			(stroke
				(width 0.1)
				(type default)
			)
			(layer "B.Fab")
		)
		(fp_line
			(start -0.67945 -0.3048)
			(end -0.67945 0.3048)
			(stroke
				(width 0.1)
				(type default)
			)
			(layer "B.Fab")
		)
		(fp_line
			(start -0.12065 -0.3048)
			(end -0.67945 -0.3048)
			(stroke
				(width 0.1)
				(type default)
			)
			(layer "B.Fab")
		)
		(fp_line
			(start 0.12065 -0.305054)
			(end 0.12065 -0.2794)
			(stroke
				(width 0.1)
				(type default)
			)
			(layer "B.Fab")
		)
		(fp_line
			(start 0.67945 -0.305054)
			(end 0.12065 -0.305054)
			(stroke
				(width 0.1)
				(type default)
			)
			(layer "B.Fab")
		)
		(pad "1" smd circle
			(at 0.40005 0 90)
			(size 0 0)
			(layers "B.Cu" "B.Mask" "B.Paste")
			(net "PVCCFA_EHV_FIVRA_CPU0_PVCC1")
		)
		(pad "2" smd circle
			(at -0.40005 0 90)
			(size 0 0)
			(layers "B.Cu" "B.Mask" "B.Paste")
			(net "PVCCFA_EHV_FIVRA_CPU0_VDD1")
		)
	)
	(footprint ""
		(layer "B.Cu")
		(at 206.955898 -193.37401)
		(property "Reference" "U21"
			(at 0.22606 1.93167 0)
			(unlocked yes)
			(layer "B.SilkS")
			(effects
				(font
					(size 0.7874 0.5842)
					(thickness 0.1524)
				)
				(justify mirror)
			)
		)
		(property "Value" ""
			(at 0 0 0)
			(layer "B.Fab")
			(effects
				(font
					(size 1.27 1.27)
				)
				(justify mirror)
			)
		)
		(duplicate_pad_numbers_are_jumpers no)
		(fp_line
			(start -1.7272 -1.1176)
			(end -1.7272 1.1176)
			(stroke
				(width 0.1524)
				(type default)
			)
			(layer "B.SilkS")
		)
		(fp_line
			(start -1.7272 -1.1176)
			(end -0.254 -1.1176)
			(stroke
				(width 0.1524)
				(type default)
			)
			(layer "B.SilkS")
		)
		(fp_line
			(start -1.7272 1.1176)
			(end 1.7272 1.1176)
			(stroke
				(width 0.1524)
				(type default)
			)
			(layer "B.SilkS")
		)
		(fp_line
			(start -0.254 -1.1176)
			(end 0 -0.7366)
			(stroke
				(width 0.1524)
				(type default)
			)
			(layer "B.SilkS")
		)
		(fp_line
			(start 0 -0.7366)
			(end 0.254 -1.1176)
			(stroke
				(width 0.1524)
				(type default)
			)
			(layer "B.SilkS")
		)
		(fp_line
			(start 0.254 -1.1176)
			(end 1.7272 -1.1176)
			(stroke
				(width 0.1524)
				(type default)
			)
			(layer "B.SilkS")
		)
		(fp_line
			(start 1.7272 1.1176)
			(end 1.7272 -1.1176)
			(stroke
				(width 0.1524)
				(type default)
			)
			(layer "B.SilkS")
		)
		(fp_poly
			(pts
				(xy 1.064514 -1.395476) (xy 0.683514 -2.157476) (xy 1.445514 -2.157476)
			)
			(stroke
				(width 0)
				(type default)
			)
			(fill yes)
			(layer "B.SilkS")
		)
		(fp_line
			(start -1.5748 -1.1176)
			(end 1.5748 -1.1176)
			(stroke
				(width 0.1)
				(type default)
			)
			(layer "B.Fab")
		)
		(fp_line
			(start -1.5748 1.1176)
			(end -1.5748 -1.1176)
			(stroke
				(width 0.1)
				(type default)
			)
			(layer "B.Fab")
		)
		(fp_line
			(start 1.5748 -1.1176)
			(end 1.5748 1.1176)
			(stroke
				(width 0.1)
				(type default)
			)
			(layer "B.Fab")
		)
		(fp_line
			(start 1.5748 1.1176)
			(end -1.5748 1.1176)
			(stroke
				(width 0.1)
				(type default)
			)
			(layer "B.Fab")
		)
		(fp_poly
			(pts
				(xy 1.9558 -0.649986) (xy 2.7178 -0.268986) (xy 2.7178 -1.030986)
			)
			(stroke
				(width 0)
				(type default)
			)
			(fill yes)
			(layer "B.Fab")
		)
		(pad "1" smd rect
			(at 0.999998 -0.649986 270)
			(size 0.3556 1.1176)
			(layers "B.Cu" "B.Mask" "B.Paste")
			(net "JTAG_MUX_CPU1_GTL_TDI")
		)
		(pad "2" smd rect
			(at 0.999998 0 270)
			(size 0.3556 1.1176)
			(layers "B.Cu" "B.Mask" "B.Paste")
			(net "GND")
		)
		(pad "3" smd rect
			(at 0.999998 0.649986 270)
			(size 0.3556 1.1176)
			(layers "B.Cu" "B.Mask" "B.Paste")
			(net "JTAG_MUX_CPU0_GTL_TDI")
		)
		(pad "4" smd rect
			(at -0.999998 0.649986 270)
			(size 0.3556 1.1176)
			(layers "B.Cu" "B.Mask" "B.Paste")
			(net "JTAG_QS_MUX_GTL_TDI")
		)
		(pad "5" smd rect
			(at -0.999998 0 270)
			(size 0.3556 1.1176)
			(layers "B.Cu" "B.Mask" "B.Paste")
			(net "P3V3_AUX")
		)
		(pad "6" smd rect
			(at -0.999998 -0.649986 270)
			(size 0.3556 1.1176)
			(layers "B.Cu" "B.Mask" "B.Paste")
			(net "FM_CPU0_SKTOCC_N")
		)
	)
	(footprint ""
		(layer "B.Cu")
		(at 106.661712 -337.607402 -90)
		(property "Reference" "PC568_P1_2"
			(at 0 0 90)
			(layer "B.SilkS")
			(hide yes)
			(effects
				(font
					(size 1.27 1.27)
				)
				(justify mirror)
			)
		)
		(property "Value" ""
			(at 0 0 90)
			(layer "B.Fab")
			(effects
				(font
					(size 1.27 1.27)
				)
				(justify mirror)
			)
		)
		(duplicate_pad_numbers_are_jumpers no)
		(fp_line
			(start -1.524 0.762)
			(end 1.524 0.762)
			(stroke
				(width 0.1524)
				(type default)
			)
			(layer "B.SilkS")
		)
		(fp_line
			(start 1.524 0.762)
			(end 1.524 -0.762)
			(stroke
				(width 0.1524)
				(type default)
			)
			(layer "B.SilkS")
		)
		(fp_line
			(start -1.524 -0.762)
			(end -1.524 0.762)
			(stroke
				(width 0.1524)
				(type default)
			)
			(layer "B.SilkS")
		)
		(fp_line
			(start 1.524 -0.762)
			(end -1.524 -0.762)
			(stroke
				(width 0.1524)
				(type default)
			)
			(layer "B.SilkS")
		)
		(fp_line
			(start -1.1049 0.724916)
			(end -1.1049 -0.724916)
			(stroke
				(width 0.1)
				(type default)
			)
			(layer "B.Fab")
		)
		(fp_line
			(start 1.1049 0.724916)
			(end -1.1049 0.724916)
			(stroke
				(width 0.1)
				(type default)
			)
			(layer "B.Fab")
		)
		(fp_line
			(start -1.1049 -0.724916)
			(end 1.1049 -0.724916)
			(stroke
				(width 0.1)
				(type default)
			)
			(layer "B.Fab")
		)
		(fp_line
			(start 1.1049 -0.724916)
			(end 1.1049 0.724916)
			(stroke
				(width 0.1)
				(type default)
			)
			(layer "B.Fab")
		)
		(pad "1" smd rect
			(at 0.889 0 270)
			(size 1.016 1.27)
			(layers "B.Cu" "B.Mask" "B.Paste")
			(net "SW_P12V_PVCCIN_CPU1_FLT")
		)
		(pad "2" smd rect
			(at -0.889 0 270)
			(size 1.016 1.27)
			(layers "B.Cu" "B.Mask" "B.Paste")
			(net "GND")
		)
	)
	(footprint ""
		(layer "B.Cu")
		(at 329.646534 -25.803352 -90)
		(property "Reference" "R1310"
			(at 0 0 90)
			(layer "B.SilkS")
			(hide yes)
			(effects
				(font
					(size 1.27 1.27)
				)
				(justify mirror)
			)
		)
		(property "Value" ""
			(at 0 0 90)
			(layer "B.Fab")
			(effects
				(font
					(size 1.27 1.27)
				)
				(justify mirror)
			)
		)
		(duplicate_pad_numbers_are_jumpers no)
		(fp_line
			(start -0.7874 0.4064)
			(end 0.7874 0.4064)
			(stroke
				(width 0.1524)
				(type default)
			)
			(layer "B.SilkS")
		)
		(fp_line
			(start 0.7874 0.4064)
			(end 0.7874 -0.4064)
			(stroke
				(width 0.1524)
				(type default)
			)
			(layer "B.SilkS")
		)
		(fp_line
			(start -0.7874 -0.4064)
			(end -0.7874 0.4064)
			(stroke
				(width 0.1524)
				(type default)
			)
			(layer "B.SilkS")
		)
		(fp_line
			(start 0.7874 -0.4064)
			(end -0.7874 -0.4064)
			(stroke
				(width 0.1524)
				(type default)
			)
			(layer "B.SilkS")
		)
		(fp_line
			(start -0.67945 0.3048)
			(end -0.120396 0.3048)
			(stroke
				(width 0.1)
				(type default)
			)
			(layer "B.Fab")
		)
		(fp_line
			(start -0.120396 0.3048)
			(end -0.120396 0.2794)
			(stroke
				(width 0.1)
				(type default)
			)
			(layer "B.Fab")
		)
		(fp_line
			(start 0.12065 0.3048)
			(end 0.67945 0.3048)
			(stroke
				(width 0.1)
				(type default)
			)
			(layer "B.Fab")
		)
		(fp_line
			(start 0.67945 0.3048)
			(end 0.67945 -0.305054)
			(stroke
				(width 0.1)
				(type default)
			)
			(layer "B.Fab")
		)
		(fp_line
			(start -0.120396 0.2794)
			(end 0.12065 0.2794)
			(stroke
				(width 0.1)
				(type default)
			)
			(layer "B.Fab")
		)
		(fp_line
			(start 0.12065 0.2794)
			(end 0.12065 0.3048)
			(stroke
				(width 0.1)
				(type default)
			)
			(layer "B.Fab")
		)
		(fp_line
			(start -0.12065 -0.2794)
			(end -0.12065 -0.3048)
			(stroke
				(width 0.1)
				(type default)
			)
			(layer "B.Fab")
		)
		(fp_line
			(start 0.12065 -0.2794)
			(end -0.12065 -0.2794)
			(stroke
				(width 0.1)
				(type default)
			)
			(layer "B.Fab")
		)
		(fp_line
			(start -0.67945 -0.3048)
			(end -0.67945 0.3048)
			(stroke
				(width 0.1)
				(type default)
			)
			(layer "B.Fab")
		)
		(fp_line
			(start -0.12065 -0.3048)
			(end -0.67945 -0.3048)
			(stroke
				(width 0.1)
				(type default)
			)
			(layer "B.Fab")
		)
		(fp_line
			(start 0.12065 -0.305054)
			(end 0.12065 -0.2794)
			(stroke
				(width 0.1)
				(type default)
			)
			(layer "B.Fab")
		)
		(fp_line
			(start 0.67945 -0.305054)
			(end 0.12065 -0.305054)
			(stroke
				(width 0.1)
				(type default)
			)
			(layer "B.Fab")
		)
		(pad "1" smd circle
			(at 0.40005 0 90)
			(size 0 0)
			(layers "B.Cu" "B.Mask" "B.Paste")
			(net "IRQ_PCH_CPU_NMI_EVENT_R_N")
		)
		(pad "2" smd circle
			(at -0.40005 0 90)
			(size 0 0)
			(layers "B.Cu" "B.Mask" "B.Paste")
			(net "IRQ_PCH_CPU_NMI_EVENT_N")
		)
	)
	(footprint ""
		(layer "B.Cu")
		(at 353.535742 -262.348726)
		(property "Reference" "C356"
			(at 0 0 0)
			(layer "B.SilkS")
			(hide yes)
			(effects
				(font
					(size 1.27 1.27)
				)
				(justify mirror)
			)
		)
		(property "Value" ""
			(at 0 0 0)
			(layer "B.Fab")
			(effects
				(font
					(size 1.27 1.27)
				)
				(justify mirror)
			)
		)
		(duplicate_pad_numbers_are_jumpers no)
		(fp_line
			(start -1.524 -0.762)
			(end -1.524 0.762)
			(stroke
				(width 0.1524)
				(type default)
			)
			(layer "B.SilkS")
		)
		(fp_line
			(start -1.524 0.762)
			(end 1.524 0.762)
			(stroke
				(width 0.1524)
				(type default)
			)
			(layer "B.SilkS")
		)
		(fp_line
			(start 1.524 -0.762)
			(end -1.524 -0.762)
			(stroke
				(width 0.1524)
				(type default)
			)
			(layer "B.SilkS")
		)
		(fp_line
			(start 1.524 0.762)
			(end 1.524 -0.762)
			(stroke
				(width 0.1524)
				(type default)
			)
			(layer "B.SilkS")
		)
		(fp_line
			(start -1.1049 -0.724916)
			(end 1.1049 -0.724916)
			(stroke
				(width 0.1)
				(type default)
			)
			(layer "B.Fab")
		)
		(fp_line
			(start -1.1049 0.724916)
			(end -1.1049 -0.724916)
			(stroke
				(width 0.1)
				(type default)
			)
			(layer "B.Fab")
		)
		(fp_line
			(start 1.1049 -0.724916)
			(end 1.1049 0.724916)
			(stroke
				(width 0.1)
				(type default)
			)
			(layer "B.Fab")
		)
		(fp_line
			(start 1.1049 0.724916)
			(end -1.1049 0.724916)
			(stroke
				(width 0.1)
				(type default)
			)
			(layer "B.Fab")
		)
		(pad "1" smd rect
			(at 0.889 0)
			(size 1.016 1.27)
			(layers "B.Cu" "B.Mask" "B.Paste")
			(net "PVCCIN_CPU0")
		)
		(pad "2" smd rect
			(at -0.889 0)
			(size 1.016 1.27)
			(layers "B.Cu" "B.Mask" "B.Paste")
			(net "GND")
		)
	)
	(footprint ""
		(layer "B.Cu")
		(at 95.614998 -324.753986 -90)
		(property "Reference" "PC576_P1_1"
			(at 0 0 90)
			(layer "B.SilkS")
			(hide yes)
			(effects
				(font
					(size 1.27 1.27)
				)
				(justify mirror)
			)
		)
		(property "Value" ""
			(at 0 0 90)
			(layer "B.Fab")
			(effects
				(font
					(size 1.27 1.27)
				)
				(justify mirror)
			)
		)
		(duplicate_pad_numbers_are_jumpers no)
		(fp_line
			(start -1.524 0.762)
			(end 1.524 0.762)
			(stroke
				(width 0.1524)
				(type default)
			)
			(layer "B.SilkS")
		)
		(fp_line
			(start 1.524 0.762)
			(end 1.524 -0.762)
			(stroke
				(width 0.1524)
				(type default)
			)
			(layer "B.SilkS")
		)
		(fp_line
			(start -1.524 -0.762)
			(end -1.524 0.762)
			(stroke
				(width 0.1524)
				(type default)
			)
			(layer "B.SilkS")
		)
		(fp_line
			(start 1.524 -0.762)
			(end -1.524 -0.762)
			(stroke
				(width 0.1524)
				(type default)
			)
			(layer "B.SilkS")
		)
		(fp_line
			(start -1.1049 0.724916)
			(end -1.1049 -0.724916)
			(stroke
				(width 0.1)
				(type default)
			)
			(layer "B.Fab")
		)
		(fp_line
			(start 1.1049 0.724916)
			(end -1.1049 0.724916)
			(stroke
				(width 0.1)
				(type default)
			)
			(layer "B.Fab")
		)
		(fp_line
			(start -1.1049 -0.724916)
			(end 1.1049 -0.724916)
			(stroke
				(width 0.1)
				(type default)
			)
			(layer "B.Fab")
		)
		(fp_line
			(start 1.1049 -0.724916)
			(end 1.1049 0.724916)
			(stroke
				(width 0.1)
				(type default)
			)
			(layer "B.Fab")
		)
		(pad "1" smd rect
			(at 0.889 0 270)
			(size 1.016 1.27)
			(layers "B.Cu" "B.Mask" "B.Paste")
			(net "PVCCIN_CPU1")
		)
		(pad "2" smd rect
			(at -0.889 0 270)
			(size 1.016 1.27)
			(layers "B.Cu" "B.Mask" "B.Paste")
			(net "GND")
		)
	)
	(footprint ""
		(layer "B.Cu")
		(at 433.14874 -313.913266 180)
		(property "Reference" "D44"
			(at 2.36474 0.731012 0)
			(unlocked yes)
			(layer "B.SilkS")
			(effects
				(font
					(size 0.7874 0.5842)
					(thickness 0.1524)
				)
				(justify left mirror)
			)
		)
		(property "Value" ""
			(at 0 0 0)
			(layer "B.Fab")
			(effects
				(font
					(size 1.27 1.27)
				)
				(justify mirror)
			)
		)
		(duplicate_pad_numbers_are_jumpers no)
		(fp_line
			(start 2.050796 0.700024)
			(end 2.050796 -0.700024)
			(stroke
				(width 0.1524)
				(type default)
			)
			(layer "B.SilkS")
		)
		(fp_line
			(start 2.050796 -0.700024)
			(end -2.050796 -0.700024)
			(stroke
				(width 0.1524)
				(type default)
			)
			(layer "B.SilkS")
		)
		(fp_line
			(start 0.30607 0.500126)
			(end -0.193802 0)
			(stroke
				(width 0.1524)
				(type default)
			)
			(layer "B.SilkS")
		)
		(fp_line
			(start 0.30607 -0.500126)
			(end 0.30607 0.500126)
			(stroke
				(width 0.1524)
				(type default)
			)
			(layer "B.SilkS")
		)
		(fp_line
			(start -0.193802 0)
			(end 0.30607 -0.500126)
			(stroke
				(width 0.1524)
				(type default)
			)
			(layer "B.SilkS")
		)
		(fp_line
			(start -0.293878 -0.500126)
			(end -0.293878 0.500126)
			(stroke
				(width 0.1524)
				(type default)
			)
			(layer "B.SilkS")
		)
		(fp_line
			(start -2.050796 0.700024)
			(end 2.050796 0.700024)
			(stroke
				(width 0.1524)
				(type default)
			)
			(layer "B.SilkS")
		)
		(fp_line
			(start -2.050796 -0.700024)
			(end -2.050796 0.700024)
			(stroke
				(width 0.1524)
				(type default)
			)
			(layer "B.SilkS")
		)
		(fp_line
			(start -2.051304 0.6985)
			(end -2.051304 0.635)
			(stroke
				(width 0.1524)
				(type default)
			)
			(layer "B.SilkS")
		)
		(fp_line
			(start -2.051304 0.635)
			(end -2.152904 0.635)
			(stroke
				(width 0.1524)
				(type default)
			)
			(layer "B.SilkS")
		)
		(fp_line
			(start -2.064004 -0.6731)
			(end -2.064004 -0.6985)
			(stroke
				(width 0.1524)
				(type default)
			)
			(layer "B.SilkS")
		)
		(fp_line
			(start -2.064004 -0.6985)
			(end -2.229104 -0.6985)
			(stroke
				(width 0.1524)
				(type default)
			)
			(layer "B.SilkS")
		)
		(fp_line
			(start -2.152904 0.635)
			(end -2.152904 -0.6985)
			(stroke
				(width 0.1524)
				(type default)
			)
			(layer "B.SilkS")
		)
		(fp_line
			(start -2.152904 -0.6985)
			(end -2.343404 -0.6985)
			(stroke
				(width 0.1524)
				(type default)
			)
			(layer "B.SilkS")
		)
		(fp_line
			(start -2.229104 0.6985)
			(end -2.051304 0.6985)
			(stroke
				(width 0.1524)
				(type default)
			)
			(layer "B.SilkS")
		)
		(fp_line
			(start -2.229104 -0.6985)
			(end -2.229104 0.6985)
			(stroke
				(width 0.1524)
				(type default)
			)
			(layer "B.SilkS")
		)
		(fp_line
			(start -2.343404 0.6985)
			(end -2.216404 0.6985)
			(stroke
				(width 0.1524)
				(type default)
			)
			(layer "B.SilkS")
		)
		(fp_line
			(start -2.343404 -0.6985)
			(end -2.343404 0.6985)
			(stroke
				(width 0.1524)
				(type default)
			)
			(layer "B.SilkS")
		)
		(fp_line
			(start 0.899922 0.700024)
			(end 0.899922 -0.700024)
			(stroke
				(width 0.1)
				(type default)
			)
			(layer "B.Fab")
		)
		(fp_line
			(start 0.899922 -0.700024)
			(end -0.899922 -0.700024)
			(stroke
				(width 0.1)
				(type default)
			)
			(layer "B.Fab")
		)
		(fp_line
			(start -0.899922 0.700024)
			(end 0.899922 0.700024)
			(stroke
				(width 0.1)
				(type default)
			)
			(layer "B.Fab")
		)
		(fp_line
			(start -0.899922 -0.700024)
			(end -0.899922 0.700024)
			(stroke
				(width 0.1)
				(type default)
			)
			(layer "B.Fab")
		)
		(fp_text user "+"
			(at 3.72999 0.503682 90)
			(unlocked yes)
			(layer "B.SilkS")
			(effects
				(font
					(size 1.905 1.4224)
					(thickness 0.1524)
				)
				(justify left mirror)
			)
		)
		(fp_text user "-"
			(at -4.261104 0.10795 0)
			(unlocked yes)
			(layer "B.SilkS")
			(effects
				(font
					(size 1.905 1.4224)
					(thickness 0.1524)
				)
				(justify left mirror)
			)
		)
		(fp_text user "+"
			(at 3.123946 0.762 90)
			(unlocked yes)
			(layer "B.Fab")
			(effects
				(font
					(size 1.905 1.4224)
					(thickness 0.1524)
				)
				(justify left mirror)
			)
		)
		(fp_text user "-"
			(at -3.880104 0.23495 0)
			(unlocked yes)
			(layer "B.Fab")
			(effects
				(font
					(size 1.905 1.4224)
					(thickness 0.1524)
				)
				(justify left mirror)
			)
		)
		(pad "1" smd rect
			(at 1.199896 0 90)
			(size 0.6604 1.3716)
			(layers "B.Cu" "B.Mask" "B.Paste")
			(net "PWRGD_FAIL_CPU0_EF_R1")
		)
		(pad "2" smd rect
			(at -1.199896 0 270)
			(size 0.6604 1.3716)
			(layers "B.Cu" "B.Mask" "B.Paste")
			(net "P3V3_AUX")
		)
	)
	(footprint ""
		(layer "B.Cu")
		(at 228.114098 -117.960648 -90)
		(property "Reference" "R4517"
			(at 0 0 90)
			(layer "B.SilkS")
			(hide yes)
			(effects
				(font
					(size 1.27 1.27)
				)
				(justify mirror)
			)
		)
		(property "Value" ""
			(at 0 0 90)
			(layer "B.Fab")
			(effects
				(font
					(size 1.27 1.27)
				)
				(justify mirror)
			)
		)
		(duplicate_pad_numbers_are_jumpers no)
		(fp_line
			(start -0.7874 0.4064)
			(end 0.7874 0.4064)
			(stroke
				(width 0.1524)
				(type default)
			)
			(layer "B.SilkS")
		)
		(fp_line
			(start 0.7874 0.4064)
			(end 0.7874 -0.4064)
			(stroke
				(width 0.1524)
				(type default)
			)
			(layer "B.SilkS")
		)
		(fp_line
			(start -0.7874 -0.4064)
			(end -0.7874 0.4064)
			(stroke
				(width 0.1524)
				(type default)
			)
			(layer "B.SilkS")
		)
		(fp_line
			(start 0.7874 -0.4064)
			(end -0.7874 -0.4064)
			(stroke
				(width 0.1524)
				(type default)
			)
			(layer "B.SilkS")
		)
		(fp_line
			(start -0.67945 0.3048)
			(end -0.120396 0.3048)
			(stroke
				(width 0.1)
				(type default)
			)
			(layer "B.Fab")
		)
		(fp_line
			(start -0.120396 0.3048)
			(end -0.120396 0.2794)
			(stroke
				(width 0.1)
				(type default)
			)
			(layer "B.Fab")
		)
		(fp_line
			(start 0.12065 0.3048)
			(end 0.67945 0.3048)
			(stroke
				(width 0.1)
				(type default)
			)
			(layer "B.Fab")
		)
		(fp_line
			(start 0.67945 0.3048)
			(end 0.67945 -0.305054)
			(stroke
				(width 0.1)
				(type default)
			)
			(layer "B.Fab")
		)
		(fp_line
			(start -0.120396 0.2794)
			(end 0.12065 0.2794)
			(stroke
				(width 0.1)
				(type default)
			)
			(layer "B.Fab")
		)
		(fp_line
			(start 0.12065 0.2794)
			(end 0.12065 0.3048)
			(stroke
				(width 0.1)
				(type default)
			)
			(layer "B.Fab")
		)
		(fp_line
			(start -0.12065 -0.2794)
			(end -0.12065 -0.3048)
			(stroke
				(width 0.1)
				(type default)
			)
			(layer "B.Fab")
		)
		(fp_line
			(start 0.12065 -0.2794)
			(end -0.12065 -0.2794)
			(stroke
				(width 0.1)
				(type default)
			)
			(layer "B.Fab")
		)
		(fp_line
			(start -0.67945 -0.3048)
			(end -0.67945 0.3048)
			(stroke
				(width 0.1)
				(type default)
			)
			(layer "B.Fab")
		)
		(fp_line
			(start -0.12065 -0.3048)
			(end -0.67945 -0.3048)
			(stroke
				(width 0.1)
				(type default)
			)
			(layer "B.Fab")
		)
		(fp_line
			(start 0.12065 -0.305054)
			(end 0.12065 -0.2794)
			(stroke
				(width 0.1)
				(type default)
			)
			(layer "B.Fab")
		)
		(fp_line
			(start 0.67945 -0.305054)
			(end 0.12065 -0.305054)
			(stroke
				(width 0.1)
				(type default)
			)
			(layer "B.Fab")
		)
		(pad "1" smd circle
			(at 0.40005 0 90)
			(size 0 0)
			(layers "B.Cu" "B.Mask" "B.Paste")
			(net "P3V3")
		)
		(pad "2" smd circle
			(at -0.40005 0 90)
			(size 0 0)
			(layers "B.Cu" "B.Mask" "B.Paste")
			(net "OCP_SFF_CLK_OE_N")
		)
	)
	(footprint ""
		(layer "B.Cu")
		(at 80.35163 -52.482496 90)
		(property "Reference" "R3832"
			(at 0 0 90)
			(layer "B.SilkS")
			(hide yes)
			(effects
				(font
					(size 1.27 1.27)
				)
				(justify mirror)
			)
		)
		(property "Value" ""
			(at 0 0 90)
			(layer "B.Fab")
			(effects
				(font
					(size 1.27 1.27)
				)
				(justify mirror)
			)
		)
		(duplicate_pad_numbers_are_jumpers no)
		(fp_line
			(start 0.7874 -0.4064)
			(end -0.7874 -0.4064)
			(stroke
				(width 0.1524)
				(type default)
			)
			(layer "B.SilkS")
		)
		(fp_line
			(start -0.7874 -0.4064)
			(end -0.7874 0.4064)
			(stroke
				(width 0.1524)
				(type default)
			)
			(layer "B.SilkS")
		)
		(fp_line
			(start 0.7874 0.4064)
			(end 0.7874 -0.4064)
			(stroke
				(width 0.1524)
				(type default)
			)
			(layer "B.SilkS")
		)
		(fp_line
			(start -0.7874 0.4064)
			(end 0.7874 0.4064)
			(stroke
				(width 0.1524)
				(type default)
			)
			(layer "B.SilkS")
		)
		(fp_line
			(start 0.67945 -0.305054)
			(end 0.12065 -0.305054)
			(stroke
				(width 0.1)
				(type default)
			)
			(layer "B.Fab")
		)
		(fp_line
			(start 0.12065 -0.305054)
			(end 0.12065 -0.2794)
			(stroke
				(width 0.1)
				(type default)
			)
			(layer "B.Fab")
		)
		(fp_line
			(start -0.12065 -0.3048)
			(end -0.67945 -0.3048)
			(stroke
				(width 0.1)
				(type default)
			)
			(layer "B.Fab")
		)
		(fp_line
			(start -0.67945 -0.3048)
			(end -0.67945 0.3048)
			(stroke
				(width 0.1)
				(type default)
			)
			(layer "B.Fab")
		)
		(fp_line
			(start 0.12065 -0.2794)
			(end -0.12065 -0.2794)
			(stroke
				(width 0.1)
				(type default)
			)
			(layer "B.Fab")
		)
		(fp_line
			(start -0.12065 -0.2794)
			(end -0.12065 -0.3048)
			(stroke
				(width 0.1)
				(type default)
			)
			(layer "B.Fab")
		)
		(fp_line
			(start 0.12065 0.2794)
			(end 0.12065 0.3048)
			(stroke
				(width 0.1)
				(type default)
			)
			(layer "B.Fab")
		)
		(fp_line
			(start -0.120396 0.2794)
			(end 0.12065 0.2794)
			(stroke
				(width 0.1)
				(type default)
			)
			(layer "B.Fab")
		)
		(fp_line
			(start 0.67945 0.3048)
			(end 0.67945 -0.305054)
			(stroke
				(width 0.1)
				(type default)
			)
			(layer "B.Fab")
		)
		(fp_line
			(start 0.12065 0.3048)
			(end 0.67945 0.3048)
			(stroke
				(width 0.1)
				(type default)
			)
			(layer "B.Fab")
		)
		(fp_line
			(start -0.120396 0.3048)
			(end -0.120396 0.2794)
			(stroke
				(width 0.1)
				(type default)
			)
			(layer "B.Fab")
		)
		(fp_line
			(start -0.67945 0.3048)
			(end -0.120396 0.3048)
			(stroke
				(width 0.1)
				(type default)
			)
			(layer "B.Fab")
		)
		(pad "1" smd circle
			(at 0.40005 0 270)
			(size 0 0)
			(layers "B.Cu" "B.Mask" "B.Paste")
			(net "P3V3_OCP_PWRGD_2")
		)
		(pad "2" smd circle
			(at -0.40005 0 270)
			(size 0 0)
			(layers "B.Cu" "B.Mask" "B.Paste")
			(net "OCP_V3_2_P3V3_PWRGD")
		)
	)
	(footprint ""
		(layer "B.Cu")
		(at 407.0731 -317.25108 90)
		(property "Reference" "R3884"
			(at 0 0 90)
			(layer "B.SilkS")
			(hide yes)
			(effects
				(font
					(size 1.27 1.27)
				)
				(justify mirror)
			)
		)
		(property "Value" ""
			(at 0 0 90)
			(layer "B.Fab")
			(effects
				(font
					(size 1.27 1.27)
				)
				(justify mirror)
			)
		)
		(duplicate_pad_numbers_are_jumpers no)
		(fp_line
			(start 0.7874 -0.4064)
			(end -0.7874 -0.4064)
			(stroke
				(width 0.1524)
				(type default)
			)
			(layer "B.SilkS")
		)
		(fp_line
			(start -0.7874 -0.4064)
			(end -0.7874 0.4064)
			(stroke
				(width 0.1524)
				(type default)
			)
			(layer "B.SilkS")
		)
		(fp_line
			(start 0.7874 0.4064)
			(end 0.7874 -0.4064)
			(stroke
				(width 0.1524)
				(type default)
			)
			(layer "B.SilkS")
		)
		(fp_line
			(start -0.7874 0.4064)
			(end 0.7874 0.4064)
			(stroke
				(width 0.1524)
				(type default)
			)
			(layer "B.SilkS")
		)
		(fp_line
			(start 0.67945 -0.305054)
			(end 0.12065 -0.305054)
			(stroke
				(width 0.1)
				(type default)
			)
			(layer "B.Fab")
		)
		(fp_line
			(start 0.12065 -0.305054)
			(end 0.12065 -0.2794)
			(stroke
				(width 0.1)
				(type default)
			)
			(layer "B.Fab")
		)
		(fp_line
			(start -0.12065 -0.3048)
			(end -0.67945 -0.3048)
			(stroke
				(width 0.1)
				(type default)
			)
			(layer "B.Fab")
		)
		(fp_line
			(start -0.67945 -0.3048)
			(end -0.67945 0.3048)
			(stroke
				(width 0.1)
				(type default)
			)
			(layer "B.Fab")
		)
		(fp_line
			(start 0.12065 -0.2794)
			(end -0.12065 -0.2794)
			(stroke
				(width 0.1)
				(type default)
			)
			(layer "B.Fab")
		)
		(fp_line
			(start -0.12065 -0.2794)
			(end -0.12065 -0.3048)
			(stroke
				(width 0.1)
				(type default)
			)
			(layer "B.Fab")
		)
		(fp_line
			(start 0.12065 0.2794)
			(end 0.12065 0.3048)
			(stroke
				(width 0.1)
				(type default)
			)
			(layer "B.Fab")
		)
		(fp_line
			(start -0.120396 0.2794)
			(end 0.12065 0.2794)
			(stroke
				(width 0.1)
				(type default)
			)
			(layer "B.Fab")
		)
		(fp_line
			(start 0.67945 0.3048)
			(end 0.67945 -0.305054)
			(stroke
				(width 0.1)
				(type default)
			)
			(layer "B.Fab")
		)
		(fp_line
			(start 0.12065 0.3048)
			(end 0.67945 0.3048)
			(stroke
				(width 0.1)
				(type default)
			)
			(layer "B.Fab")
		)
		(fp_line
			(start -0.120396 0.3048)
			(end -0.120396 0.2794)
			(stroke
				(width 0.1)
				(type default)
			)
			(layer "B.Fab")
		)
		(fp_line
			(start -0.67945 0.3048)
			(end -0.120396 0.3048)
			(stroke
				(width 0.1)
				(type default)
			)
			(layer "B.Fab")
		)
		(pad "1" smd circle
			(at 0.40005 0 270)
			(size 0 0)
			(layers "B.Cu" "B.Mask" "B.Paste")
			(net "I3C_SPD_DDREFGH_CPU0_LVC1_SCL_1")
		)
		(pad "2" smd circle
			(at -0.40005 0 270)
			(size 0 0)
			(layers "B.Cu" "B.Mask" "B.Paste")
			(net "I3C_SPD_DDREFGH_CPU0_LVC1_SCL")
		)
	)
	(footprint ""
		(layer "B.Cu")
		(at 35.586416 -395.243558 -90)
		(property "Reference" "C2355"
			(at 0 0 90)
			(layer "B.SilkS")
			(hide yes)
			(effects
				(font
					(size 1.27 1.27)
				)
				(justify mirror)
			)
		)
		(property "Value" ""
			(at 0 0 90)
			(layer "B.Fab")
			(effects
				(font
					(size 1.27 1.27)
				)
				(justify mirror)
			)
		)
		(duplicate_pad_numbers_are_jumpers no)
		(fp_line
			(start -0.7874 0.4064)
			(end 0.7874 0.4064)
			(stroke
				(width 0.1524)
				(type default)
			)
			(layer "B.SilkS")
		)
		(fp_line
			(start 0.7874 0.4064)
			(end 0.7874 -0.4064)
			(stroke
				(width 0.1524)
				(type default)
			)
			(layer "B.SilkS")
		)
		(fp_line
			(start -0.7874 -0.4064)
			(end -0.7874 0.4064)
			(stroke
				(width 0.1524)
				(type default)
			)
			(layer "B.SilkS")
		)
		(fp_line
			(start 0.7874 -0.4064)
			(end -0.7874 -0.4064)
			(stroke
				(width 0.1524)
				(type default)
			)
			(layer "B.SilkS")
		)
		(fp_line
			(start -0.67945 0.3048)
			(end -0.120396 0.3048)
			(stroke
				(width 0.1)
				(type default)
			)
			(layer "B.Fab")
		)
		(fp_line
			(start -0.120396 0.3048)
			(end -0.120396 0.2794)
			(stroke
				(width 0.1)
				(type default)
			)
			(layer "B.Fab")
		)
		(fp_line
			(start 0.12065 0.3048)
			(end 0.67945 0.3048)
			(stroke
				(width 0.1)
				(type default)
			)
			(layer "B.Fab")
		)
		(fp_line
			(start 0.67945 0.3048)
			(end 0.67945 -0.305054)
			(stroke
				(width 0.1)
				(type default)
			)
			(layer "B.Fab")
		)
		(fp_line
			(start -0.120396 0.2794)
			(end 0.12065 0.2794)
			(stroke
				(width 0.1)
				(type default)
			)
			(layer "B.Fab")
		)
		(fp_line
			(start 0.12065 0.2794)
			(end 0.12065 0.3048)
			(stroke
				(width 0.1)
				(type default)
			)
			(layer "B.Fab")
		)
		(fp_line
			(start -0.12065 -0.2794)
			(end -0.12065 -0.3048)
			(stroke
				(width 0.1)
				(type default)
			)
			(layer "B.Fab")
		)
		(fp_line
			(start 0.12065 -0.2794)
			(end -0.12065 -0.2794)
			(stroke
				(width 0.1)
				(type default)
			)
			(layer "B.Fab")
		)
		(fp_line
			(start -0.67945 -0.3048)
			(end -0.67945 0.3048)
			(stroke
				(width 0.1)
				(type default)
			)
			(layer "B.Fab")
		)
		(fp_line
			(start -0.12065 -0.3048)
			(end -0.67945 -0.3048)
			(stroke
				(width 0.1)
				(type default)
			)
			(layer "B.Fab")
		)
		(fp_line
			(start 0.12065 -0.305054)
			(end 0.12065 -0.2794)
			(stroke
				(width 0.1)
				(type default)
			)
			(layer "B.Fab")
		)
		(fp_line
			(start 0.67945 -0.305054)
			(end 0.12065 -0.305054)
			(stroke
				(width 0.1)
				(type default)
			)
			(layer "B.Fab")
		)
		(pad "1" smd circle
			(at 0.40005 0 90)
			(size 0 0)
			(layers "B.Cu" "B.Mask" "B.Paste")
			(net "P3V3_AUX")
		)
		(pad "2" smd circle
			(at -0.40005 0 90)
			(size 0 0)
			(layers "B.Cu" "B.Mask" "B.Paste")
			(net "GND")
		)
	)
	(footprint ""
		(layer "B.Cu")
		(at 162.825176 -258.399534 -90)
		(property "Reference" "C479"
			(at 0 0 90)
			(layer "B.SilkS")
			(hide yes)
			(effects
				(font
					(size 1.27 1.27)
				)
				(justify mirror)
			)
		)
		(property "Value" ""
			(at 0 0 90)
			(layer "B.Fab")
			(effects
				(font
					(size 1.27 1.27)
				)
				(justify mirror)
			)
		)
		(duplicate_pad_numbers_are_jumpers no)
		(fp_line
			(start -1.524 0.762)
			(end 1.524 0.762)
			(stroke
				(width 0.1524)
				(type default)
			)
			(layer "B.SilkS")
		)
		(fp_line
			(start 1.524 0.762)
			(end 1.524 -0.762)
			(stroke
				(width 0.1524)
				(type default)
			)
			(layer "B.SilkS")
		)
		(fp_line
			(start -1.524 -0.762)
			(end -1.524 0.762)
			(stroke
				(width 0.1524)
				(type default)
			)
			(layer "B.SilkS")
		)
		(fp_line
			(start 1.524 -0.762)
			(end -1.524 -0.762)
			(stroke
				(width 0.1524)
				(type default)
			)
			(layer "B.SilkS")
		)
		(fp_line
			(start -1.1049 0.724916)
			(end -1.1049 -0.724916)
			(stroke
				(width 0.1)
				(type default)
			)
			(layer "B.Fab")
		)
		(fp_line
			(start 1.1049 0.724916)
			(end -1.1049 0.724916)
			(stroke
				(width 0.1)
				(type default)
			)
			(layer "B.Fab")
		)
		(fp_line
			(start -1.1049 -0.724916)
			(end 1.1049 -0.724916)
			(stroke
				(width 0.1)
				(type default)
			)
			(layer "B.Fab")
		)
		(fp_line
			(start 1.1049 -0.724916)
			(end 1.1049 0.724916)
			(stroke
				(width 0.1)
				(type default)
			)
			(layer "B.Fab")
		)
		(pad "1" smd rect
			(at 0.889 0 270)
			(size 1.016 1.27)
			(layers "B.Cu" "B.Mask" "B.Paste")
			(net "PVCCFA_EHV_FIVRA_CPU1")
		)
		(pad "2" smd rect
			(at -0.889 0 270)
			(size 1.016 1.27)
			(layers "B.Cu" "B.Mask" "B.Paste")
			(net "GND")
		)
	)
	(footprint ""
		(layer "B.Cu")
		(at 323.661278 -188.48451 90)
		(property "Reference" "R302"
			(at 0 0 90)
			(layer "B.SilkS")
			(hide yes)
			(effects
				(font
					(size 1.27 1.27)
				)
				(justify mirror)
			)
		)
		(property "Value" ""
			(at 0 0 90)
			(layer "B.Fab")
			(effects
				(font
					(size 1.27 1.27)
				)
				(justify mirror)
			)
		)
		(duplicate_pad_numbers_are_jumpers no)
		(fp_line
			(start 0.7874 -0.4064)
			(end -0.7874 -0.4064)
			(stroke
				(width 0.1524)
				(type default)
			)
			(layer "B.SilkS")
		)
		(fp_line
			(start -0.7874 -0.4064)
			(end -0.7874 0.4064)
			(stroke
				(width 0.1524)
				(type default)
			)
			(layer "B.SilkS")
		)
		(fp_line
			(start 0.7874 0.4064)
			(end 0.7874 -0.4064)
			(stroke
				(width 0.1524)
				(type default)
			)
			(layer "B.SilkS")
		)
		(fp_line
			(start -0.7874 0.4064)
			(end 0.7874 0.4064)
			(stroke
				(width 0.1524)
				(type default)
			)
			(layer "B.SilkS")
		)
		(fp_line
			(start 0.67945 -0.305054)
			(end 0.12065 -0.305054)
			(stroke
				(width 0.1)
				(type default)
			)
			(layer "B.Fab")
		)
		(fp_line
			(start 0.12065 -0.305054)
			(end 0.12065 -0.2794)
			(stroke
				(width 0.1)
				(type default)
			)
			(layer "B.Fab")
		)
		(fp_line
			(start -0.12065 -0.3048)
			(end -0.67945 -0.3048)
			(stroke
				(width 0.1)
				(type default)
			)
			(layer "B.Fab")
		)
		(fp_line
			(start -0.67945 -0.3048)
			(end -0.67945 0.3048)
			(stroke
				(width 0.1)
				(type default)
			)
			(layer "B.Fab")
		)
		(fp_line
			(start 0.12065 -0.2794)
			(end -0.12065 -0.2794)
			(stroke
				(width 0.1)
				(type default)
			)
			(layer "B.Fab")
		)
		(fp_line
			(start -0.12065 -0.2794)
			(end -0.12065 -0.3048)
			(stroke
				(width 0.1)
				(type default)
			)
			(layer "B.Fab")
		)
		(fp_line
			(start 0.12065 0.2794)
			(end 0.12065 0.3048)
			(stroke
				(width 0.1)
				(type default)
			)
			(layer "B.Fab")
		)
		(fp_line
			(start -0.120396 0.2794)
			(end 0.12065 0.2794)
			(stroke
				(width 0.1)
				(type default)
			)
			(layer "B.Fab")
		)
		(fp_line
			(start 0.67945 0.3048)
			(end 0.67945 -0.305054)
			(stroke
				(width 0.1)
				(type default)
			)
			(layer "B.Fab")
		)
		(fp_line
			(start 0.12065 0.3048)
			(end 0.67945 0.3048)
			(stroke
				(width 0.1)
				(type default)
			)
			(layer "B.Fab")
		)
		(fp_line
			(start -0.120396 0.3048)
			(end -0.120396 0.2794)
			(stroke
				(width 0.1)
				(type default)
			)
			(layer "B.Fab")
		)
		(fp_line
			(start -0.67945 0.3048)
			(end -0.120396 0.3048)
			(stroke
				(width 0.1)
				(type default)
			)
			(layer "B.Fab")
		)
		(pad "1" smd circle
			(at 0.40005 0 270)
			(size 0 0)
			(layers "B.Cu" "B.Mask" "B.Paste")
			(net "H_CPU0_RMCA_LVC1_R_N")
		)
		(pad "2" smd circle
			(at -0.40005 0 270)
			(size 0 0)
			(layers "B.Cu" "B.Mask" "B.Paste")
			(net "H_CPU_RMCA_LVC1_R_N")
		)
	)
	(footprint ""
		(layer "B.Cu")
		(at 333.786988 -44.962064)
		(property "Reference" "C1206"
			(at 0 0 0)
			(layer "B.SilkS")
			(hide yes)
			(effects
				(font
					(size 1.27 1.27)
				)
				(justify mirror)
			)
		)
		(property "Value" ""
			(at 0 0 0)
			(layer "B.Fab")
			(effects
				(font
					(size 1.27 1.27)
				)
				(justify mirror)
			)
		)
		(duplicate_pad_numbers_are_jumpers no)
		(fp_line
			(start -0.7874 -0.4064)
			(end -0.7874 0.4064)
			(stroke
				(width 0.1524)
				(type default)
			)
			(layer "B.SilkS")
		)
		(fp_line
			(start -0.7874 0.4064)
			(end 0.7874 0.4064)
			(stroke
				(width 0.1524)
				(type default)
			)
			(layer "B.SilkS")
		)
		(fp_line
			(start 0.7874 -0.4064)
			(end -0.7874 -0.4064)
			(stroke
				(width 0.1524)
				(type default)
			)
			(layer "B.SilkS")
		)
		(fp_line
			(start 0.7874 0.4064)
			(end 0.7874 -0.4064)
			(stroke
				(width 0.1524)
				(type default)
			)
			(layer "B.SilkS")
		)
		(fp_line
			(start -0.67945 -0.3048)
			(end -0.67945 0.3048)
			(stroke
				(width 0.1)
				(type default)
			)
			(layer "B.Fab")
		)
		(fp_line
			(start -0.67945 0.3048)
			(end -0.120396 0.3048)
			(stroke
				(width 0.1)
				(type default)
			)
			(layer "B.Fab")
		)
		(fp_line
			(start -0.12065 -0.3048)
			(end -0.67945 -0.3048)
			(stroke
				(width 0.1)
				(type default)
			)
			(layer "B.Fab")
		)
		(fp_line
			(start -0.12065 -0.2794)
			(end -0.12065 -0.3048)
			(stroke
				(width 0.1)
				(type default)
			)
			(layer "B.Fab")
		)
		(fp_line
			(start -0.120396 0.2794)
			(end 0.12065 0.2794)
			(stroke
				(width 0.1)
				(type default)
			)
			(layer "B.Fab")
		)
		(fp_line
			(start -0.120396 0.3048)
			(end -0.120396 0.2794)
			(stroke
				(width 0.1)
				(type default)
			)
			(layer "B.Fab")
		)
		(fp_line
			(start 0.12065 -0.305054)
			(end 0.12065 -0.2794)
			(stroke
				(width 0.1)
				(type default)
			)
			(layer "B.Fab")
		)
		(fp_line
			(start 0.12065 -0.2794)
			(end -0.12065 -0.2794)
			(stroke
				(width 0.1)
				(type default)
			)
			(layer "B.Fab")
		)
		(fp_line
			(start 0.12065 0.2794)
			(end 0.12065 0.3048)
			(stroke
				(width 0.1)
				(type default)
			)
			(layer "B.Fab")
		)
		(fp_line
			(start 0.12065 0.3048)
			(end 0.67945 0.3048)
			(stroke
				(width 0.1)
				(type default)
			)
			(layer "B.Fab")
		)
		(fp_line
			(start 0.67945 -0.305054)
			(end 0.12065 -0.305054)
			(stroke
				(width 0.1)
				(type default)
			)
			(layer "B.Fab")
		)
		(fp_line
			(start 0.67945 0.3048)
			(end 0.67945 -0.305054)
			(stroke
				(width 0.1)
				(type default)
			)
			(layer "B.Fab")
		)
		(pad "1" smd circle
			(at 0.40005 0 180)
			(size 0 0)
			(layers "B.Cu" "B.Mask" "B.Paste")
			(net "P3V3_AUX")
		)
		(pad "2" smd circle
			(at -0.40005 0 180)
			(size 0 0)
			(layers "B.Cu" "B.Mask" "B.Paste")
			(net "GND")
		)
	)
	(footprint ""
		(layer "B.Cu")
		(at 293.764208 -354.02139 -90)
		(property "Reference" "PC1183_P0_4"
			(at 0 0 90)
			(layer "B.SilkS")
			(hide yes)
			(effects
				(font
					(size 1.27 1.27)
				)
				(justify mirror)
			)
		)
		(property "Value" ""
			(at 0 0 90)
			(layer "B.Fab")
			(effects
				(font
					(size 1.27 1.27)
				)
				(justify mirror)
			)
		)
		(duplicate_pad_numbers_are_jumpers no)
		(fp_line
			(start -0.7874 0.4064)
			(end 0.7874 0.4064)
			(stroke
				(width 0.1524)
				(type default)
			)
			(layer "B.SilkS")
		)
		(fp_line
			(start 0.7874 0.4064)
			(end 0.7874 -0.4064)
			(stroke
				(width 0.1524)
				(type default)
			)
			(layer "B.SilkS")
		)
		(fp_line
			(start -0.7874 -0.4064)
			(end -0.7874 0.4064)
			(stroke
				(width 0.1524)
				(type default)
			)
			(layer "B.SilkS")
		)
		(fp_line
			(start 0.7874 -0.4064)
			(end -0.7874 -0.4064)
			(stroke
				(width 0.1524)
				(type default)
			)
			(layer "B.SilkS")
		)
		(fp_line
			(start -0.67945 0.3048)
			(end -0.120396 0.3048)
			(stroke
				(width 0.1)
				(type default)
			)
			(layer "B.Fab")
		)
		(fp_line
			(start -0.120396 0.3048)
			(end -0.120396 0.2794)
			(stroke
				(width 0.1)
				(type default)
			)
			(layer "B.Fab")
		)
		(fp_line
			(start 0.12065 0.3048)
			(end 0.67945 0.3048)
			(stroke
				(width 0.1)
				(type default)
			)
			(layer "B.Fab")
		)
		(fp_line
			(start 0.67945 0.3048)
			(end 0.67945 -0.305054)
			(stroke
				(width 0.1)
				(type default)
			)
			(layer "B.Fab")
		)
		(fp_line
			(start -0.120396 0.2794)
			(end 0.12065 0.2794)
			(stroke
				(width 0.1)
				(type default)
			)
			(layer "B.Fab")
		)
		(fp_line
			(start 0.12065 0.2794)
			(end 0.12065 0.3048)
			(stroke
				(width 0.1)
				(type default)
			)
			(layer "B.Fab")
		)
		(fp_line
			(start -0.12065 -0.2794)
			(end -0.12065 -0.3048)
			(stroke
				(width 0.1)
				(type default)
			)
			(layer "B.Fab")
		)
		(fp_line
			(start 0.12065 -0.2794)
			(end -0.12065 -0.2794)
			(stroke
				(width 0.1)
				(type default)
			)
			(layer "B.Fab")
		)
		(fp_line
			(start -0.67945 -0.3048)
			(end -0.67945 0.3048)
			(stroke
				(width 0.1)
				(type default)
			)
			(layer "B.Fab")
		)
		(fp_line
			(start -0.12065 -0.3048)
			(end -0.67945 -0.3048)
			(stroke
				(width 0.1)
				(type default)
			)
			(layer "B.Fab")
		)
		(fp_line
			(start 0.12065 -0.305054)
			(end 0.12065 -0.2794)
			(stroke
				(width 0.1)
				(type default)
			)
			(layer "B.Fab")
		)
		(fp_line
			(start 0.67945 -0.305054)
			(end 0.12065 -0.305054)
			(stroke
				(width 0.1)
				(type default)
			)
			(layer "B.Fab")
		)
		(pad "1" smd circle
			(at 0.40005 0 90)
			(size 0 0)
			(layers "B.Cu" "B.Mask" "B.Paste")
			(net "PVCCFA_EHV_FIVRA_CPU0")
		)
		(pad "2" smd circle
			(at -0.40005 0 90)
			(size 0 0)
			(layers "B.Cu" "B.Mask" "B.Paste")
			(net "GND")
		)
	)
	(footprint ""
		(layer "B.Cu")
		(at 187.88888 -102.707948 180)
		(property "Reference" "C1944"
			(at 0 0 0)
			(layer "B.SilkS")
			(hide yes)
			(effects
				(font
					(size 1.27 1.27)
				)
				(justify mirror)
			)
		)
		(property "Value" ""
			(at 0 0 0)
			(layer "B.Fab")
			(effects
				(font
					(size 1.27 1.27)
				)
				(justify mirror)
			)
		)
		(duplicate_pad_numbers_are_jumpers no)
		(fp_line
			(start 0.7874 0.4064)
			(end 0.7874 -0.4064)
			(stroke
				(width 0.1524)
				(type default)
			)
			(layer "B.SilkS")
		)
		(fp_line
			(start 0.7874 -0.4064)
			(end -0.7874 -0.4064)
			(stroke
				(width 0.1524)
				(type default)
			)
			(layer "B.SilkS")
		)
		(fp_line
			(start -0.7874 0.4064)
			(end 0.7874 0.4064)
			(stroke
				(width 0.1524)
				(type default)
			)
			(layer "B.SilkS")
		)
		(fp_line
			(start -0.7874 -0.4064)
			(end -0.7874 0.4064)
			(stroke
				(width 0.1524)
				(type default)
			)
			(layer "B.SilkS")
		)
		(fp_line
			(start 0.67945 0.3048)
			(end 0.67945 -0.305054)
			(stroke
				(width 0.1)
				(type default)
			)
			(layer "B.Fab")
		)
		(fp_line
			(start 0.67945 -0.305054)
			(end 0.12065 -0.305054)
			(stroke
				(width 0.1)
				(type default)
			)
			(layer "B.Fab")
		)
		(fp_line
			(start 0.12065 0.3048)
			(end 0.67945 0.3048)
			(stroke
				(width 0.1)
				(type default)
			)
			(layer "B.Fab")
		)
		(fp_line
			(start 0.12065 0.2794)
			(end 0.12065 0.3048)
			(stroke
				(width 0.1)
				(type default)
			)
			(layer "B.Fab")
		)
		(fp_line
			(start 0.12065 -0.2794)
			(end -0.12065 -0.2794)
			(stroke
				(width 0.1)
				(type default)
			)
			(layer "B.Fab")
		)
		(fp_line
			(start 0.12065 -0.305054)
			(end 0.12065 -0.2794)
			(stroke
				(width 0.1)
				(type default)
			)
			(layer "B.Fab")
		)
		(fp_line
			(start -0.120396 0.3048)
			(end -0.120396 0.2794)
			(stroke
				(width 0.1)
				(type default)
			)
			(layer "B.Fab")
		)
		(fp_line
			(start -0.120396 0.2794)
			(end 0.12065 0.2794)
			(stroke
				(width 0.1)
				(type default)
			)
			(layer "B.Fab")
		)
		(fp_line
			(start -0.12065 -0.2794)
			(end -0.12065 -0.3048)
			(stroke
				(width 0.1)
				(type default)
			)
			(layer "B.Fab")
		)
		(fp_line
			(start -0.12065 -0.3048)
			(end -0.67945 -0.3048)
			(stroke
				(width 0.1)
				(type default)
			)
			(layer "B.Fab")
		)
		(fp_line
			(start -0.67945 0.3048)
			(end -0.120396 0.3048)
			(stroke
				(width 0.1)
				(type default)
			)
			(layer "B.Fab")
		)
		(fp_line
			(start -0.67945 -0.3048)
			(end -0.67945 0.3048)
			(stroke
				(width 0.1)
				(type default)
			)
			(layer "B.Fab")
		)
		(pad "1" smd circle
			(at 0.40005 0)
			(size 0 0)
			(layers "B.Cu" "B.Mask" "B.Paste")
			(net "P3V3_AUX_FPGA_VCCIO2")
		)
		(pad "2" smd circle
			(at -0.40005 0)
			(size 0 0)
			(layers "B.Cu" "B.Mask" "B.Paste")
			(net "GND")
		)
	)
	(footprint ""
		(layer "B.Cu")
		(at 178.803554 -354.565204 -90)
		(property "Reference" "PR1306"
			(at 0 0 90)
			(layer "B.SilkS")
			(hide yes)
			(effects
				(font
					(size 1.27 1.27)
				)
				(justify mirror)
			)
		)
		(property "Value" ""
			(at 0 0 90)
			(layer "B.Fab")
			(effects
				(font
					(size 1.27 1.27)
				)
				(justify mirror)
			)
		)
		(duplicate_pad_numbers_are_jumpers no)
		(fp_line
			(start -0.7874 0.4064)
			(end 0.7874 0.4064)
			(stroke
				(width 0.1524)
				(type default)
			)
			(layer "B.SilkS")
		)
		(fp_line
			(start 0.7874 0.4064)
			(end 0.7874 -0.4064)
			(stroke
				(width 0.1524)
				(type default)
			)
			(layer "B.SilkS")
		)
		(fp_line
			(start -0.7874 -0.4064)
			(end -0.7874 0.4064)
			(stroke
				(width 0.1524)
				(type default)
			)
			(layer "B.SilkS")
		)
		(fp_line
			(start 0.7874 -0.4064)
			(end -0.7874 -0.4064)
			(stroke
				(width 0.1524)
				(type default)
			)
			(layer "B.SilkS")
		)
		(fp_line
			(start -0.67945 0.3048)
			(end -0.120396 0.3048)
			(stroke
				(width 0.1)
				(type default)
			)
			(layer "B.Fab")
		)
		(fp_line
			(start -0.120396 0.3048)
			(end -0.120396 0.2794)
			(stroke
				(width 0.1)
				(type default)
			)
			(layer "B.Fab")
		)
		(fp_line
			(start 0.12065 0.3048)
			(end 0.67945 0.3048)
			(stroke
				(width 0.1)
				(type default)
			)
			(layer "B.Fab")
		)
		(fp_line
			(start 0.67945 0.3048)
			(end 0.67945 -0.305054)
			(stroke
				(width 0.1)
				(type default)
			)
			(layer "B.Fab")
		)
		(fp_line
			(start -0.120396 0.2794)
			(end 0.12065 0.2794)
			(stroke
				(width 0.1)
				(type default)
			)
			(layer "B.Fab")
		)
		(fp_line
			(start 0.12065 0.2794)
			(end 0.12065 0.3048)
			(stroke
				(width 0.1)
				(type default)
			)
			(layer "B.Fab")
		)
		(fp_line
			(start -0.12065 -0.2794)
			(end -0.12065 -0.3048)
			(stroke
				(width 0.1)
				(type default)
			)
			(layer "B.Fab")
		)
		(fp_line
			(start 0.12065 -0.2794)
			(end -0.12065 -0.2794)
			(stroke
				(width 0.1)
				(type default)
			)
			(layer "B.Fab")
		)
		(fp_line
			(start -0.67945 -0.3048)
			(end -0.67945 0.3048)
			(stroke
				(width 0.1)
				(type default)
			)
			(layer "B.Fab")
		)
		(fp_line
			(start -0.12065 -0.3048)
			(end -0.67945 -0.3048)
			(stroke
				(width 0.1)
				(type default)
			)
			(layer "B.Fab")
		)
		(fp_line
			(start 0.12065 -0.305054)
			(end 0.12065 -0.2794)
			(stroke
				(width 0.1)
				(type default)
			)
			(layer "B.Fab")
		)
		(fp_line
			(start 0.67945 -0.305054)
			(end 0.12065 -0.305054)
			(stroke
				(width 0.1)
				(type default)
			)
			(layer "B.Fab")
		)
		(pad "1" smd circle
			(at 0.40005 0 90)
			(size 0 0)
			(layers "B.Cu" "B.Mask" "B.Paste")
			(net "PVCCFA_EHV_FIVRA_CPU1_PVCC1")
		)
		(pad "2" smd circle
			(at -0.40005 0 90)
			(size 0 0)
			(layers "B.Cu" "B.Mask" "B.Paste")
			(net "PVCCFA_EHV_FIVRA_CPU1_VDD3")
		)
	)
	(footprint ""
		(layer "B.Cu")
		(at 157.02788 -113.756948 180)
		(property "Reference" "R1681"
			(at 0 0 0)
			(layer "B.SilkS")
			(hide yes)
			(effects
				(font
					(size 1.27 1.27)
				)
				(justify mirror)
			)
		)
		(property "Value" ""
			(at 0 0 0)
			(layer "B.Fab")
			(effects
				(font
					(size 1.27 1.27)
				)
				(justify mirror)
			)
		)
		(duplicate_pad_numbers_are_jumpers no)
		(fp_line
			(start 0.7874 0.4064)
			(end 0.7874 -0.4064)
			(stroke
				(width 0.1524)
				(type default)
			)
			(layer "B.SilkS")
		)
		(fp_line
			(start 0.7874 -0.4064)
			(end -0.7874 -0.4064)
			(stroke
				(width 0.1524)
				(type default)
			)
			(layer "B.SilkS")
		)
		(fp_line
			(start -0.7874 0.4064)
			(end 0.7874 0.4064)
			(stroke
				(width 0.1524)
				(type default)
			)
			(layer "B.SilkS")
		)
		(fp_line
			(start -0.7874 -0.4064)
			(end -0.7874 0.4064)
			(stroke
				(width 0.1524)
				(type default)
			)
			(layer "B.SilkS")
		)
		(fp_line
			(start 0.67945 0.3048)
			(end 0.67945 -0.305054)
			(stroke
				(width 0.1)
				(type default)
			)
			(layer "B.Fab")
		)
		(fp_line
			(start 0.67945 -0.305054)
			(end 0.12065 -0.305054)
			(stroke
				(width 0.1)
				(type default)
			)
			(layer "B.Fab")
		)
		(fp_line
			(start 0.12065 0.3048)
			(end 0.67945 0.3048)
			(stroke
				(width 0.1)
				(type default)
			)
			(layer "B.Fab")
		)
		(fp_line
			(start 0.12065 0.2794)
			(end 0.12065 0.3048)
			(stroke
				(width 0.1)
				(type default)
			)
			(layer "B.Fab")
		)
		(fp_line
			(start 0.12065 -0.2794)
			(end -0.12065 -0.2794)
			(stroke
				(width 0.1)
				(type default)
			)
			(layer "B.Fab")
		)
		(fp_line
			(start 0.12065 -0.305054)
			(end 0.12065 -0.2794)
			(stroke
				(width 0.1)
				(type default)
			)
			(layer "B.Fab")
		)
		(fp_line
			(start -0.120396 0.3048)
			(end -0.120396 0.2794)
			(stroke
				(width 0.1)
				(type default)
			)
			(layer "B.Fab")
		)
		(fp_line
			(start -0.120396 0.2794)
			(end 0.12065 0.2794)
			(stroke
				(width 0.1)
				(type default)
			)
			(layer "B.Fab")
		)
		(fp_line
			(start -0.12065 -0.2794)
			(end -0.12065 -0.3048)
			(stroke
				(width 0.1)
				(type default)
			)
			(layer "B.Fab")
		)
		(fp_line
			(start -0.12065 -0.3048)
			(end -0.67945 -0.3048)
			(stroke
				(width 0.1)
				(type default)
			)
			(layer "B.Fab")
		)
		(fp_line
			(start -0.67945 0.3048)
			(end -0.120396 0.3048)
			(stroke
				(width 0.1)
				(type default)
			)
			(layer "B.Fab")
		)
		(fp_line
			(start -0.67945 -0.3048)
			(end -0.67945 0.3048)
			(stroke
				(width 0.1)
				(type default)
			)
			(layer "B.Fab")
		)
		(pad "1" smd circle
			(at 0.40005 0)
			(size 0 0)
			(layers "B.Cu" "B.Mask" "B.Paste")
			(net "P3V3_AUX")
		)
		(pad "2" smd circle
			(at -0.40005 0)
			(size 0 0)
			(layers "B.Cu" "B.Mask" "B.Paste")
			(net "PU_RST_DEDI_BUSY_PLD_N")
		)
	)
	(footprint ""
		(layer "B.Cu")
		(at 294.91813 -400.999452 -90)
		(property "Reference" "PR2526"
			(at 0 0 90)
			(layer "B.SilkS")
			(hide yes)
			(effects
				(font
					(size 1.27 1.27)
				)
				(justify mirror)
			)
		)
		(property "Value" ""
			(at 0 0 90)
			(layer "B.Fab")
			(effects
				(font
					(size 1.27 1.27)
				)
				(justify mirror)
			)
		)
		(duplicate_pad_numbers_are_jumpers no)
		(fp_line
			(start -0.7874 0.4064)
			(end 0.7874 0.4064)
			(stroke
				(width 0.1524)
				(type default)
			)
			(layer "B.SilkS")
		)
		(fp_line
			(start 0.7874 0.4064)
			(end 0.7874 -0.4064)
			(stroke
				(width 0.1524)
				(type default)
			)
			(layer "B.SilkS")
		)
		(fp_line
			(start -0.7874 -0.4064)
			(end -0.7874 0.4064)
			(stroke
				(width 0.1524)
				(type default)
			)
			(layer "B.SilkS")
		)
		(fp_line
			(start 0.7874 -0.4064)
			(end -0.7874 -0.4064)
			(stroke
				(width 0.1524)
				(type default)
			)
			(layer "B.SilkS")
		)
		(fp_line
			(start -0.67945 0.3048)
			(end -0.120396 0.3048)
			(stroke
				(width 0.1)
				(type default)
			)
			(layer "B.Fab")
		)
		(fp_line
			(start -0.120396 0.3048)
			(end -0.120396 0.2794)
			(stroke
				(width 0.1)
				(type default)
			)
			(layer "B.Fab")
		)
		(fp_line
			(start 0.12065 0.3048)
			(end 0.67945 0.3048)
			(stroke
				(width 0.1)
				(type default)
			)
			(layer "B.Fab")
		)
		(fp_line
			(start 0.67945 0.3048)
			(end 0.67945 -0.305054)
			(stroke
				(width 0.1)
				(type default)
			)
			(layer "B.Fab")
		)
		(fp_line
			(start -0.120396 0.2794)
			(end 0.12065 0.2794)
			(stroke
				(width 0.1)
				(type default)
			)
			(layer "B.Fab")
		)
		(fp_line
			(start 0.12065 0.2794)
			(end 0.12065 0.3048)
			(stroke
				(width 0.1)
				(type default)
			)
			(layer "B.Fab")
		)
		(fp_line
			(start -0.12065 -0.2794)
			(end -0.12065 -0.3048)
			(stroke
				(width 0.1)
				(type default)
			)
			(layer "B.Fab")
		)
		(fp_line
			(start 0.12065 -0.2794)
			(end -0.12065 -0.2794)
			(stroke
				(width 0.1)
				(type default)
			)
			(layer "B.Fab")
		)
		(fp_line
			(start -0.67945 -0.3048)
			(end -0.67945 0.3048)
			(stroke
				(width 0.1)
				(type default)
			)
			(layer "B.Fab")
		)
		(fp_line
			(start -0.12065 -0.3048)
			(end -0.67945 -0.3048)
			(stroke
				(width 0.1)
				(type default)
			)
			(layer "B.Fab")
		)
		(fp_line
			(start 0.12065 -0.305054)
			(end 0.12065 -0.2794)
			(stroke
				(width 0.1)
				(type default)
			)
			(layer "B.Fab")
		)
		(fp_line
			(start 0.67945 -0.305054)
			(end 0.12065 -0.305054)
			(stroke
				(width 0.1)
				(type default)
			)
			(layer "B.Fab")
		)
		(pad "1" smd circle
			(at 0.40005 0 90)
			(size 0 0)
			(layers "B.Cu" "B.Mask" "B.Paste")
			(net "P12V_HSC_SENSE2_N")
		)
		(pad "2" smd circle
			(at -0.40005 0 90)
			(size 0 0)
			(layers "B.Cu" "B.Mask" "B.Paste")
			(net "P12V_HSC_SENSE2_R3_N")
		)
	)
	(footprint ""
		(layer "B.Cu")
		(at 256.09169 -318.482726 180)
		(property "Reference" "R3881"
			(at 0 0 0)
			(layer "B.SilkS")
			(hide yes)
			(effects
				(font
					(size 1.27 1.27)
				)
				(justify mirror)
			)
		)
		(property "Value" ""
			(at 0 0 0)
			(layer "B.Fab")
			(effects
				(font
					(size 1.27 1.27)
				)
				(justify mirror)
			)
		)
		(duplicate_pad_numbers_are_jumpers no)
		(fp_line
			(start 0.7874 0.4064)
			(end 0.7874 -0.4064)
			(stroke
				(width 0.1524)
				(type default)
			)
			(layer "B.SilkS")
		)
		(fp_line
			(start 0.7874 -0.4064)
			(end -0.7874 -0.4064)
			(stroke
				(width 0.1524)
				(type default)
			)
			(layer "B.SilkS")
		)
		(fp_line
			(start -0.7874 0.4064)
			(end 0.7874 0.4064)
			(stroke
				(width 0.1524)
				(type default)
			)
			(layer "B.SilkS")
		)
		(fp_line
			(start -0.7874 -0.4064)
			(end -0.7874 0.4064)
			(stroke
				(width 0.1524)
				(type default)
			)
			(layer "B.SilkS")
		)
		(fp_line
			(start 0.67945 0.3048)
			(end 0.67945 -0.305054)
			(stroke
				(width 0.1)
				(type default)
			)
			(layer "B.Fab")
		)
		(fp_line
			(start 0.67945 -0.305054)
			(end 0.12065 -0.305054)
			(stroke
				(width 0.1)
				(type default)
			)
			(layer "B.Fab")
		)
		(fp_line
			(start 0.12065 0.3048)
			(end 0.67945 0.3048)
			(stroke
				(width 0.1)
				(type default)
			)
			(layer "B.Fab")
		)
		(fp_line
			(start 0.12065 0.2794)
			(end 0.12065 0.3048)
			(stroke
				(width 0.1)
				(type default)
			)
			(layer "B.Fab")
		)
		(fp_line
			(start 0.12065 -0.2794)
			(end -0.12065 -0.2794)
			(stroke
				(width 0.1)
				(type default)
			)
			(layer "B.Fab")
		)
		(fp_line
			(start 0.12065 -0.305054)
			(end 0.12065 -0.2794)
			(stroke
				(width 0.1)
				(type default)
			)
			(layer "B.Fab")
		)
		(fp_line
			(start -0.120396 0.3048)
			(end -0.120396 0.2794)
			(stroke
				(width 0.1)
				(type default)
			)
			(layer "B.Fab")
		)
		(fp_line
			(start -0.120396 0.2794)
			(end 0.12065 0.2794)
			(stroke
				(width 0.1)
				(type default)
			)
			(layer "B.Fab")
		)
		(fp_line
			(start -0.12065 -0.2794)
			(end -0.12065 -0.3048)
			(stroke
				(width 0.1)
				(type default)
			)
			(layer "B.Fab")
		)
		(fp_line
			(start -0.12065 -0.3048)
			(end -0.67945 -0.3048)
			(stroke
				(width 0.1)
				(type default)
			)
			(layer "B.Fab")
		)
		(fp_line
			(start -0.67945 0.3048)
			(end -0.120396 0.3048)
			(stroke
				(width 0.1)
				(type default)
			)
			(layer "B.Fab")
		)
		(fp_line
			(start -0.67945 -0.3048)
			(end -0.67945 0.3048)
			(stroke
				(width 0.1)
				(type default)
			)
			(layer "B.Fab")
		)
		(pad "1" smd circle
			(at 0.40005 0)
			(size 0 0)
			(layers "B.Cu" "B.Mask" "B.Paste")
			(net "I3C_SPD_DDRABCD_CPU0_LVC1_SCL_6")
		)
		(pad "2" smd circle
			(at -0.40005 0)
			(size 0 0)
			(layers "B.Cu" "B.Mask" "B.Paste")
			(net "I3C_SPD_DDRABCD_CPU0_LVC1_SCL")
		)
	)
	(footprint ""
		(layer "B.Cu")
		(at 353.551998 -56.833516)
		(property "Reference" "R1464"
			(at 0 0 0)
			(layer "B.SilkS")
			(hide yes)
			(effects
				(font
					(size 1.27 1.27)
				)
				(justify mirror)
			)
		)
		(property "Value" ""
			(at 0 0 0)
			(layer "B.Fab")
			(effects
				(font
					(size 1.27 1.27)
				)
				(justify mirror)
			)
		)
		(duplicate_pad_numbers_are_jumpers no)
		(fp_line
			(start -0.7874 -0.4064)
			(end -0.7874 0.4064)
			(stroke
				(width 0.1524)
				(type default)
			)
			(layer "B.SilkS")
		)
		(fp_line
			(start -0.7874 0.4064)
			(end 0.7874 0.4064)
			(stroke
				(width 0.1524)
				(type default)
			)
			(layer "B.SilkS")
		)
		(fp_line
			(start 0.7874 -0.4064)
			(end -0.7874 -0.4064)
			(stroke
				(width 0.1524)
				(type default)
			)
			(layer "B.SilkS")
		)
		(fp_line
			(start 0.7874 0.4064)
			(end 0.7874 -0.4064)
			(stroke
				(width 0.1524)
				(type default)
			)
			(layer "B.SilkS")
		)
		(fp_line
			(start -0.67945 -0.3048)
			(end -0.67945 0.3048)
			(stroke
				(width 0.1)
				(type default)
			)
			(layer "B.Fab")
		)
		(fp_line
			(start -0.67945 0.3048)
			(end -0.120396 0.3048)
			(stroke
				(width 0.1)
				(type default)
			)
			(layer "B.Fab")
		)
		(fp_line
			(start -0.12065 -0.3048)
			(end -0.67945 -0.3048)
			(stroke
				(width 0.1)
				(type default)
			)
			(layer "B.Fab")
		)
		(fp_line
			(start -0.12065 -0.2794)
			(end -0.12065 -0.3048)
			(stroke
				(width 0.1)
				(type default)
			)
			(layer "B.Fab")
		)
		(fp_line
			(start -0.120396 0.2794)
			(end 0.12065 0.2794)
			(stroke
				(width 0.1)
				(type default)
			)
			(layer "B.Fab")
		)
		(fp_line
			(start -0.120396 0.3048)
			(end -0.120396 0.2794)
			(stroke
				(width 0.1)
				(type default)
			)
			(layer "B.Fab")
		)
		(fp_line
			(start 0.12065 -0.305054)
			(end 0.12065 -0.2794)
			(stroke
				(width 0.1)
				(type default)
			)
			(layer "B.Fab")
		)
		(fp_line
			(start 0.12065 -0.2794)
			(end -0.12065 -0.2794)
			(stroke
				(width 0.1)
				(type default)
			)
			(layer "B.Fab")
		)
		(fp_line
			(start 0.12065 0.2794)
			(end 0.12065 0.3048)
			(stroke
				(width 0.1)
				(type default)
			)
			(layer "B.Fab")
		)
		(fp_line
			(start 0.12065 0.3048)
			(end 0.67945 0.3048)
			(stroke
				(width 0.1)
				(type default)
			)
			(layer "B.Fab")
		)
		(fp_line
			(start 0.67945 -0.305054)
			(end 0.12065 -0.305054)
			(stroke
				(width 0.1)
				(type default)
			)
			(layer "B.Fab")
		)
		(fp_line
			(start 0.67945 0.3048)
			(end 0.67945 -0.305054)
			(stroke
				(width 0.1)
				(type default)
			)
			(layer "B.Fab")
		)
		(pad "1" smd circle
			(at 0.40005 0 180)
			(size 0 0)
			(layers "B.Cu" "B.Mask" "B.Paste")
			(net "P1V8_PCH_AUX")
		)
		(pad "2" smd circle
			(at -0.40005 0 180)
			(size 0 0)
			(layers "B.Cu" "B.Mask" "B.Paste")
			(net "P1V8_PCH_PLL_AUX")
		)
	)
	(footprint ""
		(layer "B.Cu")
		(at 407.91257 -175.986948 180)
		(property "Reference" "PC203_P0_2"
			(at 0 0 0)
			(layer "B.SilkS")
			(hide yes)
			(effects
				(font
					(size 1.27 1.27)
				)
				(justify mirror)
			)
		)
		(property "Value" ""
			(at 0 0 0)
			(layer "B.Fab")
			(effects
				(font
					(size 1.27 1.27)
				)
				(justify mirror)
			)
		)
		(duplicate_pad_numbers_are_jumpers no)
		(fp_line
			(start 1.524 0.762)
			(end 1.524 -0.762)
			(stroke
				(width 0.1524)
				(type default)
			)
			(layer "B.SilkS")
		)
		(fp_line
			(start 1.524 -0.762)
			(end -1.524 -0.762)
			(stroke
				(width 0.1524)
				(type default)
			)
			(layer "B.SilkS")
		)
		(fp_line
			(start -1.524 0.762)
			(end 1.524 0.762)
			(stroke
				(width 0.1524)
				(type default)
			)
			(layer "B.SilkS")
		)
		(fp_line
			(start -1.524 -0.762)
			(end -1.524 0.762)
			(stroke
				(width 0.1524)
				(type default)
			)
			(layer "B.SilkS")
		)
		(fp_line
			(start 1.1049 0.724916)
			(end -1.1049 0.724916)
			(stroke
				(width 0.1)
				(type default)
			)
			(layer "B.Fab")
		)
		(fp_line
			(start 1.1049 -0.724916)
			(end 1.1049 0.724916)
			(stroke
				(width 0.1)
				(type default)
			)
			(layer "B.Fab")
		)
		(fp_line
			(start -1.1049 0.724916)
			(end -1.1049 -0.724916)
			(stroke
				(width 0.1)
				(type default)
			)
			(layer "B.Fab")
		)
		(fp_line
			(start -1.1049 -0.724916)
			(end 1.1049 -0.724916)
			(stroke
				(width 0.1)
				(type default)
			)
			(layer "B.Fab")
		)
		(pad "1" smd rect
			(at 0.889 0 180)
			(size 1.016 1.27)
			(layers "B.Cu" "B.Mask" "B.Paste")
			(net "PVCCINFAON_CPU0")
		)
		(pad "2" smd rect
			(at -0.889 0 180)
			(size 1.016 1.27)
			(layers "B.Cu" "B.Mask" "B.Paste")
			(net "GND")
		)
	)
	(footprint ""
		(layer "B.Cu")
		(at 164.64788 -109.565948 180)
		(property "Reference" "R2664"
			(at 0 0 0)
			(layer "B.SilkS")
			(hide yes)
			(effects
				(font
					(size 1.27 1.27)
				)
				(justify mirror)
			)
		)
		(property "Value" ""
			(at 0 0 0)
			(layer "B.Fab")
			(effects
				(font
					(size 1.27 1.27)
				)
				(justify mirror)
			)
		)
		(duplicate_pad_numbers_are_jumpers no)
		(fp_line
			(start 0.7874 0.4064)
			(end 0.7874 -0.4064)
			(stroke
				(width 0.1524)
				(type default)
			)
			(layer "B.SilkS")
		)
		(fp_line
			(start 0.7874 -0.4064)
			(end -0.7874 -0.4064)
			(stroke
				(width 0.1524)
				(type default)
			)
			(layer "B.SilkS")
		)
		(fp_line
			(start -0.7874 0.4064)
			(end 0.7874 0.4064)
			(stroke
				(width 0.1524)
				(type default)
			)
			(layer "B.SilkS")
		)
		(fp_line
			(start -0.7874 -0.4064)
			(end -0.7874 0.4064)
			(stroke
				(width 0.1524)
				(type default)
			)
			(layer "B.SilkS")
		)
		(fp_line
			(start 0.67945 0.3048)
			(end 0.67945 -0.305054)
			(stroke
				(width 0.1)
				(type default)
			)
			(layer "B.Fab")
		)
		(fp_line
			(start 0.67945 -0.305054)
			(end 0.12065 -0.305054)
			(stroke
				(width 0.1)
				(type default)
			)
			(layer "B.Fab")
		)
		(fp_line
			(start 0.12065 0.3048)
			(end 0.67945 0.3048)
			(stroke
				(width 0.1)
				(type default)
			)
			(layer "B.Fab")
		)
		(fp_line
			(start 0.12065 0.2794)
			(end 0.12065 0.3048)
			(stroke
				(width 0.1)
				(type default)
			)
			(layer "B.Fab")
		)
		(fp_line
			(start 0.12065 -0.2794)
			(end -0.12065 -0.2794)
			(stroke
				(width 0.1)
				(type default)
			)
			(layer "B.Fab")
		)
		(fp_line
			(start 0.12065 -0.305054)
			(end 0.12065 -0.2794)
			(stroke
				(width 0.1)
				(type default)
			)
			(layer "B.Fab")
		)
		(fp_line
			(start -0.120396 0.3048)
			(end -0.120396 0.2794)
			(stroke
				(width 0.1)
				(type default)
			)
			(layer "B.Fab")
		)
		(fp_line
			(start -0.120396 0.2794)
			(end 0.12065 0.2794)
			(stroke
				(width 0.1)
				(type default)
			)
			(layer "B.Fab")
		)
		(fp_line
			(start -0.12065 -0.2794)
			(end -0.12065 -0.3048)
			(stroke
				(width 0.1)
				(type default)
			)
			(layer "B.Fab")
		)
		(fp_line
			(start -0.12065 -0.3048)
			(end -0.67945 -0.3048)
			(stroke
				(width 0.1)
				(type default)
			)
			(layer "B.Fab")
		)
		(fp_line
			(start -0.67945 0.3048)
			(end -0.120396 0.3048)
			(stroke
				(width 0.1)
				(type default)
			)
			(layer "B.Fab")
		)
		(fp_line
			(start -0.67945 -0.3048)
			(end -0.67945 0.3048)
			(stroke
				(width 0.1)
				(type default)
			)
			(layer "B.Fab")
		)
		(pad "1" smd circle
			(at 0.40005 0)
			(size 0 0)
			(layers "B.Cu" "B.Mask" "B.Paste")
			(net "FM_GPU_PWRGD_ISO")
		)
		(pad "2" smd circle
			(at -0.40005 0)
			(size 0 0)
			(layers "B.Cu" "B.Mask" "B.Paste")
			(net "FM_GPU_PWRGD_ISO_R")
		)
	)
	(footprint ""
		(layer "B.Cu")
		(at 14.616176 -101.217984 90)
		(property "Reference" "C2031"
			(at 0 0 90)
			(layer "B.SilkS")
			(hide yes)
			(effects
				(font
					(size 1.27 1.27)
				)
				(justify mirror)
			)
		)
		(property "Value" ""
			(at 0 0 90)
			(layer "B.Fab")
			(effects
				(font
					(size 1.27 1.27)
				)
				(justify mirror)
			)
		)
		(duplicate_pad_numbers_are_jumpers no)
		(fp_line
			(start 0.7874 -0.4064)
			(end -0.7874 -0.4064)
			(stroke
				(width 0.1524)
				(type default)
			)
			(layer "B.SilkS")
		)
		(fp_line
			(start -0.7874 -0.4064)
			(end -0.7874 0.4064)
			(stroke
				(width 0.1524)
				(type default)
			)
			(layer "B.SilkS")
		)
		(fp_line
			(start 0.7874 0.4064)
			(end 0.7874 -0.4064)
			(stroke
				(width 0.1524)
				(type default)
			)
			(layer "B.SilkS")
		)
		(fp_line
			(start -0.7874 0.4064)
			(end 0.7874 0.4064)
			(stroke
				(width 0.1524)
				(type default)
			)
			(layer "B.SilkS")
		)
		(fp_line
			(start 0.67945 -0.305054)
			(end 0.12065 -0.305054)
			(stroke
				(width 0.1)
				(type default)
			)
			(layer "B.Fab")
		)
		(fp_line
			(start 0.12065 -0.305054)
			(end 0.12065 -0.2794)
			(stroke
				(width 0.1)
				(type default)
			)
			(layer "B.Fab")
		)
		(fp_line
			(start -0.12065 -0.3048)
			(end -0.67945 -0.3048)
			(stroke
				(width 0.1)
				(type default)
			)
			(layer "B.Fab")
		)
		(fp_line
			(start -0.67945 -0.3048)
			(end -0.67945 0.3048)
			(stroke
				(width 0.1)
				(type default)
			)
			(layer "B.Fab")
		)
		(fp_line
			(start 0.12065 -0.2794)
			(end -0.12065 -0.2794)
			(stroke
				(width 0.1)
				(type default)
			)
			(layer "B.Fab")
		)
		(fp_line
			(start -0.12065 -0.2794)
			(end -0.12065 -0.3048)
			(stroke
				(width 0.1)
				(type default)
			)
			(layer "B.Fab")
		)
		(fp_line
			(start 0.12065 0.2794)
			(end 0.12065 0.3048)
			(stroke
				(width 0.1)
				(type default)
			)
			(layer "B.Fab")
		)
		(fp_line
			(start -0.120396 0.2794)
			(end 0.12065 0.2794)
			(stroke
				(width 0.1)
				(type default)
			)
			(layer "B.Fab")
		)
		(fp_line
			(start 0.67945 0.3048)
			(end 0.67945 -0.305054)
			(stroke
				(width 0.1)
				(type default)
			)
			(layer "B.Fab")
		)
		(fp_line
			(start 0.12065 0.3048)
			(end 0.67945 0.3048)
			(stroke
				(width 0.1)
				(type default)
			)
			(layer "B.Fab")
		)
		(fp_line
			(start -0.120396 0.3048)
			(end -0.120396 0.2794)
			(stroke
				(width 0.1)
				(type default)
			)
			(layer "B.Fab")
		)
		(fp_line
			(start -0.67945 0.3048)
			(end -0.120396 0.3048)
			(stroke
				(width 0.1)
				(type default)
			)
			(layer "B.Fab")
		)
		(pad "1" smd circle
			(at 0.40005 0 270)
			(size 0 0)
			(layers "B.Cu" "B.Mask" "B.Paste")
			(net "P3V3_AUX_USB_HUB")
		)
		(pad "2" smd circle
			(at -0.40005 0 270)
			(size 0 0)
			(layers "B.Cu" "B.Mask" "B.Paste")
			(net "GND")
		)
	)
	(footprint ""
		(layer "B.Cu")
		(at 420.682166 -136.162034 180)
		(property "Reference" "PR107"
			(at 0 0 0)
			(layer "B.SilkS")
			(hide yes)
			(effects
				(font
					(size 1.27 1.27)
				)
				(justify mirror)
			)
		)
		(property "Value" ""
			(at 0 0 0)
			(layer "B.Fab")
			(effects
				(font
					(size 1.27 1.27)
				)
				(justify mirror)
			)
		)
		(duplicate_pad_numbers_are_jumpers no)
		(fp_line
			(start 0.7874 0.4064)
			(end 0.7874 -0.4064)
			(stroke
				(width 0.1524)
				(type default)
			)
			(layer "B.SilkS")
		)
		(fp_line
			(start 0.7874 -0.4064)
			(end -0.7874 -0.4064)
			(stroke
				(width 0.1524)
				(type default)
			)
			(layer "B.SilkS")
		)
		(fp_line
			(start -0.7874 0.4064)
			(end 0.7874 0.4064)
			(stroke
				(width 0.1524)
				(type default)
			)
			(layer "B.SilkS")
		)
		(fp_line
			(start -0.7874 -0.4064)
			(end -0.7874 0.4064)
			(stroke
				(width 0.1524)
				(type default)
			)
			(layer "B.SilkS")
		)
		(fp_line
			(start 0.67945 0.3048)
			(end 0.67945 -0.305054)
			(stroke
				(width 0.1)
				(type default)
			)
			(layer "B.Fab")
		)
		(fp_line
			(start 0.67945 -0.305054)
			(end 0.12065 -0.305054)
			(stroke
				(width 0.1)
				(type default)
			)
			(layer "B.Fab")
		)
		(fp_line
			(start 0.12065 0.3048)
			(end 0.67945 0.3048)
			(stroke
				(width 0.1)
				(type default)
			)
			(layer "B.Fab")
		)
		(fp_line
			(start 0.12065 0.2794)
			(end 0.12065 0.3048)
			(stroke
				(width 0.1)
				(type default)
			)
			(layer "B.Fab")
		)
		(fp_line
			(start 0.12065 -0.2794)
			(end -0.12065 -0.2794)
			(stroke
				(width 0.1)
				(type default)
			)
			(layer "B.Fab")
		)
		(fp_line
			(start 0.12065 -0.305054)
			(end 0.12065 -0.2794)
			(stroke
				(width 0.1)
				(type default)
			)
			(layer "B.Fab")
		)
		(fp_line
			(start -0.120396 0.3048)
			(end -0.120396 0.2794)
			(stroke
				(width 0.1)
				(type default)
			)
			(layer "B.Fab")
		)
		(fp_line
			(start -0.120396 0.2794)
			(end 0.12065 0.2794)
			(stroke
				(width 0.1)
				(type default)
			)
			(layer "B.Fab")
		)
		(fp_line
			(start -0.12065 -0.2794)
			(end -0.12065 -0.3048)
			(stroke
				(width 0.1)
				(type default)
			)
			(layer "B.Fab")
		)
		(fp_line
			(start -0.12065 -0.3048)
			(end -0.67945 -0.3048)
			(stroke
				(width 0.1)
				(type default)
			)
			(layer "B.Fab")
		)
		(fp_line
			(start -0.67945 0.3048)
			(end -0.120396 0.3048)
			(stroke
				(width 0.1)
				(type default)
			)
			(layer "B.Fab")
		)
		(fp_line
			(start -0.67945 -0.3048)
			(end -0.67945 0.3048)
			(stroke
				(width 0.1)
				(type default)
			)
			(layer "B.Fab")
		)
		(pad "1" smd circle
			(at 0.40005 0)
			(size 0 0)
			(layers "B.Cu" "B.Mask" "B.Paste")
			(net "P12V_AUX")
		)
		(pad "2" smd circle
			(at -0.40005 0)
			(size 0 0)
			(layers "B.Cu" "B.Mask" "B.Paste")
			(net "PVCCINFAON_CPU0_CSPIN")
		)
	)
	(footprint ""
		(layer "B.Cu")
		(at 114.693446 -358.566212 180)
		(property "Reference" "PR637"
			(at 0 0 0)
			(layer "B.SilkS")
			(hide yes)
			(effects
				(font
					(size 1.27 1.27)
				)
				(justify mirror)
			)
		)
		(property "Value" ""
			(at 0 0 0)
			(layer "B.Fab")
			(effects
				(font
					(size 1.27 1.27)
				)
				(justify mirror)
			)
		)
		(duplicate_pad_numbers_are_jumpers no)
		(fp_line
			(start 0.7874 0.4064)
			(end 0.7874 -0.4064)
			(stroke
				(width 0.1524)
				(type default)
			)
			(layer "B.SilkS")
		)
		(fp_line
			(start 0.7874 -0.4064)
			(end -0.7874 -0.4064)
			(stroke
				(width 0.1524)
				(type default)
			)
			(layer "B.SilkS")
		)
		(fp_line
			(start -0.7874 0.4064)
			(end 0.7874 0.4064)
			(stroke
				(width 0.1524)
				(type default)
			)
			(layer "B.SilkS")
		)
		(fp_line
			(start -0.7874 -0.4064)
			(end -0.7874 0.4064)
			(stroke
				(width 0.1524)
				(type default)
			)
			(layer "B.SilkS")
		)
		(fp_line
			(start 0.67945 0.3048)
			(end 0.67945 -0.305054)
			(stroke
				(width 0.1)
				(type default)
			)
			(layer "B.Fab")
		)
		(fp_line
			(start 0.67945 -0.305054)
			(end 0.12065 -0.305054)
			(stroke
				(width 0.1)
				(type default)
			)
			(layer "B.Fab")
		)
		(fp_line
			(start 0.12065 0.3048)
			(end 0.67945 0.3048)
			(stroke
				(width 0.1)
				(type default)
			)
			(layer "B.Fab")
		)
		(fp_line
			(start 0.12065 0.2794)
			(end 0.12065 0.3048)
			(stroke
				(width 0.1)
				(type default)
			)
			(layer "B.Fab")
		)
		(fp_line
			(start 0.12065 -0.2794)
			(end -0.12065 -0.2794)
			(stroke
				(width 0.1)
				(type default)
			)
			(layer "B.Fab")
		)
		(fp_line
			(start 0.12065 -0.305054)
			(end 0.12065 -0.2794)
			(stroke
				(width 0.1)
				(type default)
			)
			(layer "B.Fab")
		)
		(fp_line
			(start -0.120396 0.3048)
			(end -0.120396 0.2794)
			(stroke
				(width 0.1)
				(type default)
			)
			(layer "B.Fab")
		)
		(fp_line
			(start -0.120396 0.2794)
			(end 0.12065 0.2794)
			(stroke
				(width 0.1)
				(type default)
			)
			(layer "B.Fab")
		)
		(fp_line
			(start -0.12065 -0.2794)
			(end -0.12065 -0.3048)
			(stroke
				(width 0.1)
				(type default)
			)
			(layer "B.Fab")
		)
		(fp_line
			(start -0.12065 -0.3048)
			(end -0.67945 -0.3048)
			(stroke
				(width 0.1)
				(type default)
			)
			(layer "B.Fab")
		)
		(fp_line
			(start -0.67945 0.3048)
			(end -0.120396 0.3048)
			(stroke
				(width 0.1)
				(type default)
			)
			(layer "B.Fab")
		)
		(fp_line
			(start -0.67945 -0.3048)
			(end -0.67945 0.3048)
			(stroke
				(width 0.1)
				(type default)
			)
			(layer "B.Fab")
		)
		(pad "1" smd circle
			(at 0.40005 0)
			(size 0 0)
			(layers "B.Cu" "B.Mask" "B.Paste")
			(net "PVCCIN_CPU1_ATSEN")
		)
		(pad "2" smd circle
			(at -0.40005 0)
			(size 0 0)
			(layers "B.Cu" "B.Mask" "B.Paste")
			(net "GND")
		)
	)
	(footprint ""
		(layer "B.Cu")
		(at 126.065026 -339.602572 -90)
		(property "Reference" "PR296"
			(at 0 0 90)
			(layer "B.SilkS")
			(hide yes)
			(effects
				(font
					(size 1.27 1.27)
				)
				(justify mirror)
			)
		)
		(property "Value" ""
			(at 0 0 90)
			(layer "B.Fab")
			(effects
				(font
					(size 1.27 1.27)
				)
				(justify mirror)
			)
		)
		(duplicate_pad_numbers_are_jumpers no)
		(fp_line
			(start -0.7874 0.4064)
			(end 0.7874 0.4064)
			(stroke
				(width 0.1524)
				(type default)
			)
			(layer "B.SilkS")
		)
		(fp_line
			(start 0.7874 0.4064)
			(end 0.7874 -0.4064)
			(stroke
				(width 0.1524)
				(type default)
			)
			(layer "B.SilkS")
		)
		(fp_line
			(start -0.7874 -0.4064)
			(end -0.7874 0.4064)
			(stroke
				(width 0.1524)
				(type default)
			)
			(layer "B.SilkS")
		)
		(fp_line
			(start 0.7874 -0.4064)
			(end -0.7874 -0.4064)
			(stroke
				(width 0.1524)
				(type default)
			)
			(layer "B.SilkS")
		)
		(fp_line
			(start -0.67945 0.3048)
			(end -0.120396 0.3048)
			(stroke
				(width 0.1)
				(type default)
			)
			(layer "B.Fab")
		)
		(fp_line
			(start -0.120396 0.3048)
			(end -0.120396 0.2794)
			(stroke
				(width 0.1)
				(type default)
			)
			(layer "B.Fab")
		)
		(fp_line
			(start 0.12065 0.3048)
			(end 0.67945 0.3048)
			(stroke
				(width 0.1)
				(type default)
			)
			(layer "B.Fab")
		)
		(fp_line
			(start 0.67945 0.3048)
			(end 0.67945 -0.305054)
			(stroke
				(width 0.1)
				(type default)
			)
			(layer "B.Fab")
		)
		(fp_line
			(start -0.120396 0.2794)
			(end 0.12065 0.2794)
			(stroke
				(width 0.1)
				(type default)
			)
			(layer "B.Fab")
		)
		(fp_line
			(start 0.12065 0.2794)
			(end 0.12065 0.3048)
			(stroke
				(width 0.1)
				(type default)
			)
			(layer "B.Fab")
		)
		(fp_line
			(start -0.12065 -0.2794)
			(end -0.12065 -0.3048)
			(stroke
				(width 0.1)
				(type default)
			)
			(layer "B.Fab")
		)
		(fp_line
			(start 0.12065 -0.2794)
			(end -0.12065 -0.2794)
			(stroke
				(width 0.1)
				(type default)
			)
			(layer "B.Fab")
		)
		(fp_line
			(start -0.67945 -0.3048)
			(end -0.67945 0.3048)
			(stroke
				(width 0.1)
				(type default)
			)
			(layer "B.Fab")
		)
		(fp_line
			(start -0.12065 -0.3048)
			(end -0.67945 -0.3048)
			(stroke
				(width 0.1)
				(type default)
			)
			(layer "B.Fab")
		)
		(fp_line
			(start 0.12065 -0.305054)
			(end 0.12065 -0.2794)
			(stroke
				(width 0.1)
				(type default)
			)
			(layer "B.Fab")
		)
		(fp_line
			(start 0.67945 -0.305054)
			(end 0.12065 -0.305054)
			(stroke
				(width 0.1)
				(type default)
			)
			(layer "B.Fab")
		)
		(pad "1" smd circle
			(at 0.40005 0 90)
			(size 0 0)
			(layers "B.Cu" "B.Mask" "B.Paste")
			(net "PVCCIN_CPU1_VOS5")
		)
		(pad "2" smd circle
			(at -0.40005 0 90)
			(size 0 0)
			(layers "B.Cu" "B.Mask" "B.Paste")
			(net "PVCCIN_CPU1")
		)
	)
	(footprint ""
		(layer "B.Cu")
		(at 366.120934 -252.176026 -90)
		(property "Reference" "C367"
			(at 0 0 90)
			(layer "B.SilkS")
			(hide yes)
			(effects
				(font
					(size 1.27 1.27)
				)
				(justify mirror)
			)
		)
		(property "Value" ""
			(at 0 0 90)
			(layer "B.Fab")
			(effects
				(font
					(size 1.27 1.27)
				)
				(justify mirror)
			)
		)
		(duplicate_pad_numbers_are_jumpers no)
		(fp_line
			(start -1.524 0.762)
			(end 1.524 0.762)
			(stroke
				(width 0.1524)
				(type default)
			)
			(layer "B.SilkS")
		)
		(fp_line
			(start 1.524 0.762)
			(end 1.524 -0.762)
			(stroke
				(width 0.1524)
				(type default)
			)
			(layer "B.SilkS")
		)
		(fp_line
			(start -1.524 -0.762)
			(end -1.524 0.762)
			(stroke
				(width 0.1524)
				(type default)
			)
			(layer "B.SilkS")
		)
		(fp_line
			(start 1.524 -0.762)
			(end -1.524 -0.762)
			(stroke
				(width 0.1524)
				(type default)
			)
			(layer "B.SilkS")
		)
		(fp_line
			(start -1.1049 0.724916)
			(end -1.1049 -0.724916)
			(stroke
				(width 0.1)
				(type default)
			)
			(layer "B.Fab")
		)
		(fp_line
			(start 1.1049 0.724916)
			(end -1.1049 0.724916)
			(stroke
				(width 0.1)
				(type default)
			)
			(layer "B.Fab")
		)
		(fp_line
			(start -1.1049 -0.724916)
			(end 1.1049 -0.724916)
			(stroke
				(width 0.1)
				(type default)
			)
			(layer "B.Fab")
		)
		(fp_line
			(start 1.1049 -0.724916)
			(end 1.1049 0.724916)
			(stroke
				(width 0.1)
				(type default)
			)
			(layer "B.Fab")
		)
		(pad "1" smd rect
			(at 0.889 0 270)
			(size 1.016 1.27)
			(layers "B.Cu" "B.Mask" "B.Paste")
			(net "PVCCIN_CPU0")
		)
		(pad "2" smd rect
			(at -0.889 0 270)
			(size 1.016 1.27)
			(layers "B.Cu" "B.Mask" "B.Paste")
			(net "GND")
		)
	)
	(footprint ""
		(layer "B.Cu")
		(at 197.41388 -107.495848)
		(property "Reference" "R4056"
			(at 0 0 0)
			(layer "B.SilkS")
			(hide yes)
			(effects
				(font
					(size 1.27 1.27)
				)
				(justify mirror)
			)
		)
		(property "Value" ""
			(at 0 0 0)
			(layer "B.Fab")
			(effects
				(font
					(size 1.27 1.27)
				)
				(justify mirror)
			)
		)
		(duplicate_pad_numbers_are_jumpers no)
		(fp_line
			(start -0.7874 -0.4064)
			(end -0.7874 0.4064)
			(stroke
				(width 0.1524)
				(type default)
			)
			(layer "B.SilkS")
		)
		(fp_line
			(start -0.7874 0.4064)
			(end 0.7874 0.4064)
			(stroke
				(width 0.1524)
				(type default)
			)
			(layer "B.SilkS")
		)
		(fp_line
			(start 0.7874 -0.4064)
			(end -0.7874 -0.4064)
			(stroke
				(width 0.1524)
				(type default)
			)
			(layer "B.SilkS")
		)
		(fp_line
			(start 0.7874 0.4064)
			(end 0.7874 -0.4064)
			(stroke
				(width 0.1524)
				(type default)
			)
			(layer "B.SilkS")
		)
		(fp_line
			(start -0.67945 -0.3048)
			(end -0.67945 0.3048)
			(stroke
				(width 0.1)
				(type default)
			)
			(layer "B.Fab")
		)
		(fp_line
			(start -0.67945 0.3048)
			(end -0.120396 0.3048)
			(stroke
				(width 0.1)
				(type default)
			)
			(layer "B.Fab")
		)
		(fp_line
			(start -0.12065 -0.3048)
			(end -0.67945 -0.3048)
			(stroke
				(width 0.1)
				(type default)
			)
			(layer "B.Fab")
		)
		(fp_line
			(start -0.12065 -0.2794)
			(end -0.12065 -0.3048)
			(stroke
				(width 0.1)
				(type default)
			)
			(layer "B.Fab")
		)
		(fp_line
			(start -0.120396 0.2794)
			(end 0.12065 0.2794)
			(stroke
				(width 0.1)
				(type default)
			)
			(layer "B.Fab")
		)
		(fp_line
			(start -0.120396 0.3048)
			(end -0.120396 0.2794)
			(stroke
				(width 0.1)
				(type default)
			)
			(layer "B.Fab")
		)
		(fp_line
			(start 0.12065 -0.305054)
			(end 0.12065 -0.2794)
			(stroke
				(width 0.1)
				(type default)
			)
			(layer "B.Fab")
		)
		(fp_line
			(start 0.12065 -0.2794)
			(end -0.12065 -0.2794)
			(stroke
				(width 0.1)
				(type default)
			)
			(layer "B.Fab")
		)
		(fp_line
			(start 0.12065 0.2794)
			(end 0.12065 0.3048)
			(stroke
				(width 0.1)
				(type default)
			)
			(layer "B.Fab")
		)
		(fp_line
			(start 0.12065 0.3048)
			(end 0.67945 0.3048)
			(stroke
				(width 0.1)
				(type default)
			)
			(layer "B.Fab")
		)
		(fp_line
			(start 0.67945 -0.305054)
			(end 0.12065 -0.305054)
			(stroke
				(width 0.1)
				(type default)
			)
			(layer "B.Fab")
		)
		(fp_line
			(start 0.67945 0.3048)
			(end 0.67945 -0.305054)
			(stroke
				(width 0.1)
				(type default)
			)
			(layer "B.Fab")
		)
		(pad "1" smd circle
			(at 0.40005 0 180)
			(size 0 0)
			(layers "B.Cu" "B.Mask" "B.Paste")
			(net "HSC_D_OC")
		)
		(pad "2" smd circle
			(at -0.40005 0 180)
			(size 0 0)
			(layers "B.Cu" "B.Mask" "B.Paste")
			(net "HSC_D_OC_R1")
		)
	)
	(footprint ""
		(layer "B.Cu")
		(at 229.87254 -125.040898 -90)
		(property "Reference" "C204"
			(at 0 0 90)
			(layer "B.SilkS")
			(hide yes)
			(effects
				(font
					(size 1.27 1.27)
				)
				(justify mirror)
			)
		)
		(property "Value" ""
			(at 0 0 90)
			(layer "B.Fab")
			(effects
				(font
					(size 1.27 1.27)
				)
				(justify mirror)
			)
		)
		(duplicate_pad_numbers_are_jumpers no)
		(fp_line
			(start -0.7874 0.4064)
			(end 0.7874 0.4064)
			(stroke
				(width 0.1524)
				(type default)
			)
			(layer "B.SilkS")
		)
		(fp_line
			(start 0.7874 0.4064)
			(end 0.7874 -0.4064)
			(stroke
				(width 0.1524)
				(type default)
			)
			(layer "B.SilkS")
		)
		(fp_line
			(start -0.7874 -0.4064)
			(end -0.7874 0.4064)
			(stroke
				(width 0.1524)
				(type default)
			)
			(layer "B.SilkS")
		)
		(fp_line
			(start 0.7874 -0.4064)
			(end -0.7874 -0.4064)
			(stroke
				(width 0.1524)
				(type default)
			)
			(layer "B.SilkS")
		)
		(fp_line
			(start -0.67945 0.3048)
			(end -0.120396 0.3048)
			(stroke
				(width 0.1)
				(type default)
			)
			(layer "B.Fab")
		)
		(fp_line
			(start -0.120396 0.3048)
			(end -0.120396 0.2794)
			(stroke
				(width 0.1)
				(type default)
			)
			(layer "B.Fab")
		)
		(fp_line
			(start 0.12065 0.3048)
			(end 0.67945 0.3048)
			(stroke
				(width 0.1)
				(type default)
			)
			(layer "B.Fab")
		)
		(fp_line
			(start 0.67945 0.3048)
			(end 0.67945 -0.305054)
			(stroke
				(width 0.1)
				(type default)
			)
			(layer "B.Fab")
		)
		(fp_line
			(start -0.120396 0.2794)
			(end 0.12065 0.2794)
			(stroke
				(width 0.1)
				(type default)
			)
			(layer "B.Fab")
		)
		(fp_line
			(start 0.12065 0.2794)
			(end 0.12065 0.3048)
			(stroke
				(width 0.1)
				(type default)
			)
			(layer "B.Fab")
		)
		(fp_line
			(start -0.12065 -0.2794)
			(end -0.12065 -0.3048)
			(stroke
				(width 0.1)
				(type default)
			)
			(layer "B.Fab")
		)
		(fp_line
			(start 0.12065 -0.2794)
			(end -0.12065 -0.2794)
			(stroke
				(width 0.1)
				(type default)
			)
			(layer "B.Fab")
		)
		(fp_line
			(start -0.67945 -0.3048)
			(end -0.67945 0.3048)
			(stroke
				(width 0.1)
				(type default)
			)
			(layer "B.Fab")
		)
		(fp_line
			(start -0.12065 -0.3048)
			(end -0.67945 -0.3048)
			(stroke
				(width 0.1)
				(type default)
			)
			(layer "B.Fab")
		)
		(fp_line
			(start 0.12065 -0.305054)
			(end 0.12065 -0.2794)
			(stroke
				(width 0.1)
				(type default)
			)
			(layer "B.Fab")
		)
		(fp_line
			(start 0.67945 -0.305054)
			(end 0.12065 -0.305054)
			(stroke
				(width 0.1)
				(type default)
			)
			(layer "B.Fab")
		)
		(pad "1" smd circle
			(at 0.40005 0 90)
			(size 0 0)
			(layers "B.Cu" "B.Mask" "B.Paste")
			(net "P3V3_DB2000_VDD")
		)
		(pad "2" smd circle
			(at -0.40005 0 90)
			(size 0 0)
			(layers "B.Cu" "B.Mask" "B.Paste")
			(net "GND")
		)
	)
	(footprint ""
		(layer "B.Cu")
		(at 287.448498 -403.031452 90)
		(property "Reference" "PR2519"
			(at 0 0 90)
			(layer "B.SilkS")
			(hide yes)
			(effects
				(font
					(size 1.27 1.27)
				)
				(justify mirror)
			)
		)
		(property "Value" ""
			(at 0 0 90)
			(layer "B.Fab")
			(effects
				(font
					(size 1.27 1.27)
				)
				(justify mirror)
			)
		)
		(duplicate_pad_numbers_are_jumpers no)
		(fp_line
			(start 0.7874 -0.4064)
			(end -0.7874 -0.4064)
			(stroke
				(width 0.1524)
				(type default)
			)
			(layer "B.SilkS")
		)
		(fp_line
			(start -0.7874 -0.4064)
			(end -0.7874 0.4064)
			(stroke
				(width 0.1524)
				(type default)
			)
			(layer "B.SilkS")
		)
		(fp_line
			(start 0.7874 0.4064)
			(end 0.7874 -0.4064)
			(stroke
				(width 0.1524)
				(type default)
			)
			(layer "B.SilkS")
		)
		(fp_line
			(start -0.7874 0.4064)
			(end 0.7874 0.4064)
			(stroke
				(width 0.1524)
				(type default)
			)
			(layer "B.SilkS")
		)
		(fp_line
			(start 0.67945 -0.305054)
			(end 0.12065 -0.305054)
			(stroke
				(width 0.1)
				(type default)
			)
			(layer "B.Fab")
		)
		(fp_line
			(start 0.12065 -0.305054)
			(end 0.12065 -0.2794)
			(stroke
				(width 0.1)
				(type default)
			)
			(layer "B.Fab")
		)
		(fp_line
			(start -0.12065 -0.3048)
			(end -0.67945 -0.3048)
			(stroke
				(width 0.1)
				(type default)
			)
			(layer "B.Fab")
		)
		(fp_line
			(start -0.67945 -0.3048)
			(end -0.67945 0.3048)
			(stroke
				(width 0.1)
				(type default)
			)
			(layer "B.Fab")
		)
		(fp_line
			(start 0.12065 -0.2794)
			(end -0.12065 -0.2794)
			(stroke
				(width 0.1)
				(type default)
			)
			(layer "B.Fab")
		)
		(fp_line
			(start -0.12065 -0.2794)
			(end -0.12065 -0.3048)
			(stroke
				(width 0.1)
				(type default)
			)
			(layer "B.Fab")
		)
		(fp_line
			(start 0.12065 0.2794)
			(end 0.12065 0.3048)
			(stroke
				(width 0.1)
				(type default)
			)
			(layer "B.Fab")
		)
		(fp_line
			(start -0.120396 0.2794)
			(end 0.12065 0.2794)
			(stroke
				(width 0.1)
				(type default)
			)
			(layer "B.Fab")
		)
		(fp_line
			(start 0.67945 0.3048)
			(end 0.67945 -0.305054)
			(stroke
				(width 0.1)
				(type default)
			)
			(layer "B.Fab")
		)
		(fp_line
			(start 0.12065 0.3048)
			(end 0.67945 0.3048)
			(stroke
				(width 0.1)
				(type default)
			)
			(layer "B.Fab")
		)
		(fp_line
			(start -0.120396 0.3048)
			(end -0.120396 0.2794)
			(stroke
				(width 0.1)
				(type default)
			)
			(layer "B.Fab")
		)
		(fp_line
			(start -0.67945 0.3048)
			(end -0.120396 0.3048)
			(stroke
				(width 0.1)
				(type default)
			)
			(layer "B.Fab")
		)
		(pad "1" smd circle
			(at 0.40005 0 270)
			(size 0 0)
			(layers "B.Cu" "B.Mask" "B.Paste")
			(net "P12V_HSC_ADC_N")
		)
		(pad "2" smd circle
			(at -0.40005 0 270)
			(size 0 0)
			(layers "B.Cu" "B.Mask" "B.Paste")
			(net "P12V_HSC_SENSE1_N")
		)
	)
	(footprint ""
		(layer "B.Cu")
		(at 75.745594 -45.536866 90)
		(property "Reference" "C2020"
			(at 0 0 90)
			(layer "B.SilkS")
			(hide yes)
			(effects
				(font
					(size 1.27 1.27)
				)
				(justify mirror)
			)
		)
		(property "Value" ""
			(at 0 0 90)
			(layer "B.Fab")
			(effects
				(font
					(size 1.27 1.27)
				)
				(justify mirror)
			)
		)
		(duplicate_pad_numbers_are_jumpers no)
		(fp_line
			(start 0.7874 -0.4064)
			(end -0.7874 -0.4064)
			(stroke
				(width 0.1524)
				(type default)
			)
			(layer "B.SilkS")
		)
		(fp_line
			(start -0.7874 -0.4064)
			(end -0.7874 0.4064)
			(stroke
				(width 0.1524)
				(type default)
			)
			(layer "B.SilkS")
		)
		(fp_line
			(start 0.7874 0.4064)
			(end 0.7874 -0.4064)
			(stroke
				(width 0.1524)
				(type default)
			)
			(layer "B.SilkS")
		)
		(fp_line
			(start -0.7874 0.4064)
			(end 0.7874 0.4064)
			(stroke
				(width 0.1524)
				(type default)
			)
			(layer "B.SilkS")
		)
		(fp_line
			(start 0.67945 -0.305054)
			(end 0.12065 -0.305054)
			(stroke
				(width 0.1)
				(type default)
			)
			(layer "B.Fab")
		)
		(fp_line
			(start 0.12065 -0.305054)
			(end 0.12065 -0.2794)
			(stroke
				(width 0.1)
				(type default)
			)
			(layer "B.Fab")
		)
		(fp_line
			(start -0.12065 -0.3048)
			(end -0.67945 -0.3048)
			(stroke
				(width 0.1)
				(type default)
			)
			(layer "B.Fab")
		)
		(fp_line
			(start -0.67945 -0.3048)
			(end -0.67945 0.3048)
			(stroke
				(width 0.1)
				(type default)
			)
			(layer "B.Fab")
		)
		(fp_line
			(start 0.12065 -0.2794)
			(end -0.12065 -0.2794)
			(stroke
				(width 0.1)
				(type default)
			)
			(layer "B.Fab")
		)
		(fp_line
			(start -0.12065 -0.2794)
			(end -0.12065 -0.3048)
			(stroke
				(width 0.1)
				(type default)
			)
			(layer "B.Fab")
		)
		(fp_line
			(start 0.12065 0.2794)
			(end 0.12065 0.3048)
			(stroke
				(width 0.1)
				(type default)
			)
			(layer "B.Fab")
		)
		(fp_line
			(start -0.120396 0.2794)
			(end 0.12065 0.2794)
			(stroke
				(width 0.1)
				(type default)
			)
			(layer "B.Fab")
		)
		(fp_line
			(start 0.67945 0.3048)
			(end 0.67945 -0.305054)
			(stroke
				(width 0.1)
				(type default)
			)
			(layer "B.Fab")
		)
		(fp_line
			(start 0.12065 0.3048)
			(end 0.67945 0.3048)
			(stroke
				(width 0.1)
				(type default)
			)
			(layer "B.Fab")
		)
		(fp_line
			(start -0.120396 0.3048)
			(end -0.120396 0.2794)
			(stroke
				(width 0.1)
				(type default)
			)
			(layer "B.Fab")
		)
		(fp_line
			(start -0.67945 0.3048)
			(end -0.120396 0.3048)
			(stroke
				(width 0.1)
				(type default)
			)
			(layer "B.Fab")
		)
		(pad "1" smd circle
			(at 0.40005 0 270)
			(size 0 0)
			(layers "B.Cu" "B.Mask" "B.Paste")
			(net "VSENSE_P12V_INA230_3_INP")
		)
		(pad "2" smd circle
			(at -0.40005 0 270)
			(size 0 0)
			(layers "B.Cu" "B.Mask" "B.Paste")
			(net "VSENSE_P12V_INA230_3_INN")
		)
	)
	(footprint ""
		(layer "B.Cu")
		(at 378.099574 2.923794)
		(property "Reference" "J117"
			(at 4.651756 1.394206 270)
			(unlocked yes)
			(layer "B.SilkS")
			(effects
				(font
					(size 0.7874 0.5842)
					(thickness 0.1524)
				)
				(justify left mirror)
			)
		)
		(property "Value" ""
			(at 0 0 0)
			(layer "B.Fab")
			(effects
				(font
					(size 1.27 1.27)
				)
				(justify mirror)
			)
		)
		(duplicate_pad_numbers_are_jumpers no)
		(fp_line
			(start -1.2192 -2.1082)
			(end -1.2192 2.1082)
			(stroke
				(width 0.1524)
				(type default)
			)
			(layer "B.SilkS")
		)
		(fp_line
			(start -1.2192 2.1082)
			(end 1.2192 2.1082)
			(stroke
				(width 0.1524)
				(type default)
			)
			(layer "B.SilkS")
		)
		(fp_line
			(start 1.2192 -2.1082)
			(end -1.2192 -2.1082)
			(stroke
				(width 0.1524)
				(type default)
			)
			(layer "B.SilkS")
		)
		(fp_line
			(start 1.2192 2.1082)
			(end 1.2192 -2.1082)
			(stroke
				(width 0.1524)
				(type default)
			)
			(layer "B.SilkS")
		)
		(pad "" np_thru_hole circle
			(at -3.4671 -1.27 270)
			(size 1.0414 1.0414)
			(drill 1.0414)
			(layers "*.Cu" "*.Mask")
			(clearance 0.381)
			(thermal_gap 0.381)
		)
		(pad "" np_thru_hole circle
			(at -3.4671 1.27 270)
			(size 1.0414 1.0414)
			(drill 1.0414)
			(layers "*.Cu" "*.Mask")
			(clearance 0.381)
			(thermal_gap 0.381)
		)
		(pad "" np_thru_hole circle
			(at 2.8829 -1.27 270)
			(size 1.0414 1.0414)
			(drill 1.0414)
			(layers "*.Cu" "*.Mask")
			(clearance 0.381)
			(thermal_gap 0.381)
		)
		(pad "" np_thru_hole circle
			(at 2.8829 1.27 270)
			(size 1.0414 1.0414)
			(drill 1.0414)
			(layers "*.Cu" "*.Mask")
			(clearance 0.381)
			(thermal_gap 0.381)
		)
		(pad "1" smd rect
			(at -0.8255 -0.249936 270)
			(size 0.3048 0.508)
			(layers "B.Cu" "B.Mask" "B.Paste")
			(net "DELTA_L_85_5INCH_IN6_DN")
		)
		(pad "2" smd rect
			(at -0.8255 0.249936 270)
			(size 0.3048 0.508)
			(layers "B.Cu" "B.Mask" "B.Paste")
			(net "DELTA_L_85_5INCH_IN6_DP")
		)
		(pad "3" smd circle
			(at 0 0 180)
			(size 0 0)
			(layers "B.Cu" "B.Mask" "B.Paste")
			(net "DELTA_L_GND_1")
		)
		(zone
			(layers "F.Cu" "B.Cu" "In1.Cu" "In2.Cu" "In3.Cu" "In4.Cu" "In5.Cu" "In6.Cu"
				"In7.Cu" "In8.Cu" "In9.Cu" "In10.Cu" "In11.Cu" "In12.Cu" "In13.Cu" "In14.Cu"
				"In15.Cu" "In16.Cu"
			)
			(hatch none 0.5)
			(connect_pads
				(clearance 0)
			)
			(min_thickness 0.25)
			(keepout
				(tracks not_allowed)
				(vias allowed)
				(pads allowed)
				(copperpour not_allowed)
				(footprints allowed)
			)
			(placement
				(enabled no)
				(sheetname "")
			)
			(fill
				(thermal_gap 0.5)
				(thermal_bridge_width 0.5)
				(island_removal_mode 0)
			)
			(polygon
				(pts
					(arc
						(start 375.559574 1.653794)
						(mid 373.705374 1.653794)
						(end 375.559574 1.653794)
					)
				)
			)
		)
		(zone
			(layers "F.Cu" "B.Cu" "In1.Cu" "In2.Cu" "In3.Cu" "In4.Cu" "In5.Cu" "In6.Cu"
				"In7.Cu" "In8.Cu" "In9.Cu" "In10.Cu" "In11.Cu" "In12.Cu" "In13.Cu" "In14.Cu"
				"In15.Cu" "In16.Cu"
			)
			(hatch none 0.5)
			(connect_pads
				(clearance 0)
			)
			(min_thickness 0.25)
			(keepout
				(tracks not_allowed)
				(vias allowed)
				(pads allowed)
				(copperpour not_allowed)
				(footprints allowed)
			)
			(placement
				(enabled no)
				(sheetname "")
			)
			(fill
				(thermal_gap 0.5)
				(thermal_bridge_width 0.5)
				(island_removal_mode 0)
			)
			(polygon
				(pts
					(arc
						(start 375.559574 4.193794)
						(mid 373.705374 4.193794)
						(end 375.559574 4.193794)
					)
				)
			)
		)
		(zone
			(layers "F.Cu" "B.Cu" "In1.Cu" "In2.Cu" "In3.Cu" "In4.Cu" "In5.Cu" "In6.Cu"
				"In7.Cu" "In8.Cu" "In9.Cu" "In10.Cu" "In11.Cu" "In12.Cu" "In13.Cu" "In14.Cu"
				"In15.Cu" "In16.Cu"
			)
			(hatch none 0.5)
			(connect_pads
				(clearance 0)
			)
			(min_thickness 0.25)
			(keepout
				(tracks not_allowed)
				(vias allowed)
				(pads allowed)
				(copperpour not_allowed)
				(footprints allowed)
			)
			(placement
				(enabled no)
				(sheetname "")
			)
			(fill
				(thermal_gap 0.5)
				(thermal_bridge_width 0.5)
				(island_removal_mode 0)
			)
			(polygon
				(pts
					(arc
						(start 381.909574 1.653794)
						(mid 380.055374 1.653794)
						(end 381.909574 1.653794)
					)
				)
			)
		)
		(zone
			(layers "F.Cu" "B.Cu" "In1.Cu" "In2.Cu" "In3.Cu" "In4.Cu" "In5.Cu" "In6.Cu"
				"In7.Cu" "In8.Cu" "In9.Cu" "In10.Cu" "In11.Cu" "In12.Cu" "In13.Cu" "In14.Cu"
				"In15.Cu" "In16.Cu"
			)
			(hatch none 0.5)
			(connect_pads
				(clearance 0)
			)
			(min_thickness 0.25)
			(keepout
				(tracks not_allowed)
				(vias allowed)
				(pads allowed)
				(copperpour not_allowed)
				(footprints allowed)
			)
			(placement
				(enabled no)
				(sheetname "")
			)
			(fill
				(thermal_gap 0.5)
				(thermal_bridge_width 0.5)
				(island_removal_mode 0)
			)
			(polygon
				(pts
					(arc
						(start 381.909574 4.193794)
						(mid 380.055374 4.193794)
						(end 381.909574 4.193794)
					)
				)
			)
		)
		(zone
			(layer "B.Cu")
			(hatch none 0.5)
			(connect_pads
				(clearance 0)
			)
			(min_thickness 0.25)
			(keepout
				(tracks not_allowed)
				(vias allowed)
				(pads allowed)
				(copperpour not_allowed)
				(footprints allowed)
			)
			(placement
				(enabled no)
				(sheetname "")
			)
			(fill
				(thermal_gap 0.5)
				(thermal_bridge_width 0.5)
				(island_removal_mode 0)
			)
			(polygon
				(pts
					(xy 376.981974 2.375154) (xy 376.981974 2.470658) (xy 377.578874 2.470658) (xy 377.578874 2.877058)
					(xy 376.981974 2.877058) (xy 376.981974 2.97053) (xy 377.578874 2.97053) (xy 377.578874 3.37693)
					(xy 376.981974 3.37693) (xy 376.981974 3.472434) (xy 377.680474 3.472434) (xy 377.680474 2.375154)
				)
			)
		)
	)
	(footprint ""
		(layer "B.Cu")
		(at 215.840818 -317.06566 90)
		(property "Reference" "R2497"
			(at 0 0 90)
			(layer "B.SilkS")
			(hide yes)
			(effects
				(font
					(size 1.27 1.27)
				)
				(justify mirror)
			)
		)
		(property "Value" ""
			(at 0 0 90)
			(layer "B.Fab")
			(effects
				(font
					(size 1.27 1.27)
				)
				(justify mirror)
			)
		)
		(duplicate_pad_numbers_are_jumpers no)
		(fp_line
			(start 0.7874 -0.4064)
			(end -0.7874 -0.4064)
			(stroke
				(width 0.1524)
				(type default)
			)
			(layer "B.SilkS")
		)
		(fp_line
			(start -0.7874 -0.4064)
			(end -0.7874 0.4064)
			(stroke
				(width 0.1524)
				(type default)
			)
			(layer "B.SilkS")
		)
		(fp_line
			(start 0.7874 0.4064)
			(end 0.7874 -0.4064)
			(stroke
				(width 0.1524)
				(type default)
			)
			(layer "B.SilkS")
		)
		(fp_line
			(start -0.7874 0.4064)
			(end 0.7874 0.4064)
			(stroke
				(width 0.1524)
				(type default)
			)
			(layer "B.SilkS")
		)
		(fp_line
			(start 0.67945 -0.305054)
			(end 0.12065 -0.305054)
			(stroke
				(width 0.1)
				(type default)
			)
			(layer "B.Fab")
		)
		(fp_line
			(start 0.12065 -0.305054)
			(end 0.12065 -0.2794)
			(stroke
				(width 0.1)
				(type default)
			)
			(layer "B.Fab")
		)
		(fp_line
			(start -0.12065 -0.3048)
			(end -0.67945 -0.3048)
			(stroke
				(width 0.1)
				(type default)
			)
			(layer "B.Fab")
		)
		(fp_line
			(start -0.67945 -0.3048)
			(end -0.67945 0.3048)
			(stroke
				(width 0.1)
				(type default)
			)
			(layer "B.Fab")
		)
		(fp_line
			(start 0.12065 -0.2794)
			(end -0.12065 -0.2794)
			(stroke
				(width 0.1)
				(type default)
			)
			(layer "B.Fab")
		)
		(fp_line
			(start -0.12065 -0.2794)
			(end -0.12065 -0.3048)
			(stroke
				(width 0.1)
				(type default)
			)
			(layer "B.Fab")
		)
		(fp_line
			(start 0.12065 0.2794)
			(end 0.12065 0.3048)
			(stroke
				(width 0.1)
				(type default)
			)
			(layer "B.Fab")
		)
		(fp_line
			(start -0.120396 0.2794)
			(end 0.12065 0.2794)
			(stroke
				(width 0.1)
				(type default)
			)
			(layer "B.Fab")
		)
		(fp_line
			(start 0.67945 0.3048)
			(end 0.67945 -0.305054)
			(stroke
				(width 0.1)
				(type default)
			)
			(layer "B.Fab")
		)
		(fp_line
			(start 0.12065 0.3048)
			(end 0.67945 0.3048)
			(stroke
				(width 0.1)
				(type default)
			)
			(layer "B.Fab")
		)
		(fp_line
			(start -0.120396 0.3048)
			(end -0.120396 0.2794)
			(stroke
				(width 0.1)
				(type default)
			)
			(layer "B.Fab")
		)
		(fp_line
			(start -0.67945 0.3048)
			(end -0.120396 0.3048)
			(stroke
				(width 0.1)
				(type default)
			)
			(layer "B.Fab")
		)
		(pad "1" smd circle
			(at 0.40005 0 270)
			(size 0 0)
			(layers "B.Cu" "B.Mask" "B.Paste")
			(net "PWRGD_FAIL_CPU1_GH")
		)
		(pad "2" smd circle
			(at -0.40005 0 270)
			(size 0 0)
			(layers "B.Cu" "B.Mask" "B.Paste")
			(net "PWRGD_FAIL_CPU1_GH_R1")
		)
	)
	(footprint ""
		(layer "B.Cu")
		(at 162.306 -13.426948 90)
		(property "Reference" "R4506"
			(at 0 0 90)
			(layer "B.SilkS")
			(hide yes)
			(effects
				(font
					(size 1.27 1.27)
				)
				(justify mirror)
			)
		)
		(property "Value" ""
			(at 0 0 90)
			(layer "B.Fab")
			(effects
				(font
					(size 1.27 1.27)
				)
				(justify mirror)
			)
		)
		(duplicate_pad_numbers_are_jumpers no)
		(fp_line
			(start 0.7874 -0.4064)
			(end -0.7874 -0.4064)
			(stroke
				(width 0.1524)
				(type default)
			)
			(layer "B.SilkS")
		)
		(fp_line
			(start -0.7874 -0.4064)
			(end -0.7874 0.4064)
			(stroke
				(width 0.1524)
				(type default)
			)
			(layer "B.SilkS")
		)
		(fp_line
			(start 0.7874 0.4064)
			(end 0.7874 -0.4064)
			(stroke
				(width 0.1524)
				(type default)
			)
			(layer "B.SilkS")
		)
		(fp_line
			(start -0.7874 0.4064)
			(end 0.7874 0.4064)
			(stroke
				(width 0.1524)
				(type default)
			)
			(layer "B.SilkS")
		)
		(fp_line
			(start 0.67945 -0.305054)
			(end 0.12065 -0.305054)
			(stroke
				(width 0.1)
				(type default)
			)
			(layer "B.Fab")
		)
		(fp_line
			(start 0.12065 -0.305054)
			(end 0.12065 -0.2794)
			(stroke
				(width 0.1)
				(type default)
			)
			(layer "B.Fab")
		)
		(fp_line
			(start -0.12065 -0.3048)
			(end -0.67945 -0.3048)
			(stroke
				(width 0.1)
				(type default)
			)
			(layer "B.Fab")
		)
		(fp_line
			(start -0.67945 -0.3048)
			(end -0.67945 0.3048)
			(stroke
				(width 0.1)
				(type default)
			)
			(layer "B.Fab")
		)
		(fp_line
			(start 0.12065 -0.2794)
			(end -0.12065 -0.2794)
			(stroke
				(width 0.1)
				(type default)
			)
			(layer "B.Fab")
		)
		(fp_line
			(start -0.12065 -0.2794)
			(end -0.12065 -0.3048)
			(stroke
				(width 0.1)
				(type default)
			)
			(layer "B.Fab")
		)
		(fp_line
			(start 0.12065 0.2794)
			(end 0.12065 0.3048)
			(stroke
				(width 0.1)
				(type default)
			)
			(layer "B.Fab")
		)
		(fp_line
			(start -0.120396 0.2794)
			(end 0.12065 0.2794)
			(stroke
				(width 0.1)
				(type default)
			)
			(layer "B.Fab")
		)
		(fp_line
			(start 0.67945 0.3048)
			(end 0.67945 -0.305054)
			(stroke
				(width 0.1)
				(type default)
			)
			(layer "B.Fab")
		)
		(fp_line
			(start 0.12065 0.3048)
			(end 0.67945 0.3048)
			(stroke
				(width 0.1)
				(type default)
			)
			(layer "B.Fab")
		)
		(fp_line
			(start -0.120396 0.3048)
			(end -0.120396 0.2794)
			(stroke
				(width 0.1)
				(type default)
			)
			(layer "B.Fab")
		)
		(fp_line
			(start -0.67945 0.3048)
			(end -0.120396 0.3048)
			(stroke
				(width 0.1)
				(type default)
			)
			(layer "B.Fab")
		)
		(pad "1" smd circle
			(at 0.40005 0 270)
			(size 0 0)
			(layers "B.Cu" "B.Mask" "B.Paste")
			(net "SMB_SML0_3V3AUX_SCL")
		)
		(pad "2" smd circle
			(at -0.40005 0 270)
			(size 0 0)
			(layers "B.Cu" "B.Mask" "B.Paste")
			(net "SMB_SML0_3V3AUX_SCL_R1")
		)
	)
	(footprint ""
		(layer "B.Cu")
		(at 310.843422 -314.550044 90)
		(property "Reference" "R2498"
			(at 0 0 90)
			(layer "B.SilkS")
			(hide yes)
			(effects
				(font
					(size 1.27 1.27)
				)
				(justify mirror)
			)
		)
		(property "Value" ""
			(at 0 0 90)
			(layer "B.Fab")
			(effects
				(font
					(size 1.27 1.27)
				)
				(justify mirror)
			)
		)
		(duplicate_pad_numbers_are_jumpers no)
		(fp_line
			(start 0.7874 -0.4064)
			(end -0.7874 -0.4064)
			(stroke
				(width 0.1524)
				(type default)
			)
			(layer "B.SilkS")
		)
		(fp_line
			(start -0.7874 -0.4064)
			(end -0.7874 0.4064)
			(stroke
				(width 0.1524)
				(type default)
			)
			(layer "B.SilkS")
		)
		(fp_line
			(start 0.7874 0.4064)
			(end 0.7874 -0.4064)
			(stroke
				(width 0.1524)
				(type default)
			)
			(layer "B.SilkS")
		)
		(fp_line
			(start -0.7874 0.4064)
			(end 0.7874 0.4064)
			(stroke
				(width 0.1524)
				(type default)
			)
			(layer "B.SilkS")
		)
		(fp_line
			(start 0.67945 -0.305054)
			(end 0.12065 -0.305054)
			(stroke
				(width 0.1)
				(type default)
			)
			(layer "B.Fab")
		)
		(fp_line
			(start 0.12065 -0.305054)
			(end 0.12065 -0.2794)
			(stroke
				(width 0.1)
				(type default)
			)
			(layer "B.Fab")
		)
		(fp_line
			(start -0.12065 -0.3048)
			(end -0.67945 -0.3048)
			(stroke
				(width 0.1)
				(type default)
			)
			(layer "B.Fab")
		)
		(fp_line
			(start -0.67945 -0.3048)
			(end -0.67945 0.3048)
			(stroke
				(width 0.1)
				(type default)
			)
			(layer "B.Fab")
		)
		(fp_line
			(start 0.12065 -0.2794)
			(end -0.12065 -0.2794)
			(stroke
				(width 0.1)
				(type default)
			)
			(layer "B.Fab")
		)
		(fp_line
			(start -0.12065 -0.2794)
			(end -0.12065 -0.3048)
			(stroke
				(width 0.1)
				(type default)
			)
			(layer "B.Fab")
		)
		(fp_line
			(start 0.12065 0.2794)
			(end 0.12065 0.3048)
			(stroke
				(width 0.1)
				(type default)
			)
			(layer "B.Fab")
		)
		(fp_line
			(start -0.120396 0.2794)
			(end 0.12065 0.2794)
			(stroke
				(width 0.1)
				(type default)
			)
			(layer "B.Fab")
		)
		(fp_line
			(start 0.67945 0.3048)
			(end 0.67945 -0.305054)
			(stroke
				(width 0.1)
				(type default)
			)
			(layer "B.Fab")
		)
		(fp_line
			(start 0.12065 0.3048)
			(end 0.67945 0.3048)
			(stroke
				(width 0.1)
				(type default)
			)
			(layer "B.Fab")
		)
		(fp_line
			(start -0.120396 0.3048)
			(end -0.120396 0.2794)
			(stroke
				(width 0.1)
				(type default)
			)
			(layer "B.Fab")
		)
		(fp_line
			(start -0.67945 0.3048)
			(end -0.120396 0.3048)
			(stroke
				(width 0.1)
				(type default)
			)
			(layer "B.Fab")
		)
		(pad "1" smd circle
			(at 0.40005 0 270)
			(size 0 0)
			(layers "B.Cu" "B.Mask" "B.Paste")
			(net "PWRGD_FAIL_CPU0_AB_R1")
		)
		(pad "2" smd circle
			(at -0.40005 0 270)
			(size 0 0)
			(layers "B.Cu" "B.Mask" "B.Paste")
			(net "PWRGD_FAIL_CPU0_AB_R")
		)
	)
	(footprint ""
		(layer "B.Cu")
		(at 34.003742 -315.557662)
		(property "Reference" "R3893"
			(at 0 0 0)
			(layer "B.SilkS")
			(hide yes)
			(effects
				(font
					(size 1.27 1.27)
				)
				(justify mirror)
			)
		)
		(property "Value" ""
			(at 0 0 0)
			(layer "B.Fab")
			(effects
				(font
					(size 1.27 1.27)
				)
				(justify mirror)
			)
		)
		(duplicate_pad_numbers_are_jumpers no)
		(fp_line
			(start -0.7874 -0.4064)
			(end -0.7874 0.4064)
			(stroke
				(width 0.1524)
				(type default)
			)
			(layer "B.SilkS")
		)
		(fp_line
			(start -0.7874 0.4064)
			(end 0.7874 0.4064)
			(stroke
				(width 0.1524)
				(type default)
			)
			(layer "B.SilkS")
		)
		(fp_line
			(start 0.7874 -0.4064)
			(end -0.7874 -0.4064)
			(stroke
				(width 0.1524)
				(type default)
			)
			(layer "B.SilkS")
		)
		(fp_line
			(start 0.7874 0.4064)
			(end 0.7874 -0.4064)
			(stroke
				(width 0.1524)
				(type default)
			)
			(layer "B.SilkS")
		)
		(fp_line
			(start -0.67945 -0.3048)
			(end -0.67945 0.3048)
			(stroke
				(width 0.1)
				(type default)
			)
			(layer "B.Fab")
		)
		(fp_line
			(start -0.67945 0.3048)
			(end -0.120396 0.3048)
			(stroke
				(width 0.1)
				(type default)
			)
			(layer "B.Fab")
		)
		(fp_line
			(start -0.12065 -0.3048)
			(end -0.67945 -0.3048)
			(stroke
				(width 0.1)
				(type default)
			)
			(layer "B.Fab")
		)
		(fp_line
			(start -0.12065 -0.2794)
			(end -0.12065 -0.3048)
			(stroke
				(width 0.1)
				(type default)
			)
			(layer "B.Fab")
		)
		(fp_line
			(start -0.120396 0.2794)
			(end 0.12065 0.2794)
			(stroke
				(width 0.1)
				(type default)
			)
			(layer "B.Fab")
		)
		(fp_line
			(start -0.120396 0.3048)
			(end -0.120396 0.2794)
			(stroke
				(width 0.1)
				(type default)
			)
			(layer "B.Fab")
		)
		(fp_line
			(start 0.12065 -0.305054)
			(end 0.12065 -0.2794)
			(stroke
				(width 0.1)
				(type default)
			)
			(layer "B.Fab")
		)
		(fp_line
			(start 0.12065 -0.2794)
			(end -0.12065 -0.2794)
			(stroke
				(width 0.1)
				(type default)
			)
			(layer "B.Fab")
		)
		(fp_line
			(start 0.12065 0.2794)
			(end 0.12065 0.3048)
			(stroke
				(width 0.1)
				(type default)
			)
			(layer "B.Fab")
		)
		(fp_line
			(start 0.12065 0.3048)
			(end 0.67945 0.3048)
			(stroke
				(width 0.1)
				(type default)
			)
			(layer "B.Fab")
		)
		(fp_line
			(start 0.67945 -0.305054)
			(end 0.12065 -0.305054)
			(stroke
				(width 0.1)
				(type default)
			)
			(layer "B.Fab")
		)
		(fp_line
			(start 0.67945 0.3048)
			(end 0.67945 -0.305054)
			(stroke
				(width 0.1)
				(type default)
			)
			(layer "B.Fab")
		)
		(pad "1" smd circle
			(at 0.40005 0 180)
			(size 0 0)
			(layers "B.Cu" "B.Mask" "B.Paste")
			(net "I3C_SPD_DDRABCD_CPU1_LVC1_SCL_2")
		)
		(pad "2" smd circle
			(at -0.40005 0 180)
			(size 0 0)
			(layers "B.Cu" "B.Mask" "B.Paste")
			(net "I3C_SPD_DDRABCD_CPU1_LVC1_SCL")
		)
	)
	(footprint ""
		(layer "B.Cu")
		(at 389.636 -32.603948 90)
		(property "Reference" "R3160"
			(at 0 0 90)
			(layer "B.SilkS")
			(hide yes)
			(effects
				(font
					(size 1.27 1.27)
				)
				(justify mirror)
			)
		)
		(property "Value" ""
			(at 0 0 90)
			(layer "B.Fab")
			(effects
				(font
					(size 1.27 1.27)
				)
				(justify mirror)
			)
		)
		(duplicate_pad_numbers_are_jumpers no)
		(fp_line
			(start 0.7874 -0.4064)
			(end -0.7874 -0.4064)
			(stroke
				(width 0.1524)
				(type default)
			)
			(layer "B.SilkS")
		)
		(fp_line
			(start -0.7874 -0.4064)
			(end -0.7874 0.4064)
			(stroke
				(width 0.1524)
				(type default)
			)
			(layer "B.SilkS")
		)
		(fp_line
			(start 0.7874 0.4064)
			(end 0.7874 -0.4064)
			(stroke
				(width 0.1524)
				(type default)
			)
			(layer "B.SilkS")
		)
		(fp_line
			(start -0.7874 0.4064)
			(end 0.7874 0.4064)
			(stroke
				(width 0.1524)
				(type default)
			)
			(layer "B.SilkS")
		)
		(fp_line
			(start 0.67945 -0.305054)
			(end 0.12065 -0.305054)
			(stroke
				(width 0.1)
				(type default)
			)
			(layer "B.Fab")
		)
		(fp_line
			(start 0.12065 -0.305054)
			(end 0.12065 -0.2794)
			(stroke
				(width 0.1)
				(type default)
			)
			(layer "B.Fab")
		)
		(fp_line
			(start -0.12065 -0.3048)
			(end -0.67945 -0.3048)
			(stroke
				(width 0.1)
				(type default)
			)
			(layer "B.Fab")
		)
		(fp_line
			(start -0.67945 -0.3048)
			(end -0.67945 0.3048)
			(stroke
				(width 0.1)
				(type default)
			)
			(layer "B.Fab")
		)
		(fp_line
			(start 0.12065 -0.2794)
			(end -0.12065 -0.2794)
			(stroke
				(width 0.1)
				(type default)
			)
			(layer "B.Fab")
		)
		(fp_line
			(start -0.12065 -0.2794)
			(end -0.12065 -0.3048)
			(stroke
				(width 0.1)
				(type default)
			)
			(layer "B.Fab")
		)
		(fp_line
			(start 0.12065 0.2794)
			(end 0.12065 0.3048)
			(stroke
				(width 0.1)
				(type default)
			)
			(layer "B.Fab")
		)
		(fp_line
			(start -0.120396 0.2794)
			(end 0.12065 0.2794)
			(stroke
				(width 0.1)
				(type default)
			)
			(layer "B.Fab")
		)
		(fp_line
			(start 0.67945 0.3048)
			(end 0.67945 -0.305054)
			(stroke
				(width 0.1)
				(type default)
			)
			(layer "B.Fab")
		)
		(fp_line
			(start 0.12065 0.3048)
			(end 0.67945 0.3048)
			(stroke
				(width 0.1)
				(type default)
			)
			(layer "B.Fab")
		)
		(fp_line
			(start -0.120396 0.3048)
			(end -0.120396 0.2794)
			(stroke
				(width 0.1)
				(type default)
			)
			(layer "B.Fab")
		)
		(fp_line
			(start -0.67945 0.3048)
			(end -0.120396 0.3048)
			(stroke
				(width 0.1)
				(type default)
			)
			(layer "B.Fab")
		)
		(pad "1" smd circle
			(at 0.40005 0 270)
			(size 0 0)
			(layers "B.Cu" "B.Mask" "B.Paste")
			(net "P3V3_AUX")
		)
		(pad "2" smd circle
			(at -0.40005 0 270)
			(size 0 0)
			(layers "B.Cu" "B.Mask" "B.Paste")
			(net "HP_OCP_V3_1_RST_R")
		)
	)
	(footprint ""
		(layer "B.Cu")
		(at 185.555128 -317.40475 180)
		(property "Reference" "R2496"
			(at 0 0 0)
			(layer "B.SilkS")
			(hide yes)
			(effects
				(font
					(size 1.27 1.27)
				)
				(justify mirror)
			)
		)
		(property "Value" ""
			(at 0 0 0)
			(layer "B.Fab")
			(effects
				(font
					(size 1.27 1.27)
				)
				(justify mirror)
			)
		)
		(duplicate_pad_numbers_are_jumpers no)
		(fp_line
			(start 0.7874 0.4064)
			(end 0.7874 -0.4064)
			(stroke
				(width 0.1524)
				(type default)
			)
			(layer "B.SilkS")
		)
		(fp_line
			(start 0.7874 -0.4064)
			(end -0.7874 -0.4064)
			(stroke
				(width 0.1524)
				(type default)
			)
			(layer "B.SilkS")
		)
		(fp_line
			(start -0.7874 0.4064)
			(end 0.7874 0.4064)
			(stroke
				(width 0.1524)
				(type default)
			)
			(layer "B.SilkS")
		)
		(fp_line
			(start -0.7874 -0.4064)
			(end -0.7874 0.4064)
			(stroke
				(width 0.1524)
				(type default)
			)
			(layer "B.SilkS")
		)
		(fp_line
			(start 0.67945 0.3048)
			(end 0.67945 -0.305054)
			(stroke
				(width 0.1)
				(type default)
			)
			(layer "B.Fab")
		)
		(fp_line
			(start 0.67945 -0.305054)
			(end 0.12065 -0.305054)
			(stroke
				(width 0.1)
				(type default)
			)
			(layer "B.Fab")
		)
		(fp_line
			(start 0.12065 0.3048)
			(end 0.67945 0.3048)
			(stroke
				(width 0.1)
				(type default)
			)
			(layer "B.Fab")
		)
		(fp_line
			(start 0.12065 0.2794)
			(end 0.12065 0.3048)
			(stroke
				(width 0.1)
				(type default)
			)
			(layer "B.Fab")
		)
		(fp_line
			(start 0.12065 -0.2794)
			(end -0.12065 -0.2794)
			(stroke
				(width 0.1)
				(type default)
			)
			(layer "B.Fab")
		)
		(fp_line
			(start 0.12065 -0.305054)
			(end 0.12065 -0.2794)
			(stroke
				(width 0.1)
				(type default)
			)
			(layer "B.Fab")
		)
		(fp_line
			(start -0.120396 0.3048)
			(end -0.120396 0.2794)
			(stroke
				(width 0.1)
				(type default)
			)
			(layer "B.Fab")
		)
		(fp_line
			(start -0.120396 0.2794)
			(end 0.12065 0.2794)
			(stroke
				(width 0.1)
				(type default)
			)
			(layer "B.Fab")
		)
		(fp_line
			(start -0.12065 -0.2794)
			(end -0.12065 -0.3048)
			(stroke
				(width 0.1)
				(type default)
			)
			(layer "B.Fab")
		)
		(fp_line
			(start -0.12065 -0.3048)
			(end -0.67945 -0.3048)
			(stroke
				(width 0.1)
				(type default)
			)
			(layer "B.Fab")
		)
		(fp_line
			(start -0.67945 0.3048)
			(end -0.120396 0.3048)
			(stroke
				(width 0.1)
				(type default)
			)
			(layer "B.Fab")
		)
		(fp_line
			(start -0.67945 -0.3048)
			(end -0.67945 0.3048)
			(stroke
				(width 0.1)
				(type default)
			)
			(layer "B.Fab")
		)
		(pad "1" smd circle
			(at 0.40005 0)
			(size 0 0)
			(layers "B.Cu" "B.Mask" "B.Paste")
			(net "PWRGD_FAIL_CPU1_EF")
		)
		(pad "2" smd circle
			(at -0.40005 0)
			(size 0 0)
			(layers "B.Cu" "B.Mask" "B.Paste")
			(net "PWRGD_FAIL_CPU1_EF_R1")
		)
	)
	(footprint ""
		(layer "B.Cu")
		(at 322.984622 -58.283348 180)
		(property "Reference" "R1485"
			(at 0 0 0)
			(layer "B.SilkS")
			(hide yes)
			(effects
				(font
					(size 1.27 1.27)
				)
				(justify mirror)
			)
		)
		(property "Value" ""
			(at 0 0 0)
			(layer "B.Fab")
			(effects
				(font
					(size 1.27 1.27)
				)
				(justify mirror)
			)
		)
		(duplicate_pad_numbers_are_jumpers no)
		(fp_line
			(start 0.7874 0.4064)
			(end 0.7874 -0.4064)
			(stroke
				(width 0.1524)
				(type default)
			)
			(layer "B.SilkS")
		)
		(fp_line
			(start 0.7874 -0.4064)
			(end -0.7874 -0.4064)
			(stroke
				(width 0.1524)
				(type default)
			)
			(layer "B.SilkS")
		)
		(fp_line
			(start -0.7874 0.4064)
			(end 0.7874 0.4064)
			(stroke
				(width 0.1524)
				(type default)
			)
			(layer "B.SilkS")
		)
		(fp_line
			(start -0.7874 -0.4064)
			(end -0.7874 0.4064)
			(stroke
				(width 0.1524)
				(type default)
			)
			(layer "B.SilkS")
		)
		(fp_line
			(start 0.67945 0.3048)
			(end 0.67945 -0.305054)
			(stroke
				(width 0.1)
				(type default)
			)
			(layer "B.Fab")
		)
		(fp_line
			(start 0.67945 -0.305054)
			(end 0.12065 -0.305054)
			(stroke
				(width 0.1)
				(type default)
			)
			(layer "B.Fab")
		)
		(fp_line
			(start 0.12065 0.3048)
			(end 0.67945 0.3048)
			(stroke
				(width 0.1)
				(type default)
			)
			(layer "B.Fab")
		)
		(fp_line
			(start 0.12065 0.2794)
			(end 0.12065 0.3048)
			(stroke
				(width 0.1)
				(type default)
			)
			(layer "B.Fab")
		)
		(fp_line
			(start 0.12065 -0.2794)
			(end -0.12065 -0.2794)
			(stroke
				(width 0.1)
				(type default)
			)
			(layer "B.Fab")
		)
		(fp_line
			(start 0.12065 -0.305054)
			(end 0.12065 -0.2794)
			(stroke
				(width 0.1)
				(type default)
			)
			(layer "B.Fab")
		)
		(fp_line
			(start -0.120396 0.3048)
			(end -0.120396 0.2794)
			(stroke
				(width 0.1)
				(type default)
			)
			(layer "B.Fab")
		)
		(fp_line
			(start -0.120396 0.2794)
			(end 0.12065 0.2794)
			(stroke
				(width 0.1)
				(type default)
			)
			(layer "B.Fab")
		)
		(fp_line
			(start -0.12065 -0.2794)
			(end -0.12065 -0.3048)
			(stroke
				(width 0.1)
				(type default)
			)
			(layer "B.Fab")
		)
		(fp_line
			(start -0.12065 -0.3048)
			(end -0.67945 -0.3048)
			(stroke
				(width 0.1)
				(type default)
			)
			(layer "B.Fab")
		)
		(fp_line
			(start -0.67945 0.3048)
			(end -0.120396 0.3048)
			(stroke
				(width 0.1)
				(type default)
			)
			(layer "B.Fab")
		)
		(fp_line
			(start -0.67945 -0.3048)
			(end -0.67945 0.3048)
			(stroke
				(width 0.1)
				(type default)
			)
			(layer "B.Fab")
		)
		(pad "1" smd circle
			(at 0.40005 0)
			(size 0 0)
			(layers "B.Cu" "B.Mask" "B.Paste")
			(net "PVNN_TERM_CPU0")
		)
		(pad "2" smd circle
			(at -0.40005 0)
			(size 0 0)
			(layers "B.Cu" "B.Mask" "B.Paste")
			(net "FM_PCH_TRIGGER0_R_N")
		)
	)
	(footprint ""
		(layer "B.Cu")
		(at 326.205342 -48.358298)
		(property "Reference" "R1960"
			(at 0 0 0)
			(layer "B.SilkS")
			(hide yes)
			(effects
				(font
					(size 1.27 1.27)
				)
				(justify mirror)
			)
		)
		(property "Value" ""
			(at 0 0 0)
			(layer "B.Fab")
			(effects
				(font
					(size 1.27 1.27)
				)
				(justify mirror)
			)
		)
		(duplicate_pad_numbers_are_jumpers no)
		(fp_line
			(start -0.7874 -0.4064)
			(end -0.7874 0.4064)
			(stroke
				(width 0.1524)
				(type default)
			)
			(layer "B.SilkS")
		)
		(fp_line
			(start -0.7874 0.4064)
			(end 0.7874 0.4064)
			(stroke
				(width 0.1524)
				(type default)
			)
			(layer "B.SilkS")
		)
		(fp_line
			(start 0.7874 -0.4064)
			(end -0.7874 -0.4064)
			(stroke
				(width 0.1524)
				(type default)
			)
			(layer "B.SilkS")
		)
		(fp_line
			(start 0.7874 0.4064)
			(end 0.7874 -0.4064)
			(stroke
				(width 0.1524)
				(type default)
			)
			(layer "B.SilkS")
		)
		(fp_line
			(start -0.67945 -0.3048)
			(end -0.67945 0.3048)
			(stroke
				(width 0.1)
				(type default)
			)
			(layer "B.Fab")
		)
		(fp_line
			(start -0.67945 0.3048)
			(end -0.120396 0.3048)
			(stroke
				(width 0.1)
				(type default)
			)
			(layer "B.Fab")
		)
		(fp_line
			(start -0.12065 -0.3048)
			(end -0.67945 -0.3048)
			(stroke
				(width 0.1)
				(type default)
			)
			(layer "B.Fab")
		)
		(fp_line
			(start -0.12065 -0.2794)
			(end -0.12065 -0.3048)
			(stroke
				(width 0.1)
				(type default)
			)
			(layer "B.Fab")
		)
		(fp_line
			(start -0.120396 0.2794)
			(end 0.12065 0.2794)
			(stroke
				(width 0.1)
				(type default)
			)
			(layer "B.Fab")
		)
		(fp_line
			(start -0.120396 0.3048)
			(end -0.120396 0.2794)
			(stroke
				(width 0.1)
				(type default)
			)
			(layer "B.Fab")
		)
		(fp_line
			(start 0.12065 -0.305054)
			(end 0.12065 -0.2794)
			(stroke
				(width 0.1)
				(type default)
			)
			(layer "B.Fab")
		)
		(fp_line
			(start 0.12065 -0.2794)
			(end -0.12065 -0.2794)
			(stroke
				(width 0.1)
				(type default)
			)
			(layer "B.Fab")
		)
		(fp_line
			(start 0.12065 0.2794)
			(end 0.12065 0.3048)
			(stroke
				(width 0.1)
				(type default)
			)
			(layer "B.Fab")
		)
		(fp_line
			(start 0.12065 0.3048)
			(end 0.67945 0.3048)
			(stroke
				(width 0.1)
				(type default)
			)
			(layer "B.Fab")
		)
		(fp_line
			(start 0.67945 -0.305054)
			(end 0.12065 -0.305054)
			(stroke
				(width 0.1)
				(type default)
			)
			(layer "B.Fab")
		)
		(fp_line
			(start 0.67945 0.3048)
			(end 0.67945 -0.305054)
			(stroke
				(width 0.1)
				(type default)
			)
			(layer "B.Fab")
		)
		(pad "1" smd circle
			(at 0.40005 0 180)
			(size 0 0)
			(layers "B.Cu" "B.Mask" "B.Paste")
			(net "H_CPU0_PMSYNC_PCH_R2")
		)
		(pad "2" smd circle
			(at -0.40005 0 180)
			(size 0 0)
			(layers "B.Cu" "B.Mask" "B.Paste")
			(net "H_CPU0_PMSYNC_PCH_R")
		)
	)
	(footprint ""
		(layer "B.Cu")
		(at 200.661778 -109.86897 180)
		(property "Reference" "R126"
			(at 0 0 0)
			(layer "B.SilkS")
			(hide yes)
			(effects
				(font
					(size 1.27 1.27)
				)
				(justify mirror)
			)
		)
		(property "Value" ""
			(at 0 0 0)
			(layer "B.Fab")
			(effects
				(font
					(size 1.27 1.27)
				)
				(justify mirror)
			)
		)
		(duplicate_pad_numbers_are_jumpers no)
		(fp_line
			(start 0.7874 0.4064)
			(end 0.7874 -0.4064)
			(stroke
				(width 0.1524)
				(type default)
			)
			(layer "B.SilkS")
		)
		(fp_line
			(start 0.7874 -0.4064)
			(end -0.7874 -0.4064)
			(stroke
				(width 0.1524)
				(type default)
			)
			(layer "B.SilkS")
		)
		(fp_line
			(start -0.7874 0.4064)
			(end 0.7874 0.4064)
			(stroke
				(width 0.1524)
				(type default)
			)
			(layer "B.SilkS")
		)
		(fp_line
			(start -0.7874 -0.4064)
			(end -0.7874 0.4064)
			(stroke
				(width 0.1524)
				(type default)
			)
			(layer "B.SilkS")
		)
		(fp_line
			(start 0.67945 0.3048)
			(end 0.67945 -0.305054)
			(stroke
				(width 0.1)
				(type default)
			)
			(layer "B.Fab")
		)
		(fp_line
			(start 0.67945 -0.305054)
			(end 0.12065 -0.305054)
			(stroke
				(width 0.1)
				(type default)
			)
			(layer "B.Fab")
		)
		(fp_line
			(start 0.12065 0.3048)
			(end 0.67945 0.3048)
			(stroke
				(width 0.1)
				(type default)
			)
			(layer "B.Fab")
		)
		(fp_line
			(start 0.12065 0.2794)
			(end 0.12065 0.3048)
			(stroke
				(width 0.1)
				(type default)
			)
			(layer "B.Fab")
		)
		(fp_line
			(start 0.12065 -0.2794)
			(end -0.12065 -0.2794)
			(stroke
				(width 0.1)
				(type default)
			)
			(layer "B.Fab")
		)
		(fp_line
			(start 0.12065 -0.305054)
			(end 0.12065 -0.2794)
			(stroke
				(width 0.1)
				(type default)
			)
			(layer "B.Fab")
		)
		(fp_line
			(start -0.120396 0.3048)
			(end -0.120396 0.2794)
			(stroke
				(width 0.1)
				(type default)
			)
			(layer "B.Fab")
		)
		(fp_line
			(start -0.120396 0.2794)
			(end 0.12065 0.2794)
			(stroke
				(width 0.1)
				(type default)
			)
			(layer "B.Fab")
		)
		(fp_line
			(start -0.12065 -0.2794)
			(end -0.12065 -0.3048)
			(stroke
				(width 0.1)
				(type default)
			)
			(layer "B.Fab")
		)
		(fp_line
			(start -0.12065 -0.3048)
			(end -0.67945 -0.3048)
			(stroke
				(width 0.1)
				(type default)
			)
			(layer "B.Fab")
		)
		(fp_line
			(start -0.67945 0.3048)
			(end -0.120396 0.3048)
			(stroke
				(width 0.1)
				(type default)
			)
			(layer "B.Fab")
		)
		(fp_line
			(start -0.67945 -0.3048)
			(end -0.67945 0.3048)
			(stroke
				(width 0.1)
				(type default)
			)
			(layer "B.Fab")
		)
		(pad "1" smd circle
			(at 0.40005 0)
			(size 0 0)
			(layers "B.Cu" "B.Mask" "B.Paste")
			(net "PWRGD_DRAMPWRGD_CPU1_EF_R_LVC1")
		)
		(pad "2" smd circle
			(at -0.40005 0)
			(size 0 0)
			(layers "B.Cu" "B.Mask" "B.Paste")
			(net "PWRGD_DRAMPWRGD_CPU1_EF_LVC1_R2")
		)
	)
	(footprint ""
		(layer "B.Cu")
		(at 63.718186 -15.772384 90)
		(property "Reference" "R3208"
			(at 0 0 90)
			(layer "B.SilkS")
			(hide yes)
			(effects
				(font
					(size 1.27 1.27)
				)
				(justify mirror)
			)
		)
		(property "Value" ""
			(at 0 0 90)
			(layer "B.Fab")
			(effects
				(font
					(size 1.27 1.27)
				)
				(justify mirror)
			)
		)
		(duplicate_pad_numbers_are_jumpers no)
		(fp_line
			(start 0.7874 -0.4064)
			(end -0.7874 -0.4064)
			(stroke
				(width 0.1524)
				(type default)
			)
			(layer "B.SilkS")
		)
		(fp_line
			(start -0.7874 -0.4064)
			(end -0.7874 0.4064)
			(stroke
				(width 0.1524)
				(type default)
			)
			(layer "B.SilkS")
		)
		(fp_line
			(start 0.7874 0.4064)
			(end 0.7874 -0.4064)
			(stroke
				(width 0.1524)
				(type default)
			)
			(layer "B.SilkS")
		)
		(fp_line
			(start -0.7874 0.4064)
			(end 0.7874 0.4064)
			(stroke
				(width 0.1524)
				(type default)
			)
			(layer "B.SilkS")
		)
		(fp_line
			(start 0.67945 -0.305054)
			(end 0.12065 -0.305054)
			(stroke
				(width 0.1)
				(type default)
			)
			(layer "B.Fab")
		)
		(fp_line
			(start 0.12065 -0.305054)
			(end 0.12065 -0.2794)
			(stroke
				(width 0.1)
				(type default)
			)
			(layer "B.Fab")
		)
		(fp_line
			(start -0.12065 -0.3048)
			(end -0.67945 -0.3048)
			(stroke
				(width 0.1)
				(type default)
			)
			(layer "B.Fab")
		)
		(fp_line
			(start -0.67945 -0.3048)
			(end -0.67945 0.3048)
			(stroke
				(width 0.1)
				(type default)
			)
			(layer "B.Fab")
		)
		(fp_line
			(start 0.12065 -0.2794)
			(end -0.12065 -0.2794)
			(stroke
				(width 0.1)
				(type default)
			)
			(layer "B.Fab")
		)
		(fp_line
			(start -0.12065 -0.2794)
			(end -0.12065 -0.3048)
			(stroke
				(width 0.1)
				(type default)
			)
			(layer "B.Fab")
		)
		(fp_line
			(start 0.12065 0.2794)
			(end 0.12065 0.3048)
			(stroke
				(width 0.1)
				(type default)
			)
			(layer "B.Fab")
		)
		(fp_line
			(start -0.120396 0.2794)
			(end 0.12065 0.2794)
			(stroke
				(width 0.1)
				(type default)
			)
			(layer "B.Fab")
		)
		(fp_line
			(start 0.67945 0.3048)
			(end 0.67945 -0.305054)
			(stroke
				(width 0.1)
				(type default)
			)
			(layer "B.Fab")
		)
		(fp_line
			(start 0.12065 0.3048)
			(end 0.67945 0.3048)
			(stroke
				(width 0.1)
				(type default)
			)
			(layer "B.Fab")
		)
		(fp_line
			(start -0.120396 0.3048)
			(end -0.120396 0.2794)
			(stroke
				(width 0.1)
				(type default)
			)
			(layer "B.Fab")
		)
		(fp_line
			(start -0.67945 0.3048)
			(end -0.120396 0.3048)
			(stroke
				(width 0.1)
				(type default)
			)
			(layer "B.Fab")
		)
		(pad "1" smd circle
			(at 0.40005 0 270)
			(size 0 0)
			(layers "B.Cu" "B.Mask" "B.Paste")
			(net "OCP_V3_2_ISO_BIF0_EN")
		)
		(pad "2" smd circle
			(at -0.40005 0 270)
			(size 0 0)
			(layers "B.Cu" "B.Mask" "B.Paste")
			(net "GND")
		)
	)
	(footprint ""
		(layer "B.Cu")
		(at 318.223138 -189.73673 90)
		(property "Reference" "R243"
			(at 0 0 90)
			(layer "B.SilkS")
			(hide yes)
			(effects
				(font
					(size 1.27 1.27)
				)
				(justify mirror)
			)
		)
		(property "Value" ""
			(at 0 0 90)
			(layer "B.Fab")
			(effects
				(font
					(size 1.27 1.27)
				)
				(justify mirror)
			)
		)
		(duplicate_pad_numbers_are_jumpers no)
		(fp_line
			(start 0.7874 -0.4064)
			(end -0.7874 -0.4064)
			(stroke
				(width 0.1524)
				(type default)
			)
			(layer "B.SilkS")
		)
		(fp_line
			(start -0.7874 -0.4064)
			(end -0.7874 0.4064)
			(stroke
				(width 0.1524)
				(type default)
			)
			(layer "B.SilkS")
		)
		(fp_line
			(start 0.7874 0.4064)
			(end 0.7874 -0.4064)
			(stroke
				(width 0.1524)
				(type default)
			)
			(layer "B.SilkS")
		)
		(fp_line
			(start -0.7874 0.4064)
			(end 0.7874 0.4064)
			(stroke
				(width 0.1524)
				(type default)
			)
			(layer "B.SilkS")
		)
		(fp_line
			(start 0.67945 -0.305054)
			(end 0.12065 -0.305054)
			(stroke
				(width 0.1)
				(type default)
			)
			(layer "B.Fab")
		)
		(fp_line
			(start 0.12065 -0.305054)
			(end 0.12065 -0.2794)
			(stroke
				(width 0.1)
				(type default)
			)
			(layer "B.Fab")
		)
		(fp_line
			(start -0.12065 -0.3048)
			(end -0.67945 -0.3048)
			(stroke
				(width 0.1)
				(type default)
			)
			(layer "B.Fab")
		)
		(fp_line
			(start -0.67945 -0.3048)
			(end -0.67945 0.3048)
			(stroke
				(width 0.1)
				(type default)
			)
			(layer "B.Fab")
		)
		(fp_line
			(start 0.12065 -0.2794)
			(end -0.12065 -0.2794)
			(stroke
				(width 0.1)
				(type default)
			)
			(layer "B.Fab")
		)
		(fp_line
			(start -0.12065 -0.2794)
			(end -0.12065 -0.3048)
			(stroke
				(width 0.1)
				(type default)
			)
			(layer "B.Fab")
		)
		(fp_line
			(start 0.12065 0.2794)
			(end 0.12065 0.3048)
			(stroke
				(width 0.1)
				(type default)
			)
			(layer "B.Fab")
		)
		(fp_line
			(start -0.120396 0.2794)
			(end 0.12065 0.2794)
			(stroke
				(width 0.1)
				(type default)
			)
			(layer "B.Fab")
		)
		(fp_line
			(start 0.67945 0.3048)
			(end 0.67945 -0.305054)
			(stroke
				(width 0.1)
				(type default)
			)
			(layer "B.Fab")
		)
		(fp_line
			(start 0.12065 0.3048)
			(end 0.67945 0.3048)
			(stroke
				(width 0.1)
				(type default)
			)
			(layer "B.Fab")
		)
		(fp_line
			(start -0.120396 0.3048)
			(end -0.120396 0.2794)
			(stroke
				(width 0.1)
				(type default)
			)
			(layer "B.Fab")
		)
		(fp_line
			(start -0.67945 0.3048)
			(end -0.120396 0.3048)
			(stroke
				(width 0.1)
				(type default)
			)
			(layer "B.Fab")
		)
		(pad "1" smd circle
			(at 0.40005 0 270)
			(size 0 0)
			(layers "B.Cu" "B.Mask" "B.Paste")
			(net "PVNN_TERM_CPU0")
		)
		(pad "2" smd circle
			(at -0.40005 0 270)
			(size 0 0)
			(layers "B.Cu" "B.Mask" "B.Paste")
			(net "H_CPU0_PROCHOT_LVC1_N")
		)
	)
	(footprint ""
		(layer "B.Cu")
		(at 252.242574 -101.754178 180)
		(property "Reference" "C114"
			(at 0 0 0)
			(layer "B.SilkS")
			(hide yes)
			(effects
				(font
					(size 1.27 1.27)
				)
				(justify mirror)
			)
		)
		(property "Value" ""
			(at 0 0 0)
			(layer "B.Fab")
			(effects
				(font
					(size 1.27 1.27)
				)
				(justify mirror)
			)
		)
		(duplicate_pad_numbers_are_jumpers no)
		(fp_line
			(start 0.7874 0.4064)
			(end 0.7874 -0.4064)
			(stroke
				(width 0.1524)
				(type default)
			)
			(layer "B.SilkS")
		)
		(fp_line
			(start 0.7874 -0.4064)
			(end -0.7874 -0.4064)
			(stroke
				(width 0.1524)
				(type default)
			)
			(layer "B.SilkS")
		)
		(fp_line
			(start -0.7874 0.4064)
			(end 0.7874 0.4064)
			(stroke
				(width 0.1524)
				(type default)
			)
			(layer "B.SilkS")
		)
		(fp_line
			(start -0.7874 -0.4064)
			(end -0.7874 0.4064)
			(stroke
				(width 0.1524)
				(type default)
			)
			(layer "B.SilkS")
		)
		(fp_line
			(start 0.67945 0.3048)
			(end 0.67945 -0.305054)
			(stroke
				(width 0.1)
				(type default)
			)
			(layer "B.Fab")
		)
		(fp_line
			(start 0.67945 -0.305054)
			(end 0.12065 -0.305054)
			(stroke
				(width 0.1)
				(type default)
			)
			(layer "B.Fab")
		)
		(fp_line
			(start 0.12065 0.3048)
			(end 0.67945 0.3048)
			(stroke
				(width 0.1)
				(type default)
			)
			(layer "B.Fab")
		)
		(fp_line
			(start 0.12065 0.2794)
			(end 0.12065 0.3048)
			(stroke
				(width 0.1)
				(type default)
			)
			(layer "B.Fab")
		)
		(fp_line
			(start 0.12065 -0.2794)
			(end -0.12065 -0.2794)
			(stroke
				(width 0.1)
				(type default)
			)
			(layer "B.Fab")
		)
		(fp_line
			(start 0.12065 -0.305054)
			(end 0.12065 -0.2794)
			(stroke
				(width 0.1)
				(type default)
			)
			(layer "B.Fab")
		)
		(fp_line
			(start -0.120396 0.3048)
			(end -0.120396 0.2794)
			(stroke
				(width 0.1)
				(type default)
			)
			(layer "B.Fab")
		)
		(fp_line
			(start -0.120396 0.2794)
			(end 0.12065 0.2794)
			(stroke
				(width 0.1)
				(type default)
			)
			(layer "B.Fab")
		)
		(fp_line
			(start -0.12065 -0.2794)
			(end -0.12065 -0.3048)
			(stroke
				(width 0.1)
				(type default)
			)
			(layer "B.Fab")
		)
		(fp_line
			(start -0.12065 -0.3048)
			(end -0.67945 -0.3048)
			(stroke
				(width 0.1)
				(type default)
			)
			(layer "B.Fab")
		)
		(fp_line
			(start -0.67945 0.3048)
			(end -0.120396 0.3048)
			(stroke
				(width 0.1)
				(type default)
			)
			(layer "B.Fab")
		)
		(fp_line
			(start -0.67945 -0.3048)
			(end -0.67945 0.3048)
			(stroke
				(width 0.1)
				(type default)
			)
			(layer "B.Fab")
		)
		(pad "1" smd circle
			(at 0.40005 0)
			(size 0 0)
			(layers "B.Cu" "B.Mask" "B.Paste")
			(net "P3V3_AUX_CLK_GEN_VDDA25M_CK440")
		)
		(pad "2" smd circle
			(at -0.40005 0)
			(size 0 0)
			(layers "B.Cu" "B.Mask" "B.Paste")
			(net "GND")
		)
	)
	(footprint ""
		(layer "B.Cu")
		(at 307.363622 -30.724348)
		(property "Reference" "R379"
			(at 0 0 0)
			(layer "B.SilkS")
			(hide yes)
			(effects
				(font
					(size 1.27 1.27)
				)
				(justify mirror)
			)
		)
		(property "Value" ""
			(at 0 0 0)
			(layer "B.Fab")
			(effects
				(font
					(size 1.27 1.27)
				)
				(justify mirror)
			)
		)
		(duplicate_pad_numbers_are_jumpers no)
		(fp_line
			(start -0.7874 -0.4064)
			(end -0.7874 0.4064)
			(stroke
				(width 0.1524)
				(type default)
			)
			(layer "B.SilkS")
		)
		(fp_line
			(start -0.7874 0.4064)
			(end 0.7874 0.4064)
			(stroke
				(width 0.1524)
				(type default)
			)
			(layer "B.SilkS")
		)
		(fp_line
			(start 0.7874 -0.4064)
			(end -0.7874 -0.4064)
			(stroke
				(width 0.1524)
				(type default)
			)
			(layer "B.SilkS")
		)
		(fp_line
			(start 0.7874 0.4064)
			(end 0.7874 -0.4064)
			(stroke
				(width 0.1524)
				(type default)
			)
			(layer "B.SilkS")
		)
		(fp_line
			(start -0.67945 -0.3048)
			(end -0.67945 0.3048)
			(stroke
				(width 0.1)
				(type default)
			)
			(layer "B.Fab")
		)
		(fp_line
			(start -0.67945 0.3048)
			(end -0.120396 0.3048)
			(stroke
				(width 0.1)
				(type default)
			)
			(layer "B.Fab")
		)
		(fp_line
			(start -0.12065 -0.3048)
			(end -0.67945 -0.3048)
			(stroke
				(width 0.1)
				(type default)
			)
			(layer "B.Fab")
		)
		(fp_line
			(start -0.12065 -0.2794)
			(end -0.12065 -0.3048)
			(stroke
				(width 0.1)
				(type default)
			)
			(layer "B.Fab")
		)
		(fp_line
			(start -0.120396 0.2794)
			(end 0.12065 0.2794)
			(stroke
				(width 0.1)
				(type default)
			)
			(layer "B.Fab")
		)
		(fp_line
			(start -0.120396 0.3048)
			(end -0.120396 0.2794)
			(stroke
				(width 0.1)
				(type default)
			)
			(layer "B.Fab")
		)
		(fp_line
			(start 0.12065 -0.305054)
			(end 0.12065 -0.2794)
			(stroke
				(width 0.1)
				(type default)
			)
			(layer "B.Fab")
		)
		(fp_line
			(start 0.12065 -0.2794)
			(end -0.12065 -0.2794)
			(stroke
				(width 0.1)
				(type default)
			)
			(layer "B.Fab")
		)
		(fp_line
			(start 0.12065 0.2794)
			(end 0.12065 0.3048)
			(stroke
				(width 0.1)
				(type default)
			)
			(layer "B.Fab")
		)
		(fp_line
			(start 0.12065 0.3048)
			(end 0.67945 0.3048)
			(stroke
				(width 0.1)
				(type default)
			)
			(layer "B.Fab")
		)
		(fp_line
			(start 0.67945 -0.305054)
			(end 0.12065 -0.305054)
			(stroke
				(width 0.1)
				(type default)
			)
			(layer "B.Fab")
		)
		(fp_line
			(start 0.67945 0.3048)
			(end 0.67945 -0.305054)
			(stroke
				(width 0.1)
				(type default)
			)
			(layer "B.Fab")
		)
		(pad "1" smd circle
			(at 0.40005 0 180)
			(size 0 0)
			(layers "B.Cu" "B.Mask" "B.Paste")
			(net "FM_ADR_MODE1")
		)
		(pad "2" smd circle
			(at -0.40005 0 180)
			(size 0 0)
			(layers "B.Cu" "B.Mask" "B.Paste")
			(net "GND")
		)
	)
	(footprint ""
		(layer "B.Cu")
		(at 92.973398 -355.03231 90)
		(property "Reference" "PR2556"
			(at 0 0 90)
			(layer "B.SilkS")
			(hide yes)
			(effects
				(font
					(size 1.27 1.27)
				)
				(justify mirror)
			)
		)
		(property "Value" ""
			(at 0 0 90)
			(layer "B.Fab")
			(effects
				(font
					(size 1.27 1.27)
				)
				(justify mirror)
			)
		)
		(duplicate_pad_numbers_are_jumpers no)
		(fp_line
			(start 4.0386 -1.7526)
			(end -4.0386 -1.7526)
			(stroke
				(width 0.1524)
				(type default)
			)
			(layer "B.SilkS")
		)
		(fp_line
			(start -4.0386 -1.7526)
			(end -4.0386 1.7526)
			(stroke
				(width 0.1524)
				(type default)
			)
			(layer "B.SilkS")
		)
		(fp_line
			(start 4.0386 1.7526)
			(end 4.0386 -1.7526)
			(stroke
				(width 0.1524)
				(type default)
			)
			(layer "B.SilkS")
		)
		(fp_line
			(start -4.0386 1.7526)
			(end 4.0386 1.7526)
			(stroke
				(width 0.1524)
				(type default)
			)
			(layer "B.SilkS")
		)
		(fp_line
			(start 4.0386 -1.7526)
			(end -4.0386 -1.7526)
			(stroke
				(width 0.1)
				(type default)
			)
			(layer "B.Fab")
		)
		(fp_line
			(start -4.0386 -1.7526)
			(end -4.0386 1.7526)
			(stroke
				(width 0.1)
				(type default)
			)
			(layer "B.Fab")
		)
		(fp_line
			(start 4.0386 1.7526)
			(end 4.0386 -1.7526)
			(stroke
				(width 0.1)
				(type default)
			)
			(layer "B.Fab")
		)
		(fp_line
			(start -4.0386 1.7526)
			(end 4.0386 1.7526)
			(stroke
				(width 0.1)
				(type default)
			)
			(layer "B.Fab")
		)
		(pad "1" smd rect
			(at 3.1115 0 270)
			(size 1.524 3.2004)
			(layers "B.Cu" "B.Mask" "B.Paste")
			(net "P12V_AUX")
		)
		(pad "2" smd rect
			(at -3.1115 0 270)
			(size 1.524 3.2004)
			(layers "B.Cu" "B.Mask" "B.Paste")
			(net "SW_P12V_PVCCIN_CPU1_FLT")
		)
	)
	(footprint ""
		(layer "B.Cu")
		(at 156.580078 -102.661466)
		(property "Reference" "R122"
			(at 0 0 0)
			(layer "B.SilkS")
			(hide yes)
			(effects
				(font
					(size 1.27 1.27)
				)
				(justify mirror)
			)
		)
		(property "Value" ""
			(at 0 0 0)
			(layer "B.Fab")
			(effects
				(font
					(size 1.27 1.27)
				)
				(justify mirror)
			)
		)
		(duplicate_pad_numbers_are_jumpers no)
		(fp_line
			(start -0.7874 -0.4064)
			(end -0.7874 0.4064)
			(stroke
				(width 0.1524)
				(type default)
			)
			(layer "B.SilkS")
		)
		(fp_line
			(start -0.7874 0.4064)
			(end 0.7874 0.4064)
			(stroke
				(width 0.1524)
				(type default)
			)
			(layer "B.SilkS")
		)
		(fp_line
			(start 0.7874 -0.4064)
			(end -0.7874 -0.4064)
			(stroke
				(width 0.1524)
				(type default)
			)
			(layer "B.SilkS")
		)
		(fp_line
			(start 0.7874 0.4064)
			(end 0.7874 -0.4064)
			(stroke
				(width 0.1524)
				(type default)
			)
			(layer "B.SilkS")
		)
		(fp_line
			(start -0.67945 -0.3048)
			(end -0.67945 0.3048)
			(stroke
				(width 0.1)
				(type default)
			)
			(layer "B.Fab")
		)
		(fp_line
			(start -0.67945 0.3048)
			(end -0.120396 0.3048)
			(stroke
				(width 0.1)
				(type default)
			)
			(layer "B.Fab")
		)
		(fp_line
			(start -0.12065 -0.3048)
			(end -0.67945 -0.3048)
			(stroke
				(width 0.1)
				(type default)
			)
			(layer "B.Fab")
		)
		(fp_line
			(start -0.12065 -0.2794)
			(end -0.12065 -0.3048)
			(stroke
				(width 0.1)
				(type default)
			)
			(layer "B.Fab")
		)
		(fp_line
			(start -0.120396 0.2794)
			(end 0.12065 0.2794)
			(stroke
				(width 0.1)
				(type default)
			)
			(layer "B.Fab")
		)
		(fp_line
			(start -0.120396 0.3048)
			(end -0.120396 0.2794)
			(stroke
				(width 0.1)
				(type default)
			)
			(layer "B.Fab")
		)
		(fp_line
			(start 0.12065 -0.305054)
			(end 0.12065 -0.2794)
			(stroke
				(width 0.1)
				(type default)
			)
			(layer "B.Fab")
		)
		(fp_line
			(start 0.12065 -0.2794)
			(end -0.12065 -0.2794)
			(stroke
				(width 0.1)
				(type default)
			)
			(layer "B.Fab")
		)
		(fp_line
			(start 0.12065 0.2794)
			(end 0.12065 0.3048)
			(stroke
				(width 0.1)
				(type default)
			)
			(layer "B.Fab")
		)
		(fp_line
			(start 0.12065 0.3048)
			(end 0.67945 0.3048)
			(stroke
				(width 0.1)
				(type default)
			)
			(layer "B.Fab")
		)
		(fp_line
			(start 0.67945 -0.305054)
			(end 0.12065 -0.305054)
			(stroke
				(width 0.1)
				(type default)
			)
			(layer "B.Fab")
		)
		(fp_line
			(start 0.67945 0.3048)
			(end 0.67945 -0.305054)
			(stroke
				(width 0.1)
				(type default)
			)
			(layer "B.Fab")
		)
		(pad "1" smd circle
			(at 0.40005 0 180)
			(size 0 0)
			(layers "B.Cu" "B.Mask" "B.Paste")
			(net "PWRGD_DRAMPWRGD_CPU1_AB_R_LVC1")
		)
		(pad "2" smd circle
			(at -0.40005 0 180)
			(size 0 0)
			(layers "B.Cu" "B.Mask" "B.Paste")
			(net "PWRGD_DRAMPWRGD_CPU1_AB_LVC1_R2")
		)
	)
	(footprint ""
		(layer "B.Cu")
		(at 461.35544 -314.772294 90)
		(property "Reference" "R3889"
			(at 0 0 90)
			(layer "B.SilkS")
			(hide yes)
			(effects
				(font
					(size 1.27 1.27)
				)
				(justify mirror)
			)
		)
		(property "Value" ""
			(at 0 0 90)
			(layer "B.Fab")
			(effects
				(font
					(size 1.27 1.27)
				)
				(justify mirror)
			)
		)
		(duplicate_pad_numbers_are_jumpers no)
		(fp_line
			(start 0.7874 -0.4064)
			(end -0.7874 -0.4064)
			(stroke
				(width 0.1524)
				(type default)
			)
			(layer "B.SilkS")
		)
		(fp_line
			(start -0.7874 -0.4064)
			(end -0.7874 0.4064)
			(stroke
				(width 0.1524)
				(type default)
			)
			(layer "B.SilkS")
		)
		(fp_line
			(start 0.7874 0.4064)
			(end 0.7874 -0.4064)
			(stroke
				(width 0.1524)
				(type default)
			)
			(layer "B.SilkS")
		)
		(fp_line
			(start -0.7874 0.4064)
			(end 0.7874 0.4064)
			(stroke
				(width 0.1524)
				(type default)
			)
			(layer "B.SilkS")
		)
		(fp_line
			(start 0.67945 -0.305054)
			(end 0.12065 -0.305054)
			(stroke
				(width 0.1)
				(type default)
			)
			(layer "B.Fab")
		)
		(fp_line
			(start 0.12065 -0.305054)
			(end 0.12065 -0.2794)
			(stroke
				(width 0.1)
				(type default)
			)
			(layer "B.Fab")
		)
		(fp_line
			(start -0.12065 -0.3048)
			(end -0.67945 -0.3048)
			(stroke
				(width 0.1)
				(type default)
			)
			(layer "B.Fab")
		)
		(fp_line
			(start -0.67945 -0.3048)
			(end -0.67945 0.3048)
			(stroke
				(width 0.1)
				(type default)
			)
			(layer "B.Fab")
		)
		(fp_line
			(start 0.12065 -0.2794)
			(end -0.12065 -0.2794)
			(stroke
				(width 0.1)
				(type default)
			)
			(layer "B.Fab")
		)
		(fp_line
			(start -0.12065 -0.2794)
			(end -0.12065 -0.3048)
			(stroke
				(width 0.1)
				(type default)
			)
			(layer "B.Fab")
		)
		(fp_line
			(start 0.12065 0.2794)
			(end 0.12065 0.3048)
			(stroke
				(width 0.1)
				(type default)
			)
			(layer "B.Fab")
		)
		(fp_line
			(start -0.120396 0.2794)
			(end 0.12065 0.2794)
			(stroke
				(width 0.1)
				(type default)
			)
			(layer "B.Fab")
		)
		(fp_line
			(start 0.67945 0.3048)
			(end 0.67945 -0.305054)
			(stroke
				(width 0.1)
				(type default)
			)
			(layer "B.Fab")
		)
		(fp_line
			(start 0.12065 0.3048)
			(end 0.67945 0.3048)
			(stroke
				(width 0.1)
				(type default)
			)
			(layer "B.Fab")
		)
		(fp_line
			(start -0.120396 0.3048)
			(end -0.120396 0.2794)
			(stroke
				(width 0.1)
				(type default)
			)
			(layer "B.Fab")
		)
		(fp_line
			(start -0.67945 0.3048)
			(end -0.120396 0.3048)
			(stroke
				(width 0.1)
				(type default)
			)
			(layer "B.Fab")
		)
		(pad "1" smd circle
			(at 0.40005 0 270)
			(size 0 0)
			(layers "B.Cu" "B.Mask" "B.Paste")
			(net "I3C_SPD_DDREFGH_CPU0_LVC1_SCL_6")
		)
		(pad "2" smd circle
			(at -0.40005 0 270)
			(size 0 0)
			(layers "B.Cu" "B.Mask" "B.Paste")
			(net "I3C_SPD_DDREFGH_CPU0_LVC1_SCL")
		)
	)
	(footprint ""
		(layer "B.Cu")
		(at 309.25389 -30.734508)
		(property "Reference" "R378"
			(at 0 0 0)
			(layer "B.SilkS")
			(hide yes)
			(effects
				(font
					(size 1.27 1.27)
				)
				(justify mirror)
			)
		)
		(property "Value" ""
			(at 0 0 0)
			(layer "B.Fab")
			(effects
				(font
					(size 1.27 1.27)
				)
				(justify mirror)
			)
		)
		(duplicate_pad_numbers_are_jumpers no)
		(fp_line
			(start -0.7874 -0.4064)
			(end -0.7874 0.4064)
			(stroke
				(width 0.1524)
				(type default)
			)
			(layer "B.SilkS")
		)
		(fp_line
			(start -0.7874 0.4064)
			(end 0.7874 0.4064)
			(stroke
				(width 0.1524)
				(type default)
			)
			(layer "B.SilkS")
		)
		(fp_line
			(start 0.7874 -0.4064)
			(end -0.7874 -0.4064)
			(stroke
				(width 0.1524)
				(type default)
			)
			(layer "B.SilkS")
		)
		(fp_line
			(start 0.7874 0.4064)
			(end 0.7874 -0.4064)
			(stroke
				(width 0.1524)
				(type default)
			)
			(layer "B.SilkS")
		)
		(fp_line
			(start -0.67945 -0.3048)
			(end -0.67945 0.3048)
			(stroke
				(width 0.1)
				(type default)
			)
			(layer "B.Fab")
		)
		(fp_line
			(start -0.67945 0.3048)
			(end -0.120396 0.3048)
			(stroke
				(width 0.1)
				(type default)
			)
			(layer "B.Fab")
		)
		(fp_line
			(start -0.12065 -0.3048)
			(end -0.67945 -0.3048)
			(stroke
				(width 0.1)
				(type default)
			)
			(layer "B.Fab")
		)
		(fp_line
			(start -0.12065 -0.2794)
			(end -0.12065 -0.3048)
			(stroke
				(width 0.1)
				(type default)
			)
			(layer "B.Fab")
		)
		(fp_line
			(start -0.120396 0.2794)
			(end 0.12065 0.2794)
			(stroke
				(width 0.1)
				(type default)
			)
			(layer "B.Fab")
		)
		(fp_line
			(start -0.120396 0.3048)
			(end -0.120396 0.2794)
			(stroke
				(width 0.1)
				(type default)
			)
			(layer "B.Fab")
		)
		(fp_line
			(start 0.12065 -0.305054)
			(end 0.12065 -0.2794)
			(stroke
				(width 0.1)
				(type default)
			)
			(layer "B.Fab")
		)
		(fp_line
			(start 0.12065 -0.2794)
			(end -0.12065 -0.2794)
			(stroke
				(width 0.1)
				(type default)
			)
			(layer "B.Fab")
		)
		(fp_line
			(start 0.12065 0.2794)
			(end 0.12065 0.3048)
			(stroke
				(width 0.1)
				(type default)
			)
			(layer "B.Fab")
		)
		(fp_line
			(start 0.12065 0.3048)
			(end 0.67945 0.3048)
			(stroke
				(width 0.1)
				(type default)
			)
			(layer "B.Fab")
		)
		(fp_line
			(start 0.67945 -0.305054)
			(end 0.12065 -0.305054)
			(stroke
				(width 0.1)
				(type default)
			)
			(layer "B.Fab")
		)
		(fp_line
			(start 0.67945 0.3048)
			(end 0.67945 -0.305054)
			(stroke
				(width 0.1)
				(type default)
			)
			(layer "B.Fab")
		)
		(pad "1" smd circle
			(at 0.40005 0 180)
			(size 0 0)
			(layers "B.Cu" "B.Mask" "B.Paste")
			(net "P3V3_AUX")
		)
		(pad "2" smd circle
			(at -0.40005 0 180)
			(size 0 0)
			(layers "B.Cu" "B.Mask" "B.Paste")
			(net "FM_ADR_MODE1")
		)
	)
	(footprint ""
		(layer "B.Cu")
		(at 197.225158 -77.192632)
		(property "Reference" "U67"
			(at 2.032 -3.27533 0)
			(unlocked yes)
			(layer "B.SilkS")
			(effects
				(font
					(size 0.7874 0.5842)
					(thickness 0.1524)
				)
				(justify left mirror)
			)
		)
		(property "Value" ""
			(at 0 0 0)
			(layer "B.Fab")
			(effects
				(font
					(size 1.27 1.27)
				)
				(justify mirror)
			)
		)
		(duplicate_pad_numbers_are_jumpers no)
		(fp_line
			(start -2.0066 -2.5527)
			(end -2.0066 2.5527)
			(stroke
				(width 0.1524)
				(type default)
			)
			(layer "B.SilkS")
		)
		(fp_line
			(start -2.0066 2.5527)
			(end 2.0066 2.5527)
			(stroke
				(width 0.1524)
				(type default)
			)
			(layer "B.SilkS")
		)
		(fp_line
			(start -0.5715 -2.5527)
			(end -2.0066 -2.5527)
			(stroke
				(width 0.1524)
				(type default)
			)
			(layer "B.SilkS")
		)
		(fp_line
			(start 0 -1.9812)
			(end -0.5715 -2.5527)
			(stroke
				(width 0.1524)
				(type default)
			)
			(layer "B.SilkS")
		)
		(fp_line
			(start 0.5715 -2.5527)
			(end 0 -1.9812)
			(stroke
				(width 0.1524)
				(type default)
			)
			(layer "B.SilkS")
		)
		(fp_line
			(start 2.0066 -2.5527)
			(end 0.5715 -2.5527)
			(stroke
				(width 0.1524)
				(type default)
			)
			(layer "B.SilkS")
		)
		(fp_line
			(start 2.0066 2.5527)
			(end 2.0066 -2.5527)
			(stroke
				(width 0.1524)
				(type default)
			)
			(layer "B.SilkS")
		)
		(fp_poly
			(pts
				(xy 3.81 -1.905) (xy 4.36372 -2.233168) (xy 4.36372 -1.608328)
			)
			(stroke
				(width 0)
				(type default)
			)
			(fill yes)
			(layer "B.SilkS")
		)
		(fp_line
			(start -2.249932 -2.549906)
			(end -2.249932 2.549906)
			(stroke
				(width 0.1)
				(type default)
			)
			(layer "B.Fab")
		)
		(fp_line
			(start -2.249932 2.549906)
			(end 2.249932 2.549906)
			(stroke
				(width 0.1)
				(type default)
			)
			(layer "B.Fab")
		)
		(fp_line
			(start 2.249932 -2.549906)
			(end -2.249932 -2.549906)
			(stroke
				(width 0.1)
				(type default)
			)
			(layer "B.Fab")
		)
		(fp_line
			(start 2.249932 2.549906)
			(end 2.249932 -2.549906)
			(stroke
				(width 0.1)
				(type default)
			)
			(layer "B.Fab")
		)
		(fp_poly
			(pts
				(xy 4.36372 -1.608328) (xy 4.36372 -2.233168) (xy 3.81 -1.905)
			)
			(stroke
				(width 0)
				(type default)
			)
			(fill yes)
			(layer "B.Fab")
		)
		(pad "1" smd rect
			(at 2.921 -1.949958 270)
			(size 0.3556 1.4986)
			(layers "B.Cu" "B.Mask" "B.Paste")
			(net "FB_BMC_ISOLATE")
		)
		(pad "2" smd rect
			(at 2.921 -1.299972 270)
			(size 0.3556 1.4986)
			(layers "B.Cu" "B.Mask" "B.Paste")
			(net "NCSI_BMC_RXD1_R")
		)
		(pad "3" smd rect
			(at 2.921 -0.649986 270)
			(size 0.3556 1.4986)
			(layers "B.Cu" "B.Mask" "B.Paste")
			(net "NCSI_OCP_SFF_RXD1")
		)
		(pad "4" smd rect
			(at 2.921 0 270)
			(size 0.3556 1.4986)
			(layers "B.Cu" "B.Mask" "B.Paste")
			(net "FB_BMC_ISOLATE")
		)
		(pad "5" smd rect
			(at 2.921 0.649986 270)
			(size 0.3556 1.4986)
			(layers "B.Cu" "B.Mask" "B.Paste")
			(net "NCSI_BMC_RXD0_R")
		)
		(pad "6" smd rect
			(at 2.921 1.299972 270)
			(size 0.3556 1.4986)
			(layers "B.Cu" "B.Mask" "B.Paste")
			(net "NCSI_OCP_SFF_RXD0")
		)
		(pad "7" smd rect
			(at 2.921 1.949958 270)
			(size 0.3556 1.4986)
			(layers "B.Cu" "B.Mask" "B.Paste")
			(net "GND")
		)
		(pad "8" smd rect
			(at -2.921 1.949958 270)
			(size 0.3556 1.4986)
			(layers "B.Cu" "B.Mask" "B.Paste")
			(net "NCSI_OCP_SFF_CRS_DV")
		)
		(pad "9" smd rect
			(at -2.921 1.299972 270)
			(size 0.3556 1.4986)
			(layers "B.Cu" "B.Mask" "B.Paste")
			(net "NCSI_BMC_CRS_DV_R")
		)
		(pad "10" smd rect
			(at -2.921 0.649986 270)
			(size 0.3556 1.4986)
			(layers "B.Cu" "B.Mask" "B.Paste")
			(net "FB_BMC_ISOLATE")
		)
		(pad "11" smd rect
			(at -2.921 0 270)
			(size 0.3556 1.4986)
			(layers "B.Cu" "B.Mask" "B.Paste")
			(net "OCP_SFF_ISO1_RBT_ARB_IN")
		)
		(pad "12" smd rect
			(at -2.921 -0.649986 270)
			(size 0.3556 1.4986)
			(layers "B.Cu" "B.Mask" "B.Paste")
			(net "OCP_SFF_RBT_ARB_IN_R")
		)
		(pad "13" smd rect
			(at -2.921 -1.299972 270)
			(size 0.3556 1.4986)
			(layers "B.Cu" "B.Mask" "B.Paste")
			(net "FB_BMC_ISOLATE")
		)
		(pad "14" smd rect
			(at -2.921 -1.949958 270)
			(size 0.3556 1.4986)
			(layers "B.Cu" "B.Mask" "B.Paste")
			(net "P3V3_AUX")
		)
	)
	(footprint ""
		(layer "B.Cu")
		(at 349.344742 -210.41868 180)
		(property "Reference" "C516"
			(at 0 0 0)
			(layer "B.SilkS")
			(hide yes)
			(effects
				(font
					(size 1.27 1.27)
				)
				(justify mirror)
			)
		)
		(property "Value" ""
			(at 0 0 0)
			(layer "B.Fab")
			(effects
				(font
					(size 1.27 1.27)
				)
				(justify mirror)
			)
		)
		(duplicate_pad_numbers_are_jumpers no)
		(fp_line
			(start 1.2954 0.5842)
			(end 1.2954 -0.5842)
			(stroke
				(width 0.1524)
				(type default)
			)
			(layer "B.SilkS")
		)
		(fp_line
			(start 1.2954 -0.5842)
			(end -1.2954 -0.5842)
			(stroke
				(width 0.1524)
				(type default)
			)
			(layer "B.SilkS")
		)
		(fp_line
			(start 0 -0.5842)
			(end 0 0.5842)
			(stroke
				(width 0.1524)
				(type default)
			)
			(layer "B.SilkS")
		)
		(fp_line
			(start -1.2954 0.5842)
			(end 1.2954 0.5842)
			(stroke
				(width 0.1524)
				(type default)
			)
			(layer "B.SilkS")
		)
		(fp_line
			(start -1.2954 -0.5842)
			(end -1.2954 0.5842)
			(stroke
				(width 0.1524)
				(type default)
			)
			(layer "B.SilkS")
		)
		(fp_line
			(start 1.1938 0.4064)
			(end 1.1938 -0.4064)
			(stroke
				(width 0.1)
				(type default)
			)
			(layer "B.Fab")
		)
		(fp_line
			(start 1.1938 -0.4064)
			(end 0.8636 -0.4064)
			(stroke
				(width 0.1)
				(type default)
			)
			(layer "B.Fab")
		)
		(fp_line
			(start 0.8636 0.4572)
			(end 0.8636 0.4064)
			(stroke
				(width 0.1)
				(type default)
			)
			(layer "B.Fab")
		)
		(fp_line
			(start 0.8636 0.4064)
			(end 1.1938 0.4064)
			(stroke
				(width 0.1)
				(type default)
			)
			(layer "B.Fab")
		)
		(fp_line
			(start 0.8636 -0.4064)
			(end 0.8636 -0.4572)
			(stroke
				(width 0.1)
				(type default)
			)
			(layer "B.Fab")
		)
		(fp_line
			(start 0.8636 -0.4572)
			(end -0.8636 -0.4572)
			(stroke
				(width 0.1)
				(type default)
			)
			(layer "B.Fab")
		)
		(fp_line
			(start -0.8636 0.4572)
			(end 0.8636 0.4572)
			(stroke
				(width 0.1)
				(type default)
			)
			(layer "B.Fab")
		)
		(fp_line
			(start -0.8636 0.4064)
			(end -0.8636 0.4572)
			(stroke
				(width 0.1)
				(type default)
			)
			(layer "B.Fab")
		)
		(fp_line
			(start -0.8636 -0.4064)
			(end -1.1938 -0.4064)
			(stroke
				(width 0.1)
				(type default)
			)
			(layer "B.Fab")
		)
		(fp_line
			(start -0.8636 -0.4572)
			(end -0.8636 -0.4064)
			(stroke
				(width 0.1)
				(type default)
			)
			(layer "B.Fab")
		)
		(fp_line
			(start -1.1938 0.4064)
			(end -0.8636 0.4064)
			(stroke
				(width 0.1)
				(type default)
			)
			(layer "B.Fab")
		)
		(fp_line
			(start -1.1938 -0.4064)
			(end -1.1938 0.4064)
			(stroke
				(width 0.1)
				(type default)
			)
			(layer "B.Fab")
		)
		(pad "1" smd rect
			(at 0.7366 0 90)
			(size 0.7112 0.8128)
			(layers "B.Cu" "B.Mask" "B.Paste")
			(net "PVCCFA_EHV_CPU0")
		)
		(pad "2" smd rect
			(at -0.7366 0 90)
			(size 0.7112 0.8128)
			(layers "B.Cu" "B.Mask" "B.Paste")
			(net "GND")
		)
	)
	(footprint ""
		(layer "B.Cu")
		(at 143.793718 -335.62798)
		(property "Reference" "C1390"
			(at 0 0 0)
			(layer "B.SilkS")
			(hide yes)
			(effects
				(font
					(size 1.27 1.27)
				)
				(justify mirror)
			)
		)
		(property "Value" ""
			(at 0 0 0)
			(layer "B.Fab")
			(effects
				(font
					(size 1.27 1.27)
				)
				(justify mirror)
			)
		)
		(duplicate_pad_numbers_are_jumpers no)
		(fp_line
			(start -1.524 -0.762)
			(end -1.524 0.762)
			(stroke
				(width 0.1524)
				(type default)
			)
			(layer "B.SilkS")
		)
		(fp_line
			(start -1.524 0.762)
			(end 1.524 0.762)
			(stroke
				(width 0.1524)
				(type default)
			)
			(layer "B.SilkS")
		)
		(fp_line
			(start 1.524 -0.762)
			(end -1.524 -0.762)
			(stroke
				(width 0.1524)
				(type default)
			)
			(layer "B.SilkS")
		)
		(fp_line
			(start 1.524 0.762)
			(end 1.524 -0.762)
			(stroke
				(width 0.1524)
				(type default)
			)
			(layer "B.SilkS")
		)
		(fp_line
			(start -1.1049 -0.724916)
			(end 1.1049 -0.724916)
			(stroke
				(width 0.1)
				(type default)
			)
			(layer "B.Fab")
		)
		(fp_line
			(start -1.1049 0.724916)
			(end -1.1049 -0.724916)
			(stroke
				(width 0.1)
				(type default)
			)
			(layer "B.Fab")
		)
		(fp_line
			(start 1.1049 -0.724916)
			(end 1.1049 0.724916)
			(stroke
				(width 0.1)
				(type default)
			)
			(layer "B.Fab")
		)
		(fp_line
			(start 1.1049 0.724916)
			(end -1.1049 0.724916)
			(stroke
				(width 0.1)
				(type default)
			)
			(layer "B.Fab")
		)
		(pad "1" smd rect
			(at 0.889 0)
			(size 1.016 1.27)
			(layers "B.Cu" "B.Mask" "B.Paste")
			(net "PVPP_HBM_CPU1")
		)
		(pad "2" smd rect
			(at -0.889 0)
			(size 1.016 1.27)
			(layers "B.Cu" "B.Mask" "B.Paste")
			(net "GND")
		)
	)
	(footprint ""
		(layer "B.Cu")
		(at 277.138384 -193.669666 -90)
		(property "Reference" "R249"
			(at 0 0 90)
			(layer "B.SilkS")
			(hide yes)
			(effects
				(font
					(size 1.27 1.27)
				)
				(justify mirror)
			)
		)
		(property "Value" ""
			(at 0 0 90)
			(layer "B.Fab")
			(effects
				(font
					(size 1.27 1.27)
				)
				(justify mirror)
			)
		)
		(duplicate_pad_numbers_are_jumpers no)
		(fp_line
			(start -0.7874 0.4064)
			(end 0.7874 0.4064)
			(stroke
				(width 0.1524)
				(type default)
			)
			(layer "B.SilkS")
		)
		(fp_line
			(start 0.7874 0.4064)
			(end 0.7874 -0.4064)
			(stroke
				(width 0.1524)
				(type default)
			)
			(layer "B.SilkS")
		)
		(fp_line
			(start -0.7874 -0.4064)
			(end -0.7874 0.4064)
			(stroke
				(width 0.1524)
				(type default)
			)
			(layer "B.SilkS")
		)
		(fp_line
			(start 0.7874 -0.4064)
			(end -0.7874 -0.4064)
			(stroke
				(width 0.1524)
				(type default)
			)
			(layer "B.SilkS")
		)
		(fp_line
			(start -0.67945 0.3048)
			(end -0.120396 0.3048)
			(stroke
				(width 0.1)
				(type default)
			)
			(layer "B.Fab")
		)
		(fp_line
			(start -0.120396 0.3048)
			(end -0.120396 0.2794)
			(stroke
				(width 0.1)
				(type default)
			)
			(layer "B.Fab")
		)
		(fp_line
			(start 0.12065 0.3048)
			(end 0.67945 0.3048)
			(stroke
				(width 0.1)
				(type default)
			)
			(layer "B.Fab")
		)
		(fp_line
			(start 0.67945 0.3048)
			(end 0.67945 -0.305054)
			(stroke
				(width 0.1)
				(type default)
			)
			(layer "B.Fab")
		)
		(fp_line
			(start -0.120396 0.2794)
			(end 0.12065 0.2794)
			(stroke
				(width 0.1)
				(type default)
			)
			(layer "B.Fab")
		)
		(fp_line
			(start 0.12065 0.2794)
			(end 0.12065 0.3048)
			(stroke
				(width 0.1)
				(type default)
			)
			(layer "B.Fab")
		)
		(fp_line
			(start -0.12065 -0.2794)
			(end -0.12065 -0.3048)
			(stroke
				(width 0.1)
				(type default)
			)
			(layer "B.Fab")
		)
		(fp_line
			(start 0.12065 -0.2794)
			(end -0.12065 -0.2794)
			(stroke
				(width 0.1)
				(type default)
			)
			(layer "B.Fab")
		)
		(fp_line
			(start -0.67945 -0.3048)
			(end -0.67945 0.3048)
			(stroke
				(width 0.1)
				(type default)
			)
			(layer "B.Fab")
		)
		(fp_line
			(start -0.12065 -0.3048)
			(end -0.67945 -0.3048)
			(stroke
				(width 0.1)
				(type default)
			)
			(layer "B.Fab")
		)
		(fp_line
			(start 0.12065 -0.305054)
			(end 0.12065 -0.2794)
			(stroke
				(width 0.1)
				(type default)
			)
			(layer "B.Fab")
		)
		(fp_line
			(start 0.67945 -0.305054)
			(end 0.12065 -0.305054)
			(stroke
				(width 0.1)
				(type default)
			)
			(layer "B.Fab")
		)
		(pad "1" smd circle
			(at 0.40005 0 90)
			(size 0 0)
			(layers "B.Cu" "B.Mask" "B.Paste")
			(net "PVNN_TERM_CPU0")
		)
		(pad "2" smd circle
			(at -0.40005 0 90)
			(size 0 0)
			(layers "B.Cu" "B.Mask" "B.Paste")
			(net "FM_S3M_CPU0_LVC1_GPIO_0")
		)
	)
	(footprint ""
		(layer "B.Cu")
		(at 54.880002 -151.098758 180)
		(property "Reference" "PC449_P1_2"
			(at 0 0 0)
			(layer "B.SilkS")
			(hide yes)
			(effects
				(font
					(size 1.27 1.27)
				)
				(justify mirror)
			)
		)
		(property "Value" ""
			(at 0 0 0)
			(layer "B.Fab")
			(effects
				(font
					(size 1.27 1.27)
				)
				(justify mirror)
			)
		)
		(duplicate_pad_numbers_are_jumpers no)
		(fp_line
			(start 1.524 0.762)
			(end 1.524 -0.762)
			(stroke
				(width 0.1524)
				(type default)
			)
			(layer "B.SilkS")
		)
		(fp_line
			(start 1.524 -0.762)
			(end -1.524 -0.762)
			(stroke
				(width 0.1524)
				(type default)
			)
			(layer "B.SilkS")
		)
		(fp_line
			(start -1.524 0.762)
			(end 1.524 0.762)
			(stroke
				(width 0.1524)
				(type default)
			)
			(layer "B.SilkS")
		)
		(fp_line
			(start -1.524 -0.762)
			(end -1.524 0.762)
			(stroke
				(width 0.1524)
				(type default)
			)
			(layer "B.SilkS")
		)
		(fp_line
			(start 1.1049 0.724916)
			(end -1.1049 0.724916)
			(stroke
				(width 0.1)
				(type default)
			)
			(layer "B.Fab")
		)
		(fp_line
			(start 1.1049 -0.724916)
			(end 1.1049 0.724916)
			(stroke
				(width 0.1)
				(type default)
			)
			(layer "B.Fab")
		)
		(fp_line
			(start -1.1049 0.724916)
			(end -1.1049 -0.724916)
			(stroke
				(width 0.1)
				(type default)
			)
			(layer "B.Fab")
		)
		(fp_line
			(start -1.1049 -0.724916)
			(end 1.1049 -0.724916)
			(stroke
				(width 0.1)
				(type default)
			)
			(layer "B.Fab")
		)
		(pad "1" smd rect
			(at 0.889 0 180)
			(size 1.016 1.27)
			(layers "B.Cu" "B.Mask" "B.Paste")
			(net "SW_P12V_PVCCINFAON_CPU1_FLT")
		)
		(pad "2" smd rect
			(at -0.889 0 180)
			(size 1.016 1.27)
			(layers "B.Cu" "B.Mask" "B.Paste")
			(net "GND")
		)
	)
	(footprint ""
		(layer "B.Cu")
		(at 362.762038 -337.564984 -90)
		(property "Reference" "PC285_P0_3"
			(at 0 0 90)
			(layer "B.SilkS")
			(hide yes)
			(effects
				(font
					(size 1.27 1.27)
				)
				(justify mirror)
			)
		)
		(property "Value" ""
			(at 0 0 90)
			(layer "B.Fab")
			(effects
				(font
					(size 1.27 1.27)
				)
				(justify mirror)
			)
		)
		(duplicate_pad_numbers_are_jumpers no)
		(fp_line
			(start -1.524 0.762)
			(end 1.524 0.762)
			(stroke
				(width 0.1524)
				(type default)
			)
			(layer "B.SilkS")
		)
		(fp_line
			(start 1.524 0.762)
			(end 1.524 -0.762)
			(stroke
				(width 0.1524)
				(type default)
			)
			(layer "B.SilkS")
		)
		(fp_line
			(start -1.524 -0.762)
			(end -1.524 0.762)
			(stroke
				(width 0.1524)
				(type default)
			)
			(layer "B.SilkS")
		)
		(fp_line
			(start 1.524 -0.762)
			(end -1.524 -0.762)
			(stroke
				(width 0.1524)
				(type default)
			)
			(layer "B.SilkS")
		)
		(fp_line
			(start -1.1049 0.724916)
			(end -1.1049 -0.724916)
			(stroke
				(width 0.1)
				(type default)
			)
			(layer "B.Fab")
		)
		(fp_line
			(start 1.1049 0.724916)
			(end -1.1049 0.724916)
			(stroke
				(width 0.1)
				(type default)
			)
			(layer "B.Fab")
		)
		(fp_line
			(start -1.1049 -0.724916)
			(end 1.1049 -0.724916)
			(stroke
				(width 0.1)
				(type default)
			)
			(layer "B.Fab")
		)
		(fp_line
			(start 1.1049 -0.724916)
			(end 1.1049 0.724916)
			(stroke
				(width 0.1)
				(type default)
			)
			(layer "B.Fab")
		)
		(pad "1" smd rect
			(at 0.889 0 270)
			(size 1.016 1.27)
			(layers "B.Cu" "B.Mask" "B.Paste")
			(net "SW_P12V_PVCCIN_CPU0_FLT")
		)
		(pad "2" smd rect
			(at -0.889 0 270)
			(size 1.016 1.27)
			(layers "B.Cu" "B.Mask" "B.Paste")
			(net "GND")
		)
	)
	(footprint ""
		(layer "B.Cu")
		(at 509.384808 -153.16708 90)
		(property "Reference" "X25"
			(at 1.517142 2.940558 270)
			(unlocked yes)
			(layer "B.SilkS")
			(effects
				(font
					(size 0.7874 0.5842)
					(thickness 0.1524)
				)
				(justify left mirror)
			)
		)
		(property "Value" ""
			(at 0 0 90)
			(layer "B.Fab")
			(effects
				(font
					(size 1.27 1.27)
				)
				(justify mirror)
			)
		)
		(property "Device Type" "TP_TDR_4P_FTS_TH-TP_TDR_4P_DIPA"
			(at -1.30175 1.27 0)
			(unlocked yes)
			(layer "B.Fab")
			(hide yes)
			(effects
				(font
					(size 0.635 0.4064)
					(thickness 0.1524)
				)
				(justify mirror)
			)
		)
		(property "User Part Number" "N_A"
			(at -1.30175 1.27 0)
			(unlocked yes)
			(layer "Cmts.User")
			(hide yes)
			(effects
				(font
					(size 0.635 0.4064)
					(thickness 0.1524)
				)
				(justify mirror)
			)
		)
		(duplicate_pad_numbers_are_jumpers no)
		(fp_line
			(start 0 -1.27)
			(end 0 -0.635)
			(stroke
				(width 0.1524)
				(type default)
			)
			(layer "B.SilkS")
		)
		(fp_line
			(start -2.54 -1.27)
			(end 0 -1.27)
			(stroke
				(width 0.1524)
				(type default)
			)
			(layer "B.SilkS")
		)
		(fp_line
			(start -2.54 -1.1303)
			(end -2.54 -1.27)
			(stroke
				(width 0.1524)
				(type default)
			)
			(layer "B.SilkS")
		)
		(fp_line
			(start 0 0.635)
			(end 0 1.905)
			(stroke
				(width 0.1524)
				(type default)
			)
			(layer "B.SilkS")
		)
		(fp_line
			(start -2.54 1.4097)
			(end -2.54 1.1303)
			(stroke
				(width 0.1524)
				(type default)
			)
			(layer "B.SilkS")
		)
		(fp_line
			(start 0 3.175)
			(end 0 3.81)
			(stroke
				(width 0.1524)
				(type default)
			)
			(layer "B.SilkS")
		)
		(fp_line
			(start 0 3.81)
			(end -2.54 3.81)
			(stroke
				(width 0.1524)
				(type default)
			)
			(layer "B.SilkS")
		)
		(fp_line
			(start -2.54 3.81)
			(end -2.54 3.6703)
			(stroke
				(width 0.1524)
				(type default)
			)
			(layer "B.SilkS")
		)
		(fp_poly
			(pts
				(xy 2.917444 -0.951484) (xy 2.917444 0.572516) (xy 1.393444 -0.189484)
			)
			(stroke
				(width 0)
				(type default)
			)
			(fill yes)
			(layer "B.SilkS")
		)
		(fp_line
			(start 0 -1.27)
			(end 0 3.81)
			(stroke
				(width 0.1)
				(type default)
			)
			(layer "B.Fab")
		)
		(fp_line
			(start -2.54 -1.27)
			(end 0 -1.27)
			(stroke
				(width 0.1)
				(type default)
			)
			(layer "B.Fab")
		)
		(fp_line
			(start 0 3.81)
			(end -2.54 3.81)
			(stroke
				(width 0.1)
				(type default)
			)
			(layer "B.Fab")
		)
		(fp_line
			(start -2.54 3.81)
			(end -2.54 -1.27)
			(stroke
				(width 0.1)
				(type default)
			)
			(layer "B.Fab")
		)
		(fp_poly
			(pts
				(xy 0.761746 0) (xy 2.285746 -0.762) (xy 2.285746 0.762)
			)
			(stroke
				(width 0)
				(type default)
			)
			(fill yes)
			(layer "B.Fab")
		)
		(pad "1" thru_hole circle
			(at 0 0 270)
			(size 1.0033 1.0033)
			(drill 0.249936)
			(layers "*.Cu" "*.Mask")
			(remove_unused_layers no)
			(net "TDR_DIFF_85_IN5_DP")
			(clearance 0.10795)
			(padstack
				(mode front_inner_back)
				(layer "Inner"
					(shape circle)
					(size 0.8001 0.8001)
					(clearance 0.1524)
				)
				(layer "B.Cu"
					(shape circle)
					(size 1.0033 1.0033)
					(thermal_gap 0.10795)
					(clearance 0.10795)
				)
			)
		)
		(pad "2" thru_hole circle
			(at -2.54 0 270)
			(size 1.9939 1.9939)
			(drill 0.249936)
			(layers "*.Cu" "*.Mask")
			(remove_unused_layers no)
			(net "T1_GND")
			(clearance 0.10795)
			(padstack
				(mode front_inner_back)
				(layer "Inner"
					(shape circle)
					(size 0.8001 0.8001)
					(clearance 0.1524)
				)
				(layer "B.Cu"
					(shape circle)
					(size 1.9939 1.9939)
					(thermal_gap 0.10795)
					(clearance 0.10795)
				)
			)
		)
		(pad "3" thru_hole circle
			(at -2.54 2.54 270)
			(size 1.9939 1.9939)
			(drill 0.249936)
			(layers "*.Cu" "*.Mask")
			(remove_unused_layers no)
			(net "T1_GND")
			(clearance 0.10795)
			(padstack
				(mode front_inner_back)
				(layer "Inner"
					(shape circle)
					(size 0.8001 0.8001)
					(clearance 0.1524)
				)
				(layer "B.Cu"
					(shape circle)
					(size 1.9939 1.9939)
					(thermal_gap 0.10795)
					(clearance 0.10795)
				)
			)
		)
		(pad "4" thru_hole circle
			(at 0 2.54 270)
			(size 1.0033 1.0033)
			(drill 0.249936)
			(layers "*.Cu" "*.Mask")
			(remove_unused_layers no)
			(net "TDR_DIFF_85_IN5_DN")
			(clearance 0.10795)
			(padstack
				(mode front_inner_back)
				(layer "Inner"
					(shape circle)
					(size 0.8001 0.8001)
					(clearance 0.1524)
				)
				(layer "B.Cu"
					(shape circle)
					(size 1.0033 1.0033)
					(thermal_gap 0.10795)
					(clearance 0.10795)
				)
			)
		)
	)
	(footprint ""
		(layer "B.Cu")
		(at 123.57862 -27.424888)
		(property "Reference" "C2292"
			(at 0 0 0)
			(layer "B.SilkS")
			(hide yes)
			(effects
				(font
					(size 1.27 1.27)
				)
				(justify mirror)
			)
		)
		(property "Value" ""
			(at 0 0 0)
			(layer "B.Fab")
			(effects
				(font
					(size 1.27 1.27)
				)
				(justify mirror)
			)
		)
		(duplicate_pad_numbers_are_jumpers no)
		(fp_line
			(start -0.299974 -0.150114)
			(end -0.299974 0.150114)
			(stroke
				(width 0.1)
				(type default)
			)
			(layer "B.Fab")
		)
		(fp_line
			(start -0.299974 0.150114)
			(end 0.299974 0.150114)
			(stroke
				(width 0.1)
				(type default)
			)
			(layer "B.Fab")
		)
		(fp_line
			(start 0.299974 -0.150114)
			(end -0.299974 -0.150114)
			(stroke
				(width 0.1)
				(type default)
			)
			(layer "B.Fab")
		)
		(fp_line
			(start 0.299974 0.150114)
			(end 0.299974 -0.150114)
			(stroke
				(width 0.1)
				(type default)
			)
			(layer "B.Fab")
		)
		(pad "1" smd rect
			(at 0.2667 0 180)
			(size 0.3048 0.381)
			(layers "B.Cu" "B.Mask" "B.Paste")
			(net "USB3_PCH_RX_BUF_C_DN<4>")
		)
		(pad "2" smd rect
			(at -0.2667 0 180)
			(size 0.3048 0.381)
			(layers "B.Cu" "B.Mask" "B.Paste")
			(net "USB3_PCH_RX_BUF_DN<4>")
		)
	)
	(footprint ""
		(layer "B.Cu")
		(at 160.83788 -121.376948)
		(property "Reference" "R987"
			(at 0 0 0)
			(layer "B.SilkS")
			(hide yes)
			(effects
				(font
					(size 1.27 1.27)
				)
				(justify mirror)
			)
		)
		(property "Value" ""
			(at 0 0 0)
			(layer "B.Fab")
			(effects
				(font
					(size 1.27 1.27)
				)
				(justify mirror)
			)
		)
		(duplicate_pad_numbers_are_jumpers no)
		(fp_line
			(start -0.7874 -0.4064)
			(end -0.7874 0.4064)
			(stroke
				(width 0.1524)
				(type default)
			)
			(layer "B.SilkS")
		)
		(fp_line
			(start -0.7874 0.4064)
			(end 0.7874 0.4064)
			(stroke
				(width 0.1524)
				(type default)
			)
			(layer "B.SilkS")
		)
		(fp_line
			(start 0.7874 -0.4064)
			(end -0.7874 -0.4064)
			(stroke
				(width 0.1524)
				(type default)
			)
			(layer "B.SilkS")
		)
		(fp_line
			(start 0.7874 0.4064)
			(end 0.7874 -0.4064)
			(stroke
				(width 0.1524)
				(type default)
			)
			(layer "B.SilkS")
		)
		(fp_line
			(start -0.67945 -0.3048)
			(end -0.67945 0.3048)
			(stroke
				(width 0.1)
				(type default)
			)
			(layer "B.Fab")
		)
		(fp_line
			(start -0.67945 0.3048)
			(end -0.120396 0.3048)
			(stroke
				(width 0.1)
				(type default)
			)
			(layer "B.Fab")
		)
		(fp_line
			(start -0.12065 -0.3048)
			(end -0.67945 -0.3048)
			(stroke
				(width 0.1)
				(type default)
			)
			(layer "B.Fab")
		)
		(fp_line
			(start -0.12065 -0.2794)
			(end -0.12065 -0.3048)
			(stroke
				(width 0.1)
				(type default)
			)
			(layer "B.Fab")
		)
		(fp_line
			(start -0.120396 0.2794)
			(end 0.12065 0.2794)
			(stroke
				(width 0.1)
				(type default)
			)
			(layer "B.Fab")
		)
		(fp_line
			(start -0.120396 0.3048)
			(end -0.120396 0.2794)
			(stroke
				(width 0.1)
				(type default)
			)
			(layer "B.Fab")
		)
		(fp_line
			(start 0.12065 -0.305054)
			(end 0.12065 -0.2794)
			(stroke
				(width 0.1)
				(type default)
			)
			(layer "B.Fab")
		)
		(fp_line
			(start 0.12065 -0.2794)
			(end -0.12065 -0.2794)
			(stroke
				(width 0.1)
				(type default)
			)
			(layer "B.Fab")
		)
		(fp_line
			(start 0.12065 0.2794)
			(end 0.12065 0.3048)
			(stroke
				(width 0.1)
				(type default)
			)
			(layer "B.Fab")
		)
		(fp_line
			(start 0.12065 0.3048)
			(end 0.67945 0.3048)
			(stroke
				(width 0.1)
				(type default)
			)
			(layer "B.Fab")
		)
		(fp_line
			(start 0.67945 -0.305054)
			(end 0.12065 -0.305054)
			(stroke
				(width 0.1)
				(type default)
			)
			(layer "B.Fab")
		)
		(fp_line
			(start 0.67945 0.3048)
			(end 0.67945 -0.305054)
			(stroke
				(width 0.1)
				(type default)
			)
			(layer "B.Fab")
		)
		(pad "1" smd circle
			(at 0.40005 0 180)
			(size 0 0)
			(layers "B.Cu" "B.Mask" "B.Paste")
			(net "FM_PVCCINFAON_CPU1_R_EN")
		)
		(pad "2" smd circle
			(at -0.40005 0 180)
			(size 0 0)
			(layers "B.Cu" "B.Mask" "B.Paste")
			(net "FM_PVCCINFAON_CPU1_EN")
		)
	)
	(footprint ""
		(layer "B.Cu")
		(at 261.375906 -104.832912 180)
		(property "Reference" "R447"
			(at 0 0 0)
			(layer "B.SilkS")
			(hide yes)
			(effects
				(font
					(size 1.27 1.27)
				)
				(justify mirror)
			)
		)
		(property "Value" ""
			(at 0 0 0)
			(layer "B.Fab")
			(effects
				(font
					(size 1.27 1.27)
				)
				(justify mirror)
			)
		)
		(duplicate_pad_numbers_are_jumpers no)
		(fp_line
			(start 1.2954 0.5842)
			(end 1.2954 -0.5842)
			(stroke
				(width 0.1524)
				(type default)
			)
			(layer "B.SilkS")
		)
		(fp_line
			(start 1.2954 -0.5842)
			(end -1.2954 -0.5842)
			(stroke
				(width 0.1524)
				(type default)
			)
			(layer "B.SilkS")
		)
		(fp_line
			(start -1.2954 0.5842)
			(end 1.2954 0.5842)
			(stroke
				(width 0.1524)
				(type default)
			)
			(layer "B.SilkS")
		)
		(fp_line
			(start -1.2954 -0.5842)
			(end -1.2954 0.5842)
			(stroke
				(width 0.1524)
				(type default)
			)
			(layer "B.SilkS")
		)
		(fp_line
			(start 1.1938 0.4064)
			(end 1.1938 -0.406654)
			(stroke
				(width 0.1)
				(type default)
			)
			(layer "B.Fab")
		)
		(fp_line
			(start 1.1938 -0.406654)
			(end 0.8636 -0.406654)
			(stroke
				(width 0.1)
				(type default)
			)
			(layer "B.Fab")
		)
		(fp_line
			(start 0.8636 0.4572)
			(end 0.8636 0.4318)
			(stroke
				(width 0.1)
				(type default)
			)
			(layer "B.Fab")
		)
		(fp_line
			(start 0.8636 0.4318)
			(end 0.8636 0.4064)
			(stroke
				(width 0.1)
				(type default)
			)
			(layer "B.Fab")
		)
		(fp_line
			(start 0.8636 0.4064)
			(end 1.1938 0.4064)
			(stroke
				(width 0.1)
				(type default)
			)
			(layer "B.Fab")
		)
		(fp_line
			(start 0.8636 -0.406654)
			(end 0.8636 -0.4572)
			(stroke
				(width 0.1)
				(type default)
			)
			(layer "B.Fab")
		)
		(fp_line
			(start 0.8636 -0.4572)
			(end -0.8636 -0.4572)
			(stroke
				(width 0.1)
				(type default)
			)
			(layer "B.Fab")
		)
		(fp_line
			(start -0.8636 0.4572)
			(end 0.8636 0.4572)
			(stroke
				(width 0.1)
				(type default)
			)
			(layer "B.Fab")
		)
		(fp_line
			(start -0.8636 0.4064)
			(end -0.8636 0.4572)
			(stroke
				(width 0.1)
				(type default)
			)
			(layer "B.Fab")
		)
		(fp_line
			(start -0.8636 -0.406654)
			(end -1.1938 -0.406654)
			(stroke
				(width 0.1)
				(type default)
			)
			(layer "B.Fab")
		)
		(fp_line
			(start -0.8636 -0.4572)
			(end -0.8636 -0.406654)
			(stroke
				(width 0.1)
				(type default)
			)
			(layer "B.Fab")
		)
		(fp_line
			(start -1.1938 0.4064)
			(end -0.8636 0.4064)
			(stroke
				(width 0.1)
				(type default)
			)
			(layer "B.Fab")
		)
		(fp_line
			(start -1.1938 -0.406654)
			(end -1.1938 0.4064)
			(stroke
				(width 0.1)
				(type default)
			)
			(layer "B.Fab")
		)
		(pad "1" smd rect
			(at 0.7366 0 90)
			(size 0.7112 0.8128)
			(layers "B.Cu" "B.Mask" "B.Paste")
			(net "P3V3_AUX_CLK_GEN_VDDMXCK_CK440")
		)
		(pad "2" smd rect
			(at -0.7366 0 90)
			(size 0.7112 0.8128)
			(layers "B.Cu" "B.Mask" "B.Paste")
			(net "P3V3_AUX_CLK_GEN_VDDPT_CK440")
		)
	)
	(footprint ""
		(layer "B.Cu")
		(at 179.705 -19.522948 -90)
		(property "Reference" "R4505"
			(at 0 0 90)
			(layer "B.SilkS")
			(hide yes)
			(effects
				(font
					(size 1.27 1.27)
				)
				(justify mirror)
			)
		)
		(property "Value" ""
			(at 0 0 90)
			(layer "B.Fab")
			(effects
				(font
					(size 1.27 1.27)
				)
				(justify mirror)
			)
		)
		(duplicate_pad_numbers_are_jumpers no)
		(fp_line
			(start -0.7874 0.4064)
			(end 0.7874 0.4064)
			(stroke
				(width 0.1524)
				(type default)
			)
			(layer "B.SilkS")
		)
		(fp_line
			(start 0.7874 0.4064)
			(end 0.7874 -0.4064)
			(stroke
				(width 0.1524)
				(type default)
			)
			(layer "B.SilkS")
		)
		(fp_line
			(start -0.7874 -0.4064)
			(end -0.7874 0.4064)
			(stroke
				(width 0.1524)
				(type default)
			)
			(layer "B.SilkS")
		)
		(fp_line
			(start 0.7874 -0.4064)
			(end -0.7874 -0.4064)
			(stroke
				(width 0.1524)
				(type default)
			)
			(layer "B.SilkS")
		)
		(fp_line
			(start -0.67945 0.3048)
			(end -0.120396 0.3048)
			(stroke
				(width 0.1)
				(type default)
			)
			(layer "B.Fab")
		)
		(fp_line
			(start -0.120396 0.3048)
			(end -0.120396 0.2794)
			(stroke
				(width 0.1)
				(type default)
			)
			(layer "B.Fab")
		)
		(fp_line
			(start 0.12065 0.3048)
			(end 0.67945 0.3048)
			(stroke
				(width 0.1)
				(type default)
			)
			(layer "B.Fab")
		)
		(fp_line
			(start 0.67945 0.3048)
			(end 0.67945 -0.305054)
			(stroke
				(width 0.1)
				(type default)
			)
			(layer "B.Fab")
		)
		(fp_line
			(start -0.120396 0.2794)
			(end 0.12065 0.2794)
			(stroke
				(width 0.1)
				(type default)
			)
			(layer "B.Fab")
		)
		(fp_line
			(start 0.12065 0.2794)
			(end 0.12065 0.3048)
			(stroke
				(width 0.1)
				(type default)
			)
			(layer "B.Fab")
		)
		(fp_line
			(start -0.12065 -0.2794)
			(end -0.12065 -0.3048)
			(stroke
				(width 0.1)
				(type default)
			)
			(layer "B.Fab")
		)
		(fp_line
			(start 0.12065 -0.2794)
			(end -0.12065 -0.2794)
			(stroke
				(width 0.1)
				(type default)
			)
			(layer "B.Fab")
		)
		(fp_line
			(start -0.67945 -0.3048)
			(end -0.67945 0.3048)
			(stroke
				(width 0.1)
				(type default)
			)
			(layer "B.Fab")
		)
		(fp_line
			(start -0.12065 -0.3048)
			(end -0.67945 -0.3048)
			(stroke
				(width 0.1)
				(type default)
			)
			(layer "B.Fab")
		)
		(fp_line
			(start 0.12065 -0.305054)
			(end 0.12065 -0.2794)
			(stroke
				(width 0.1)
				(type default)
			)
			(layer "B.Fab")
		)
		(fp_line
			(start 0.67945 -0.305054)
			(end 0.12065 -0.305054)
			(stroke
				(width 0.1)
				(type default)
			)
			(layer "B.Fab")
		)
		(pad "1" smd circle
			(at 0.40005 0 90)
			(size 0 0)
			(layers "B.Cu" "B.Mask" "B.Paste")
			(net "SMB_SML1_PMBUS_3V3AUX_PCH_SCL")
		)
		(pad "2" smd circle
			(at -0.40005 0 90)
			(size 0 0)
			(layers "B.Cu" "B.Mask" "B.Paste")
			(net "SMB_SML1_PMBUS_3V3AUX_PCH_SCL_1")
		)
	)
	(footprint ""
		(layer "B.Cu")
		(at 107.457494 -238.04372 -90)
		(property "Reference" "C1387"
			(at 0 0 90)
			(layer "B.SilkS")
			(hide yes)
			(effects
				(font
					(size 1.27 1.27)
				)
				(justify mirror)
			)
		)
		(property "Value" ""
			(at 0 0 90)
			(layer "B.Fab")
			(effects
				(font
					(size 1.27 1.27)
				)
				(justify mirror)
			)
		)
		(duplicate_pad_numbers_are_jumpers no)
		(fp_line
			(start -1.524 0.762)
			(end 1.524 0.762)
			(stroke
				(width 0.1524)
				(type default)
			)
			(layer "B.SilkS")
		)
		(fp_line
			(start 1.524 0.762)
			(end 1.524 -0.762)
			(stroke
				(width 0.1524)
				(type default)
			)
			(layer "B.SilkS")
		)
		(fp_line
			(start -1.524 -0.762)
			(end -1.524 0.762)
			(stroke
				(width 0.1524)
				(type default)
			)
			(layer "B.SilkS")
		)
		(fp_line
			(start 1.524 -0.762)
			(end -1.524 -0.762)
			(stroke
				(width 0.1524)
				(type default)
			)
			(layer "B.SilkS")
		)
		(fp_line
			(start -1.1049 0.724916)
			(end -1.1049 -0.724916)
			(stroke
				(width 0.1)
				(type default)
			)
			(layer "B.Fab")
		)
		(fp_line
			(start 1.1049 0.724916)
			(end -1.1049 0.724916)
			(stroke
				(width 0.1)
				(type default)
			)
			(layer "B.Fab")
		)
		(fp_line
			(start -1.1049 -0.724916)
			(end 1.1049 -0.724916)
			(stroke
				(width 0.1)
				(type default)
			)
			(layer "B.Fab")
		)
		(fp_line
			(start 1.1049 -0.724916)
			(end 1.1049 0.724916)
			(stroke
				(width 0.1)
				(type default)
			)
			(layer "B.Fab")
		)
		(pad "1" smd rect
			(at 0.889 0 270)
			(size 1.016 1.27)
			(layers "B.Cu" "B.Mask" "B.Paste")
			(net "PVNN_MAIN_CPU1")
		)
		(pad "2" smd rect
			(at -0.889 0 270)
			(size 1.016 1.27)
			(layers "B.Cu" "B.Mask" "B.Paste")
			(net "GND")
		)
	)
	(footprint ""
		(layer "B.Cu")
		(at 144.399 -9.362948 -90)
		(property "Reference" "R1383"
			(at 0 0 90)
			(layer "B.SilkS")
			(hide yes)
			(effects
				(font
					(size 1.27 1.27)
				)
				(justify mirror)
			)
		)
		(property "Value" ""
			(at 0 0 90)
			(layer "B.Fab")
			(effects
				(font
					(size 1.27 1.27)
				)
				(justify mirror)
			)
		)
		(duplicate_pad_numbers_are_jumpers no)
		(fp_line
			(start -0.7874 0.4064)
			(end 0.7874 0.4064)
			(stroke
				(width 0.1524)
				(type default)
			)
			(layer "B.SilkS")
		)
		(fp_line
			(start 0.7874 0.4064)
			(end 0.7874 -0.4064)
			(stroke
				(width 0.1524)
				(type default)
			)
			(layer "B.SilkS")
		)
		(fp_line
			(start -0.7874 -0.4064)
			(end -0.7874 0.4064)
			(stroke
				(width 0.1524)
				(type default)
			)
			(layer "B.SilkS")
		)
		(fp_line
			(start 0.7874 -0.4064)
			(end -0.7874 -0.4064)
			(stroke
				(width 0.1524)
				(type default)
			)
			(layer "B.SilkS")
		)
		(fp_line
			(start -0.67945 0.3048)
			(end -0.120396 0.3048)
			(stroke
				(width 0.1)
				(type default)
			)
			(layer "B.Fab")
		)
		(fp_line
			(start -0.120396 0.3048)
			(end -0.120396 0.2794)
			(stroke
				(width 0.1)
				(type default)
			)
			(layer "B.Fab")
		)
		(fp_line
			(start 0.12065 0.3048)
			(end 0.67945 0.3048)
			(stroke
				(width 0.1)
				(type default)
			)
			(layer "B.Fab")
		)
		(fp_line
			(start 0.67945 0.3048)
			(end 0.67945 -0.305054)
			(stroke
				(width 0.1)
				(type default)
			)
			(layer "B.Fab")
		)
		(fp_line
			(start -0.120396 0.2794)
			(end 0.12065 0.2794)
			(stroke
				(width 0.1)
				(type default)
			)
			(layer "B.Fab")
		)
		(fp_line
			(start 0.12065 0.2794)
			(end 0.12065 0.3048)
			(stroke
				(width 0.1)
				(type default)
			)
			(layer "B.Fab")
		)
		(fp_line
			(start -0.12065 -0.2794)
			(end -0.12065 -0.3048)
			(stroke
				(width 0.1)
				(type default)
			)
			(layer "B.Fab")
		)
		(fp_line
			(start 0.12065 -0.2794)
			(end -0.12065 -0.2794)
			(stroke
				(width 0.1)
				(type default)
			)
			(layer "B.Fab")
		)
		(fp_line
			(start -0.67945 -0.3048)
			(end -0.67945 0.3048)
			(stroke
				(width 0.1)
				(type default)
			)
			(layer "B.Fab")
		)
		(fp_line
			(start -0.12065 -0.3048)
			(end -0.67945 -0.3048)
			(stroke
				(width 0.1)
				(type default)
			)
			(layer "B.Fab")
		)
		(fp_line
			(start 0.12065 -0.305054)
			(end 0.12065 -0.2794)
			(stroke
				(width 0.1)
				(type default)
			)
			(layer "B.Fab")
		)
		(fp_line
			(start 0.67945 -0.305054)
			(end 0.12065 -0.305054)
			(stroke
				(width 0.1)
				(type default)
			)
			(layer "B.Fab")
		)
		(pad "1" smd circle
			(at 0.40005 0 90)
			(size 0 0)
			(layers "B.Cu" "B.Mask" "B.Paste")
			(net "P3V3_AUX")
		)
		(pad "2" smd circle
			(at -0.40005 0 90)
			(size 0 0)
			(layers "B.Cu" "B.Mask" "B.Paste")
			(net "JTAG_BMC_DBP_PREQ_N")
		)
	)
	(footprint ""
		(layer "B.Cu")
		(at 361.691174 -362.698792 180)
		(property "Reference" "PR176"
			(at 0 0 0)
			(layer "B.SilkS")
			(hide yes)
			(effects
				(font
					(size 1.27 1.27)
				)
				(justify mirror)
			)
		)
		(property "Value" ""
			(at 0 0 0)
			(layer "B.Fab")
			(effects
				(font
					(size 1.27 1.27)
				)
				(justify mirror)
			)
		)
		(duplicate_pad_numbers_are_jumpers no)
		(fp_line
			(start 0.7874 0.4064)
			(end 0.7874 -0.4064)
			(stroke
				(width 0.1524)
				(type default)
			)
			(layer "B.SilkS")
		)
		(fp_line
			(start 0.7874 -0.4064)
			(end -0.7874 -0.4064)
			(stroke
				(width 0.1524)
				(type default)
			)
			(layer "B.SilkS")
		)
		(fp_line
			(start -0.7874 0.4064)
			(end 0.7874 0.4064)
			(stroke
				(width 0.1524)
				(type default)
			)
			(layer "B.SilkS")
		)
		(fp_line
			(start -0.7874 -0.4064)
			(end -0.7874 0.4064)
			(stroke
				(width 0.1524)
				(type default)
			)
			(layer "B.SilkS")
		)
		(fp_line
			(start 0.67945 0.3048)
			(end 0.67945 -0.305054)
			(stroke
				(width 0.1)
				(type default)
			)
			(layer "B.Fab")
		)
		(fp_line
			(start 0.67945 -0.305054)
			(end 0.12065 -0.305054)
			(stroke
				(width 0.1)
				(type default)
			)
			(layer "B.Fab")
		)
		(fp_line
			(start 0.12065 0.3048)
			(end 0.67945 0.3048)
			(stroke
				(width 0.1)
				(type default)
			)
			(layer "B.Fab")
		)
		(fp_line
			(start 0.12065 0.2794)
			(end 0.12065 0.3048)
			(stroke
				(width 0.1)
				(type default)
			)
			(layer "B.Fab")
		)
		(fp_line
			(start 0.12065 -0.2794)
			(end -0.12065 -0.2794)
			(stroke
				(width 0.1)
				(type default)
			)
			(layer "B.Fab")
		)
		(fp_line
			(start 0.12065 -0.305054)
			(end 0.12065 -0.2794)
			(stroke
				(width 0.1)
				(type default)
			)
			(layer "B.Fab")
		)
		(fp_line
			(start -0.120396 0.3048)
			(end -0.120396 0.2794)
			(stroke
				(width 0.1)
				(type default)
			)
			(layer "B.Fab")
		)
		(fp_line
			(start -0.120396 0.2794)
			(end 0.12065 0.2794)
			(stroke
				(width 0.1)
				(type default)
			)
			(layer "B.Fab")
		)
		(fp_line
			(start -0.12065 -0.2794)
			(end -0.12065 -0.3048)
			(stroke
				(width 0.1)
				(type default)
			)
			(layer "B.Fab")
		)
		(fp_line
			(start -0.12065 -0.3048)
			(end -0.67945 -0.3048)
			(stroke
				(width 0.1)
				(type default)
			)
			(layer "B.Fab")
		)
		(fp_line
			(start -0.67945 0.3048)
			(end -0.120396 0.3048)
			(stroke
				(width 0.1)
				(type default)
			)
			(layer "B.Fab")
		)
		(fp_line
			(start -0.67945 -0.3048)
			(end -0.67945 0.3048)
			(stroke
				(width 0.1)
				(type default)
			)
			(layer "B.Fab")
		)
		(pad "1" smd circle
			(at 0.40005 0)
			(size 0 0)
			(layers "B.Cu" "B.Mask" "B.Paste")
			(net "PVCCIN_CPU0_VCC")
		)
		(pad "2" smd circle
			(at -0.40005 0)
			(size 0 0)
			(layers "B.Cu" "B.Mask" "B.Paste")
			(net "P3V3_AUX")
		)
	)
	(footprint ""
		(layer "B.Cu")
		(at 309.55742 -33.22574 180)
		(property "Reference" "R4766"
			(at 0 0 0)
			(layer "B.SilkS")
			(hide yes)
			(effects
				(font
					(size 1.27 1.27)
				)
				(justify mirror)
			)
		)
		(property "Value" ""
			(at 0 0 0)
			(layer "B.Fab")
			(effects
				(font
					(size 1.27 1.27)
				)
				(justify mirror)
			)
		)
		(duplicate_pad_numbers_are_jumpers no)
		(fp_line
			(start 0.7874 0.4064)
			(end 0.7874 -0.4064)
			(stroke
				(width 0.1524)
				(type default)
			)
			(layer "B.SilkS")
		)
		(fp_line
			(start 0.7874 -0.4064)
			(end -0.7874 -0.4064)
			(stroke
				(width 0.1524)
				(type default)
			)
			(layer "B.SilkS")
		)
		(fp_line
			(start -0.7874 0.4064)
			(end 0.7874 0.4064)
			(stroke
				(width 0.1524)
				(type default)
			)
			(layer "B.SilkS")
		)
		(fp_line
			(start -0.7874 -0.4064)
			(end -0.7874 0.4064)
			(stroke
				(width 0.1524)
				(type default)
			)
			(layer "B.SilkS")
		)
		(fp_line
			(start 0.67945 0.3048)
			(end 0.67945 -0.305054)
			(stroke
				(width 0.1)
				(type default)
			)
			(layer "B.Fab")
		)
		(fp_line
			(start 0.67945 -0.305054)
			(end 0.12065 -0.305054)
			(stroke
				(width 0.1)
				(type default)
			)
			(layer "B.Fab")
		)
		(fp_line
			(start 0.12065 0.3048)
			(end 0.67945 0.3048)
			(stroke
				(width 0.1)
				(type default)
			)
			(layer "B.Fab")
		)
		(fp_line
			(start 0.12065 0.2794)
			(end 0.12065 0.3048)
			(stroke
				(width 0.1)
				(type default)
			)
			(layer "B.Fab")
		)
		(fp_line
			(start 0.12065 -0.2794)
			(end -0.12065 -0.2794)
			(stroke
				(width 0.1)
				(type default)
			)
			(layer "B.Fab")
		)
		(fp_line
			(start 0.12065 -0.305054)
			(end 0.12065 -0.2794)
			(stroke
				(width 0.1)
				(type default)
			)
			(layer "B.Fab")
		)
		(fp_line
			(start -0.120396 0.3048)
			(end -0.120396 0.2794)
			(stroke
				(width 0.1)
				(type default)
			)
			(layer "B.Fab")
		)
		(fp_line
			(start -0.120396 0.2794)
			(end 0.12065 0.2794)
			(stroke
				(width 0.1)
				(type default)
			)
			(layer "B.Fab")
		)
		(fp_line
			(start -0.12065 -0.2794)
			(end -0.12065 -0.3048)
			(stroke
				(width 0.1)
				(type default)
			)
			(layer "B.Fab")
		)
		(fp_line
			(start -0.12065 -0.3048)
			(end -0.67945 -0.3048)
			(stroke
				(width 0.1)
				(type default)
			)
			(layer "B.Fab")
		)
		(fp_line
			(start -0.67945 0.3048)
			(end -0.120396 0.3048)
			(stroke
				(width 0.1)
				(type default)
			)
			(layer "B.Fab")
		)
		(fp_line
			(start -0.67945 -0.3048)
			(end -0.67945 0.3048)
			(stroke
				(width 0.1)
				(type default)
			)
			(layer "B.Fab")
		)
		(pad "1" smd circle
			(at 0.40005 0)
			(size 0 0)
			(layers "B.Cu" "B.Mask" "B.Paste")
			(net "E1S_0_CLK_OE_N")
		)
		(pad "2" smd circle
			(at -0.40005 0)
			(size 0 0)
			(layers "B.Cu" "B.Mask" "B.Paste")
			(net "E1S_0_CLKREQ_N")
		)
	)
	(footprint ""
		(layer "B.Cu")
		(at 184.969404 -353.573842 90)
		(property "Reference" "PC1201_P1_3"
			(at 0 0 90)
			(layer "B.SilkS")
			(hide yes)
			(effects
				(font
					(size 1.27 1.27)
				)
				(justify mirror)
			)
		)
		(property "Value" ""
			(at 0 0 90)
			(layer "B.Fab")
			(effects
				(font
					(size 1.27 1.27)
				)
				(justify mirror)
			)
		)
		(duplicate_pad_numbers_are_jumpers no)
		(fp_line
			(start 1.524 -0.762)
			(end -1.524 -0.762)
			(stroke
				(width 0.1524)
				(type default)
			)
			(layer "B.SilkS")
		)
		(fp_line
			(start -1.524 -0.762)
			(end -1.524 0.762)
			(stroke
				(width 0.1524)
				(type default)
			)
			(layer "B.SilkS")
		)
		(fp_line
			(start 1.524 0.762)
			(end 1.524 -0.762)
			(stroke
				(width 0.1524)
				(type default)
			)
			(layer "B.SilkS")
		)
		(fp_line
			(start -1.524 0.762)
			(end 1.524 0.762)
			(stroke
				(width 0.1524)
				(type default)
			)
			(layer "B.SilkS")
		)
		(fp_line
			(start 1.1049 -0.724916)
			(end 1.1049 0.724916)
			(stroke
				(width 0.1)
				(type default)
			)
			(layer "B.Fab")
		)
		(fp_line
			(start -1.1049 -0.724916)
			(end 1.1049 -0.724916)
			(stroke
				(width 0.1)
				(type default)
			)
			(layer "B.Fab")
		)
		(fp_line
			(start 1.1049 0.724916)
			(end -1.1049 0.724916)
			(stroke
				(width 0.1)
				(type default)
			)
			(layer "B.Fab")
		)
		(fp_line
			(start -1.1049 0.724916)
			(end -1.1049 -0.724916)
			(stroke
				(width 0.1)
				(type default)
			)
			(layer "B.Fab")
		)
		(pad "1" smd rect
			(at 0.889 0 90)
			(size 1.016 1.27)
			(layers "B.Cu" "B.Mask" "B.Paste")
			(net "SW_P12V_PVCCFA_EHV_FIVRA_CPU1_R")
		)
		(pad "2" smd rect
			(at -0.889 0 90)
			(size 1.016 1.27)
			(layers "B.Cu" "B.Mask" "B.Paste")
			(net "GND")
		)
	)
	(footprint ""
		(layer "B.Cu")
		(at 342.251792 -64.088264 90)
		(property "Reference" "C164"
			(at 0 0 90)
			(layer "B.SilkS")
			(hide yes)
			(effects
				(font
					(size 1.27 1.27)
				)
				(justify mirror)
			)
		)
		(property "Value" ""
			(at 0 0 90)
			(layer "B.Fab")
			(effects
				(font
					(size 1.27 1.27)
				)
				(justify mirror)
			)
		)
		(duplicate_pad_numbers_are_jumpers no)
		(fp_line
			(start 0.299974 -0.150114)
			(end -0.299974 -0.150114)
			(stroke
				(width 0.1)
				(type default)
			)
			(layer "B.Fab")
		)
		(fp_line
			(start -0.299974 -0.150114)
			(end -0.299974 0.150114)
			(stroke
				(width 0.1)
				(type default)
			)
			(layer "B.Fab")
		)
		(fp_line
			(start 0.299974 0.150114)
			(end 0.299974 -0.150114)
			(stroke
				(width 0.1)
				(type default)
			)
			(layer "B.Fab")
		)
		(fp_line
			(start -0.299974 0.150114)
			(end 0.299974 0.150114)
			(stroke
				(width 0.1)
				(type default)
			)
			(layer "B.Fab")
		)
		(pad "1" smd rect
			(at 0.2667 0 270)
			(size 0.3048 0.381)
			(layers "B.Cu" "B.Mask" "B.Paste")
			(net "DMI_CPU0_PCH_RX_C_DP<3>")
		)
		(pad "2" smd rect
			(at -0.2667 0 270)
			(size 0.3048 0.381)
			(layers "B.Cu" "B.Mask" "B.Paste")
			(net "DMI_CPU0_PCH_RX_DP<3>")
		)
	)
	(footprint ""
		(layer "B.Cu")
		(at 302.150526 -49.06772 180)
		(property "Reference" "C1247"
			(at 0 0 0)
			(layer "B.SilkS")
			(hide yes)
			(effects
				(font
					(size 1.27 1.27)
				)
				(justify mirror)
			)
		)
		(property "Value" ""
			(at 0 0 0)
			(layer "B.Fab")
			(effects
				(font
					(size 1.27 1.27)
				)
				(justify mirror)
			)
		)
		(duplicate_pad_numbers_are_jumpers no)
		(fp_line
			(start 1.524 0.762)
			(end 1.524 -0.762)
			(stroke
				(width 0.1524)
				(type default)
			)
			(layer "B.SilkS")
		)
		(fp_line
			(start 1.524 -0.762)
			(end -1.524 -0.762)
			(stroke
				(width 0.1524)
				(type default)
			)
			(layer "B.SilkS")
		)
		(fp_line
			(start -1.524 0.762)
			(end 1.524 0.762)
			(stroke
				(width 0.1524)
				(type default)
			)
			(layer "B.SilkS")
		)
		(fp_line
			(start -1.524 -0.762)
			(end -1.524 0.762)
			(stroke
				(width 0.1524)
				(type default)
			)
			(layer "B.SilkS")
		)
		(fp_line
			(start 1.1049 0.724916)
			(end -1.1049 0.724916)
			(stroke
				(width 0.1)
				(type default)
			)
			(layer "B.Fab")
		)
		(fp_line
			(start 1.1049 -0.724916)
			(end 1.1049 0.724916)
			(stroke
				(width 0.1)
				(type default)
			)
			(layer "B.Fab")
		)
		(fp_line
			(start -1.1049 0.724916)
			(end -1.1049 -0.724916)
			(stroke
				(width 0.1)
				(type default)
			)
			(layer "B.Fab")
		)
		(fp_line
			(start -1.1049 -0.724916)
			(end 1.1049 -0.724916)
			(stroke
				(width 0.1)
				(type default)
			)
			(layer "B.Fab")
		)
		(pad "1" smd rect
			(at 0.889 0 180)
			(size 1.016 1.27)
			(layers "B.Cu" "B.Mask" "B.Paste")
			(net "P1V05_PCH_AUX")
		)
		(pad "2" smd rect
			(at -0.889 0 180)
			(size 1.016 1.27)
			(layers "B.Cu" "B.Mask" "B.Paste")
			(net "GND")
		)
	)
	(footprint ""
		(layer "B.Cu")
		(at 362.674662 -210.19389 180)
		(property "Reference" "C511"
			(at 0 0 0)
			(layer "B.SilkS")
			(hide yes)
			(effects
				(font
					(size 1.27 1.27)
				)
				(justify mirror)
			)
		)
		(property "Value" ""
			(at 0 0 0)
			(layer "B.Fab")
			(effects
				(font
					(size 1.27 1.27)
				)
				(justify mirror)
			)
		)
		(duplicate_pad_numbers_are_jumpers no)
		(fp_line
			(start 1.524 0.762)
			(end 1.524 -0.762)
			(stroke
				(width 0.1524)
				(type default)
			)
			(layer "B.SilkS")
		)
		(fp_line
			(start 1.524 -0.762)
			(end -1.524 -0.762)
			(stroke
				(width 0.1524)
				(type default)
			)
			(layer "B.SilkS")
		)
		(fp_line
			(start -1.524 0.762)
			(end 1.524 0.762)
			(stroke
				(width 0.1524)
				(type default)
			)
			(layer "B.SilkS")
		)
		(fp_line
			(start -1.524 -0.762)
			(end -1.524 0.762)
			(stroke
				(width 0.1524)
				(type default)
			)
			(layer "B.SilkS")
		)
		(fp_line
			(start 1.1049 0.724916)
			(end -1.1049 0.724916)
			(stroke
				(width 0.1)
				(type default)
			)
			(layer "B.Fab")
		)
		(fp_line
			(start 1.1049 -0.724916)
			(end 1.1049 0.724916)
			(stroke
				(width 0.1)
				(type default)
			)
			(layer "B.Fab")
		)
		(fp_line
			(start -1.1049 0.724916)
			(end -1.1049 -0.724916)
			(stroke
				(width 0.1)
				(type default)
			)
			(layer "B.Fab")
		)
		(fp_line
			(start -1.1049 -0.724916)
			(end 1.1049 -0.724916)
			(stroke
				(width 0.1)
				(type default)
			)
			(layer "B.Fab")
		)
		(pad "1" smd rect
			(at 0.889 0 180)
			(size 1.016 1.27)
			(layers "B.Cu" "B.Mask" "B.Paste")
			(net "PVCCD_HV_CPU0")
		)
		(pad "2" smd rect
			(at -0.889 0 180)
			(size 1.016 1.27)
			(layers "B.Cu" "B.Mask" "B.Paste")
			(net "GND")
		)
	)
	(footprint ""
		(layer "B.Cu")
		(at 435.549802 -11.088116 180)
		(property "Reference" "C1239"
			(at 0 0 0)
			(layer "B.SilkS")
			(hide yes)
			(effects
				(font
					(size 1.27 1.27)
				)
				(justify mirror)
			)
		)
		(property "Value" ""
			(at 0 0 0)
			(layer "B.Fab")
			(effects
				(font
					(size 1.27 1.27)
				)
				(justify mirror)
			)
		)
		(duplicate_pad_numbers_are_jumpers no)
		(fp_line
			(start 0.7874 0.4064)
			(end 0.7874 -0.4064)
			(stroke
				(width 0.1524)
				(type default)
			)
			(layer "B.SilkS")
		)
		(fp_line
			(start 0.7874 -0.4064)
			(end -0.7874 -0.4064)
			(stroke
				(width 0.1524)
				(type default)
			)
			(layer "B.SilkS")
		)
		(fp_line
			(start -0.7874 0.4064)
			(end 0.7874 0.4064)
			(stroke
				(width 0.1524)
				(type default)
			)
			(layer "B.SilkS")
		)
		(fp_line
			(start -0.7874 -0.4064)
			(end -0.7874 0.4064)
			(stroke
				(width 0.1524)
				(type default)
			)
			(layer "B.SilkS")
		)
		(fp_line
			(start 0.67945 0.3048)
			(end 0.67945 -0.305054)
			(stroke
				(width 0.1)
				(type default)
			)
			(layer "B.Fab")
		)
		(fp_line
			(start 0.67945 -0.305054)
			(end 0.12065 -0.305054)
			(stroke
				(width 0.1)
				(type default)
			)
			(layer "B.Fab")
		)
		(fp_line
			(start 0.12065 0.3048)
			(end 0.67945 0.3048)
			(stroke
				(width 0.1)
				(type default)
			)
			(layer "B.Fab")
		)
		(fp_line
			(start 0.12065 0.2794)
			(end 0.12065 0.3048)
			(stroke
				(width 0.1)
				(type default)
			)
			(layer "B.Fab")
		)
		(fp_line
			(start 0.12065 -0.2794)
			(end -0.12065 -0.2794)
			(stroke
				(width 0.1)
				(type default)
			)
			(layer "B.Fab")
		)
		(fp_line
			(start 0.12065 -0.305054)
			(end 0.12065 -0.2794)
			(stroke
				(width 0.1)
				(type default)
			)
			(layer "B.Fab")
		)
		(fp_line
			(start -0.120396 0.3048)
			(end -0.120396 0.2794)
			(stroke
				(width 0.1)
				(type default)
			)
			(layer "B.Fab")
		)
		(fp_line
			(start -0.120396 0.2794)
			(end 0.12065 0.2794)
			(stroke
				(width 0.1)
				(type default)
			)
			(layer "B.Fab")
		)
		(fp_line
			(start -0.12065 -0.2794)
			(end -0.12065 -0.3048)
			(stroke
				(width 0.1)
				(type default)
			)
			(layer "B.Fab")
		)
		(fp_line
			(start -0.12065 -0.3048)
			(end -0.67945 -0.3048)
			(stroke
				(width 0.1)
				(type default)
			)
			(layer "B.Fab")
		)
		(fp_line
			(start -0.67945 0.3048)
			(end -0.120396 0.3048)
			(stroke
				(width 0.1)
				(type default)
			)
			(layer "B.Fab")
		)
		(fp_line
			(start -0.67945 -0.3048)
			(end -0.67945 0.3048)
			(stroke
				(width 0.1)
				(type default)
			)
			(layer "B.Fab")
		)
		(pad "1" smd circle
			(at 0.40005 0)
			(size 0 0)
			(layers "B.Cu" "B.Mask" "B.Paste")
			(net "P3V3_OCP_SFF")
		)
		(pad "2" smd circle
			(at -0.40005 0)
			(size 0 0)
			(layers "B.Cu" "B.Mask" "B.Paste")
			(net "GND")
		)
	)
	(footprint ""
		(layer "B.Cu")
		(at 312.93054 -48.890428 180)
		(property "Reference" "R1944"
			(at 0 0 0)
			(layer "B.SilkS")
			(hide yes)
			(effects
				(font
					(size 1.27 1.27)
				)
				(justify mirror)
			)
		)
		(property "Value" ""
			(at 0 0 0)
			(layer "B.Fab")
			(effects
				(font
					(size 1.27 1.27)
				)
				(justify mirror)
			)
		)
		(duplicate_pad_numbers_are_jumpers no)
		(fp_line
			(start 0.7874 0.4064)
			(end 0.7874 -0.4064)
			(stroke
				(width 0.1524)
				(type default)
			)
			(layer "B.SilkS")
		)
		(fp_line
			(start 0.7874 -0.4064)
			(end -0.7874 -0.4064)
			(stroke
				(width 0.1524)
				(type default)
			)
			(layer "B.SilkS")
		)
		(fp_line
			(start -0.7874 0.4064)
			(end 0.7874 0.4064)
			(stroke
				(width 0.1524)
				(type default)
			)
			(layer "B.SilkS")
		)
		(fp_line
			(start -0.7874 -0.4064)
			(end -0.7874 0.4064)
			(stroke
				(width 0.1524)
				(type default)
			)
			(layer "B.SilkS")
		)
		(fp_line
			(start 0.67945 0.3048)
			(end 0.67945 -0.305054)
			(stroke
				(width 0.1)
				(type default)
			)
			(layer "B.Fab")
		)
		(fp_line
			(start 0.67945 -0.305054)
			(end 0.12065 -0.305054)
			(stroke
				(width 0.1)
				(type default)
			)
			(layer "B.Fab")
		)
		(fp_line
			(start 0.12065 0.3048)
			(end 0.67945 0.3048)
			(stroke
				(width 0.1)
				(type default)
			)
			(layer "B.Fab")
		)
		(fp_line
			(start 0.12065 0.2794)
			(end 0.12065 0.3048)
			(stroke
				(width 0.1)
				(type default)
			)
			(layer "B.Fab")
		)
		(fp_line
			(start 0.12065 -0.2794)
			(end -0.12065 -0.2794)
			(stroke
				(width 0.1)
				(type default)
			)
			(layer "B.Fab")
		)
		(fp_line
			(start 0.12065 -0.305054)
			(end 0.12065 -0.2794)
			(stroke
				(width 0.1)
				(type default)
			)
			(layer "B.Fab")
		)
		(fp_line
			(start -0.120396 0.3048)
			(end -0.120396 0.2794)
			(stroke
				(width 0.1)
				(type default)
			)
			(layer "B.Fab")
		)
		(fp_line
			(start -0.120396 0.2794)
			(end 0.12065 0.2794)
			(stroke
				(width 0.1)
				(type default)
			)
			(layer "B.Fab")
		)
		(fp_line
			(start -0.12065 -0.2794)
			(end -0.12065 -0.3048)
			(stroke
				(width 0.1)
				(type default)
			)
			(layer "B.Fab")
		)
		(fp_line
			(start -0.12065 -0.3048)
			(end -0.67945 -0.3048)
			(stroke
				(width 0.1)
				(type default)
			)
			(layer "B.Fab")
		)
		(fp_line
			(start -0.67945 0.3048)
			(end -0.120396 0.3048)
			(stroke
				(width 0.1)
				(type default)
			)
			(layer "B.Fab")
		)
		(fp_line
			(start -0.67945 -0.3048)
			(end -0.67945 0.3048)
			(stroke
				(width 0.1)
				(type default)
			)
			(layer "B.Fab")
		)
		(pad "1" smd circle
			(at 0.40005 0)
			(size 0 0)
			(layers "B.Cu" "B.Mask" "B.Paste")
			(net "IRQ_PCH_SCI_WHEA_R_N")
		)
		(pad "2" smd circle
			(at -0.40005 0)
			(size 0 0)
			(layers "B.Cu" "B.Mask" "B.Paste")
			(net "IRQ_PCH_SCI_WHEA_N")
		)
	)
	(footprint ""
		(layer "B.Cu")
		(at 136.417558 -333.62138 -90)
		(property "Reference" "PC497_P1_8"
			(at 0 0 90)
			(layer "B.SilkS")
			(hide yes)
			(effects
				(font
					(size 1.27 1.27)
				)
				(justify mirror)
			)
		)
		(property "Value" ""
			(at 0 0 90)
			(layer "B.Fab")
			(effects
				(font
					(size 1.27 1.27)
				)
				(justify mirror)
			)
		)
		(duplicate_pad_numbers_are_jumpers no)
		(fp_line
			(start -1.524 0.762)
			(end 1.524 0.762)
			(stroke
				(width 0.1524)
				(type default)
			)
			(layer "B.SilkS")
		)
		(fp_line
			(start 1.524 0.762)
			(end 1.524 -0.762)
			(stroke
				(width 0.1524)
				(type default)
			)
			(layer "B.SilkS")
		)
		(fp_line
			(start -1.524 -0.762)
			(end -1.524 0.762)
			(stroke
				(width 0.1524)
				(type default)
			)
			(layer "B.SilkS")
		)
		(fp_line
			(start 1.524 -0.762)
			(end -1.524 -0.762)
			(stroke
				(width 0.1524)
				(type default)
			)
			(layer "B.SilkS")
		)
		(fp_line
			(start -1.1049 0.724916)
			(end -1.1049 -0.724916)
			(stroke
				(width 0.1)
				(type default)
			)
			(layer "B.Fab")
		)
		(fp_line
			(start 1.1049 0.724916)
			(end -1.1049 0.724916)
			(stroke
				(width 0.1)
				(type default)
			)
			(layer "B.Fab")
		)
		(fp_line
			(start -1.1049 -0.724916)
			(end 1.1049 -0.724916)
			(stroke
				(width 0.1)
				(type default)
			)
			(layer "B.Fab")
		)
		(fp_line
			(start 1.1049 -0.724916)
			(end 1.1049 0.724916)
			(stroke
				(width 0.1)
				(type default)
			)
			(layer "B.Fab")
		)
		(pad "1" smd rect
			(at 0.889 0 270)
			(size 1.016 1.27)
			(layers "B.Cu" "B.Mask" "B.Paste")
			(net "PVCCIN_CPU1")
		)
		(pad "2" smd rect
			(at -0.889 0 270)
			(size 1.016 1.27)
			(layers "B.Cu" "B.Mask" "B.Paste")
			(net "GND")
		)
	)
	(footprint ""
		(layer "B.Cu")
		(at 237.836202 -127.48895 180)
		(property "Reference" "C210"
			(at 0 0 0)
			(layer "B.SilkS")
			(hide yes)
			(effects
				(font
					(size 1.27 1.27)
				)
				(justify mirror)
			)
		)
		(property "Value" ""
			(at 0 0 0)
			(layer "B.Fab")
			(effects
				(font
					(size 1.27 1.27)
				)
				(justify mirror)
			)
		)
		(duplicate_pad_numbers_are_jumpers no)
		(fp_line
			(start 0.7874 0.4064)
			(end 0.7874 -0.4064)
			(stroke
				(width 0.1524)
				(type default)
			)
			(layer "B.SilkS")
		)
		(fp_line
			(start 0.7874 -0.4064)
			(end -0.7874 -0.4064)
			(stroke
				(width 0.1524)
				(type default)
			)
			(layer "B.SilkS")
		)
		(fp_line
			(start -0.7874 0.4064)
			(end 0.7874 0.4064)
			(stroke
				(width 0.1524)
				(type default)
			)
			(layer "B.SilkS")
		)
		(fp_line
			(start -0.7874 -0.4064)
			(end -0.7874 0.4064)
			(stroke
				(width 0.1524)
				(type default)
			)
			(layer "B.SilkS")
		)
		(fp_line
			(start 0.67945 0.3048)
			(end 0.67945 -0.305054)
			(stroke
				(width 0.1)
				(type default)
			)
			(layer "B.Fab")
		)
		(fp_line
			(start 0.67945 -0.305054)
			(end 0.12065 -0.305054)
			(stroke
				(width 0.1)
				(type default)
			)
			(layer "B.Fab")
		)
		(fp_line
			(start 0.12065 0.3048)
			(end 0.67945 0.3048)
			(stroke
				(width 0.1)
				(type default)
			)
			(layer "B.Fab")
		)
		(fp_line
			(start 0.12065 0.2794)
			(end 0.12065 0.3048)
			(stroke
				(width 0.1)
				(type default)
			)
			(layer "B.Fab")
		)
		(fp_line
			(start 0.12065 -0.2794)
			(end -0.12065 -0.2794)
			(stroke
				(width 0.1)
				(type default)
			)
			(layer "B.Fab")
		)
		(fp_line
			(start 0.12065 -0.305054)
			(end 0.12065 -0.2794)
			(stroke
				(width 0.1)
				(type default)
			)
			(layer "B.Fab")
		)
		(fp_line
			(start -0.120396 0.3048)
			(end -0.120396 0.2794)
			(stroke
				(width 0.1)
				(type default)
			)
			(layer "B.Fab")
		)
		(fp_line
			(start -0.120396 0.2794)
			(end 0.12065 0.2794)
			(stroke
				(width 0.1)
				(type default)
			)
			(layer "B.Fab")
		)
		(fp_line
			(start -0.12065 -0.2794)
			(end -0.12065 -0.3048)
			(stroke
				(width 0.1)
				(type default)
			)
			(layer "B.Fab")
		)
		(fp_line
			(start -0.12065 -0.3048)
			(end -0.67945 -0.3048)
			(stroke
				(width 0.1)
				(type default)
			)
			(layer "B.Fab")
		)
		(fp_line
			(start -0.67945 0.3048)
			(end -0.120396 0.3048)
			(stroke
				(width 0.1)
				(type default)
			)
			(layer "B.Fab")
		)
		(fp_line
			(start -0.67945 -0.3048)
			(end -0.67945 0.3048)
			(stroke
				(width 0.1)
				(type default)
			)
			(layer "B.Fab")
		)
		(pad "1" smd circle
			(at 0.40005 0)
			(size 0 0)
			(layers "B.Cu" "B.Mask" "B.Paste")
			(net "P3V3_DB2000_VDDR")
		)
		(pad "2" smd circle
			(at -0.40005 0)
			(size 0 0)
			(layers "B.Cu" "B.Mask" "B.Paste")
			(net "GND")
		)
	)
	(footprint ""
		(layer "B.Cu")
		(at 53.446426 -316.213744)
		(property "Reference" "R3891"
			(at 0 0 0)
			(layer "B.SilkS")
			(hide yes)
			(effects
				(font
					(size 1.27 1.27)
				)
				(justify mirror)
			)
		)
		(property "Value" ""
			(at 0 0 0)
			(layer "B.Fab")
			(effects
				(font
					(size 1.27 1.27)
				)
				(justify mirror)
			)
		)
		(duplicate_pad_numbers_are_jumpers no)
		(fp_line
			(start -0.7874 -0.4064)
			(end -0.7874 0.4064)
			(stroke
				(width 0.1524)
				(type default)
			)
			(layer "B.SilkS")
		)
		(fp_line
			(start -0.7874 0.4064)
			(end 0.7874 0.4064)
			(stroke
				(width 0.1524)
				(type default)
			)
			(layer "B.SilkS")
		)
		(fp_line
			(start 0.7874 -0.4064)
			(end -0.7874 -0.4064)
			(stroke
				(width 0.1524)
				(type default)
			)
			(layer "B.SilkS")
		)
		(fp_line
			(start 0.7874 0.4064)
			(end 0.7874 -0.4064)
			(stroke
				(width 0.1524)
				(type default)
			)
			(layer "B.SilkS")
		)
		(fp_line
			(start -0.67945 -0.3048)
			(end -0.67945 0.3048)
			(stroke
				(width 0.1)
				(type default)
			)
			(layer "B.Fab")
		)
		(fp_line
			(start -0.67945 0.3048)
			(end -0.120396 0.3048)
			(stroke
				(width 0.1)
				(type default)
			)
			(layer "B.Fab")
		)
		(fp_line
			(start -0.12065 -0.3048)
			(end -0.67945 -0.3048)
			(stroke
				(width 0.1)
				(type default)
			)
			(layer "B.Fab")
		)
		(fp_line
			(start -0.12065 -0.2794)
			(end -0.12065 -0.3048)
			(stroke
				(width 0.1)
				(type default)
			)
			(layer "B.Fab")
		)
		(fp_line
			(start -0.120396 0.2794)
			(end 0.12065 0.2794)
			(stroke
				(width 0.1)
				(type default)
			)
			(layer "B.Fab")
		)
		(fp_line
			(start -0.120396 0.3048)
			(end -0.120396 0.2794)
			(stroke
				(width 0.1)
				(type default)
			)
			(layer "B.Fab")
		)
		(fp_line
			(start 0.12065 -0.305054)
			(end 0.12065 -0.2794)
			(stroke
				(width 0.1)
				(type default)
			)
			(layer "B.Fab")
		)
		(fp_line
			(start 0.12065 -0.2794)
			(end -0.12065 -0.2794)
			(stroke
				(width 0.1)
				(type default)
			)
			(layer "B.Fab")
		)
		(fp_line
			(start 0.12065 0.2794)
			(end 0.12065 0.3048)
			(stroke
				(width 0.1)
				(type default)
			)
			(layer "B.Fab")
		)
		(fp_line
			(start 0.12065 0.3048)
			(end 0.67945 0.3048)
			(stroke
				(width 0.1)
				(type default)
			)
			(layer "B.Fab")
		)
		(fp_line
			(start 0.67945 -0.305054)
			(end 0.12065 -0.305054)
			(stroke
				(width 0.1)
				(type default)
			)
			(layer "B.Fab")
		)
		(fp_line
			(start 0.67945 0.3048)
			(end 0.67945 -0.305054)
			(stroke
				(width 0.1)
				(type default)
			)
			(layer "B.Fab")
		)
		(pad "1" smd circle
			(at 0.40005 0 180)
			(size 0 0)
			(layers "B.Cu" "B.Mask" "B.Paste")
			(net "I3C_SPD_DDRABCD_CPU1_LVC1_SCL_R")
		)
		(pad "2" smd circle
			(at -0.40005 0 180)
			(size 0 0)
			(layers "B.Cu" "B.Mask" "B.Paste")
			(net "I3C_SPD_DDRABCD_CPU1_LVC1_SCL")
		)
	)
	(footprint ""
		(layer "B.Cu")
		(at 125.052836 -24.986742 180)
		(property "Reference" "C1096"
			(at 0 0 0)
			(layer "B.SilkS")
			(hide yes)
			(effects
				(font
					(size 1.27 1.27)
				)
				(justify mirror)
			)
		)
		(property "Value" ""
			(at 0 0 0)
			(layer "B.Fab")
			(effects
				(font
					(size 1.27 1.27)
				)
				(justify mirror)
			)
		)
		(duplicate_pad_numbers_are_jumpers no)
		(fp_line
			(start 0.299974 0.150114)
			(end 0.299974 -0.150114)
			(stroke
				(width 0.1)
				(type default)
			)
			(layer "B.Fab")
		)
		(fp_line
			(start 0.299974 -0.150114)
			(end -0.299974 -0.150114)
			(stroke
				(width 0.1)
				(type default)
			)
			(layer "B.Fab")
		)
		(fp_line
			(start -0.299974 0.150114)
			(end 0.299974 0.150114)
			(stroke
				(width 0.1)
				(type default)
			)
			(layer "B.Fab")
		)
		(fp_line
			(start -0.299974 -0.150114)
			(end -0.299974 0.150114)
			(stroke
				(width 0.1)
				(type default)
			)
			(layer "B.Fab")
		)
		(pad "1" smd rect
			(at 0.2667 0)
			(size 0.3048 0.381)
			(layers "B.Cu" "B.Mask" "B.Paste")
			(net "USB3_PCH_TX_DP<4>")
		)
		(pad "2" smd rect
			(at -0.2667 0)
			(size 0.3048 0.381)
			(layers "B.Cu" "B.Mask" "B.Paste")
			(net "USB3_PCH_TX_C_DP<4>")
		)
	)
	(footprint ""
		(layer "B.Cu")
		(at 272.363946 -71.341996)
		(property "Reference" "PC1225"
			(at 0 0 0)
			(layer "B.SilkS")
			(hide yes)
			(effects
				(font
					(size 1.27 1.27)
				)
				(justify mirror)
			)
		)
		(property "Value" ""
			(at 0 0 0)
			(layer "B.Fab")
			(effects
				(font
					(size 1.27 1.27)
				)
				(justify mirror)
			)
		)
		(duplicate_pad_numbers_are_jumpers no)
		(fp_line
			(start -1.524 -0.762)
			(end -1.524 0.762)
			(stroke
				(width 0.1524)
				(type default)
			)
			(layer "B.SilkS")
		)
		(fp_line
			(start -1.524 0.762)
			(end 1.524 0.762)
			(stroke
				(width 0.1524)
				(type default)
			)
			(layer "B.SilkS")
		)
		(fp_line
			(start 1.524 -0.762)
			(end -1.524 -0.762)
			(stroke
				(width 0.1524)
				(type default)
			)
			(layer "B.SilkS")
		)
		(fp_line
			(start 1.524 0.762)
			(end 1.524 -0.762)
			(stroke
				(width 0.1524)
				(type default)
			)
			(layer "B.SilkS")
		)
		(fp_line
			(start -1.1049 -0.724916)
			(end 1.1049 -0.724916)
			(stroke
				(width 0.1)
				(type default)
			)
			(layer "B.Fab")
		)
		(fp_line
			(start -1.1049 0.724916)
			(end -1.1049 -0.724916)
			(stroke
				(width 0.1)
				(type default)
			)
			(layer "B.Fab")
		)
		(fp_line
			(start 1.1049 -0.724916)
			(end 1.1049 0.724916)
			(stroke
				(width 0.1)
				(type default)
			)
			(layer "B.Fab")
		)
		(fp_line
			(start 1.1049 0.724916)
			(end -1.1049 0.724916)
			(stroke
				(width 0.1)
				(type default)
			)
			(layer "B.Fab")
		)
		(pad "1" smd rect
			(at 0.889 0)
			(size 1.016 1.27)
			(layers "B.Cu" "B.Mask" "B.Paste")
			(net "P1V05_PCH_AUX")
		)
		(pad "2" smd rect
			(at -0.889 0)
			(size 1.016 1.27)
			(layers "B.Cu" "B.Mask" "B.Paste")
			(net "GND")
		)
	)
	(footprint ""
		(layer "B.Cu")
		(at 30.163516 -129.000758 180)
		(property "Reference" "PR275"
			(at 0 0 0)
			(layer "B.SilkS")
			(hide yes)
			(effects
				(font
					(size 1.27 1.27)
				)
				(justify mirror)
			)
		)
		(property "Value" ""
			(at 0 0 0)
			(layer "B.Fab")
			(effects
				(font
					(size 1.27 1.27)
				)
				(justify mirror)
			)
		)
		(duplicate_pad_numbers_are_jumpers no)
		(fp_line
			(start 0.7874 0.4064)
			(end 0.7874 -0.4064)
			(stroke
				(width 0.1524)
				(type default)
			)
			(layer "B.SilkS")
		)
		(fp_line
			(start 0.7874 -0.4064)
			(end -0.7874 -0.4064)
			(stroke
				(width 0.1524)
				(type default)
			)
			(layer "B.SilkS")
		)
		(fp_line
			(start -0.7874 0.4064)
			(end 0.7874 0.4064)
			(stroke
				(width 0.1524)
				(type default)
			)
			(layer "B.SilkS")
		)
		(fp_line
			(start -0.7874 -0.4064)
			(end -0.7874 0.4064)
			(stroke
				(width 0.1524)
				(type default)
			)
			(layer "B.SilkS")
		)
		(fp_line
			(start 0.67945 0.3048)
			(end 0.67945 -0.305054)
			(stroke
				(width 0.1)
				(type default)
			)
			(layer "B.Fab")
		)
		(fp_line
			(start 0.67945 -0.305054)
			(end 0.12065 -0.305054)
			(stroke
				(width 0.1)
				(type default)
			)
			(layer "B.Fab")
		)
		(fp_line
			(start 0.12065 0.3048)
			(end 0.67945 0.3048)
			(stroke
				(width 0.1)
				(type default)
			)
			(layer "B.Fab")
		)
		(fp_line
			(start 0.12065 0.2794)
			(end 0.12065 0.3048)
			(stroke
				(width 0.1)
				(type default)
			)
			(layer "B.Fab")
		)
		(fp_line
			(start 0.12065 -0.2794)
			(end -0.12065 -0.2794)
			(stroke
				(width 0.1)
				(type default)
			)
			(layer "B.Fab")
		)
		(fp_line
			(start 0.12065 -0.305054)
			(end 0.12065 -0.2794)
			(stroke
				(width 0.1)
				(type default)
			)
			(layer "B.Fab")
		)
		(fp_line
			(start -0.120396 0.3048)
			(end -0.120396 0.2794)
			(stroke
				(width 0.1)
				(type default)
			)
			(layer "B.Fab")
		)
		(fp_line
			(start -0.120396 0.2794)
			(end 0.12065 0.2794)
			(stroke
				(width 0.1)
				(type default)
			)
			(layer "B.Fab")
		)
		(fp_line
			(start -0.12065 -0.2794)
			(end -0.12065 -0.3048)
			(stroke
				(width 0.1)
				(type default)
			)
			(layer "B.Fab")
		)
		(fp_line
			(start -0.12065 -0.3048)
			(end -0.67945 -0.3048)
			(stroke
				(width 0.1)
				(type default)
			)
			(layer "B.Fab")
		)
		(fp_line
			(start -0.67945 0.3048)
			(end -0.120396 0.3048)
			(stroke
				(width 0.1)
				(type default)
			)
			(layer "B.Fab")
		)
		(fp_line
			(start -0.67945 -0.3048)
			(end -0.67945 0.3048)
			(stroke
				(width 0.1)
				(type default)
			)
			(layer "B.Fab")
		)
		(pad "1" smd circle
			(at 0.40005 0)
			(size 0 0)
			(layers "B.Cu" "B.Mask" "B.Paste")
			(net "PVCCINFAON_CPU1_CSPIN")
		)
		(pad "2" smd circle
			(at -0.40005 0)
			(size 0 0)
			(layers "B.Cu" "B.Mask" "B.Paste")
			(net "GND")
		)
	)
	(footprint ""
		(layer "B.Cu")
		(at 77.90688 -11.267948 -90)
		(property "Reference" "R413"
			(at 0 0 90)
			(layer "B.SilkS")
			(hide yes)
			(effects
				(font
					(size 1.27 1.27)
				)
				(justify mirror)
			)
		)
		(property "Value" ""
			(at 0 0 90)
			(layer "B.Fab")
			(effects
				(font
					(size 1.27 1.27)
				)
				(justify mirror)
			)
		)
		(duplicate_pad_numbers_are_jumpers no)
		(fp_line
			(start -0.7874 0.4064)
			(end 0.7874 0.4064)
			(stroke
				(width 0.1524)
				(type default)
			)
			(layer "B.SilkS")
		)
		(fp_line
			(start 0.7874 0.4064)
			(end 0.7874 -0.4064)
			(stroke
				(width 0.1524)
				(type default)
			)
			(layer "B.SilkS")
		)
		(fp_line
			(start -0.7874 -0.4064)
			(end -0.7874 0.4064)
			(stroke
				(width 0.1524)
				(type default)
			)
			(layer "B.SilkS")
		)
		(fp_line
			(start 0.7874 -0.4064)
			(end -0.7874 -0.4064)
			(stroke
				(width 0.1524)
				(type default)
			)
			(layer "B.SilkS")
		)
		(fp_line
			(start -0.67945 0.3048)
			(end -0.120396 0.3048)
			(stroke
				(width 0.1)
				(type default)
			)
			(layer "B.Fab")
		)
		(fp_line
			(start -0.120396 0.3048)
			(end -0.120396 0.2794)
			(stroke
				(width 0.1)
				(type default)
			)
			(layer "B.Fab")
		)
		(fp_line
			(start 0.12065 0.3048)
			(end 0.67945 0.3048)
			(stroke
				(width 0.1)
				(type default)
			)
			(layer "B.Fab")
		)
		(fp_line
			(start 0.67945 0.3048)
			(end 0.67945 -0.305054)
			(stroke
				(width 0.1)
				(type default)
			)
			(layer "B.Fab")
		)
		(fp_line
			(start -0.120396 0.2794)
			(end 0.12065 0.2794)
			(stroke
				(width 0.1)
				(type default)
			)
			(layer "B.Fab")
		)
		(fp_line
			(start 0.12065 0.2794)
			(end 0.12065 0.3048)
			(stroke
				(width 0.1)
				(type default)
			)
			(layer "B.Fab")
		)
		(fp_line
			(start -0.12065 -0.2794)
			(end -0.12065 -0.3048)
			(stroke
				(width 0.1)
				(type default)
			)
			(layer "B.Fab")
		)
		(fp_line
			(start 0.12065 -0.2794)
			(end -0.12065 -0.2794)
			(stroke
				(width 0.1)
				(type default)
			)
			(layer "B.Fab")
		)
		(fp_line
			(start -0.67945 -0.3048)
			(end -0.67945 0.3048)
			(stroke
				(width 0.1)
				(type default)
			)
			(layer "B.Fab")
		)
		(fp_line
			(start -0.12065 -0.3048)
			(end -0.67945 -0.3048)
			(stroke
				(width 0.1)
				(type default)
			)
			(layer "B.Fab")
		)
		(fp_line
			(start 0.12065 -0.305054)
			(end 0.12065 -0.2794)
			(stroke
				(width 0.1)
				(type default)
			)
			(layer "B.Fab")
		)
		(fp_line
			(start 0.67945 -0.305054)
			(end 0.12065 -0.305054)
			(stroke
				(width 0.1)
				(type default)
			)
			(layer "B.Fab")
		)
		(pad "1" smd circle
			(at 0.40005 0 90)
			(size 0 0)
			(layers "B.Cu" "B.Mask" "B.Paste")
			(net "GND")
		)
		(pad "2" smd circle
			(at -0.40005 0 90)
			(size 0 0)
			(layers "B.Cu" "B.Mask" "B.Paste")
			(net "FM_OCP_V3_2_PWR_GOOD")
		)
	)
	(footprint ""
		(layer "B.Cu")
		(at 188.190886 -193.599816 -90)
		(property "Reference" "R704"
			(at 0 0 90)
			(layer "B.SilkS")
			(hide yes)
			(effects
				(font
					(size 1.27 1.27)
				)
				(justify mirror)
			)
		)
		(property "Value" ""
			(at 0 0 90)
			(layer "B.Fab")
			(effects
				(font
					(size 1.27 1.27)
				)
				(justify mirror)
			)
		)
		(duplicate_pad_numbers_are_jumpers no)
		(fp_line
			(start -0.7874 0.4064)
			(end 0.7874 0.4064)
			(stroke
				(width 0.1524)
				(type default)
			)
			(layer "B.SilkS")
		)
		(fp_line
			(start 0.7874 0.4064)
			(end 0.7874 -0.4064)
			(stroke
				(width 0.1524)
				(type default)
			)
			(layer "B.SilkS")
		)
		(fp_line
			(start -0.7874 -0.4064)
			(end -0.7874 0.4064)
			(stroke
				(width 0.1524)
				(type default)
			)
			(layer "B.SilkS")
		)
		(fp_line
			(start 0.7874 -0.4064)
			(end -0.7874 -0.4064)
			(stroke
				(width 0.1524)
				(type default)
			)
			(layer "B.SilkS")
		)
		(fp_line
			(start -0.67945 0.3048)
			(end -0.120396 0.3048)
			(stroke
				(width 0.1)
				(type default)
			)
			(layer "B.Fab")
		)
		(fp_line
			(start -0.120396 0.3048)
			(end -0.120396 0.2794)
			(stroke
				(width 0.1)
				(type default)
			)
			(layer "B.Fab")
		)
		(fp_line
			(start 0.12065 0.3048)
			(end 0.67945 0.3048)
			(stroke
				(width 0.1)
				(type default)
			)
			(layer "B.Fab")
		)
		(fp_line
			(start 0.67945 0.3048)
			(end 0.67945 -0.305054)
			(stroke
				(width 0.1)
				(type default)
			)
			(layer "B.Fab")
		)
		(fp_line
			(start -0.120396 0.2794)
			(end 0.12065 0.2794)
			(stroke
				(width 0.1)
				(type default)
			)
			(layer "B.Fab")
		)
		(fp_line
			(start 0.12065 0.2794)
			(end 0.12065 0.3048)
			(stroke
				(width 0.1)
				(type default)
			)
			(layer "B.Fab")
		)
		(fp_line
			(start -0.12065 -0.2794)
			(end -0.12065 -0.3048)
			(stroke
				(width 0.1)
				(type default)
			)
			(layer "B.Fab")
		)
		(fp_line
			(start 0.12065 -0.2794)
			(end -0.12065 -0.2794)
			(stroke
				(width 0.1)
				(type default)
			)
			(layer "B.Fab")
		)
		(fp_line
			(start -0.67945 -0.3048)
			(end -0.67945 0.3048)
			(stroke
				(width 0.1)
				(type default)
			)
			(layer "B.Fab")
		)
		(fp_line
			(start -0.12065 -0.3048)
			(end -0.67945 -0.3048)
			(stroke
				(width 0.1)
				(type default)
			)
			(layer "B.Fab")
		)
		(fp_line
			(start 0.12065 -0.305054)
			(end 0.12065 -0.2794)
			(stroke
				(width 0.1)
				(type default)
			)
			(layer "B.Fab")
		)
		(fp_line
			(start 0.67945 -0.305054)
			(end 0.12065 -0.305054)
			(stroke
				(width 0.1)
				(type default)
			)
			(layer "B.Fab")
		)
		(pad "1" smd circle
			(at 0.40005 0 90)
			(size 0 0)
			(layers "B.Cu" "B.Mask" "B.Paste")
			(net "RST_PLD_CPU1_DRAM_EF_N")
		)
		(pad "2" smd circle
			(at -0.40005 0 90)
			(size 0 0)
			(layers "B.Cu" "B.Mask" "B.Paste")
			(net "GND")
		)
	)
	(footprint ""
		(layer "B.Cu")
		(at 376.83694 -130.90906)
		(property "Reference" "ME14"
			(at 9.652 -9.540748 0)
			(unlocked yes)
			(layer "B.SilkS")
			(effects
				(font
					(size 0.7874 0.5842)
					(thickness 0.1524)
				)
				(justify left mirror)
			)
		)
		(property "Value" ""
			(at 0 0 0)
			(layer "B.Fab")
			(effects
				(font
					(size 1.27 1.27)
				)
				(justify mirror)
			)
		)
		(duplicate_pad_numbers_are_jumpers no)
		(zone
			(layer "B.Cu")
			(hatch none 0.5)
			(connect_pads
				(clearance 0)
			)
			(min_thickness 0.25)
			(keepout
				(tracks allowed)
				(vias allowed)
				(pads allowed)
				(copperpour allowed)
				(footprints not_allowed)
			)
			(placement
				(enabled no)
				(sheetname "")
			)
			(fill
				(thermal_gap 0.5)
				(thermal_bridge_width 0.5)
				(island_removal_mode 0)
			)
			(polygon
				(pts
					(arc
						(start 386.83692 -130.90906)
						(mid 366.83696 -130.90906)
						(end 386.83692 -130.90906)
					)
				)
			)
		)
	)
	(footprint ""
		(layer "B.Cu")
		(at 175.469804 -344.941906 -90)
		(property "Reference" "PC412_P1_1"
			(at 0 0 90)
			(layer "B.SilkS")
			(hide yes)
			(effects
				(font
					(size 1.27 1.27)
				)
				(justify mirror)
			)
		)
		(property "Value" ""
			(at 0 0 90)
			(layer "B.Fab")
			(effects
				(font
					(size 1.27 1.27)
				)
				(justify mirror)
			)
		)
		(duplicate_pad_numbers_are_jumpers no)
		(fp_line
			(start -1.524 0.762)
			(end 1.524 0.762)
			(stroke
				(width 0.1524)
				(type default)
			)
			(layer "B.SilkS")
		)
		(fp_line
			(start 1.524 0.762)
			(end 1.524 -0.762)
			(stroke
				(width 0.1524)
				(type default)
			)
			(layer "B.SilkS")
		)
		(fp_line
			(start -1.524 -0.762)
			(end -1.524 0.762)
			(stroke
				(width 0.1524)
				(type default)
			)
			(layer "B.SilkS")
		)
		(fp_line
			(start 1.524 -0.762)
			(end -1.524 -0.762)
			(stroke
				(width 0.1524)
				(type default)
			)
			(layer "B.SilkS")
		)
		(fp_line
			(start -1.1049 0.724916)
			(end -1.1049 -0.724916)
			(stroke
				(width 0.1)
				(type default)
			)
			(layer "B.Fab")
		)
		(fp_line
			(start 1.1049 0.724916)
			(end -1.1049 0.724916)
			(stroke
				(width 0.1)
				(type default)
			)
			(layer "B.Fab")
		)
		(fp_line
			(start -1.1049 -0.724916)
			(end 1.1049 -0.724916)
			(stroke
				(width 0.1)
				(type default)
			)
			(layer "B.Fab")
		)
		(fp_line
			(start 1.1049 -0.724916)
			(end 1.1049 0.724916)
			(stroke
				(width 0.1)
				(type default)
			)
			(layer "B.Fab")
		)
		(pad "1" smd rect
			(at 0.889 0 270)
			(size 1.016 1.27)
			(layers "B.Cu" "B.Mask" "B.Paste")
			(net "PVCCFA_EHV_FIVRA_CPU1")
		)
		(pad "2" smd rect
			(at -0.889 0 270)
			(size 1.016 1.27)
			(layers "B.Cu" "B.Mask" "B.Paste")
			(net "GND")
		)
	)
	(footprint ""
		(layer "B.Cu")
		(at 239.091724 -97.084642 180)
		(property "Reference" "L13"
			(at 0 0 0)
			(layer "B.SilkS")
			(hide yes)
			(effects
				(font
					(size 1.27 1.27)
				)
				(justify mirror)
			)
		)
		(property "Value" ""
			(at 0 0 0)
			(layer "B.Fab")
			(effects
				(font
					(size 1.27 1.27)
				)
				(justify mirror)
			)
		)
		(duplicate_pad_numbers_are_jumpers no)
		(fp_line
			(start 1.63576 -0.8128)
			(end 1.63576 0.8128)
			(stroke
				(width 0.1524)
				(type default)
			)
			(layer "B.SilkS")
		)
		(fp_line
			(start 1.63576 -0.8128)
			(end -1.63576 -0.8128)
			(stroke
				(width 0.1524)
				(type default)
			)
			(layer "B.SilkS")
		)
		(fp_line
			(start -1.63576 0.8128)
			(end 1.63576 0.8128)
			(stroke
				(width 0.1524)
				(type default)
			)
			(layer "B.SilkS")
		)
		(fp_line
			(start -1.63576 -0.8128)
			(end -1.63576 0.8128)
			(stroke
				(width 0.1524)
				(type default)
			)
			(layer "B.SilkS")
		)
		(fp_line
			(start 1.56083 0.7366)
			(end 1.524 0.7366)
			(stroke
				(width 0.1)
				(type default)
			)
			(layer "B.Fab")
		)
		(fp_line
			(start 1.56083 -0.738632)
			(end 1.56083 0.7366)
			(stroke
				(width 0.1)
				(type default)
			)
			(layer "B.Fab")
		)
		(fp_line
			(start 1.524 0.7366)
			(end -1.524 0.7366)
			(stroke
				(width 0.1)
				(type default)
			)
			(layer "B.Fab")
		)
		(fp_line
			(start -1.524 0.7366)
			(end -1.560576 0.7366)
			(stroke
				(width 0.1)
				(type default)
			)
			(layer "B.Fab")
		)
		(fp_line
			(start -1.560576 0.7366)
			(end -1.560576 -0.738632)
			(stroke
				(width 0.1)
				(type default)
			)
			(layer "B.Fab")
		)
		(fp_line
			(start -1.560576 -0.738632)
			(end 1.56083 -0.738632)
			(stroke
				(width 0.1)
				(type default)
			)
			(layer "B.Fab")
		)
		(pad "1" smd rect
			(at 0.94996 0 180)
			(size 1.1176 1.3716)
			(layers "B.Cu" "B.Mask" "B.Paste")
			(net "P3V3_AUX")
		)
		(pad "2" smd rect
			(at -0.94996 0 180)
			(size 1.1176 1.3716)
			(layers "B.Cu" "B.Mask" "B.Paste")
			(net "P3V3_AUX_CLK_GEN_VDDXTAL_CK440")
		)
	)
	(footprint ""
		(layer "B.Cu")
		(at 363.2962 -356.094792)
		(property "Reference" "R2589"
			(at 0 0 0)
			(layer "B.SilkS")
			(hide yes)
			(effects
				(font
					(size 1.27 1.27)
				)
				(justify mirror)
			)
		)
		(property "Value" ""
			(at 0 0 0)
			(layer "B.Fab")
			(effects
				(font
					(size 1.27 1.27)
				)
				(justify mirror)
			)
		)
		(duplicate_pad_numbers_are_jumpers no)
		(fp_line
			(start -0.7874 -0.4064)
			(end -0.7874 0.4064)
			(stroke
				(width 0.1524)
				(type default)
			)
			(layer "B.SilkS")
		)
		(fp_line
			(start -0.7874 0.4064)
			(end 0.7874 0.4064)
			(stroke
				(width 0.1524)
				(type default)
			)
			(layer "B.SilkS")
		)
		(fp_line
			(start 0.7874 -0.4064)
			(end -0.7874 -0.4064)
			(stroke
				(width 0.1524)
				(type default)
			)
			(layer "B.SilkS")
		)
		(fp_line
			(start 0.7874 0.4064)
			(end 0.7874 -0.4064)
			(stroke
				(width 0.1524)
				(type default)
			)
			(layer "B.SilkS")
		)
		(fp_line
			(start -0.67945 -0.3048)
			(end -0.67945 0.3048)
			(stroke
				(width 0.1)
				(type default)
			)
			(layer "B.Fab")
		)
		(fp_line
			(start -0.67945 0.3048)
			(end -0.120396 0.3048)
			(stroke
				(width 0.1)
				(type default)
			)
			(layer "B.Fab")
		)
		(fp_line
			(start -0.12065 -0.3048)
			(end -0.67945 -0.3048)
			(stroke
				(width 0.1)
				(type default)
			)
			(layer "B.Fab")
		)
		(fp_line
			(start -0.12065 -0.2794)
			(end -0.12065 -0.3048)
			(stroke
				(width 0.1)
				(type default)
			)
			(layer "B.Fab")
		)
		(fp_line
			(start -0.120396 0.2794)
			(end 0.12065 0.2794)
			(stroke
				(width 0.1)
				(type default)
			)
			(layer "B.Fab")
		)
		(fp_line
			(start -0.120396 0.3048)
			(end -0.120396 0.2794)
			(stroke
				(width 0.1)
				(type default)
			)
			(layer "B.Fab")
		)
		(fp_line
			(start 0.12065 -0.305054)
			(end 0.12065 -0.2794)
			(stroke
				(width 0.1)
				(type default)
			)
			(layer "B.Fab")
		)
		(fp_line
			(start 0.12065 -0.2794)
			(end -0.12065 -0.2794)
			(stroke
				(width 0.1)
				(type default)
			)
			(layer "B.Fab")
		)
		(fp_line
			(start 0.12065 0.2794)
			(end 0.12065 0.3048)
			(stroke
				(width 0.1)
				(type default)
			)
			(layer "B.Fab")
		)
		(fp_line
			(start 0.12065 0.3048)
			(end 0.67945 0.3048)
			(stroke
				(width 0.1)
				(type default)
			)
			(layer "B.Fab")
		)
		(fp_line
			(start 0.67945 -0.305054)
			(end 0.12065 -0.305054)
			(stroke
				(width 0.1)
				(type default)
			)
			(layer "B.Fab")
		)
		(fp_line
			(start 0.67945 0.3048)
			(end 0.67945 -0.305054)
			(stroke
				(width 0.1)
				(type default)
			)
			(layer "B.Fab")
		)
		(pad "1" smd circle
			(at 0.40005 0 180)
			(size 0 0)
			(layers "B.Cu" "B.Mask" "B.Paste")
			(net "P3V3_AUX")
		)
		(pad "2" smd circle
			(at -0.40005 0 180)
			(size 0 0)
			(layers "B.Cu" "B.Mask" "B.Paste")
			(net "PVCCIN_CPU0_VR_FAULT")
		)
	)
	(footprint ""
		(layer "B.Cu")
		(at 139.021058 -347.008704 -90)
		(property "Reference" "PC491_P1_8"
			(at 0 0 90)
			(layer "B.SilkS")
			(hide yes)
			(effects
				(font
					(size 1.27 1.27)
				)
				(justify mirror)
			)
		)
		(property "Value" ""
			(at 0 0 90)
			(layer "B.Fab")
			(effects
				(font
					(size 1.27 1.27)
				)
				(justify mirror)
			)
		)
		(duplicate_pad_numbers_are_jumpers no)
		(fp_line
			(start -1.524 0.762)
			(end 1.524 0.762)
			(stroke
				(width 0.1524)
				(type default)
			)
			(layer "B.SilkS")
		)
		(fp_line
			(start 1.524 0.762)
			(end 1.524 -0.762)
			(stroke
				(width 0.1524)
				(type default)
			)
			(layer "B.SilkS")
		)
		(fp_line
			(start -1.524 -0.762)
			(end -1.524 0.762)
			(stroke
				(width 0.1524)
				(type default)
			)
			(layer "B.SilkS")
		)
		(fp_line
			(start 1.524 -0.762)
			(end -1.524 -0.762)
			(stroke
				(width 0.1524)
				(type default)
			)
			(layer "B.SilkS")
		)
		(fp_line
			(start -1.1049 0.724916)
			(end -1.1049 -0.724916)
			(stroke
				(width 0.1)
				(type default)
			)
			(layer "B.Fab")
		)
		(fp_line
			(start 1.1049 0.724916)
			(end -1.1049 0.724916)
			(stroke
				(width 0.1)
				(type default)
			)
			(layer "B.Fab")
		)
		(fp_line
			(start -1.1049 -0.724916)
			(end 1.1049 -0.724916)
			(stroke
				(width 0.1)
				(type default)
			)
			(layer "B.Fab")
		)
		(fp_line
			(start 1.1049 -0.724916)
			(end 1.1049 0.724916)
			(stroke
				(width 0.1)
				(type default)
			)
			(layer "B.Fab")
		)
		(pad "1" smd rect
			(at 0.889 0 270)
			(size 1.016 1.27)
			(layers "B.Cu" "B.Mask" "B.Paste")
			(net "SW_P12V_PVCCIN_CPU1_FLT")
		)
		(pad "2" smd rect
			(at -0.889 0 270)
			(size 1.016 1.27)
			(layers "B.Cu" "B.Mask" "B.Paste")
			(net "GND")
		)
	)
	(footprint ""
		(layer "B.Cu")
		(at 118.158006 -212.049868)
		(property "Reference" "C481"
			(at 0 0 0)
			(layer "B.SilkS")
			(hide yes)
			(effects
				(font
					(size 1.27 1.27)
				)
				(justify mirror)
			)
		)
		(property "Value" ""
			(at 0 0 0)
			(layer "B.Fab")
			(effects
				(font
					(size 1.27 1.27)
				)
				(justify mirror)
			)
		)
		(duplicate_pad_numbers_are_jumpers no)
		(fp_line
			(start -1.524 -0.762)
			(end -1.524 0.762)
			(stroke
				(width 0.1524)
				(type default)
			)
			(layer "B.SilkS")
		)
		(fp_line
			(start -1.524 0.762)
			(end 1.524 0.762)
			(stroke
				(width 0.1524)
				(type default)
			)
			(layer "B.SilkS")
		)
		(fp_line
			(start 1.524 -0.762)
			(end -1.524 -0.762)
			(stroke
				(width 0.1524)
				(type default)
			)
			(layer "B.SilkS")
		)
		(fp_line
			(start 1.524 0.762)
			(end 1.524 -0.762)
			(stroke
				(width 0.1524)
				(type default)
			)
			(layer "B.SilkS")
		)
		(fp_line
			(start -1.1049 -0.724916)
			(end 1.1049 -0.724916)
			(stroke
				(width 0.1)
				(type default)
			)
			(layer "B.Fab")
		)
		(fp_line
			(start -1.1049 0.724916)
			(end -1.1049 -0.724916)
			(stroke
				(width 0.1)
				(type default)
			)
			(layer "B.Fab")
		)
		(fp_line
			(start 1.1049 -0.724916)
			(end 1.1049 0.724916)
			(stroke
				(width 0.1)
				(type default)
			)
			(layer "B.Fab")
		)
		(fp_line
			(start 1.1049 0.724916)
			(end -1.1049 0.724916)
			(stroke
				(width 0.1)
				(type default)
			)
			(layer "B.Fab")
		)
		(pad "1" smd rect
			(at 0.889 0)
			(size 1.016 1.27)
			(layers "B.Cu" "B.Mask" "B.Paste")
			(net "PVCCINFAON_CPU1")
		)
		(pad "2" smd rect
			(at -0.889 0)
			(size 1.016 1.27)
			(layers "B.Cu" "B.Mask" "B.Paste")
			(net "GND")
		)
	)
	(footprint ""
		(layer "B.Cu")
		(at 404.09241 -193.05143 -90)
		(property "Reference" "R1233"
			(at 0 0 90)
			(layer "B.SilkS")
			(hide yes)
			(effects
				(font
					(size 1.27 1.27)
				)
				(justify mirror)
			)
		)
		(property "Value" ""
			(at 0 0 90)
			(layer "B.Fab")
			(effects
				(font
					(size 1.27 1.27)
				)
				(justify mirror)
			)
		)
		(duplicate_pad_numbers_are_jumpers no)
		(fp_line
			(start -0.7874 0.4064)
			(end 0.7874 0.4064)
			(stroke
				(width 0.1524)
				(type default)
			)
			(layer "B.SilkS")
		)
		(fp_line
			(start 0.7874 0.4064)
			(end 0.7874 -0.4064)
			(stroke
				(width 0.1524)
				(type default)
			)
			(layer "B.SilkS")
		)
		(fp_line
			(start -0.7874 -0.4064)
			(end -0.7874 0.4064)
			(stroke
				(width 0.1524)
				(type default)
			)
			(layer "B.SilkS")
		)
		(fp_line
			(start 0.7874 -0.4064)
			(end -0.7874 -0.4064)
			(stroke
				(width 0.1524)
				(type default)
			)
			(layer "B.SilkS")
		)
		(fp_line
			(start -0.67945 0.3048)
			(end -0.120396 0.3048)
			(stroke
				(width 0.1)
				(type default)
			)
			(layer "B.Fab")
		)
		(fp_line
			(start -0.120396 0.3048)
			(end -0.120396 0.2794)
			(stroke
				(width 0.1)
				(type default)
			)
			(layer "B.Fab")
		)
		(fp_line
			(start 0.12065 0.3048)
			(end 0.67945 0.3048)
			(stroke
				(width 0.1)
				(type default)
			)
			(layer "B.Fab")
		)
		(fp_line
			(start 0.67945 0.3048)
			(end 0.67945 -0.305054)
			(stroke
				(width 0.1)
				(type default)
			)
			(layer "B.Fab")
		)
		(fp_line
			(start -0.120396 0.2794)
			(end 0.12065 0.2794)
			(stroke
				(width 0.1)
				(type default)
			)
			(layer "B.Fab")
		)
		(fp_line
			(start 0.12065 0.2794)
			(end 0.12065 0.3048)
			(stroke
				(width 0.1)
				(type default)
			)
			(layer "B.Fab")
		)
		(fp_line
			(start -0.12065 -0.2794)
			(end -0.12065 -0.3048)
			(stroke
				(width 0.1)
				(type default)
			)
			(layer "B.Fab")
		)
		(fp_line
			(start 0.12065 -0.2794)
			(end -0.12065 -0.2794)
			(stroke
				(width 0.1)
				(type default)
			)
			(layer "B.Fab")
		)
		(fp_line
			(start -0.67945 -0.3048)
			(end -0.67945 0.3048)
			(stroke
				(width 0.1)
				(type default)
			)
			(layer "B.Fab")
		)
		(fp_line
			(start -0.12065 -0.3048)
			(end -0.67945 -0.3048)
			(stroke
				(width 0.1)
				(type default)
			)
			(layer "B.Fab")
		)
		(fp_line
			(start 0.12065 -0.305054)
			(end 0.12065 -0.2794)
			(stroke
				(width 0.1)
				(type default)
			)
			(layer "B.Fab")
		)
		(fp_line
			(start 0.67945 -0.305054)
			(end 0.12065 -0.305054)
			(stroke
				(width 0.1)
				(type default)
			)
			(layer "B.Fab")
		)
		(pad "1" smd circle
			(at 0.40005 0 90)
			(size 0 0)
			(layers "B.Cu" "B.Mask" "B.Paste")
			(net "PVNN_TERM_CPU0")
		)
		(pad "2" smd circle
			(at -0.40005 0 90)
			(size 0 0)
			(layers "B.Cu" "B.Mask" "B.Paste")
			(net "PUD_XTAL_CPU0_MODE1")
		)
	)
	(footprint ""
		(layer "B.Cu")
		(at 76.463652 -181.65699 -90)
		(property "Reference" "R758"
			(at 0 0 90)
			(layer "B.SilkS")
			(hide yes)
			(effects
				(font
					(size 1.27 1.27)
				)
				(justify mirror)
			)
		)
		(property "Value" ""
			(at 0 0 90)
			(layer "B.Fab")
			(effects
				(font
					(size 1.27 1.27)
				)
				(justify mirror)
			)
		)
		(duplicate_pad_numbers_are_jumpers no)
		(fp_line
			(start -0.7874 0.4064)
			(end 0.7874 0.4064)
			(stroke
				(width 0.1524)
				(type default)
			)
			(layer "B.SilkS")
		)
		(fp_line
			(start 0.7874 0.4064)
			(end 0.7874 -0.4064)
			(stroke
				(width 0.1524)
				(type default)
			)
			(layer "B.SilkS")
		)
		(fp_line
			(start -0.7874 -0.4064)
			(end -0.7874 0.4064)
			(stroke
				(width 0.1524)
				(type default)
			)
			(layer "B.SilkS")
		)
		(fp_line
			(start 0.7874 -0.4064)
			(end -0.7874 -0.4064)
			(stroke
				(width 0.1524)
				(type default)
			)
			(layer "B.SilkS")
		)
		(fp_line
			(start -0.67945 0.3048)
			(end -0.120396 0.3048)
			(stroke
				(width 0.1)
				(type default)
			)
			(layer "B.Fab")
		)
		(fp_line
			(start -0.120396 0.3048)
			(end -0.120396 0.2794)
			(stroke
				(width 0.1)
				(type default)
			)
			(layer "B.Fab")
		)
		(fp_line
			(start 0.12065 0.3048)
			(end 0.67945 0.3048)
			(stroke
				(width 0.1)
				(type default)
			)
			(layer "B.Fab")
		)
		(fp_line
			(start 0.67945 0.3048)
			(end 0.67945 -0.305054)
			(stroke
				(width 0.1)
				(type default)
			)
			(layer "B.Fab")
		)
		(fp_line
			(start -0.120396 0.2794)
			(end 0.12065 0.2794)
			(stroke
				(width 0.1)
				(type default)
			)
			(layer "B.Fab")
		)
		(fp_line
			(start 0.12065 0.2794)
			(end 0.12065 0.3048)
			(stroke
				(width 0.1)
				(type default)
			)
			(layer "B.Fab")
		)
		(fp_line
			(start -0.12065 -0.2794)
			(end -0.12065 -0.3048)
			(stroke
				(width 0.1)
				(type default)
			)
			(layer "B.Fab")
		)
		(fp_line
			(start 0.12065 -0.2794)
			(end -0.12065 -0.2794)
			(stroke
				(width 0.1)
				(type default)
			)
			(layer "B.Fab")
		)
		(fp_line
			(start -0.67945 -0.3048)
			(end -0.67945 0.3048)
			(stroke
				(width 0.1)
				(type default)
			)
			(layer "B.Fab")
		)
		(fp_line
			(start -0.12065 -0.3048)
			(end -0.67945 -0.3048)
			(stroke
				(width 0.1)
				(type default)
			)
			(layer "B.Fab")
		)
		(fp_line
			(start 0.12065 -0.305054)
			(end 0.12065 -0.2794)
			(stroke
				(width 0.1)
				(type default)
			)
			(layer "B.Fab")
		)
		(fp_line
			(start 0.67945 -0.305054)
			(end 0.12065 -0.305054)
			(stroke
				(width 0.1)
				(type default)
			)
			(layer "B.Fab")
		)
		(pad "1" smd circle
			(at 0.40005 0 90)
			(size 0 0)
			(layers "B.Cu" "B.Mask" "B.Paste")
			(net "PVNN_TERM_CPU0")
		)
		(pad "2" smd circle
			(at -0.40005 0 90)
			(size 0 0)
			(layers "B.Cu" "B.Mask" "B.Paste")
			(net "H_CPU_PREQ_QS_GTL_N")
		)
	)
	(footprint ""
		(layer "B.Cu")
		(at 233.9086 -250.505468 180)
		(property "Reference" "C2259"
			(at 0 0 0)
			(layer "B.SilkS")
			(hide yes)
			(effects
				(font
					(size 1.27 1.27)
				)
				(justify mirror)
			)
		)
		(property "Value" ""
			(at 0 0 0)
			(layer "B.Fab")
			(effects
				(font
					(size 1.27 1.27)
				)
				(justify mirror)
			)
		)
		(duplicate_pad_numbers_are_jumpers no)
		(fp_line
			(start 0.7874 0.4064)
			(end 0.7874 -0.4064)
			(stroke
				(width 0.1524)
				(type default)
			)
			(layer "B.SilkS")
		)
		(fp_line
			(start 0.7874 -0.4064)
			(end -0.7874 -0.4064)
			(stroke
				(width 0.1524)
				(type default)
			)
			(layer "B.SilkS")
		)
		(fp_line
			(start -0.7874 0.4064)
			(end 0.7874 0.4064)
			(stroke
				(width 0.1524)
				(type default)
			)
			(layer "B.SilkS")
		)
		(fp_line
			(start -0.7874 -0.4064)
			(end -0.7874 0.4064)
			(stroke
				(width 0.1524)
				(type default)
			)
			(layer "B.SilkS")
		)
		(fp_line
			(start 0.67945 0.3048)
			(end 0.67945 -0.305054)
			(stroke
				(width 0.1)
				(type default)
			)
			(layer "B.Fab")
		)
		(fp_line
			(start 0.67945 -0.305054)
			(end 0.12065 -0.305054)
			(stroke
				(width 0.1)
				(type default)
			)
			(layer "B.Fab")
		)
		(fp_line
			(start 0.12065 0.3048)
			(end 0.67945 0.3048)
			(stroke
				(width 0.1)
				(type default)
			)
			(layer "B.Fab")
		)
		(fp_line
			(start 0.12065 0.2794)
			(end 0.12065 0.3048)
			(stroke
				(width 0.1)
				(type default)
			)
			(layer "B.Fab")
		)
		(fp_line
			(start 0.12065 -0.2794)
			(end -0.12065 -0.2794)
			(stroke
				(width 0.1)
				(type default)
			)
			(layer "B.Fab")
		)
		(fp_line
			(start 0.12065 -0.305054)
			(end 0.12065 -0.2794)
			(stroke
				(width 0.1)
				(type default)
			)
			(layer "B.Fab")
		)
		(fp_line
			(start -0.120396 0.3048)
			(end -0.120396 0.2794)
			(stroke
				(width 0.1)
				(type default)
			)
			(layer "B.Fab")
		)
		(fp_line
			(start -0.120396 0.2794)
			(end 0.12065 0.2794)
			(stroke
				(width 0.1)
				(type default)
			)
			(layer "B.Fab")
		)
		(fp_line
			(start -0.12065 -0.2794)
			(end -0.12065 -0.3048)
			(stroke
				(width 0.1)
				(type default)
			)
			(layer "B.Fab")
		)
		(fp_line
			(start -0.12065 -0.3048)
			(end -0.67945 -0.3048)
			(stroke
				(width 0.1)
				(type default)
			)
			(layer "B.Fab")
		)
		(fp_line
			(start -0.67945 0.3048)
			(end -0.120396 0.3048)
			(stroke
				(width 0.1)
				(type default)
			)
			(layer "B.Fab")
		)
		(fp_line
			(start -0.67945 -0.3048)
			(end -0.67945 0.3048)
			(stroke
				(width 0.1)
				(type default)
			)
			(layer "B.Fab")
		)
		(pad "1" smd circle
			(at 0.40005 0)
			(size 0 0)
			(layers "B.Cu" "B.Mask" "B.Paste")
			(net "VFG_3P3A_CLK_GEN")
		)
		(pad "2" smd circle
			(at -0.40005 0)
			(size 0 0)
			(layers "B.Cu" "B.Mask" "B.Paste")
			(net "GND")
		)
	)
	(footprint ""
		(layer "B.Cu")
		(at 401.828 -192.623948 -90)
		(property "Reference" "R4297"
			(at 0 0 90)
			(layer "B.SilkS")
			(hide yes)
			(effects
				(font
					(size 1.27 1.27)
				)
				(justify mirror)
			)
		)
		(property "Value" ""
			(at 0 0 90)
			(layer "B.Fab")
			(effects
				(font
					(size 1.27 1.27)
				)
				(justify mirror)
			)
		)
		(duplicate_pad_numbers_are_jumpers no)
		(fp_line
			(start -0.7874 0.4064)
			(end 0.7874 0.4064)
			(stroke
				(width 0.1524)
				(type default)
			)
			(layer "B.SilkS")
		)
		(fp_line
			(start 0.7874 0.4064)
			(end 0.7874 -0.4064)
			(stroke
				(width 0.1524)
				(type default)
			)
			(layer "B.SilkS")
		)
		(fp_line
			(start -0.7874 -0.4064)
			(end -0.7874 0.4064)
			(stroke
				(width 0.1524)
				(type default)
			)
			(layer "B.SilkS")
		)
		(fp_line
			(start 0.7874 -0.4064)
			(end -0.7874 -0.4064)
			(stroke
				(width 0.1524)
				(type default)
			)
			(layer "B.SilkS")
		)
		(fp_line
			(start -0.67945 0.3048)
			(end -0.120396 0.3048)
			(stroke
				(width 0.1)
				(type default)
			)
			(layer "B.Fab")
		)
		(fp_line
			(start -0.120396 0.3048)
			(end -0.120396 0.2794)
			(stroke
				(width 0.1)
				(type default)
			)
			(layer "B.Fab")
		)
		(fp_line
			(start 0.12065 0.3048)
			(end 0.67945 0.3048)
			(stroke
				(width 0.1)
				(type default)
			)
			(layer "B.Fab")
		)
		(fp_line
			(start 0.67945 0.3048)
			(end 0.67945 -0.305054)
			(stroke
				(width 0.1)
				(type default)
			)
			(layer "B.Fab")
		)
		(fp_line
			(start -0.120396 0.2794)
			(end 0.12065 0.2794)
			(stroke
				(width 0.1)
				(type default)
			)
			(layer "B.Fab")
		)
		(fp_line
			(start 0.12065 0.2794)
			(end 0.12065 0.3048)
			(stroke
				(width 0.1)
				(type default)
			)
			(layer "B.Fab")
		)
		(fp_line
			(start -0.12065 -0.2794)
			(end -0.12065 -0.3048)
			(stroke
				(width 0.1)
				(type default)
			)
			(layer "B.Fab")
		)
		(fp_line
			(start 0.12065 -0.2794)
			(end -0.12065 -0.2794)
			(stroke
				(width 0.1)
				(type default)
			)
			(layer "B.Fab")
		)
		(fp_line
			(start -0.67945 -0.3048)
			(end -0.67945 0.3048)
			(stroke
				(width 0.1)
				(type default)
			)
			(layer "B.Fab")
		)
		(fp_line
			(start -0.12065 -0.3048)
			(end -0.67945 -0.3048)
			(stroke
				(width 0.1)
				(type default)
			)
			(layer "B.Fab")
		)
		(fp_line
			(start 0.12065 -0.305054)
			(end 0.12065 -0.2794)
			(stroke
				(width 0.1)
				(type default)
			)
			(layer "B.Fab")
		)
		(fp_line
			(start 0.67945 -0.305054)
			(end 0.12065 -0.305054)
			(stroke
				(width 0.1)
				(type default)
			)
			(layer "B.Fab")
		)
		(pad "1" smd circle
			(at 0.40005 0 90)
			(size 0 0)
			(layers "B.Cu" "B.Mask" "B.Paste")
			(net "PWRGD_DRAMPWRGD_CPU0_EF_LVC1_R2")
		)
		(pad "2" smd circle
			(at -0.40005 0 90)
			(size 0 0)
			(layers "B.Cu" "B.Mask" "B.Paste")
			(net "PWRGD_DRAMPWRGD_CPU0_EF_LVC1_R")
		)
	)
	(footprint ""
		(layer "B.Cu")
		(at 286.478726 -193.691256 -90)
		(property "Reference" "R840"
			(at 0 0 90)
			(layer "B.SilkS")
			(hide yes)
			(effects
				(font
					(size 1.27 1.27)
				)
				(justify mirror)
			)
		)
		(property "Value" ""
			(at 0 0 90)
			(layer "B.Fab")
			(effects
				(font
					(size 1.27 1.27)
				)
				(justify mirror)
			)
		)
		(duplicate_pad_numbers_are_jumpers no)
		(fp_line
			(start -0.7874 0.4064)
			(end 0.7874 0.4064)
			(stroke
				(width 0.1524)
				(type default)
			)
			(layer "B.SilkS")
		)
		(fp_line
			(start 0.7874 0.4064)
			(end 0.7874 -0.4064)
			(stroke
				(width 0.1524)
				(type default)
			)
			(layer "B.SilkS")
		)
		(fp_line
			(start -0.7874 -0.4064)
			(end -0.7874 0.4064)
			(stroke
				(width 0.1524)
				(type default)
			)
			(layer "B.SilkS")
		)
		(fp_line
			(start 0.7874 -0.4064)
			(end -0.7874 -0.4064)
			(stroke
				(width 0.1524)
				(type default)
			)
			(layer "B.SilkS")
		)
		(fp_line
			(start -0.67945 0.3048)
			(end -0.120396 0.3048)
			(stroke
				(width 0.1)
				(type default)
			)
			(layer "B.Fab")
		)
		(fp_line
			(start -0.120396 0.3048)
			(end -0.120396 0.2794)
			(stroke
				(width 0.1)
				(type default)
			)
			(layer "B.Fab")
		)
		(fp_line
			(start 0.12065 0.3048)
			(end 0.67945 0.3048)
			(stroke
				(width 0.1)
				(type default)
			)
			(layer "B.Fab")
		)
		(fp_line
			(start 0.67945 0.3048)
			(end 0.67945 -0.305054)
			(stroke
				(width 0.1)
				(type default)
			)
			(layer "B.Fab")
		)
		(fp_line
			(start -0.120396 0.2794)
			(end 0.12065 0.2794)
			(stroke
				(width 0.1)
				(type default)
			)
			(layer "B.Fab")
		)
		(fp_line
			(start 0.12065 0.2794)
			(end 0.12065 0.3048)
			(stroke
				(width 0.1)
				(type default)
			)
			(layer "B.Fab")
		)
		(fp_line
			(start -0.12065 -0.2794)
			(end -0.12065 -0.3048)
			(stroke
				(width 0.1)
				(type default)
			)
			(layer "B.Fab")
		)
		(fp_line
			(start 0.12065 -0.2794)
			(end -0.12065 -0.2794)
			(stroke
				(width 0.1)
				(type default)
			)
			(layer "B.Fab")
		)
		(fp_line
			(start -0.67945 -0.3048)
			(end -0.67945 0.3048)
			(stroke
				(width 0.1)
				(type default)
			)
			(layer "B.Fab")
		)
		(fp_line
			(start -0.12065 -0.3048)
			(end -0.67945 -0.3048)
			(stroke
				(width 0.1)
				(type default)
			)
			(layer "B.Fab")
		)
		(fp_line
			(start 0.12065 -0.305054)
			(end 0.12065 -0.2794)
			(stroke
				(width 0.1)
				(type default)
			)
			(layer "B.Fab")
		)
		(fp_line
			(start 0.67945 -0.305054)
			(end 0.12065 -0.305054)
			(stroke
				(width 0.1)
				(type default)
			)
			(layer "B.Fab")
		)
		(pad "1" smd circle
			(at 0.40005 0 90)
			(size 0 0)
			(layers "B.Cu" "B.Mask" "B.Paste")
			(net "PVCCD_HV_CPU0")
		)
		(pad "2" smd circle
			(at -0.40005 0 90)
			(size 0 0)
			(layers "B.Cu" "B.Mask" "B.Paste")
			(net "RST_M_AB_CPU0_FPGA_N")
		)
	)
	(footprint ""
		(layer "B.Cu")
		(at 256.370836 -102.277418 90)
		(property "Reference" "C117"
			(at 0 0 90)
			(layer "B.SilkS")
			(hide yes)
			(effects
				(font
					(size 1.27 1.27)
				)
				(justify mirror)
			)
		)
		(property "Value" ""
			(at 0 0 90)
			(layer "B.Fab")
			(effects
				(font
					(size 1.27 1.27)
				)
				(justify mirror)
			)
		)
		(duplicate_pad_numbers_are_jumpers no)
		(fp_line
			(start 0.7874 -0.4064)
			(end -0.7874 -0.4064)
			(stroke
				(width 0.1524)
				(type default)
			)
			(layer "B.SilkS")
		)
		(fp_line
			(start -0.7874 -0.4064)
			(end -0.7874 0.4064)
			(stroke
				(width 0.1524)
				(type default)
			)
			(layer "B.SilkS")
		)
		(fp_line
			(start 0.7874 0.4064)
			(end 0.7874 -0.4064)
			(stroke
				(width 0.1524)
				(type default)
			)
			(layer "B.SilkS")
		)
		(fp_line
			(start -0.7874 0.4064)
			(end 0.7874 0.4064)
			(stroke
				(width 0.1524)
				(type default)
			)
			(layer "B.SilkS")
		)
		(fp_line
			(start 0.67945 -0.305054)
			(end 0.12065 -0.305054)
			(stroke
				(width 0.1)
				(type default)
			)
			(layer "B.Fab")
		)
		(fp_line
			(start 0.12065 -0.305054)
			(end 0.12065 -0.2794)
			(stroke
				(width 0.1)
				(type default)
			)
			(layer "B.Fab")
		)
		(fp_line
			(start -0.12065 -0.3048)
			(end -0.67945 -0.3048)
			(stroke
				(width 0.1)
				(type default)
			)
			(layer "B.Fab")
		)
		(fp_line
			(start -0.67945 -0.3048)
			(end -0.67945 0.3048)
			(stroke
				(width 0.1)
				(type default)
			)
			(layer "B.Fab")
		)
		(fp_line
			(start 0.12065 -0.2794)
			(end -0.12065 -0.2794)
			(stroke
				(width 0.1)
				(type default)
			)
			(layer "B.Fab")
		)
		(fp_line
			(start -0.12065 -0.2794)
			(end -0.12065 -0.3048)
			(stroke
				(width 0.1)
				(type default)
			)
			(layer "B.Fab")
		)
		(fp_line
			(start 0.12065 0.2794)
			(end 0.12065 0.3048)
			(stroke
				(width 0.1)
				(type default)
			)
			(layer "B.Fab")
		)
		(fp_line
			(start -0.120396 0.2794)
			(end 0.12065 0.2794)
			(stroke
				(width 0.1)
				(type default)
			)
			(layer "B.Fab")
		)
		(fp_line
			(start 0.67945 0.3048)
			(end 0.67945 -0.305054)
			(stroke
				(width 0.1)
				(type default)
			)
			(layer "B.Fab")
		)
		(fp_line
			(start 0.12065 0.3048)
			(end 0.67945 0.3048)
			(stroke
				(width 0.1)
				(type default)
			)
			(layer "B.Fab")
		)
		(fp_line
			(start -0.120396 0.3048)
			(end -0.120396 0.2794)
			(stroke
				(width 0.1)
				(type default)
			)
			(layer "B.Fab")
		)
		(fp_line
			(start -0.67945 0.3048)
			(end -0.120396 0.3048)
			(stroke
				(width 0.1)
				(type default)
			)
			(layer "B.Fab")
		)
		(pad "1" smd circle
			(at 0.40005 0 270)
			(size 0 0)
			(layers "B.Cu" "B.Mask" "B.Paste")
			(net "P3V3_AUX_CLK_GEN_VDDMXCK_CK440")
		)
		(pad "2" smd circle
			(at -0.40005 0 270)
			(size 0 0)
			(layers "B.Cu" "B.Mask" "B.Paste")
			(net "GND")
		)
	)
	(footprint ""
		(layer "B.Cu")
		(at 160.83788 -118.836948)
		(property "Reference" "R986"
			(at 0 0 0)
			(layer "B.SilkS")
			(hide yes)
			(effects
				(font
					(size 1.27 1.27)
				)
				(justify mirror)
			)
		)
		(property "Value" ""
			(at 0 0 0)
			(layer "B.Fab")
			(effects
				(font
					(size 1.27 1.27)
				)
				(justify mirror)
			)
		)
		(duplicate_pad_numbers_are_jumpers no)
		(fp_line
			(start -0.7874 -0.4064)
			(end -0.7874 0.4064)
			(stroke
				(width 0.1524)
				(type default)
			)
			(layer "B.SilkS")
		)
		(fp_line
			(start -0.7874 0.4064)
			(end 0.7874 0.4064)
			(stroke
				(width 0.1524)
				(type default)
			)
			(layer "B.SilkS")
		)
		(fp_line
			(start 0.7874 -0.4064)
			(end -0.7874 -0.4064)
			(stroke
				(width 0.1524)
				(type default)
			)
			(layer "B.SilkS")
		)
		(fp_line
			(start 0.7874 0.4064)
			(end 0.7874 -0.4064)
			(stroke
				(width 0.1524)
				(type default)
			)
			(layer "B.SilkS")
		)
		(fp_line
			(start -0.67945 -0.3048)
			(end -0.67945 0.3048)
			(stroke
				(width 0.1)
				(type default)
			)
			(layer "B.Fab")
		)
		(fp_line
			(start -0.67945 0.3048)
			(end -0.120396 0.3048)
			(stroke
				(width 0.1)
				(type default)
			)
			(layer "B.Fab")
		)
		(fp_line
			(start -0.12065 -0.3048)
			(end -0.67945 -0.3048)
			(stroke
				(width 0.1)
				(type default)
			)
			(layer "B.Fab")
		)
		(fp_line
			(start -0.12065 -0.2794)
			(end -0.12065 -0.3048)
			(stroke
				(width 0.1)
				(type default)
			)
			(layer "B.Fab")
		)
		(fp_line
			(start -0.120396 0.2794)
			(end 0.12065 0.2794)
			(stroke
				(width 0.1)
				(type default)
			)
			(layer "B.Fab")
		)
		(fp_line
			(start -0.120396 0.3048)
			(end -0.120396 0.2794)
			(stroke
				(width 0.1)
				(type default)
			)
			(layer "B.Fab")
		)
		(fp_line
			(start 0.12065 -0.305054)
			(end 0.12065 -0.2794)
			(stroke
				(width 0.1)
				(type default)
			)
			(layer "B.Fab")
		)
		(fp_line
			(start 0.12065 -0.2794)
			(end -0.12065 -0.2794)
			(stroke
				(width 0.1)
				(type default)
			)
			(layer "B.Fab")
		)
		(fp_line
			(start 0.12065 0.2794)
			(end 0.12065 0.3048)
			(stroke
				(width 0.1)
				(type default)
			)
			(layer "B.Fab")
		)
		(fp_line
			(start 0.12065 0.3048)
			(end 0.67945 0.3048)
			(stroke
				(width 0.1)
				(type default)
			)
			(layer "B.Fab")
		)
		(fp_line
			(start 0.67945 -0.305054)
			(end 0.12065 -0.305054)
			(stroke
				(width 0.1)
				(type default)
			)
			(layer "B.Fab")
		)
		(fp_line
			(start 0.67945 0.3048)
			(end 0.67945 -0.305054)
			(stroke
				(width 0.1)
				(type default)
			)
			(layer "B.Fab")
		)
		(pad "1" smd circle
			(at 0.40005 0 180)
			(size 0 0)
			(layers "B.Cu" "B.Mask" "B.Paste")
			(net "FM_PVCCFA_EHV_CPU1_R_EN")
		)
		(pad "2" smd circle
			(at -0.40005 0 180)
			(size 0 0)
			(layers "B.Cu" "B.Mask" "B.Paste")
			(net "FM_PVCCFA_EHV_CPU1_EN")
		)
	)
	(footprint ""
		(layer "B.Cu")
		(at 57.429146 -319.41008 180)
		(property "Reference" "R893"
			(at 0 0 0)
			(layer "B.SilkS")
			(hide yes)
			(effects
				(font
					(size 1.27 1.27)
				)
				(justify mirror)
			)
		)
		(property "Value" ""
			(at 0 0 0)
			(layer "B.Fab")
			(effects
				(font
					(size 1.27 1.27)
				)
				(justify mirror)
			)
		)
		(duplicate_pad_numbers_are_jumpers no)
		(fp_line
			(start 0.7874 0.4064)
			(end 0.7874 -0.4064)
			(stroke
				(width 0.1524)
				(type default)
			)
			(layer "B.SilkS")
		)
		(fp_line
			(start 0.7874 -0.4064)
			(end -0.7874 -0.4064)
			(stroke
				(width 0.1524)
				(type default)
			)
			(layer "B.SilkS")
		)
		(fp_line
			(start -0.7874 0.4064)
			(end 0.7874 0.4064)
			(stroke
				(width 0.1524)
				(type default)
			)
			(layer "B.SilkS")
		)
		(fp_line
			(start -0.7874 -0.4064)
			(end -0.7874 0.4064)
			(stroke
				(width 0.1524)
				(type default)
			)
			(layer "B.SilkS")
		)
		(fp_line
			(start 0.67945 0.3048)
			(end 0.67945 -0.305054)
			(stroke
				(width 0.1)
				(type default)
			)
			(layer "B.Fab")
		)
		(fp_line
			(start 0.67945 -0.305054)
			(end 0.12065 -0.305054)
			(stroke
				(width 0.1)
				(type default)
			)
			(layer "B.Fab")
		)
		(fp_line
			(start 0.12065 0.3048)
			(end 0.67945 0.3048)
			(stroke
				(width 0.1)
				(type default)
			)
			(layer "B.Fab")
		)
		(fp_line
			(start 0.12065 0.2794)
			(end 0.12065 0.3048)
			(stroke
				(width 0.1)
				(type default)
			)
			(layer "B.Fab")
		)
		(fp_line
			(start 0.12065 -0.2794)
			(end -0.12065 -0.2794)
			(stroke
				(width 0.1)
				(type default)
			)
			(layer "B.Fab")
		)
		(fp_line
			(start 0.12065 -0.305054)
			(end 0.12065 -0.2794)
			(stroke
				(width 0.1)
				(type default)
			)
			(layer "B.Fab")
		)
		(fp_line
			(start -0.120396 0.3048)
			(end -0.120396 0.2794)
			(stroke
				(width 0.1)
				(type default)
			)
			(layer "B.Fab")
		)
		(fp_line
			(start -0.120396 0.2794)
			(end 0.12065 0.2794)
			(stroke
				(width 0.1)
				(type default)
			)
			(layer "B.Fab")
		)
		(fp_line
			(start -0.12065 -0.2794)
			(end -0.12065 -0.3048)
			(stroke
				(width 0.1)
				(type default)
			)
			(layer "B.Fab")
		)
		(fp_line
			(start -0.12065 -0.3048)
			(end -0.67945 -0.3048)
			(stroke
				(width 0.1)
				(type default)
			)
			(layer "B.Fab")
		)
		(fp_line
			(start -0.67945 0.3048)
			(end -0.120396 0.3048)
			(stroke
				(width 0.1)
				(type default)
			)
			(layer "B.Fab")
		)
		(fp_line
			(start -0.67945 -0.3048)
			(end -0.67945 0.3048)
			(stroke
				(width 0.1)
				(type default)
			)
			(layer "B.Fab")
		)
		(pad "1" smd circle
			(at 0.40005 0)
			(size 0 0)
			(layers "B.Cu" "B.Mask" "B.Paste")
			(net "PWRGD_CHA_CPU1_DIMM1")
		)
		(pad "2" smd circle
			(at -0.40005 0)
			(size 0 0)
			(layers "B.Cu" "B.Mask" "B.Paste")
			(net "PWRGD_FAIL_CPU1_AB")
		)
	)
	(footprint ""
		(layer "B.Cu")
		(at 83.46948 -331.864208 -90)
		(property "Reference" "PC496_P1_7"
			(at 0 0 90)
			(layer "B.SilkS")
			(hide yes)
			(effects
				(font
					(size 1.27 1.27)
				)
				(justify mirror)
			)
		)
		(property "Value" ""
			(at 0 0 90)
			(layer "B.Fab")
			(effects
				(font
					(size 1.27 1.27)
				)
				(justify mirror)
			)
		)
		(duplicate_pad_numbers_are_jumpers no)
		(fp_line
			(start -0.7874 0.4064)
			(end 0.7874 0.4064)
			(stroke
				(width 0.1524)
				(type default)
			)
			(layer "B.SilkS")
		)
		(fp_line
			(start 0.7874 0.4064)
			(end 0.7874 -0.4064)
			(stroke
				(width 0.1524)
				(type default)
			)
			(layer "B.SilkS")
		)
		(fp_line
			(start -0.7874 -0.4064)
			(end -0.7874 0.4064)
			(stroke
				(width 0.1524)
				(type default)
			)
			(layer "B.SilkS")
		)
		(fp_line
			(start 0.7874 -0.4064)
			(end -0.7874 -0.4064)
			(stroke
				(width 0.1524)
				(type default)
			)
			(layer "B.SilkS")
		)
		(fp_line
			(start -0.67945 0.3048)
			(end -0.120396 0.3048)
			(stroke
				(width 0.1)
				(type default)
			)
			(layer "B.Fab")
		)
		(fp_line
			(start -0.120396 0.3048)
			(end -0.120396 0.2794)
			(stroke
				(width 0.1)
				(type default)
			)
			(layer "B.Fab")
		)
		(fp_line
			(start 0.12065 0.3048)
			(end 0.67945 0.3048)
			(stroke
				(width 0.1)
				(type default)
			)
			(layer "B.Fab")
		)
		(fp_line
			(start 0.67945 0.3048)
			(end 0.67945 -0.305054)
			(stroke
				(width 0.1)
				(type default)
			)
			(layer "B.Fab")
		)
		(fp_line
			(start -0.120396 0.2794)
			(end 0.12065 0.2794)
			(stroke
				(width 0.1)
				(type default)
			)
			(layer "B.Fab")
		)
		(fp_line
			(start 0.12065 0.2794)
			(end 0.12065 0.3048)
			(stroke
				(width 0.1)
				(type default)
			)
			(layer "B.Fab")
		)
		(fp_line
			(start -0.12065 -0.2794)
			(end -0.12065 -0.3048)
			(stroke
				(width 0.1)
				(type default)
			)
			(layer "B.Fab")
		)
		(fp_line
			(start 0.12065 -0.2794)
			(end -0.12065 -0.2794)
			(stroke
				(width 0.1)
				(type default)
			)
			(layer "B.Fab")
		)
		(fp_line
			(start -0.67945 -0.3048)
			(end -0.67945 0.3048)
			(stroke
				(width 0.1)
				(type default)
			)
			(layer "B.Fab")
		)
		(fp_line
			(start -0.12065 -0.3048)
			(end -0.67945 -0.3048)
			(stroke
				(width 0.1)
				(type default)
			)
			(layer "B.Fab")
		)
		(fp_line
			(start 0.12065 -0.305054)
			(end 0.12065 -0.2794)
			(stroke
				(width 0.1)
				(type default)
			)
			(layer "B.Fab")
		)
		(fp_line
			(start 0.67945 -0.305054)
			(end 0.12065 -0.305054)
			(stroke
				(width 0.1)
				(type default)
			)
			(layer "B.Fab")
		)
		(pad "1" smd circle
			(at 0.40005 0 90)
			(size 0 0)
			(layers "B.Cu" "B.Mask" "B.Paste")
			(net "PVCCIN_CPU1")
		)
		(pad "2" smd circle
			(at -0.40005 0 90)
			(size 0 0)
			(layers "B.Cu" "B.Mask" "B.Paste")
			(net "GND")
		)
	)
	(footprint ""
		(layer "B.Cu")
		(at 309.501032 -319.224406)
		(property "Reference" "R27"
			(at 0 0 0)
			(layer "B.SilkS")
			(hide yes)
			(effects
				(font
					(size 1.27 1.27)
				)
				(justify mirror)
			)
		)
		(property "Value" ""
			(at 0 0 0)
			(layer "B.Fab")
			(effects
				(font
					(size 1.27 1.27)
				)
				(justify mirror)
			)
		)
		(duplicate_pad_numbers_are_jumpers no)
		(fp_line
			(start -0.7874 -0.4064)
			(end -0.7874 0.4064)
			(stroke
				(width 0.1524)
				(type default)
			)
			(layer "B.SilkS")
		)
		(fp_line
			(start -0.7874 0.4064)
			(end 0.7874 0.4064)
			(stroke
				(width 0.1524)
				(type default)
			)
			(layer "B.SilkS")
		)
		(fp_line
			(start 0.7874 -0.4064)
			(end -0.7874 -0.4064)
			(stroke
				(width 0.1524)
				(type default)
			)
			(layer "B.SilkS")
		)
		(fp_line
			(start 0.7874 0.4064)
			(end 0.7874 -0.4064)
			(stroke
				(width 0.1524)
				(type default)
			)
			(layer "B.SilkS")
		)
		(fp_line
			(start -0.67945 -0.3048)
			(end -0.67945 0.3048)
			(stroke
				(width 0.1)
				(type default)
			)
			(layer "B.Fab")
		)
		(fp_line
			(start -0.67945 0.3048)
			(end -0.120396 0.3048)
			(stroke
				(width 0.1)
				(type default)
			)
			(layer "B.Fab")
		)
		(fp_line
			(start -0.12065 -0.3048)
			(end -0.67945 -0.3048)
			(stroke
				(width 0.1)
				(type default)
			)
			(layer "B.Fab")
		)
		(fp_line
			(start -0.12065 -0.2794)
			(end -0.12065 -0.3048)
			(stroke
				(width 0.1)
				(type default)
			)
			(layer "B.Fab")
		)
		(fp_line
			(start -0.120396 0.2794)
			(end 0.12065 0.2794)
			(stroke
				(width 0.1)
				(type default)
			)
			(layer "B.Fab")
		)
		(fp_line
			(start -0.120396 0.3048)
			(end -0.120396 0.2794)
			(stroke
				(width 0.1)
				(type default)
			)
			(layer "B.Fab")
		)
		(fp_line
			(start 0.12065 -0.305054)
			(end 0.12065 -0.2794)
			(stroke
				(width 0.1)
				(type default)
			)
			(layer "B.Fab")
		)
		(fp_line
			(start 0.12065 -0.2794)
			(end -0.12065 -0.2794)
			(stroke
				(width 0.1)
				(type default)
			)
			(layer "B.Fab")
		)
		(fp_line
			(start 0.12065 0.2794)
			(end 0.12065 0.3048)
			(stroke
				(width 0.1)
				(type default)
			)
			(layer "B.Fab")
		)
		(fp_line
			(start 0.12065 0.3048)
			(end 0.67945 0.3048)
			(stroke
				(width 0.1)
				(type default)
			)
			(layer "B.Fab")
		)
		(fp_line
			(start 0.67945 -0.305054)
			(end 0.12065 -0.305054)
			(stroke
				(width 0.1)
				(type default)
			)
			(layer "B.Fab")
		)
		(fp_line
			(start 0.67945 0.3048)
			(end 0.67945 -0.305054)
			(stroke
				(width 0.1)
				(type default)
			)
			(layer "B.Fab")
		)
		(pad "1" smd circle
			(at 0.40005 0 180)
			(size 0 0)
			(layers "B.Cu" "B.Mask" "B.Paste")
			(net "PD_CHA_CPU0_DIMM2_SAA")
		)
		(pad "2" smd circle
			(at -0.40005 0 180)
			(size 0 0)
			(layers "B.Cu" "B.Mask" "B.Paste")
			(net "GND")
		)
	)
	(footprint ""
		(layer "B.Cu")
		(at 28.6766 -162.423348 -90)
		(property "Reference" "PR4256"
			(at 0 0 90)
			(layer "B.SilkS")
			(hide yes)
			(effects
				(font
					(size 1.27 1.27)
				)
				(justify mirror)
			)
		)
		(property "Value" ""
			(at 0 0 90)
			(layer "B.Fab")
			(effects
				(font
					(size 1.27 1.27)
				)
				(justify mirror)
			)
		)
		(duplicate_pad_numbers_are_jumpers no)
		(fp_line
			(start -0.7874 0.4064)
			(end 0.7874 0.4064)
			(stroke
				(width 0.1524)
				(type default)
			)
			(layer "B.SilkS")
		)
		(fp_line
			(start 0.7874 0.4064)
			(end 0.7874 -0.4064)
			(stroke
				(width 0.1524)
				(type default)
			)
			(layer "B.SilkS")
		)
		(fp_line
			(start -0.7874 -0.4064)
			(end -0.7874 0.4064)
			(stroke
				(width 0.1524)
				(type default)
			)
			(layer "B.SilkS")
		)
		(fp_line
			(start 0.7874 -0.4064)
			(end -0.7874 -0.4064)
			(stroke
				(width 0.1524)
				(type default)
			)
			(layer "B.SilkS")
		)
		(fp_line
			(start -0.67945 0.3048)
			(end -0.120396 0.3048)
			(stroke
				(width 0.1)
				(type default)
			)
			(layer "B.Fab")
		)
		(fp_line
			(start -0.120396 0.3048)
			(end -0.120396 0.2794)
			(stroke
				(width 0.1)
				(type default)
			)
			(layer "B.Fab")
		)
		(fp_line
			(start 0.12065 0.3048)
			(end 0.67945 0.3048)
			(stroke
				(width 0.1)
				(type default)
			)
			(layer "B.Fab")
		)
		(fp_line
			(start 0.67945 0.3048)
			(end 0.67945 -0.305054)
			(stroke
				(width 0.1)
				(type default)
			)
			(layer "B.Fab")
		)
		(fp_line
			(start -0.120396 0.2794)
			(end 0.12065 0.2794)
			(stroke
				(width 0.1)
				(type default)
			)
			(layer "B.Fab")
		)
		(fp_line
			(start 0.12065 0.2794)
			(end 0.12065 0.3048)
			(stroke
				(width 0.1)
				(type default)
			)
			(layer "B.Fab")
		)
		(fp_line
			(start -0.12065 -0.2794)
			(end -0.12065 -0.3048)
			(stroke
				(width 0.1)
				(type default)
			)
			(layer "B.Fab")
		)
		(fp_line
			(start 0.12065 -0.2794)
			(end -0.12065 -0.2794)
			(stroke
				(width 0.1)
				(type default)
			)
			(layer "B.Fab")
		)
		(fp_line
			(start -0.67945 -0.3048)
			(end -0.67945 0.3048)
			(stroke
				(width 0.1)
				(type default)
			)
			(layer "B.Fab")
		)
		(fp_line
			(start -0.12065 -0.3048)
			(end -0.67945 -0.3048)
			(stroke
				(width 0.1)
				(type default)
			)
			(layer "B.Fab")
		)
		(fp_line
			(start 0.12065 -0.305054)
			(end 0.12065 -0.2794)
			(stroke
				(width 0.1)
				(type default)
			)
			(layer "B.Fab")
		)
		(fp_line
			(start 0.67945 -0.305054)
			(end 0.12065 -0.305054)
			(stroke
				(width 0.1)
				(type default)
			)
			(layer "B.Fab")
		)
		(pad "1" smd circle
			(at 0.40005 0 90)
			(size 0 0)
			(layers "B.Cu" "B.Mask" "B.Paste")
			(net "NC_PVCCD_HV_CPU1_ACSP7")
		)
		(pad "2" smd circle
			(at -0.40005 0 90)
			(size 0 0)
			(layers "B.Cu" "B.Mask" "B.Paste")
			(net "GND")
		)
	)
	(footprint ""
		(layer "B.Cu")
		(at 151.281638 -190.35522 -90)
		(property "Reference" "R664"
			(at 0 0 90)
			(layer "B.SilkS")
			(hide yes)
			(effects
				(font
					(size 1.27 1.27)
				)
				(justify mirror)
			)
		)
		(property "Value" ""
			(at 0 0 90)
			(layer "B.Fab")
			(effects
				(font
					(size 1.27 1.27)
				)
				(justify mirror)
			)
		)
		(duplicate_pad_numbers_are_jumpers no)
		(fp_line
			(start -0.7874 0.4064)
			(end 0.7874 0.4064)
			(stroke
				(width 0.1524)
				(type default)
			)
			(layer "B.SilkS")
		)
		(fp_line
			(start 0.7874 0.4064)
			(end 0.7874 -0.4064)
			(stroke
				(width 0.1524)
				(type default)
			)
			(layer "B.SilkS")
		)
		(fp_line
			(start -0.7874 -0.4064)
			(end -0.7874 0.4064)
			(stroke
				(width 0.1524)
				(type default)
			)
			(layer "B.SilkS")
		)
		(fp_line
			(start 0.7874 -0.4064)
			(end -0.7874 -0.4064)
			(stroke
				(width 0.1524)
				(type default)
			)
			(layer "B.SilkS")
		)
		(fp_line
			(start -0.67945 0.3048)
			(end -0.120396 0.3048)
			(stroke
				(width 0.1)
				(type default)
			)
			(layer "B.Fab")
		)
		(fp_line
			(start -0.120396 0.3048)
			(end -0.120396 0.2794)
			(stroke
				(width 0.1)
				(type default)
			)
			(layer "B.Fab")
		)
		(fp_line
			(start 0.12065 0.3048)
			(end 0.67945 0.3048)
			(stroke
				(width 0.1)
				(type default)
			)
			(layer "B.Fab")
		)
		(fp_line
			(start 0.67945 0.3048)
			(end 0.67945 -0.305054)
			(stroke
				(width 0.1)
				(type default)
			)
			(layer "B.Fab")
		)
		(fp_line
			(start -0.120396 0.2794)
			(end 0.12065 0.2794)
			(stroke
				(width 0.1)
				(type default)
			)
			(layer "B.Fab")
		)
		(fp_line
			(start 0.12065 0.2794)
			(end 0.12065 0.3048)
			(stroke
				(width 0.1)
				(type default)
			)
			(layer "B.Fab")
		)
		(fp_line
			(start -0.12065 -0.2794)
			(end -0.12065 -0.3048)
			(stroke
				(width 0.1)
				(type default)
			)
			(layer "B.Fab")
		)
		(fp_line
			(start 0.12065 -0.2794)
			(end -0.12065 -0.2794)
			(stroke
				(width 0.1)
				(type default)
			)
			(layer "B.Fab")
		)
		(fp_line
			(start -0.67945 -0.3048)
			(end -0.67945 0.3048)
			(stroke
				(width 0.1)
				(type default)
			)
			(layer "B.Fab")
		)
		(fp_line
			(start -0.12065 -0.3048)
			(end -0.67945 -0.3048)
			(stroke
				(width 0.1)
				(type default)
			)
			(layer "B.Fab")
		)
		(fp_line
			(start 0.12065 -0.305054)
			(end 0.12065 -0.2794)
			(stroke
				(width 0.1)
				(type default)
			)
			(layer "B.Fab")
		)
		(fp_line
			(start 0.67945 -0.305054)
			(end 0.12065 -0.305054)
			(stroke
				(width 0.1)
				(type default)
			)
			(layer "B.Fab")
		)
		(pad "1" smd circle
			(at 0.40005 0 90)
			(size 0 0)
			(layers "B.Cu" "B.Mask" "B.Paste")
			(net "PVNN_TERM_CPU1")
		)
		(pad "2" smd circle
			(at -0.40005 0 90)
			(size 0 0)
			(layers "B.Cu" "B.Mask" "B.Paste")
			(net "I3C_SPD_DDREFGH_CPU1_SCL")
		)
	)
	(footprint ""
		(layer "B.Cu")
		(at 430.600104 -134.494778)
		(property "Reference" "R2594"
			(at 0 0 0)
			(layer "B.SilkS")
			(hide yes)
			(effects
				(font
					(size 1.27 1.27)
				)
				(justify mirror)
			)
		)
		(property "Value" ""
			(at 0 0 0)
			(layer "B.Fab")
			(effects
				(font
					(size 1.27 1.27)
				)
				(justify mirror)
			)
		)
		(duplicate_pad_numbers_are_jumpers no)
		(fp_line
			(start -0.7874 -0.4064)
			(end -0.7874 0.4064)
			(stroke
				(width 0.1524)
				(type default)
			)
			(layer "B.SilkS")
		)
		(fp_line
			(start -0.7874 0.4064)
			(end 0.7874 0.4064)
			(stroke
				(width 0.1524)
				(type default)
			)
			(layer "B.SilkS")
		)
		(fp_line
			(start 0.7874 -0.4064)
			(end -0.7874 -0.4064)
			(stroke
				(width 0.1524)
				(type default)
			)
			(layer "B.SilkS")
		)
		(fp_line
			(start 0.7874 0.4064)
			(end 0.7874 -0.4064)
			(stroke
				(width 0.1524)
				(type default)
			)
			(layer "B.SilkS")
		)
		(fp_line
			(start -0.67945 -0.3048)
			(end -0.67945 0.3048)
			(stroke
				(width 0.1)
				(type default)
			)
			(layer "B.Fab")
		)
		(fp_line
			(start -0.67945 0.3048)
			(end -0.120396 0.3048)
			(stroke
				(width 0.1)
				(type default)
			)
			(layer "B.Fab")
		)
		(fp_line
			(start -0.12065 -0.3048)
			(end -0.67945 -0.3048)
			(stroke
				(width 0.1)
				(type default)
			)
			(layer "B.Fab")
		)
		(fp_line
			(start -0.12065 -0.2794)
			(end -0.12065 -0.3048)
			(stroke
				(width 0.1)
				(type default)
			)
			(layer "B.Fab")
		)
		(fp_line
			(start -0.120396 0.2794)
			(end 0.12065 0.2794)
			(stroke
				(width 0.1)
				(type default)
			)
			(layer "B.Fab")
		)
		(fp_line
			(start -0.120396 0.3048)
			(end -0.120396 0.2794)
			(stroke
				(width 0.1)
				(type default)
			)
			(layer "B.Fab")
		)
		(fp_line
			(start 0.12065 -0.305054)
			(end 0.12065 -0.2794)
			(stroke
				(width 0.1)
				(type default)
			)
			(layer "B.Fab")
		)
		(fp_line
			(start 0.12065 -0.2794)
			(end -0.12065 -0.2794)
			(stroke
				(width 0.1)
				(type default)
			)
			(layer "B.Fab")
		)
		(fp_line
			(start 0.12065 0.2794)
			(end 0.12065 0.3048)
			(stroke
				(width 0.1)
				(type default)
			)
			(layer "B.Fab")
		)
		(fp_line
			(start 0.12065 0.3048)
			(end 0.67945 0.3048)
			(stroke
				(width 0.1)
				(type default)
			)
			(layer "B.Fab")
		)
		(fp_line
			(start 0.67945 -0.305054)
			(end 0.12065 -0.305054)
			(stroke
				(width 0.1)
				(type default)
			)
			(layer "B.Fab")
		)
		(fp_line
			(start 0.67945 0.3048)
			(end 0.67945 -0.305054)
			(stroke
				(width 0.1)
				(type default)
			)
			(layer "B.Fab")
		)
		(pad "1" smd circle
			(at 0.40005 0 180)
			(size 0 0)
			(layers "B.Cu" "B.Mask" "B.Paste")
			(net "FM_PVCCINFAON_CPU0_EN")
		)
		(pad "2" smd circle
			(at -0.40005 0 180)
			(size 0 0)
			(layers "B.Cu" "B.Mask" "B.Paste")
			(net "PVCCINFAON_CPU0_EN_R")
		)
	)
	(footprint ""
		(layer "B.Cu")
		(at 112.020604 -296.05478)
		(property "Reference" "C348"
			(at 0 0 0)
			(layer "B.SilkS")
			(hide yes)
			(effects
				(font
					(size 1.27 1.27)
				)
				(justify mirror)
			)
		)
		(property "Value" ""
			(at 0 0 0)
			(layer "B.Fab")
			(effects
				(font
					(size 1.27 1.27)
				)
				(justify mirror)
			)
		)
		(duplicate_pad_numbers_are_jumpers no)
		(fp_line
			(start -1.524 -0.762)
			(end -1.524 0.762)
			(stroke
				(width 0.1524)
				(type default)
			)
			(layer "B.SilkS")
		)
		(fp_line
			(start -1.524 0.762)
			(end 1.524 0.762)
			(stroke
				(width 0.1524)
				(type default)
			)
			(layer "B.SilkS")
		)
		(fp_line
			(start 1.524 -0.762)
			(end -1.524 -0.762)
			(stroke
				(width 0.1524)
				(type default)
			)
			(layer "B.SilkS")
		)
		(fp_line
			(start 1.524 0.762)
			(end 1.524 -0.762)
			(stroke
				(width 0.1524)
				(type default)
			)
			(layer "B.SilkS")
		)
		(fp_line
			(start -1.1049 -0.724916)
			(end 1.1049 -0.724916)
			(stroke
				(width 0.1)
				(type default)
			)
			(layer "B.Fab")
		)
		(fp_line
			(start -1.1049 0.724916)
			(end -1.1049 -0.724916)
			(stroke
				(width 0.1)
				(type default)
			)
			(layer "B.Fab")
		)
		(fp_line
			(start 1.1049 -0.724916)
			(end 1.1049 0.724916)
			(stroke
				(width 0.1)
				(type default)
			)
			(layer "B.Fab")
		)
		(fp_line
			(start 1.1049 0.724916)
			(end -1.1049 0.724916)
			(stroke
				(width 0.1)
				(type default)
			)
			(layer "B.Fab")
		)
		(pad "1" smd rect
			(at 0.889 0)
			(size 1.016 1.27)
			(layers "B.Cu" "B.Mask" "B.Paste")
			(net "PVCCIN_CPU1")
		)
		(pad "2" smd rect
			(at -0.889 0)
			(size 1.016 1.27)
			(layers "B.Cu" "B.Mask" "B.Paste")
			(net "GND")
		)
	)
	(footprint ""
		(layer "B.Cu")
		(at 288.175192 -320.004948)
		(property "Reference" "R28"
			(at 0 0 0)
			(layer "B.SilkS")
			(hide yes)
			(effects
				(font
					(size 1.27 1.27)
				)
				(justify mirror)
			)
		)
		(property "Value" ""
			(at 0 0 0)
			(layer "B.Fab")
			(effects
				(font
					(size 1.27 1.27)
				)
				(justify mirror)
			)
		)
		(duplicate_pad_numbers_are_jumpers no)
		(fp_line
			(start -0.7874 -0.4064)
			(end -0.7874 0.4064)
			(stroke
				(width 0.1524)
				(type default)
			)
			(layer "B.SilkS")
		)
		(fp_line
			(start -0.7874 0.4064)
			(end 0.7874 0.4064)
			(stroke
				(width 0.1524)
				(type default)
			)
			(layer "B.SilkS")
		)
		(fp_line
			(start 0.7874 -0.4064)
			(end -0.7874 -0.4064)
			(stroke
				(width 0.1524)
				(type default)
			)
			(layer "B.SilkS")
		)
		(fp_line
			(start 0.7874 0.4064)
			(end 0.7874 -0.4064)
			(stroke
				(width 0.1524)
				(type default)
			)
			(layer "B.SilkS")
		)
		(fp_line
			(start -0.67945 -0.3048)
			(end -0.67945 0.3048)
			(stroke
				(width 0.1)
				(type default)
			)
			(layer "B.Fab")
		)
		(fp_line
			(start -0.67945 0.3048)
			(end -0.120396 0.3048)
			(stroke
				(width 0.1)
				(type default)
			)
			(layer "B.Fab")
		)
		(fp_line
			(start -0.12065 -0.3048)
			(end -0.67945 -0.3048)
			(stroke
				(width 0.1)
				(type default)
			)
			(layer "B.Fab")
		)
		(fp_line
			(start -0.12065 -0.2794)
			(end -0.12065 -0.3048)
			(stroke
				(width 0.1)
				(type default)
			)
			(layer "B.Fab")
		)
		(fp_line
			(start -0.120396 0.2794)
			(end 0.12065 0.2794)
			(stroke
				(width 0.1)
				(type default)
			)
			(layer "B.Fab")
		)
		(fp_line
			(start -0.120396 0.3048)
			(end -0.120396 0.2794)
			(stroke
				(width 0.1)
				(type default)
			)
			(layer "B.Fab")
		)
		(fp_line
			(start 0.12065 -0.305054)
			(end 0.12065 -0.2794)
			(stroke
				(width 0.1)
				(type default)
			)
			(layer "B.Fab")
		)
		(fp_line
			(start 0.12065 -0.2794)
			(end -0.12065 -0.2794)
			(stroke
				(width 0.1)
				(type default)
			)
			(layer "B.Fab")
		)
		(fp_line
			(start 0.12065 0.2794)
			(end 0.12065 0.3048)
			(stroke
				(width 0.1)
				(type default)
			)
			(layer "B.Fab")
		)
		(fp_line
			(start 0.12065 0.3048)
			(end 0.67945 0.3048)
			(stroke
				(width 0.1)
				(type default)
			)
			(layer "B.Fab")
		)
		(fp_line
			(start 0.67945 -0.305054)
			(end 0.12065 -0.305054)
			(stroke
				(width 0.1)
				(type default)
			)
			(layer "B.Fab")
		)
		(fp_line
			(start 0.67945 0.3048)
			(end 0.67945 -0.305054)
			(stroke
				(width 0.1)
				(type default)
			)
			(layer "B.Fab")
		)
		(pad "1" smd circle
			(at 0.40005 0 180)
			(size 0 0)
			(layers "B.Cu" "B.Mask" "B.Paste")
			(net "PD_CHB_CPU0_DIMM1_SAA")
		)
		(pad "2" smd circle
			(at -0.40005 0 180)
			(size 0 0)
			(layers "B.Cu" "B.Mask" "B.Paste")
			(net "GND")
		)
	)
	(footprint ""
		(layer "B.Cu")
		(at 336.1563 -42.537888)
		(property "Reference" "C1204"
			(at 0 0 0)
			(layer "B.SilkS")
			(hide yes)
			(effects
				(font
					(size 1.27 1.27)
				)
				(justify mirror)
			)
		)
		(property "Value" ""
			(at 0 0 0)
			(layer "B.Fab")
			(effects
				(font
					(size 1.27 1.27)
				)
				(justify mirror)
			)
		)
		(duplicate_pad_numbers_are_jumpers no)
		(fp_line
			(start -0.7874 -0.4064)
			(end -0.7874 0.4064)
			(stroke
				(width 0.1524)
				(type default)
			)
			(layer "B.SilkS")
		)
		(fp_line
			(start -0.7874 0.4064)
			(end 0.7874 0.4064)
			(stroke
				(width 0.1524)
				(type default)
			)
			(layer "B.SilkS")
		)
		(fp_line
			(start 0.7874 -0.4064)
			(end -0.7874 -0.4064)
			(stroke
				(width 0.1524)
				(type default)
			)
			(layer "B.SilkS")
		)
		(fp_line
			(start 0.7874 0.4064)
			(end 0.7874 -0.4064)
			(stroke
				(width 0.1524)
				(type default)
			)
			(layer "B.SilkS")
		)
		(fp_line
			(start -0.67945 -0.3048)
			(end -0.67945 0.3048)
			(stroke
				(width 0.1)
				(type default)
			)
			(layer "B.Fab")
		)
		(fp_line
			(start -0.67945 0.3048)
			(end -0.120396 0.3048)
			(stroke
				(width 0.1)
				(type default)
			)
			(layer "B.Fab")
		)
		(fp_line
			(start -0.12065 -0.3048)
			(end -0.67945 -0.3048)
			(stroke
				(width 0.1)
				(type default)
			)
			(layer "B.Fab")
		)
		(fp_line
			(start -0.12065 -0.2794)
			(end -0.12065 -0.3048)
			(stroke
				(width 0.1)
				(type default)
			)
			(layer "B.Fab")
		)
		(fp_line
			(start -0.120396 0.2794)
			(end 0.12065 0.2794)
			(stroke
				(width 0.1)
				(type default)
			)
			(layer "B.Fab")
		)
		(fp_line
			(start -0.120396 0.3048)
			(end -0.120396 0.2794)
			(stroke
				(width 0.1)
				(type default)
			)
			(layer "B.Fab")
		)
		(fp_line
			(start 0.12065 -0.305054)
			(end 0.12065 -0.2794)
			(stroke
				(width 0.1)
				(type default)
			)
			(layer "B.Fab")
		)
		(fp_line
			(start 0.12065 -0.2794)
			(end -0.12065 -0.2794)
			(stroke
				(width 0.1)
				(type default)
			)
			(layer "B.Fab")
		)
		(fp_line
			(start 0.12065 0.2794)
			(end 0.12065 0.3048)
			(stroke
				(width 0.1)
				(type default)
			)
			(layer "B.Fab")
		)
		(fp_line
			(start 0.12065 0.3048)
			(end 0.67945 0.3048)
			(stroke
				(width 0.1)
				(type default)
			)
			(layer "B.Fab")
		)
		(fp_line
			(start 0.67945 -0.305054)
			(end 0.12065 -0.305054)
			(stroke
				(width 0.1)
				(type default)
			)
			(layer "B.Fab")
		)
		(fp_line
			(start 0.67945 0.3048)
			(end 0.67945 -0.305054)
			(stroke
				(width 0.1)
				(type default)
			)
			(layer "B.Fab")
		)
		(pad "1" smd circle
			(at 0.40005 0 180)
			(size 0 0)
			(layers "B.Cu" "B.Mask" "B.Paste")
			(net "P1V05_PCH_AUX")
		)
		(pad "2" smd circle
			(at -0.40005 0 180)
			(size 0 0)
			(layers "B.Cu" "B.Mask" "B.Paste")
			(net "GND")
		)
	)
	(footprint ""
		(layer "B.Cu")
		(at 174.98568 -24.653748)
		(property "Reference" "PC2240"
			(at 0 0 0)
			(layer "B.SilkS")
			(hide yes)
			(effects
				(font
					(size 1.27 1.27)
				)
				(justify mirror)
			)
		)
		(property "Value" ""
			(at 0 0 0)
			(layer "B.Fab")
			(effects
				(font
					(size 1.27 1.27)
				)
				(justify mirror)
			)
		)
		(duplicate_pad_numbers_are_jumpers no)
		(fp_line
			(start -1.524 -0.762)
			(end -1.524 0.762)
			(stroke
				(width 0.1524)
				(type default)
			)
			(layer "B.SilkS")
		)
		(fp_line
			(start -1.524 0.762)
			(end 1.524 0.762)
			(stroke
				(width 0.1524)
				(type default)
			)
			(layer "B.SilkS")
		)
		(fp_line
			(start 1.524 -0.762)
			(end -1.524 -0.762)
			(stroke
				(width 0.1524)
				(type default)
			)
			(layer "B.SilkS")
		)
		(fp_line
			(start 1.524 0.762)
			(end 1.524 -0.762)
			(stroke
				(width 0.1524)
				(type default)
			)
			(layer "B.SilkS")
		)
		(fp_line
			(start -1.1049 -0.724916)
			(end 1.1049 -0.724916)
			(stroke
				(width 0.1)
				(type default)
			)
			(layer "B.Fab")
		)
		(fp_line
			(start -1.1049 0.724916)
			(end -1.1049 -0.724916)
			(stroke
				(width 0.1)
				(type default)
			)
			(layer "B.Fab")
		)
		(fp_line
			(start 1.1049 -0.724916)
			(end 1.1049 0.724916)
			(stroke
				(width 0.1)
				(type default)
			)
			(layer "B.Fab")
		)
		(fp_line
			(start 1.1049 0.724916)
			(end -1.1049 0.724916)
			(stroke
				(width 0.1)
				(type default)
			)
			(layer "B.Fab")
		)
		(pad "1" smd rect
			(at 0.889 0)
			(size 1.016 1.27)
			(layers "B.Cu" "B.Mask" "B.Paste")
			(net "P12V_SCM_R")
		)
		(pad "2" smd rect
			(at -0.889 0)
			(size 1.016 1.27)
			(layers "B.Cu" "B.Mask" "B.Paste")
			(net "GND")
		)
	)
	(footprint ""
		(layer "B.Cu")
		(at 275.244814 -321.549776 -90)
		(property "Reference" "C15"
			(at 0 0 90)
			(layer "B.SilkS")
			(hide yes)
			(effects
				(font
					(size 1.27 1.27)
				)
				(justify mirror)
			)
		)
		(property "Value" ""
			(at 0 0 90)
			(layer "B.Fab")
			(effects
				(font
					(size 1.27 1.27)
				)
				(justify mirror)
			)
		)
		(duplicate_pad_numbers_are_jumpers no)
		(fp_line
			(start -1.524 0.762)
			(end 1.524 0.762)
			(stroke
				(width 0.1524)
				(type default)
			)
			(layer "B.SilkS")
		)
		(fp_line
			(start 1.524 0.762)
			(end 1.524 -0.762)
			(stroke
				(width 0.1524)
				(type default)
			)
			(layer "B.SilkS")
		)
		(fp_line
			(start -1.524 -0.762)
			(end -1.524 0.762)
			(stroke
				(width 0.1524)
				(type default)
			)
			(layer "B.SilkS")
		)
		(fp_line
			(start 1.524 -0.762)
			(end -1.524 -0.762)
			(stroke
				(width 0.1524)
				(type default)
			)
			(layer "B.SilkS")
		)
		(fp_line
			(start -1.1049 0.724916)
			(end -1.1049 -0.724916)
			(stroke
				(width 0.1)
				(type default)
			)
			(layer "B.Fab")
		)
		(fp_line
			(start 1.1049 0.724916)
			(end -1.1049 0.724916)
			(stroke
				(width 0.1)
				(type default)
			)
			(layer "B.Fab")
		)
		(fp_line
			(start -1.1049 -0.724916)
			(end 1.1049 -0.724916)
			(stroke
				(width 0.1)
				(type default)
			)
			(layer "B.Fab")
		)
		(fp_line
			(start 1.1049 -0.724916)
			(end 1.1049 0.724916)
			(stroke
				(width 0.1)
				(type default)
			)
			(layer "B.Fab")
		)
		(pad "1" smd rect
			(at 0.889 0 270)
			(size 1.016 1.27)
			(layers "B.Cu" "B.Mask" "B.Paste")
			(net "P12V_S3_AUX_CPU0_NVDIMM")
		)
		(pad "2" smd rect
			(at -0.889 0 270)
			(size 1.016 1.27)
			(layers "B.Cu" "B.Mask" "B.Paste")
			(net "GND")
		)
	)
	(footprint ""
		(layer "B.Cu")
		(at 352.402902 -210.19389)
		(property "Reference" "C500"
			(at 0 0 0)
			(layer "B.SilkS")
			(hide yes)
			(effects
				(font
					(size 1.27 1.27)
				)
				(justify mirror)
			)
		)
		(property "Value" ""
			(at 0 0 0)
			(layer "B.Fab")
			(effects
				(font
					(size 1.27 1.27)
				)
				(justify mirror)
			)
		)
		(duplicate_pad_numbers_are_jumpers no)
		(fp_line
			(start -1.524 -0.762)
			(end -1.524 0.762)
			(stroke
				(width 0.1524)
				(type default)
			)
			(layer "B.SilkS")
		)
		(fp_line
			(start -1.524 0.762)
			(end 1.524 0.762)
			(stroke
				(width 0.1524)
				(type default)
			)
			(layer "B.SilkS")
		)
		(fp_line
			(start 1.524 -0.762)
			(end -1.524 -0.762)
			(stroke
				(width 0.1524)
				(type default)
			)
			(layer "B.SilkS")
		)
		(fp_line
			(start 1.524 0.762)
			(end 1.524 -0.762)
			(stroke
				(width 0.1524)
				(type default)
			)
			(layer "B.SilkS")
		)
		(fp_line
			(start -1.1049 -0.724916)
			(end 1.1049 -0.724916)
			(stroke
				(width 0.1)
				(type default)
			)
			(layer "B.Fab")
		)
		(fp_line
			(start -1.1049 0.724916)
			(end -1.1049 -0.724916)
			(stroke
				(width 0.1)
				(type default)
			)
			(layer "B.Fab")
		)
		(fp_line
			(start 1.1049 -0.724916)
			(end 1.1049 0.724916)
			(stroke
				(width 0.1)
				(type default)
			)
			(layer "B.Fab")
		)
		(fp_line
			(start 1.1049 0.724916)
			(end -1.1049 0.724916)
			(stroke
				(width 0.1)
				(type default)
			)
			(layer "B.Fab")
		)
		(pad "1" smd rect
			(at 0.889 0)
			(size 1.016 1.27)
			(layers "B.Cu" "B.Mask" "B.Paste")
			(net "PVCCFA_EHV_CPU0")
		)
		(pad "2" smd rect
			(at -0.889 0)
			(size 1.016 1.27)
			(layers "B.Cu" "B.Mask" "B.Paste")
			(net "GND")
		)
	)
	(footprint ""
		(layer "B.Cu")
		(at 338.553044 -32.437578 90)
		(property "Reference" "R1457"
			(at 0 0 90)
			(layer "B.SilkS")
			(hide yes)
			(effects
				(font
					(size 1.27 1.27)
				)
				(justify mirror)
			)
		)
		(property "Value" ""
			(at 0 0 90)
			(layer "B.Fab")
			(effects
				(font
					(size 1.27 1.27)
				)
				(justify mirror)
			)
		)
		(duplicate_pad_numbers_are_jumpers no)
		(fp_line
			(start 0.7874 -0.4064)
			(end -0.7874 -0.4064)
			(stroke
				(width 0.1524)
				(type default)
			)
			(layer "B.SilkS")
		)
		(fp_line
			(start -0.7874 -0.4064)
			(end -0.7874 0.4064)
			(stroke
				(width 0.1524)
				(type default)
			)
			(layer "B.SilkS")
		)
		(fp_line
			(start 0.7874 0.4064)
			(end 0.7874 -0.4064)
			(stroke
				(width 0.1524)
				(type default)
			)
			(layer "B.SilkS")
		)
		(fp_line
			(start -0.7874 0.4064)
			(end 0.7874 0.4064)
			(stroke
				(width 0.1524)
				(type default)
			)
			(layer "B.SilkS")
		)
		(fp_line
			(start 0.67945 -0.305054)
			(end 0.12065 -0.305054)
			(stroke
				(width 0.1)
				(type default)
			)
			(layer "B.Fab")
		)
		(fp_line
			(start 0.12065 -0.305054)
			(end 0.12065 -0.2794)
			(stroke
				(width 0.1)
				(type default)
			)
			(layer "B.Fab")
		)
		(fp_line
			(start -0.12065 -0.3048)
			(end -0.67945 -0.3048)
			(stroke
				(width 0.1)
				(type default)
			)
			(layer "B.Fab")
		)
		(fp_line
			(start -0.67945 -0.3048)
			(end -0.67945 0.3048)
			(stroke
				(width 0.1)
				(type default)
			)
			(layer "B.Fab")
		)
		(fp_line
			(start 0.12065 -0.2794)
			(end -0.12065 -0.2794)
			(stroke
				(width 0.1)
				(type default)
			)
			(layer "B.Fab")
		)
		(fp_line
			(start -0.12065 -0.2794)
			(end -0.12065 -0.3048)
			(stroke
				(width 0.1)
				(type default)
			)
			(layer "B.Fab")
		)
		(fp_line
			(start 0.12065 0.2794)
			(end 0.12065 0.3048)
			(stroke
				(width 0.1)
				(type default)
			)
			(layer "B.Fab")
		)
		(fp_line
			(start -0.120396 0.2794)
			(end 0.12065 0.2794)
			(stroke
				(width 0.1)
				(type default)
			)
			(layer "B.Fab")
		)
		(fp_line
			(start 0.67945 0.3048)
			(end 0.67945 -0.305054)
			(stroke
				(width 0.1)
				(type default)
			)
			(layer "B.Fab")
		)
		(fp_line
			(start 0.12065 0.3048)
			(end 0.67945 0.3048)
			(stroke
				(width 0.1)
				(type default)
			)
			(layer "B.Fab")
		)
		(fp_line
			(start -0.120396 0.3048)
			(end -0.120396 0.2794)
			(stroke
				(width 0.1)
				(type default)
			)
			(layer "B.Fab")
		)
		(fp_line
			(start -0.67945 0.3048)
			(end -0.120396 0.3048)
			(stroke
				(width 0.1)
				(type default)
			)
			(layer "B.Fab")
		)
		(pad "1" smd circle
			(at 0.40005 0 270)
			(size 0 0)
			(layers "B.Cu" "B.Mask" "B.Paste")
			(net "FM_XTAL_INPUT_FREQUENCY_1_MGPIO")
		)
		(pad "2" smd circle
			(at -0.40005 0 270)
			(size 0 0)
			(layers "B.Cu" "B.Mask" "B.Paste")
			(net "GND")
		)
	)
	(footprint ""
		(layer "B.Cu")
		(at 238.30788 -422.976548 90)
		(property "Reference" "C2297"
			(at 0 0 90)
			(layer "B.SilkS")
			(hide yes)
			(effects
				(font
					(size 1.27 1.27)
				)
				(justify mirror)
			)
		)
		(property "Value" ""
			(at 0 0 90)
			(layer "B.Fab")
			(effects
				(font
					(size 1.27 1.27)
				)
				(justify mirror)
			)
		)
		(duplicate_pad_numbers_are_jumpers no)
		(fp_line
			(start 0.7874 -0.4064)
			(end -0.7874 -0.4064)
			(stroke
				(width 0.1524)
				(type default)
			)
			(layer "B.SilkS")
		)
		(fp_line
			(start -0.7874 -0.4064)
			(end -0.7874 0.4064)
			(stroke
				(width 0.1524)
				(type default)
			)
			(layer "B.SilkS")
		)
		(fp_line
			(start 0.7874 0.4064)
			(end 0.7874 -0.4064)
			(stroke
				(width 0.1524)
				(type default)
			)
			(layer "B.SilkS")
		)
		(fp_line
			(start -0.7874 0.4064)
			(end 0.7874 0.4064)
			(stroke
				(width 0.1524)
				(type default)
			)
			(layer "B.SilkS")
		)
		(fp_line
			(start 0.67945 -0.305054)
			(end 0.12065 -0.305054)
			(stroke
				(width 0.1)
				(type default)
			)
			(layer "B.Fab")
		)
		(fp_line
			(start 0.12065 -0.305054)
			(end 0.12065 -0.2794)
			(stroke
				(width 0.1)
				(type default)
			)
			(layer "B.Fab")
		)
		(fp_line
			(start -0.12065 -0.3048)
			(end -0.67945 -0.3048)
			(stroke
				(width 0.1)
				(type default)
			)
			(layer "B.Fab")
		)
		(fp_line
			(start -0.67945 -0.3048)
			(end -0.67945 0.3048)
			(stroke
				(width 0.1)
				(type default)
			)
			(layer "B.Fab")
		)
		(fp_line
			(start 0.12065 -0.2794)
			(end -0.12065 -0.2794)
			(stroke
				(width 0.1)
				(type default)
			)
			(layer "B.Fab")
		)
		(fp_line
			(start -0.12065 -0.2794)
			(end -0.12065 -0.3048)
			(stroke
				(width 0.1)
				(type default)
			)
			(layer "B.Fab")
		)
		(fp_line
			(start 0.12065 0.2794)
			(end 0.12065 0.3048)
			(stroke
				(width 0.1)
				(type default)
			)
			(layer "B.Fab")
		)
		(fp_line
			(start -0.120396 0.2794)
			(end 0.12065 0.2794)
			(stroke
				(width 0.1)
				(type default)
			)
			(layer "B.Fab")
		)
		(fp_line
			(start 0.67945 0.3048)
			(end 0.67945 -0.305054)
			(stroke
				(width 0.1)
				(type default)
			)
			(layer "B.Fab")
		)
		(fp_line
			(start 0.12065 0.3048)
			(end 0.67945 0.3048)
			(stroke
				(width 0.1)
				(type default)
			)
			(layer "B.Fab")
		)
		(fp_line
			(start -0.120396 0.3048)
			(end -0.120396 0.2794)
			(stroke
				(width 0.1)
				(type default)
			)
			(layer "B.Fab")
		)
		(fp_line
			(start -0.67945 0.3048)
			(end -0.120396 0.3048)
			(stroke
				(width 0.1)
				(type default)
			)
			(layer "B.Fab")
		)
		(pad "1" smd circle
			(at 0.40005 0 270)
			(size 0 0)
			(layers "B.Cu" "B.Mask" "B.Paste")
			(net "FM_GPU_HSC_EN_BUF_R1")
		)
		(pad "2" smd circle
			(at -0.40005 0 270)
			(size 0 0)
			(layers "B.Cu" "B.Mask" "B.Paste")
			(net "GND")
		)
	)
	(footprint ""
		(layer "B.Cu")
		(at 179.091082 -422.273222 90)
		(property "Reference" "R2811"
			(at 0 0 90)
			(layer "B.SilkS")
			(hide yes)
			(effects
				(font
					(size 1.27 1.27)
				)
				(justify mirror)
			)
		)
		(property "Value" ""
			(at 0 0 90)
			(layer "B.Fab")
			(effects
				(font
					(size 1.27 1.27)
				)
				(justify mirror)
			)
		)
		(duplicate_pad_numbers_are_jumpers no)
		(fp_line
			(start 0.7874 -0.4064)
			(end -0.7874 -0.4064)
			(stroke
				(width 0.1524)
				(type default)
			)
			(layer "B.SilkS")
		)
		(fp_line
			(start -0.7874 -0.4064)
			(end -0.7874 0.4064)
			(stroke
				(width 0.1524)
				(type default)
			)
			(layer "B.SilkS")
		)
		(fp_line
			(start 0.7874 0.4064)
			(end 0.7874 -0.4064)
			(stroke
				(width 0.1524)
				(type default)
			)
			(layer "B.SilkS")
		)
		(fp_line
			(start -0.7874 0.4064)
			(end 0.7874 0.4064)
			(stroke
				(width 0.1524)
				(type default)
			)
			(layer "B.SilkS")
		)
		(fp_line
			(start 0.67945 -0.305054)
			(end 0.12065 -0.305054)
			(stroke
				(width 0.1)
				(type default)
			)
			(layer "B.Fab")
		)
		(fp_line
			(start 0.12065 -0.305054)
			(end 0.12065 -0.2794)
			(stroke
				(width 0.1)
				(type default)
			)
			(layer "B.Fab")
		)
		(fp_line
			(start -0.12065 -0.3048)
			(end -0.67945 -0.3048)
			(stroke
				(width 0.1)
				(type default)
			)
			(layer "B.Fab")
		)
		(fp_line
			(start -0.67945 -0.3048)
			(end -0.67945 0.3048)
			(stroke
				(width 0.1)
				(type default)
			)
			(layer "B.Fab")
		)
		(fp_line
			(start 0.12065 -0.2794)
			(end -0.12065 -0.2794)
			(stroke
				(width 0.1)
				(type default)
			)
			(layer "B.Fab")
		)
		(fp_line
			(start -0.12065 -0.2794)
			(end -0.12065 -0.3048)
			(stroke
				(width 0.1)
				(type default)
			)
			(layer "B.Fab")
		)
		(fp_line
			(start 0.12065 0.2794)
			(end 0.12065 0.3048)
			(stroke
				(width 0.1)
				(type default)
			)
			(layer "B.Fab")
		)
		(fp_line
			(start -0.120396 0.2794)
			(end 0.12065 0.2794)
			(stroke
				(width 0.1)
				(type default)
			)
			(layer "B.Fab")
		)
		(fp_line
			(start 0.67945 0.3048)
			(end 0.67945 -0.305054)
			(stroke
				(width 0.1)
				(type default)
			)
			(layer "B.Fab")
		)
		(fp_line
			(start 0.12065 0.3048)
			(end 0.67945 0.3048)
			(stroke
				(width 0.1)
				(type default)
			)
			(layer "B.Fab")
		)
		(fp_line
			(start -0.120396 0.3048)
			(end -0.120396 0.2794)
			(stroke
				(width 0.1)
				(type default)
			)
			(layer "B.Fab")
		)
		(fp_line
			(start -0.67945 0.3048)
			(end -0.120396 0.3048)
			(stroke
				(width 0.1)
				(type default)
			)
			(layer "B.Fab")
		)
		(pad "1" smd circle
			(at 0.40005 0 270)
			(size 0 0)
			(layers "B.Cu" "B.Mask" "B.Paste")
			(net "SMB_FAN_3V3AUX_BUF_SCL")
		)
		(pad "2" smd circle
			(at -0.40005 0 270)
			(size 0 0)
			(layers "B.Cu" "B.Mask" "B.Paste")
			(net "SMB_FAN_3V3AUX_BUF_R_SCL")
		)
	)
	(footprint ""
		(layer "B.Cu")
		(at 38.328346 -321.554856 -90)
		(property "Reference" "C58"
			(at 0 0 90)
			(layer "B.SilkS")
			(hide yes)
			(effects
				(font
					(size 1.27 1.27)
				)
				(justify mirror)
			)
		)
		(property "Value" ""
			(at 0 0 90)
			(layer "B.Fab")
			(effects
				(font
					(size 1.27 1.27)
				)
				(justify mirror)
			)
		)
		(duplicate_pad_numbers_are_jumpers no)
		(fp_line
			(start -1.524 0.762)
			(end 1.524 0.762)
			(stroke
				(width 0.1524)
				(type default)
			)
			(layer "B.SilkS")
		)
		(fp_line
			(start 1.524 0.762)
			(end 1.524 -0.762)
			(stroke
				(width 0.1524)
				(type default)
			)
			(layer "B.SilkS")
		)
		(fp_line
			(start -1.524 -0.762)
			(end -1.524 0.762)
			(stroke
				(width 0.1524)
				(type default)
			)
			(layer "B.SilkS")
		)
		(fp_line
			(start 1.524 -0.762)
			(end -1.524 -0.762)
			(stroke
				(width 0.1524)
				(type default)
			)
			(layer "B.SilkS")
		)
		(fp_line
			(start -1.1049 0.724916)
			(end -1.1049 -0.724916)
			(stroke
				(width 0.1)
				(type default)
			)
			(layer "B.Fab")
		)
		(fp_line
			(start 1.1049 0.724916)
			(end -1.1049 0.724916)
			(stroke
				(width 0.1)
				(type default)
			)
			(layer "B.Fab")
		)
		(fp_line
			(start -1.1049 -0.724916)
			(end 1.1049 -0.724916)
			(stroke
				(width 0.1)
				(type default)
			)
			(layer "B.Fab")
		)
		(fp_line
			(start 1.1049 -0.724916)
			(end 1.1049 0.724916)
			(stroke
				(width 0.1)
				(type default)
			)
			(layer "B.Fab")
		)
		(pad "1" smd rect
			(at 0.889 0 270)
			(size 1.016 1.27)
			(layers "B.Cu" "B.Mask" "B.Paste")
			(net "P12V_S3_AUX_CPU1_NVDIMM")
		)
		(pad "2" smd rect
			(at -0.889 0 270)
			(size 1.016 1.27)
			(layers "B.Cu" "B.Mask" "B.Paste")
			(net "GND")
		)
	)
	(footprint ""
		(layer "B.Cu")
		(at 432.562 -24.094948 -90)
		(property "Reference" "R1896"
			(at 0 0 90)
			(layer "B.SilkS")
			(hide yes)
			(effects
				(font
					(size 1.27 1.27)
				)
				(justify mirror)
			)
		)
		(property "Value" ""
			(at 0 0 90)
			(layer "B.Fab")
			(effects
				(font
					(size 1.27 1.27)
				)
				(justify mirror)
			)
		)
		(duplicate_pad_numbers_are_jumpers no)
		(fp_line
			(start -0.7874 0.4064)
			(end 0.7874 0.4064)
			(stroke
				(width 0.1524)
				(type default)
			)
			(layer "B.SilkS")
		)
		(fp_line
			(start 0.7874 0.4064)
			(end 0.7874 -0.4064)
			(stroke
				(width 0.1524)
				(type default)
			)
			(layer "B.SilkS")
		)
		(fp_line
			(start -0.7874 -0.4064)
			(end -0.7874 0.4064)
			(stroke
				(width 0.1524)
				(type default)
			)
			(layer "B.SilkS")
		)
		(fp_line
			(start 0.7874 -0.4064)
			(end -0.7874 -0.4064)
			(stroke
				(width 0.1524)
				(type default)
			)
			(layer "B.SilkS")
		)
		(fp_line
			(start -0.67945 0.3048)
			(end -0.120396 0.3048)
			(stroke
				(width 0.1)
				(type default)
			)
			(layer "B.Fab")
		)
		(fp_line
			(start -0.120396 0.3048)
			(end -0.120396 0.2794)
			(stroke
				(width 0.1)
				(type default)
			)
			(layer "B.Fab")
		)
		(fp_line
			(start 0.12065 0.3048)
			(end 0.67945 0.3048)
			(stroke
				(width 0.1)
				(type default)
			)
			(layer "B.Fab")
		)
		(fp_line
			(start 0.67945 0.3048)
			(end 0.67945 -0.305054)
			(stroke
				(width 0.1)
				(type default)
			)
			(layer "B.Fab")
		)
		(fp_line
			(start -0.120396 0.2794)
			(end 0.12065 0.2794)
			(stroke
				(width 0.1)
				(type default)
			)
			(layer "B.Fab")
		)
		(fp_line
			(start 0.12065 0.2794)
			(end 0.12065 0.3048)
			(stroke
				(width 0.1)
				(type default)
			)
			(layer "B.Fab")
		)
		(fp_line
			(start -0.12065 -0.2794)
			(end -0.12065 -0.3048)
			(stroke
				(width 0.1)
				(type default)
			)
			(layer "B.Fab")
		)
		(fp_line
			(start 0.12065 -0.2794)
			(end -0.12065 -0.2794)
			(stroke
				(width 0.1)
				(type default)
			)
			(layer "B.Fab")
		)
		(fp_line
			(start -0.67945 -0.3048)
			(end -0.67945 0.3048)
			(stroke
				(width 0.1)
				(type default)
			)
			(layer "B.Fab")
		)
		(fp_line
			(start -0.12065 -0.3048)
			(end -0.67945 -0.3048)
			(stroke
				(width 0.1)
				(type default)
			)
			(layer "B.Fab")
		)
		(fp_line
			(start 0.12065 -0.305054)
			(end 0.12065 -0.2794)
			(stroke
				(width 0.1)
				(type default)
			)
			(layer "B.Fab")
		)
		(fp_line
			(start 0.67945 -0.305054)
			(end 0.12065 -0.305054)
			(stroke
				(width 0.1)
				(type default)
			)
			(layer "B.Fab")
		)
		(pad "1" smd circle
			(at 0.40005 0 90)
			(size 0 0)
			(layers "B.Cu" "B.Mask" "B.Paste")
			(net "OCP_SFF_ISO_BIF0_EN")
		)
		(pad "2" smd circle
			(at -0.40005 0 90)
			(size 0 0)
			(layers "B.Cu" "B.Mask" "B.Paste")
			(net "GND")
		)
	)
	(footprint ""
		(layer "B.Cu")
		(at 238.14278 -245.730268)
		(property "Reference" "L17"
			(at 0 0 0)
			(layer "B.SilkS")
			(hide yes)
			(effects
				(font
					(size 1.27 1.27)
				)
				(justify mirror)
			)
		)
		(property "Value" ""
			(at 0 0 0)
			(layer "B.Fab")
			(effects
				(font
					(size 1.27 1.27)
				)
				(justify mirror)
			)
		)
		(duplicate_pad_numbers_are_jumpers no)
		(fp_line
			(start -1.63576 -0.8128)
			(end -1.63576 0.8128)
			(stroke
				(width 0.1524)
				(type default)
			)
			(layer "B.SilkS")
		)
		(fp_line
			(start -1.63576 0.8128)
			(end 1.63576 0.8128)
			(stroke
				(width 0.1524)
				(type default)
			)
			(layer "B.SilkS")
		)
		(fp_line
			(start 1.63576 -0.8128)
			(end -1.63576 -0.8128)
			(stroke
				(width 0.1524)
				(type default)
			)
			(layer "B.SilkS")
		)
		(fp_line
			(start 1.63576 -0.8128)
			(end 1.63576 0.8128)
			(stroke
				(width 0.1524)
				(type default)
			)
			(layer "B.SilkS")
		)
		(fp_line
			(start -1.560576 -0.738632)
			(end 1.56083 -0.738632)
			(stroke
				(width 0.1)
				(type default)
			)
			(layer "B.Fab")
		)
		(fp_line
			(start -1.560576 0.7366)
			(end -1.560576 -0.738632)
			(stroke
				(width 0.1)
				(type default)
			)
			(layer "B.Fab")
		)
		(fp_line
			(start -1.524 0.7366)
			(end -1.560576 0.7366)
			(stroke
				(width 0.1)
				(type default)
			)
			(layer "B.Fab")
		)
		(fp_line
			(start 1.524 0.7366)
			(end -1.524 0.7366)
			(stroke
				(width 0.1)
				(type default)
			)
			(layer "B.Fab")
		)
		(fp_line
			(start 1.56083 -0.738632)
			(end 1.56083 0.7366)
			(stroke
				(width 0.1)
				(type default)
			)
			(layer "B.Fab")
		)
		(fp_line
			(start 1.56083 0.7366)
			(end 1.524 0.7366)
			(stroke
				(width 0.1)
				(type default)
			)
			(layer "B.Fab")
		)
		(pad "1" smd rect
			(at 0.94996 0)
			(size 1.1176 1.3716)
			(layers "B.Cu" "B.Mask" "B.Paste")
			(net "P3V3_AUX")
		)
		(pad "2" smd rect
			(at -0.94996 0)
			(size 1.1176 1.3716)
			(layers "B.Cu" "B.Mask" "B.Paste")
			(net "VFG3P3_CLK_GEN")
		)
	)
	(footprint ""
		(layer "B.Cu")
		(at 305.420014 -321.549776 -90)
		(property "Reference" "C3"
			(at 0 0 90)
			(layer "B.SilkS")
			(hide yes)
			(effects
				(font
					(size 1.27 1.27)
				)
				(justify mirror)
			)
		)
		(property "Value" ""
			(at 0 0 90)
			(layer "B.Fab")
			(effects
				(font
					(size 1.27 1.27)
				)
				(justify mirror)
			)
		)
		(duplicate_pad_numbers_are_jumpers no)
		(fp_line
			(start -1.524 0.762)
			(end 1.524 0.762)
			(stroke
				(width 0.1524)
				(type default)
			)
			(layer "B.SilkS")
		)
		(fp_line
			(start 1.524 0.762)
			(end 1.524 -0.762)
			(stroke
				(width 0.1524)
				(type default)
			)
			(layer "B.SilkS")
		)
		(fp_line
			(start -1.524 -0.762)
			(end -1.524 0.762)
			(stroke
				(width 0.1524)
				(type default)
			)
			(layer "B.SilkS")
		)
		(fp_line
			(start 1.524 -0.762)
			(end -1.524 -0.762)
			(stroke
				(width 0.1524)
				(type default)
			)
			(layer "B.SilkS")
		)
		(fp_line
			(start -1.1049 0.724916)
			(end -1.1049 -0.724916)
			(stroke
				(width 0.1)
				(type default)
			)
			(layer "B.Fab")
		)
		(fp_line
			(start 1.1049 0.724916)
			(end -1.1049 0.724916)
			(stroke
				(width 0.1)
				(type default)
			)
			(layer "B.Fab")
		)
		(fp_line
			(start -1.1049 -0.724916)
			(end 1.1049 -0.724916)
			(stroke
				(width 0.1)
				(type default)
			)
			(layer "B.Fab")
		)
		(fp_line
			(start 1.1049 -0.724916)
			(end 1.1049 0.724916)
			(stroke
				(width 0.1)
				(type default)
			)
			(layer "B.Fab")
		)
		(pad "1" smd rect
			(at 0.889 0 270)
			(size 1.016 1.27)
			(layers "B.Cu" "B.Mask" "B.Paste")
			(net "P12V_S3_AUX_CPU0_NVDIMM")
		)
		(pad "2" smd rect
			(at -0.889 0 270)
			(size 1.016 1.27)
			(layers "B.Cu" "B.Mask" "B.Paste")
			(net "GND")
		)
	)
	(footprint ""
		(layer "B.Cu")
		(at 114.13744 -413.093408)
		(property "Reference" "C2335"
			(at 0 0 0)
			(layer "B.SilkS")
			(hide yes)
			(effects
				(font
					(size 1.27 1.27)
				)
				(justify mirror)
			)
		)
		(property "Value" ""
			(at 0 0 0)
			(layer "B.Fab")
			(effects
				(font
					(size 1.27 1.27)
				)
				(justify mirror)
			)
		)
		(duplicate_pad_numbers_are_jumpers no)
		(fp_line
			(start -0.7874 -0.4064)
			(end -0.7874 0.4064)
			(stroke
				(width 0.1524)
				(type default)
			)
			(layer "B.SilkS")
		)
		(fp_line
			(start -0.7874 0.4064)
			(end 0.7874 0.4064)
			(stroke
				(width 0.1524)
				(type default)
			)
			(layer "B.SilkS")
		)
		(fp_line
			(start 0.7874 -0.4064)
			(end -0.7874 -0.4064)
			(stroke
				(width 0.1524)
				(type default)
			)
			(layer "B.SilkS")
		)
		(fp_line
			(start 0.7874 0.4064)
			(end 0.7874 -0.4064)
			(stroke
				(width 0.1524)
				(type default)
			)
			(layer "B.SilkS")
		)
		(fp_line
			(start -0.67945 -0.3048)
			(end -0.67945 0.3048)
			(stroke
				(width 0.1)
				(type default)
			)
			(layer "B.Fab")
		)
		(fp_line
			(start -0.67945 0.3048)
			(end -0.120396 0.3048)
			(stroke
				(width 0.1)
				(type default)
			)
			(layer "B.Fab")
		)
		(fp_line
			(start -0.12065 -0.3048)
			(end -0.67945 -0.3048)
			(stroke
				(width 0.1)
				(type default)
			)
			(layer "B.Fab")
		)
		(fp_line
			(start -0.12065 -0.2794)
			(end -0.12065 -0.3048)
			(stroke
				(width 0.1)
				(type default)
			)
			(layer "B.Fab")
		)
		(fp_line
			(start -0.120396 0.2794)
			(end 0.12065 0.2794)
			(stroke
				(width 0.1)
				(type default)
			)
			(layer "B.Fab")
		)
		(fp_line
			(start -0.120396 0.3048)
			(end -0.120396 0.2794)
			(stroke
				(width 0.1)
				(type default)
			)
			(layer "B.Fab")
		)
		(fp_line
			(start 0.12065 -0.305054)
			(end 0.12065 -0.2794)
			(stroke
				(width 0.1)
				(type default)
			)
			(layer "B.Fab")
		)
		(fp_line
			(start 0.12065 -0.2794)
			(end -0.12065 -0.2794)
			(stroke
				(width 0.1)
				(type default)
			)
			(layer "B.Fab")
		)
		(fp_line
			(start 0.12065 0.2794)
			(end 0.12065 0.3048)
			(stroke
				(width 0.1)
				(type default)
			)
			(layer "B.Fab")
		)
		(fp_line
			(start 0.12065 0.3048)
			(end 0.67945 0.3048)
			(stroke
				(width 0.1)
				(type default)
			)
			(layer "B.Fab")
		)
		(fp_line
			(start 0.67945 -0.305054)
			(end 0.12065 -0.305054)
			(stroke
				(width 0.1)
				(type default)
			)
			(layer "B.Fab")
		)
		(fp_line
			(start 0.67945 0.3048)
			(end 0.67945 -0.305054)
			(stroke
				(width 0.1)
				(type default)
			)
			(layer "B.Fab")
		)
		(pad "1" smd circle
			(at 0.40005 0 180)
			(size 0 0)
			(layers "B.Cu" "B.Mask" "B.Paste")
			(net "P3V3_9ZXL045_VDDR")
		)
		(pad "2" smd circle
			(at -0.40005 0 180)
			(size 0 0)
			(layers "B.Cu" "B.Mask" "B.Paste")
			(net "GND")
		)
	)
	(footprint ""
		(layer "B.Cu")
		(at 119.95912 -248.49836 -90)
		(property "Reference" "C447"
			(at 0 0 90)
			(layer "B.SilkS")
			(hide yes)
			(effects
				(font
					(size 1.27 1.27)
				)
				(justify mirror)
			)
		)
		(property "Value" ""
			(at 0 0 90)
			(layer "B.Fab")
			(effects
				(font
					(size 1.27 1.27)
				)
				(justify mirror)
			)
		)
		(duplicate_pad_numbers_are_jumpers no)
		(fp_line
			(start -1.524 0.762)
			(end 1.524 0.762)
			(stroke
				(width 0.1524)
				(type default)
			)
			(layer "B.SilkS")
		)
		(fp_line
			(start 1.524 0.762)
			(end 1.524 -0.762)
			(stroke
				(width 0.1524)
				(type default)
			)
			(layer "B.SilkS")
		)
		(fp_line
			(start -1.524 -0.762)
			(end -1.524 0.762)
			(stroke
				(width 0.1524)
				(type default)
			)
			(layer "B.SilkS")
		)
		(fp_line
			(start 1.524 -0.762)
			(end -1.524 -0.762)
			(stroke
				(width 0.1524)
				(type default)
			)
			(layer "B.SilkS")
		)
		(fp_line
			(start -1.1049 0.724916)
			(end -1.1049 -0.724916)
			(stroke
				(width 0.1)
				(type default)
			)
			(layer "B.Fab")
		)
		(fp_line
			(start 1.1049 0.724916)
			(end -1.1049 0.724916)
			(stroke
				(width 0.1)
				(type default)
			)
			(layer "B.Fab")
		)
		(fp_line
			(start -1.1049 -0.724916)
			(end 1.1049 -0.724916)
			(stroke
				(width 0.1)
				(type default)
			)
			(layer "B.Fab")
		)
		(fp_line
			(start 1.1049 -0.724916)
			(end 1.1049 0.724916)
			(stroke
				(width 0.1)
				(type default)
			)
			(layer "B.Fab")
		)
		(pad "1" smd rect
			(at 0.889 0 270)
			(size 1.016 1.27)
			(layers "B.Cu" "B.Mask" "B.Paste")
			(net "PVCCD_HV_CPU1")
		)
		(pad "2" smd rect
			(at -0.889 0 270)
			(size 1.016 1.27)
			(layers "B.Cu" "B.Mask" "B.Paste")
			(net "GND")
		)
	)
	(footprint ""
		(layer "B.Cu")
		(at 180.848 -18.710148 90)
		(property "Reference" "R2420"
			(at 0 0 90)
			(layer "B.SilkS")
			(hide yes)
			(effects
				(font
					(size 1.27 1.27)
				)
				(justify mirror)
			)
		)
		(property "Value" ""
			(at 0 0 90)
			(layer "B.Fab")
			(effects
				(font
					(size 1.27 1.27)
				)
				(justify mirror)
			)
		)
		(duplicate_pad_numbers_are_jumpers no)
		(fp_line
			(start 0.7874 -0.4064)
			(end -0.7874 -0.4064)
			(stroke
				(width 0.1524)
				(type default)
			)
			(layer "B.SilkS")
		)
		(fp_line
			(start -0.7874 -0.4064)
			(end -0.7874 0.4064)
			(stroke
				(width 0.1524)
				(type default)
			)
			(layer "B.SilkS")
		)
		(fp_line
			(start 0.7874 0.4064)
			(end 0.7874 -0.4064)
			(stroke
				(width 0.1524)
				(type default)
			)
			(layer "B.SilkS")
		)
		(fp_line
			(start -0.7874 0.4064)
			(end 0.7874 0.4064)
			(stroke
				(width 0.1524)
				(type default)
			)
			(layer "B.SilkS")
		)
		(fp_line
			(start 0.67945 -0.305054)
			(end 0.12065 -0.305054)
			(stroke
				(width 0.1)
				(type default)
			)
			(layer "B.Fab")
		)
		(fp_line
			(start 0.12065 -0.305054)
			(end 0.12065 -0.2794)
			(stroke
				(width 0.1)
				(type default)
			)
			(layer "B.Fab")
		)
		(fp_line
			(start -0.12065 -0.3048)
			(end -0.67945 -0.3048)
			(stroke
				(width 0.1)
				(type default)
			)
			(layer "B.Fab")
		)
		(fp_line
			(start -0.67945 -0.3048)
			(end -0.67945 0.3048)
			(stroke
				(width 0.1)
				(type default)
			)
			(layer "B.Fab")
		)
		(fp_line
			(start 0.12065 -0.2794)
			(end -0.12065 -0.2794)
			(stroke
				(width 0.1)
				(type default)
			)
			(layer "B.Fab")
		)
		(fp_line
			(start -0.12065 -0.2794)
			(end -0.12065 -0.3048)
			(stroke
				(width 0.1)
				(type default)
			)
			(layer "B.Fab")
		)
		(fp_line
			(start 0.12065 0.2794)
			(end 0.12065 0.3048)
			(stroke
				(width 0.1)
				(type default)
			)
			(layer "B.Fab")
		)
		(fp_line
			(start -0.120396 0.2794)
			(end 0.12065 0.2794)
			(stroke
				(width 0.1)
				(type default)
			)
			(layer "B.Fab")
		)
		(fp_line
			(start 0.67945 0.3048)
			(end 0.67945 -0.305054)
			(stroke
				(width 0.1)
				(type default)
			)
			(layer "B.Fab")
		)
		(fp_line
			(start 0.12065 0.3048)
			(end 0.67945 0.3048)
			(stroke
				(width 0.1)
				(type default)
			)
			(layer "B.Fab")
		)
		(fp_line
			(start -0.120396 0.3048)
			(end -0.120396 0.2794)
			(stroke
				(width 0.1)
				(type default)
			)
			(layer "B.Fab")
		)
		(fp_line
			(start -0.67945 0.3048)
			(end -0.120396 0.3048)
			(stroke
				(width 0.1)
				(type default)
			)
			(layer "B.Fab")
		)
		(pad "1" smd circle
			(at 0.40005 0 270)
			(size 0 0)
			(layers "B.Cu" "B.Mask" "B.Paste")
			(net "SMB_HOST_3V3AUX_SDA")
		)
		(pad "2" smd circle
			(at -0.40005 0 270)
			(size 0 0)
			(layers "B.Cu" "B.Mask" "B.Paste")
			(net "SMB_HOST_3V3AUX_SDA_R0")
		)
	)
	(footprint ""
		(layer "B.Cu")
		(at 364.342934 -255.853946 -90)
		(property "Reference" "C355"
			(at 0 0 90)
			(layer "B.SilkS")
			(hide yes)
			(effects
				(font
					(size 1.27 1.27)
				)
				(justify mirror)
			)
		)
		(property "Value" ""
			(at 0 0 90)
			(layer "B.Fab")
			(effects
				(font
					(size 1.27 1.27)
				)
				(justify mirror)
			)
		)
		(duplicate_pad_numbers_are_jumpers no)
		(fp_line
			(start -1.524 0.762)
			(end 1.524 0.762)
			(stroke
				(width 0.1524)
				(type default)
			)
			(layer "B.SilkS")
		)
		(fp_line
			(start 1.524 0.762)
			(end 1.524 -0.762)
			(stroke
				(width 0.1524)
				(type default)
			)
			(layer "B.SilkS")
		)
		(fp_line
			(start -1.524 -0.762)
			(end -1.524 0.762)
			(stroke
				(width 0.1524)
				(type default)
			)
			(layer "B.SilkS")
		)
		(fp_line
			(start 1.524 -0.762)
			(end -1.524 -0.762)
			(stroke
				(width 0.1524)
				(type default)
			)
			(layer "B.SilkS")
		)
		(fp_line
			(start -1.1049 0.724916)
			(end -1.1049 -0.724916)
			(stroke
				(width 0.1)
				(type default)
			)
			(layer "B.Fab")
		)
		(fp_line
			(start 1.1049 0.724916)
			(end -1.1049 0.724916)
			(stroke
				(width 0.1)
				(type default)
			)
			(layer "B.Fab")
		)
		(fp_line
			(start -1.1049 -0.724916)
			(end 1.1049 -0.724916)
			(stroke
				(width 0.1)
				(type default)
			)
			(layer "B.Fab")
		)
		(fp_line
			(start 1.1049 -0.724916)
			(end 1.1049 0.724916)
			(stroke
				(width 0.1)
				(type default)
			)
			(layer "B.Fab")
		)
		(pad "1" smd rect
			(at 0.889 0 270)
			(size 1.016 1.27)
			(layers "B.Cu" "B.Mask" "B.Paste")
			(net "PVCCIN_CPU0")
		)
		(pad "2" smd rect
			(at -0.889 0 270)
			(size 1.016 1.27)
			(layers "B.Cu" "B.Mask" "B.Paste")
			(net "GND")
		)
	)
	(footprint ""
		(layer "B.Cu")
		(at 113.78438 -361.764326)
		(property "Reference" "PR303"
			(at 0 0 0)
			(layer "B.SilkS")
			(hide yes)
			(effects
				(font
					(size 1.27 1.27)
				)
				(justify mirror)
			)
		)
		(property "Value" ""
			(at 0 0 0)
			(layer "B.Fab")
			(effects
				(font
					(size 1.27 1.27)
				)
				(justify mirror)
			)
		)
		(duplicate_pad_numbers_are_jumpers no)
		(fp_line
			(start -0.7874 -0.4064)
			(end -0.7874 0.4064)
			(stroke
				(width 0.1524)
				(type default)
			)
			(layer "B.SilkS")
		)
		(fp_line
			(start -0.7874 0.4064)
			(end 0.7874 0.4064)
			(stroke
				(width 0.1524)
				(type default)
			)
			(layer "B.SilkS")
		)
		(fp_line
			(start 0.7874 -0.4064)
			(end -0.7874 -0.4064)
			(stroke
				(width 0.1524)
				(type default)
			)
			(layer "B.SilkS")
		)
		(fp_line
			(start 0.7874 0.4064)
			(end 0.7874 -0.4064)
			(stroke
				(width 0.1524)
				(type default)
			)
			(layer "B.SilkS")
		)
		(fp_line
			(start -0.67945 -0.3048)
			(end -0.67945 0.3048)
			(stroke
				(width 0.1)
				(type default)
			)
			(layer "B.Fab")
		)
		(fp_line
			(start -0.67945 0.3048)
			(end -0.120396 0.3048)
			(stroke
				(width 0.1)
				(type default)
			)
			(layer "B.Fab")
		)
		(fp_line
			(start -0.12065 -0.3048)
			(end -0.67945 -0.3048)
			(stroke
				(width 0.1)
				(type default)
			)
			(layer "B.Fab")
		)
		(fp_line
			(start -0.12065 -0.2794)
			(end -0.12065 -0.3048)
			(stroke
				(width 0.1)
				(type default)
			)
			(layer "B.Fab")
		)
		(fp_line
			(start -0.120396 0.2794)
			(end 0.12065 0.2794)
			(stroke
				(width 0.1)
				(type default)
			)
			(layer "B.Fab")
		)
		(fp_line
			(start -0.120396 0.3048)
			(end -0.120396 0.2794)
			(stroke
				(width 0.1)
				(type default)
			)
			(layer "B.Fab")
		)
		(fp_line
			(start 0.12065 -0.305054)
			(end 0.12065 -0.2794)
			(stroke
				(width 0.1)
				(type default)
			)
			(layer "B.Fab")
		)
		(fp_line
			(start 0.12065 -0.2794)
			(end -0.12065 -0.2794)
			(stroke
				(width 0.1)
				(type default)
			)
			(layer "B.Fab")
		)
		(fp_line
			(start 0.12065 0.2794)
			(end 0.12065 0.3048)
			(stroke
				(width 0.1)
				(type default)
			)
			(layer "B.Fab")
		)
		(fp_line
			(start 0.12065 0.3048)
			(end 0.67945 0.3048)
			(stroke
				(width 0.1)
				(type default)
			)
			(layer "B.Fab")
		)
		(fp_line
			(start 0.67945 -0.305054)
			(end 0.12065 -0.305054)
			(stroke
				(width 0.1)
				(type default)
			)
			(layer "B.Fab")
		)
		(fp_line
			(start 0.67945 0.3048)
			(end 0.67945 -0.305054)
			(stroke
				(width 0.1)
				(type default)
			)
			(layer "B.Fab")
		)
		(pad "1" smd circle
			(at 0.40005 0 180)
			(size 0 0)
			(layers "B.Cu" "B.Mask" "B.Paste")
			(net "P12V_AUX")
		)
		(pad "2" smd circle
			(at -0.40005 0 180)
			(size 0 0)
			(layers "B.Cu" "B.Mask" "B.Paste")
			(net "PVCCIN_CPU1_VIN_CSNIN")
		)
	)
	(footprint ""
		(layer "B.Cu")
		(at 8.19277 -113.161826)
		(property "Reference" "R5238"
			(at 0 0 0)
			(layer "B.SilkS")
			(hide yes)
			(effects
				(font
					(size 1.27 1.27)
				)
				(justify mirror)
			)
		)
		(property "Value" ""
			(at 0 0 0)
			(layer "B.Fab")
			(effects
				(font
					(size 1.27 1.27)
				)
				(justify mirror)
			)
		)
		(duplicate_pad_numbers_are_jumpers no)
		(fp_line
			(start -0.7874 -0.4064)
			(end -0.7874 0.4064)
			(stroke
				(width 0.1524)
				(type default)
			)
			(layer "B.SilkS")
		)
		(fp_line
			(start -0.7874 0.4064)
			(end 0.7874 0.4064)
			(stroke
				(width 0.1524)
				(type default)
			)
			(layer "B.SilkS")
		)
		(fp_line
			(start 0.7874 -0.4064)
			(end -0.7874 -0.4064)
			(stroke
				(width 0.1524)
				(type default)
			)
			(layer "B.SilkS")
		)
		(fp_line
			(start 0.7874 0.4064)
			(end 0.7874 -0.4064)
			(stroke
				(width 0.1524)
				(type default)
			)
			(layer "B.SilkS")
		)
		(fp_line
			(start -0.67945 -0.3048)
			(end -0.67945 0.3048)
			(stroke
				(width 0.1)
				(type default)
			)
			(layer "B.Fab")
		)
		(fp_line
			(start -0.67945 0.3048)
			(end -0.120396 0.3048)
			(stroke
				(width 0.1)
				(type default)
			)
			(layer "B.Fab")
		)
		(fp_line
			(start -0.12065 -0.3048)
			(end -0.67945 -0.3048)
			(stroke
				(width 0.1)
				(type default)
			)
			(layer "B.Fab")
		)
		(fp_line
			(start -0.12065 -0.2794)
			(end -0.12065 -0.3048)
			(stroke
				(width 0.1)
				(type default)
			)
			(layer "B.Fab")
		)
		(fp_line
			(start -0.120396 0.2794)
			(end 0.12065 0.2794)
			(stroke
				(width 0.1)
				(type default)
			)
			(layer "B.Fab")
		)
		(fp_line
			(start -0.120396 0.3048)
			(end -0.120396 0.2794)
			(stroke
				(width 0.1)
				(type default)
			)
			(layer "B.Fab")
		)
		(fp_line
			(start 0.12065 -0.305054)
			(end 0.12065 -0.2794)
			(stroke
				(width 0.1)
				(type default)
			)
			(layer "B.Fab")
		)
		(fp_line
			(start 0.12065 -0.2794)
			(end -0.12065 -0.2794)
			(stroke
				(width 0.1)
				(type default)
			)
			(layer "B.Fab")
		)
		(fp_line
			(start 0.12065 0.2794)
			(end 0.12065 0.3048)
			(stroke
				(width 0.1)
				(type default)
			)
			(layer "B.Fab")
		)
		(fp_line
			(start 0.12065 0.3048)
			(end 0.67945 0.3048)
			(stroke
				(width 0.1)
				(type default)
			)
			(layer "B.Fab")
		)
		(fp_line
			(start 0.67945 -0.305054)
			(end 0.12065 -0.305054)
			(stroke
				(width 0.1)
				(type default)
			)
			(layer "B.Fab")
		)
		(fp_line
			(start 0.67945 0.3048)
			(end 0.67945 -0.305054)
			(stroke
				(width 0.1)
				(type default)
			)
			(layer "B.Fab")
		)
		(pad "1" smd circle
			(at 0.40005 0 180)
			(size 0 0)
			(layers "B.Cu" "B.Mask" "B.Paste")
			(net "PD_U5201_EQ")
		)
		(pad "2" smd circle
			(at -0.40005 0 180)
			(size 0 0)
			(layers "B.Cu" "B.Mask" "B.Paste")
			(net "GND")
		)
	)
	(footprint ""
		(layer "B.Cu")
		(at 107.457494 -259.53212 90)
		(property "Reference" "C457"
			(at 0 0 90)
			(layer "B.SilkS")
			(hide yes)
			(effects
				(font
					(size 1.27 1.27)
				)
				(justify mirror)
			)
		)
		(property "Value" ""
			(at 0 0 90)
			(layer "B.Fab")
			(effects
				(font
					(size 1.27 1.27)
				)
				(justify mirror)
			)
		)
		(duplicate_pad_numbers_are_jumpers no)
		(fp_line
			(start 1.524 -0.762)
			(end -1.524 -0.762)
			(stroke
				(width 0.1524)
				(type default)
			)
			(layer "B.SilkS")
		)
		(fp_line
			(start -1.524 -0.762)
			(end -1.524 0.762)
			(stroke
				(width 0.1524)
				(type default)
			)
			(layer "B.SilkS")
		)
		(fp_line
			(start 1.524 0.762)
			(end 1.524 -0.762)
			(stroke
				(width 0.1524)
				(type default)
			)
			(layer "B.SilkS")
		)
		(fp_line
			(start -1.524 0.762)
			(end 1.524 0.762)
			(stroke
				(width 0.1524)
				(type default)
			)
			(layer "B.SilkS")
		)
		(fp_line
			(start 1.1049 -0.724916)
			(end 1.1049 0.724916)
			(stroke
				(width 0.1)
				(type default)
			)
			(layer "B.Fab")
		)
		(fp_line
			(start -1.1049 -0.724916)
			(end 1.1049 -0.724916)
			(stroke
				(width 0.1)
				(type default)
			)
			(layer "B.Fab")
		)
		(fp_line
			(start 1.1049 0.724916)
			(end -1.1049 0.724916)
			(stroke
				(width 0.1)
				(type default)
			)
			(layer "B.Fab")
		)
		(fp_line
			(start -1.1049 0.724916)
			(end -1.1049 -0.724916)
			(stroke
				(width 0.1)
				(type default)
			)
			(layer "B.Fab")
		)
		(pad "1" smd rect
			(at 0.889 0 90)
			(size 1.016 1.27)
			(layers "B.Cu" "B.Mask" "B.Paste")
			(net "PVCCFA_EHV_FIVRA_CPU1")
		)
		(pad "2" smd rect
			(at -0.889 0 90)
			(size 1.016 1.27)
			(layers "B.Cu" "B.Mask" "B.Paste")
			(net "GND")
		)
	)
	(footprint ""
		(layer "B.Cu")
		(at 34.846514 -165.841426)
		(property "Reference" "PR1400"
			(at 0 0 0)
			(layer "B.SilkS")
			(hide yes)
			(effects
				(font
					(size 1.27 1.27)
				)
				(justify mirror)
			)
		)
		(property "Value" ""
			(at 0 0 0)
			(layer "B.Fab")
			(effects
				(font
					(size 1.27 1.27)
				)
				(justify mirror)
			)
		)
		(duplicate_pad_numbers_are_jumpers no)
		(fp_line
			(start -0.7874 -0.4064)
			(end -0.7874 0.4064)
			(stroke
				(width 0.1524)
				(type default)
			)
			(layer "B.SilkS")
		)
		(fp_line
			(start -0.7874 0.4064)
			(end 0.7874 0.4064)
			(stroke
				(width 0.1524)
				(type default)
			)
			(layer "B.SilkS")
		)
		(fp_line
			(start 0.7874 -0.4064)
			(end -0.7874 -0.4064)
			(stroke
				(width 0.1524)
				(type default)
			)
			(layer "B.SilkS")
		)
		(fp_line
			(start 0.7874 0.4064)
			(end 0.7874 -0.4064)
			(stroke
				(width 0.1524)
				(type default)
			)
			(layer "B.SilkS")
		)
		(fp_line
			(start -0.67945 -0.3048)
			(end -0.67945 0.3048)
			(stroke
				(width 0.1)
				(type default)
			)
			(layer "B.Fab")
		)
		(fp_line
			(start -0.67945 0.3048)
			(end -0.120396 0.3048)
			(stroke
				(width 0.1)
				(type default)
			)
			(layer "B.Fab")
		)
		(fp_line
			(start -0.12065 -0.3048)
			(end -0.67945 -0.3048)
			(stroke
				(width 0.1)
				(type default)
			)
			(layer "B.Fab")
		)
		(fp_line
			(start -0.12065 -0.2794)
			(end -0.12065 -0.3048)
			(stroke
				(width 0.1)
				(type default)
			)
			(layer "B.Fab")
		)
		(fp_line
			(start -0.120396 0.2794)
			(end 0.12065 0.2794)
			(stroke
				(width 0.1)
				(type default)
			)
			(layer "B.Fab")
		)
		(fp_line
			(start -0.120396 0.3048)
			(end -0.120396 0.2794)
			(stroke
				(width 0.1)
				(type default)
			)
			(layer "B.Fab")
		)
		(fp_line
			(start 0.12065 -0.305054)
			(end 0.12065 -0.2794)
			(stroke
				(width 0.1)
				(type default)
			)
			(layer "B.Fab")
		)
		(fp_line
			(start 0.12065 -0.2794)
			(end -0.12065 -0.2794)
			(stroke
				(width 0.1)
				(type default)
			)
			(layer "B.Fab")
		)
		(fp_line
			(start 0.12065 0.2794)
			(end 0.12065 0.3048)
			(stroke
				(width 0.1)
				(type default)
			)
			(layer "B.Fab")
		)
		(fp_line
			(start 0.12065 0.3048)
			(end 0.67945 0.3048)
			(stroke
				(width 0.1)
				(type default)
			)
			(layer "B.Fab")
		)
		(fp_line
			(start 0.67945 -0.305054)
			(end 0.12065 -0.305054)
			(stroke
				(width 0.1)
				(type default)
			)
			(layer "B.Fab")
		)
		(fp_line
			(start 0.67945 0.3048)
			(end 0.67945 -0.305054)
			(stroke
				(width 0.1)
				(type default)
			)
			(layer "B.Fab")
		)
		(pad "1" smd circle
			(at 0.40005 0 180)
			(size 0 0)
			(layers "B.Cu" "B.Mask" "B.Paste")
			(net "P12V_AUX_CPU1_DIMM_ISEN_P")
		)
		(pad "2" smd circle
			(at -0.40005 0 180)
			(size 0 0)
			(layers "B.Cu" "B.Mask" "B.Paste")
			(net "PVCCD_HV_CPU1_ISENSE_P")
		)
	)
	(footprint ""
		(layer "B.Cu")
		(at 28.574238 -130.877056 -90)
		(property "Reference" "PR667"
			(at 0 0 90)
			(layer "B.SilkS")
			(hide yes)
			(effects
				(font
					(size 1.27 1.27)
				)
				(justify mirror)
			)
		)
		(property "Value" ""
			(at 0 0 90)
			(layer "B.Fab")
			(effects
				(font
					(size 1.27 1.27)
				)
				(justify mirror)
			)
		)
		(duplicate_pad_numbers_are_jumpers no)
		(fp_line
			(start -0.7874 0.4064)
			(end 0.7874 0.4064)
			(stroke
				(width 0.1524)
				(type default)
			)
			(layer "B.SilkS")
		)
		(fp_line
			(start 0.7874 0.4064)
			(end 0.7874 -0.4064)
			(stroke
				(width 0.1524)
				(type default)
			)
			(layer "B.SilkS")
		)
		(fp_line
			(start -0.7874 -0.4064)
			(end -0.7874 0.4064)
			(stroke
				(width 0.1524)
				(type default)
			)
			(layer "B.SilkS")
		)
		(fp_line
			(start 0.7874 -0.4064)
			(end -0.7874 -0.4064)
			(stroke
				(width 0.1524)
				(type default)
			)
			(layer "B.SilkS")
		)
		(fp_line
			(start -0.67945 0.3048)
			(end -0.120396 0.3048)
			(stroke
				(width 0.1)
				(type default)
			)
			(layer "B.Fab")
		)
		(fp_line
			(start -0.120396 0.3048)
			(end -0.120396 0.2794)
			(stroke
				(width 0.1)
				(type default)
			)
			(layer "B.Fab")
		)
		(fp_line
			(start 0.12065 0.3048)
			(end 0.67945 0.3048)
			(stroke
				(width 0.1)
				(type default)
			)
			(layer "B.Fab")
		)
		(fp_line
			(start 0.67945 0.3048)
			(end 0.67945 -0.305054)
			(stroke
				(width 0.1)
				(type default)
			)
			(layer "B.Fab")
		)
		(fp_line
			(start -0.120396 0.2794)
			(end 0.12065 0.2794)
			(stroke
				(width 0.1)
				(type default)
			)
			(layer "B.Fab")
		)
		(fp_line
			(start 0.12065 0.2794)
			(end 0.12065 0.3048)
			(stroke
				(width 0.1)
				(type default)
			)
			(layer "B.Fab")
		)
		(fp_line
			(start -0.12065 -0.2794)
			(end -0.12065 -0.3048)
			(stroke
				(width 0.1)
				(type default)
			)
			(layer "B.Fab")
		)
		(fp_line
			(start 0.12065 -0.2794)
			(end -0.12065 -0.2794)
			(stroke
				(width 0.1)
				(type default)
			)
			(layer "B.Fab")
		)
		(fp_line
			(start -0.67945 -0.3048)
			(end -0.67945 0.3048)
			(stroke
				(width 0.1)
				(type default)
			)
			(layer "B.Fab")
		)
		(fp_line
			(start -0.12065 -0.3048)
			(end -0.67945 -0.3048)
			(stroke
				(width 0.1)
				(type default)
			)
			(layer "B.Fab")
		)
		(fp_line
			(start 0.12065 -0.305054)
			(end 0.12065 -0.2794)
			(stroke
				(width 0.1)
				(type default)
			)
			(layer "B.Fab")
		)
		(fp_line
			(start 0.67945 -0.305054)
			(end 0.12065 -0.305054)
			(stroke
				(width 0.1)
				(type default)
			)
			(layer "B.Fab")
		)
		(pad "1" smd circle
			(at 0.40005 0 90)
			(size 0 0)
			(layers "B.Cu" "B.Mask" "B.Paste")
			(net "PVCCFA_EHV_CPU1_BTSEN")
		)
		(pad "2" smd circle
			(at -0.40005 0 90)
			(size 0 0)
			(layers "B.Cu" "B.Mask" "B.Paste")
			(net "GND")
		)
	)
	(footprint ""
		(layer "B.Cu")
		(at 178.1556 -112.57534 90)
		(property "Reference" "C1931"
			(at 0 0 90)
			(layer "B.SilkS")
			(hide yes)
			(effects
				(font
					(size 1.27 1.27)
				)
				(justify mirror)
			)
		)
		(property "Value" ""
			(at 0 0 90)
			(layer "B.Fab")
			(effects
				(font
					(size 1.27 1.27)
				)
				(justify mirror)
			)
		)
		(duplicate_pad_numbers_are_jumpers no)
		(fp_line
			(start 0.69215 -0.2921)
			(end -0.69215 -0.2921)
			(stroke
				(width 0.1524)
				(type default)
			)
			(layer "B.SilkS")
		)
		(fp_line
			(start -0.69215 -0.2921)
			(end -0.69215 0.2921)
			(stroke
				(width 0.1524)
				(type default)
			)
			(layer "B.SilkS")
		)
		(fp_line
			(start 0.69215 0.2921)
			(end 0.69215 -0.2921)
			(stroke
				(width 0.1524)
				(type default)
			)
			(layer "B.SilkS")
		)
		(fp_line
			(start -0.69215 0.2921)
			(end 0.69215 0.2921)
			(stroke
				(width 0.1524)
				(type default)
			)
			(layer "B.SilkS")
		)
		(fp_line
			(start 0.51435 -0.2794)
			(end -0.51435 -0.2794)
			(stroke
				(width 0.1)
				(type default)
			)
			(layer "B.Fab")
		)
		(fp_line
			(start -0.51435 -0.2794)
			(end -0.51435 0.2794)
			(stroke
				(width 0.1)
				(type default)
			)
			(layer "B.Fab")
		)
		(fp_line
			(start 0.51435 0.2794)
			(end 0.51435 -0.2794)
			(stroke
				(width 0.1)
				(type default)
			)
			(layer "B.Fab")
		)
		(fp_line
			(start -0.51435 0.2794)
			(end 0.51435 0.2794)
			(stroke
				(width 0.1)
				(type default)
			)
			(layer "B.Fab")
		)
		(pad "1" smd circle
			(at 0.40005 0 270)
			(size 0 0)
			(layers "B.Cu" "B.Mask" "B.Paste")
			(net "VCC_PLD_CORE")
		)
		(pad "2" smd circle
			(at -0.40005 0 270)
			(size 0 0)
			(layers "B.Cu" "B.Mask" "B.Paste")
			(net "GND")
		)
		(zone
			(layer "B.Cu")
			(hatch none 0.5)
			(connect_pads
				(clearance 0)
			)
			(min_thickness 0.25)
			(keepout
				(tracks not_allowed)
				(vias allowed)
				(pads allowed)
				(copperpour not_allowed)
				(footprints allowed)
			)
			(placement
				(enabled no)
				(sheetname "")
			)
			(fill
				(thermal_gap 0.5)
				(thermal_bridge_width 0.5)
				(island_removal_mode 0)
			)
			(polygon
				(pts
					(xy 178.24323 -112.76584) (xy 178.301396 -112.6744) (xy 178.301396 -112.47501) (xy 178.24323 -112.38484)
					(xy 178.06797 -112.38484) (xy 178.00955 -112.47501) (xy 178.00955 -112.6744) (xy 178.067716 -112.76584)
				)
			)
		)
	)
	(footprint ""
		(layer "B.Cu")
		(at 410.902658 -153.147522 180)
		(property "Reference" "PC1900"
			(at 0 0 0)
			(layer "B.SilkS")
			(hide yes)
			(effects
				(font
					(size 1.27 1.27)
				)
				(justify mirror)
			)
		)
		(property "Value" ""
			(at 0 0 0)
			(layer "B.Fab")
			(effects
				(font
					(size 1.27 1.27)
				)
				(justify mirror)
			)
		)
		(duplicate_pad_numbers_are_jumpers no)
		(fp_line
			(start 4.533392 2.249932)
			(end 4.533392 -2.249932)
			(stroke
				(width 0.1524)
				(type default)
			)
			(layer "B.SilkS")
		)
		(fp_line
			(start 4.533392 -2.249932)
			(end -4.533392 -2.249932)
			(stroke
				(width 0.1524)
				(type default)
			)
			(layer "B.SilkS")
		)
		(fp_line
			(start -4.533392 2.249932)
			(end 4.533392 2.249932)
			(stroke
				(width 0.1524)
				(type default)
			)
			(layer "B.SilkS")
		)
		(fp_line
			(start -4.533392 -2.249932)
			(end -4.533392 2.249932)
			(stroke
				(width 0.1524)
				(type default)
			)
			(layer "B.SilkS")
		)
		(fp_rect
			(start 5.39242 -2.326132)
			(end 4.533392 2.326132)
			(stroke
				(width 0)
				(type default)
			)
			(fill yes)
			(layer "B.SilkS")
		)
		(fp_line
			(start 3.750056 2.249932)
			(end 3.750056 -2.249932)
			(stroke
				(width 0.1)
				(type default)
			)
			(layer "B.Fab")
		)
		(fp_line
			(start 3.750056 -2.249932)
			(end -3.750056 -2.249932)
			(stroke
				(width 0.1)
				(type default)
			)
			(layer "B.Fab")
		)
		(fp_line
			(start -3.750056 2.249932)
			(end 3.750056 2.249932)
			(stroke
				(width 0.1)
				(type default)
			)
			(layer "B.Fab")
		)
		(fp_line
			(start -3.750056 -2.249932)
			(end -3.750056 2.249932)
			(stroke
				(width 0.1)
				(type default)
			)
			(layer "B.Fab")
		)
		(fp_text user "+"
			(at 6.322314 0.786384 90)
			(unlocked yes)
			(layer "B.SilkS")
			(effects
				(font
					(size 1.905 1.4224)
					(thickness 0.1524)
				)
				(justify left mirror)
			)
		)
		(fp_text user "-"
			(at -4.8514 -0.14605 180)
			(unlocked yes)
			(layer "B.SilkS")
			(effects
				(font
					(size 1.905 1.4224)
					(thickness 0.1524)
				)
				(justify left mirror)
			)
		)
		(fp_text user "+"
			(at 6.322314 0.786384 90)
			(unlocked yes)
			(layer "B.Fab")
			(effects
				(font
					(size 1.905 1.4224)
					(thickness 0.1524)
				)
				(justify left mirror)
			)
		)
		(fp_text user "-"
			(at -4.8514 -0.14605 180)
			(unlocked yes)
			(layer "B.Fab")
			(effects
				(font
					(size 1.905 1.4224)
					(thickness 0.1524)
				)
				(justify left mirror)
			)
		)
		(pad "1" smd rect
			(at 3.199892 0)
			(size 2.413 2.8194)
			(layers "B.Cu" "B.Mask" "B.Paste")
			(net "PVCCFA_EHV_CPU0")
		)
		(pad "2" smd rect
			(at -3.199892 0)
			(size 2.413 2.8194)
			(layers "B.Cu" "B.Mask" "B.Paste")
			(net "GND")
		)
	)
	(footprint ""
		(layer "B.Cu")
		(at 68.29298 -189.374272 -90)
		(property "Reference" "R290"
			(at 0 0 90)
			(layer "B.SilkS")
			(hide yes)
			(effects
				(font
					(size 1.27 1.27)
				)
				(justify mirror)
			)
		)
		(property "Value" ""
			(at 0 0 90)
			(layer "B.Fab")
			(effects
				(font
					(size 1.27 1.27)
				)
				(justify mirror)
			)
		)
		(duplicate_pad_numbers_are_jumpers no)
		(fp_line
			(start -0.7874 0.4064)
			(end 0.7874 0.4064)
			(stroke
				(width 0.1524)
				(type default)
			)
			(layer "B.SilkS")
		)
		(fp_line
			(start 0.7874 0.4064)
			(end 0.7874 -0.4064)
			(stroke
				(width 0.1524)
				(type default)
			)
			(layer "B.SilkS")
		)
		(fp_line
			(start -0.7874 -0.4064)
			(end -0.7874 0.4064)
			(stroke
				(width 0.1524)
				(type default)
			)
			(layer "B.SilkS")
		)
		(fp_line
			(start 0.7874 -0.4064)
			(end -0.7874 -0.4064)
			(stroke
				(width 0.1524)
				(type default)
			)
			(layer "B.SilkS")
		)
		(fp_line
			(start -0.67945 0.3048)
			(end -0.120396 0.3048)
			(stroke
				(width 0.1)
				(type default)
			)
			(layer "B.Fab")
		)
		(fp_line
			(start -0.120396 0.3048)
			(end -0.120396 0.2794)
			(stroke
				(width 0.1)
				(type default)
			)
			(layer "B.Fab")
		)
		(fp_line
			(start 0.12065 0.3048)
			(end 0.67945 0.3048)
			(stroke
				(width 0.1)
				(type default)
			)
			(layer "B.Fab")
		)
		(fp_line
			(start 0.67945 0.3048)
			(end 0.67945 -0.305054)
			(stroke
				(width 0.1)
				(type default)
			)
			(layer "B.Fab")
		)
		(fp_line
			(start -0.120396 0.2794)
			(end 0.12065 0.2794)
			(stroke
				(width 0.1)
				(type default)
			)
			(layer "B.Fab")
		)
		(fp_line
			(start 0.12065 0.2794)
			(end 0.12065 0.3048)
			(stroke
				(width 0.1)
				(type default)
			)
			(layer "B.Fab")
		)
		(fp_line
			(start -0.12065 -0.2794)
			(end -0.12065 -0.3048)
			(stroke
				(width 0.1)
				(type default)
			)
			(layer "B.Fab")
		)
		(fp_line
			(start 0.12065 -0.2794)
			(end -0.12065 -0.2794)
			(stroke
				(width 0.1)
				(type default)
			)
			(layer "B.Fab")
		)
		(fp_line
			(start -0.67945 -0.3048)
			(end -0.67945 0.3048)
			(stroke
				(width 0.1)
				(type default)
			)
			(layer "B.Fab")
		)
		(fp_line
			(start -0.12065 -0.3048)
			(end -0.67945 -0.3048)
			(stroke
				(width 0.1)
				(type default)
			)
			(layer "B.Fab")
		)
		(fp_line
			(start 0.12065 -0.305054)
			(end 0.12065 -0.2794)
			(stroke
				(width 0.1)
				(type default)
			)
			(layer "B.Fab")
		)
		(fp_line
			(start 0.67945 -0.305054)
			(end 0.12065 -0.305054)
			(stroke
				(width 0.1)
				(type default)
			)
			(layer "B.Fab")
		)
		(pad "1" smd circle
			(at 0.40005 0 90)
			(size 0 0)
			(layers "B.Cu" "B.Mask" "B.Paste")
			(net "GND")
		)
		(pad "2" smd circle
			(at -0.40005 0 90)
			(size 0 0)
			(layers "B.Cu" "B.Mask" "B.Paste")
			(net "PD_CPU1_DMIMODE_OVERRIDE")
		)
	)
	(footprint ""
		(layer "B.Cu")
		(at 321.369182 -39.574724 45)
		(property "Reference" "R1659"
			(at 0 0 45)
			(layer "B.SilkS")
			(hide yes)
			(effects
				(font
					(size 1.27 1.27)
				)
				(justify mirror)
			)
		)
		(property "Value" ""
			(at 0 0 45)
			(layer "B.Fab")
			(effects
				(font
					(size 1.27 1.27)
				)
				(justify mirror)
			)
		)
		(duplicate_pad_numbers_are_jumpers no)
		(fp_line
			(start -0.787389 -0.406267)
			(end -0.787389 0.406267)
			(stroke
				(width 0.1524)
				(type default)
			)
			(layer "B.SilkS")
		)
		(fp_line
			(start -0.787389 0.406267)
			(end 0.787389 0.406267)
			(stroke
				(width 0.1524)
				(type default)
			)
			(layer "B.SilkS")
		)
		(fp_line
			(start 0.787389 -0.406267)
			(end -0.787389 -0.406267)
			(stroke
				(width 0.1524)
				(type default)
			)
			(layer "B.SilkS")
		)
		(fp_line
			(start 0.787389 0.406267)
			(end 0.787389 -0.406267)
			(stroke
				(width 0.1524)
				(type default)
			)
			(layer "B.SilkS")
		)
		(fp_line
			(start -0.679446 -0.30479)
			(end -0.679446 0.30479)
			(stroke
				(width 0.1)
				(type default)
			)
			(layer "B.Fab")
		)
		(fp_line
			(start -0.120515 -0.30479)
			(end -0.679446 -0.30479)
			(stroke
				(width 0.1)
				(type default)
			)
			(layer "B.Fab")
		)
		(fp_line
			(start -0.120695 -0.279466)
			(end -0.120515 -0.30479)
			(stroke
				(width 0.1)
				(type default)
			)
			(layer "B.Fab")
		)
		(fp_line
			(start -0.679446 0.30479)
			(end -0.120515 0.30479)
			(stroke
				(width 0.1)
				(type default)
			)
			(layer "B.Fab")
		)
		(fp_line
			(start 0.120695 -0.304969)
			(end 0.120695 -0.279466)
			(stroke
				(width 0.1)
				(type default)
			)
			(layer "B.Fab")
		)
		(fp_line
			(start 0.120695 -0.279466)
			(end -0.120695 -0.279466)
			(stroke
				(width 0.1)
				(type default)
			)
			(layer "B.Fab")
		)
		(fp_line
			(start -0.120335 0.279466)
			(end 0.120695 0.279466)
			(stroke
				(width 0.1)
				(type default)
			)
			(layer "B.Fab")
		)
		(fp_line
			(start -0.120515 0.30479)
			(end -0.120335 0.279466)
			(stroke
				(width 0.1)
				(type default)
			)
			(layer "B.Fab")
		)
		(fp_line
			(start 0.679446 -0.305149)
			(end 0.120695 -0.304969)
			(stroke
				(width 0.1)
				(type default)
			)
			(layer "B.Fab")
		)
		(fp_line
			(start 0.120695 0.279466)
			(end 0.120515 0.30479)
			(stroke
				(width 0.1)
				(type default)
			)
			(layer "B.Fab")
		)
		(fp_line
			(start 0.120515 0.30479)
			(end 0.679446 0.30479)
			(stroke
				(width 0.1)
				(type default)
			)
			(layer "B.Fab")
		)
		(fp_line
			(start 0.679446 0.30479)
			(end 0.679446 -0.305149)
			(stroke
				(width 0.1)
				(type default)
			)
			(layer "B.Fab")
		)
		(pad "1" smd circle
			(at 0.40005 0 225)
			(size 0 0)
			(layers "B.Cu" "B.Mask" "B.Paste")
			(net "FM_PMBUS_ALERT_B_EN")
		)
		(pad "2" smd circle
			(at -0.40005 0 225)
			(size 0 0)
			(layers "B.Cu" "B.Mask" "B.Paste")
			(net "P3V3_AUX")
		)
	)
	(footprint ""
		(layer "B.Cu")
		(at 446.55105 -10.594086 -90)
		(property "Reference" "R409"
			(at 0 0 90)
			(layer "B.SilkS")
			(hide yes)
			(effects
				(font
					(size 1.27 1.27)
				)
				(justify mirror)
			)
		)
		(property "Value" ""
			(at 0 0 90)
			(layer "B.Fab")
			(effects
				(font
					(size 1.27 1.27)
				)
				(justify mirror)
			)
		)
		(duplicate_pad_numbers_are_jumpers no)
		(fp_line
			(start -0.7874 0.4064)
			(end 0.7874 0.4064)
			(stroke
				(width 0.1524)
				(type default)
			)
			(layer "B.SilkS")
		)
		(fp_line
			(start 0.7874 0.4064)
			(end 0.7874 -0.4064)
			(stroke
				(width 0.1524)
				(type default)
			)
			(layer "B.SilkS")
		)
		(fp_line
			(start -0.7874 -0.4064)
			(end -0.7874 0.4064)
			(stroke
				(width 0.1524)
				(type default)
			)
			(layer "B.SilkS")
		)
		(fp_line
			(start 0.7874 -0.4064)
			(end -0.7874 -0.4064)
			(stroke
				(width 0.1524)
				(type default)
			)
			(layer "B.SilkS")
		)
		(fp_line
			(start -0.67945 0.3048)
			(end -0.120396 0.3048)
			(stroke
				(width 0.1)
				(type default)
			)
			(layer "B.Fab")
		)
		(fp_line
			(start -0.120396 0.3048)
			(end -0.120396 0.2794)
			(stroke
				(width 0.1)
				(type default)
			)
			(layer "B.Fab")
		)
		(fp_line
			(start 0.12065 0.3048)
			(end 0.67945 0.3048)
			(stroke
				(width 0.1)
				(type default)
			)
			(layer "B.Fab")
		)
		(fp_line
			(start 0.67945 0.3048)
			(end 0.67945 -0.305054)
			(stroke
				(width 0.1)
				(type default)
			)
			(layer "B.Fab")
		)
		(fp_line
			(start -0.120396 0.2794)
			(end 0.12065 0.2794)
			(stroke
				(width 0.1)
				(type default)
			)
			(layer "B.Fab")
		)
		(fp_line
			(start 0.12065 0.2794)
			(end 0.12065 0.3048)
			(stroke
				(width 0.1)
				(type default)
			)
			(layer "B.Fab")
		)
		(fp_line
			(start -0.12065 -0.2794)
			(end -0.12065 -0.3048)
			(stroke
				(width 0.1)
				(type default)
			)
			(layer "B.Fab")
		)
		(fp_line
			(start 0.12065 -0.2794)
			(end -0.12065 -0.2794)
			(stroke
				(width 0.1)
				(type default)
			)
			(layer "B.Fab")
		)
		(fp_line
			(start -0.67945 -0.3048)
			(end -0.67945 0.3048)
			(stroke
				(width 0.1)
				(type default)
			)
			(layer "B.Fab")
		)
		(fp_line
			(start -0.12065 -0.3048)
			(end -0.67945 -0.3048)
			(stroke
				(width 0.1)
				(type default)
			)
			(layer "B.Fab")
		)
		(fp_line
			(start 0.12065 -0.305054)
			(end 0.12065 -0.2794)
			(stroke
				(width 0.1)
				(type default)
			)
			(layer "B.Fab")
		)
		(fp_line
			(start 0.67945 -0.305054)
			(end 0.12065 -0.305054)
			(stroke
				(width 0.1)
				(type default)
			)
			(layer "B.Fab")
		)
		(pad "1" smd circle
			(at 0.40005 0 90)
			(size 0 0)
			(layers "B.Cu" "B.Mask" "B.Paste")
			(net "P3V3_OCP_SFF")
		)
		(pad "2" smd circle
			(at -0.40005 0 90)
			(size 0 0)
			(layers "B.Cu" "B.Mask" "B.Paste")
			(net "OCP_SFF_ID0")
		)
	)
	(footprint ""
		(layer "B.Cu")
		(at 444.42126 -316.709044 90)
		(property "Reference" "R3887"
			(at 0 0 90)
			(layer "B.SilkS")
			(hide yes)
			(effects
				(font
					(size 1.27 1.27)
				)
				(justify mirror)
			)
		)
		(property "Value" ""
			(at 0 0 90)
			(layer "B.Fab")
			(effects
				(font
					(size 1.27 1.27)
				)
				(justify mirror)
			)
		)
		(duplicate_pad_numbers_are_jumpers no)
		(fp_line
			(start 0.7874 -0.4064)
			(end -0.7874 -0.4064)
			(stroke
				(width 0.1524)
				(type default)
			)
			(layer "B.SilkS")
		)
		(fp_line
			(start -0.7874 -0.4064)
			(end -0.7874 0.4064)
			(stroke
				(width 0.1524)
				(type default)
			)
			(layer "B.SilkS")
		)
		(fp_line
			(start 0.7874 0.4064)
			(end 0.7874 -0.4064)
			(stroke
				(width 0.1524)
				(type default)
			)
			(layer "B.SilkS")
		)
		(fp_line
			(start -0.7874 0.4064)
			(end 0.7874 0.4064)
			(stroke
				(width 0.1524)
				(type default)
			)
			(layer "B.SilkS")
		)
		(fp_line
			(start 0.67945 -0.305054)
			(end 0.12065 -0.305054)
			(stroke
				(width 0.1)
				(type default)
			)
			(layer "B.Fab")
		)
		(fp_line
			(start 0.12065 -0.305054)
			(end 0.12065 -0.2794)
			(stroke
				(width 0.1)
				(type default)
			)
			(layer "B.Fab")
		)
		(fp_line
			(start -0.12065 -0.3048)
			(end -0.67945 -0.3048)
			(stroke
				(width 0.1)
				(type default)
			)
			(layer "B.Fab")
		)
		(fp_line
			(start -0.67945 -0.3048)
			(end -0.67945 0.3048)
			(stroke
				(width 0.1)
				(type default)
			)
			(layer "B.Fab")
		)
		(fp_line
			(start 0.12065 -0.2794)
			(end -0.12065 -0.2794)
			(stroke
				(width 0.1)
				(type default)
			)
			(layer "B.Fab")
		)
		(fp_line
			(start -0.12065 -0.2794)
			(end -0.12065 -0.3048)
			(stroke
				(width 0.1)
				(type default)
			)
			(layer "B.Fab")
		)
		(fp_line
			(start 0.12065 0.2794)
			(end 0.12065 0.3048)
			(stroke
				(width 0.1)
				(type default)
			)
			(layer "B.Fab")
		)
		(fp_line
			(start -0.120396 0.2794)
			(end 0.12065 0.2794)
			(stroke
				(width 0.1)
				(type default)
			)
			(layer "B.Fab")
		)
		(fp_line
			(start 0.67945 0.3048)
			(end 0.67945 -0.305054)
			(stroke
				(width 0.1)
				(type default)
			)
			(layer "B.Fab")
		)
		(fp_line
			(start 0.12065 0.3048)
			(end 0.67945 0.3048)
			(stroke
				(width 0.1)
				(type default)
			)
			(layer "B.Fab")
		)
		(fp_line
			(start -0.120396 0.3048)
			(end -0.120396 0.2794)
			(stroke
				(width 0.1)
				(type default)
			)
			(layer "B.Fab")
		)
		(fp_line
			(start -0.67945 0.3048)
			(end -0.120396 0.3048)
			(stroke
				(width 0.1)
				(type default)
			)
			(layer "B.Fab")
		)
		(pad "1" smd circle
			(at 0.40005 0 270)
			(size 0 0)
			(layers "B.Cu" "B.Mask" "B.Paste")
			(net "I3C_SPD_DDREFGH_CPU0_LVC1_SCL_4")
		)
		(pad "2" smd circle
			(at -0.40005 0 270)
			(size 0 0)
			(layers "B.Cu" "B.Mask" "B.Paste")
			(net "I3C_SPD_DDREFGH_CPU0_LVC1_SCL")
		)
	)
	(footprint ""
		(layer "B.Cu")
		(at 45.872146 -319.268856 180)
		(property "Reference" "C59"
			(at 0 0 0)
			(layer "B.SilkS")
			(hide yes)
			(effects
				(font
					(size 1.27 1.27)
				)
				(justify mirror)
			)
		)
		(property "Value" ""
			(at 0 0 0)
			(layer "B.Fab")
			(effects
				(font
					(size 1.27 1.27)
				)
				(justify mirror)
			)
		)
		(duplicate_pad_numbers_are_jumpers no)
		(fp_line
			(start 0.7874 0.4064)
			(end 0.7874 -0.4064)
			(stroke
				(width 0.1524)
				(type default)
			)
			(layer "B.SilkS")
		)
		(fp_line
			(start 0.7874 -0.4064)
			(end -0.7874 -0.4064)
			(stroke
				(width 0.1524)
				(type default)
			)
			(layer "B.SilkS")
		)
		(fp_line
			(start -0.7874 0.4064)
			(end 0.7874 0.4064)
			(stroke
				(width 0.1524)
				(type default)
			)
			(layer "B.SilkS")
		)
		(fp_line
			(start -0.7874 -0.4064)
			(end -0.7874 0.4064)
			(stroke
				(width 0.1524)
				(type default)
			)
			(layer "B.SilkS")
		)
		(fp_line
			(start 0.67945 0.3048)
			(end 0.67945 -0.305054)
			(stroke
				(width 0.1)
				(type default)
			)
			(layer "B.Fab")
		)
		(fp_line
			(start 0.67945 -0.305054)
			(end 0.12065 -0.305054)
			(stroke
				(width 0.1)
				(type default)
			)
			(layer "B.Fab")
		)
		(fp_line
			(start 0.12065 0.3048)
			(end 0.67945 0.3048)
			(stroke
				(width 0.1)
				(type default)
			)
			(layer "B.Fab")
		)
		(fp_line
			(start 0.12065 0.2794)
			(end 0.12065 0.3048)
			(stroke
				(width 0.1)
				(type default)
			)
			(layer "B.Fab")
		)
		(fp_line
			(start 0.12065 -0.2794)
			(end -0.12065 -0.2794)
			(stroke
				(width 0.1)
				(type default)
			)
			(layer "B.Fab")
		)
		(fp_line
			(start 0.12065 -0.305054)
			(end 0.12065 -0.2794)
			(stroke
				(width 0.1)
				(type default)
			)
			(layer "B.Fab")
		)
		(fp_line
			(start -0.120396 0.3048)
			(end -0.120396 0.2794)
			(stroke
				(width 0.1)
				(type default)
			)
			(layer "B.Fab")
		)
		(fp_line
			(start -0.120396 0.2794)
			(end 0.12065 0.2794)
			(stroke
				(width 0.1)
				(type default)
			)
			(layer "B.Fab")
		)
		(fp_line
			(start -0.12065 -0.2794)
			(end -0.12065 -0.3048)
			(stroke
				(width 0.1)
				(type default)
			)
			(layer "B.Fab")
		)
		(fp_line
			(start -0.12065 -0.3048)
			(end -0.67945 -0.3048)
			(stroke
				(width 0.1)
				(type default)
			)
			(layer "B.Fab")
		)
		(fp_line
			(start -0.67945 0.3048)
			(end -0.120396 0.3048)
			(stroke
				(width 0.1)
				(type default)
			)
			(layer "B.Fab")
		)
		(fp_line
			(start -0.67945 -0.3048)
			(end -0.67945 0.3048)
			(stroke
				(width 0.1)
				(type default)
			)
			(layer "B.Fab")
		)
		(pad "1" smd circle
			(at 0.40005 0)
			(size 0 0)
			(layers "B.Cu" "B.Mask" "B.Paste")
			(net "P3V3_AUX")
		)
		(pad "2" smd circle
			(at -0.40005 0)
			(size 0 0)
			(layers "B.Cu" "B.Mask" "B.Paste")
			(net "GND")
		)
	)
	(footprint ""
		(layer "B.Cu")
		(at 24.327866 -193.152776 -90)
		(property "Reference" "R701"
			(at 0 0 90)
			(layer "B.SilkS")
			(hide yes)
			(effects
				(font
					(size 1.27 1.27)
				)
				(justify mirror)
			)
		)
		(property "Value" ""
			(at 0 0 90)
			(layer "B.Fab")
			(effects
				(font
					(size 1.27 1.27)
				)
				(justify mirror)
			)
		)
		(duplicate_pad_numbers_are_jumpers no)
		(fp_line
			(start -0.7874 0.4064)
			(end 0.7874 0.4064)
			(stroke
				(width 0.1524)
				(type default)
			)
			(layer "B.SilkS")
		)
		(fp_line
			(start 0.7874 0.4064)
			(end 0.7874 -0.4064)
			(stroke
				(width 0.1524)
				(type default)
			)
			(layer "B.SilkS")
		)
		(fp_line
			(start -0.7874 -0.4064)
			(end -0.7874 0.4064)
			(stroke
				(width 0.1524)
				(type default)
			)
			(layer "B.SilkS")
		)
		(fp_line
			(start 0.7874 -0.4064)
			(end -0.7874 -0.4064)
			(stroke
				(width 0.1524)
				(type default)
			)
			(layer "B.SilkS")
		)
		(fp_line
			(start -0.67945 0.3048)
			(end -0.120396 0.3048)
			(stroke
				(width 0.1)
				(type default)
			)
			(layer "B.Fab")
		)
		(fp_line
			(start -0.120396 0.3048)
			(end -0.120396 0.2794)
			(stroke
				(width 0.1)
				(type default)
			)
			(layer "B.Fab")
		)
		(fp_line
			(start 0.12065 0.3048)
			(end 0.67945 0.3048)
			(stroke
				(width 0.1)
				(type default)
			)
			(layer "B.Fab")
		)
		(fp_line
			(start 0.67945 0.3048)
			(end 0.67945 -0.305054)
			(stroke
				(width 0.1)
				(type default)
			)
			(layer "B.Fab")
		)
		(fp_line
			(start -0.120396 0.2794)
			(end 0.12065 0.2794)
			(stroke
				(width 0.1)
				(type default)
			)
			(layer "B.Fab")
		)
		(fp_line
			(start 0.12065 0.2794)
			(end 0.12065 0.3048)
			(stroke
				(width 0.1)
				(type default)
			)
			(layer "B.Fab")
		)
		(fp_line
			(start -0.12065 -0.2794)
			(end -0.12065 -0.3048)
			(stroke
				(width 0.1)
				(type default)
			)
			(layer "B.Fab")
		)
		(fp_line
			(start 0.12065 -0.2794)
			(end -0.12065 -0.2794)
			(stroke
				(width 0.1)
				(type default)
			)
			(layer "B.Fab")
		)
		(fp_line
			(start -0.67945 -0.3048)
			(end -0.67945 0.3048)
			(stroke
				(width 0.1)
				(type default)
			)
			(layer "B.Fab")
		)
		(fp_line
			(start -0.12065 -0.3048)
			(end -0.67945 -0.3048)
			(stroke
				(width 0.1)
				(type default)
			)
			(layer "B.Fab")
		)
		(fp_line
			(start 0.12065 -0.305054)
			(end 0.12065 -0.2794)
			(stroke
				(width 0.1)
				(type default)
			)
			(layer "B.Fab")
		)
		(fp_line
			(start 0.67945 -0.305054)
			(end 0.12065 -0.305054)
			(stroke
				(width 0.1)
				(type default)
			)
			(layer "B.Fab")
		)
		(pad "1" smd circle
			(at 0.40005 0 90)
			(size 0 0)
			(layers "B.Cu" "B.Mask" "B.Paste")
			(net "RST_PLD_CPU1_DRAM_CD_N")
		)
		(pad "2" smd circle
			(at -0.40005 0 90)
			(size 0 0)
			(layers "B.Cu" "B.Mask" "B.Paste")
			(net "GND")
		)
	)
	(footprint ""
		(layer "B.Cu")
		(at 422.218104 -137.658094 -90)
		(property "Reference" "PR436"
			(at 0 0 90)
			(layer "B.SilkS")
			(hide yes)
			(effects
				(font
					(size 1.27 1.27)
				)
				(justify mirror)
			)
		)
		(property "Value" ""
			(at 0 0 90)
			(layer "B.Fab")
			(effects
				(font
					(size 1.27 1.27)
				)
				(justify mirror)
			)
		)
		(duplicate_pad_numbers_are_jumpers no)
		(fp_line
			(start -0.7874 0.4064)
			(end 0.7874 0.4064)
			(stroke
				(width 0.1524)
				(type default)
			)
			(layer "B.SilkS")
		)
		(fp_line
			(start 0.7874 0.4064)
			(end 0.7874 -0.4064)
			(stroke
				(width 0.1524)
				(type default)
			)
			(layer "B.SilkS")
		)
		(fp_line
			(start -0.7874 -0.4064)
			(end -0.7874 0.4064)
			(stroke
				(width 0.1524)
				(type default)
			)
			(layer "B.SilkS")
		)
		(fp_line
			(start 0.7874 -0.4064)
			(end -0.7874 -0.4064)
			(stroke
				(width 0.1524)
				(type default)
			)
			(layer "B.SilkS")
		)
		(fp_line
			(start -0.67945 0.3048)
			(end -0.120396 0.3048)
			(stroke
				(width 0.1)
				(type default)
			)
			(layer "B.Fab")
		)
		(fp_line
			(start -0.120396 0.3048)
			(end -0.120396 0.2794)
			(stroke
				(width 0.1)
				(type default)
			)
			(layer "B.Fab")
		)
		(fp_line
			(start 0.12065 0.3048)
			(end 0.67945 0.3048)
			(stroke
				(width 0.1)
				(type default)
			)
			(layer "B.Fab")
		)
		(fp_line
			(start 0.67945 0.3048)
			(end 0.67945 -0.305054)
			(stroke
				(width 0.1)
				(type default)
			)
			(layer "B.Fab")
		)
		(fp_line
			(start -0.120396 0.2794)
			(end 0.12065 0.2794)
			(stroke
				(width 0.1)
				(type default)
			)
			(layer "B.Fab")
		)
		(fp_line
			(start 0.12065 0.2794)
			(end 0.12065 0.3048)
			(stroke
				(width 0.1)
				(type default)
			)
			(layer "B.Fab")
		)
		(fp_line
			(start -0.12065 -0.2794)
			(end -0.12065 -0.3048)
			(stroke
				(width 0.1)
				(type default)
			)
			(layer "B.Fab")
		)
		(fp_line
			(start 0.12065 -0.2794)
			(end -0.12065 -0.2794)
			(stroke
				(width 0.1)
				(type default)
			)
			(layer "B.Fab")
		)
		(fp_line
			(start -0.67945 -0.3048)
			(end -0.67945 0.3048)
			(stroke
				(width 0.1)
				(type default)
			)
			(layer "B.Fab")
		)
		(fp_line
			(start -0.12065 -0.3048)
			(end -0.67945 -0.3048)
			(stroke
				(width 0.1)
				(type default)
			)
			(layer "B.Fab")
		)
		(fp_line
			(start 0.12065 -0.305054)
			(end 0.12065 -0.2794)
			(stroke
				(width 0.1)
				(type default)
			)
			(layer "B.Fab")
		)
		(fp_line
			(start 0.67945 -0.305054)
			(end 0.12065 -0.305054)
			(stroke
				(width 0.1)
				(type default)
			)
			(layer "B.Fab")
		)
		(pad "1" smd circle
			(at 0.40005 0 90)
			(size 0 0)
			(layers "B.Cu" "B.Mask" "B.Paste")
			(net "PVCCFA_EHV_CPU0_BTSEN")
		)
		(pad "2" smd circle
			(at -0.40005 0 90)
			(size 0 0)
			(layers "B.Cu" "B.Mask" "B.Paste")
			(net "GND")
		)
	)
	(footprint ""
		(layer "B.Cu")
		(at 41.830244 -99.75723 -90)
		(property "Reference" "R3939"
			(at 0 0 90)
			(layer "B.SilkS")
			(hide yes)
			(effects
				(font
					(size 1.27 1.27)
				)
				(justify mirror)
			)
		)
		(property "Value" ""
			(at 0 0 90)
			(layer "B.Fab")
			(effects
				(font
					(size 1.27 1.27)
				)
				(justify mirror)
			)
		)
		(duplicate_pad_numbers_are_jumpers no)
		(fp_line
			(start -0.7874 0.4064)
			(end 0.7874 0.4064)
			(stroke
				(width 0.1524)
				(type default)
			)
			(layer "B.SilkS")
		)
		(fp_line
			(start 0.7874 0.4064)
			(end 0.7874 -0.4064)
			(stroke
				(width 0.1524)
				(type default)
			)
			(layer "B.SilkS")
		)
		(fp_line
			(start -0.7874 -0.4064)
			(end -0.7874 0.4064)
			(stroke
				(width 0.1524)
				(type default)
			)
			(layer "B.SilkS")
		)
		(fp_line
			(start 0.7874 -0.4064)
			(end -0.7874 -0.4064)
			(stroke
				(width 0.1524)
				(type default)
			)
			(layer "B.SilkS")
		)
		(fp_line
			(start -0.67945 0.3048)
			(end -0.120396 0.3048)
			(stroke
				(width 0.1)
				(type default)
			)
			(layer "B.Fab")
		)
		(fp_line
			(start -0.120396 0.3048)
			(end -0.120396 0.2794)
			(stroke
				(width 0.1)
				(type default)
			)
			(layer "B.Fab")
		)
		(fp_line
			(start 0.12065 0.3048)
			(end 0.67945 0.3048)
			(stroke
				(width 0.1)
				(type default)
			)
			(layer "B.Fab")
		)
		(fp_line
			(start 0.67945 0.3048)
			(end 0.67945 -0.305054)
			(stroke
				(width 0.1)
				(type default)
			)
			(layer "B.Fab")
		)
		(fp_line
			(start -0.120396 0.2794)
			(end 0.12065 0.2794)
			(stroke
				(width 0.1)
				(type default)
			)
			(layer "B.Fab")
		)
		(fp_line
			(start 0.12065 0.2794)
			(end 0.12065 0.3048)
			(stroke
				(width 0.1)
				(type default)
			)
			(layer "B.Fab")
		)
		(fp_line
			(start -0.12065 -0.2794)
			(end -0.12065 -0.3048)
			(stroke
				(width 0.1)
				(type default)
			)
			(layer "B.Fab")
		)
		(fp_line
			(start 0.12065 -0.2794)
			(end -0.12065 -0.2794)
			(stroke
				(width 0.1)
				(type default)
			)
			(layer "B.Fab")
		)
		(fp_line
			(start -0.67945 -0.3048)
			(end -0.67945 0.3048)
			(stroke
				(width 0.1)
				(type default)
			)
			(layer "B.Fab")
		)
		(fp_line
			(start -0.12065 -0.3048)
			(end -0.67945 -0.3048)
			(stroke
				(width 0.1)
				(type default)
			)
			(layer "B.Fab")
		)
		(fp_line
			(start 0.12065 -0.305054)
			(end 0.12065 -0.2794)
			(stroke
				(width 0.1)
				(type default)
			)
			(layer "B.Fab")
		)
		(fp_line
			(start 0.67945 -0.305054)
			(end 0.12065 -0.305054)
			(stroke
				(width 0.1)
				(type default)
			)
			(layer "B.Fab")
		)
		(pad "1" smd rect
			(at 0.40005 0 270)
			(size 0.4572 0.508)
			(layers "B.Cu" "B.Mask" "B.Paste")
			(net "P12V_E1S_0_ISENSE_MAM_MAM")
		)
		(pad "2" smd rect
			(at -0.40005 0 270)
			(size 0.4572 0.508)
			(layers "B.Cu" "B.Mask" "B.Paste")
			(net "P12V_E1S_0_ISENSE_MAM")
		)
	)
	(footprint ""
		(layer "B.Cu")
		(at 407.91257 -158.714948 180)
		(property "Reference" "PC1"
			(at 0 0 0)
			(layer "B.SilkS")
			(hide yes)
			(effects
				(font
					(size 1.27 1.27)
				)
				(justify mirror)
			)
		)
		(property "Value" ""
			(at 0 0 0)
			(layer "B.Fab")
			(effects
				(font
					(size 1.27 1.27)
				)
				(justify mirror)
			)
		)
		(duplicate_pad_numbers_are_jumpers no)
		(fp_line
			(start 1.524 0.762)
			(end 1.524 -0.762)
			(stroke
				(width 0.1524)
				(type default)
			)
			(layer "B.SilkS")
		)
		(fp_line
			(start 1.524 -0.762)
			(end -1.524 -0.762)
			(stroke
				(width 0.1524)
				(type default)
			)
			(layer "B.SilkS")
		)
		(fp_line
			(start -1.524 0.762)
			(end 1.524 0.762)
			(stroke
				(width 0.1524)
				(type default)
			)
			(layer "B.SilkS")
		)
		(fp_line
			(start -1.524 -0.762)
			(end -1.524 0.762)
			(stroke
				(width 0.1524)
				(type default)
			)
			(layer "B.SilkS")
		)
		(fp_line
			(start 1.1049 0.724916)
			(end -1.1049 0.724916)
			(stroke
				(width 0.1)
				(type default)
			)
			(layer "B.Fab")
		)
		(fp_line
			(start 1.1049 -0.724916)
			(end 1.1049 0.724916)
			(stroke
				(width 0.1)
				(type default)
			)
			(layer "B.Fab")
		)
		(fp_line
			(start -1.1049 0.724916)
			(end -1.1049 -0.724916)
			(stroke
				(width 0.1)
				(type default)
			)
			(layer "B.Fab")
		)
		(fp_line
			(start -1.1049 -0.724916)
			(end 1.1049 -0.724916)
			(stroke
				(width 0.1)
				(type default)
			)
			(layer "B.Fab")
		)
		(pad "1" smd rect
			(at 0.889 0 180)
			(size 1.016 1.27)
			(layers "B.Cu" "B.Mask" "B.Paste")
			(net "PVCCD_HV_CPU0")
		)
		(pad "2" smd rect
			(at -0.889 0 180)
			(size 1.016 1.27)
			(layers "B.Cu" "B.Mask" "B.Paste")
			(net "GND")
		)
	)
	(footprint ""
		(layer "B.Cu")
		(at 16.208502 -98.669348)
		(property "Reference" "C2032"
			(at 0 0 0)
			(layer "B.SilkS")
			(hide yes)
			(effects
				(font
					(size 1.27 1.27)
				)
				(justify mirror)
			)
		)
		(property "Value" ""
			(at 0 0 0)
			(layer "B.Fab")
			(effects
				(font
					(size 1.27 1.27)
				)
				(justify mirror)
			)
		)
		(duplicate_pad_numbers_are_jumpers no)
		(fp_line
			(start -0.7874 -0.4064)
			(end -0.7874 0.4064)
			(stroke
				(width 0.1524)
				(type default)
			)
			(layer "B.SilkS")
		)
		(fp_line
			(start -0.7874 0.4064)
			(end 0.7874 0.4064)
			(stroke
				(width 0.1524)
				(type default)
			)
			(layer "B.SilkS")
		)
		(fp_line
			(start 0.7874 -0.4064)
			(end -0.7874 -0.4064)
			(stroke
				(width 0.1524)
				(type default)
			)
			(layer "B.SilkS")
		)
		(fp_line
			(start 0.7874 0.4064)
			(end 0.7874 -0.4064)
			(stroke
				(width 0.1524)
				(type default)
			)
			(layer "B.SilkS")
		)
		(fp_line
			(start -0.67945 -0.3048)
			(end -0.67945 0.3048)
			(stroke
				(width 0.1)
				(type default)
			)
			(layer "B.Fab")
		)
		(fp_line
			(start -0.67945 0.3048)
			(end -0.120396 0.3048)
			(stroke
				(width 0.1)
				(type default)
			)
			(layer "B.Fab")
		)
		(fp_line
			(start -0.12065 -0.3048)
			(end -0.67945 -0.3048)
			(stroke
				(width 0.1)
				(type default)
			)
			(layer "B.Fab")
		)
		(fp_line
			(start -0.12065 -0.2794)
			(end -0.12065 -0.3048)
			(stroke
				(width 0.1)
				(type default)
			)
			(layer "B.Fab")
		)
		(fp_line
			(start -0.120396 0.2794)
			(end 0.12065 0.2794)
			(stroke
				(width 0.1)
				(type default)
			)
			(layer "B.Fab")
		)
		(fp_line
			(start -0.120396 0.3048)
			(end -0.120396 0.2794)
			(stroke
				(width 0.1)
				(type default)
			)
			(layer "B.Fab")
		)
		(fp_line
			(start 0.12065 -0.305054)
			(end 0.12065 -0.2794)
			(stroke
				(width 0.1)
				(type default)
			)
			(layer "B.Fab")
		)
		(fp_line
			(start 0.12065 -0.2794)
			(end -0.12065 -0.2794)
			(stroke
				(width 0.1)
				(type default)
			)
			(layer "B.Fab")
		)
		(fp_line
			(start 0.12065 0.2794)
			(end 0.12065 0.3048)
			(stroke
				(width 0.1)
				(type default)
			)
			(layer "B.Fab")
		)
		(fp_line
			(start 0.12065 0.3048)
			(end 0.67945 0.3048)
			(stroke
				(width 0.1)
				(type default)
			)
			(layer "B.Fab")
		)
		(fp_line
			(start 0.67945 -0.305054)
			(end 0.12065 -0.305054)
			(stroke
				(width 0.1)
				(type default)
			)
			(layer "B.Fab")
		)
		(fp_line
			(start 0.67945 0.3048)
			(end 0.67945 -0.305054)
			(stroke
				(width 0.1)
				(type default)
			)
			(layer "B.Fab")
		)
		(pad "1" smd circle
			(at 0.40005 0 180)
			(size 0 0)
			(layers "B.Cu" "B.Mask" "B.Paste")
			(net "P3V3_AUX_USB_HUB")
		)
		(pad "2" smd circle
			(at -0.40005 0 180)
			(size 0 0)
			(layers "B.Cu" "B.Mask" "B.Paste")
			(net "GND")
		)
	)
	(footprint ""
		(layer "B.Cu")
		(at 63.017908 -258.465066 -90)
		(property "Reference" "C454"
			(at 0 0 90)
			(layer "B.SilkS")
			(hide yes)
			(effects
				(font
					(size 1.27 1.27)
				)
				(justify mirror)
			)
		)
		(property "Value" ""
			(at 0 0 90)
			(layer "B.Fab")
			(effects
				(font
					(size 1.27 1.27)
				)
				(justify mirror)
			)
		)
		(duplicate_pad_numbers_are_jumpers no)
		(fp_line
			(start -1.524 0.762)
			(end 1.524 0.762)
			(stroke
				(width 0.1524)
				(type default)
			)
			(layer "B.SilkS")
		)
		(fp_line
			(start 1.524 0.762)
			(end 1.524 -0.762)
			(stroke
				(width 0.1524)
				(type default)
			)
			(layer "B.SilkS")
		)
		(fp_line
			(start -1.524 -0.762)
			(end -1.524 0.762)
			(stroke
				(width 0.1524)
				(type default)
			)
			(layer "B.SilkS")
		)
		(fp_line
			(start 1.524 -0.762)
			(end -1.524 -0.762)
			(stroke
				(width 0.1524)
				(type default)
			)
			(layer "B.SilkS")
		)
		(fp_line
			(start -1.1049 0.724916)
			(end -1.1049 -0.724916)
			(stroke
				(width 0.1)
				(type default)
			)
			(layer "B.Fab")
		)
		(fp_line
			(start 1.1049 0.724916)
			(end -1.1049 0.724916)
			(stroke
				(width 0.1)
				(type default)
			)
			(layer "B.Fab")
		)
		(fp_line
			(start -1.1049 -0.724916)
			(end 1.1049 -0.724916)
			(stroke
				(width 0.1)
				(type default)
			)
			(layer "B.Fab")
		)
		(fp_line
			(start 1.1049 -0.724916)
			(end 1.1049 0.724916)
			(stroke
				(width 0.1)
				(type default)
			)
			(layer "B.Fab")
		)
		(pad "1" smd rect
			(at 0.889 0 270)
			(size 1.016 1.27)
			(layers "B.Cu" "B.Mask" "B.Paste")
			(net "PVCCFA_EHV_FIVRA_CPU1")
		)
		(pad "2" smd rect
			(at -0.889 0 270)
			(size 1.016 1.27)
			(layers "B.Cu" "B.Mask" "B.Paste")
			(net "GND")
		)
	)
	(footprint ""
		(layer "B.Cu")
		(at 241.3254 -422.9862 90)
		(property "Reference" "R2803"
			(at 0 0 90)
			(layer "B.SilkS")
			(hide yes)
			(effects
				(font
					(size 1.27 1.27)
				)
				(justify mirror)
			)
		)
		(property "Value" ""
			(at 0 0 90)
			(layer "B.Fab")
			(effects
				(font
					(size 1.27 1.27)
				)
				(justify mirror)
			)
		)
		(duplicate_pad_numbers_are_jumpers no)
		(fp_line
			(start 0.7874 -0.4064)
			(end -0.7874 -0.4064)
			(stroke
				(width 0.1524)
				(type default)
			)
			(layer "B.SilkS")
		)
		(fp_line
			(start -0.7874 -0.4064)
			(end -0.7874 0.4064)
			(stroke
				(width 0.1524)
				(type default)
			)
			(layer "B.SilkS")
		)
		(fp_line
			(start 0.7874 0.4064)
			(end 0.7874 -0.4064)
			(stroke
				(width 0.1524)
				(type default)
			)
			(layer "B.SilkS")
		)
		(fp_line
			(start -0.7874 0.4064)
			(end 0.7874 0.4064)
			(stroke
				(width 0.1524)
				(type default)
			)
			(layer "B.SilkS")
		)
		(fp_line
			(start 0.67945 -0.305054)
			(end 0.12065 -0.305054)
			(stroke
				(width 0.1)
				(type default)
			)
			(layer "B.Fab")
		)
		(fp_line
			(start 0.12065 -0.305054)
			(end 0.12065 -0.2794)
			(stroke
				(width 0.1)
				(type default)
			)
			(layer "B.Fab")
		)
		(fp_line
			(start -0.12065 -0.3048)
			(end -0.67945 -0.3048)
			(stroke
				(width 0.1)
				(type default)
			)
			(layer "B.Fab")
		)
		(fp_line
			(start -0.67945 -0.3048)
			(end -0.67945 0.3048)
			(stroke
				(width 0.1)
				(type default)
			)
			(layer "B.Fab")
		)
		(fp_line
			(start 0.12065 -0.2794)
			(end -0.12065 -0.2794)
			(stroke
				(width 0.1)
				(type default)
			)
			(layer "B.Fab")
		)
		(fp_line
			(start -0.12065 -0.2794)
			(end -0.12065 -0.3048)
			(stroke
				(width 0.1)
				(type default)
			)
			(layer "B.Fab")
		)
		(fp_line
			(start 0.12065 0.2794)
			(end 0.12065 0.3048)
			(stroke
				(width 0.1)
				(type default)
			)
			(layer "B.Fab")
		)
		(fp_line
			(start -0.120396 0.2794)
			(end 0.12065 0.2794)
			(stroke
				(width 0.1)
				(type default)
			)
			(layer "B.Fab")
		)
		(fp_line
			(start 0.67945 0.3048)
			(end 0.67945 -0.305054)
			(stroke
				(width 0.1)
				(type default)
			)
			(layer "B.Fab")
		)
		(fp_line
			(start 0.12065 0.3048)
			(end 0.67945 0.3048)
			(stroke
				(width 0.1)
				(type default)
			)
			(layer "B.Fab")
		)
		(fp_line
			(start -0.120396 0.3048)
			(end -0.120396 0.2794)
			(stroke
				(width 0.1)
				(type default)
			)
			(layer "B.Fab")
		)
		(fp_line
			(start -0.67945 0.3048)
			(end -0.120396 0.3048)
			(stroke
				(width 0.1)
				(type default)
			)
			(layer "B.Fab")
		)
		(pad "1" smd circle
			(at 0.40005 0 270)
			(size 0 0)
			(layers "B.Cu" "B.Mask" "B.Paste")
			(net "FM_FAN_PWR_EN_R")
		)
		(pad "2" smd circle
			(at -0.40005 0 270)
			(size 0 0)
			(layers "B.Cu" "B.Mask" "B.Paste")
			(net "FM_FAN_PWR_EN")
		)
	)
	(footprint ""
		(layer "B.Cu")
		(at 364.5154 -333.73568 90)
		(property "Reference" "PC283_P0_3"
			(at 0 0 90)
			(layer "B.SilkS")
			(hide yes)
			(effects
				(font
					(size 1.27 1.27)
				)
				(justify mirror)
			)
		)
		(property "Value" ""
			(at 0 0 90)
			(layer "B.Fab")
			(effects
				(font
					(size 1.27 1.27)
				)
				(justify mirror)
			)
		)
		(duplicate_pad_numbers_are_jumpers no)
		(fp_line
			(start 1.524 -0.762)
			(end -1.524 -0.762)
			(stroke
				(width 0.1524)
				(type default)
			)
			(layer "B.SilkS")
		)
		(fp_line
			(start -1.524 -0.762)
			(end -1.524 0.762)
			(stroke
				(width 0.1524)
				(type default)
			)
			(layer "B.SilkS")
		)
		(fp_line
			(start 1.524 0.762)
			(end 1.524 -0.762)
			(stroke
				(width 0.1524)
				(type default)
			)
			(layer "B.SilkS")
		)
		(fp_line
			(start -1.524 0.762)
			(end 1.524 0.762)
			(stroke
				(width 0.1524)
				(type default)
			)
			(layer "B.SilkS")
		)
		(fp_line
			(start 1.1049 -0.724916)
			(end 1.1049 0.724916)
			(stroke
				(width 0.1)
				(type default)
			)
			(layer "B.Fab")
		)
		(fp_line
			(start -1.1049 -0.724916)
			(end 1.1049 -0.724916)
			(stroke
				(width 0.1)
				(type default)
			)
			(layer "B.Fab")
		)
		(fp_line
			(start 1.1049 0.724916)
			(end -1.1049 0.724916)
			(stroke
				(width 0.1)
				(type default)
			)
			(layer "B.Fab")
		)
		(fp_line
			(start -1.1049 0.724916)
			(end -1.1049 -0.724916)
			(stroke
				(width 0.1)
				(type default)
			)
			(layer "B.Fab")
		)
		(pad "1" smd rect
			(at 0.889 0 90)
			(size 1.016 1.27)
			(layers "B.Cu" "B.Mask" "B.Paste")
			(net "SW_P12V_PVCCIN_CPU0_FLT")
		)
		(pad "2" smd rect
			(at -0.889 0 90)
			(size 1.016 1.27)
			(layers "B.Cu" "B.Mask" "B.Paste")
			(net "GND")
		)
	)
	(footprint ""
		(layer "B.Cu")
		(at 242.2906 -422.9862 90)
		(property "Reference" "R4701"
			(at 0 0 90)
			(layer "B.SilkS")
			(hide yes)
			(effects
				(font
					(size 1.27 1.27)
				)
				(justify mirror)
			)
		)
		(property "Value" ""
			(at 0 0 90)
			(layer "B.Fab")
			(effects
				(font
					(size 1.27 1.27)
				)
				(justify mirror)
			)
		)
		(duplicate_pad_numbers_are_jumpers no)
		(fp_line
			(start 0.7874 -0.4064)
			(end -0.7874 -0.4064)
			(stroke
				(width 0.1524)
				(type default)
			)
			(layer "B.SilkS")
		)
		(fp_line
			(start -0.7874 -0.4064)
			(end -0.7874 0.4064)
			(stroke
				(width 0.1524)
				(type default)
			)
			(layer "B.SilkS")
		)
		(fp_line
			(start 0.7874 0.4064)
			(end 0.7874 -0.4064)
			(stroke
				(width 0.1524)
				(type default)
			)
			(layer "B.SilkS")
		)
		(fp_line
			(start -0.7874 0.4064)
			(end 0.7874 0.4064)
			(stroke
				(width 0.1524)
				(type default)
			)
			(layer "B.SilkS")
		)
		(fp_line
			(start 0.67945 -0.305054)
			(end 0.12065 -0.305054)
			(stroke
				(width 0.1)
				(type default)
			)
			(layer "B.Fab")
		)
		(fp_line
			(start 0.12065 -0.305054)
			(end 0.12065 -0.2794)
			(stroke
				(width 0.1)
				(type default)
			)
			(layer "B.Fab")
		)
		(fp_line
			(start -0.12065 -0.3048)
			(end -0.67945 -0.3048)
			(stroke
				(width 0.1)
				(type default)
			)
			(layer "B.Fab")
		)
		(fp_line
			(start -0.67945 -0.3048)
			(end -0.67945 0.3048)
			(stroke
				(width 0.1)
				(type default)
			)
			(layer "B.Fab")
		)
		(fp_line
			(start 0.12065 -0.2794)
			(end -0.12065 -0.2794)
			(stroke
				(width 0.1)
				(type default)
			)
			(layer "B.Fab")
		)
		(fp_line
			(start -0.12065 -0.2794)
			(end -0.12065 -0.3048)
			(stroke
				(width 0.1)
				(type default)
			)
			(layer "B.Fab")
		)
		(fp_line
			(start 0.12065 0.2794)
			(end 0.12065 0.3048)
			(stroke
				(width 0.1)
				(type default)
			)
			(layer "B.Fab")
		)
		(fp_line
			(start -0.120396 0.2794)
			(end 0.12065 0.2794)
			(stroke
				(width 0.1)
				(type default)
			)
			(layer "B.Fab")
		)
		(fp_line
			(start 0.67945 0.3048)
			(end 0.67945 -0.305054)
			(stroke
				(width 0.1)
				(type default)
			)
			(layer "B.Fab")
		)
		(fp_line
			(start 0.12065 0.3048)
			(end 0.67945 0.3048)
			(stroke
				(width 0.1)
				(type default)
			)
			(layer "B.Fab")
		)
		(fp_line
			(start -0.120396 0.3048)
			(end -0.120396 0.2794)
			(stroke
				(width 0.1)
				(type default)
			)
			(layer "B.Fab")
		)
		(fp_line
			(start -0.67945 0.3048)
			(end -0.120396 0.3048)
			(stroke
				(width 0.1)
				(type default)
			)
			(layer "B.Fab")
		)
		(pad "1" smd circle
			(at 0.40005 0 270)
			(size 0 0)
			(layers "B.Cu" "B.Mask" "B.Paste")
			(net "P3V3_AUX")
		)
		(pad "2" smd circle
			(at -0.40005 0 270)
			(size 0 0)
			(layers "B.Cu" "B.Mask" "B.Paste")
			(net "FM_FAN_PWR_EN")
		)
	)
	(footprint ""
		(layer "B.Cu")
		(at 92.333572 -328.298048 -90)
		(property "Reference" "PC521_P1_6"
			(at 0 0 90)
			(layer "B.SilkS")
			(hide yes)
			(effects
				(font
					(size 1.27 1.27)
				)
				(justify mirror)
			)
		)
		(property "Value" ""
			(at 0 0 90)
			(layer "B.Fab")
			(effects
				(font
					(size 1.27 1.27)
				)
				(justify mirror)
			)
		)
		(duplicate_pad_numbers_are_jumpers no)
		(fp_line
			(start -1.524 0.762)
			(end 1.524 0.762)
			(stroke
				(width 0.1524)
				(type default)
			)
			(layer "B.SilkS")
		)
		(fp_line
			(start 1.524 0.762)
			(end 1.524 -0.762)
			(stroke
				(width 0.1524)
				(type default)
			)
			(layer "B.SilkS")
		)
		(fp_line
			(start -1.524 -0.762)
			(end -1.524 0.762)
			(stroke
				(width 0.1524)
				(type default)
			)
			(layer "B.SilkS")
		)
		(fp_line
			(start 1.524 -0.762)
			(end -1.524 -0.762)
			(stroke
				(width 0.1524)
				(type default)
			)
			(layer "B.SilkS")
		)
		(fp_line
			(start -1.1049 0.724916)
			(end -1.1049 -0.724916)
			(stroke
				(width 0.1)
				(type default)
			)
			(layer "B.Fab")
		)
		(fp_line
			(start 1.1049 0.724916)
			(end -1.1049 0.724916)
			(stroke
				(width 0.1)
				(type default)
			)
			(layer "B.Fab")
		)
		(fp_line
			(start -1.1049 -0.724916)
			(end 1.1049 -0.724916)
			(stroke
				(width 0.1)
				(type default)
			)
			(layer "B.Fab")
		)
		(fp_line
			(start 1.1049 -0.724916)
			(end 1.1049 0.724916)
			(stroke
				(width 0.1)
				(type default)
			)
			(layer "B.Fab")
		)
		(pad "1" smd rect
			(at 0.889 0 270)
			(size 1.016 1.27)
			(layers "B.Cu" "B.Mask" "B.Paste")
			(net "PVCCIN_CPU1")
		)
		(pad "2" smd rect
			(at -0.889 0 270)
			(size 1.016 1.27)
			(layers "B.Cu" "B.Mask" "B.Paste")
			(net "GND")
		)
	)
	(footprint ""
		(layer "B.Cu")
		(at 38.335458 -315.46673 -90)
		(property "Reference" "D47"
			(at 3.662172 3.237738 0)
			(unlocked yes)
			(layer "B.SilkS")
			(effects
				(font
					(size 0.7874 0.5842)
					(thickness 0.1524)
				)
				(justify left mirror)
			)
		)
		(property "Value" ""
			(at 0 0 90)
			(layer "B.Fab")
			(effects
				(font
					(size 1.27 1.27)
				)
				(justify mirror)
			)
		)
		(duplicate_pad_numbers_are_jumpers no)
		(fp_line
			(start -2.050796 0.700024)
			(end 2.050796 0.700024)
			(stroke
				(width 0.1524)
				(type default)
			)
			(layer "B.SilkS")
		)
		(fp_line
			(start 2.050796 0.700024)
			(end 2.050796 -0.700024)
			(stroke
				(width 0.1524)
				(type default)
			)
			(layer "B.SilkS")
		)
		(fp_line
			(start -2.343404 0.6985)
			(end -2.216404 0.6985)
			(stroke
				(width 0.1524)
				(type default)
			)
			(layer "B.SilkS")
		)
		(fp_line
			(start -2.229104 0.6985)
			(end -2.051304 0.6985)
			(stroke
				(width 0.1524)
				(type default)
			)
			(layer "B.SilkS")
		)
		(fp_line
			(start -2.051304 0.6985)
			(end -2.051304 0.635)
			(stroke
				(width 0.1524)
				(type default)
			)
			(layer "B.SilkS")
		)
		(fp_line
			(start -2.152904 0.635)
			(end -2.152904 -0.6985)
			(stroke
				(width 0.1524)
				(type default)
			)
			(layer "B.SilkS")
		)
		(fp_line
			(start -2.051304 0.635)
			(end -2.152904 0.635)
			(stroke
				(width 0.1524)
				(type default)
			)
			(layer "B.SilkS")
		)
		(fp_line
			(start 0.30607 0.500126)
			(end -0.193802 0)
			(stroke
				(width 0.1524)
				(type default)
			)
			(layer "B.SilkS")
		)
		(fp_line
			(start -0.193802 0)
			(end 0.30607 -0.500126)
			(stroke
				(width 0.1524)
				(type default)
			)
			(layer "B.SilkS")
		)
		(fp_line
			(start -0.293878 -0.500126)
			(end -0.293878 0.500126)
			(stroke
				(width 0.1524)
				(type default)
			)
			(layer "B.SilkS")
		)
		(fp_line
			(start 0.30607 -0.500126)
			(end 0.30607 0.500126)
			(stroke
				(width 0.1524)
				(type default)
			)
			(layer "B.SilkS")
		)
		(fp_line
			(start -2.064004 -0.6731)
			(end -2.064004 -0.6985)
			(stroke
				(width 0.1524)
				(type default)
			)
			(layer "B.SilkS")
		)
		(fp_line
			(start -2.343404 -0.6985)
			(end -2.343404 0.6985)
			(stroke
				(width 0.1524)
				(type default)
			)
			(layer "B.SilkS")
		)
		(fp_line
			(start -2.229104 -0.6985)
			(end -2.229104 0.6985)
			(stroke
				(width 0.1524)
				(type default)
			)
			(layer "B.SilkS")
		)
		(fp_line
			(start -2.152904 -0.6985)
			(end -2.343404 -0.6985)
			(stroke
				(width 0.1524)
				(type default)
			)
			(layer "B.SilkS")
		)
		(fp_line
			(start -2.064004 -0.6985)
			(end -2.229104 -0.6985)
			(stroke
				(width 0.1524)
				(type default)
			)
			(layer "B.SilkS")
		)
		(fp_line
			(start -2.050796 -0.700024)
			(end -2.050796 0.700024)
			(stroke
				(width 0.1524)
				(type default)
			)
			(layer "B.SilkS")
		)
		(fp_line
			(start 2.050796 -0.700024)
			(end -2.050796 -0.700024)
			(stroke
				(width 0.1524)
				(type default)
			)
			(layer "B.SilkS")
		)
		(fp_line
			(start -0.899922 0.700024)
			(end 0.899922 0.700024)
			(stroke
				(width 0.1)
				(type default)
			)
			(layer "B.Fab")
		)
		(fp_line
			(start 0.899922 0.700024)
			(end 0.899922 -0.700024)
			(stroke
				(width 0.1)
				(type default)
			)
			(layer "B.Fab")
		)
		(fp_line
			(start -0.899922 -0.700024)
			(end -0.899922 0.700024)
			(stroke
				(width 0.1)
				(type default)
			)
			(layer "B.Fab")
		)
		(fp_line
			(start 0.899922 -0.700024)
			(end -0.899922 -0.700024)
			(stroke
				(width 0.1)
				(type default)
			)
			(layer "B.Fab")
		)
		(fp_text user "-"
			(at -0.138938 1.966468 90)
			(unlocked yes)
			(layer "B.SilkS")
			(effects
				(font
					(size 1.905 1.4224)
					(thickness 0.1524)
				)
				(justify left mirror)
			)
		)
		(fp_text user "+"
			(at 3.123946 0.762 180)
			(unlocked yes)
			(layer "B.SilkS")
			(effects
				(font
					(size 1.905 1.4224)
					(thickness 0.1524)
				)
				(justify left mirror)
			)
		)
		(fp_text user "+"
			(at 3.123946 0.762 180)
			(unlocked yes)
			(layer "B.Fab")
			(effects
				(font
					(size 1.905 1.4224)
					(thickness 0.1524)
				)
				(justify left mirror)
			)
		)
		(fp_text user "-"
			(at -3.880104 0.23495 90)
			(unlocked yes)
			(layer "B.Fab")
			(effects
				(font
					(size 1.905 1.4224)
					(thickness 0.1524)
				)
				(justify left mirror)
			)
		)
		(pad "1" smd rect
			(at 1.199896 0 180)
			(size 0.6604 1.3716)
			(layers "B.Cu" "B.Mask" "B.Paste")
			(net "PWRGD_FAIL_CPU1_CD_R1")
		)
		(pad "2" smd rect
			(at -1.199896 0)
			(size 0.6604 1.3716)
			(layers "B.Cu" "B.Mask" "B.Paste")
			(net "P3V3_AUX")
		)
	)
	(footprint ""
		(layer "B.Cu")
		(at 105.670604 -296.05478)
		(property "Reference" "C344"
			(at 0 0 0)
			(layer "B.SilkS")
			(hide yes)
			(effects
				(font
					(size 1.27 1.27)
				)
				(justify mirror)
			)
		)
		(property "Value" ""
			(at 0 0 0)
			(layer "B.Fab")
			(effects
				(font
					(size 1.27 1.27)
				)
				(justify mirror)
			)
		)
		(duplicate_pad_numbers_are_jumpers no)
		(fp_line
			(start -1.524 -0.762)
			(end -1.524 0.762)
			(stroke
				(width 0.1524)
				(type default)
			)
			(layer "B.SilkS")
		)
		(fp_line
			(start -1.524 0.762)
			(end 1.524 0.762)
			(stroke
				(width 0.1524)
				(type default)
			)
			(layer "B.SilkS")
		)
		(fp_line
			(start 1.524 -0.762)
			(end -1.524 -0.762)
			(stroke
				(width 0.1524)
				(type default)
			)
			(layer "B.SilkS")
		)
		(fp_line
			(start 1.524 0.762)
			(end 1.524 -0.762)
			(stroke
				(width 0.1524)
				(type default)
			)
			(layer "B.SilkS")
		)
		(fp_line
			(start -1.1049 -0.724916)
			(end 1.1049 -0.724916)
			(stroke
				(width 0.1)
				(type default)
			)
			(layer "B.Fab")
		)
		(fp_line
			(start -1.1049 0.724916)
			(end -1.1049 -0.724916)
			(stroke
				(width 0.1)
				(type default)
			)
			(layer "B.Fab")
		)
		(fp_line
			(start 1.1049 -0.724916)
			(end 1.1049 0.724916)
			(stroke
				(width 0.1)
				(type default)
			)
			(layer "B.Fab")
		)
		(fp_line
			(start 1.1049 0.724916)
			(end -1.1049 0.724916)
			(stroke
				(width 0.1)
				(type default)
			)
			(layer "B.Fab")
		)
		(pad "1" smd rect
			(at 0.889 0)
			(size 1.016 1.27)
			(layers "B.Cu" "B.Mask" "B.Paste")
			(net "PVCCIN_CPU1")
		)
		(pad "2" smd rect
			(at -0.889 0)
			(size 1.016 1.27)
			(layers "B.Cu" "B.Mask" "B.Paste")
			(net "GND")
		)
	)
	(footprint ""
		(layer "B.Cu")
		(at 76.413106 -332.627224 90)
		(property "Reference" "PR578"
			(at 0 0 90)
			(layer "B.SilkS")
			(hide yes)
			(effects
				(font
					(size 1.27 1.27)
				)
				(justify mirror)
			)
		)
		(property "Value" ""
			(at 0 0 90)
			(layer "B.Fab")
			(effects
				(font
					(size 1.27 1.27)
				)
				(justify mirror)
			)
		)
		(duplicate_pad_numbers_are_jumpers no)
		(fp_line
			(start 0.7874 -0.4064)
			(end -0.7874 -0.4064)
			(stroke
				(width 0.1524)
				(type default)
			)
			(layer "B.SilkS")
		)
		(fp_line
			(start -0.7874 -0.4064)
			(end -0.7874 0.4064)
			(stroke
				(width 0.1524)
				(type default)
			)
			(layer "B.SilkS")
		)
		(fp_line
			(start 0.7874 0.4064)
			(end 0.7874 -0.4064)
			(stroke
				(width 0.1524)
				(type default)
			)
			(layer "B.SilkS")
		)
		(fp_line
			(start -0.7874 0.4064)
			(end 0.7874 0.4064)
			(stroke
				(width 0.1524)
				(type default)
			)
			(layer "B.SilkS")
		)
		(fp_line
			(start 0.67945 -0.305054)
			(end 0.12065 -0.305054)
			(stroke
				(width 0.1)
				(type default)
			)
			(layer "B.Fab")
		)
		(fp_line
			(start 0.12065 -0.305054)
			(end 0.12065 -0.2794)
			(stroke
				(width 0.1)
				(type default)
			)
			(layer "B.Fab")
		)
		(fp_line
			(start -0.12065 -0.3048)
			(end -0.67945 -0.3048)
			(stroke
				(width 0.1)
				(type default)
			)
			(layer "B.Fab")
		)
		(fp_line
			(start -0.67945 -0.3048)
			(end -0.67945 0.3048)
			(stroke
				(width 0.1)
				(type default)
			)
			(layer "B.Fab")
		)
		(fp_line
			(start 0.12065 -0.2794)
			(end -0.12065 -0.2794)
			(stroke
				(width 0.1)
				(type default)
			)
			(layer "B.Fab")
		)
		(fp_line
			(start -0.12065 -0.2794)
			(end -0.12065 -0.3048)
			(stroke
				(width 0.1)
				(type default)
			)
			(layer "B.Fab")
		)
		(fp_line
			(start 0.12065 0.2794)
			(end 0.12065 0.3048)
			(stroke
				(width 0.1)
				(type default)
			)
			(layer "B.Fab")
		)
		(fp_line
			(start -0.120396 0.2794)
			(end 0.12065 0.2794)
			(stroke
				(width 0.1)
				(type default)
			)
			(layer "B.Fab")
		)
		(fp_line
			(start 0.67945 0.3048)
			(end 0.67945 -0.305054)
			(stroke
				(width 0.1)
				(type default)
			)
			(layer "B.Fab")
		)
		(fp_line
			(start 0.12065 0.3048)
			(end 0.67945 0.3048)
			(stroke
				(width 0.1)
				(type default)
			)
			(layer "B.Fab")
		)
		(fp_line
			(start -0.120396 0.3048)
			(end -0.120396 0.2794)
			(stroke
				(width 0.1)
				(type default)
			)
			(layer "B.Fab")
		)
		(fp_line
			(start -0.67945 0.3048)
			(end -0.120396 0.3048)
			(stroke
				(width 0.1)
				(type default)
			)
			(layer "B.Fab")
		)
		(pad "1" smd circle
			(at 0.40005 0 270)
			(size 0 0)
			(layers "B.Cu" "B.Mask" "B.Paste")
			(net "VSENSE_PVCCIN_CPU1_DP")
		)
		(pad "2" smd circle
			(at -0.40005 0 270)
			(size 0 0)
			(layers "B.Cu" "B.Mask" "B.Paste")
			(net "PVCCIN_CPU1")
		)
	)
	(footprint ""
		(layer "B.Cu")
		(at 183.755538 -105.375456 90)
		(property "Reference" "C1124"
			(at 0 0 90)
			(layer "B.SilkS")
			(hide yes)
			(effects
				(font
					(size 1.27 1.27)
				)
				(justify mirror)
			)
		)
		(property "Value" ""
			(at 0 0 90)
			(layer "B.Fab")
			(effects
				(font
					(size 1.27 1.27)
				)
				(justify mirror)
			)
		)
		(duplicate_pad_numbers_are_jumpers no)
		(fp_line
			(start 0.69215 -0.2921)
			(end -0.69215 -0.2921)
			(stroke
				(width 0.1524)
				(type default)
			)
			(layer "B.SilkS")
		)
		(fp_line
			(start -0.69215 -0.2921)
			(end -0.69215 0.2921)
			(stroke
				(width 0.1524)
				(type default)
			)
			(layer "B.SilkS")
		)
		(fp_line
			(start 0.69215 0.2921)
			(end 0.69215 -0.2921)
			(stroke
				(width 0.1524)
				(type default)
			)
			(layer "B.SilkS")
		)
		(fp_line
			(start -0.69215 0.2921)
			(end 0.69215 0.2921)
			(stroke
				(width 0.1524)
				(type default)
			)
			(layer "B.SilkS")
		)
		(fp_line
			(start 0.51435 -0.2794)
			(end -0.51435 -0.2794)
			(stroke
				(width 0.1)
				(type default)
			)
			(layer "B.Fab")
		)
		(fp_line
			(start -0.51435 -0.2794)
			(end -0.51435 0.2794)
			(stroke
				(width 0.1)
				(type default)
			)
			(layer "B.Fab")
		)
		(fp_line
			(start 0.51435 0.2794)
			(end 0.51435 -0.2794)
			(stroke
				(width 0.1)
				(type default)
			)
			(layer "B.Fab")
		)
		(fp_line
			(start -0.51435 0.2794)
			(end 0.51435 0.2794)
			(stroke
				(width 0.1)
				(type default)
			)
			(layer "B.Fab")
		)
		(pad "1" smd circle
			(at 0.40005 0 270)
			(size 0 0)
			(layers "B.Cu" "B.Mask" "B.Paste")
			(net "P3V3_AUX_FPGA_VCCIO3")
		)
		(pad "2" smd circle
			(at -0.40005 0 270)
			(size 0 0)
			(layers "B.Cu" "B.Mask" "B.Paste")
			(net "GND")
		)
		(zone
			(layer "B.Cu")
			(hatch none 0.5)
			(connect_pads
				(clearance 0)
			)
			(min_thickness 0.25)
			(keepout
				(tracks not_allowed)
				(vias allowed)
				(pads allowed)
				(copperpour not_allowed)
				(footprints allowed)
			)
			(placement
				(enabled no)
				(sheetname "")
			)
			(fill
				(thermal_gap 0.5)
				(thermal_bridge_width 0.5)
				(island_removal_mode 0)
			)
			(polygon
				(pts
					(xy 183.843168 -105.565956) (xy 183.901334 -105.474516) (xy 183.901334 -105.275126) (xy 183.843168 -105.184956)
					(xy 183.667908 -105.184956) (xy 183.609488 -105.275126) (xy 183.609488 -105.474516) (xy 183.667654 -105.565956)
				)
			)
		)
	)
	(footprint ""
		(layer "B.Cu")
		(at 197.41388 -106.225848)
		(property "Reference" "R2347"
			(at 0 0 0)
			(layer "B.SilkS")
			(hide yes)
			(effects
				(font
					(size 1.27 1.27)
				)
				(justify mirror)
			)
		)
		(property "Value" ""
			(at 0 0 0)
			(layer "B.Fab")
			(effects
				(font
					(size 1.27 1.27)
				)
				(justify mirror)
			)
		)
		(duplicate_pad_numbers_are_jumpers no)
		(fp_line
			(start -0.7874 -0.4064)
			(end -0.7874 0.4064)
			(stroke
				(width 0.1524)
				(type default)
			)
			(layer "B.SilkS")
		)
		(fp_line
			(start -0.7874 0.4064)
			(end 0.7874 0.4064)
			(stroke
				(width 0.1524)
				(type default)
			)
			(layer "B.SilkS")
		)
		(fp_line
			(start 0.7874 -0.4064)
			(end -0.7874 -0.4064)
			(stroke
				(width 0.1524)
				(type default)
			)
			(layer "B.SilkS")
		)
		(fp_line
			(start 0.7874 0.4064)
			(end 0.7874 -0.4064)
			(stroke
				(width 0.1524)
				(type default)
			)
			(layer "B.SilkS")
		)
		(fp_line
			(start -0.67945 -0.3048)
			(end -0.67945 0.3048)
			(stroke
				(width 0.1)
				(type default)
			)
			(layer "B.Fab")
		)
		(fp_line
			(start -0.67945 0.3048)
			(end -0.120396 0.3048)
			(stroke
				(width 0.1)
				(type default)
			)
			(layer "B.Fab")
		)
		(fp_line
			(start -0.12065 -0.3048)
			(end -0.67945 -0.3048)
			(stroke
				(width 0.1)
				(type default)
			)
			(layer "B.Fab")
		)
		(fp_line
			(start -0.12065 -0.2794)
			(end -0.12065 -0.3048)
			(stroke
				(width 0.1)
				(type default)
			)
			(layer "B.Fab")
		)
		(fp_line
			(start -0.120396 0.2794)
			(end 0.12065 0.2794)
			(stroke
				(width 0.1)
				(type default)
			)
			(layer "B.Fab")
		)
		(fp_line
			(start -0.120396 0.3048)
			(end -0.120396 0.2794)
			(stroke
				(width 0.1)
				(type default)
			)
			(layer "B.Fab")
		)
		(fp_line
			(start 0.12065 -0.305054)
			(end 0.12065 -0.2794)
			(stroke
				(width 0.1)
				(type default)
			)
			(layer "B.Fab")
		)
		(fp_line
			(start 0.12065 -0.2794)
			(end -0.12065 -0.2794)
			(stroke
				(width 0.1)
				(type default)
			)
			(layer "B.Fab")
		)
		(fp_line
			(start 0.12065 0.2794)
			(end 0.12065 0.3048)
			(stroke
				(width 0.1)
				(type default)
			)
			(layer "B.Fab")
		)
		(fp_line
			(start 0.12065 0.3048)
			(end 0.67945 0.3048)
			(stroke
				(width 0.1)
				(type default)
			)
			(layer "B.Fab")
		)
		(fp_line
			(start 0.67945 -0.305054)
			(end 0.12065 -0.305054)
			(stroke
				(width 0.1)
				(type default)
			)
			(layer "B.Fab")
		)
		(fp_line
			(start 0.67945 0.3048)
			(end 0.67945 -0.305054)
			(stroke
				(width 0.1)
				(type default)
			)
			(layer "B.Fab")
		)
		(pad "1" smd circle
			(at 0.40005 0 180)
			(size 0 0)
			(layers "B.Cu" "B.Mask" "B.Paste")
			(net "FM_REMOTE_DEBUG_DET_R")
		)
		(pad "2" smd circle
			(at -0.40005 0 180)
			(size 0 0)
			(layers "B.Cu" "B.Mask" "B.Paste")
			(net "FM_REMOTE_DEBUG_DET")
		)
	)
	(footprint ""
		(layer "B.Cu")
		(at 315.110622 -55.235348 180)
		(property "Reference" "R1201"
			(at 0 0 0)
			(layer "B.SilkS")
			(hide yes)
			(effects
				(font
					(size 1.27 1.27)
				)
				(justify mirror)
			)
		)
		(property "Value" ""
			(at 0 0 0)
			(layer "B.Fab")
			(effects
				(font
					(size 1.27 1.27)
				)
				(justify mirror)
			)
		)
		(duplicate_pad_numbers_are_jumpers no)
		(fp_line
			(start 0.7874 0.4064)
			(end 0.7874 -0.4064)
			(stroke
				(width 0.1524)
				(type default)
			)
			(layer "B.SilkS")
		)
		(fp_line
			(start 0.7874 -0.4064)
			(end -0.7874 -0.4064)
			(stroke
				(width 0.1524)
				(type default)
			)
			(layer "B.SilkS")
		)
		(fp_line
			(start -0.7874 0.4064)
			(end 0.7874 0.4064)
			(stroke
				(width 0.1524)
				(type default)
			)
			(layer "B.SilkS")
		)
		(fp_line
			(start -0.7874 -0.4064)
			(end -0.7874 0.4064)
			(stroke
				(width 0.1524)
				(type default)
			)
			(layer "B.SilkS")
		)
		(fp_line
			(start 0.67945 0.3048)
			(end 0.67945 -0.305054)
			(stroke
				(width 0.1)
				(type default)
			)
			(layer "B.Fab")
		)
		(fp_line
			(start 0.67945 -0.305054)
			(end 0.12065 -0.305054)
			(stroke
				(width 0.1)
				(type default)
			)
			(layer "B.Fab")
		)
		(fp_line
			(start 0.12065 0.3048)
			(end 0.67945 0.3048)
			(stroke
				(width 0.1)
				(type default)
			)
			(layer "B.Fab")
		)
		(fp_line
			(start 0.12065 0.2794)
			(end 0.12065 0.3048)
			(stroke
				(width 0.1)
				(type default)
			)
			(layer "B.Fab")
		)
		(fp_line
			(start 0.12065 -0.2794)
			(end -0.12065 -0.2794)
			(stroke
				(width 0.1)
				(type default)
			)
			(layer "B.Fab")
		)
		(fp_line
			(start 0.12065 -0.305054)
			(end 0.12065 -0.2794)
			(stroke
				(width 0.1)
				(type default)
			)
			(layer "B.Fab")
		)
		(fp_line
			(start -0.120396 0.3048)
			(end -0.120396 0.2794)
			(stroke
				(width 0.1)
				(type default)
			)
			(layer "B.Fab")
		)
		(fp_line
			(start -0.120396 0.2794)
			(end 0.12065 0.2794)
			(stroke
				(width 0.1)
				(type default)
			)
			(layer "B.Fab")
		)
		(fp_line
			(start -0.12065 -0.2794)
			(end -0.12065 -0.3048)
			(stroke
				(width 0.1)
				(type default)
			)
			(layer "B.Fab")
		)
		(fp_line
			(start -0.12065 -0.3048)
			(end -0.67945 -0.3048)
			(stroke
				(width 0.1)
				(type default)
			)
			(layer "B.Fab")
		)
		(fp_line
			(start -0.67945 0.3048)
			(end -0.120396 0.3048)
			(stroke
				(width 0.1)
				(type default)
			)
			(layer "B.Fab")
		)
		(fp_line
			(start -0.67945 -0.3048)
			(end -0.67945 0.3048)
			(stroke
				(width 0.1)
				(type default)
			)
			(layer "B.Fab")
		)
		(pad "1" smd circle
			(at 0.40005 0)
			(size 0 0)
			(layers "B.Cu" "B.Mask" "B.Paste")
			(net "FM_PCH_TRIGGER1_N")
		)
		(pad "2" smd circle
			(at -0.40005 0)
			(size 0 0)
			(layers "B.Cu" "B.Mask" "B.Paste")
			(net "FM_PCH_TRIGGER1_R_N")
		)
	)
	(footprint ""
		(layer "B.Cu")
		(at 182.68188 -101.564948 180)
		(property "Reference" "R3344"
			(at 0 0 0)
			(layer "B.SilkS")
			(hide yes)
			(effects
				(font
					(size 1.27 1.27)
				)
				(justify mirror)
			)
		)
		(property "Value" ""
			(at 0 0 0)
			(layer "B.Fab")
			(effects
				(font
					(size 1.27 1.27)
				)
				(justify mirror)
			)
		)
		(duplicate_pad_numbers_are_jumpers no)
		(fp_line
			(start 1.2954 0.5842)
			(end 1.2954 -0.5842)
			(stroke
				(width 0.1524)
				(type default)
			)
			(layer "B.SilkS")
		)
		(fp_line
			(start 1.2954 -0.5842)
			(end -1.2954 -0.5842)
			(stroke
				(width 0.1524)
				(type default)
			)
			(layer "B.SilkS")
		)
		(fp_line
			(start -1.2954 0.5842)
			(end 1.2954 0.5842)
			(stroke
				(width 0.1524)
				(type default)
			)
			(layer "B.SilkS")
		)
		(fp_line
			(start -1.2954 -0.5842)
			(end -1.2954 0.5842)
			(stroke
				(width 0.1524)
				(type default)
			)
			(layer "B.SilkS")
		)
		(fp_line
			(start 1.1938 0.4064)
			(end 1.1938 -0.406654)
			(stroke
				(width 0.1)
				(type default)
			)
			(layer "B.Fab")
		)
		(fp_line
			(start 1.1938 -0.406654)
			(end 0.8636 -0.406654)
			(stroke
				(width 0.1)
				(type default)
			)
			(layer "B.Fab")
		)
		(fp_line
			(start 0.8636 0.4572)
			(end 0.8636 0.4318)
			(stroke
				(width 0.1)
				(type default)
			)
			(layer "B.Fab")
		)
		(fp_line
			(start 0.8636 0.4318)
			(end 0.8636 0.4064)
			(stroke
				(width 0.1)
				(type default)
			)
			(layer "B.Fab")
		)
		(fp_line
			(start 0.8636 0.4064)
			(end 1.1938 0.4064)
			(stroke
				(width 0.1)
				(type default)
			)
			(layer "B.Fab")
		)
		(fp_line
			(start 0.8636 -0.406654)
			(end 0.8636 -0.4572)
			(stroke
				(width 0.1)
				(type default)
			)
			(layer "B.Fab")
		)
		(fp_line
			(start 0.8636 -0.4572)
			(end -0.8636 -0.4572)
			(stroke
				(width 0.1)
				(type default)
			)
			(layer "B.Fab")
		)
		(fp_line
			(start -0.8636 0.4572)
			(end 0.8636 0.4572)
			(stroke
				(width 0.1)
				(type default)
			)
			(layer "B.Fab")
		)
		(fp_line
			(start -0.8636 0.4064)
			(end -0.8636 0.4572)
			(stroke
				(width 0.1)
				(type default)
			)
			(layer "B.Fab")
		)
		(fp_line
			(start -0.8636 -0.406654)
			(end -1.1938 -0.406654)
			(stroke
				(width 0.1)
				(type default)
			)
			(layer "B.Fab")
		)
		(fp_line
			(start -0.8636 -0.4572)
			(end -0.8636 -0.406654)
			(stroke
				(width 0.1)
				(type default)
			)
			(layer "B.Fab")
		)
		(fp_line
			(start -1.1938 0.4064)
			(end -0.8636 0.4064)
			(stroke
				(width 0.1)
				(type default)
			)
			(layer "B.Fab")
		)
		(fp_line
			(start -1.1938 -0.406654)
			(end -1.1938 0.4064)
			(stroke
				(width 0.1)
				(type default)
			)
			(layer "B.Fab")
		)
		(pad "1" smd rect
			(at 0.7366 0 90)
			(size 0.7112 0.8128)
			(layers "B.Cu" "B.Mask" "B.Paste")
			(net "P3V3_AUX")
		)
		(pad "2" smd rect
			(at -0.7366 0 90)
			(size 0.7112 0.8128)
			(layers "B.Cu" "B.Mask" "B.Paste")
			(net "P3V3_AUX_FPGA_VCCIO3")
		)
	)
	(footprint ""
		(layer "B.Cu")
		(at 213.422484 -321.554856 -90)
		(property "Reference" "C77"
			(at 0 0 90)
			(layer "B.SilkS")
			(hide yes)
			(effects
				(font
					(size 1.27 1.27)
				)
				(justify mirror)
			)
		)
		(property "Value" ""
			(at 0 0 90)
			(layer "B.Fab")
			(effects
				(font
					(size 1.27 1.27)
				)
				(justify mirror)
			)
		)
		(duplicate_pad_numbers_are_jumpers no)
		(fp_line
			(start -1.524 0.762)
			(end 1.524 0.762)
			(stroke
				(width 0.1524)
				(type default)
			)
			(layer "B.SilkS")
		)
		(fp_line
			(start 1.524 0.762)
			(end 1.524 -0.762)
			(stroke
				(width 0.1524)
				(type default)
			)
			(layer "B.SilkS")
		)
		(fp_line
			(start -1.524 -0.762)
			(end -1.524 0.762)
			(stroke
				(width 0.1524)
				(type default)
			)
			(layer "B.SilkS")
		)
		(fp_line
			(start 1.524 -0.762)
			(end -1.524 -0.762)
			(stroke
				(width 0.1524)
				(type default)
			)
			(layer "B.SilkS")
		)
		(fp_line
			(start -1.1049 0.724916)
			(end -1.1049 -0.724916)
			(stroke
				(width 0.1)
				(type default)
			)
			(layer "B.Fab")
		)
		(fp_line
			(start 1.1049 0.724916)
			(end -1.1049 0.724916)
			(stroke
				(width 0.1)
				(type default)
			)
			(layer "B.Fab")
		)
		(fp_line
			(start -1.1049 -0.724916)
			(end 1.1049 -0.724916)
			(stroke
				(width 0.1)
				(type default)
			)
			(layer "B.Fab")
		)
		(fp_line
			(start 1.1049 -0.724916)
			(end 1.1049 0.724916)
			(stroke
				(width 0.1)
				(type default)
			)
			(layer "B.Fab")
		)
		(pad "1" smd rect
			(at 0.889 0 270)
			(size 1.016 1.27)
			(layers "B.Cu" "B.Mask" "B.Paste")
			(net "P12V_S3_AUX_CPU1_NVDIMM")
		)
		(pad "2" smd rect
			(at -0.889 0 270)
			(size 1.016 1.27)
			(layers "B.Cu" "B.Mask" "B.Paste")
			(net "GND")
		)
	)
	(footprint ""
		(layer "B.Cu")
		(at 313.78144 -193.53911 -90)
		(property "Reference" "R2"
			(at 0 0 90)
			(layer "B.SilkS")
			(hide yes)
			(effects
				(font
					(size 1.27 1.27)
				)
				(justify mirror)
			)
		)
		(property "Value" ""
			(at 0 0 90)
			(layer "B.Fab")
			(effects
				(font
					(size 1.27 1.27)
				)
				(justify mirror)
			)
		)
		(duplicate_pad_numbers_are_jumpers no)
		(fp_line
			(start -0.7874 0.4064)
			(end 0.7874 0.4064)
			(stroke
				(width 0.1524)
				(type default)
			)
			(layer "B.SilkS")
		)
		(fp_line
			(start 0.7874 0.4064)
			(end 0.7874 -0.4064)
			(stroke
				(width 0.1524)
				(type default)
			)
			(layer "B.SilkS")
		)
		(fp_line
			(start -0.7874 -0.4064)
			(end -0.7874 0.4064)
			(stroke
				(width 0.1524)
				(type default)
			)
			(layer "B.SilkS")
		)
		(fp_line
			(start 0.7874 -0.4064)
			(end -0.7874 -0.4064)
			(stroke
				(width 0.1524)
				(type default)
			)
			(layer "B.SilkS")
		)
		(fp_line
			(start -0.67945 0.3048)
			(end -0.120396 0.3048)
			(stroke
				(width 0.1)
				(type default)
			)
			(layer "B.Fab")
		)
		(fp_line
			(start -0.120396 0.3048)
			(end -0.120396 0.2794)
			(stroke
				(width 0.1)
				(type default)
			)
			(layer "B.Fab")
		)
		(fp_line
			(start 0.12065 0.3048)
			(end 0.67945 0.3048)
			(stroke
				(width 0.1)
				(type default)
			)
			(layer "B.Fab")
		)
		(fp_line
			(start 0.67945 0.3048)
			(end 0.67945 -0.305054)
			(stroke
				(width 0.1)
				(type default)
			)
			(layer "B.Fab")
		)
		(fp_line
			(start -0.120396 0.2794)
			(end 0.12065 0.2794)
			(stroke
				(width 0.1)
				(type default)
			)
			(layer "B.Fab")
		)
		(fp_line
			(start 0.12065 0.2794)
			(end 0.12065 0.3048)
			(stroke
				(width 0.1)
				(type default)
			)
			(layer "B.Fab")
		)
		(fp_line
			(start -0.12065 -0.2794)
			(end -0.12065 -0.3048)
			(stroke
				(width 0.1)
				(type default)
			)
			(layer "B.Fab")
		)
		(fp_line
			(start 0.12065 -0.2794)
			(end -0.12065 -0.2794)
			(stroke
				(width 0.1)
				(type default)
			)
			(layer "B.Fab")
		)
		(fp_line
			(start -0.67945 -0.3048)
			(end -0.67945 0.3048)
			(stroke
				(width 0.1)
				(type default)
			)
			(layer "B.Fab")
		)
		(fp_line
			(start -0.12065 -0.3048)
			(end -0.67945 -0.3048)
			(stroke
				(width 0.1)
				(type default)
			)
			(layer "B.Fab")
		)
		(fp_line
			(start 0.12065 -0.305054)
			(end 0.12065 -0.2794)
			(stroke
				(width 0.1)
				(type default)
			)
			(layer "B.Fab")
		)
		(fp_line
			(start 0.67945 -0.305054)
			(end 0.12065 -0.305054)
			(stroke
				(width 0.1)
				(type default)
			)
			(layer "B.Fab")
		)
		(pad "1" smd circle
			(at 0.40005 0 90)
			(size 0 0)
			(layers "B.Cu" "B.Mask" "B.Paste")
			(net "H_CPU_PREQ_QS_GTL_N")
		)
		(pad "2" smd circle
			(at -0.40005 0 90)
			(size 0 0)
			(layers "B.Cu" "B.Mask" "B.Paste")
			(net "H_CPU0_PREQ_QS_GTL_R_N")
		)
	)
	(footprint ""
		(layer "B.Cu")
		(at 265.406378 -318.697102)
		(property "Reference" "R33"
			(at 0 0 0)
			(layer "B.SilkS")
			(hide yes)
			(effects
				(font
					(size 1.27 1.27)
				)
				(justify mirror)
			)
		)
		(property "Value" ""
			(at 0 0 0)
			(layer "B.Fab")
			(effects
				(font
					(size 1.27 1.27)
				)
				(justify mirror)
			)
		)
		(duplicate_pad_numbers_are_jumpers no)
		(fp_line
			(start -0.7874 -0.4064)
			(end -0.7874 0.4064)
			(stroke
				(width 0.1524)
				(type default)
			)
			(layer "B.SilkS")
		)
		(fp_line
			(start -0.7874 0.4064)
			(end 0.7874 0.4064)
			(stroke
				(width 0.1524)
				(type default)
			)
			(layer "B.SilkS")
		)
		(fp_line
			(start 0.7874 -0.4064)
			(end -0.7874 -0.4064)
			(stroke
				(width 0.1524)
				(type default)
			)
			(layer "B.SilkS")
		)
		(fp_line
			(start 0.7874 0.4064)
			(end 0.7874 -0.4064)
			(stroke
				(width 0.1524)
				(type default)
			)
			(layer "B.SilkS")
		)
		(fp_line
			(start -0.67945 -0.3048)
			(end -0.67945 0.3048)
			(stroke
				(width 0.1)
				(type default)
			)
			(layer "B.Fab")
		)
		(fp_line
			(start -0.67945 0.3048)
			(end -0.120396 0.3048)
			(stroke
				(width 0.1)
				(type default)
			)
			(layer "B.Fab")
		)
		(fp_line
			(start -0.12065 -0.3048)
			(end -0.67945 -0.3048)
			(stroke
				(width 0.1)
				(type default)
			)
			(layer "B.Fab")
		)
		(fp_line
			(start -0.12065 -0.2794)
			(end -0.12065 -0.3048)
			(stroke
				(width 0.1)
				(type default)
			)
			(layer "B.Fab")
		)
		(fp_line
			(start -0.120396 0.2794)
			(end 0.12065 0.2794)
			(stroke
				(width 0.1)
				(type default)
			)
			(layer "B.Fab")
		)
		(fp_line
			(start -0.120396 0.3048)
			(end -0.120396 0.2794)
			(stroke
				(width 0.1)
				(type default)
			)
			(layer "B.Fab")
		)
		(fp_line
			(start 0.12065 -0.305054)
			(end 0.12065 -0.2794)
			(stroke
				(width 0.1)
				(type default)
			)
			(layer "B.Fab")
		)
		(fp_line
			(start 0.12065 -0.2794)
			(end -0.12065 -0.2794)
			(stroke
				(width 0.1)
				(type default)
			)
			(layer "B.Fab")
		)
		(fp_line
			(start 0.12065 0.2794)
			(end 0.12065 0.3048)
			(stroke
				(width 0.1)
				(type default)
			)
			(layer "B.Fab")
		)
		(fp_line
			(start 0.12065 0.3048)
			(end 0.67945 0.3048)
			(stroke
				(width 0.1)
				(type default)
			)
			(layer "B.Fab")
		)
		(fp_line
			(start 0.67945 -0.305054)
			(end 0.12065 -0.305054)
			(stroke
				(width 0.1)
				(type default)
			)
			(layer "B.Fab")
		)
		(fp_line
			(start 0.67945 0.3048)
			(end 0.67945 -0.305054)
			(stroke
				(width 0.1)
				(type default)
			)
			(layer "B.Fab")
		)
		(pad "1" smd circle
			(at 0.40005 0 180)
			(size 0 0)
			(layers "B.Cu" "B.Mask" "B.Paste")
			(net "PD_CHD_CPU0_DIMM2_SAA")
		)
		(pad "2" smd circle
			(at -0.40005 0 180)
			(size 0 0)
			(layers "B.Cu" "B.Mask" "B.Paste")
			(net "GND")
		)
	)
	(footprint ""
		(layer "B.Cu")
		(at 312.443622 -36.820348)
		(property "Reference" "R1656"
			(at 0 0 0)
			(layer "B.SilkS")
			(hide yes)
			(effects
				(font
					(size 1.27 1.27)
				)
				(justify mirror)
			)
		)
		(property "Value" ""
			(at 0 0 0)
			(layer "B.Fab")
			(effects
				(font
					(size 1.27 1.27)
				)
				(justify mirror)
			)
		)
		(duplicate_pad_numbers_are_jumpers no)
		(fp_line
			(start -0.7874 -0.4064)
			(end -0.7874 0.4064)
			(stroke
				(width 0.1524)
				(type default)
			)
			(layer "B.SilkS")
		)
		(fp_line
			(start -0.7874 0.4064)
			(end 0.7874 0.4064)
			(stroke
				(width 0.1524)
				(type default)
			)
			(layer "B.SilkS")
		)
		(fp_line
			(start 0.7874 -0.4064)
			(end -0.7874 -0.4064)
			(stroke
				(width 0.1524)
				(type default)
			)
			(layer "B.SilkS")
		)
		(fp_line
			(start 0.7874 0.4064)
			(end 0.7874 -0.4064)
			(stroke
				(width 0.1524)
				(type default)
			)
			(layer "B.SilkS")
		)
		(fp_line
			(start -0.67945 -0.3048)
			(end -0.67945 0.3048)
			(stroke
				(width 0.1)
				(type default)
			)
			(layer "B.Fab")
		)
		(fp_line
			(start -0.67945 0.3048)
			(end -0.120396 0.3048)
			(stroke
				(width 0.1)
				(type default)
			)
			(layer "B.Fab")
		)
		(fp_line
			(start -0.12065 -0.3048)
			(end -0.67945 -0.3048)
			(stroke
				(width 0.1)
				(type default)
			)
			(layer "B.Fab")
		)
		(fp_line
			(start -0.12065 -0.2794)
			(end -0.12065 -0.3048)
			(stroke
				(width 0.1)
				(type default)
			)
			(layer "B.Fab")
		)
		(fp_line
			(start -0.120396 0.2794)
			(end 0.12065 0.2794)
			(stroke
				(width 0.1)
				(type default)
			)
			(layer "B.Fab")
		)
		(fp_line
			(start -0.120396 0.3048)
			(end -0.120396 0.2794)
			(stroke
				(width 0.1)
				(type default)
			)
			(layer "B.Fab")
		)
		(fp_line
			(start 0.12065 -0.305054)
			(end 0.12065 -0.2794)
			(stroke
				(width 0.1)
				(type default)
			)
			(layer "B.Fab")
		)
		(fp_line
			(start 0.12065 -0.2794)
			(end -0.12065 -0.2794)
			(stroke
				(width 0.1)
				(type default)
			)
			(layer "B.Fab")
		)
		(fp_line
			(start 0.12065 0.2794)
			(end 0.12065 0.3048)
			(stroke
				(width 0.1)
				(type default)
			)
			(layer "B.Fab")
		)
		(fp_line
			(start 0.12065 0.3048)
			(end 0.67945 0.3048)
			(stroke
				(width 0.1)
				(type default)
			)
			(layer "B.Fab")
		)
		(fp_line
			(start 0.67945 -0.305054)
			(end 0.12065 -0.305054)
			(stroke
				(width 0.1)
				(type default)
			)
			(layer "B.Fab")
		)
		(fp_line
			(start 0.67945 0.3048)
			(end 0.67945 -0.305054)
			(stroke
				(width 0.1)
				(type default)
			)
			(layer "B.Fab")
		)
		(pad "1" smd circle
			(at 0.40005 0 180)
			(size 0 0)
			(layers "B.Cu" "B.Mask" "B.Paste")
			(net "IRQ_SML1_PMBUS_ALERT_N")
		)
		(pad "2" smd circle
			(at -0.40005 0 180)
			(size 0 0)
			(layers "B.Cu" "B.Mask" "B.Paste")
			(net "IRQ_SML1_PMBUS_PLD_ALERT_N")
		)
	)
	(footprint ""
		(layer "B.Cu")
		(at 74.85888 -11.267948 90)
		(property "Reference" "R3173"
			(at 0 0 90)
			(layer "B.SilkS")
			(hide yes)
			(effects
				(font
					(size 1.27 1.27)
				)
				(justify mirror)
			)
		)
		(property "Value" ""
			(at 0 0 90)
			(layer "B.Fab")
			(effects
				(font
					(size 1.27 1.27)
				)
				(justify mirror)
			)
		)
		(duplicate_pad_numbers_are_jumpers no)
		(fp_line
			(start 0.7874 -0.4064)
			(end -0.7874 -0.4064)
			(stroke
				(width 0.1524)
				(type default)
			)
			(layer "B.SilkS")
		)
		(fp_line
			(start -0.7874 -0.4064)
			(end -0.7874 0.4064)
			(stroke
				(width 0.1524)
				(type default)
			)
			(layer "B.SilkS")
		)
		(fp_line
			(start 0.7874 0.4064)
			(end 0.7874 -0.4064)
			(stroke
				(width 0.1524)
				(type default)
			)
			(layer "B.SilkS")
		)
		(fp_line
			(start -0.7874 0.4064)
			(end 0.7874 0.4064)
			(stroke
				(width 0.1524)
				(type default)
			)
			(layer "B.SilkS")
		)
		(fp_line
			(start 0.67945 -0.305054)
			(end 0.12065 -0.305054)
			(stroke
				(width 0.1)
				(type default)
			)
			(layer "B.Fab")
		)
		(fp_line
			(start 0.12065 -0.305054)
			(end 0.12065 -0.2794)
			(stroke
				(width 0.1)
				(type default)
			)
			(layer "B.Fab")
		)
		(fp_line
			(start -0.12065 -0.3048)
			(end -0.67945 -0.3048)
			(stroke
				(width 0.1)
				(type default)
			)
			(layer "B.Fab")
		)
		(fp_line
			(start -0.67945 -0.3048)
			(end -0.67945 0.3048)
			(stroke
				(width 0.1)
				(type default)
			)
			(layer "B.Fab")
		)
		(fp_line
			(start 0.12065 -0.2794)
			(end -0.12065 -0.2794)
			(stroke
				(width 0.1)
				(type default)
			)
			(layer "B.Fab")
		)
		(fp_line
			(start -0.12065 -0.2794)
			(end -0.12065 -0.3048)
			(stroke
				(width 0.1)
				(type default)
			)
			(layer "B.Fab")
		)
		(fp_line
			(start 0.12065 0.2794)
			(end 0.12065 0.3048)
			(stroke
				(width 0.1)
				(type default)
			)
			(layer "B.Fab")
		)
		(fp_line
			(start -0.120396 0.2794)
			(end 0.12065 0.2794)
			(stroke
				(width 0.1)
				(type default)
			)
			(layer "B.Fab")
		)
		(fp_line
			(start 0.67945 0.3048)
			(end 0.67945 -0.305054)
			(stroke
				(width 0.1)
				(type default)
			)
			(layer "B.Fab")
		)
		(fp_line
			(start 0.12065 0.3048)
			(end 0.67945 0.3048)
			(stroke
				(width 0.1)
				(type default)
			)
			(layer "B.Fab")
		)
		(fp_line
			(start -0.120396 0.3048)
			(end -0.120396 0.2794)
			(stroke
				(width 0.1)
				(type default)
			)
			(layer "B.Fab")
		)
		(fp_line
			(start -0.67945 0.3048)
			(end -0.120396 0.3048)
			(stroke
				(width 0.1)
				(type default)
			)
			(layer "B.Fab")
		)
		(pad "1" smd circle
			(at 0.40005 0 270)
			(size 0 0)
			(layers "B.Cu" "B.Mask" "B.Paste")
			(net "SGPIO_OCP_V3_2_LD_N")
		)
		(pad "2" smd circle
			(at -0.40005 0 270)
			(size 0 0)
			(layers "B.Cu" "B.Mask" "B.Paste")
			(net "P3V3_OCP_V3_2")
		)
	)
	(footprint ""
		(layer "B.Cu")
		(at 404.006812 -52.722018 180)
		(property "Reference" "R772"
			(at 0 0 0)
			(layer "B.SilkS")
			(hide yes)
			(effects
				(font
					(size 1.27 1.27)
				)
				(justify mirror)
			)
		)
		(property "Value" ""
			(at 0 0 0)
			(layer "B.Fab")
			(effects
				(font
					(size 1.27 1.27)
				)
				(justify mirror)
			)
		)
		(duplicate_pad_numbers_are_jumpers no)
		(fp_line
			(start 0.7874 0.4064)
			(end 0.7874 -0.4064)
			(stroke
				(width 0.1524)
				(type default)
			)
			(layer "B.SilkS")
		)
		(fp_line
			(start 0.7874 -0.4064)
			(end -0.7874 -0.4064)
			(stroke
				(width 0.1524)
				(type default)
			)
			(layer "B.SilkS")
		)
		(fp_line
			(start -0.7874 0.4064)
			(end 0.7874 0.4064)
			(stroke
				(width 0.1524)
				(type default)
			)
			(layer "B.SilkS")
		)
		(fp_line
			(start -0.7874 -0.4064)
			(end -0.7874 0.4064)
			(stroke
				(width 0.1524)
				(type default)
			)
			(layer "B.SilkS")
		)
		(fp_line
			(start 0.67945 0.3048)
			(end 0.67945 -0.305054)
			(stroke
				(width 0.1)
				(type default)
			)
			(layer "B.Fab")
		)
		(fp_line
			(start 0.67945 -0.305054)
			(end 0.12065 -0.305054)
			(stroke
				(width 0.1)
				(type default)
			)
			(layer "B.Fab")
		)
		(fp_line
			(start 0.12065 0.3048)
			(end 0.67945 0.3048)
			(stroke
				(width 0.1)
				(type default)
			)
			(layer "B.Fab")
		)
		(fp_line
			(start 0.12065 0.2794)
			(end 0.12065 0.3048)
			(stroke
				(width 0.1)
				(type default)
			)
			(layer "B.Fab")
		)
		(fp_line
			(start 0.12065 -0.2794)
			(end -0.12065 -0.2794)
			(stroke
				(width 0.1)
				(type default)
			)
			(layer "B.Fab")
		)
		(fp_line
			(start 0.12065 -0.305054)
			(end 0.12065 -0.2794)
			(stroke
				(width 0.1)
				(type default)
			)
			(layer "B.Fab")
		)
		(fp_line
			(start -0.120396 0.3048)
			(end -0.120396 0.2794)
			(stroke
				(width 0.1)
				(type default)
			)
			(layer "B.Fab")
		)
		(fp_line
			(start -0.120396 0.2794)
			(end 0.12065 0.2794)
			(stroke
				(width 0.1)
				(type default)
			)
			(layer "B.Fab")
		)
		(fp_line
			(start -0.12065 -0.2794)
			(end -0.12065 -0.3048)
			(stroke
				(width 0.1)
				(type default)
			)
			(layer "B.Fab")
		)
		(fp_line
			(start -0.12065 -0.3048)
			(end -0.67945 -0.3048)
			(stroke
				(width 0.1)
				(type default)
			)
			(layer "B.Fab")
		)
		(fp_line
			(start -0.67945 0.3048)
			(end -0.120396 0.3048)
			(stroke
				(width 0.1)
				(type default)
			)
			(layer "B.Fab")
		)
		(fp_line
			(start -0.67945 -0.3048)
			(end -0.67945 0.3048)
			(stroke
				(width 0.1)
				(type default)
			)
			(layer "B.Fab")
		)
		(pad "1" smd circle
			(at 0.40005 0)
			(size 0 0)
			(layers "B.Cu" "B.Mask" "B.Paste")
			(net "JTAG_RST_DBP_RSMRST_N")
		)
		(pad "2" smd circle
			(at -0.40005 0)
			(size 0 0)
			(layers "B.Cu" "B.Mask" "B.Paste")
			(net "RST_RSMRST_PCH_N")
		)
	)
	(footprint ""
		(layer "B.Cu")
		(at 290.332414 -321.549776 -90)
		(property "Reference" "C10"
			(at 0 0 90)
			(layer "B.SilkS")
			(hide yes)
			(effects
				(font
					(size 1.27 1.27)
				)
				(justify mirror)
			)
		)
		(property "Value" ""
			(at 0 0 90)
			(layer "B.Fab")
			(effects
				(font
					(size 1.27 1.27)
				)
				(justify mirror)
			)
		)
		(duplicate_pad_numbers_are_jumpers no)
		(fp_line
			(start -1.524 0.762)
			(end 1.524 0.762)
			(stroke
				(width 0.1524)
				(type default)
			)
			(layer "B.SilkS")
		)
		(fp_line
			(start 1.524 0.762)
			(end 1.524 -0.762)
			(stroke
				(width 0.1524)
				(type default)
			)
			(layer "B.SilkS")
		)
		(fp_line
			(start -1.524 -0.762)
			(end -1.524 0.762)
			(stroke
				(width 0.1524)
				(type default)
			)
			(layer "B.SilkS")
		)
		(fp_line
			(start 1.524 -0.762)
			(end -1.524 -0.762)
			(stroke
				(width 0.1524)
				(type default)
			)
			(layer "B.SilkS")
		)
		(fp_line
			(start -1.1049 0.724916)
			(end -1.1049 -0.724916)
			(stroke
				(width 0.1)
				(type default)
			)
			(layer "B.Fab")
		)
		(fp_line
			(start 1.1049 0.724916)
			(end -1.1049 0.724916)
			(stroke
				(width 0.1)
				(type default)
			)
			(layer "B.Fab")
		)
		(fp_line
			(start -1.1049 -0.724916)
			(end 1.1049 -0.724916)
			(stroke
				(width 0.1)
				(type default)
			)
			(layer "B.Fab")
		)
		(fp_line
			(start 1.1049 -0.724916)
			(end 1.1049 0.724916)
			(stroke
				(width 0.1)
				(type default)
			)
			(layer "B.Fab")
		)
		(pad "1" smd rect
			(at 0.889 0 270)
			(size 1.016 1.27)
			(layers "B.Cu" "B.Mask" "B.Paste")
			(net "P12V_S3_AUX_CPU0_NVDIMM")
		)
		(pad "2" smd rect
			(at -0.889 0 270)
			(size 1.016 1.27)
			(layers "B.Cu" "B.Mask" "B.Paste")
			(net "GND")
		)
	)
	(footprint ""
		(layer "B.Cu")
		(at 366.120934 -255.853946 -90)
		(property "Reference" "C358"
			(at 0 0 90)
			(layer "B.SilkS")
			(hide yes)
			(effects
				(font
					(size 1.27 1.27)
				)
				(justify mirror)
			)
		)
		(property "Value" ""
			(at 0 0 90)
			(layer "B.Fab")
			(effects
				(font
					(size 1.27 1.27)
				)
				(justify mirror)
			)
		)
		(duplicate_pad_numbers_are_jumpers no)
		(fp_line
			(start -1.524 0.762)
			(end 1.524 0.762)
			(stroke
				(width 0.1524)
				(type default)
			)
			(layer "B.SilkS")
		)
		(fp_line
			(start 1.524 0.762)
			(end 1.524 -0.762)
			(stroke
				(width 0.1524)
				(type default)
			)
			(layer "B.SilkS")
		)
		(fp_line
			(start -1.524 -0.762)
			(end -1.524 0.762)
			(stroke
				(width 0.1524)
				(type default)
			)
			(layer "B.SilkS")
		)
		(fp_line
			(start 1.524 -0.762)
			(end -1.524 -0.762)
			(stroke
				(width 0.1524)
				(type default)
			)
			(layer "B.SilkS")
		)
		(fp_line
			(start -1.1049 0.724916)
			(end -1.1049 -0.724916)
			(stroke
				(width 0.1)
				(type default)
			)
			(layer "B.Fab")
		)
		(fp_line
			(start 1.1049 0.724916)
			(end -1.1049 0.724916)
			(stroke
				(width 0.1)
				(type default)
			)
			(layer "B.Fab")
		)
		(fp_line
			(start -1.1049 -0.724916)
			(end 1.1049 -0.724916)
			(stroke
				(width 0.1)
				(type default)
			)
			(layer "B.Fab")
		)
		(fp_line
			(start 1.1049 -0.724916)
			(end 1.1049 0.724916)
			(stroke
				(width 0.1)
				(type default)
			)
			(layer "B.Fab")
		)
		(pad "1" smd rect
			(at 0.889 0 270)
			(size 1.016 1.27)
			(layers "B.Cu" "B.Mask" "B.Paste")
			(net "PVCCIN_CPU0")
		)
		(pad "2" smd rect
			(at -0.889 0 270)
			(size 1.016 1.27)
			(layers "B.Cu" "B.Mask" "B.Paste")
			(net "GND")
		)
	)
	(footprint ""
		(layer "B.Cu")
		(at 327.613518 -188.61278 90)
		(property "Reference" "R744"
			(at 0 0 90)
			(layer "B.SilkS")
			(hide yes)
			(effects
				(font
					(size 1.27 1.27)
				)
				(justify mirror)
			)
		)
		(property "Value" ""
			(at 0 0 90)
			(layer "B.Fab")
			(effects
				(font
					(size 1.27 1.27)
				)
				(justify mirror)
			)
		)
		(duplicate_pad_numbers_are_jumpers no)
		(fp_line
			(start 0.7874 -0.4064)
			(end -0.7874 -0.4064)
			(stroke
				(width 0.1524)
				(type default)
			)
			(layer "B.SilkS")
		)
		(fp_line
			(start -0.7874 -0.4064)
			(end -0.7874 0.4064)
			(stroke
				(width 0.1524)
				(type default)
			)
			(layer "B.SilkS")
		)
		(fp_line
			(start 0.7874 0.4064)
			(end 0.7874 -0.4064)
			(stroke
				(width 0.1524)
				(type default)
			)
			(layer "B.SilkS")
		)
		(fp_line
			(start -0.7874 0.4064)
			(end 0.7874 0.4064)
			(stroke
				(width 0.1524)
				(type default)
			)
			(layer "B.SilkS")
		)
		(fp_line
			(start 0.67945 -0.305054)
			(end 0.12065 -0.305054)
			(stroke
				(width 0.1)
				(type default)
			)
			(layer "B.Fab")
		)
		(fp_line
			(start 0.12065 -0.305054)
			(end 0.12065 -0.2794)
			(stroke
				(width 0.1)
				(type default)
			)
			(layer "B.Fab")
		)
		(fp_line
			(start -0.12065 -0.3048)
			(end -0.67945 -0.3048)
			(stroke
				(width 0.1)
				(type default)
			)
			(layer "B.Fab")
		)
		(fp_line
			(start -0.67945 -0.3048)
			(end -0.67945 0.3048)
			(stroke
				(width 0.1)
				(type default)
			)
			(layer "B.Fab")
		)
		(fp_line
			(start 0.12065 -0.2794)
			(end -0.12065 -0.2794)
			(stroke
				(width 0.1)
				(type default)
			)
			(layer "B.Fab")
		)
		(fp_line
			(start -0.12065 -0.2794)
			(end -0.12065 -0.3048)
			(stroke
				(width 0.1)
				(type default)
			)
			(layer "B.Fab")
		)
		(fp_line
			(start 0.12065 0.2794)
			(end 0.12065 0.3048)
			(stroke
				(width 0.1)
				(type default)
			)
			(layer "B.Fab")
		)
		(fp_line
			(start -0.120396 0.2794)
			(end 0.12065 0.2794)
			(stroke
				(width 0.1)
				(type default)
			)
			(layer "B.Fab")
		)
		(fp_line
			(start 0.67945 0.3048)
			(end 0.67945 -0.305054)
			(stroke
				(width 0.1)
				(type default)
			)
			(layer "B.Fab")
		)
		(fp_line
			(start 0.12065 0.3048)
			(end 0.67945 0.3048)
			(stroke
				(width 0.1)
				(type default)
			)
			(layer "B.Fab")
		)
		(fp_line
			(start -0.120396 0.3048)
			(end -0.120396 0.2794)
			(stroke
				(width 0.1)
				(type default)
			)
			(layer "B.Fab")
		)
		(fp_line
			(start -0.67945 0.3048)
			(end -0.120396 0.3048)
			(stroke
				(width 0.1)
				(type default)
			)
			(layer "B.Fab")
		)
		(pad "1" smd circle
			(at 0.40005 0 270)
			(size 0 0)
			(layers "B.Cu" "B.Mask" "B.Paste")
			(net "PVNN_TERM_CPU0")
		)
		(pad "2" smd circle
			(at -0.40005 0 270)
			(size 0 0)
			(layers "B.Cu" "B.Mask" "B.Paste")
			(net "JTAG_CPU0_MUX_GTL_TDO")
		)
	)
	(footprint ""
		(layer "B.Cu")
		(at 239.615726 -128.670812 90)
		(property "Reference" "R108"
			(at 0 0 90)
			(layer "B.SilkS")
			(hide yes)
			(effects
				(font
					(size 1.27 1.27)
				)
				(justify mirror)
			)
		)
		(property "Value" ""
			(at 0 0 90)
			(layer "B.Fab")
			(effects
				(font
					(size 1.27 1.27)
				)
				(justify mirror)
			)
		)
		(duplicate_pad_numbers_are_jumpers no)
		(fp_line
			(start 0.7874 -0.4064)
			(end -0.7874 -0.4064)
			(stroke
				(width 0.1524)
				(type default)
			)
			(layer "B.SilkS")
		)
		(fp_line
			(start -0.7874 -0.4064)
			(end -0.7874 0.4064)
			(stroke
				(width 0.1524)
				(type default)
			)
			(layer "B.SilkS")
		)
		(fp_line
			(start 0.7874 0.4064)
			(end 0.7874 -0.4064)
			(stroke
				(width 0.1524)
				(type default)
			)
			(layer "B.SilkS")
		)
		(fp_line
			(start -0.7874 0.4064)
			(end 0.7874 0.4064)
			(stroke
				(width 0.1524)
				(type default)
			)
			(layer "B.SilkS")
		)
		(fp_line
			(start 0.67945 -0.305054)
			(end 0.12065 -0.305054)
			(stroke
				(width 0.1)
				(type default)
			)
			(layer "B.Fab")
		)
		(fp_line
			(start 0.12065 -0.305054)
			(end 0.12065 -0.2794)
			(stroke
				(width 0.1)
				(type default)
			)
			(layer "B.Fab")
		)
		(fp_line
			(start -0.12065 -0.3048)
			(end -0.67945 -0.3048)
			(stroke
				(width 0.1)
				(type default)
			)
			(layer "B.Fab")
		)
		(fp_line
			(start -0.67945 -0.3048)
			(end -0.67945 0.3048)
			(stroke
				(width 0.1)
				(type default)
			)
			(layer "B.Fab")
		)
		(fp_line
			(start 0.12065 -0.2794)
			(end -0.12065 -0.2794)
			(stroke
				(width 0.1)
				(type default)
			)
			(layer "B.Fab")
		)
		(fp_line
			(start -0.12065 -0.2794)
			(end -0.12065 -0.3048)
			(stroke
				(width 0.1)
				(type default)
			)
			(layer "B.Fab")
		)
		(fp_line
			(start 0.12065 0.2794)
			(end 0.12065 0.3048)
			(stroke
				(width 0.1)
				(type default)
			)
			(layer "B.Fab")
		)
		(fp_line
			(start -0.120396 0.2794)
			(end 0.12065 0.2794)
			(stroke
				(width 0.1)
				(type default)
			)
			(layer "B.Fab")
		)
		(fp_line
			(start 0.67945 0.3048)
			(end 0.67945 -0.305054)
			(stroke
				(width 0.1)
				(type default)
			)
			(layer "B.Fab")
		)
		(fp_line
			(start 0.12065 0.3048)
			(end 0.67945 0.3048)
			(stroke
				(width 0.1)
				(type default)
			)
			(layer "B.Fab")
		)
		(fp_line
			(start -0.120396 0.3048)
			(end -0.120396 0.2794)
			(stroke
				(width 0.1)
				(type default)
			)
			(layer "B.Fab")
		)
		(fp_line
			(start -0.67945 0.3048)
			(end -0.120396 0.3048)
			(stroke
				(width 0.1)
				(type default)
			)
			(layer "B.Fab")
		)
		(pad "1" smd circle
			(at 0.40005 0 270)
			(size 0 0)
			(layers "B.Cu" "B.Mask" "B.Paste")
			(net "SMB_HOST_3V3AUX_SDA_R")
		)
		(pad "2" smd circle
			(at -0.40005 0 270)
			(size 0 0)
			(layers "B.Cu" "B.Mask" "B.Paste")
			(net "SMB_HOST_CLK_BUF_3V3AUX_SDA")
		)
	)
	(footprint ""
		(layer "B.Cu")
		(at 436.926482 -317.848996 90)
		(property "Reference" "R3888"
			(at 0 0 90)
			(layer "B.SilkS")
			(hide yes)
			(effects
				(font
					(size 1.27 1.27)
				)
				(justify mirror)
			)
		)
		(property "Value" ""
			(at 0 0 90)
			(layer "B.Fab")
			(effects
				(font
					(size 1.27 1.27)
				)
				(justify mirror)
			)
		)
		(duplicate_pad_numbers_are_jumpers no)
		(fp_line
			(start 0.7874 -0.4064)
			(end -0.7874 -0.4064)
			(stroke
				(width 0.1524)
				(type default)
			)
			(layer "B.SilkS")
		)
		(fp_line
			(start -0.7874 -0.4064)
			(end -0.7874 0.4064)
			(stroke
				(width 0.1524)
				(type default)
			)
			(layer "B.SilkS")
		)
		(fp_line
			(start 0.7874 0.4064)
			(end 0.7874 -0.4064)
			(stroke
				(width 0.1524)
				(type default)
			)
			(layer "B.SilkS")
		)
		(fp_line
			(start -0.7874 0.4064)
			(end 0.7874 0.4064)
			(stroke
				(width 0.1524)
				(type default)
			)
			(layer "B.SilkS")
		)
		(fp_line
			(start 0.67945 -0.305054)
			(end 0.12065 -0.305054)
			(stroke
				(width 0.1)
				(type default)
			)
			(layer "B.Fab")
		)
		(fp_line
			(start 0.12065 -0.305054)
			(end 0.12065 -0.2794)
			(stroke
				(width 0.1)
				(type default)
			)
			(layer "B.Fab")
		)
		(fp_line
			(start -0.12065 -0.3048)
			(end -0.67945 -0.3048)
			(stroke
				(width 0.1)
				(type default)
			)
			(layer "B.Fab")
		)
		(fp_line
			(start -0.67945 -0.3048)
			(end -0.67945 0.3048)
			(stroke
				(width 0.1)
				(type default)
			)
			(layer "B.Fab")
		)
		(fp_line
			(start 0.12065 -0.2794)
			(end -0.12065 -0.2794)
			(stroke
				(width 0.1)
				(type default)
			)
			(layer "B.Fab")
		)
		(fp_line
			(start -0.12065 -0.2794)
			(end -0.12065 -0.3048)
			(stroke
				(width 0.1)
				(type default)
			)
			(layer "B.Fab")
		)
		(fp_line
			(start 0.12065 0.2794)
			(end 0.12065 0.3048)
			(stroke
				(width 0.1)
				(type default)
			)
			(layer "B.Fab")
		)
		(fp_line
			(start -0.120396 0.2794)
			(end 0.12065 0.2794)
			(stroke
				(width 0.1)
				(type default)
			)
			(layer "B.Fab")
		)
		(fp_line
			(start 0.67945 0.3048)
			(end 0.67945 -0.305054)
			(stroke
				(width 0.1)
				(type default)
			)
			(layer "B.Fab")
		)
		(fp_line
			(start 0.12065 0.3048)
			(end 0.67945 0.3048)
			(stroke
				(width 0.1)
				(type default)
			)
			(layer "B.Fab")
		)
		(fp_line
			(start -0.120396 0.3048)
			(end -0.120396 0.2794)
			(stroke
				(width 0.1)
				(type default)
			)
			(layer "B.Fab")
		)
		(fp_line
			(start -0.67945 0.3048)
			(end -0.120396 0.3048)
			(stroke
				(width 0.1)
				(type default)
			)
			(layer "B.Fab")
		)
		(pad "1" smd circle
			(at 0.40005 0 270)
			(size 0 0)
			(layers "B.Cu" "B.Mask" "B.Paste")
			(net "I3C_SPD_DDREFGH_CPU0_LVC1_SCL_5")
		)
		(pad "2" smd circle
			(at -0.40005 0 270)
			(size 0 0)
			(layers "B.Cu" "B.Mask" "B.Paste")
			(net "I3C_SPD_DDREFGH_CPU0_LVC1_SCL")
		)
	)
	(footprint ""
		(layer "B.Cu")
		(at 75.460098 -184.255918 -90)
		(property "Reference" "R262"
			(at 0 0 90)
			(layer "B.SilkS")
			(hide yes)
			(effects
				(font
					(size 1.27 1.27)
				)
				(justify mirror)
			)
		)
		(property "Value" ""
			(at 0 0 90)
			(layer "B.Fab")
			(effects
				(font
					(size 1.27 1.27)
				)
				(justify mirror)
			)
		)
		(duplicate_pad_numbers_are_jumpers no)
		(fp_line
			(start -0.7874 0.4064)
			(end 0.7874 0.4064)
			(stroke
				(width 0.1524)
				(type default)
			)
			(layer "B.SilkS")
		)
		(fp_line
			(start 0.7874 0.4064)
			(end 0.7874 -0.4064)
			(stroke
				(width 0.1524)
				(type default)
			)
			(layer "B.SilkS")
		)
		(fp_line
			(start -0.7874 -0.4064)
			(end -0.7874 0.4064)
			(stroke
				(width 0.1524)
				(type default)
			)
			(layer "B.SilkS")
		)
		(fp_line
			(start 0.7874 -0.4064)
			(end -0.7874 -0.4064)
			(stroke
				(width 0.1524)
				(type default)
			)
			(layer "B.SilkS")
		)
		(fp_line
			(start -0.67945 0.3048)
			(end -0.120396 0.3048)
			(stroke
				(width 0.1)
				(type default)
			)
			(layer "B.Fab")
		)
		(fp_line
			(start -0.120396 0.3048)
			(end -0.120396 0.2794)
			(stroke
				(width 0.1)
				(type default)
			)
			(layer "B.Fab")
		)
		(fp_line
			(start 0.12065 0.3048)
			(end 0.67945 0.3048)
			(stroke
				(width 0.1)
				(type default)
			)
			(layer "B.Fab")
		)
		(fp_line
			(start 0.67945 0.3048)
			(end 0.67945 -0.305054)
			(stroke
				(width 0.1)
				(type default)
			)
			(layer "B.Fab")
		)
		(fp_line
			(start -0.120396 0.2794)
			(end 0.12065 0.2794)
			(stroke
				(width 0.1)
				(type default)
			)
			(layer "B.Fab")
		)
		(fp_line
			(start 0.12065 0.2794)
			(end 0.12065 0.3048)
			(stroke
				(width 0.1)
				(type default)
			)
			(layer "B.Fab")
		)
		(fp_line
			(start -0.12065 -0.2794)
			(end -0.12065 -0.3048)
			(stroke
				(width 0.1)
				(type default)
			)
			(layer "B.Fab")
		)
		(fp_line
			(start 0.12065 -0.2794)
			(end -0.12065 -0.2794)
			(stroke
				(width 0.1)
				(type default)
			)
			(layer "B.Fab")
		)
		(fp_line
			(start -0.67945 -0.3048)
			(end -0.67945 0.3048)
			(stroke
				(width 0.1)
				(type default)
			)
			(layer "B.Fab")
		)
		(fp_line
			(start -0.12065 -0.3048)
			(end -0.67945 -0.3048)
			(stroke
				(width 0.1)
				(type default)
			)
			(layer "B.Fab")
		)
		(fp_line
			(start 0.12065 -0.305054)
			(end 0.12065 -0.2794)
			(stroke
				(width 0.1)
				(type default)
			)
			(layer "B.Fab")
		)
		(fp_line
			(start 0.67945 -0.305054)
			(end 0.12065 -0.305054)
			(stroke
				(width 0.1)
				(type default)
			)
			(layer "B.Fab")
		)
		(pad "1" smd circle
			(at 0.40005 0 90)
			(size 0 0)
			(layers "B.Cu" "B.Mask" "B.Paste")
			(net "PVNN_TERM_CPU1")
		)
		(pad "2" smd circle
			(at -0.40005 0 90)
			(size 0 0)
			(layers "B.Cu" "B.Mask" "B.Paste")
			(net "PU_CPU1_SAFE_MODE_BOOT")
		)
	)
	(footprint ""
		(layer "B.Cu")
		(at 179.755546 -115.775486 90)
		(property "Reference" "C1915"
			(at 0 0 90)
			(layer "B.SilkS")
			(hide yes)
			(effects
				(font
					(size 1.27 1.27)
				)
				(justify mirror)
			)
		)
		(property "Value" ""
			(at 0 0 90)
			(layer "B.Fab")
			(effects
				(font
					(size 1.27 1.27)
				)
				(justify mirror)
			)
		)
		(duplicate_pad_numbers_are_jumpers no)
		(fp_line
			(start 0.69215 -0.2921)
			(end -0.69215 -0.2921)
			(stroke
				(width 0.1524)
				(type default)
			)
			(layer "B.SilkS")
		)
		(fp_line
			(start -0.69215 -0.2921)
			(end -0.69215 0.2921)
			(stroke
				(width 0.1524)
				(type default)
			)
			(layer "B.SilkS")
		)
		(fp_line
			(start 0.69215 0.2921)
			(end 0.69215 -0.2921)
			(stroke
				(width 0.1524)
				(type default)
			)
			(layer "B.SilkS")
		)
		(fp_line
			(start -0.69215 0.2921)
			(end 0.69215 0.2921)
			(stroke
				(width 0.1524)
				(type default)
			)
			(layer "B.SilkS")
		)
		(fp_line
			(start 0.51435 -0.2794)
			(end -0.51435 -0.2794)
			(stroke
				(width 0.1)
				(type default)
			)
			(layer "B.Fab")
		)
		(fp_line
			(start -0.51435 -0.2794)
			(end -0.51435 0.2794)
			(stroke
				(width 0.1)
				(type default)
			)
			(layer "B.Fab")
		)
		(fp_line
			(start 0.51435 0.2794)
			(end 0.51435 -0.2794)
			(stroke
				(width 0.1)
				(type default)
			)
			(layer "B.Fab")
		)
		(fp_line
			(start -0.51435 0.2794)
			(end 0.51435 0.2794)
			(stroke
				(width 0.1)
				(type default)
			)
			(layer "B.Fab")
		)
		(pad "1" smd circle
			(at 0.40005 0 270)
			(size 0 0)
			(layers "B.Cu" "B.Mask" "B.Paste")
			(net "P3V3_AUX_FPGA_VCCIO1")
		)
		(pad "2" smd circle
			(at -0.40005 0 270)
			(size 0 0)
			(layers "B.Cu" "B.Mask" "B.Paste")
			(net "GND")
		)
		(zone
			(layer "B.Cu")
			(hatch none 0.5)
			(connect_pads
				(clearance 0)
			)
			(min_thickness 0.25)
			(keepout
				(tracks not_allowed)
				(vias allowed)
				(pads allowed)
				(copperpour not_allowed)
				(footprints allowed)
			)
			(placement
				(enabled no)
				(sheetname "")
			)
			(fill
				(thermal_gap 0.5)
				(thermal_bridge_width 0.5)
				(island_removal_mode 0)
			)
			(polygon
				(pts
					(xy 179.843176 -115.965986) (xy 179.901342 -115.874546) (xy 179.901342 -115.675156) (xy 179.843176 -115.584986)
					(xy 179.667916 -115.584986) (xy 179.609496 -115.675156) (xy 179.609496 -115.874546) (xy 179.667662 -115.965986)
				)
			)
		)
	)
	(footprint ""
		(layer "B.Cu")
		(at 295.628314 -319.177416 -90)
		(property "Reference" "R29"
			(at 0 0 90)
			(layer "B.SilkS")
			(hide yes)
			(effects
				(font
					(size 1.27 1.27)
				)
				(justify mirror)
			)
		)
		(property "Value" ""
			(at 0 0 90)
			(layer "B.Fab")
			(effects
				(font
					(size 1.27 1.27)
				)
				(justify mirror)
			)
		)
		(duplicate_pad_numbers_are_jumpers no)
		(fp_line
			(start -0.7874 0.4064)
			(end 0.7874 0.4064)
			(stroke
				(width 0.1524)
				(type default)
			)
			(layer "B.SilkS")
		)
		(fp_line
			(start 0.7874 0.4064)
			(end 0.7874 -0.4064)
			(stroke
				(width 0.1524)
				(type default)
			)
			(layer "B.SilkS")
		)
		(fp_line
			(start -0.7874 -0.4064)
			(end -0.7874 0.4064)
			(stroke
				(width 0.1524)
				(type default)
			)
			(layer "B.SilkS")
		)
		(fp_line
			(start 0.7874 -0.4064)
			(end -0.7874 -0.4064)
			(stroke
				(width 0.1524)
				(type default)
			)
			(layer "B.SilkS")
		)
		(fp_line
			(start -0.67945 0.3048)
			(end -0.120396 0.3048)
			(stroke
				(width 0.1)
				(type default)
			)
			(layer "B.Fab")
		)
		(fp_line
			(start -0.120396 0.3048)
			(end -0.120396 0.2794)
			(stroke
				(width 0.1)
				(type default)
			)
			(layer "B.Fab")
		)
		(fp_line
			(start 0.12065 0.3048)
			(end 0.67945 0.3048)
			(stroke
				(width 0.1)
				(type default)
			)
			(layer "B.Fab")
		)
		(fp_line
			(start 0.67945 0.3048)
			(end 0.67945 -0.305054)
			(stroke
				(width 0.1)
				(type default)
			)
			(layer "B.Fab")
		)
		(fp_line
			(start -0.120396 0.2794)
			(end 0.12065 0.2794)
			(stroke
				(width 0.1)
				(type default)
			)
			(layer "B.Fab")
		)
		(fp_line
			(start 0.12065 0.2794)
			(end 0.12065 0.3048)
			(stroke
				(width 0.1)
				(type default)
			)
			(layer "B.Fab")
		)
		(fp_line
			(start -0.12065 -0.2794)
			(end -0.12065 -0.3048)
			(stroke
				(width 0.1)
				(type default)
			)
			(layer "B.Fab")
		)
		(fp_line
			(start 0.12065 -0.2794)
			(end -0.12065 -0.2794)
			(stroke
				(width 0.1)
				(type default)
			)
			(layer "B.Fab")
		)
		(fp_line
			(start -0.67945 -0.3048)
			(end -0.67945 0.3048)
			(stroke
				(width 0.1)
				(type default)
			)
			(layer "B.Fab")
		)
		(fp_line
			(start -0.12065 -0.3048)
			(end -0.67945 -0.3048)
			(stroke
				(width 0.1)
				(type default)
			)
			(layer "B.Fab")
		)
		(fp_line
			(start 0.12065 -0.305054)
			(end 0.12065 -0.2794)
			(stroke
				(width 0.1)
				(type default)
			)
			(layer "B.Fab")
		)
		(fp_line
			(start 0.67945 -0.305054)
			(end 0.12065 -0.305054)
			(stroke
				(width 0.1)
				(type default)
			)
			(layer "B.Fab")
		)
		(pad "1" smd circle
			(at 0.40005 0 90)
			(size 0 0)
			(layers "B.Cu" "B.Mask" "B.Paste")
			(net "PD_CHB_CPU0_DIMM2_SAA")
		)
		(pad "2" smd circle
			(at -0.40005 0 90)
			(size 0 0)
			(layers "B.Cu" "B.Mask" "B.Paste")
			(net "GND")
		)
	)
	(footprint ""
		(layer "B.Cu")
		(at 178.9557 -110.975394 -90)
		(property "Reference" "C1893"
			(at 0 0 90)
			(layer "B.SilkS")
			(hide yes)
			(effects
				(font
					(size 1.27 1.27)
				)
				(justify mirror)
			)
		)
		(property "Value" ""
			(at 0 0 90)
			(layer "B.Fab")
			(effects
				(font
					(size 1.27 1.27)
				)
				(justify mirror)
			)
		)
		(duplicate_pad_numbers_are_jumpers no)
		(fp_line
			(start -0.69215 0.2921)
			(end 0.69215 0.2921)
			(stroke
				(width 0.1524)
				(type default)
			)
			(layer "B.SilkS")
		)
		(fp_line
			(start 0.69215 0.2921)
			(end 0.69215 -0.2921)
			(stroke
				(width 0.1524)
				(type default)
			)
			(layer "B.SilkS")
		)
		(fp_line
			(start -0.69215 -0.2921)
			(end -0.69215 0.2921)
			(stroke
				(width 0.1524)
				(type default)
			)
			(layer "B.SilkS")
		)
		(fp_line
			(start 0.69215 -0.2921)
			(end -0.69215 -0.2921)
			(stroke
				(width 0.1524)
				(type default)
			)
			(layer "B.SilkS")
		)
		(fp_line
			(start -0.51435 0.2794)
			(end 0.51435 0.2794)
			(stroke
				(width 0.1)
				(type default)
			)
			(layer "B.Fab")
		)
		(fp_line
			(start 0.51435 0.2794)
			(end 0.51435 -0.2794)
			(stroke
				(width 0.1)
				(type default)
			)
			(layer "B.Fab")
		)
		(fp_line
			(start -0.51435 -0.2794)
			(end -0.51435 0.2794)
			(stroke
				(width 0.1)
				(type default)
			)
			(layer "B.Fab")
		)
		(fp_line
			(start 0.51435 -0.2794)
			(end -0.51435 -0.2794)
			(stroke
				(width 0.1)
				(type default)
			)
			(layer "B.Fab")
		)
		(pad "1" smd circle
			(at 0.40005 0 90)
			(size 0 0)
			(layers "B.Cu" "B.Mask" "B.Paste")
			(net "P3V3_AUX_FPGA_VCCIO4")
		)
		(pad "2" smd circle
			(at -0.40005 0 90)
			(size 0 0)
			(layers "B.Cu" "B.Mask" "B.Paste")
			(net "GND")
		)
		(zone
			(layer "B.Cu")
			(hatch none 0.5)
			(connect_pads
				(clearance 0)
			)
			(min_thickness 0.25)
			(keepout
				(tracks not_allowed)
				(vias allowed)
				(pads allowed)
				(copperpour not_allowed)
				(footprints allowed)
			)
			(placement
				(enabled no)
				(sheetname "")
			)
			(fill
				(thermal_gap 0.5)
				(thermal_bridge_width 0.5)
				(island_removal_mode 0)
			)
			(polygon
				(pts
					(xy 178.86807 -110.784894) (xy 178.809904 -110.876334) (xy 178.809904 -111.075724) (xy 178.86807 -111.165894)
					(xy 179.04333 -111.165894) (xy 179.10175 -111.075724) (xy 179.10175 -110.876334) (xy 179.043584 -110.784894)
				)
			)
		)
	)
	(footprint ""
		(layer "B.Cu")
		(at 386.214112 -331.60208 -90)
		(property "Reference" "PC244_P0_8"
			(at 0 0 90)
			(layer "B.SilkS")
			(hide yes)
			(effects
				(font
					(size 1.27 1.27)
				)
				(justify mirror)
			)
		)
		(property "Value" ""
			(at 0 0 90)
			(layer "B.Fab")
			(effects
				(font
					(size 1.27 1.27)
				)
				(justify mirror)
			)
		)
		(duplicate_pad_numbers_are_jumpers no)
		(fp_line
			(start -1.524 0.762)
			(end 1.524 0.762)
			(stroke
				(width 0.1524)
				(type default)
			)
			(layer "B.SilkS")
		)
		(fp_line
			(start 1.524 0.762)
			(end 1.524 -0.762)
			(stroke
				(width 0.1524)
				(type default)
			)
			(layer "B.SilkS")
		)
		(fp_line
			(start -1.524 -0.762)
			(end -1.524 0.762)
			(stroke
				(width 0.1524)
				(type default)
			)
			(layer "B.SilkS")
		)
		(fp_line
			(start 1.524 -0.762)
			(end -1.524 -0.762)
			(stroke
				(width 0.1524)
				(type default)
			)
			(layer "B.SilkS")
		)
		(fp_line
			(start -1.1049 0.724916)
			(end -1.1049 -0.724916)
			(stroke
				(width 0.1)
				(type default)
			)
			(layer "B.Fab")
		)
		(fp_line
			(start 1.1049 0.724916)
			(end -1.1049 0.724916)
			(stroke
				(width 0.1)
				(type default)
			)
			(layer "B.Fab")
		)
		(fp_line
			(start -1.1049 -0.724916)
			(end 1.1049 -0.724916)
			(stroke
				(width 0.1)
				(type default)
			)
			(layer "B.Fab")
		)
		(fp_line
			(start 1.1049 -0.724916)
			(end 1.1049 0.724916)
			(stroke
				(width 0.1)
				(type default)
			)
			(layer "B.Fab")
		)
		(pad "1" smd rect
			(at 0.889 0 270)
			(size 1.016 1.27)
			(layers "B.Cu" "B.Mask" "B.Paste")
			(net "PVCCIN_CPU0")
		)
		(pad "2" smd rect
			(at -0.889 0 270)
			(size 1.016 1.27)
			(layers "B.Cu" "B.Mask" "B.Paste")
			(net "GND")
		)
	)
	(footprint ""
		(layer "B.Cu")
		(at 65.828926 -20.04822)
		(property "Reference" "PC2141"
			(at 0 0 0)
			(layer "B.SilkS")
			(hide yes)
			(effects
				(font
					(size 1.27 1.27)
				)
				(justify mirror)
			)
		)
		(property "Value" ""
			(at 0 0 0)
			(layer "B.Fab")
			(effects
				(font
					(size 1.27 1.27)
				)
				(justify mirror)
			)
		)
		(duplicate_pad_numbers_are_jumpers no)
		(fp_line
			(start -1.524 -0.762)
			(end -1.524 0.762)
			(stroke
				(width 0.1524)
				(type default)
			)
			(layer "B.SilkS")
		)
		(fp_line
			(start -1.524 0.762)
			(end 1.524 0.762)
			(stroke
				(width 0.1524)
				(type default)
			)
			(layer "B.SilkS")
		)
		(fp_line
			(start 1.524 -0.762)
			(end -1.524 -0.762)
			(stroke
				(width 0.1524)
				(type default)
			)
			(layer "B.SilkS")
		)
		(fp_line
			(start 1.524 0.762)
			(end 1.524 -0.762)
			(stroke
				(width 0.1524)
				(type default)
			)
			(layer "B.SilkS")
		)
		(fp_line
			(start -1.1049 -0.724916)
			(end 1.1049 -0.724916)
			(stroke
				(width 0.1)
				(type default)
			)
			(layer "B.Fab")
		)
		(fp_line
			(start -1.1049 0.724916)
			(end -1.1049 -0.724916)
			(stroke
				(width 0.1)
				(type default)
			)
			(layer "B.Fab")
		)
		(fp_line
			(start 1.1049 -0.724916)
			(end 1.1049 0.724916)
			(stroke
				(width 0.1)
				(type default)
			)
			(layer "B.Fab")
		)
		(fp_line
			(start 1.1049 0.724916)
			(end -1.1049 0.724916)
			(stroke
				(width 0.1)
				(type default)
			)
			(layer "B.Fab")
		)
		(pad "1" smd rect
			(at 0.889 0)
			(size 1.016 1.27)
			(layers "B.Cu" "B.Mask" "B.Paste")
			(net "P12V_OCP_V3_2")
		)
		(pad "2" smd rect
			(at -0.889 0)
			(size 1.016 1.27)
			(layers "B.Cu" "B.Mask" "B.Paste")
			(net "GND")
		)
	)
	(footprint ""
		(layer "B.Cu")
		(at 229.761796 -128.866392 180)
		(property "Reference" "R576"
			(at 0 0 0)
			(layer "B.SilkS")
			(hide yes)
			(effects
				(font
					(size 1.27 1.27)
				)
				(justify mirror)
			)
		)
		(property "Value" ""
			(at 0 0 0)
			(layer "B.Fab")
			(effects
				(font
					(size 1.27 1.27)
				)
				(justify mirror)
			)
		)
		(duplicate_pad_numbers_are_jumpers no)
		(fp_line
			(start 0.7874 0.4064)
			(end 0.7874 -0.4064)
			(stroke
				(width 0.1524)
				(type default)
			)
			(layer "B.SilkS")
		)
		(fp_line
			(start 0.7874 -0.4064)
			(end -0.7874 -0.4064)
			(stroke
				(width 0.1524)
				(type default)
			)
			(layer "B.SilkS")
		)
		(fp_line
			(start -0.7874 0.4064)
			(end 0.7874 0.4064)
			(stroke
				(width 0.1524)
				(type default)
			)
			(layer "B.SilkS")
		)
		(fp_line
			(start -0.7874 -0.4064)
			(end -0.7874 0.4064)
			(stroke
				(width 0.1524)
				(type default)
			)
			(layer "B.SilkS")
		)
		(fp_line
			(start 0.67945 0.3048)
			(end 0.67945 -0.305054)
			(stroke
				(width 0.1)
				(type default)
			)
			(layer "B.Fab")
		)
		(fp_line
			(start 0.67945 -0.305054)
			(end 0.12065 -0.305054)
			(stroke
				(width 0.1)
				(type default)
			)
			(layer "B.Fab")
		)
		(fp_line
			(start 0.12065 0.3048)
			(end 0.67945 0.3048)
			(stroke
				(width 0.1)
				(type default)
			)
			(layer "B.Fab")
		)
		(fp_line
			(start 0.12065 0.2794)
			(end 0.12065 0.3048)
			(stroke
				(width 0.1)
				(type default)
			)
			(layer "B.Fab")
		)
		(fp_line
			(start 0.12065 -0.2794)
			(end -0.12065 -0.2794)
			(stroke
				(width 0.1)
				(type default)
			)
			(layer "B.Fab")
		)
		(fp_line
			(start 0.12065 -0.305054)
			(end 0.12065 -0.2794)
			(stroke
				(width 0.1)
				(type default)
			)
			(layer "B.Fab")
		)
		(fp_line
			(start -0.120396 0.3048)
			(end -0.120396 0.2794)
			(stroke
				(width 0.1)
				(type default)
			)
			(layer "B.Fab")
		)
		(fp_line
			(start -0.120396 0.2794)
			(end 0.12065 0.2794)
			(stroke
				(width 0.1)
				(type default)
			)
			(layer "B.Fab")
		)
		(fp_line
			(start -0.12065 -0.2794)
			(end -0.12065 -0.3048)
			(stroke
				(width 0.1)
				(type default)
			)
			(layer "B.Fab")
		)
		(fp_line
			(start -0.12065 -0.3048)
			(end -0.67945 -0.3048)
			(stroke
				(width 0.1)
				(type default)
			)
			(layer "B.Fab")
		)
		(fp_line
			(start -0.67945 0.3048)
			(end -0.120396 0.3048)
			(stroke
				(width 0.1)
				(type default)
			)
			(layer "B.Fab")
		)
		(fp_line
			(start -0.67945 -0.3048)
			(end -0.67945 0.3048)
			(stroke
				(width 0.1)
				(type default)
			)
			(layer "B.Fab")
		)
		(pad "1" smd circle
			(at 0.40005 0)
			(size 0 0)
			(layers "B.Cu" "B.Mask" "B.Paste")
			(net "FM_DB2000_OE_N")
		)
		(pad "2" smd circle
			(at -0.40005 0)
			(size 0 0)
			(layers "B.Cu" "B.Mask" "B.Paste")
			(net "FM_DB2000_1_OE_N")
		)
	)
	(footprint ""
		(layer "B.Cu")
		(at 252.718824 -108.179108 -90)
		(property "Reference" "R1500"
			(at 0 0 90)
			(layer "B.SilkS")
			(hide yes)
			(effects
				(font
					(size 1.27 1.27)
				)
				(justify mirror)
			)
		)
		(property "Value" ""
			(at 0 0 90)
			(layer "B.Fab")
			(effects
				(font
					(size 1.27 1.27)
				)
				(justify mirror)
			)
		)
		(duplicate_pad_numbers_are_jumpers no)
		(fp_line
			(start -0.7874 0.4064)
			(end 0.7874 0.4064)
			(stroke
				(width 0.1524)
				(type default)
			)
			(layer "B.SilkS")
		)
		(fp_line
			(start 0.7874 0.4064)
			(end 0.7874 -0.4064)
			(stroke
				(width 0.1524)
				(type default)
			)
			(layer "B.SilkS")
		)
		(fp_line
			(start -0.7874 -0.4064)
			(end -0.7874 0.4064)
			(stroke
				(width 0.1524)
				(type default)
			)
			(layer "B.SilkS")
		)
		(fp_line
			(start 0.7874 -0.4064)
			(end -0.7874 -0.4064)
			(stroke
				(width 0.1524)
				(type default)
			)
			(layer "B.SilkS")
		)
		(fp_line
			(start -0.67945 0.3048)
			(end -0.120396 0.3048)
			(stroke
				(width 0.1)
				(type default)
			)
			(layer "B.Fab")
		)
		(fp_line
			(start -0.120396 0.3048)
			(end -0.120396 0.2794)
			(stroke
				(width 0.1)
				(type default)
			)
			(layer "B.Fab")
		)
		(fp_line
			(start 0.12065 0.3048)
			(end 0.67945 0.3048)
			(stroke
				(width 0.1)
				(type default)
			)
			(layer "B.Fab")
		)
		(fp_line
			(start 0.67945 0.3048)
			(end 0.67945 -0.305054)
			(stroke
				(width 0.1)
				(type default)
			)
			(layer "B.Fab")
		)
		(fp_line
			(start -0.120396 0.2794)
			(end 0.12065 0.2794)
			(stroke
				(width 0.1)
				(type default)
			)
			(layer "B.Fab")
		)
		(fp_line
			(start 0.12065 0.2794)
			(end 0.12065 0.3048)
			(stroke
				(width 0.1)
				(type default)
			)
			(layer "B.Fab")
		)
		(fp_line
			(start -0.12065 -0.2794)
			(end -0.12065 -0.3048)
			(stroke
				(width 0.1)
				(type default)
			)
			(layer "B.Fab")
		)
		(fp_line
			(start 0.12065 -0.2794)
			(end -0.12065 -0.2794)
			(stroke
				(width 0.1)
				(type default)
			)
			(layer "B.Fab")
		)
		(fp_line
			(start -0.67945 -0.3048)
			(end -0.67945 0.3048)
			(stroke
				(width 0.1)
				(type default)
			)
			(layer "B.Fab")
		)
		(fp_line
			(start -0.12065 -0.3048)
			(end -0.67945 -0.3048)
			(stroke
				(width 0.1)
				(type default)
			)
			(layer "B.Fab")
		)
		(fp_line
			(start 0.12065 -0.305054)
			(end 0.12065 -0.2794)
			(stroke
				(width 0.1)
				(type default)
			)
			(layer "B.Fab")
		)
		(fp_line
			(start 0.67945 -0.305054)
			(end 0.12065 -0.305054)
			(stroke
				(width 0.1)
				(type default)
			)
			(layer "B.Fab")
		)
		(pad "1" smd circle
			(at 0.40005 0 90)
			(size 0 0)
			(layers "B.Cu" "B.Mask" "B.Paste")
			(net "PD_CK440_SBI_DATA_IN")
		)
		(pad "2" smd circle
			(at -0.40005 0 90)
			(size 0 0)
			(layers "B.Cu" "B.Mask" "B.Paste")
			(net "GND")
		)
	)
	(footprint ""
		(layer "B.Cu")
		(at 102.845616 -360.296968 180)
		(property "Reference" "R2522"
			(at 0 0 0)
			(layer "B.SilkS")
			(hide yes)
			(effects
				(font
					(size 1.27 1.27)
				)
				(justify mirror)
			)
		)
		(property "Value" ""
			(at 0 0 0)
			(layer "B.Fab")
			(effects
				(font
					(size 1.27 1.27)
				)
				(justify mirror)
			)
		)
		(duplicate_pad_numbers_are_jumpers no)
		(fp_line
			(start 0.7874 0.4064)
			(end 0.7874 -0.4064)
			(stroke
				(width 0.1524)
				(type default)
			)
			(layer "B.SilkS")
		)
		(fp_line
			(start 0.7874 -0.4064)
			(end -0.7874 -0.4064)
			(stroke
				(width 0.1524)
				(type default)
			)
			(layer "B.SilkS")
		)
		(fp_line
			(start -0.7874 0.4064)
			(end 0.7874 0.4064)
			(stroke
				(width 0.1524)
				(type default)
			)
			(layer "B.SilkS")
		)
		(fp_line
			(start -0.7874 -0.4064)
			(end -0.7874 0.4064)
			(stroke
				(width 0.1524)
				(type default)
			)
			(layer "B.SilkS")
		)
		(fp_line
			(start 0.67945 0.3048)
			(end 0.67945 -0.305054)
			(stroke
				(width 0.1)
				(type default)
			)
			(layer "B.Fab")
		)
		(fp_line
			(start 0.67945 -0.305054)
			(end 0.12065 -0.305054)
			(stroke
				(width 0.1)
				(type default)
			)
			(layer "B.Fab")
		)
		(fp_line
			(start 0.12065 0.3048)
			(end 0.67945 0.3048)
			(stroke
				(width 0.1)
				(type default)
			)
			(layer "B.Fab")
		)
		(fp_line
			(start 0.12065 0.2794)
			(end 0.12065 0.3048)
			(stroke
				(width 0.1)
				(type default)
			)
			(layer "B.Fab")
		)
		(fp_line
			(start 0.12065 -0.2794)
			(end -0.12065 -0.2794)
			(stroke
				(width 0.1)
				(type default)
			)
			(layer "B.Fab")
		)
		(fp_line
			(start 0.12065 -0.305054)
			(end 0.12065 -0.2794)
			(stroke
				(width 0.1)
				(type default)
			)
			(layer "B.Fab")
		)
		(fp_line
			(start -0.120396 0.3048)
			(end -0.120396 0.2794)
			(stroke
				(width 0.1)
				(type default)
			)
			(layer "B.Fab")
		)
		(fp_line
			(start -0.120396 0.2794)
			(end 0.12065 0.2794)
			(stroke
				(width 0.1)
				(type default)
			)
			(layer "B.Fab")
		)
		(fp_line
			(start -0.12065 -0.2794)
			(end -0.12065 -0.3048)
			(stroke
				(width 0.1)
				(type default)
			)
			(layer "B.Fab")
		)
		(fp_line
			(start -0.12065 -0.3048)
			(end -0.67945 -0.3048)
			(stroke
				(width 0.1)
				(type default)
			)
			(layer "B.Fab")
		)
		(fp_line
			(start -0.67945 0.3048)
			(end -0.120396 0.3048)
			(stroke
				(width 0.1)
				(type default)
			)
			(layer "B.Fab")
		)
		(fp_line
			(start -0.67945 -0.3048)
			(end -0.67945 0.3048)
			(stroke
				(width 0.1)
				(type default)
			)
			(layer "B.Fab")
		)
		(pad "1" smd circle
			(at 0.40005 0)
			(size 0 0)
			(layers "B.Cu" "B.Mask" "B.Paste")
			(net "P3V3_AUX")
		)
		(pad "2" smd circle
			(at -0.40005 0)
			(size 0 0)
			(layers "B.Cu" "B.Mask" "B.Paste")
			(net "IRQ_PVCCIN_CPU1_VRHOT_R_N")
		)
	)
	(footprint ""
		(layer "B.Cu")
		(at 307.16601 -317.306452 90)
		(property "Reference" "C5"
			(at 0 0 90)
			(layer "B.SilkS")
			(hide yes)
			(effects
				(font
					(size 1.27 1.27)
				)
				(justify mirror)
			)
		)
		(property "Value" ""
			(at 0 0 90)
			(layer "B.Fab")
			(effects
				(font
					(size 1.27 1.27)
				)
				(justify mirror)
			)
		)
		(duplicate_pad_numbers_are_jumpers no)
		(fp_line
			(start 0.7874 -0.4064)
			(end -0.7874 -0.4064)
			(stroke
				(width 0.1524)
				(type default)
			)
			(layer "B.SilkS")
		)
		(fp_line
			(start -0.7874 -0.4064)
			(end -0.7874 0.4064)
			(stroke
				(width 0.1524)
				(type default)
			)
			(layer "B.SilkS")
		)
		(fp_line
			(start 0.7874 0.4064)
			(end 0.7874 -0.4064)
			(stroke
				(width 0.1524)
				(type default)
			)
			(layer "B.SilkS")
		)
		(fp_line
			(start -0.7874 0.4064)
			(end 0.7874 0.4064)
			(stroke
				(width 0.1524)
				(type default)
			)
			(layer "B.SilkS")
		)
		(fp_line
			(start 0.67945 -0.305054)
			(end 0.12065 -0.305054)
			(stroke
				(width 0.1)
				(type default)
			)
			(layer "B.Fab")
		)
		(fp_line
			(start 0.12065 -0.305054)
			(end 0.12065 -0.2794)
			(stroke
				(width 0.1)
				(type default)
			)
			(layer "B.Fab")
		)
		(fp_line
			(start -0.12065 -0.3048)
			(end -0.67945 -0.3048)
			(stroke
				(width 0.1)
				(type default)
			)
			(layer "B.Fab")
		)
		(fp_line
			(start -0.67945 -0.3048)
			(end -0.67945 0.3048)
			(stroke
				(width 0.1)
				(type default)
			)
			(layer "B.Fab")
		)
		(fp_line
			(start 0.12065 -0.2794)
			(end -0.12065 -0.2794)
			(stroke
				(width 0.1)
				(type default)
			)
			(layer "B.Fab")
		)
		(fp_line
			(start -0.12065 -0.2794)
			(end -0.12065 -0.3048)
			(stroke
				(width 0.1)
				(type default)
			)
			(layer "B.Fab")
		)
		(fp_line
			(start 0.12065 0.2794)
			(end 0.12065 0.3048)
			(stroke
				(width 0.1)
				(type default)
			)
			(layer "B.Fab")
		)
		(fp_line
			(start -0.120396 0.2794)
			(end 0.12065 0.2794)
			(stroke
				(width 0.1)
				(type default)
			)
			(layer "B.Fab")
		)
		(fp_line
			(start 0.67945 0.3048)
			(end 0.67945 -0.305054)
			(stroke
				(width 0.1)
				(type default)
			)
			(layer "B.Fab")
		)
		(fp_line
			(start 0.12065 0.3048)
			(end 0.67945 0.3048)
			(stroke
				(width 0.1)
				(type default)
			)
			(layer "B.Fab")
		)
		(fp_line
			(start -0.120396 0.3048)
			(end -0.120396 0.2794)
			(stroke
				(width 0.1)
				(type default)
			)
			(layer "B.Fab")
		)
		(fp_line
			(start -0.67945 0.3048)
			(end -0.120396 0.3048)
			(stroke
				(width 0.1)
				(type default)
			)
			(layer "B.Fab")
		)
		(pad "1" smd circle
			(at 0.40005 0 270)
			(size 0 0)
			(layers "B.Cu" "B.Mask" "B.Paste")
			(net "P3V3_AUX")
		)
		(pad "2" smd circle
			(at -0.40005 0 270)
			(size 0 0)
			(layers "B.Cu" "B.Mask" "B.Paste")
			(net "GND")
		)
	)
	(footprint ""
		(layer "B.Cu")
		(at 351.928938 -241.19967 90)
		(property "Reference" "C518"
			(at 0 0 90)
			(layer "B.SilkS")
			(hide yes)
			(effects
				(font
					(size 1.27 1.27)
				)
				(justify mirror)
			)
		)
		(property "Value" ""
			(at 0 0 90)
			(layer "B.Fab")
			(effects
				(font
					(size 1.27 1.27)
				)
				(justify mirror)
			)
		)
		(duplicate_pad_numbers_are_jumpers no)
		(fp_line
			(start 1.524 -0.762)
			(end -1.524 -0.762)
			(stroke
				(width 0.1524)
				(type default)
			)
			(layer "B.SilkS")
		)
		(fp_line
			(start -1.524 -0.762)
			(end -1.524 0.762)
			(stroke
				(width 0.1524)
				(type default)
			)
			(layer "B.SilkS")
		)
		(fp_line
			(start 1.524 0.762)
			(end 1.524 -0.762)
			(stroke
				(width 0.1524)
				(type default)
			)
			(layer "B.SilkS")
		)
		(fp_line
			(start -1.524 0.762)
			(end 1.524 0.762)
			(stroke
				(width 0.1524)
				(type default)
			)
			(layer "B.SilkS")
		)
		(fp_line
			(start 1.1049 -0.724916)
			(end 1.1049 0.724916)
			(stroke
				(width 0.1)
				(type default)
			)
			(layer "B.Fab")
		)
		(fp_line
			(start -1.1049 -0.724916)
			(end 1.1049 -0.724916)
			(stroke
				(width 0.1)
				(type default)
			)
			(layer "B.Fab")
		)
		(fp_line
			(start 1.1049 0.724916)
			(end -1.1049 0.724916)
			(stroke
				(width 0.1)
				(type default)
			)
			(layer "B.Fab")
		)
		(fp_line
			(start -1.1049 0.724916)
			(end -1.1049 -0.724916)
			(stroke
				(width 0.1)
				(type default)
			)
			(layer "B.Fab")
		)
		(pad "1" smd rect
			(at 0.889 0 90)
			(size 1.016 1.27)
			(layers "B.Cu" "B.Mask" "B.Paste")
			(net "PVCCD_HV_CPU0")
		)
		(pad "2" smd rect
			(at -0.889 0 90)
			(size 1.016 1.27)
			(layers "B.Cu" "B.Mask" "B.Paste")
			(net "GND")
		)
	)
	(footprint ""
		(layer "B.Cu")
		(at 164.64788 -120.106948)
		(property "Reference" "R1406"
			(at 0 0 0)
			(layer "B.SilkS")
			(hide yes)
			(effects
				(font
					(size 1.27 1.27)
				)
				(justify mirror)
			)
		)
		(property "Value" ""
			(at 0 0 0)
			(layer "B.Fab")
			(effects
				(font
					(size 1.27 1.27)
				)
				(justify mirror)
			)
		)
		(duplicate_pad_numbers_are_jumpers no)
		(fp_line
			(start -0.7874 -0.4064)
			(end -0.7874 0.4064)
			(stroke
				(width 0.1524)
				(type default)
			)
			(layer "B.SilkS")
		)
		(fp_line
			(start -0.7874 0.4064)
			(end 0.7874 0.4064)
			(stroke
				(width 0.1524)
				(type default)
			)
			(layer "B.SilkS")
		)
		(fp_line
			(start 0.7874 -0.4064)
			(end -0.7874 -0.4064)
			(stroke
				(width 0.1524)
				(type default)
			)
			(layer "B.SilkS")
		)
		(fp_line
			(start 0.7874 0.4064)
			(end 0.7874 -0.4064)
			(stroke
				(width 0.1524)
				(type default)
			)
			(layer "B.SilkS")
		)
		(fp_line
			(start -0.67945 -0.3048)
			(end -0.67945 0.3048)
			(stroke
				(width 0.1)
				(type default)
			)
			(layer "B.Fab")
		)
		(fp_line
			(start -0.67945 0.3048)
			(end -0.120396 0.3048)
			(stroke
				(width 0.1)
				(type default)
			)
			(layer "B.Fab")
		)
		(fp_line
			(start -0.12065 -0.3048)
			(end -0.67945 -0.3048)
			(stroke
				(width 0.1)
				(type default)
			)
			(layer "B.Fab")
		)
		(fp_line
			(start -0.12065 -0.2794)
			(end -0.12065 -0.3048)
			(stroke
				(width 0.1)
				(type default)
			)
			(layer "B.Fab")
		)
		(fp_line
			(start -0.120396 0.2794)
			(end 0.12065 0.2794)
			(stroke
				(width 0.1)
				(type default)
			)
			(layer "B.Fab")
		)
		(fp_line
			(start -0.120396 0.3048)
			(end -0.120396 0.2794)
			(stroke
				(width 0.1)
				(type default)
			)
			(layer "B.Fab")
		)
		(fp_line
			(start 0.12065 -0.305054)
			(end 0.12065 -0.2794)
			(stroke
				(width 0.1)
				(type default)
			)
			(layer "B.Fab")
		)
		(fp_line
			(start 0.12065 -0.2794)
			(end -0.12065 -0.2794)
			(stroke
				(width 0.1)
				(type default)
			)
			(layer "B.Fab")
		)
		(fp_line
			(start 0.12065 0.2794)
			(end 0.12065 0.3048)
			(stroke
				(width 0.1)
				(type default)
			)
			(layer "B.Fab")
		)
		(fp_line
			(start 0.12065 0.3048)
			(end 0.67945 0.3048)
			(stroke
				(width 0.1)
				(type default)
			)
			(layer "B.Fab")
		)
		(fp_line
			(start 0.67945 -0.305054)
			(end 0.12065 -0.305054)
			(stroke
				(width 0.1)
				(type default)
			)
			(layer "B.Fab")
		)
		(fp_line
			(start 0.67945 0.3048)
			(end 0.67945 -0.305054)
			(stroke
				(width 0.1)
				(type default)
			)
			(layer "B.Fab")
		)
		(pad "1" smd circle
			(at 0.40005 0 180)
			(size 0 0)
			(layers "B.Cu" "B.Mask" "B.Paste")
			(net "FM_PVCCIN_CPU1_R_EN")
		)
		(pad "2" smd circle
			(at -0.40005 0 180)
			(size 0 0)
			(layers "B.Cu" "B.Mask" "B.Paste")
			(net "GND")
		)
	)
	(footprint ""
		(layer "B.Cu")
		(at 370.539772 -184.400952 90)
		(property "Reference" "R2477"
			(at 0 0 90)
			(layer "B.SilkS")
			(hide yes)
			(effects
				(font
					(size 1.27 1.27)
				)
				(justify mirror)
			)
		)
		(property "Value" ""
			(at 0 0 90)
			(layer "B.Fab")
			(effects
				(font
					(size 1.27 1.27)
				)
				(justify mirror)
			)
		)
		(duplicate_pad_numbers_are_jumpers no)
		(fp_line
			(start 0.7874 -0.4064)
			(end -0.7874 -0.4064)
			(stroke
				(width 0.1524)
				(type default)
			)
			(layer "B.SilkS")
		)
		(fp_line
			(start -0.7874 -0.4064)
			(end -0.7874 0.4064)
			(stroke
				(width 0.1524)
				(type default)
			)
			(layer "B.SilkS")
		)
		(fp_line
			(start 0.7874 0.4064)
			(end 0.7874 -0.4064)
			(stroke
				(width 0.1524)
				(type default)
			)
			(layer "B.SilkS")
		)
		(fp_line
			(start -0.7874 0.4064)
			(end 0.7874 0.4064)
			(stroke
				(width 0.1524)
				(type default)
			)
			(layer "B.SilkS")
		)
		(fp_line
			(start 0.67945 -0.305054)
			(end 0.12065 -0.305054)
			(stroke
				(width 0.1)
				(type default)
			)
			(layer "B.Fab")
		)
		(fp_line
			(start 0.12065 -0.305054)
			(end 0.12065 -0.2794)
			(stroke
				(width 0.1)
				(type default)
			)
			(layer "B.Fab")
		)
		(fp_line
			(start -0.12065 -0.3048)
			(end -0.67945 -0.3048)
			(stroke
				(width 0.1)
				(type default)
			)
			(layer "B.Fab")
		)
		(fp_line
			(start -0.67945 -0.3048)
			(end -0.67945 0.3048)
			(stroke
				(width 0.1)
				(type default)
			)
			(layer "B.Fab")
		)
		(fp_line
			(start 0.12065 -0.2794)
			(end -0.12065 -0.2794)
			(stroke
				(width 0.1)
				(type default)
			)
			(layer "B.Fab")
		)
		(fp_line
			(start -0.12065 -0.2794)
			(end -0.12065 -0.3048)
			(stroke
				(width 0.1)
				(type default)
			)
			(layer "B.Fab")
		)
		(fp_line
			(start 0.12065 0.2794)
			(end 0.12065 0.3048)
			(stroke
				(width 0.1)
				(type default)
			)
			(layer "B.Fab")
		)
		(fp_line
			(start -0.120396 0.2794)
			(end 0.12065 0.2794)
			(stroke
				(width 0.1)
				(type default)
			)
			(layer "B.Fab")
		)
		(fp_line
			(start 0.67945 0.3048)
			(end 0.67945 -0.305054)
			(stroke
				(width 0.1)
				(type default)
			)
			(layer "B.Fab")
		)
		(fp_line
			(start 0.12065 0.3048)
			(end 0.67945 0.3048)
			(stroke
				(width 0.1)
				(type default)
			)
			(layer "B.Fab")
		)
		(fp_line
			(start -0.120396 0.3048)
			(end -0.120396 0.2794)
			(stroke
				(width 0.1)
				(type default)
			)
			(layer "B.Fab")
		)
		(fp_line
			(start -0.67945 0.3048)
			(end -0.120396 0.3048)
			(stroke
				(width 0.1)
				(type default)
			)
			(layer "B.Fab")
		)
		(pad "1" smd circle
			(at 0.40005 0 270)
			(size 0 0)
			(layers "B.Cu" "B.Mask" "B.Paste")
			(net "SMB_PEHPCPU0_LVC3_SCL_R0")
		)
		(pad "2" smd circle
			(at -0.40005 0 270)
			(size 0 0)
			(layers "B.Cu" "B.Mask" "B.Paste")
			(net "SMB_PEHPCPU0_LVC3_SCL")
		)
	)
	(footprint ""
		(layer "B.Cu")
		(at 49.936146 -319.268856 180)
		(property "Reference" "R896"
			(at 0 0 0)
			(layer "B.SilkS")
			(hide yes)
			(effects
				(font
					(size 1.27 1.27)
				)
				(justify mirror)
			)
		)
		(property "Value" ""
			(at 0 0 0)
			(layer "B.Fab")
			(effects
				(font
					(size 1.27 1.27)
				)
				(justify mirror)
			)
		)
		(duplicate_pad_numbers_are_jumpers no)
		(fp_line
			(start 0.7874 0.4064)
			(end 0.7874 -0.4064)
			(stroke
				(width 0.1524)
				(type default)
			)
			(layer "B.SilkS")
		)
		(fp_line
			(start 0.7874 -0.4064)
			(end -0.7874 -0.4064)
			(stroke
				(width 0.1524)
				(type default)
			)
			(layer "B.SilkS")
		)
		(fp_line
			(start -0.7874 0.4064)
			(end 0.7874 0.4064)
			(stroke
				(width 0.1524)
				(type default)
			)
			(layer "B.SilkS")
		)
		(fp_line
			(start -0.7874 -0.4064)
			(end -0.7874 0.4064)
			(stroke
				(width 0.1524)
				(type default)
			)
			(layer "B.SilkS")
		)
		(fp_line
			(start 0.67945 0.3048)
			(end 0.67945 -0.305054)
			(stroke
				(width 0.1)
				(type default)
			)
			(layer "B.Fab")
		)
		(fp_line
			(start 0.67945 -0.305054)
			(end 0.12065 -0.305054)
			(stroke
				(width 0.1)
				(type default)
			)
			(layer "B.Fab")
		)
		(fp_line
			(start 0.12065 0.3048)
			(end 0.67945 0.3048)
			(stroke
				(width 0.1)
				(type default)
			)
			(layer "B.Fab")
		)
		(fp_line
			(start 0.12065 0.2794)
			(end 0.12065 0.3048)
			(stroke
				(width 0.1)
				(type default)
			)
			(layer "B.Fab")
		)
		(fp_line
			(start 0.12065 -0.2794)
			(end -0.12065 -0.2794)
			(stroke
				(width 0.1)
				(type default)
			)
			(layer "B.Fab")
		)
		(fp_line
			(start 0.12065 -0.305054)
			(end 0.12065 -0.2794)
			(stroke
				(width 0.1)
				(type default)
			)
			(layer "B.Fab")
		)
		(fp_line
			(start -0.120396 0.3048)
			(end -0.120396 0.2794)
			(stroke
				(width 0.1)
				(type default)
			)
			(layer "B.Fab")
		)
		(fp_line
			(start -0.120396 0.2794)
			(end 0.12065 0.2794)
			(stroke
				(width 0.1)
				(type default)
			)
			(layer "B.Fab")
		)
		(fp_line
			(start -0.12065 -0.2794)
			(end -0.12065 -0.3048)
			(stroke
				(width 0.1)
				(type default)
			)
			(layer "B.Fab")
		)
		(fp_line
			(start -0.12065 -0.3048)
			(end -0.67945 -0.3048)
			(stroke
				(width 0.1)
				(type default)
			)
			(layer "B.Fab")
		)
		(fp_line
			(start -0.67945 0.3048)
			(end -0.120396 0.3048)
			(stroke
				(width 0.1)
				(type default)
			)
			(layer "B.Fab")
		)
		(fp_line
			(start -0.67945 -0.3048)
			(end -0.67945 0.3048)
			(stroke
				(width 0.1)
				(type default)
			)
			(layer "B.Fab")
		)
		(pad "1" smd circle
			(at 0.40005 0)
			(size 0 0)
			(layers "B.Cu" "B.Mask" "B.Paste")
			(net "PWRGD_CHB_CPU1_DIMM2")
		)
		(pad "2" smd circle
			(at -0.40005 0)
			(size 0 0)
			(layers "B.Cu" "B.Mask" "B.Paste")
			(net "PWRGD_FAIL_CPU1_AB")
		)
	)
	(footprint ""
		(layer "B.Cu")
		(at 173.913546 -319.268856 180)
		(property "Reference" "C84"
			(at 0 0 0)
			(layer "B.SilkS")
			(hide yes)
			(effects
				(font
					(size 1.27 1.27)
				)
				(justify mirror)
			)
		)
		(property "Value" ""
			(at 0 0 0)
			(layer "B.Fab")
			(effects
				(font
					(size 1.27 1.27)
				)
				(justify mirror)
			)
		)
		(duplicate_pad_numbers_are_jumpers no)
		(fp_line
			(start 0.7874 0.4064)
			(end 0.7874 -0.4064)
			(stroke
				(width 0.1524)
				(type default)
			)
			(layer "B.SilkS")
		)
		(fp_line
			(start 0.7874 -0.4064)
			(end -0.7874 -0.4064)
			(stroke
				(width 0.1524)
				(type default)
			)
			(layer "B.SilkS")
		)
		(fp_line
			(start -0.7874 0.4064)
			(end 0.7874 0.4064)
			(stroke
				(width 0.1524)
				(type default)
			)
			(layer "B.SilkS")
		)
		(fp_line
			(start -0.7874 -0.4064)
			(end -0.7874 0.4064)
			(stroke
				(width 0.1524)
				(type default)
			)
			(layer "B.SilkS")
		)
		(fp_line
			(start 0.67945 0.3048)
			(end 0.67945 -0.305054)
			(stroke
				(width 0.1)
				(type default)
			)
			(layer "B.Fab")
		)
		(fp_line
			(start 0.67945 -0.305054)
			(end 0.12065 -0.305054)
			(stroke
				(width 0.1)
				(type default)
			)
			(layer "B.Fab")
		)
		(fp_line
			(start 0.12065 0.3048)
			(end 0.67945 0.3048)
			(stroke
				(width 0.1)
				(type default)
			)
			(layer "B.Fab")
		)
		(fp_line
			(start 0.12065 0.2794)
			(end 0.12065 0.3048)
			(stroke
				(width 0.1)
				(type default)
			)
			(layer "B.Fab")
		)
		(fp_line
			(start 0.12065 -0.2794)
			(end -0.12065 -0.2794)
			(stroke
				(width 0.1)
				(type default)
			)
			(layer "B.Fab")
		)
		(fp_line
			(start 0.12065 -0.305054)
			(end 0.12065 -0.2794)
			(stroke
				(width 0.1)
				(type default)
			)
			(layer "B.Fab")
		)
		(fp_line
			(start -0.120396 0.3048)
			(end -0.120396 0.2794)
			(stroke
				(width 0.1)
				(type default)
			)
			(layer "B.Fab")
		)
		(fp_line
			(start -0.120396 0.2794)
			(end 0.12065 0.2794)
			(stroke
				(width 0.1)
				(type default)
			)
			(layer "B.Fab")
		)
		(fp_line
			(start -0.12065 -0.2794)
			(end -0.12065 -0.3048)
			(stroke
				(width 0.1)
				(type default)
			)
			(layer "B.Fab")
		)
		(fp_line
			(start -0.12065 -0.3048)
			(end -0.67945 -0.3048)
			(stroke
				(width 0.1)
				(type default)
			)
			(layer "B.Fab")
		)
		(fp_line
			(start -0.67945 0.3048)
			(end -0.120396 0.3048)
			(stroke
				(width 0.1)
				(type default)
			)
			(layer "B.Fab")
		)
		(fp_line
			(start -0.67945 -0.3048)
			(end -0.67945 0.3048)
			(stroke
				(width 0.1)
				(type default)
			)
			(layer "B.Fab")
		)
		(pad "1" smd circle
			(at 0.40005 0)
			(size 0 0)
			(layers "B.Cu" "B.Mask" "B.Paste")
			(net "P3V3_AUX")
		)
		(pad "2" smd circle
			(at -0.40005 0)
			(size 0 0)
			(layers "B.Cu" "B.Mask" "B.Paste")
			(net "GND")
		)
	)
	(footprint ""
		(layer "B.Cu")
		(at 156.1465 -190.99911 90)
		(property "Reference" "R1217"
			(at 0 0 90)
			(layer "B.SilkS")
			(hide yes)
			(effects
				(font
					(size 1.27 1.27)
				)
				(justify mirror)
			)
		)
		(property "Value" ""
			(at 0 0 90)
			(layer "B.Fab")
			(effects
				(font
					(size 1.27 1.27)
				)
				(justify mirror)
			)
		)
		(duplicate_pad_numbers_are_jumpers no)
		(fp_line
			(start 0.7874 -0.4064)
			(end -0.7874 -0.4064)
			(stroke
				(width 0.1524)
				(type default)
			)
			(layer "B.SilkS")
		)
		(fp_line
			(start -0.7874 -0.4064)
			(end -0.7874 0.4064)
			(stroke
				(width 0.1524)
				(type default)
			)
			(layer "B.SilkS")
		)
		(fp_line
			(start 0.7874 0.4064)
			(end 0.7874 -0.4064)
			(stroke
				(width 0.1524)
				(type default)
			)
			(layer "B.SilkS")
		)
		(fp_line
			(start -0.7874 0.4064)
			(end 0.7874 0.4064)
			(stroke
				(width 0.1524)
				(type default)
			)
			(layer "B.SilkS")
		)
		(fp_line
			(start 0.67945 -0.305054)
			(end 0.12065 -0.305054)
			(stroke
				(width 0.1)
				(type default)
			)
			(layer "B.Fab")
		)
		(fp_line
			(start 0.12065 -0.305054)
			(end 0.12065 -0.2794)
			(stroke
				(width 0.1)
				(type default)
			)
			(layer "B.Fab")
		)
		(fp_line
			(start -0.12065 -0.3048)
			(end -0.67945 -0.3048)
			(stroke
				(width 0.1)
				(type default)
			)
			(layer "B.Fab")
		)
		(fp_line
			(start -0.67945 -0.3048)
			(end -0.67945 0.3048)
			(stroke
				(width 0.1)
				(type default)
			)
			(layer "B.Fab")
		)
		(fp_line
			(start 0.12065 -0.2794)
			(end -0.12065 -0.2794)
			(stroke
				(width 0.1)
				(type default)
			)
			(layer "B.Fab")
		)
		(fp_line
			(start -0.12065 -0.2794)
			(end -0.12065 -0.3048)
			(stroke
				(width 0.1)
				(type default)
			)
			(layer "B.Fab")
		)
		(fp_line
			(start 0.12065 0.2794)
			(end 0.12065 0.3048)
			(stroke
				(width 0.1)
				(type default)
			)
			(layer "B.Fab")
		)
		(fp_line
			(start -0.120396 0.2794)
			(end 0.12065 0.2794)
			(stroke
				(width 0.1)
				(type default)
			)
			(layer "B.Fab")
		)
		(fp_line
			(start 0.67945 0.3048)
			(end 0.67945 -0.305054)
			(stroke
				(width 0.1)
				(type default)
			)
			(layer "B.Fab")
		)
		(fp_line
			(start 0.12065 0.3048)
			(end 0.67945 0.3048)
			(stroke
				(width 0.1)
				(type default)
			)
			(layer "B.Fab")
		)
		(fp_line
			(start -0.120396 0.3048)
			(end -0.120396 0.2794)
			(stroke
				(width 0.1)
				(type default)
			)
			(layer "B.Fab")
		)
		(fp_line
			(start -0.67945 0.3048)
			(end -0.120396 0.3048)
			(stroke
				(width 0.1)
				(type default)
			)
			(layer "B.Fab")
		)
		(pad "1" smd circle
			(at 0.40005 0 270)
			(size 0 0)
			(layers "B.Cu" "B.Mask" "B.Paste")
			(net "P3V3_AUX")
		)
		(pad "2" smd circle
			(at -0.40005 0 270)
			(size 0 0)
			(layers "B.Cu" "B.Mask" "B.Paste")
			(net "FM_S3M_CPU1_CPLD_CRC_ERROR")
		)
	)
	(footprint ""
		(layer "B.Cu")
		(at 294.71874 -413.95904 90)
		(property "Reference" "R4691"
			(at 0 0 90)
			(layer "B.SilkS")
			(hide yes)
			(effects
				(font
					(size 1.27 1.27)
				)
				(justify mirror)
			)
		)
		(property "Value" ""
			(at 0 0 90)
			(layer "B.Fab")
			(effects
				(font
					(size 1.27 1.27)
				)
				(justify mirror)
			)
		)
		(duplicate_pad_numbers_are_jumpers no)
		(fp_line
			(start 0.7874 -0.4064)
			(end -0.7874 -0.4064)
			(stroke
				(width 0.1524)
				(type default)
			)
			(layer "B.SilkS")
		)
		(fp_line
			(start -0.7874 -0.4064)
			(end -0.7874 0.4064)
			(stroke
				(width 0.1524)
				(type default)
			)
			(layer "B.SilkS")
		)
		(fp_line
			(start 0.7874 0.4064)
			(end 0.7874 -0.4064)
			(stroke
				(width 0.1524)
				(type default)
			)
			(layer "B.SilkS")
		)
		(fp_line
			(start -0.7874 0.4064)
			(end 0.7874 0.4064)
			(stroke
				(width 0.1524)
				(type default)
			)
			(layer "B.SilkS")
		)
		(fp_line
			(start 0.67945 -0.305054)
			(end 0.12065 -0.305054)
			(stroke
				(width 0.1)
				(type default)
			)
			(layer "B.Fab")
		)
		(fp_line
			(start 0.12065 -0.305054)
			(end 0.12065 -0.2794)
			(stroke
				(width 0.1)
				(type default)
			)
			(layer "B.Fab")
		)
		(fp_line
			(start -0.12065 -0.3048)
			(end -0.67945 -0.3048)
			(stroke
				(width 0.1)
				(type default)
			)
			(layer "B.Fab")
		)
		(fp_line
			(start -0.67945 -0.3048)
			(end -0.67945 0.3048)
			(stroke
				(width 0.1)
				(type default)
			)
			(layer "B.Fab")
		)
		(fp_line
			(start 0.12065 -0.2794)
			(end -0.12065 -0.2794)
			(stroke
				(width 0.1)
				(type default)
			)
			(layer "B.Fab")
		)
		(fp_line
			(start -0.12065 -0.2794)
			(end -0.12065 -0.3048)
			(stroke
				(width 0.1)
				(type default)
			)
			(layer "B.Fab")
		)
		(fp_line
			(start 0.12065 0.2794)
			(end 0.12065 0.3048)
			(stroke
				(width 0.1)
				(type default)
			)
			(layer "B.Fab")
		)
		(fp_line
			(start -0.120396 0.2794)
			(end 0.12065 0.2794)
			(stroke
				(width 0.1)
				(type default)
			)
			(layer "B.Fab")
		)
		(fp_line
			(start 0.67945 0.3048)
			(end 0.67945 -0.305054)
			(stroke
				(width 0.1)
				(type default)
			)
			(layer "B.Fab")
		)
		(fp_line
			(start 0.12065 0.3048)
			(end 0.67945 0.3048)
			(stroke
				(width 0.1)
				(type default)
			)
			(layer "B.Fab")
		)
		(fp_line
			(start -0.120396 0.3048)
			(end -0.120396 0.2794)
			(stroke
				(width 0.1)
				(type default)
			)
			(layer "B.Fab")
		)
		(fp_line
			(start -0.67945 0.3048)
			(end -0.120396 0.3048)
			(stroke
				(width 0.1)
				(type default)
			)
			(layer "B.Fab")
		)
		(pad "1" smd circle
			(at 0.40005 0 270)
			(size 0 0)
			(layers "B.Cu" "B.Mask" "B.Paste")
			(net "HSC_TYPE_ADC_A0")
		)
		(pad "2" smd circle
			(at -0.40005 0 270)
			(size 0 0)
			(layers "B.Cu" "B.Mask" "B.Paste")
			(net "SMB_HSC_TYPE_ADC_SDA")
		)
	)
	(footprint ""
		(layer "B.Cu")
		(at 356.785418 -294.009826 180)
		(property "Reference" "C372"
			(at 0 0 0)
			(layer "B.SilkS")
			(hide yes)
			(effects
				(font
					(size 1.27 1.27)
				)
				(justify mirror)
			)
		)
		(property "Value" ""
			(at 0 0 0)
			(layer "B.Fab")
			(effects
				(font
					(size 1.27 1.27)
				)
				(justify mirror)
			)
		)
		(duplicate_pad_numbers_are_jumpers no)
		(fp_line
			(start 1.524 0.762)
			(end 1.524 -0.762)
			(stroke
				(width 0.1524)
				(type default)
			)
			(layer "B.SilkS")
		)
		(fp_line
			(start 1.524 -0.762)
			(end -1.524 -0.762)
			(stroke
				(width 0.1524)
				(type default)
			)
			(layer "B.SilkS")
		)
		(fp_line
			(start -1.524 0.762)
			(end 1.524 0.762)
			(stroke
				(width 0.1524)
				(type default)
			)
			(layer "B.SilkS")
		)
		(fp_line
			(start -1.524 -0.762)
			(end -1.524 0.762)
			(stroke
				(width 0.1524)
				(type default)
			)
			(layer "B.SilkS")
		)
		(fp_line
			(start 1.1049 0.724916)
			(end -1.1049 0.724916)
			(stroke
				(width 0.1)
				(type default)
			)
			(layer "B.Fab")
		)
		(fp_line
			(start 1.1049 -0.724916)
			(end 1.1049 0.724916)
			(stroke
				(width 0.1)
				(type default)
			)
			(layer "B.Fab")
		)
		(fp_line
			(start -1.1049 0.724916)
			(end -1.1049 -0.724916)
			(stroke
				(width 0.1)
				(type default)
			)
			(layer "B.Fab")
		)
		(fp_line
			(start -1.1049 -0.724916)
			(end 1.1049 -0.724916)
			(stroke
				(width 0.1)
				(type default)
			)
			(layer "B.Fab")
		)
		(pad "1" smd rect
			(at 0.889 0 180)
			(size 1.016 1.27)
			(layers "B.Cu" "B.Mask" "B.Paste")
			(net "PVCCIN_CPU0")
		)
		(pad "2" smd rect
			(at -0.889 0 180)
			(size 1.016 1.27)
			(layers "B.Cu" "B.Mask" "B.Paste")
			(net "GND")
		)
	)
	(footprint ""
		(layer "B.Cu")
		(at 235.955332 -123.453652 90)
		(property "Reference" "C211"
			(at 0 0 90)
			(layer "B.SilkS")
			(hide yes)
			(effects
				(font
					(size 1.27 1.27)
				)
				(justify mirror)
			)
		)
		(property "Value" ""
			(at 0 0 90)
			(layer "B.Fab")
			(effects
				(font
					(size 1.27 1.27)
				)
				(justify mirror)
			)
		)
		(duplicate_pad_numbers_are_jumpers no)
		(fp_line
			(start 0.7874 -0.4064)
			(end -0.7874 -0.4064)
			(stroke
				(width 0.1524)
				(type default)
			)
			(layer "B.SilkS")
		)
		(fp_line
			(start -0.7874 -0.4064)
			(end -0.7874 0.4064)
			(stroke
				(width 0.1524)
				(type default)
			)
			(layer "B.SilkS")
		)
		(fp_line
			(start 0.7874 0.4064)
			(end 0.7874 -0.4064)
			(stroke
				(width 0.1524)
				(type default)
			)
			(layer "B.SilkS")
		)
		(fp_line
			(start -0.7874 0.4064)
			(end 0.7874 0.4064)
			(stroke
				(width 0.1524)
				(type default)
			)
			(layer "B.SilkS")
		)
		(fp_line
			(start 0.67945 -0.305054)
			(end 0.12065 -0.305054)
			(stroke
				(width 0.1)
				(type default)
			)
			(layer "B.Fab")
		)
		(fp_line
			(start 0.12065 -0.305054)
			(end 0.12065 -0.2794)
			(stroke
				(width 0.1)
				(type default)
			)
			(layer "B.Fab")
		)
		(fp_line
			(start -0.12065 -0.3048)
			(end -0.67945 -0.3048)
			(stroke
				(width 0.1)
				(type default)
			)
			(layer "B.Fab")
		)
		(fp_line
			(start -0.67945 -0.3048)
			(end -0.67945 0.3048)
			(stroke
				(width 0.1)
				(type default)
			)
			(layer "B.Fab")
		)
		(fp_line
			(start 0.12065 -0.2794)
			(end -0.12065 -0.2794)
			(stroke
				(width 0.1)
				(type default)
			)
			(layer "B.Fab")
		)
		(fp_line
			(start -0.12065 -0.2794)
			(end -0.12065 -0.3048)
			(stroke
				(width 0.1)
				(type default)
			)
			(layer "B.Fab")
		)
		(fp_line
			(start 0.12065 0.2794)
			(end 0.12065 0.3048)
			(stroke
				(width 0.1)
				(type default)
			)
			(layer "B.Fab")
		)
		(fp_line
			(start -0.120396 0.2794)
			(end 0.12065 0.2794)
			(stroke
				(width 0.1)
				(type default)
			)
			(layer "B.Fab")
		)
		(fp_line
			(start 0.67945 0.3048)
			(end 0.67945 -0.305054)
			(stroke
				(width 0.1)
				(type default)
			)
			(layer "B.Fab")
		)
		(fp_line
			(start 0.12065 0.3048)
			(end 0.67945 0.3048)
			(stroke
				(width 0.1)
				(type default)
			)
			(layer "B.Fab")
		)
		(fp_line
			(start -0.120396 0.3048)
			(end -0.120396 0.2794)
			(stroke
				(width 0.1)
				(type default)
			)
			(layer "B.Fab")
		)
		(fp_line
			(start -0.67945 0.3048)
			(end -0.120396 0.3048)
			(stroke
				(width 0.1)
				(type default)
			)
			(layer "B.Fab")
		)
		(pad "1" smd circle
			(at 0.40005 0 270)
			(size 0 0)
			(layers "B.Cu" "B.Mask" "B.Paste")
			(net "P3V3_DB2000_VDDA")
		)
		(pad "2" smd circle
			(at -0.40005 0 270)
			(size 0 0)
			(layers "B.Cu" "B.Mask" "B.Paste")
			(net "GND")
		)
	)
	(footprint ""
		(layer "B.Cu")
		(at 134.347966 -345.463114 -90)
		(property "Reference" "PR289"
			(at 0 0 90)
			(layer "B.SilkS")
			(hide yes)
			(effects
				(font
					(size 1.27 1.27)
				)
				(justify mirror)
			)
		)
		(property "Value" ""
			(at 0 0 90)
			(layer "B.Fab")
			(effects
				(font
					(size 1.27 1.27)
				)
				(justify mirror)
			)
		)
		(duplicate_pad_numbers_are_jumpers no)
		(fp_line
			(start -0.7874 0.4064)
			(end 0.7874 0.4064)
			(stroke
				(width 0.1524)
				(type default)
			)
			(layer "B.SilkS")
		)
		(fp_line
			(start 0.7874 0.4064)
			(end 0.7874 -0.4064)
			(stroke
				(width 0.1524)
				(type default)
			)
			(layer "B.SilkS")
		)
		(fp_line
			(start -0.7874 -0.4064)
			(end -0.7874 0.4064)
			(stroke
				(width 0.1524)
				(type default)
			)
			(layer "B.SilkS")
		)
		(fp_line
			(start 0.7874 -0.4064)
			(end -0.7874 -0.4064)
			(stroke
				(width 0.1524)
				(type default)
			)
			(layer "B.SilkS")
		)
		(fp_line
			(start -0.67945 0.3048)
			(end -0.120396 0.3048)
			(stroke
				(width 0.1)
				(type default)
			)
			(layer "B.Fab")
		)
		(fp_line
			(start -0.120396 0.3048)
			(end -0.120396 0.2794)
			(stroke
				(width 0.1)
				(type default)
			)
			(layer "B.Fab")
		)
		(fp_line
			(start 0.12065 0.3048)
			(end 0.67945 0.3048)
			(stroke
				(width 0.1)
				(type default)
			)
			(layer "B.Fab")
		)
		(fp_line
			(start 0.67945 0.3048)
			(end 0.67945 -0.305054)
			(stroke
				(width 0.1)
				(type default)
			)
			(layer "B.Fab")
		)
		(fp_line
			(start -0.120396 0.2794)
			(end 0.12065 0.2794)
			(stroke
				(width 0.1)
				(type default)
			)
			(layer "B.Fab")
		)
		(fp_line
			(start 0.12065 0.2794)
			(end 0.12065 0.3048)
			(stroke
				(width 0.1)
				(type default)
			)
			(layer "B.Fab")
		)
		(fp_line
			(start -0.12065 -0.2794)
			(end -0.12065 -0.3048)
			(stroke
				(width 0.1)
				(type default)
			)
			(layer "B.Fab")
		)
		(fp_line
			(start 0.12065 -0.2794)
			(end -0.12065 -0.2794)
			(stroke
				(width 0.1)
				(type default)
			)
			(layer "B.Fab")
		)
		(fp_line
			(start -0.67945 -0.3048)
			(end -0.67945 0.3048)
			(stroke
				(width 0.1)
				(type default)
			)
			(layer "B.Fab")
		)
		(fp_line
			(start -0.12065 -0.3048)
			(end -0.67945 -0.3048)
			(stroke
				(width 0.1)
				(type default)
			)
			(layer "B.Fab")
		)
		(fp_line
			(start 0.12065 -0.305054)
			(end 0.12065 -0.2794)
			(stroke
				(width 0.1)
				(type default)
			)
			(layer "B.Fab")
		)
		(fp_line
			(start 0.67945 -0.305054)
			(end 0.12065 -0.305054)
			(stroke
				(width 0.1)
				(type default)
			)
			(layer "B.Fab")
		)
		(pad "1" smd circle
			(at 0.40005 0 90)
			(size 0 0)
			(layers "B.Cu" "B.Mask" "B.Paste")
			(net "PVCCIN_CPU1_VOS8")
		)
		(pad "2" smd circle
			(at -0.40005 0 90)
			(size 0 0)
			(layers "B.Cu" "B.Mask" "B.Paste")
			(net "PVCCIN_CPU1")
		)
	)
	(footprint ""
		(layer "B.Cu")
		(at 181.530752 -192.699894 -90)
		(property "Reference" "R325"
			(at 0 0 90)
			(layer "B.SilkS")
			(hide yes)
			(effects
				(font
					(size 1.27 1.27)
				)
				(justify mirror)
			)
		)
		(property "Value" ""
			(at 0 0 90)
			(layer "B.Fab")
			(effects
				(font
					(size 1.27 1.27)
				)
				(justify mirror)
			)
		)
		(duplicate_pad_numbers_are_jumpers no)
		(fp_line
			(start -0.7874 0.4064)
			(end 0.7874 0.4064)
			(stroke
				(width 0.1524)
				(type default)
			)
			(layer "B.SilkS")
		)
		(fp_line
			(start 0.7874 0.4064)
			(end 0.7874 -0.4064)
			(stroke
				(width 0.1524)
				(type default)
			)
			(layer "B.SilkS")
		)
		(fp_line
			(start -0.7874 -0.4064)
			(end -0.7874 0.4064)
			(stroke
				(width 0.1524)
				(type default)
			)
			(layer "B.SilkS")
		)
		(fp_line
			(start 0.7874 -0.4064)
			(end -0.7874 -0.4064)
			(stroke
				(width 0.1524)
				(type default)
			)
			(layer "B.SilkS")
		)
		(fp_line
			(start -0.67945 0.3048)
			(end -0.120396 0.3048)
			(stroke
				(width 0.1)
				(type default)
			)
			(layer "B.Fab")
		)
		(fp_line
			(start -0.120396 0.3048)
			(end -0.120396 0.2794)
			(stroke
				(width 0.1)
				(type default)
			)
			(layer "B.Fab")
		)
		(fp_line
			(start 0.12065 0.3048)
			(end 0.67945 0.3048)
			(stroke
				(width 0.1)
				(type default)
			)
			(layer "B.Fab")
		)
		(fp_line
			(start 0.67945 0.3048)
			(end 0.67945 -0.305054)
			(stroke
				(width 0.1)
				(type default)
			)
			(layer "B.Fab")
		)
		(fp_line
			(start -0.120396 0.2794)
			(end 0.12065 0.2794)
			(stroke
				(width 0.1)
				(type default)
			)
			(layer "B.Fab")
		)
		(fp_line
			(start 0.12065 0.2794)
			(end 0.12065 0.3048)
			(stroke
				(width 0.1)
				(type default)
			)
			(layer "B.Fab")
		)
		(fp_line
			(start -0.12065 -0.2794)
			(end -0.12065 -0.3048)
			(stroke
				(width 0.1)
				(type default)
			)
			(layer "B.Fab")
		)
		(fp_line
			(start 0.12065 -0.2794)
			(end -0.12065 -0.2794)
			(stroke
				(width 0.1)
				(type default)
			)
			(layer "B.Fab")
		)
		(fp_line
			(start -0.67945 -0.3048)
			(end -0.67945 0.3048)
			(stroke
				(width 0.1)
				(type default)
			)
			(layer "B.Fab")
		)
		(fp_line
			(start -0.12065 -0.3048)
			(end -0.67945 -0.3048)
			(stroke
				(width 0.1)
				(type default)
			)
			(layer "B.Fab")
		)
		(fp_line
			(start 0.12065 -0.305054)
			(end 0.12065 -0.2794)
			(stroke
				(width 0.1)
				(type default)
			)
			(layer "B.Fab")
		)
		(fp_line
			(start 0.67945 -0.305054)
			(end 0.12065 -0.305054)
			(stroke
				(width 0.1)
				(type default)
			)
			(layer "B.Fab")
		)
		(pad "1" smd circle
			(at 0.40005 0 90)
			(size 0 0)
			(layers "B.Cu" "B.Mask" "B.Paste")
			(net "P3V3_AUX")
		)
		(pad "2" smd circle
			(at -0.40005 0 90)
			(size 0 0)
			(layers "B.Cu" "B.Mask" "B.Paste")
			(net "PU_S3M_CPU1_CPLD_STATUS")
		)
	)
	(footprint ""
		(layer "B.Cu")
		(at 331.873352 -342.936576 90)
		(property "Reference" "PC237_P0_7"
			(at 0 0 90)
			(layer "B.SilkS")
			(hide yes)
			(effects
				(font
					(size 1.27 1.27)
				)
				(justify mirror)
			)
		)
		(property "Value" ""
			(at 0 0 90)
			(layer "B.Fab")
			(effects
				(font
					(size 1.27 1.27)
				)
				(justify mirror)
			)
		)
		(duplicate_pad_numbers_are_jumpers no)
		(fp_line
			(start 1.524 -0.762)
			(end -1.524 -0.762)
			(stroke
				(width 0.1524)
				(type default)
			)
			(layer "B.SilkS")
		)
		(fp_line
			(start -1.524 -0.762)
			(end -1.524 0.762)
			(stroke
				(width 0.1524)
				(type default)
			)
			(layer "B.SilkS")
		)
		(fp_line
			(start 1.524 0.762)
			(end 1.524 -0.762)
			(stroke
				(width 0.1524)
				(type default)
			)
			(layer "B.SilkS")
		)
		(fp_line
			(start -1.524 0.762)
			(end 1.524 0.762)
			(stroke
				(width 0.1524)
				(type default)
			)
			(layer "B.SilkS")
		)
		(fp_line
			(start 1.1049 -0.724916)
			(end 1.1049 0.724916)
			(stroke
				(width 0.1)
				(type default)
			)
			(layer "B.Fab")
		)
		(fp_line
			(start -1.1049 -0.724916)
			(end 1.1049 -0.724916)
			(stroke
				(width 0.1)
				(type default)
			)
			(layer "B.Fab")
		)
		(fp_line
			(start 1.1049 0.724916)
			(end -1.1049 0.724916)
			(stroke
				(width 0.1)
				(type default)
			)
			(layer "B.Fab")
		)
		(fp_line
			(start -1.1049 0.724916)
			(end -1.1049 -0.724916)
			(stroke
				(width 0.1)
				(type default)
			)
			(layer "B.Fab")
		)
		(pad "1" smd rect
			(at 0.889 0 90)
			(size 1.016 1.27)
			(layers "B.Cu" "B.Mask" "B.Paste")
			(net "SW_P12V_PVCCIN_CPU0_FLT")
		)
		(pad "2" smd rect
			(at -0.889 0 90)
			(size 1.016 1.27)
			(layers "B.Cu" "B.Mask" "B.Paste")
			(net "GND")
		)
	)
	(footprint ""
		(layer "B.Cu")
		(at 167.078152 -318.23533)
		(property "Reference" "R901"
			(at 0 0 0)
			(layer "B.SilkS")
			(hide yes)
			(effects
				(font
					(size 1.27 1.27)
				)
				(justify mirror)
			)
		)
		(property "Value" ""
			(at 0 0 0)
			(layer "B.Fab")
			(effects
				(font
					(size 1.27 1.27)
				)
				(justify mirror)
			)
		)
		(duplicate_pad_numbers_are_jumpers no)
		(fp_line
			(start -0.7874 -0.4064)
			(end -0.7874 0.4064)
			(stroke
				(width 0.1524)
				(type default)
			)
			(layer "B.SilkS")
		)
		(fp_line
			(start -0.7874 0.4064)
			(end 0.7874 0.4064)
			(stroke
				(width 0.1524)
				(type default)
			)
			(layer "B.SilkS")
		)
		(fp_line
			(start 0.7874 -0.4064)
			(end -0.7874 -0.4064)
			(stroke
				(width 0.1524)
				(type default)
			)
			(layer "B.SilkS")
		)
		(fp_line
			(start 0.7874 0.4064)
			(end 0.7874 -0.4064)
			(stroke
				(width 0.1524)
				(type default)
			)
			(layer "B.SilkS")
		)
		(fp_line
			(start -0.67945 -0.3048)
			(end -0.67945 0.3048)
			(stroke
				(width 0.1)
				(type default)
			)
			(layer "B.Fab")
		)
		(fp_line
			(start -0.67945 0.3048)
			(end -0.120396 0.3048)
			(stroke
				(width 0.1)
				(type default)
			)
			(layer "B.Fab")
		)
		(fp_line
			(start -0.12065 -0.3048)
			(end -0.67945 -0.3048)
			(stroke
				(width 0.1)
				(type default)
			)
			(layer "B.Fab")
		)
		(fp_line
			(start -0.12065 -0.2794)
			(end -0.12065 -0.3048)
			(stroke
				(width 0.1)
				(type default)
			)
			(layer "B.Fab")
		)
		(fp_line
			(start -0.120396 0.2794)
			(end 0.12065 0.2794)
			(stroke
				(width 0.1)
				(type default)
			)
			(layer "B.Fab")
		)
		(fp_line
			(start -0.120396 0.3048)
			(end -0.120396 0.2794)
			(stroke
				(width 0.1)
				(type default)
			)
			(layer "B.Fab")
		)
		(fp_line
			(start 0.12065 -0.305054)
			(end 0.12065 -0.2794)
			(stroke
				(width 0.1)
				(type default)
			)
			(layer "B.Fab")
		)
		(fp_line
			(start 0.12065 -0.2794)
			(end -0.12065 -0.2794)
			(stroke
				(width 0.1)
				(type default)
			)
			(layer "B.Fab")
		)
		(fp_line
			(start 0.12065 0.2794)
			(end 0.12065 0.3048)
			(stroke
				(width 0.1)
				(type default)
			)
			(layer "B.Fab")
		)
		(fp_line
			(start 0.12065 0.3048)
			(end 0.67945 0.3048)
			(stroke
				(width 0.1)
				(type default)
			)
			(layer "B.Fab")
		)
		(fp_line
			(start 0.67945 -0.305054)
			(end 0.12065 -0.305054)
			(stroke
				(width 0.1)
				(type default)
			)
			(layer "B.Fab")
		)
		(fp_line
			(start 0.67945 0.3048)
			(end 0.67945 -0.305054)
			(stroke
				(width 0.1)
				(type default)
			)
			(layer "B.Fab")
		)
		(pad "1" smd circle
			(at 0.40005 0 180)
			(size 0 0)
			(layers "B.Cu" "B.Mask" "B.Paste")
			(net "PWRGD_CHE_CPU1_DIMM1")
		)
		(pad "2" smd circle
			(at -0.40005 0 180)
			(size 0 0)
			(layers "B.Cu" "B.Mask" "B.Paste")
			(net "PWRGD_FAIL_CPU1_EF")
		)
	)
	(footprint ""
		(layer "B.Cu")
		(at 173.04893 -101.564948 180)
		(property "Reference" "R3349"
			(at 0 0 0)
			(layer "B.SilkS")
			(hide yes)
			(effects
				(font
					(size 1.27 1.27)
				)
				(justify mirror)
			)
		)
		(property "Value" ""
			(at 0 0 0)
			(layer "B.Fab")
			(effects
				(font
					(size 1.27 1.27)
				)
				(justify mirror)
			)
		)
		(duplicate_pad_numbers_are_jumpers no)
		(fp_line
			(start 1.2954 0.5842)
			(end 1.2954 -0.5842)
			(stroke
				(width 0.1524)
				(type default)
			)
			(layer "B.SilkS")
		)
		(fp_line
			(start 1.2954 -0.5842)
			(end -1.2954 -0.5842)
			(stroke
				(width 0.1524)
				(type default)
			)
			(layer "B.SilkS")
		)
		(fp_line
			(start -1.2954 0.5842)
			(end 1.2954 0.5842)
			(stroke
				(width 0.1524)
				(type default)
			)
			(layer "B.SilkS")
		)
		(fp_line
			(start -1.2954 -0.5842)
			(end -1.2954 0.5842)
			(stroke
				(width 0.1524)
				(type default)
			)
			(layer "B.SilkS")
		)
		(fp_line
			(start 1.1938 0.4064)
			(end 1.1938 -0.406654)
			(stroke
				(width 0.1)
				(type default)
			)
			(layer "B.Fab")
		)
		(fp_line
			(start 1.1938 -0.406654)
			(end 0.8636 -0.406654)
			(stroke
				(width 0.1)
				(type default)
			)
			(layer "B.Fab")
		)
		(fp_line
			(start 0.8636 0.4572)
			(end 0.8636 0.4318)
			(stroke
				(width 0.1)
				(type default)
			)
			(layer "B.Fab")
		)
		(fp_line
			(start 0.8636 0.4318)
			(end 0.8636 0.4064)
			(stroke
				(width 0.1)
				(type default)
			)
			(layer "B.Fab")
		)
		(fp_line
			(start 0.8636 0.4064)
			(end 1.1938 0.4064)
			(stroke
				(width 0.1)
				(type default)
			)
			(layer "B.Fab")
		)
		(fp_line
			(start 0.8636 -0.406654)
			(end 0.8636 -0.4572)
			(stroke
				(width 0.1)
				(type default)
			)
			(layer "B.Fab")
		)
		(fp_line
			(start 0.8636 -0.4572)
			(end -0.8636 -0.4572)
			(stroke
				(width 0.1)
				(type default)
			)
			(layer "B.Fab")
		)
		(fp_line
			(start -0.8636 0.4572)
			(end 0.8636 0.4572)
			(stroke
				(width 0.1)
				(type default)
			)
			(layer "B.Fab")
		)
		(fp_line
			(start -0.8636 0.4064)
			(end -0.8636 0.4572)
			(stroke
				(width 0.1)
				(type default)
			)
			(layer "B.Fab")
		)
		(fp_line
			(start -0.8636 -0.406654)
			(end -1.1938 -0.406654)
			(stroke
				(width 0.1)
				(type default)
			)
			(layer "B.Fab")
		)
		(fp_line
			(start -0.8636 -0.4572)
			(end -0.8636 -0.406654)
			(stroke
				(width 0.1)
				(type default)
			)
			(layer "B.Fab")
		)
		(fp_line
			(start -1.1938 0.4064)
			(end -0.8636 0.4064)
			(stroke
				(width 0.1)
				(type default)
			)
			(layer "B.Fab")
		)
		(fp_line
			(start -1.1938 -0.406654)
			(end -1.1938 0.4064)
			(stroke
				(width 0.1)
				(type default)
			)
			(layer "B.Fab")
		)
		(pad "1" smd rect
			(at 0.7366 0 90)
			(size 0.7112 0.8128)
			(layers "B.Cu" "B.Mask" "B.Paste")
			(net "P3V3_AUX")
		)
		(pad "2" smd rect
			(at -0.7366 0 90)
			(size 0.7112 0.8128)
			(layers "B.Cu" "B.Mask" "B.Paste")
			(net "P3V3_AUX_FPGA_VCCIO5")
		)
	)
	(footprint ""
		(layer "B.Cu")
		(at 506.598428 -148.08708 -90)
		(property "Reference" "X29"
			(at 3.734816 3.412998 270)
			(unlocked yes)
			(layer "B.SilkS")
			(effects
				(font
					(size 0.7874 0.5842)
					(thickness 0.1524)
				)
				(justify left mirror)
			)
		)
		(property "Value" ""
			(at 0 0 90)
			(layer "B.Fab")
			(effects
				(font
					(size 1.27 1.27)
				)
				(justify mirror)
			)
		)
		(property "Device Type" "TP_TDR_4P_FTS_TH-TP_TDR_4P_DIPA"
			(at -1.30175 1.27 180)
			(unlocked yes)
			(layer "B.Fab")
			(hide yes)
			(effects
				(font
					(size 0.635 0.4064)
					(thickness 0.1524)
				)
				(justify mirror)
			)
		)
		(property "User Part Number" "N_A"
			(at -1.30175 1.27 180)
			(unlocked yes)
			(layer "Cmts.User")
			(hide yes)
			(effects
				(font
					(size 0.635 0.4064)
					(thickness 0.1524)
				)
				(justify mirror)
			)
		)
		(duplicate_pad_numbers_are_jumpers no)
		(fp_line
			(start -2.54 3.81)
			(end -2.54 3.6703)
			(stroke
				(width 0.1524)
				(type default)
			)
			(layer "B.SilkS")
		)
		(fp_line
			(start 0 3.81)
			(end -2.54 3.81)
			(stroke
				(width 0.1524)
				(type default)
			)
			(layer "B.SilkS")
		)
		(fp_line
			(start 0 3.175)
			(end 0 3.81)
			(stroke
				(width 0.1524)
				(type default)
			)
			(layer "B.SilkS")
		)
		(fp_line
			(start -2.54 1.4097)
			(end -2.54 1.1303)
			(stroke
				(width 0.1524)
				(type default)
			)
			(layer "B.SilkS")
		)
		(fp_line
			(start 0 0.635)
			(end 0 1.905)
			(stroke
				(width 0.1524)
				(type default)
			)
			(layer "B.SilkS")
		)
		(fp_line
			(start -2.54 -1.1303)
			(end -2.54 -1.27)
			(stroke
				(width 0.1524)
				(type default)
			)
			(layer "B.SilkS")
		)
		(fp_line
			(start -2.54 -1.27)
			(end 0 -1.27)
			(stroke
				(width 0.1524)
				(type default)
			)
			(layer "B.SilkS")
		)
		(fp_line
			(start 0 -1.27)
			(end 0 -0.635)
			(stroke
				(width 0.1524)
				(type default)
			)
			(layer "B.SilkS")
		)
		(fp_poly
			(pts
				(xy 2.938526 -0.71882) (xy 2.938526 0.80518) (xy 1.414526 0.04318)
			)
			(stroke
				(width 0)
				(type default)
			)
			(fill yes)
			(layer "B.SilkS")
		)
		(fp_line
			(start -2.54 3.81)
			(end -2.54 -1.27)
			(stroke
				(width 0.1)
				(type default)
			)
			(layer "B.Fab")
		)
		(fp_line
			(start 0 3.81)
			(end -2.54 3.81)
			(stroke
				(width 0.1)
				(type default)
			)
			(layer "B.Fab")
		)
		(fp_line
			(start -2.54 -1.27)
			(end 0 -1.27)
			(stroke
				(width 0.1)
				(type default)
			)
			(layer "B.Fab")
		)
		(fp_line
			(start 0 -1.27)
			(end 0 3.81)
			(stroke
				(width 0.1)
				(type default)
			)
			(layer "B.Fab")
		)
		(fp_poly
			(pts
				(xy 0.761746 0) (xy 2.285746 -0.762) (xy 2.285746 0.762)
			)
			(stroke
				(width 0)
				(type default)
			)
			(fill yes)
			(layer "B.Fab")
		)
		(pad "1" thru_hole circle
			(at 0 0 90)
			(size 1.0033 1.0033)
			(drill 0.249936)
			(layers "*.Cu" "*.Mask")
			(remove_unused_layers no)
			(net "TDR_DIFF_100_IN5_DP")
			(clearance 0.10795)
			(padstack
				(mode front_inner_back)
				(layer "Inner"
					(shape circle)
					(size 0.8001 0.8001)
					(clearance 0.1524)
				)
				(layer "B.Cu"
					(shape circle)
					(size 1.0033 1.0033)
					(thermal_gap 0.10795)
					(clearance 0.10795)
				)
			)
		)
		(pad "2" thru_hole circle
			(at -2.54 0 90)
			(size 1.9939 1.9939)
			(drill 0.249936)
			(layers "*.Cu" "*.Mask")
			(remove_unused_layers no)
			(net "T1_GND")
			(clearance 0.10795)
			(padstack
				(mode front_inner_back)
				(layer "Inner"
					(shape circle)
					(size 0.8001 0.8001)
					(clearance 0.1524)
				)
				(layer "B.Cu"
					(shape circle)
					(size 1.9939 1.9939)
					(thermal_gap 0.10795)
					(clearance 0.10795)
				)
			)
		)
		(pad "3" thru_hole circle
			(at -2.54 2.54 90)
			(size 1.9939 1.9939)
			(drill 0.249936)
			(layers "*.Cu" "*.Mask")
			(remove_unused_layers no)
			(net "T1_GND")
			(clearance 0.10795)
			(padstack
				(mode front_inner_back)
				(layer "Inner"
					(shape circle)
					(size 0.8001 0.8001)
					(clearance 0.1524)
				)
				(layer "B.Cu"
					(shape circle)
					(size 1.9939 1.9939)
					(thermal_gap 0.10795)
					(clearance 0.10795)
				)
			)
		)
		(pad "4" thru_hole circle
			(at 0 2.54 90)
			(size 1.0033 1.0033)
			(drill 0.249936)
			(layers "*.Cu" "*.Mask")
			(remove_unused_layers no)
			(net "TDR_DIFF_100_IN5_DN")
			(clearance 0.10795)
			(padstack
				(mode front_inner_back)
				(layer "Inner"
					(shape circle)
					(size 0.8001 0.8001)
					(clearance 0.1524)
				)
				(layer "B.Cu"
					(shape circle)
					(size 1.0033 1.0033)
					(thermal_gap 0.10795)
					(clearance 0.10795)
				)
			)
		)
	)
	(footprint ""
		(layer "B.Cu")
		(at 315.569092 -191.215518 90)
		(property "Reference" "R4388"
			(at 0 0 90)
			(layer "B.SilkS")
			(hide yes)
			(effects
				(font
					(size 1.27 1.27)
				)
				(justify mirror)
			)
		)
		(property "Value" ""
			(at 0 0 90)
			(layer "B.Fab")
			(effects
				(font
					(size 1.27 1.27)
				)
				(justify mirror)
			)
		)
		(duplicate_pad_numbers_are_jumpers no)
		(fp_line
			(start 0.7874 -0.4064)
			(end -0.7874 -0.4064)
			(stroke
				(width 0.1524)
				(type default)
			)
			(layer "B.SilkS")
		)
		(fp_line
			(start -0.7874 -0.4064)
			(end -0.7874 0.4064)
			(stroke
				(width 0.1524)
				(type default)
			)
			(layer "B.SilkS")
		)
		(fp_line
			(start 0.7874 0.4064)
			(end 0.7874 -0.4064)
			(stroke
				(width 0.1524)
				(type default)
			)
			(layer "B.SilkS")
		)
		(fp_line
			(start -0.7874 0.4064)
			(end 0.7874 0.4064)
			(stroke
				(width 0.1524)
				(type default)
			)
			(layer "B.SilkS")
		)
		(fp_line
			(start 0.67945 -0.305054)
			(end 0.12065 -0.305054)
			(stroke
				(width 0.1)
				(type default)
			)
			(layer "B.Fab")
		)
		(fp_line
			(start 0.12065 -0.305054)
			(end 0.12065 -0.2794)
			(stroke
				(width 0.1)
				(type default)
			)
			(layer "B.Fab")
		)
		(fp_line
			(start -0.12065 -0.3048)
			(end -0.67945 -0.3048)
			(stroke
				(width 0.1)
				(type default)
			)
			(layer "B.Fab")
		)
		(fp_line
			(start -0.67945 -0.3048)
			(end -0.67945 0.3048)
			(stroke
				(width 0.1)
				(type default)
			)
			(layer "B.Fab")
		)
		(fp_line
			(start 0.12065 -0.2794)
			(end -0.12065 -0.2794)
			(stroke
				(width 0.1)
				(type default)
			)
			(layer "B.Fab")
		)
		(fp_line
			(start -0.12065 -0.2794)
			(end -0.12065 -0.3048)
			(stroke
				(width 0.1)
				(type default)
			)
			(layer "B.Fab")
		)
		(fp_line
			(start 0.12065 0.2794)
			(end 0.12065 0.3048)
			(stroke
				(width 0.1)
				(type default)
			)
			(layer "B.Fab")
		)
		(fp_line
			(start -0.120396 0.2794)
			(end 0.12065 0.2794)
			(stroke
				(width 0.1)
				(type default)
			)
			(layer "B.Fab")
		)
		(fp_line
			(start 0.67945 0.3048)
			(end 0.67945 -0.305054)
			(stroke
				(width 0.1)
				(type default)
			)
			(layer "B.Fab")
		)
		(fp_line
			(start 0.12065 0.3048)
			(end 0.67945 0.3048)
			(stroke
				(width 0.1)
				(type default)
			)
			(layer "B.Fab")
		)
		(fp_line
			(start -0.120396 0.3048)
			(end -0.120396 0.2794)
			(stroke
				(width 0.1)
				(type default)
			)
			(layer "B.Fab")
		)
		(fp_line
			(start -0.67945 0.3048)
			(end -0.120396 0.3048)
			(stroke
				(width 0.1)
				(type default)
			)
			(layer "B.Fab")
		)
		(pad "1" smd circle
			(at 0.40005 0 270)
			(size 0 0)
			(layers "B.Cu" "B.Mask" "B.Paste")
			(net "PVNN_TERM_CPU0")
		)
		(pad "2" smd circle
			(at -0.40005 0 270)
			(size 0 0)
			(layers "B.Cu" "B.Mask" "B.Paste")
			(net "H_CPU_ERR1_LVC1_R_N")
		)
	)
	(footprint ""
		(layer "B.Cu")
		(at 382.28778 -345.463114 -90)
		(property "Reference" "PR136"
			(at 0 0 90)
			(layer "B.SilkS")
			(hide yes)
			(effects
				(font
					(size 1.27 1.27)
				)
				(justify mirror)
			)
		)
		(property "Value" ""
			(at 0 0 90)
			(layer "B.Fab")
			(effects
				(font
					(size 1.27 1.27)
				)
				(justify mirror)
			)
		)
		(duplicate_pad_numbers_are_jumpers no)
		(fp_line
			(start -0.7874 0.4064)
			(end 0.7874 0.4064)
			(stroke
				(width 0.1524)
				(type default)
			)
			(layer "B.SilkS")
		)
		(fp_line
			(start 0.7874 0.4064)
			(end 0.7874 -0.4064)
			(stroke
				(width 0.1524)
				(type default)
			)
			(layer "B.SilkS")
		)
		(fp_line
			(start -0.7874 -0.4064)
			(end -0.7874 0.4064)
			(stroke
				(width 0.1524)
				(type default)
			)
			(layer "B.SilkS")
		)
		(fp_line
			(start 0.7874 -0.4064)
			(end -0.7874 -0.4064)
			(stroke
				(width 0.1524)
				(type default)
			)
			(layer "B.SilkS")
		)
		(fp_line
			(start -0.67945 0.3048)
			(end -0.120396 0.3048)
			(stroke
				(width 0.1)
				(type default)
			)
			(layer "B.Fab")
		)
		(fp_line
			(start -0.120396 0.3048)
			(end -0.120396 0.2794)
			(stroke
				(width 0.1)
				(type default)
			)
			(layer "B.Fab")
		)
		(fp_line
			(start 0.12065 0.3048)
			(end 0.67945 0.3048)
			(stroke
				(width 0.1)
				(type default)
			)
			(layer "B.Fab")
		)
		(fp_line
			(start 0.67945 0.3048)
			(end 0.67945 -0.305054)
			(stroke
				(width 0.1)
				(type default)
			)
			(layer "B.Fab")
		)
		(fp_line
			(start -0.120396 0.2794)
			(end 0.12065 0.2794)
			(stroke
				(width 0.1)
				(type default)
			)
			(layer "B.Fab")
		)
		(fp_line
			(start 0.12065 0.2794)
			(end 0.12065 0.3048)
			(stroke
				(width 0.1)
				(type default)
			)
			(layer "B.Fab")
		)
		(fp_line
			(start -0.12065 -0.2794)
			(end -0.12065 -0.3048)
			(stroke
				(width 0.1)
				(type default)
			)
			(layer "B.Fab")
		)
		(fp_line
			(start 0.12065 -0.2794)
			(end -0.12065 -0.2794)
			(stroke
				(width 0.1)
				(type default)
			)
			(layer "B.Fab")
		)
		(fp_line
			(start -0.67945 -0.3048)
			(end -0.67945 0.3048)
			(stroke
				(width 0.1)
				(type default)
			)
			(layer "B.Fab")
		)
		(fp_line
			(start -0.12065 -0.3048)
			(end -0.67945 -0.3048)
			(stroke
				(width 0.1)
				(type default)
			)
			(layer "B.Fab")
		)
		(fp_line
			(start 0.12065 -0.305054)
			(end 0.12065 -0.2794)
			(stroke
				(width 0.1)
				(type default)
			)
			(layer "B.Fab")
		)
		(fp_line
			(start 0.67945 -0.305054)
			(end 0.12065 -0.305054)
			(stroke
				(width 0.1)
				(type default)
			)
			(layer "B.Fab")
		)
		(pad "1" smd circle
			(at 0.40005 0 90)
			(size 0 0)
			(layers "B.Cu" "B.Mask" "B.Paste")
			(net "PVCCIN_CPU0_VOS8")
		)
		(pad "2" smd circle
			(at -0.40005 0 90)
			(size 0 0)
			(layers "B.Cu" "B.Mask" "B.Paste")
			(net "PVCCIN_CPU0")
		)
	)
	(footprint ""
		(layer "B.Cu")
		(at 176.10074 -192.699894 -90)
		(property "Reference" "R258"
			(at 0 0 90)
			(layer "B.SilkS")
			(hide yes)
			(effects
				(font
					(size 1.27 1.27)
				)
				(justify mirror)
			)
		)
		(property "Value" ""
			(at 0 0 90)
			(layer "B.Fab")
			(effects
				(font
					(size 1.27 1.27)
				)
				(justify mirror)
			)
		)
		(duplicate_pad_numbers_are_jumpers no)
		(fp_line
			(start -0.7874 0.4064)
			(end 0.7874 0.4064)
			(stroke
				(width 0.1524)
				(type default)
			)
			(layer "B.SilkS")
		)
		(fp_line
			(start 0.7874 0.4064)
			(end 0.7874 -0.4064)
			(stroke
				(width 0.1524)
				(type default)
			)
			(layer "B.SilkS")
		)
		(fp_line
			(start -0.7874 -0.4064)
			(end -0.7874 0.4064)
			(stroke
				(width 0.1524)
				(type default)
			)
			(layer "B.SilkS")
		)
		(fp_line
			(start 0.7874 -0.4064)
			(end -0.7874 -0.4064)
			(stroke
				(width 0.1524)
				(type default)
			)
			(layer "B.SilkS")
		)
		(fp_line
			(start -0.67945 0.3048)
			(end -0.120396 0.3048)
			(stroke
				(width 0.1)
				(type default)
			)
			(layer "B.Fab")
		)
		(fp_line
			(start -0.120396 0.3048)
			(end -0.120396 0.2794)
			(stroke
				(width 0.1)
				(type default)
			)
			(layer "B.Fab")
		)
		(fp_line
			(start 0.12065 0.3048)
			(end 0.67945 0.3048)
			(stroke
				(width 0.1)
				(type default)
			)
			(layer "B.Fab")
		)
		(fp_line
			(start 0.67945 0.3048)
			(end 0.67945 -0.305054)
			(stroke
				(width 0.1)
				(type default)
			)
			(layer "B.Fab")
		)
		(fp_line
			(start -0.120396 0.2794)
			(end 0.12065 0.2794)
			(stroke
				(width 0.1)
				(type default)
			)
			(layer "B.Fab")
		)
		(fp_line
			(start 0.12065 0.2794)
			(end 0.12065 0.3048)
			(stroke
				(width 0.1)
				(type default)
			)
			(layer "B.Fab")
		)
		(fp_line
			(start -0.12065 -0.2794)
			(end -0.12065 -0.3048)
			(stroke
				(width 0.1)
				(type default)
			)
			(layer "B.Fab")
		)
		(fp_line
			(start 0.12065 -0.2794)
			(end -0.12065 -0.2794)
			(stroke
				(width 0.1)
				(type default)
			)
			(layer "B.Fab")
		)
		(fp_line
			(start -0.67945 -0.3048)
			(end -0.67945 0.3048)
			(stroke
				(width 0.1)
				(type default)
			)
			(layer "B.Fab")
		)
		(fp_line
			(start -0.12065 -0.3048)
			(end -0.67945 -0.3048)
			(stroke
				(width 0.1)
				(type default)
			)
			(layer "B.Fab")
		)
		(fp_line
			(start 0.12065 -0.305054)
			(end 0.12065 -0.2794)
			(stroke
				(width 0.1)
				(type default)
			)
			(layer "B.Fab")
		)
		(fp_line
			(start 0.67945 -0.305054)
			(end 0.12065 -0.305054)
			(stroke
				(width 0.1)
				(type default)
			)
			(layer "B.Fab")
		)
		(pad "1" smd circle
			(at 0.40005 0 90)
			(size 0 0)
			(layers "B.Cu" "B.Mask" "B.Paste")
			(net "PVNN_TERM_CPU1")
		)
		(pad "2" smd circle
			(at -0.40005 0 90)
			(size 0 0)
			(layers "B.Cu" "B.Mask" "B.Paste")
			(net "PUD_PCH_BOOT_MODE_CPU1")
		)
	)
	(footprint ""
		(layer "B.Cu")
		(at 122.600974 -333.73568 90)
		(property "Reference" "PC537_P1_4"
			(at 0 0 90)
			(layer "B.SilkS")
			(hide yes)
			(effects
				(font
					(size 1.27 1.27)
				)
				(justify mirror)
			)
		)
		(property "Value" ""
			(at 0 0 90)
			(layer "B.Fab")
			(effects
				(font
					(size 1.27 1.27)
				)
				(justify mirror)
			)
		)
		(duplicate_pad_numbers_are_jumpers no)
		(fp_line
			(start 1.524 -0.762)
			(end -1.524 -0.762)
			(stroke
				(width 0.1524)
				(type default)
			)
			(layer "B.SilkS")
		)
		(fp_line
			(start -1.524 -0.762)
			(end -1.524 0.762)
			(stroke
				(width 0.1524)
				(type default)
			)
			(layer "B.SilkS")
		)
		(fp_line
			(start 1.524 0.762)
			(end 1.524 -0.762)
			(stroke
				(width 0.1524)
				(type default)
			)
			(layer "B.SilkS")
		)
		(fp_line
			(start -1.524 0.762)
			(end 1.524 0.762)
			(stroke
				(width 0.1524)
				(type default)
			)
			(layer "B.SilkS")
		)
		(fp_line
			(start 1.1049 -0.724916)
			(end 1.1049 0.724916)
			(stroke
				(width 0.1)
				(type default)
			)
			(layer "B.Fab")
		)
		(fp_line
			(start -1.1049 -0.724916)
			(end 1.1049 -0.724916)
			(stroke
				(width 0.1)
				(type default)
			)
			(layer "B.Fab")
		)
		(fp_line
			(start 1.1049 0.724916)
			(end -1.1049 0.724916)
			(stroke
				(width 0.1)
				(type default)
			)
			(layer "B.Fab")
		)
		(fp_line
			(start -1.1049 0.724916)
			(end -1.1049 -0.724916)
			(stroke
				(width 0.1)
				(type default)
			)
			(layer "B.Fab")
		)
		(pad "1" smd rect
			(at 0.889 0 90)
			(size 1.016 1.27)
			(layers "B.Cu" "B.Mask" "B.Paste")
			(net "SW_P12V_PVCCIN_CPU1_FLT")
		)
		(pad "2" smd rect
			(at -0.889 0 90)
			(size 1.016 1.27)
			(layers "B.Cu" "B.Mask" "B.Paste")
			(net "GND")
		)
	)
	(footprint ""
		(layer "B.Cu")
		(at 144.51711 -28.989528 180)
		(property "Reference" "C2321"
			(at 0 0 0)
			(layer "B.SilkS")
			(hide yes)
			(effects
				(font
					(size 1.27 1.27)
				)
				(justify mirror)
			)
		)
		(property "Value" ""
			(at 0 0 0)
			(layer "B.Fab")
			(effects
				(font
					(size 1.27 1.27)
				)
				(justify mirror)
			)
		)
		(duplicate_pad_numbers_are_jumpers no)
		(fp_line
			(start 0.7874 0.4064)
			(end 0.7874 -0.4064)
			(stroke
				(width 0.1524)
				(type default)
			)
			(layer "B.SilkS")
		)
		(fp_line
			(start 0.7874 -0.4064)
			(end -0.7874 -0.4064)
			(stroke
				(width 0.1524)
				(type default)
			)
			(layer "B.SilkS")
		)
		(fp_line
			(start -0.7874 0.4064)
			(end 0.7874 0.4064)
			(stroke
				(width 0.1524)
				(type default)
			)
			(layer "B.SilkS")
		)
		(fp_line
			(start -0.7874 -0.4064)
			(end -0.7874 0.4064)
			(stroke
				(width 0.1524)
				(type default)
			)
			(layer "B.SilkS")
		)
		(fp_line
			(start 0.67945 0.3048)
			(end 0.67945 -0.305054)
			(stroke
				(width 0.1)
				(type default)
			)
			(layer "B.Fab")
		)
		(fp_line
			(start 0.67945 -0.305054)
			(end 0.12065 -0.305054)
			(stroke
				(width 0.1)
				(type default)
			)
			(layer "B.Fab")
		)
		(fp_line
			(start 0.12065 0.3048)
			(end 0.67945 0.3048)
			(stroke
				(width 0.1)
				(type default)
			)
			(layer "B.Fab")
		)
		(fp_line
			(start 0.12065 0.2794)
			(end 0.12065 0.3048)
			(stroke
				(width 0.1)
				(type default)
			)
			(layer "B.Fab")
		)
		(fp_line
			(start 0.12065 -0.2794)
			(end -0.12065 -0.2794)
			(stroke
				(width 0.1)
				(type default)
			)
			(layer "B.Fab")
		)
		(fp_line
			(start 0.12065 -0.305054)
			(end 0.12065 -0.2794)
			(stroke
				(width 0.1)
				(type default)
			)
			(layer "B.Fab")
		)
		(fp_line
			(start -0.120396 0.3048)
			(end -0.120396 0.2794)
			(stroke
				(width 0.1)
				(type default)
			)
			(layer "B.Fab")
		)
		(fp_line
			(start -0.120396 0.2794)
			(end 0.12065 0.2794)
			(stroke
				(width 0.1)
				(type default)
			)
			(layer "B.Fab")
		)
		(fp_line
			(start -0.12065 -0.2794)
			(end -0.12065 -0.3048)
			(stroke
				(width 0.1)
				(type default)
			)
			(layer "B.Fab")
		)
		(fp_line
			(start -0.12065 -0.3048)
			(end -0.67945 -0.3048)
			(stroke
				(width 0.1)
				(type default)
			)
			(layer "B.Fab")
		)
		(fp_line
			(start -0.67945 0.3048)
			(end -0.120396 0.3048)
			(stroke
				(width 0.1)
				(type default)
			)
			(layer "B.Fab")
		)
		(fp_line
			(start -0.67945 -0.3048)
			(end -0.67945 0.3048)
			(stroke
				(width 0.1)
				(type default)
			)
			(layer "B.Fab")
		)
		(pad "1" smd circle
			(at 0.40005 0)
			(size 0 0)
			(layers "B.Cu" "B.Mask" "B.Paste")
			(net "PD_USB_HUB_2_RSTN")
		)
		(pad "2" smd circle
			(at -0.40005 0)
			(size 0 0)
			(layers "B.Cu" "B.Mask" "B.Paste")
			(net "GND")
		)
	)
	(footprint ""
		(layer "B.Cu")
		(at 70.369684 -190.744856 90)
		(property "Reference" "R57"
			(at 0 0 90)
			(layer "B.SilkS")
			(hide yes)
			(effects
				(font
					(size 1.27 1.27)
				)
				(justify mirror)
			)
		)
		(property "Value" ""
			(at 0 0 90)
			(layer "B.Fab")
			(effects
				(font
					(size 1.27 1.27)
				)
				(justify mirror)
			)
		)
		(duplicate_pad_numbers_are_jumpers no)
		(fp_line
			(start 0.7874 -0.4064)
			(end -0.7874 -0.4064)
			(stroke
				(width 0.1524)
				(type default)
			)
			(layer "B.SilkS")
		)
		(fp_line
			(start -0.7874 -0.4064)
			(end -0.7874 0.4064)
			(stroke
				(width 0.1524)
				(type default)
			)
			(layer "B.SilkS")
		)
		(fp_line
			(start 0.7874 0.4064)
			(end 0.7874 -0.4064)
			(stroke
				(width 0.1524)
				(type default)
			)
			(layer "B.SilkS")
		)
		(fp_line
			(start -0.7874 0.4064)
			(end 0.7874 0.4064)
			(stroke
				(width 0.1524)
				(type default)
			)
			(layer "B.SilkS")
		)
		(fp_line
			(start 0.67945 -0.305054)
			(end 0.12065 -0.305054)
			(stroke
				(width 0.1)
				(type default)
			)
			(layer "B.Fab")
		)
		(fp_line
			(start 0.12065 -0.305054)
			(end 0.12065 -0.2794)
			(stroke
				(width 0.1)
				(type default)
			)
			(layer "B.Fab")
		)
		(fp_line
			(start -0.12065 -0.3048)
			(end -0.67945 -0.3048)
			(stroke
				(width 0.1)
				(type default)
			)
			(layer "B.Fab")
		)
		(fp_line
			(start -0.67945 -0.3048)
			(end -0.67945 0.3048)
			(stroke
				(width 0.1)
				(type default)
			)
			(layer "B.Fab")
		)
		(fp_line
			(start 0.12065 -0.2794)
			(end -0.12065 -0.2794)
			(stroke
				(width 0.1)
				(type default)
			)
			(layer "B.Fab")
		)
		(fp_line
			(start -0.12065 -0.2794)
			(end -0.12065 -0.3048)
			(stroke
				(width 0.1)
				(type default)
			)
			(layer "B.Fab")
		)
		(fp_line
			(start 0.12065 0.2794)
			(end 0.12065 0.3048)
			(stroke
				(width 0.1)
				(type default)
			)
			(layer "B.Fab")
		)
		(fp_line
			(start -0.120396 0.2794)
			(end 0.12065 0.2794)
			(stroke
				(width 0.1)
				(type default)
			)
			(layer "B.Fab")
		)
		(fp_line
			(start 0.67945 0.3048)
			(end 0.67945 -0.305054)
			(stroke
				(width 0.1)
				(type default)
			)
			(layer "B.Fab")
		)
		(fp_line
			(start 0.12065 0.3048)
			(end 0.67945 0.3048)
			(stroke
				(width 0.1)
				(type default)
			)
			(layer "B.Fab")
		)
		(fp_line
			(start -0.120396 0.3048)
			(end -0.120396 0.2794)
			(stroke
				(width 0.1)
				(type default)
			)
			(layer "B.Fab")
		)
		(fp_line
			(start -0.67945 0.3048)
			(end -0.120396 0.3048)
			(stroke
				(width 0.1)
				(type default)
			)
			(layer "B.Fab")
		)
		(pad "1" smd circle
			(at 0.40005 0 270)
			(size 0 0)
			(layers "B.Cu" "B.Mask" "B.Paste")
			(net "SVID_ALERT0_CPU1_N")
		)
		(pad "2" smd circle
			(at -0.40005 0 270)
			(size 0 0)
			(layers "B.Cu" "B.Mask" "B.Paste")
			(net "SVID_ALERT0_CPU1_R_N")
		)
	)
	(footprint ""
		(layer "B.Cu")
		(at 175.355758 -113.77549 180)
		(property "Reference" "C1929"
			(at 0 0 0)
			(layer "B.SilkS")
			(hide yes)
			(effects
				(font
					(size 1.27 1.27)
				)
				(justify mirror)
			)
		)
		(property "Value" ""
			(at 0 0 0)
			(layer "B.Fab")
			(effects
				(font
					(size 1.27 1.27)
				)
				(justify mirror)
			)
		)
		(duplicate_pad_numbers_are_jumpers no)
		(fp_line
			(start 0.69215 0.2921)
			(end 0.69215 -0.2921)
			(stroke
				(width 0.1524)
				(type default)
			)
			(layer "B.SilkS")
		)
		(fp_line
			(start 0.69215 -0.2921)
			(end -0.69215 -0.2921)
			(stroke
				(width 0.1524)
				(type default)
			)
			(layer "B.SilkS")
		)
		(fp_line
			(start -0.69215 0.2921)
			(end 0.69215 0.2921)
			(stroke
				(width 0.1524)
				(type default)
			)
			(layer "B.SilkS")
		)
		(fp_line
			(start -0.69215 -0.2921)
			(end -0.69215 0.2921)
			(stroke
				(width 0.1524)
				(type default)
			)
			(layer "B.SilkS")
		)
		(fp_line
			(start 0.51435 0.2794)
			(end 0.51435 -0.2794)
			(stroke
				(width 0.1)
				(type default)
			)
			(layer "B.Fab")
		)
		(fp_line
			(start 0.51435 -0.2794)
			(end -0.51435 -0.2794)
			(stroke
				(width 0.1)
				(type default)
			)
			(layer "B.Fab")
		)
		(fp_line
			(start -0.51435 0.2794)
			(end 0.51435 0.2794)
			(stroke
				(width 0.1)
				(type default)
			)
			(layer "B.Fab")
		)
		(fp_line
			(start -0.51435 -0.2794)
			(end -0.51435 0.2794)
			(stroke
				(width 0.1)
				(type default)
			)
			(layer "B.Fab")
		)
		(pad "1" smd circle
			(at 0.40005 0)
			(size 0 0)
			(layers "B.Cu" "B.Mask" "B.Paste")
			(net "P3V3_AUX_FPGA_VCCIO0")
		)
		(pad "2" smd circle
			(at -0.40005 0)
			(size 0 0)
			(layers "B.Cu" "B.Mask" "B.Paste")
			(net "GND")
		)
		(zone
			(layer "B.Cu")
			(hatch none 0.5)
			(connect_pads
				(clearance 0)
			)
			(min_thickness 0.25)
			(keepout
				(tracks not_allowed)
				(vias allowed)
				(pads allowed)
				(copperpour not_allowed)
				(footprints allowed)
			)
			(placement
				(enabled no)
				(sheetname "")
			)
			(fill
				(thermal_gap 0.5)
				(thermal_bridge_width 0.5)
				(island_removal_mode 0)
			)
			(polygon
				(pts
					(xy 175.165258 -113.86312) (xy 175.256698 -113.921286) (xy 175.456088 -113.921286) (xy 175.546258 -113.86312)
					(xy 175.546258 -113.68786) (xy 175.456088 -113.62944) (xy 175.256698 -113.62944) (xy 175.165258 -113.687606)
				)
			)
		)
	)
	(footprint ""
		(layer "B.Cu")
		(at 263.398 -74.933048 90)
		(property "Reference" "PR338"
			(at 0 0 90)
			(layer "B.SilkS")
			(hide yes)
			(effects
				(font
					(size 1.27 1.27)
				)
				(justify mirror)
			)
		)
		(property "Value" ""
			(at 0 0 90)
			(layer "B.Fab")
			(effects
				(font
					(size 1.27 1.27)
				)
				(justify mirror)
			)
		)
		(duplicate_pad_numbers_are_jumpers no)
		(fp_line
			(start 0.7874 -0.4064)
			(end -0.7874 -0.4064)
			(stroke
				(width 0.1524)
				(type default)
			)
			(layer "B.SilkS")
		)
		(fp_line
			(start -0.7874 -0.4064)
			(end -0.7874 0.4064)
			(stroke
				(width 0.1524)
				(type default)
			)
			(layer "B.SilkS")
		)
		(fp_line
			(start 0.7874 0.4064)
			(end 0.7874 -0.4064)
			(stroke
				(width 0.1524)
				(type default)
			)
			(layer "B.SilkS")
		)
		(fp_line
			(start -0.7874 0.4064)
			(end 0.7874 0.4064)
			(stroke
				(width 0.1524)
				(type default)
			)
			(layer "B.SilkS")
		)
		(fp_line
			(start 0.67945 -0.305054)
			(end 0.12065 -0.305054)
			(stroke
				(width 0.1)
				(type default)
			)
			(layer "B.Fab")
		)
		(fp_line
			(start 0.12065 -0.305054)
			(end 0.12065 -0.2794)
			(stroke
				(width 0.1)
				(type default)
			)
			(layer "B.Fab")
		)
		(fp_line
			(start -0.12065 -0.3048)
			(end -0.67945 -0.3048)
			(stroke
				(width 0.1)
				(type default)
			)
			(layer "B.Fab")
		)
		(fp_line
			(start -0.67945 -0.3048)
			(end -0.67945 0.3048)
			(stroke
				(width 0.1)
				(type default)
			)
			(layer "B.Fab")
		)
		(fp_line
			(start 0.12065 -0.2794)
			(end -0.12065 -0.2794)
			(stroke
				(width 0.1)
				(type default)
			)
			(layer "B.Fab")
		)
		(fp_line
			(start -0.12065 -0.2794)
			(end -0.12065 -0.3048)
			(stroke
				(width 0.1)
				(type default)
			)
			(layer "B.Fab")
		)
		(fp_line
			(start 0.12065 0.2794)
			(end 0.12065 0.3048)
			(stroke
				(width 0.1)
				(type default)
			)
			(layer "B.Fab")
		)
		(fp_line
			(start -0.120396 0.2794)
			(end 0.12065 0.2794)
			(stroke
				(width 0.1)
				(type default)
			)
			(layer "B.Fab")
		)
		(fp_line
			(start 0.67945 0.3048)
			(end 0.67945 -0.305054)
			(stroke
				(width 0.1)
				(type default)
			)
			(layer "B.Fab")
		)
		(fp_line
			(start 0.12065 0.3048)
			(end 0.67945 0.3048)
			(stroke
				(width 0.1)
				(type default)
			)
			(layer "B.Fab")
		)
		(fp_line
			(start -0.120396 0.3048)
			(end -0.120396 0.2794)
			(stroke
				(width 0.1)
				(type default)
			)
			(layer "B.Fab")
		)
		(fp_line
			(start -0.67945 0.3048)
			(end -0.120396 0.3048)
			(stroke
				(width 0.1)
				(type default)
			)
			(layer "B.Fab")
		)
		(pad "1" smd circle
			(at 0.40005 0 270)
			(size 0 0)
			(layers "B.Cu" "B.Mask" "B.Paste")
			(net "P1V05_PCH_AUX_MODE")
		)
		(pad "2" smd circle
			(at -0.40005 0 270)
			(size 0 0)
			(layers "B.Cu" "B.Mask" "B.Paste")
			(net "GND")
		)
	)
	(footprint ""
		(layer "B.Cu")
		(at 246.01932 -52.907946 -90)
		(property "Reference" "PC2280"
			(at 0 0 90)
			(layer "B.SilkS")
			(hide yes)
			(effects
				(font
					(size 1.27 1.27)
				)
				(justify mirror)
			)
		)
		(property "Value" ""
			(at 0 0 90)
			(layer "B.Fab")
			(effects
				(font
					(size 1.27 1.27)
				)
				(justify mirror)
			)
		)
		(duplicate_pad_numbers_are_jumpers no)
		(fp_line
			(start -1.524 0.762)
			(end 1.524 0.762)
			(stroke
				(width 0.1524)
				(type default)
			)
			(layer "B.SilkS")
		)
		(fp_line
			(start 1.524 0.762)
			(end 1.524 -0.762)
			(stroke
				(width 0.1524)
				(type default)
			)
			(layer "B.SilkS")
		)
		(fp_line
			(start -1.524 -0.762)
			(end -1.524 0.762)
			(stroke
				(width 0.1524)
				(type default)
			)
			(layer "B.SilkS")
		)
		(fp_line
			(start 1.524 -0.762)
			(end -1.524 -0.762)
			(stroke
				(width 0.1524)
				(type default)
			)
			(layer "B.SilkS")
		)
		(fp_line
			(start -1.1049 0.724916)
			(end -1.1049 -0.724916)
			(stroke
				(width 0.1)
				(type default)
			)
			(layer "B.Fab")
		)
		(fp_line
			(start 1.1049 0.724916)
			(end -1.1049 0.724916)
			(stroke
				(width 0.1)
				(type default)
			)
			(layer "B.Fab")
		)
		(fp_line
			(start -1.1049 -0.724916)
			(end 1.1049 -0.724916)
			(stroke
				(width 0.1)
				(type default)
			)
			(layer "B.Fab")
		)
		(fp_line
			(start 1.1049 -0.724916)
			(end 1.1049 0.724916)
			(stroke
				(width 0.1)
				(type default)
			)
			(layer "B.Fab")
		)
		(pad "1" smd rect
			(at 0.889 0 270)
			(size 1.016 1.27)
			(layers "B.Cu" "B.Mask" "B.Paste")
			(net "P12V_E1S_0")
		)
		(pad "2" smd rect
			(at -0.889 0 270)
			(size 1.016 1.27)
			(layers "B.Cu" "B.Mask" "B.Paste")
			(net "GND")
		)
	)
	(footprint ""
		(layer "B.Cu")
		(at 116.40312 -237.718092 90)
		(property "Reference" "C326"
			(at 0 0 90)
			(layer "B.SilkS")
			(hide yes)
			(effects
				(font
					(size 1.27 1.27)
				)
				(justify mirror)
			)
		)
		(property "Value" ""
			(at 0 0 90)
			(layer "B.Fab")
			(effects
				(font
					(size 1.27 1.27)
				)
				(justify mirror)
			)
		)
		(duplicate_pad_numbers_are_jumpers no)
		(fp_line
			(start 1.524 -0.762)
			(end -1.524 -0.762)
			(stroke
				(width 0.1524)
				(type default)
			)
			(layer "B.SilkS")
		)
		(fp_line
			(start -1.524 -0.762)
			(end -1.524 0.762)
			(stroke
				(width 0.1524)
				(type default)
			)
			(layer "B.SilkS")
		)
		(fp_line
			(start 1.524 0.762)
			(end 1.524 -0.762)
			(stroke
				(width 0.1524)
				(type default)
			)
			(layer "B.SilkS")
		)
		(fp_line
			(start -1.524 0.762)
			(end 1.524 0.762)
			(stroke
				(width 0.1524)
				(type default)
			)
			(layer "B.SilkS")
		)
		(fp_line
			(start 1.1049 -0.724916)
			(end 1.1049 0.724916)
			(stroke
				(width 0.1)
				(type default)
			)
			(layer "B.Fab")
		)
		(fp_line
			(start -1.1049 -0.724916)
			(end 1.1049 -0.724916)
			(stroke
				(width 0.1)
				(type default)
			)
			(layer "B.Fab")
		)
		(fp_line
			(start 1.1049 0.724916)
			(end -1.1049 0.724916)
			(stroke
				(width 0.1)
				(type default)
			)
			(layer "B.Fab")
		)
		(fp_line
			(start -1.1049 0.724916)
			(end -1.1049 -0.724916)
			(stroke
				(width 0.1)
				(type default)
			)
			(layer "B.Fab")
		)
		(pad "1" smd rect
			(at 0.889 0 90)
			(size 1.016 1.27)
			(layers "B.Cu" "B.Mask" "B.Paste")
			(net "PVCCIN_CPU1")
		)
		(pad "2" smd rect
			(at -0.889 0 90)
			(size 1.016 1.27)
			(layers "B.Cu" "B.Mask" "B.Paste")
			(net "GND")
		)
	)
	(footprint ""
		(layer "B.Cu")
		(at 236.20095 -50.193448 180)
		(property "Reference" "R3771"
			(at 0 0 0)
			(layer "B.SilkS")
			(hide yes)
			(effects
				(font
					(size 1.27 1.27)
				)
				(justify mirror)
			)
		)
		(property "Value" ""
			(at 0 0 0)
			(layer "B.Fab")
			(effects
				(font
					(size 1.27 1.27)
				)
				(justify mirror)
			)
		)
		(duplicate_pad_numbers_are_jumpers no)
		(fp_line
			(start 0.7874 0.4064)
			(end 0.7874 -0.4064)
			(stroke
				(width 0.1524)
				(type default)
			)
			(layer "B.SilkS")
		)
		(fp_line
			(start 0.7874 -0.4064)
			(end -0.7874 -0.4064)
			(stroke
				(width 0.1524)
				(type default)
			)
			(layer "B.SilkS")
		)
		(fp_line
			(start -0.7874 0.4064)
			(end 0.7874 0.4064)
			(stroke
				(width 0.1524)
				(type default)
			)
			(layer "B.SilkS")
		)
		(fp_line
			(start -0.7874 -0.4064)
			(end -0.7874 0.4064)
			(stroke
				(width 0.1524)
				(type default)
			)
			(layer "B.SilkS")
		)
		(fp_line
			(start 0.67945 0.3048)
			(end 0.67945 -0.305054)
			(stroke
				(width 0.1)
				(type default)
			)
			(layer "B.Fab")
		)
		(fp_line
			(start 0.67945 -0.305054)
			(end 0.12065 -0.305054)
			(stroke
				(width 0.1)
				(type default)
			)
			(layer "B.Fab")
		)
		(fp_line
			(start 0.12065 0.3048)
			(end 0.67945 0.3048)
			(stroke
				(width 0.1)
				(type default)
			)
			(layer "B.Fab")
		)
		(fp_line
			(start 0.12065 0.2794)
			(end 0.12065 0.3048)
			(stroke
				(width 0.1)
				(type default)
			)
			(layer "B.Fab")
		)
		(fp_line
			(start 0.12065 -0.2794)
			(end -0.12065 -0.2794)
			(stroke
				(width 0.1)
				(type default)
			)
			(layer "B.Fab")
		)
		(fp_line
			(start 0.12065 -0.305054)
			(end 0.12065 -0.2794)
			(stroke
				(width 0.1)
				(type default)
			)
			(layer "B.Fab")
		)
		(fp_line
			(start -0.120396 0.3048)
			(end -0.120396 0.2794)
			(stroke
				(width 0.1)
				(type default)
			)
			(layer "B.Fab")
		)
		(fp_line
			(start -0.120396 0.2794)
			(end 0.12065 0.2794)
			(stroke
				(width 0.1)
				(type default)
			)
			(layer "B.Fab")
		)
		(fp_line
			(start -0.12065 -0.2794)
			(end -0.12065 -0.3048)
			(stroke
				(width 0.1)
				(type default)
			)
			(layer "B.Fab")
		)
		(fp_line
			(start -0.12065 -0.3048)
			(end -0.67945 -0.3048)
			(stroke
				(width 0.1)
				(type default)
			)
			(layer "B.Fab")
		)
		(fp_line
			(start -0.67945 0.3048)
			(end -0.120396 0.3048)
			(stroke
				(width 0.1)
				(type default)
			)
			(layer "B.Fab")
		)
		(fp_line
			(start -0.67945 -0.3048)
			(end -0.67945 0.3048)
			(stroke
				(width 0.1)
				(type default)
			)
			(layer "B.Fab")
		)
		(pad "1" smd circle
			(at 0.40005 0)
			(size 0 0)
			(layers "B.Cu" "B.Mask" "B.Paste")
			(net "P3V3_AUX")
		)
		(pad "2" smd circle
			(at -0.40005 0)
			(size 0 0)
			(layers "B.Cu" "B.Mask" "B.Paste")
			(net "E1S_0_PWRDIS")
		)
	)
	(footprint ""
		(layer "B.Cu")
		(at 196.906896 -193.267584)
		(property "Reference" "U23"
			(at 1.524 -1.87833 0)
			(unlocked yes)
			(layer "B.SilkS")
			(effects
				(font
					(size 0.7874 0.5842)
					(thickness 0.1524)
				)
				(justify left mirror)
			)
		)
		(property "Value" ""
			(at 0 0 0)
			(layer "B.Fab")
			(effects
				(font
					(size 1.27 1.27)
				)
				(justify mirror)
			)
		)
		(duplicate_pad_numbers_are_jumpers no)
		(fp_line
			(start -1.4986 -1.100074)
			(end -1.4986 1.100074)
			(stroke
				(width 0.1524)
				(type default)
			)
			(layer "B.SilkS")
		)
		(fp_line
			(start -1.4986 1.100074)
			(end 1.4986 1.100074)
			(stroke
				(width 0.1524)
				(type default)
			)
			(layer "B.SilkS")
		)
		(fp_line
			(start 1.4986 -1.100074)
			(end -1.4986 -1.100074)
			(stroke
				(width 0.1524)
				(type default)
			)
			(layer "B.SilkS")
		)
		(fp_line
			(start 1.4986 1.100074)
			(end 1.4986 -1.100074)
			(stroke
				(width 0.1524)
				(type default)
			)
			(layer "B.SilkS")
		)
		(fp_poly
			(pts
				(xy 2.15138 -0.417068) (xy 1.59766 -0.71374) (xy 2.15138 -1.041908)
			)
			(stroke
				(width 0)
				(type default)
			)
			(fill yes)
			(layer "B.SilkS")
		)
		(fp_line
			(start -0.67437 -1.100074)
			(end -0.67437 1.100074)
			(stroke
				(width 0.1)
				(type default)
			)
			(layer "B.Fab")
		)
		(fp_line
			(start -0.67437 1.100074)
			(end 0.67437 1.100074)
			(stroke
				(width 0.1)
				(type default)
			)
			(layer "B.Fab")
		)
		(fp_line
			(start 0.67437 -1.100074)
			(end -0.67437 -1.100074)
			(stroke
				(width 0.1)
				(type default)
			)
			(layer "B.Fab")
		)
		(fp_line
			(start 0.67437 1.100074)
			(end 0.67437 -1.100074)
			(stroke
				(width 0.1)
				(type default)
			)
			(layer "B.Fab")
		)
		(fp_poly
			(pts
				(xy 2.20472 -0.338328) (xy 2.20472 -0.963168) (xy 1.651 -0.635)
			)
			(stroke
				(width 0)
				(type default)
			)
			(fill yes)
			(layer "B.Fab")
		)
		(pad "1" smd rect
			(at 0.889 -0.649986 180)
			(size 1.016 0.381)
			(layers "B.Cu" "B.Mask" "B.Paste")
			(net "FM_CPU1_SKTOCC_N")
		)
		(pad "2" smd rect
			(at 0.889 0 180)
			(size 1.016 0.381)
			(layers "B.Cu" "B.Mask" "B.Paste")
			(net "FM_CPU0_SKTOCC_N")
		)
		(pad "3" smd rect
			(at 0.889 0.649986 180)
			(size 1.016 0.381)
			(layers "B.Cu" "B.Mask" "B.Paste")
			(net "GND")
		)
		(pad "4" smd rect
			(at -0.889 0.649986 180)
			(size 1.016 0.381)
			(layers "B.Cu" "B.Mask" "B.Paste")
			(net "FM_CPU_EN")
		)
		(pad "5" smd rect
			(at -0.889 -0.649986 180)
			(size 1.016 0.381)
			(layers "B.Cu" "B.Mask" "B.Paste")
			(net "P3V3_AUX")
		)
	)
	(footprint ""
		(layer "B.Cu")
		(at 353.619308 -259.531866 90)
		(property "Reference" "C501"
			(at 0 0 90)
			(layer "B.SilkS")
			(hide yes)
			(effects
				(font
					(size 1.27 1.27)
				)
				(justify mirror)
			)
		)
		(property "Value" ""
			(at 0 0 90)
			(layer "B.Fab")
			(effects
				(font
					(size 1.27 1.27)
				)
				(justify mirror)
			)
		)
		(duplicate_pad_numbers_are_jumpers no)
		(fp_line
			(start 1.524 -0.762)
			(end -1.524 -0.762)
			(stroke
				(width 0.1524)
				(type default)
			)
			(layer "B.SilkS")
		)
		(fp_line
			(start -1.524 -0.762)
			(end -1.524 0.762)
			(stroke
				(width 0.1524)
				(type default)
			)
			(layer "B.SilkS")
		)
		(fp_line
			(start 1.524 0.762)
			(end 1.524 -0.762)
			(stroke
				(width 0.1524)
				(type default)
			)
			(layer "B.SilkS")
		)
		(fp_line
			(start -1.524 0.762)
			(end 1.524 0.762)
			(stroke
				(width 0.1524)
				(type default)
			)
			(layer "B.SilkS")
		)
		(fp_line
			(start 1.1049 -0.724916)
			(end 1.1049 0.724916)
			(stroke
				(width 0.1)
				(type default)
			)
			(layer "B.Fab")
		)
		(fp_line
			(start -1.1049 -0.724916)
			(end 1.1049 -0.724916)
			(stroke
				(width 0.1)
				(type default)
			)
			(layer "B.Fab")
		)
		(fp_line
			(start 1.1049 0.724916)
			(end -1.1049 0.724916)
			(stroke
				(width 0.1)
				(type default)
			)
			(layer "B.Fab")
		)
		(fp_line
			(start -1.1049 0.724916)
			(end -1.1049 -0.724916)
			(stroke
				(width 0.1)
				(type default)
			)
			(layer "B.Fab")
		)
		(pad "1" smd rect
			(at 0.889 0 90)
			(size 1.016 1.27)
			(layers "B.Cu" "B.Mask" "B.Paste")
			(net "PVCCFA_EHV_FIVRA_CPU0")
		)
		(pad "2" smd rect
			(at -0.889 0 90)
			(size 1.016 1.27)
			(layers "B.Cu" "B.Mask" "B.Paste")
			(net "GND")
		)
	)
	(footprint ""
		(layer "B.Cu")
		(at 407.91257 -167.350948 180)
		(property "Reference" "PC204_P0_1"
			(at 0 0 0)
			(layer "B.SilkS")
			(hide yes)
			(effects
				(font
					(size 1.27 1.27)
				)
				(justify mirror)
			)
		)
		(property "Value" ""
			(at 0 0 0)
			(layer "B.Fab")
			(effects
				(font
					(size 1.27 1.27)
				)
				(justify mirror)
			)
		)
		(duplicate_pad_numbers_are_jumpers no)
		(fp_line
			(start 1.524 0.762)
			(end 1.524 -0.762)
			(stroke
				(width 0.1524)
				(type default)
			)
			(layer "B.SilkS")
		)
		(fp_line
			(start 1.524 -0.762)
			(end -1.524 -0.762)
			(stroke
				(width 0.1524)
				(type default)
			)
			(layer "B.SilkS")
		)
		(fp_line
			(start -1.524 0.762)
			(end 1.524 0.762)
			(stroke
				(width 0.1524)
				(type default)
			)
			(layer "B.SilkS")
		)
		(fp_line
			(start -1.524 -0.762)
			(end -1.524 0.762)
			(stroke
				(width 0.1524)
				(type default)
			)
			(layer "B.SilkS")
		)
		(fp_line
			(start 1.1049 0.724916)
			(end -1.1049 0.724916)
			(stroke
				(width 0.1)
				(type default)
			)
			(layer "B.Fab")
		)
		(fp_line
			(start 1.1049 -0.724916)
			(end 1.1049 0.724916)
			(stroke
				(width 0.1)
				(type default)
			)
			(layer "B.Fab")
		)
		(fp_line
			(start -1.1049 0.724916)
			(end -1.1049 -0.724916)
			(stroke
				(width 0.1)
				(type default)
			)
			(layer "B.Fab")
		)
		(fp_line
			(start -1.1049 -0.724916)
			(end 1.1049 -0.724916)
			(stroke
				(width 0.1)
				(type default)
			)
			(layer "B.Fab")
		)
		(pad "1" smd rect
			(at 0.889 0 180)
			(size 1.016 1.27)
			(layers "B.Cu" "B.Mask" "B.Paste")
			(net "PVCCINFAON_CPU0")
		)
		(pad "2" smd rect
			(at -0.889 0 180)
			(size 1.016 1.27)
			(layers "B.Cu" "B.Mask" "B.Paste")
			(net "GND")
		)
	)
	(footprint ""
		(layer "B.Cu")
		(at 448.22872 -78.115668 90)
		(property "Reference" "R3117"
			(at 0 0 90)
			(layer "B.SilkS")
			(hide yes)
			(effects
				(font
					(size 1.27 1.27)
				)
				(justify mirror)
			)
		)
		(property "Value" ""
			(at 0 0 90)
			(layer "B.Fab")
			(effects
				(font
					(size 1.27 1.27)
				)
				(justify mirror)
			)
		)
		(duplicate_pad_numbers_are_jumpers no)
		(fp_line
			(start 0.7874 -0.4064)
			(end -0.7874 -0.4064)
			(stroke
				(width 0.1524)
				(type default)
			)
			(layer "B.SilkS")
		)
		(fp_line
			(start -0.7874 -0.4064)
			(end -0.7874 0.4064)
			(stroke
				(width 0.1524)
				(type default)
			)
			(layer "B.SilkS")
		)
		(fp_line
			(start 0.7874 0.4064)
			(end 0.7874 -0.4064)
			(stroke
				(width 0.1524)
				(type default)
			)
			(layer "B.SilkS")
		)
		(fp_line
			(start -0.7874 0.4064)
			(end 0.7874 0.4064)
			(stroke
				(width 0.1524)
				(type default)
			)
			(layer "B.SilkS")
		)
		(fp_line
			(start 0.67945 -0.305054)
			(end 0.12065 -0.305054)
			(stroke
				(width 0.1)
				(type default)
			)
			(layer "B.Fab")
		)
		(fp_line
			(start 0.12065 -0.305054)
			(end 0.12065 -0.2794)
			(stroke
				(width 0.1)
				(type default)
			)
			(layer "B.Fab")
		)
		(fp_line
			(start -0.12065 -0.3048)
			(end -0.67945 -0.3048)
			(stroke
				(width 0.1)
				(type default)
			)
			(layer "B.Fab")
		)
		(fp_line
			(start -0.67945 -0.3048)
			(end -0.67945 0.3048)
			(stroke
				(width 0.1)
				(type default)
			)
			(layer "B.Fab")
		)
		(fp_line
			(start 0.12065 -0.2794)
			(end -0.12065 -0.2794)
			(stroke
				(width 0.1)
				(type default)
			)
			(layer "B.Fab")
		)
		(fp_line
			(start -0.12065 -0.2794)
			(end -0.12065 -0.3048)
			(stroke
				(width 0.1)
				(type default)
			)
			(layer "B.Fab")
		)
		(fp_line
			(start 0.12065 0.2794)
			(end 0.12065 0.3048)
			(stroke
				(width 0.1)
				(type default)
			)
			(layer "B.Fab")
		)
		(fp_line
			(start -0.120396 0.2794)
			(end 0.12065 0.2794)
			(stroke
				(width 0.1)
				(type default)
			)
			(layer "B.Fab")
		)
		(fp_line
			(start 0.67945 0.3048)
			(end 0.67945 -0.305054)
			(stroke
				(width 0.1)
				(type default)
			)
			(layer "B.Fab")
		)
		(fp_line
			(start 0.12065 0.3048)
			(end 0.67945 0.3048)
			(stroke
				(width 0.1)
				(type default)
			)
			(layer "B.Fab")
		)
		(fp_line
			(start -0.120396 0.3048)
			(end -0.120396 0.2794)
			(stroke
				(width 0.1)
				(type default)
			)
			(layer "B.Fab")
		)
		(fp_line
			(start -0.67945 0.3048)
			(end -0.120396 0.3048)
			(stroke
				(width 0.1)
				(type default)
			)
			(layer "B.Fab")
		)
		(pad "1" smd circle
			(at 0.40005 0 270)
			(size 0 0)
			(layers "B.Cu" "B.Mask" "B.Paste")
			(net "P12V_AUX")
		)
		(pad "2" smd circle
			(at -0.40005 0 270)
			(size 0 0)
			(layers "B.Cu" "B.Mask" "B.Paste")
			(net "P3V3_AUX_EN")
		)
	)
	(footprint ""
		(layer "B.Cu")
		(at 76.413106 -334.566514 -90)
		(property "Reference" "PR574"
			(at 0 0 90)
			(layer "B.SilkS")
			(hide yes)
			(effects
				(font
					(size 1.27 1.27)
				)
				(justify mirror)
			)
		)
		(property "Value" ""
			(at 0 0 90)
			(layer "B.Fab")
			(effects
				(font
					(size 1.27 1.27)
				)
				(justify mirror)
			)
		)
		(duplicate_pad_numbers_are_jumpers no)
		(fp_line
			(start -0.7874 0.4064)
			(end 0.7874 0.4064)
			(stroke
				(width 0.1524)
				(type default)
			)
			(layer "B.SilkS")
		)
		(fp_line
			(start 0.7874 0.4064)
			(end 0.7874 -0.4064)
			(stroke
				(width 0.1524)
				(type default)
			)
			(layer "B.SilkS")
		)
		(fp_line
			(start -0.7874 -0.4064)
			(end -0.7874 0.4064)
			(stroke
				(width 0.1524)
				(type default)
			)
			(layer "B.SilkS")
		)
		(fp_line
			(start 0.7874 -0.4064)
			(end -0.7874 -0.4064)
			(stroke
				(width 0.1524)
				(type default)
			)
			(layer "B.SilkS")
		)
		(fp_line
			(start -0.67945 0.3048)
			(end -0.120396 0.3048)
			(stroke
				(width 0.1)
				(type default)
			)
			(layer "B.Fab")
		)
		(fp_line
			(start -0.120396 0.3048)
			(end -0.120396 0.2794)
			(stroke
				(width 0.1)
				(type default)
			)
			(layer "B.Fab")
		)
		(fp_line
			(start 0.12065 0.3048)
			(end 0.67945 0.3048)
			(stroke
				(width 0.1)
				(type default)
			)
			(layer "B.Fab")
		)
		(fp_line
			(start 0.67945 0.3048)
			(end 0.67945 -0.305054)
			(stroke
				(width 0.1)
				(type default)
			)
			(layer "B.Fab")
		)
		(fp_line
			(start -0.120396 0.2794)
			(end 0.12065 0.2794)
			(stroke
				(width 0.1)
				(type default)
			)
			(layer "B.Fab")
		)
		(fp_line
			(start 0.12065 0.2794)
			(end 0.12065 0.3048)
			(stroke
				(width 0.1)
				(type default)
			)
			(layer "B.Fab")
		)
		(fp_line
			(start -0.12065 -0.2794)
			(end -0.12065 -0.3048)
			(stroke
				(width 0.1)
				(type default)
			)
			(layer "B.Fab")
		)
		(fp_line
			(start 0.12065 -0.2794)
			(end -0.12065 -0.2794)
			(stroke
				(width 0.1)
				(type default)
			)
			(layer "B.Fab")
		)
		(fp_line
			(start -0.67945 -0.3048)
			(end -0.67945 0.3048)
			(stroke
				(width 0.1)
				(type default)
			)
			(layer "B.Fab")
		)
		(fp_line
			(start -0.12065 -0.3048)
			(end -0.67945 -0.3048)
			(stroke
				(width 0.1)
				(type default)
			)
			(layer "B.Fab")
		)
		(fp_line
			(start 0.12065 -0.305054)
			(end 0.12065 -0.2794)
			(stroke
				(width 0.1)
				(type default)
			)
			(layer "B.Fab")
		)
		(fp_line
			(start 0.67945 -0.305054)
			(end 0.12065 -0.305054)
			(stroke
				(width 0.1)
				(type default)
			)
			(layer "B.Fab")
		)
		(pad "1" smd circle
			(at 0.40005 0 90)
			(size 0 0)
			(layers "B.Cu" "B.Mask" "B.Paste")
			(net "VSENSE_PVCCIN_CPU1_DN")
		)
		(pad "2" smd circle
			(at -0.40005 0 90)
			(size 0 0)
			(layers "B.Cu" "B.Mask" "B.Paste")
			(net "GND")
		)
	)
	(footprint ""
		(layer "B.Cu")
		(at 303.959768 -365.219488 180)
		(property "Reference" "PC1672"
			(at 0 0 0)
			(layer "B.SilkS")
			(hide yes)
			(effects
				(font
					(size 1.27 1.27)
				)
				(justify mirror)
			)
		)
		(property "Value" ""
			(at 0 0 0)
			(layer "B.Fab")
			(effects
				(font
					(size 1.27 1.27)
				)
				(justify mirror)
			)
		)
		(duplicate_pad_numbers_are_jumpers no)
		(fp_line
			(start 1.524 0.762)
			(end 1.524 -0.762)
			(stroke
				(width 0.1524)
				(type default)
			)
			(layer "B.SilkS")
		)
		(fp_line
			(start 1.524 -0.762)
			(end -1.524 -0.762)
			(stroke
				(width 0.1524)
				(type default)
			)
			(layer "B.SilkS")
		)
		(fp_line
			(start -1.524 0.762)
			(end 1.524 0.762)
			(stroke
				(width 0.1524)
				(type default)
			)
			(layer "B.SilkS")
		)
		(fp_line
			(start -1.524 -0.762)
			(end -1.524 0.762)
			(stroke
				(width 0.1524)
				(type default)
			)
			(layer "B.SilkS")
		)
		(fp_line
			(start 1.1049 0.724916)
			(end -1.1049 0.724916)
			(stroke
				(width 0.1)
				(type default)
			)
			(layer "B.Fab")
		)
		(fp_line
			(start 1.1049 -0.724916)
			(end 1.1049 0.724916)
			(stroke
				(width 0.1)
				(type default)
			)
			(layer "B.Fab")
		)
		(fp_line
			(start -1.1049 0.724916)
			(end -1.1049 -0.724916)
			(stroke
				(width 0.1)
				(type default)
			)
			(layer "B.Fab")
		)
		(fp_line
			(start -1.1049 -0.724916)
			(end 1.1049 -0.724916)
			(stroke
				(width 0.1)
				(type default)
			)
			(layer "B.Fab")
		)
		(pad "1" smd rect
			(at 0.889 0 180)
			(size 1.016 1.27)
			(layers "B.Cu" "B.Mask" "B.Paste")
			(net "SW_P12V_PVCCFA_EHV_FIVRA_CPU0_L")
		)
		(pad "2" smd rect
			(at -0.889 0 180)
			(size 1.016 1.27)
			(layers "B.Cu" "B.Mask" "B.Paste")
			(net "GND")
		)
	)
	(footprint ""
		(layer "B.Cu")
		(at 344.820748 -32.58439 180)
		(property "Reference" "R1962"
			(at 0 0 0)
			(layer "B.SilkS")
			(hide yes)
			(effects
				(font
					(size 1.27 1.27)
				)
				(justify mirror)
			)
		)
		(property "Value" ""
			(at 0 0 0)
			(layer "B.Fab")
			(effects
				(font
					(size 1.27 1.27)
				)
				(justify mirror)
			)
		)
		(duplicate_pad_numbers_are_jumpers no)
		(fp_line
			(start 0.7874 0.4064)
			(end 0.7874 -0.4064)
			(stroke
				(width 0.1524)
				(type default)
			)
			(layer "B.SilkS")
		)
		(fp_line
			(start 0.7874 -0.4064)
			(end -0.7874 -0.4064)
			(stroke
				(width 0.1524)
				(type default)
			)
			(layer "B.SilkS")
		)
		(fp_line
			(start -0.7874 0.4064)
			(end 0.7874 0.4064)
			(stroke
				(width 0.1524)
				(type default)
			)
			(layer "B.SilkS")
		)
		(fp_line
			(start -0.7874 -0.4064)
			(end -0.7874 0.4064)
			(stroke
				(width 0.1524)
				(type default)
			)
			(layer "B.SilkS")
		)
		(fp_line
			(start 0.67945 0.3048)
			(end 0.67945 -0.305054)
			(stroke
				(width 0.1)
				(type default)
			)
			(layer "B.Fab")
		)
		(fp_line
			(start 0.67945 -0.305054)
			(end 0.12065 -0.305054)
			(stroke
				(width 0.1)
				(type default)
			)
			(layer "B.Fab")
		)
		(fp_line
			(start 0.12065 0.3048)
			(end 0.67945 0.3048)
			(stroke
				(width 0.1)
				(type default)
			)
			(layer "B.Fab")
		)
		(fp_line
			(start 0.12065 0.2794)
			(end 0.12065 0.3048)
			(stroke
				(width 0.1)
				(type default)
			)
			(layer "B.Fab")
		)
		(fp_line
			(start 0.12065 -0.2794)
			(end -0.12065 -0.2794)
			(stroke
				(width 0.1)
				(type default)
			)
			(layer "B.Fab")
		)
		(fp_line
			(start 0.12065 -0.305054)
			(end 0.12065 -0.2794)
			(stroke
				(width 0.1)
				(type default)
			)
			(layer "B.Fab")
		)
		(fp_line
			(start -0.120396 0.3048)
			(end -0.120396 0.2794)
			(stroke
				(width 0.1)
				(type default)
			)
			(layer "B.Fab")
		)
		(fp_line
			(start -0.120396 0.2794)
			(end 0.12065 0.2794)
			(stroke
				(width 0.1)
				(type default)
			)
			(layer "B.Fab")
		)
		(fp_line
			(start -0.12065 -0.2794)
			(end -0.12065 -0.3048)
			(stroke
				(width 0.1)
				(type default)
			)
			(layer "B.Fab")
		)
		(fp_line
			(start -0.12065 -0.3048)
			(end -0.67945 -0.3048)
			(stroke
				(width 0.1)
				(type default)
			)
			(layer "B.Fab")
		)
		(fp_line
			(start -0.67945 0.3048)
			(end -0.120396 0.3048)
			(stroke
				(width 0.1)
				(type default)
			)
			(layer "B.Fab")
		)
		(fp_line
			(start -0.67945 -0.3048)
			(end -0.67945 0.3048)
			(stroke
				(width 0.1)
				(type default)
			)
			(layer "B.Fab")
		)
		(pad "1" smd circle
			(at 0.40005 0)
			(size 0 0)
			(layers "B.Cu" "B.Mask" "B.Paste")
			(net "FM_PCH_CONSENT_STRAP_N")
		)
		(pad "2" smd circle
			(at -0.40005 0)
			(size 0 0)
			(layers "B.Cu" "B.Mask" "B.Paste")
			(net "GND")
		)
	)
	(footprint ""
		(layer "B.Cu")
		(at 52.335684 -161.260028)
		(property "Reference" "PR1805"
			(at 0 0 0)
			(layer "B.SilkS")
			(hide yes)
			(effects
				(font
					(size 1.27 1.27)
				)
				(justify mirror)
			)
		)
		(property "Value" ""
			(at 0 0 0)
			(layer "B.Fab")
			(effects
				(font
					(size 1.27 1.27)
				)
				(justify mirror)
			)
		)
		(duplicate_pad_numbers_are_jumpers no)
		(fp_line
			(start -0.7874 -0.4064)
			(end -0.7874 0.4064)
			(stroke
				(width 0.1524)
				(type default)
			)
			(layer "B.SilkS")
		)
		(fp_line
			(start -0.7874 0.4064)
			(end 0.7874 0.4064)
			(stroke
				(width 0.1524)
				(type default)
			)
			(layer "B.SilkS")
		)
		(fp_line
			(start 0.7874 -0.4064)
			(end -0.7874 -0.4064)
			(stroke
				(width 0.1524)
				(type default)
			)
			(layer "B.SilkS")
		)
		(fp_line
			(start 0.7874 0.4064)
			(end 0.7874 -0.4064)
			(stroke
				(width 0.1524)
				(type default)
			)
			(layer "B.SilkS")
		)
		(fp_line
			(start -0.67945 -0.3048)
			(end -0.67945 0.3048)
			(stroke
				(width 0.1)
				(type default)
			)
			(layer "B.Fab")
		)
		(fp_line
			(start -0.67945 0.3048)
			(end -0.120396 0.3048)
			(stroke
				(width 0.1)
				(type default)
			)
			(layer "B.Fab")
		)
		(fp_line
			(start -0.12065 -0.3048)
			(end -0.67945 -0.3048)
			(stroke
				(width 0.1)
				(type default)
			)
			(layer "B.Fab")
		)
		(fp_line
			(start -0.12065 -0.2794)
			(end -0.12065 -0.3048)
			(stroke
				(width 0.1)
				(type default)
			)
			(layer "B.Fab")
		)
		(fp_line
			(start -0.120396 0.2794)
			(end 0.12065 0.2794)
			(stroke
				(width 0.1)
				(type default)
			)
			(layer "B.Fab")
		)
		(fp_line
			(start -0.120396 0.3048)
			(end -0.120396 0.2794)
			(stroke
				(width 0.1)
				(type default)
			)
			(layer "B.Fab")
		)
		(fp_line
			(start 0.12065 -0.305054)
			(end 0.12065 -0.2794)
			(stroke
				(width 0.1)
				(type default)
			)
			(layer "B.Fab")
		)
		(fp_line
			(start 0.12065 -0.2794)
			(end -0.12065 -0.2794)
			(stroke
				(width 0.1)
				(type default)
			)
			(layer "B.Fab")
		)
		(fp_line
			(start 0.12065 0.2794)
			(end 0.12065 0.3048)
			(stroke
				(width 0.1)
				(type default)
			)
			(layer "B.Fab")
		)
		(fp_line
			(start 0.12065 0.3048)
			(end 0.67945 0.3048)
			(stroke
				(width 0.1)
				(type default)
			)
			(layer "B.Fab")
		)
		(fp_line
			(start 0.67945 -0.305054)
			(end 0.12065 -0.305054)
			(stroke
				(width 0.1)
				(type default)
			)
			(layer "B.Fab")
		)
		(fp_line
			(start 0.67945 0.3048)
			(end 0.67945 -0.305054)
			(stroke
				(width 0.1)
				(type default)
			)
			(layer "B.Fab")
		)
		(pad "1" smd circle
			(at 0.40005 0 180)
			(size 0 0)
			(layers "B.Cu" "B.Mask" "B.Paste")
			(net "PVCCD_HV_CPU1_VOS")
		)
		(pad "2" smd circle
			(at -0.40005 0 180)
			(size 0 0)
			(layers "B.Cu" "B.Mask" "B.Paste")
			(net "PVCCD_HV_CPU1")
		)
	)
	(footprint ""
		(layer "B.Cu")
		(at 338.911692 -187.998608 -90)
		(property "Reference" "R4"
			(at 0 0 90)
			(layer "B.SilkS")
			(hide yes)
			(effects
				(font
					(size 1.27 1.27)
				)
				(justify mirror)
			)
		)
		(property "Value" ""
			(at 0 0 90)
			(layer "B.Fab")
			(effects
				(font
					(size 1.27 1.27)
				)
				(justify mirror)
			)
		)
		(duplicate_pad_numbers_are_jumpers no)
		(fp_line
			(start -0.7874 0.4064)
			(end 0.7874 0.4064)
			(stroke
				(width 0.1524)
				(type default)
			)
			(layer "B.SilkS")
		)
		(fp_line
			(start 0.7874 0.4064)
			(end 0.7874 -0.4064)
			(stroke
				(width 0.1524)
				(type default)
			)
			(layer "B.SilkS")
		)
		(fp_line
			(start -0.7874 -0.4064)
			(end -0.7874 0.4064)
			(stroke
				(width 0.1524)
				(type default)
			)
			(layer "B.SilkS")
		)
		(fp_line
			(start 0.7874 -0.4064)
			(end -0.7874 -0.4064)
			(stroke
				(width 0.1524)
				(type default)
			)
			(layer "B.SilkS")
		)
		(fp_line
			(start -0.67945 0.3048)
			(end -0.120396 0.3048)
			(stroke
				(width 0.1)
				(type default)
			)
			(layer "B.Fab")
		)
		(fp_line
			(start -0.120396 0.3048)
			(end -0.120396 0.2794)
			(stroke
				(width 0.1)
				(type default)
			)
			(layer "B.Fab")
		)
		(fp_line
			(start 0.12065 0.3048)
			(end 0.67945 0.3048)
			(stroke
				(width 0.1)
				(type default)
			)
			(layer "B.Fab")
		)
		(fp_line
			(start 0.67945 0.3048)
			(end 0.67945 -0.305054)
			(stroke
				(width 0.1)
				(type default)
			)
			(layer "B.Fab")
		)
		(fp_line
			(start -0.120396 0.2794)
			(end 0.12065 0.2794)
			(stroke
				(width 0.1)
				(type default)
			)
			(layer "B.Fab")
		)
		(fp_line
			(start 0.12065 0.2794)
			(end 0.12065 0.3048)
			(stroke
				(width 0.1)
				(type default)
			)
			(layer "B.Fab")
		)
		(fp_line
			(start -0.12065 -0.2794)
			(end -0.12065 -0.3048)
			(stroke
				(width 0.1)
				(type default)
			)
			(layer "B.Fab")
		)
		(fp_line
			(start 0.12065 -0.2794)
			(end -0.12065 -0.2794)
			(stroke
				(width 0.1)
				(type default)
			)
			(layer "B.Fab")
		)
		(fp_line
			(start -0.67945 -0.3048)
			(end -0.67945 0.3048)
			(stroke
				(width 0.1)
				(type default)
			)
			(layer "B.Fab")
		)
		(fp_line
			(start -0.12065 -0.3048)
			(end -0.67945 -0.3048)
			(stroke
				(width 0.1)
				(type default)
			)
			(layer "B.Fab")
		)
		(fp_line
			(start 0.12065 -0.305054)
			(end 0.12065 -0.2794)
			(stroke
				(width 0.1)
				(type default)
			)
			(layer "B.Fab")
		)
		(fp_line
			(start 0.67945 -0.305054)
			(end 0.12065 -0.305054)
			(stroke
				(width 0.1)
				(type default)
			)
			(layer "B.Fab")
		)
		(pad "1" smd circle
			(at 0.40005 0 90)
			(size 0 0)
			(layers "B.Cu" "B.Mask" "B.Paste")
			(net "JTAG_MUX_CPU0_GTL_TDI")
		)
		(pad "2" smd circle
			(at -0.40005 0 90)
			(size 0 0)
			(layers "B.Cu" "B.Mask" "B.Paste")
			(net "JTAG_DBP_CPU0_GTL_R_TDI")
		)
	)
	(footprint ""
		(layer "B.Cu")
		(at 104.786938 -236.00791 180)
		(property "Reference" "C71"
			(at 0 0 0)
			(layer "B.SilkS")
			(hide yes)
			(effects
				(font
					(size 1.27 1.27)
				)
				(justify mirror)
			)
		)
		(property "Value" ""
			(at 0 0 0)
			(layer "B.Fab")
			(effects
				(font
					(size 1.27 1.27)
				)
				(justify mirror)
			)
		)
		(duplicate_pad_numbers_are_jumpers no)
		(fp_line
			(start 0.7874 0.4064)
			(end 0.7874 -0.4064)
			(stroke
				(width 0.1524)
				(type default)
			)
			(layer "B.SilkS")
		)
		(fp_line
			(start 0.7874 -0.4064)
			(end -0.7874 -0.4064)
			(stroke
				(width 0.1524)
				(type default)
			)
			(layer "B.SilkS")
		)
		(fp_line
			(start -0.7874 0.4064)
			(end 0.7874 0.4064)
			(stroke
				(width 0.1524)
				(type default)
			)
			(layer "B.SilkS")
		)
		(fp_line
			(start -0.7874 -0.4064)
			(end -0.7874 0.4064)
			(stroke
				(width 0.1524)
				(type default)
			)
			(layer "B.SilkS")
		)
		(fp_line
			(start 0.67945 0.3048)
			(end 0.67945 -0.305054)
			(stroke
				(width 0.1)
				(type default)
			)
			(layer "B.Fab")
		)
		(fp_line
			(start 0.67945 -0.305054)
			(end 0.12065 -0.305054)
			(stroke
				(width 0.1)
				(type default)
			)
			(layer "B.Fab")
		)
		(fp_line
			(start 0.12065 0.3048)
			(end 0.67945 0.3048)
			(stroke
				(width 0.1)
				(type default)
			)
			(layer "B.Fab")
		)
		(fp_line
			(start 0.12065 0.2794)
			(end 0.12065 0.3048)
			(stroke
				(width 0.1)
				(type default)
			)
			(layer "B.Fab")
		)
		(fp_line
			(start 0.12065 -0.2794)
			(end -0.12065 -0.2794)
			(stroke
				(width 0.1)
				(type default)
			)
			(layer "B.Fab")
		)
		(fp_line
			(start 0.12065 -0.305054)
			(end 0.12065 -0.2794)
			(stroke
				(width 0.1)
				(type default)
			)
			(layer "B.Fab")
		)
		(fp_line
			(start -0.120396 0.3048)
			(end -0.120396 0.2794)
			(stroke
				(width 0.1)
				(type default)
			)
			(layer "B.Fab")
		)
		(fp_line
			(start -0.120396 0.2794)
			(end 0.12065 0.2794)
			(stroke
				(width 0.1)
				(type default)
			)
			(layer "B.Fab")
		)
		(fp_line
			(start -0.12065 -0.2794)
			(end -0.12065 -0.3048)
			(stroke
				(width 0.1)
				(type default)
			)
			(layer "B.Fab")
		)
		(fp_line
			(start -0.12065 -0.3048)
			(end -0.67945 -0.3048)
			(stroke
				(width 0.1)
				(type default)
			)
			(layer "B.Fab")
		)
		(fp_line
			(start -0.67945 0.3048)
			(end -0.120396 0.3048)
			(stroke
				(width 0.1)
				(type default)
			)
			(layer "B.Fab")
		)
		(fp_line
			(start -0.67945 -0.3048)
			(end -0.67945 0.3048)
			(stroke
				(width 0.1)
				(type default)
			)
			(layer "B.Fab")
		)
		(pad "1" smd circle
			(at 0.40005 0)
			(size 0 0)
			(layers "B.Cu" "B.Mask" "B.Paste")
			(net "P3V3_AUX")
		)
		(pad "2" smd circle
			(at -0.40005 0)
			(size 0 0)
			(layers "B.Cu" "B.Mask" "B.Paste")
			(net "GND")
		)
	)
	(footprint ""
		(layer "B.Cu")
		(at 128.86944 -36.751768 90)
		(property "Reference" "R4274"
			(at 0 0 90)
			(layer "B.SilkS")
			(hide yes)
			(effects
				(font
					(size 1.27 1.27)
				)
				(justify mirror)
			)
		)
		(property "Value" ""
			(at 0 0 90)
			(layer "B.Fab")
			(effects
				(font
					(size 1.27 1.27)
				)
				(justify mirror)
			)
		)
		(duplicate_pad_numbers_are_jumpers no)
		(fp_line
			(start 0.7874 -0.4064)
			(end -0.7874 -0.4064)
			(stroke
				(width 0.1524)
				(type default)
			)
			(layer "B.SilkS")
		)
		(fp_line
			(start -0.7874 -0.4064)
			(end -0.7874 0.4064)
			(stroke
				(width 0.1524)
				(type default)
			)
			(layer "B.SilkS")
		)
		(fp_line
			(start 0.7874 0.4064)
			(end 0.7874 -0.4064)
			(stroke
				(width 0.1524)
				(type default)
			)
			(layer "B.SilkS")
		)
		(fp_line
			(start -0.7874 0.4064)
			(end 0.7874 0.4064)
			(stroke
				(width 0.1524)
				(type default)
			)
			(layer "B.SilkS")
		)
		(fp_line
			(start 0.67945 -0.305054)
			(end 0.12065 -0.305054)
			(stroke
				(width 0.1)
				(type default)
			)
			(layer "B.Fab")
		)
		(fp_line
			(start 0.12065 -0.305054)
			(end 0.12065 -0.2794)
			(stroke
				(width 0.1)
				(type default)
			)
			(layer "B.Fab")
		)
		(fp_line
			(start -0.12065 -0.3048)
			(end -0.67945 -0.3048)
			(stroke
				(width 0.1)
				(type default)
			)
			(layer "B.Fab")
		)
		(fp_line
			(start -0.67945 -0.3048)
			(end -0.67945 0.3048)
			(stroke
				(width 0.1)
				(type default)
			)
			(layer "B.Fab")
		)
		(fp_line
			(start 0.12065 -0.2794)
			(end -0.12065 -0.2794)
			(stroke
				(width 0.1)
				(type default)
			)
			(layer "B.Fab")
		)
		(fp_line
			(start -0.12065 -0.2794)
			(end -0.12065 -0.3048)
			(stroke
				(width 0.1)
				(type default)
			)
			(layer "B.Fab")
		)
		(fp_line
			(start 0.12065 0.2794)
			(end 0.12065 0.3048)
			(stroke
				(width 0.1)
				(type default)
			)
			(layer "B.Fab")
		)
		(fp_line
			(start -0.120396 0.2794)
			(end 0.12065 0.2794)
			(stroke
				(width 0.1)
				(type default)
			)
			(layer "B.Fab")
		)
		(fp_line
			(start 0.67945 0.3048)
			(end 0.67945 -0.305054)
			(stroke
				(width 0.1)
				(type default)
			)
			(layer "B.Fab")
		)
		(fp_line
			(start 0.12065 0.3048)
			(end 0.67945 0.3048)
			(stroke
				(width 0.1)
				(type default)
			)
			(layer "B.Fab")
		)
		(fp_line
			(start -0.120396 0.3048)
			(end -0.120396 0.2794)
			(stroke
				(width 0.1)
				(type default)
			)
			(layer "B.Fab")
		)
		(fp_line
			(start -0.67945 0.3048)
			(end -0.120396 0.3048)
			(stroke
				(width 0.1)
				(type default)
			)
			(layer "B.Fab")
		)
		(pad "1" smd circle
			(at 0.40005 0 270)
			(size 0 0)
			(layers "B.Cu" "B.Mask" "B.Paste")
			(net "FM_USB3_1_FGB")
		)
		(pad "2" smd circle
			(at -0.40005 0 270)
			(size 0 0)
			(layers "B.Cu" "B.Mask" "B.Paste")
			(net "GND")
		)
	)
	(footprint ""
		(layer "B.Cu")
		(at 174.393352 -22.564598 -90)
		(property "Reference" "R1764"
			(at 0 0 90)
			(layer "B.SilkS")
			(hide yes)
			(effects
				(font
					(size 1.27 1.27)
				)
				(justify mirror)
			)
		)
		(property "Value" ""
			(at 0 0 90)
			(layer "B.Fab")
			(effects
				(font
					(size 1.27 1.27)
				)
				(justify mirror)
			)
		)
		(duplicate_pad_numbers_are_jumpers no)
		(fp_line
			(start -0.7874 0.4064)
			(end 0.7874 0.4064)
			(stroke
				(width 0.1524)
				(type default)
			)
			(layer "B.SilkS")
		)
		(fp_line
			(start 0.7874 0.4064)
			(end 0.7874 -0.4064)
			(stroke
				(width 0.1524)
				(type default)
			)
			(layer "B.SilkS")
		)
		(fp_line
			(start -0.7874 -0.4064)
			(end -0.7874 0.4064)
			(stroke
				(width 0.1524)
				(type default)
			)
			(layer "B.SilkS")
		)
		(fp_line
			(start 0.7874 -0.4064)
			(end -0.7874 -0.4064)
			(stroke
				(width 0.1524)
				(type default)
			)
			(layer "B.SilkS")
		)
		(fp_line
			(start -0.67945 0.3048)
			(end -0.120396 0.3048)
			(stroke
				(width 0.1)
				(type default)
			)
			(layer "B.Fab")
		)
		(fp_line
			(start -0.120396 0.3048)
			(end -0.120396 0.2794)
			(stroke
				(width 0.1)
				(type default)
			)
			(layer "B.Fab")
		)
		(fp_line
			(start 0.12065 0.3048)
			(end 0.67945 0.3048)
			(stroke
				(width 0.1)
				(type default)
			)
			(layer "B.Fab")
		)
		(fp_line
			(start 0.67945 0.3048)
			(end 0.67945 -0.305054)
			(stroke
				(width 0.1)
				(type default)
			)
			(layer "B.Fab")
		)
		(fp_line
			(start -0.120396 0.2794)
			(end 0.12065 0.2794)
			(stroke
				(width 0.1)
				(type default)
			)
			(layer "B.Fab")
		)
		(fp_line
			(start 0.12065 0.2794)
			(end 0.12065 0.3048)
			(stroke
				(width 0.1)
				(type default)
			)
			(layer "B.Fab")
		)
		(fp_line
			(start -0.12065 -0.2794)
			(end -0.12065 -0.3048)
			(stroke
				(width 0.1)
				(type default)
			)
			(layer "B.Fab")
		)
		(fp_line
			(start 0.12065 -0.2794)
			(end -0.12065 -0.2794)
			(stroke
				(width 0.1)
				(type default)
			)
			(layer "B.Fab")
		)
		(fp_line
			(start -0.67945 -0.3048)
			(end -0.67945 0.3048)
			(stroke
				(width 0.1)
				(type default)
			)
			(layer "B.Fab")
		)
		(fp_line
			(start -0.12065 -0.3048)
			(end -0.67945 -0.3048)
			(stroke
				(width 0.1)
				(type default)
			)
			(layer "B.Fab")
		)
		(fp_line
			(start 0.12065 -0.305054)
			(end 0.12065 -0.2794)
			(stroke
				(width 0.1)
				(type default)
			)
			(layer "B.Fab")
		)
		(fp_line
			(start 0.67945 -0.305054)
			(end 0.12065 -0.305054)
			(stroke
				(width 0.1)
				(type default)
			)
			(layer "B.Fab")
		)
		(pad "1" smd circle
			(at 0.40005 0 90)
			(size 0 0)
			(layers "B.Cu" "B.Mask" "B.Paste")
			(net "FM_LPC_ESPI_SEL")
		)
		(pad "2" smd circle
			(at -0.40005 0 90)
			(size 0 0)
			(layers "B.Cu" "B.Mask" "B.Paste")
			(net "GND")
		)
	)
	(footprint ""
		(layer "B.Cu")
		(at 188.309758 -13.60043 -90)
		(property "Reference" "R595"
			(at 0 0 90)
			(layer "B.SilkS")
			(hide yes)
			(effects
				(font
					(size 1.27 1.27)
				)
				(justify mirror)
			)
		)
		(property "Value" ""
			(at 0 0 90)
			(layer "B.Fab")
			(effects
				(font
					(size 1.27 1.27)
				)
				(justify mirror)
			)
		)
		(duplicate_pad_numbers_are_jumpers no)
		(fp_line
			(start -0.7874 0.4064)
			(end 0.7874 0.4064)
			(stroke
				(width 0.1524)
				(type default)
			)
			(layer "B.SilkS")
		)
		(fp_line
			(start 0.7874 0.4064)
			(end 0.7874 -0.4064)
			(stroke
				(width 0.1524)
				(type default)
			)
			(layer "B.SilkS")
		)
		(fp_line
			(start -0.7874 -0.4064)
			(end -0.7874 0.4064)
			(stroke
				(width 0.1524)
				(type default)
			)
			(layer "B.SilkS")
		)
		(fp_line
			(start 0.7874 -0.4064)
			(end -0.7874 -0.4064)
			(stroke
				(width 0.1524)
				(type default)
			)
			(layer "B.SilkS")
		)
		(fp_line
			(start -0.67945 0.3048)
			(end -0.120396 0.3048)
			(stroke
				(width 0.1)
				(type default)
			)
			(layer "B.Fab")
		)
		(fp_line
			(start -0.120396 0.3048)
			(end -0.120396 0.2794)
			(stroke
				(width 0.1)
				(type default)
			)
			(layer "B.Fab")
		)
		(fp_line
			(start 0.12065 0.3048)
			(end 0.67945 0.3048)
			(stroke
				(width 0.1)
				(type default)
			)
			(layer "B.Fab")
		)
		(fp_line
			(start 0.67945 0.3048)
			(end 0.67945 -0.305054)
			(stroke
				(width 0.1)
				(type default)
			)
			(layer "B.Fab")
		)
		(fp_line
			(start -0.120396 0.2794)
			(end 0.12065 0.2794)
			(stroke
				(width 0.1)
				(type default)
			)
			(layer "B.Fab")
		)
		(fp_line
			(start 0.12065 0.2794)
			(end 0.12065 0.3048)
			(stroke
				(width 0.1)
				(type default)
			)
			(layer "B.Fab")
		)
		(fp_line
			(start -0.12065 -0.2794)
			(end -0.12065 -0.3048)
			(stroke
				(width 0.1)
				(type default)
			)
			(layer "B.Fab")
		)
		(fp_line
			(start 0.12065 -0.2794)
			(end -0.12065 -0.2794)
			(stroke
				(width 0.1)
				(type default)
			)
			(layer "B.Fab")
		)
		(fp_line
			(start -0.67945 -0.3048)
			(end -0.67945 0.3048)
			(stroke
				(width 0.1)
				(type default)
			)
			(layer "B.Fab")
		)
		(fp_line
			(start -0.12065 -0.3048)
			(end -0.67945 -0.3048)
			(stroke
				(width 0.1)
				(type default)
			)
			(layer "B.Fab")
		)
		(fp_line
			(start 0.12065 -0.305054)
			(end 0.12065 -0.2794)
			(stroke
				(width 0.1)
				(type default)
			)
			(layer "B.Fab")
		)
		(fp_line
			(start 0.67945 -0.305054)
			(end 0.12065 -0.305054)
			(stroke
				(width 0.1)
				(type default)
			)
			(layer "B.Fab")
		)
		(pad "1" smd circle
			(at 0.40005 0 90)
			(size 0 0)
			(layers "B.Cu" "B.Mask" "B.Paste")
			(net "I3C_SPD_DDREFGH_CPU0_BMC_R_SCL")
		)
		(pad "2" smd circle
			(at -0.40005 0 90)
			(size 0 0)
			(layers "B.Cu" "B.Mask" "B.Paste")
			(net "I3C_SPD_DDREFGH_CPU0_BMC_SCL")
		)
	)
	(footprint ""
		(layer "B.Cu")
		(at 429.105568 -362.107226 90)
		(property "Reference" "PC1179_P0_3"
			(at 0 0 90)
			(layer "B.SilkS")
			(hide yes)
			(effects
				(font
					(size 1.27 1.27)
				)
				(justify mirror)
			)
		)
		(property "Value" ""
			(at 0 0 90)
			(layer "B.Fab")
			(effects
				(font
					(size 1.27 1.27)
				)
				(justify mirror)
			)
		)
		(duplicate_pad_numbers_are_jumpers no)
		(fp_line
			(start 1.524 -0.762)
			(end -1.524 -0.762)
			(stroke
				(width 0.1524)
				(type default)
			)
			(layer "B.SilkS")
		)
		(fp_line
			(start -1.524 -0.762)
			(end -1.524 0.762)
			(stroke
				(width 0.1524)
				(type default)
			)
			(layer "B.SilkS")
		)
		(fp_line
			(start 1.524 0.762)
			(end 1.524 -0.762)
			(stroke
				(width 0.1524)
				(type default)
			)
			(layer "B.SilkS")
		)
		(fp_line
			(start -1.524 0.762)
			(end 1.524 0.762)
			(stroke
				(width 0.1524)
				(type default)
			)
			(layer "B.SilkS")
		)
		(fp_line
			(start 1.1049 -0.724916)
			(end 1.1049 0.724916)
			(stroke
				(width 0.1)
				(type default)
			)
			(layer "B.Fab")
		)
		(fp_line
			(start -1.1049 -0.724916)
			(end 1.1049 -0.724916)
			(stroke
				(width 0.1)
				(type default)
			)
			(layer "B.Fab")
		)
		(fp_line
			(start 1.1049 0.724916)
			(end -1.1049 0.724916)
			(stroke
				(width 0.1)
				(type default)
			)
			(layer "B.Fab")
		)
		(fp_line
			(start -1.1049 0.724916)
			(end -1.1049 -0.724916)
			(stroke
				(width 0.1)
				(type default)
			)
			(layer "B.Fab")
		)
		(pad "1" smd rect
			(at 0.889 0 90)
			(size 1.016 1.27)
			(layers "B.Cu" "B.Mask" "B.Paste")
			(net "SW_P12V_PVCCFA_EHV_FIVRA_CPU0_R")
		)
		(pad "2" smd rect
			(at -0.889 0 90)
			(size 1.016 1.27)
			(layers "B.Cu" "B.Mask" "B.Paste")
			(net "GND")
		)
	)
	(footprint ""
		(layer "B.Cu")
		(at 176.3776 -13.762228 90)
		(property "Reference" "R2424"
			(at 0 0 90)
			(layer "B.SilkS")
			(hide yes)
			(effects
				(font
					(size 1.27 1.27)
				)
				(justify mirror)
			)
		)
		(property "Value" ""
			(at 0 0 90)
			(layer "B.Fab")
			(effects
				(font
					(size 1.27 1.27)
				)
				(justify mirror)
			)
		)
		(duplicate_pad_numbers_are_jumpers no)
		(fp_line
			(start 0.7874 -0.4064)
			(end -0.7874 -0.4064)
			(stroke
				(width 0.1524)
				(type default)
			)
			(layer "B.SilkS")
		)
		(fp_line
			(start -0.7874 -0.4064)
			(end -0.7874 0.4064)
			(stroke
				(width 0.1524)
				(type default)
			)
			(layer "B.SilkS")
		)
		(fp_line
			(start 0.7874 0.4064)
			(end 0.7874 -0.4064)
			(stroke
				(width 0.1524)
				(type default)
			)
			(layer "B.SilkS")
		)
		(fp_line
			(start -0.7874 0.4064)
			(end 0.7874 0.4064)
			(stroke
				(width 0.1524)
				(type default)
			)
			(layer "B.SilkS")
		)
		(fp_line
			(start 0.67945 -0.305054)
			(end 0.12065 -0.305054)
			(stroke
				(width 0.1)
				(type default)
			)
			(layer "B.Fab")
		)
		(fp_line
			(start 0.12065 -0.305054)
			(end 0.12065 -0.2794)
			(stroke
				(width 0.1)
				(type default)
			)
			(layer "B.Fab")
		)
		(fp_line
			(start -0.12065 -0.3048)
			(end -0.67945 -0.3048)
			(stroke
				(width 0.1)
				(type default)
			)
			(layer "B.Fab")
		)
		(fp_line
			(start -0.67945 -0.3048)
			(end -0.67945 0.3048)
			(stroke
				(width 0.1)
				(type default)
			)
			(layer "B.Fab")
		)
		(fp_line
			(start 0.12065 -0.2794)
			(end -0.12065 -0.2794)
			(stroke
				(width 0.1)
				(type default)
			)
			(layer "B.Fab")
		)
		(fp_line
			(start -0.12065 -0.2794)
			(end -0.12065 -0.3048)
			(stroke
				(width 0.1)
				(type default)
			)
			(layer "B.Fab")
		)
		(fp_line
			(start 0.12065 0.2794)
			(end 0.12065 0.3048)
			(stroke
				(width 0.1)
				(type default)
			)
			(layer "B.Fab")
		)
		(fp_line
			(start -0.120396 0.2794)
			(end 0.12065 0.2794)
			(stroke
				(width 0.1)
				(type default)
			)
			(layer "B.Fab")
		)
		(fp_line
			(start 0.67945 0.3048)
			(end 0.67945 -0.305054)
			(stroke
				(width 0.1)
				(type default)
			)
			(layer "B.Fab")
		)
		(fp_line
			(start 0.12065 0.3048)
			(end 0.67945 0.3048)
			(stroke
				(width 0.1)
				(type default)
			)
			(layer "B.Fab")
		)
		(fp_line
			(start -0.120396 0.3048)
			(end -0.120396 0.2794)
			(stroke
				(width 0.1)
				(type default)
			)
			(layer "B.Fab")
		)
		(fp_line
			(start -0.67945 0.3048)
			(end -0.120396 0.3048)
			(stroke
				(width 0.1)
				(type default)
			)
			(layer "B.Fab")
		)
		(pad "1" smd circle
			(at 0.40005 0 270)
			(size 0 0)
			(layers "B.Cu" "B.Mask" "B.Paste")
			(net "SMB_SML1_PMBUS_3V3AUX_PCH_SDA")
		)
		(pad "2" smd circle
			(at -0.40005 0 270)
			(size 0 0)
			(layers "B.Cu" "B.Mask" "B.Paste")
			(net "SMB_SML1_PMBUS_3V3AUX_PCH_SDA_R")
		)
	)
	(footprint ""
		(layer "B.Cu")
		(at 477.30537 -153.123392 90)
		(property "Reference" "X38"
			(at -2.374392 -2.22504 270)
			(unlocked yes)
			(layer "B.SilkS")
			(effects
				(font
					(size 0.7874 0.5842)
					(thickness 0.1524)
				)
				(justify left mirror)
			)
		)
		(property "Value" ""
			(at 0 0 90)
			(layer "B.Fab")
			(effects
				(font
					(size 1.27 1.27)
				)
				(justify mirror)
			)
		)
		(property "Device Type" "TP_TDR_4P_FTS_TH-TP_TDR_4P_DIPA"
			(at -1.30175 1.27 0)
			(unlocked yes)
			(layer "B.Fab")
			(hide yes)
			(effects
				(font
					(size 0.635 0.4064)
					(thickness 0.1524)
				)
				(justify mirror)
			)
		)
		(property "User Part Number" "N_A"
			(at -1.30175 1.27 0)
			(unlocked yes)
			(layer "Cmts.User")
			(hide yes)
			(effects
				(font
					(size 0.635 0.4064)
					(thickness 0.1524)
				)
				(justify mirror)
			)
		)
		(duplicate_pad_numbers_are_jumpers no)
		(fp_line
			(start 0 -1.27)
			(end 0 -0.635)
			(stroke
				(width 0.1524)
				(type default)
			)
			(layer "B.SilkS")
		)
		(fp_line
			(start -2.54 -1.27)
			(end 0 -1.27)
			(stroke
				(width 0.1524)
				(type default)
			)
			(layer "B.SilkS")
		)
		(fp_line
			(start -2.54 -1.1303)
			(end -2.54 -1.27)
			(stroke
				(width 0.1524)
				(type default)
			)
			(layer "B.SilkS")
		)
		(fp_line
			(start 0 0.635)
			(end 0 1.905)
			(stroke
				(width 0.1524)
				(type default)
			)
			(layer "B.SilkS")
		)
		(fp_line
			(start -2.54 1.4097)
			(end -2.54 1.1303)
			(stroke
				(width 0.1524)
				(type default)
			)
			(layer "B.SilkS")
		)
		(fp_line
			(start 0 3.175)
			(end 0 3.81)
			(stroke
				(width 0.1524)
				(type default)
			)
			(layer "B.SilkS")
		)
		(fp_line
			(start 0 3.81)
			(end -2.54 3.81)
			(stroke
				(width 0.1524)
				(type default)
			)
			(layer "B.SilkS")
		)
		(fp_line
			(start -2.54 3.81)
			(end -2.54 3.6703)
			(stroke
				(width 0.1524)
				(type default)
			)
			(layer "B.SilkS")
		)
		(fp_poly
			(pts
				(xy 0.761746 0) (xy 2.285746 -0.762) (xy 2.285746 0.762)
			)
			(stroke
				(width 0)
				(type default)
			)
			(fill yes)
			(layer "B.SilkS")
		)
		(fp_line
			(start 0 -1.27)
			(end 0 3.81)
			(stroke
				(width 0.1)
				(type default)
			)
			(layer "B.Fab")
		)
		(fp_line
			(start -2.54 -1.27)
			(end 0 -1.27)
			(stroke
				(width 0.1)
				(type default)
			)
			(layer "B.Fab")
		)
		(fp_line
			(start 0 3.81)
			(end -2.54 3.81)
			(stroke
				(width 0.1)
				(type default)
			)
			(layer "B.Fab")
		)
		(fp_line
			(start -2.54 3.81)
			(end -2.54 -1.27)
			(stroke
				(width 0.1)
				(type default)
			)
			(layer "B.Fab")
		)
		(fp_poly
			(pts
				(xy 0.761746 0) (xy 2.285746 -0.762) (xy 2.285746 0.762)
			)
			(stroke
				(width 0)
				(type default)
			)
			(fill yes)
			(layer "B.Fab")
		)
		(pad "1" thru_hole circle
			(at 0 0 270)
			(size 1.0033 1.0033)
			(drill 0.249936)
			(layers "*.Cu" "*.Mask")
			(remove_unused_layers no)
			(net "TDR_DIFF_85_NECK_IN5_DP")
			(clearance 0.10795)
			(padstack
				(mode front_inner_back)
				(layer "Inner"
					(shape circle)
					(size 0.8001 0.8001)
					(clearance 0.1524)
				)
				(layer "B.Cu"
					(shape circle)
					(size 1.0033 1.0033)
					(thermal_gap 0.10795)
					(clearance 0.10795)
				)
			)
		)
		(pad "2" thru_hole circle
			(at -2.54 0 270)
			(size 1.9939 1.9939)
			(drill 0.249936)
			(layers "*.Cu" "*.Mask")
			(remove_unused_layers no)
			(net "T1_GND")
			(clearance 0.10795)
			(padstack
				(mode front_inner_back)
				(layer "Inner"
					(shape circle)
					(size 0.8001 0.8001)
					(clearance 0.1524)
				)
				(layer "B.Cu"
					(shape circle)
					(size 1.9939 1.9939)
					(thermal_gap 0.10795)
					(clearance 0.10795)
				)
			)
		)
		(pad "3" thru_hole circle
			(at -2.54 2.54 270)
			(size 1.9939 1.9939)
			(drill 0.249936)
			(layers "*.Cu" "*.Mask")
			(remove_unused_layers no)
			(net "T1_GND")
			(clearance 0.10795)
			(padstack
				(mode front_inner_back)
				(layer "Inner"
					(shape circle)
					(size 0.8001 0.8001)
					(clearance 0.1524)
				)
				(layer "B.Cu"
					(shape circle)
					(size 1.9939 1.9939)
					(thermal_gap 0.10795)
					(clearance 0.10795)
				)
			)
		)
		(pad "4" thru_hole circle
			(at 0 2.54 270)
			(size 1.0033 1.0033)
			(drill 0.249936)
			(layers "*.Cu" "*.Mask")
			(remove_unused_layers no)
			(net "TDR_DIFF_85_NECK_IN5_DN")
			(clearance 0.10795)
			(padstack
				(mode front_inner_back)
				(layer "Inner"
					(shape circle)
					(size 0.8001 0.8001)
					(clearance 0.1524)
				)
				(layer "B.Cu"
					(shape circle)
					(size 1.0033 1.0033)
					(thermal_gap 0.10795)
					(clearance 0.10795)
				)
			)
		)
	)
	(footprint ""
		(layer "B.Cu")
		(at 190.037212 -103.230426 90)
		(property "Reference" "R132"
			(at 0 0 90)
			(layer "B.SilkS")
			(hide yes)
			(effects
				(font
					(size 1.27 1.27)
				)
				(justify mirror)
			)
		)
		(property "Value" ""
			(at 0 0 90)
			(layer "B.Fab")
			(effects
				(font
					(size 1.27 1.27)
				)
				(justify mirror)
			)
		)
		(duplicate_pad_numbers_are_jumpers no)
		(fp_line
			(start 0.7874 -0.4064)
			(end -0.7874 -0.4064)
			(stroke
				(width 0.1524)
				(type default)
			)
			(layer "B.SilkS")
		)
		(fp_line
			(start -0.7874 -0.4064)
			(end -0.7874 0.4064)
			(stroke
				(width 0.1524)
				(type default)
			)
			(layer "B.SilkS")
		)
		(fp_line
			(start 0.7874 0.4064)
			(end 0.7874 -0.4064)
			(stroke
				(width 0.1524)
				(type default)
			)
			(layer "B.SilkS")
		)
		(fp_line
			(start -0.7874 0.4064)
			(end 0.7874 0.4064)
			(stroke
				(width 0.1524)
				(type default)
			)
			(layer "B.SilkS")
		)
		(fp_line
			(start 0.67945 -0.305054)
			(end 0.12065 -0.305054)
			(stroke
				(width 0.1)
				(type default)
			)
			(layer "B.Fab")
		)
		(fp_line
			(start 0.12065 -0.305054)
			(end 0.12065 -0.2794)
			(stroke
				(width 0.1)
				(type default)
			)
			(layer "B.Fab")
		)
		(fp_line
			(start -0.12065 -0.3048)
			(end -0.67945 -0.3048)
			(stroke
				(width 0.1)
				(type default)
			)
			(layer "B.Fab")
		)
		(fp_line
			(start -0.67945 -0.3048)
			(end -0.67945 0.3048)
			(stroke
				(width 0.1)
				(type default)
			)
			(layer "B.Fab")
		)
		(fp_line
			(start 0.12065 -0.2794)
			(end -0.12065 -0.2794)
			(stroke
				(width 0.1)
				(type default)
			)
			(layer "B.Fab")
		)
		(fp_line
			(start -0.12065 -0.2794)
			(end -0.12065 -0.3048)
			(stroke
				(width 0.1)
				(type default)
			)
			(layer "B.Fab")
		)
		(fp_line
			(start 0.12065 0.2794)
			(end 0.12065 0.3048)
			(stroke
				(width 0.1)
				(type default)
			)
			(layer "B.Fab")
		)
		(fp_line
			(start -0.120396 0.2794)
			(end 0.12065 0.2794)
			(stroke
				(width 0.1)
				(type default)
			)
			(layer "B.Fab")
		)
		(fp_line
			(start 0.67945 0.3048)
			(end 0.67945 -0.305054)
			(stroke
				(width 0.1)
				(type default)
			)
			(layer "B.Fab")
		)
		(fp_line
			(start 0.12065 0.3048)
			(end 0.67945 0.3048)
			(stroke
				(width 0.1)
				(type default)
			)
			(layer "B.Fab")
		)
		(fp_line
			(start -0.120396 0.3048)
			(end -0.120396 0.2794)
			(stroke
				(width 0.1)
				(type default)
			)
			(layer "B.Fab")
		)
		(fp_line
			(start -0.67945 0.3048)
			(end -0.120396 0.3048)
			(stroke
				(width 0.1)
				(type default)
			)
			(layer "B.Fab")
		)
		(pad "1" smd circle
			(at 0.40005 0 270)
			(size 0 0)
			(layers "B.Cu" "B.Mask" "B.Paste")
			(net "RST_CPU1_LVC1_R_N")
		)
		(pad "2" smd circle
			(at -0.40005 0 270)
			(size 0 0)
			(layers "B.Cu" "B.Mask" "B.Paste")
			(net "RST_CPU1_BUF_R_N")
		)
	)
	(footprint ""
		(layer "B.Cu")
		(at 119.95912 -244.82044 -90)
		(property "Reference" "C349"
			(at 0 0 90)
			(layer "B.SilkS")
			(hide yes)
			(effects
				(font
					(size 1.27 1.27)
				)
				(justify mirror)
			)
		)
		(property "Value" ""
			(at 0 0 90)
			(layer "B.Fab")
			(effects
				(font
					(size 1.27 1.27)
				)
				(justify mirror)
			)
		)
		(duplicate_pad_numbers_are_jumpers no)
		(fp_line
			(start -1.524 0.762)
			(end 1.524 0.762)
			(stroke
				(width 0.1524)
				(type default)
			)
			(layer "B.SilkS")
		)
		(fp_line
			(start 1.524 0.762)
			(end 1.524 -0.762)
			(stroke
				(width 0.1524)
				(type default)
			)
			(layer "B.SilkS")
		)
		(fp_line
			(start -1.524 -0.762)
			(end -1.524 0.762)
			(stroke
				(width 0.1524)
				(type default)
			)
			(layer "B.SilkS")
		)
		(fp_line
			(start 1.524 -0.762)
			(end -1.524 -0.762)
			(stroke
				(width 0.1524)
				(type default)
			)
			(layer "B.SilkS")
		)
		(fp_line
			(start -1.1049 0.724916)
			(end -1.1049 -0.724916)
			(stroke
				(width 0.1)
				(type default)
			)
			(layer "B.Fab")
		)
		(fp_line
			(start 1.1049 0.724916)
			(end -1.1049 0.724916)
			(stroke
				(width 0.1)
				(type default)
			)
			(layer "B.Fab")
		)
		(fp_line
			(start -1.1049 -0.724916)
			(end 1.1049 -0.724916)
			(stroke
				(width 0.1)
				(type default)
			)
			(layer "B.Fab")
		)
		(fp_line
			(start 1.1049 -0.724916)
			(end 1.1049 0.724916)
			(stroke
				(width 0.1)
				(type default)
			)
			(layer "B.Fab")
		)
		(pad "1" smd rect
			(at 0.889 0 270)
			(size 1.016 1.27)
			(layers "B.Cu" "B.Mask" "B.Paste")
			(net "PVCCIN_CPU1")
		)
		(pad "2" smd rect
			(at -0.889 0 270)
			(size 1.016 1.27)
			(layers "B.Cu" "B.Mask" "B.Paste")
			(net "GND")
		)
	)
	(footprint ""
		(layer "B.Cu")
		(at 122.992134 -324.792086 -90)
		(property "Reference" "PC543_P1_4"
			(at 0 0 90)
			(layer "B.SilkS")
			(hide yes)
			(effects
				(font
					(size 1.27 1.27)
				)
				(justify mirror)
			)
		)
		(property "Value" ""
			(at 0 0 90)
			(layer "B.Fab")
			(effects
				(font
					(size 1.27 1.27)
				)
				(justify mirror)
			)
		)
		(duplicate_pad_numbers_are_jumpers no)
		(fp_line
			(start -1.524 0.762)
			(end 1.524 0.762)
			(stroke
				(width 0.1524)
				(type default)
			)
			(layer "B.SilkS")
		)
		(fp_line
			(start 1.524 0.762)
			(end 1.524 -0.762)
			(stroke
				(width 0.1524)
				(type default)
			)
			(layer "B.SilkS")
		)
		(fp_line
			(start -1.524 -0.762)
			(end -1.524 0.762)
			(stroke
				(width 0.1524)
				(type default)
			)
			(layer "B.SilkS")
		)
		(fp_line
			(start 1.524 -0.762)
			(end -1.524 -0.762)
			(stroke
				(width 0.1524)
				(type default)
			)
			(layer "B.SilkS")
		)
		(fp_line
			(start -1.1049 0.724916)
			(end -1.1049 -0.724916)
			(stroke
				(width 0.1)
				(type default)
			)
			(layer "B.Fab")
		)
		(fp_line
			(start 1.1049 0.724916)
			(end -1.1049 0.724916)
			(stroke
				(width 0.1)
				(type default)
			)
			(layer "B.Fab")
		)
		(fp_line
			(start -1.1049 -0.724916)
			(end 1.1049 -0.724916)
			(stroke
				(width 0.1)
				(type default)
			)
			(layer "B.Fab")
		)
		(fp_line
			(start 1.1049 -0.724916)
			(end 1.1049 0.724916)
			(stroke
				(width 0.1)
				(type default)
			)
			(layer "B.Fab")
		)
		(pad "1" smd rect
			(at 0.889 0 270)
			(size 1.016 1.27)
			(layers "B.Cu" "B.Mask" "B.Paste")
			(net "PVCCIN_CPU1")
		)
		(pad "2" smd rect
			(at -0.889 0 270)
			(size 1.016 1.27)
			(layers "B.Cu" "B.Mask" "B.Paste")
			(net "GND")
		)
	)
	(footprint ""
		(layer "B.Cu")
		(at 250.65482 5.461)
		(property "Reference" "J86"
			(at 4.20751 1.143 270)
			(unlocked yes)
			(layer "B.SilkS")
			(effects
				(font
					(size 0.7874 0.5842)
					(thickness 0.1524)
				)
				(justify left mirror)
			)
		)
		(property "Value" ""
			(at 0 0 0)
			(layer "B.Fab")
			(effects
				(font
					(size 1.27 1.27)
				)
				(justify mirror)
			)
		)
		(duplicate_pad_numbers_are_jumpers no)
		(fp_line
			(start -1.2192 -2.1082)
			(end -1.2192 2.1082)
			(stroke
				(width 0.1524)
				(type default)
			)
			(layer "B.SilkS")
		)
		(fp_line
			(start -1.2192 2.1082)
			(end 1.2192 2.1082)
			(stroke
				(width 0.1524)
				(type default)
			)
			(layer "B.SilkS")
		)
		(fp_line
			(start 1.2192 -2.1082)
			(end -1.2192 -2.1082)
			(stroke
				(width 0.1524)
				(type default)
			)
			(layer "B.SilkS")
		)
		(fp_line
			(start 1.2192 2.1082)
			(end 1.2192 -2.1082)
			(stroke
				(width 0.1524)
				(type default)
			)
			(layer "B.SilkS")
		)
		(pad "" np_thru_hole circle
			(at -3.4671 -1.27 270)
			(size 1.0414 1.0414)
			(drill 1.0414)
			(layers "*.Cu" "*.Mask")
			(clearance 0.381)
			(thermal_gap 0.381)
		)
		(pad "" np_thru_hole circle
			(at -3.4671 1.27 270)
			(size 1.0414 1.0414)
			(drill 1.0414)
			(layers "*.Cu" "*.Mask")
			(clearance 0.381)
			(thermal_gap 0.381)
		)
		(pad "" np_thru_hole circle
			(at 2.8829 -1.27 270)
			(size 1.0414 1.0414)
			(drill 1.0414)
			(layers "*.Cu" "*.Mask")
			(clearance 0.381)
			(thermal_gap 0.381)
		)
		(pad "" np_thru_hole circle
			(at 2.8829 1.27 270)
			(size 1.0414 1.0414)
			(drill 1.0414)
			(layers "*.Cu" "*.Mask")
			(clearance 0.381)
			(thermal_gap 0.381)
		)
		(pad "1" smd rect
			(at -0.8255 -0.249936 270)
			(size 0.3048 0.508)
			(layers "B.Cu" "B.Mask" "B.Paste")
			(net "DELTA_L_85_10INCH_IN4_DN")
		)
		(pad "2" smd rect
			(at -0.8255 0.249936 270)
			(size 0.3048 0.508)
			(layers "B.Cu" "B.Mask" "B.Paste")
			(net "DELTA_L_85_10INCH_IN4_DP")
		)
		(pad "3" smd circle
			(at 0 0 180)
			(size 0 0)
			(layers "B.Cu" "B.Mask" "B.Paste")
			(net "DELTA_L_GND_1")
		)
		(zone
			(layers "F.Cu" "B.Cu" "In1.Cu" "In2.Cu" "In3.Cu" "In4.Cu" "In5.Cu" "In6.Cu"
				"In7.Cu" "In8.Cu" "In9.Cu" "In10.Cu" "In11.Cu" "In12.Cu" "In13.Cu" "In14.Cu"
				"In15.Cu" "In16.Cu"
			)
			(hatch none 0.5)
			(connect_pads
				(clearance 0)
			)
			(min_thickness 0.25)
			(keepout
				(tracks not_allowed)
				(vias allowed)
				(pads allowed)
				(copperpour not_allowed)
				(footprints allowed)
			)
			(placement
				(enabled no)
				(sheetname "")
			)
			(fill
				(thermal_gap 0.5)
				(thermal_bridge_width 0.5)
				(island_removal_mode 0)
			)
			(polygon
				(pts
					(arc
						(start 248.11482 4.191)
						(mid 246.26062 4.191)
						(end 248.11482 4.191)
					)
				)
			)
		)
		(zone
			(layers "F.Cu" "B.Cu" "In1.Cu" "In2.Cu" "In3.Cu" "In4.Cu" "In5.Cu" "In6.Cu"
				"In7.Cu" "In8.Cu" "In9.Cu" "In10.Cu" "In11.Cu" "In12.Cu" "In13.Cu" "In14.Cu"
				"In15.Cu" "In16.Cu"
			)
			(hatch none 0.5)
			(connect_pads
				(clearance 0)
			)
			(min_thickness 0.25)
			(keepout
				(tracks not_allowed)
				(vias allowed)
				(pads allowed)
				(copperpour not_allowed)
				(footprints allowed)
			)
			(placement
				(enabled no)
				(sheetname "")
			)
			(fill
				(thermal_gap 0.5)
				(thermal_bridge_width 0.5)
				(island_removal_mode 0)
			)
			(polygon
				(pts
					(arc
						(start 248.11482 6.731)
						(mid 246.26062 6.731)
						(end 248.11482 6.731)
					)
				)
			)
		)
		(zone
			(layers "F.Cu" "B.Cu" "In1.Cu" "In2.Cu" "In3.Cu" "In4.Cu" "In5.Cu" "In6.Cu"
				"In7.Cu" "In8.Cu" "In9.Cu" "In10.Cu" "In11.Cu" "In12.Cu" "In13.Cu" "In14.Cu"
				"In15.Cu" "In16.Cu"
			)
			(hatch none 0.5)
			(connect_pads
				(clearance 0)
			)
			(min_thickness 0.25)
			(keepout
				(tracks not_allowed)
				(vias allowed)
				(pads allowed)
				(copperpour not_allowed)
				(footprints allowed)
			)
			(placement
				(enabled no)
				(sheetname "")
			)
			(fill
				(thermal_gap 0.5)
				(thermal_bridge_width 0.5)
				(island_removal_mode 0)
			)
			(polygon
				(pts
					(arc
						(start 254.46482 4.191)
						(mid 252.61062 4.191)
						(end 254.46482 4.191)
					)
				)
			)
		)
		(zone
			(layers "F.Cu" "B.Cu" "In1.Cu" "In2.Cu" "In3.Cu" "In4.Cu" "In5.Cu" "In6.Cu"
				"In7.Cu" "In8.Cu" "In9.Cu" "In10.Cu" "In11.Cu" "In12.Cu" "In13.Cu" "In14.Cu"
				"In15.Cu" "In16.Cu"
			)
			(hatch none 0.5)
			(connect_pads
				(clearance 0)
			)
			(min_thickness 0.25)
			(keepout
				(tracks not_allowed)
				(vias allowed)
				(pads allowed)
				(copperpour not_allowed)
				(footprints allowed)
			)
			(placement
				(enabled no)
				(sheetname "")
			)
			(fill
				(thermal_gap 0.5)
				(thermal_bridge_width 0.5)
				(island_removal_mode 0)
			)
			(polygon
				(pts
					(arc
						(start 254.46482 6.731)
						(mid 252.61062 6.731)
						(end 254.46482 6.731)
					)
				)
			)
		)
		(zone
			(layer "B.Cu")
			(hatch none 0.5)
			(connect_pads
				(clearance 0)
			)
			(min_thickness 0.25)
			(keepout
				(tracks not_allowed)
				(vias allowed)
				(pads allowed)
				(copperpour not_allowed)
				(footprints allowed)
			)
			(placement
				(enabled no)
				(sheetname "")
			)
			(fill
				(thermal_gap 0.5)
				(thermal_bridge_width 0.5)
				(island_removal_mode 0)
			)
			(polygon
				(pts
					(xy 249.53722 4.91236) (xy 249.53722 5.007864) (xy 250.13412 5.007864) (xy 250.13412 5.414264)
					(xy 249.53722 5.414264) (xy 249.53722 5.507736) (xy 250.13412 5.507736) (xy 250.13412 5.914136)
					(xy 249.53722 5.914136) (xy 249.53722 6.00964) (xy 250.23572 6.00964) (xy 250.23572 4.91236)
				)
			)
		)
	)
	(footprint ""
		(layer "B.Cu")
		(at 12.217146 -319.268856 180)
		(property "Reference" "R899"
			(at 0 0 0)
			(layer "B.SilkS")
			(hide yes)
			(effects
				(font
					(size 1.27 1.27)
				)
				(justify mirror)
			)
		)
		(property "Value" ""
			(at 0 0 0)
			(layer "B.Fab")
			(effects
				(font
					(size 1.27 1.27)
				)
				(justify mirror)
			)
		)
		(duplicate_pad_numbers_are_jumpers no)
		(fp_line
			(start 0.7874 0.4064)
			(end 0.7874 -0.4064)
			(stroke
				(width 0.1524)
				(type default)
			)
			(layer "B.SilkS")
		)
		(fp_line
			(start 0.7874 -0.4064)
			(end -0.7874 -0.4064)
			(stroke
				(width 0.1524)
				(type default)
			)
			(layer "B.SilkS")
		)
		(fp_line
			(start -0.7874 0.4064)
			(end 0.7874 0.4064)
			(stroke
				(width 0.1524)
				(type default)
			)
			(layer "B.SilkS")
		)
		(fp_line
			(start -0.7874 -0.4064)
			(end -0.7874 0.4064)
			(stroke
				(width 0.1524)
				(type default)
			)
			(layer "B.SilkS")
		)
		(fp_line
			(start 0.67945 0.3048)
			(end 0.67945 -0.305054)
			(stroke
				(width 0.1)
				(type default)
			)
			(layer "B.Fab")
		)
		(fp_line
			(start 0.67945 -0.305054)
			(end 0.12065 -0.305054)
			(stroke
				(width 0.1)
				(type default)
			)
			(layer "B.Fab")
		)
		(fp_line
			(start 0.12065 0.3048)
			(end 0.67945 0.3048)
			(stroke
				(width 0.1)
				(type default)
			)
			(layer "B.Fab")
		)
		(fp_line
			(start 0.12065 0.2794)
			(end 0.12065 0.3048)
			(stroke
				(width 0.1)
				(type default)
			)
			(layer "B.Fab")
		)
		(fp_line
			(start 0.12065 -0.2794)
			(end -0.12065 -0.2794)
			(stroke
				(width 0.1)
				(type default)
			)
			(layer "B.Fab")
		)
		(fp_line
			(start 0.12065 -0.305054)
			(end 0.12065 -0.2794)
			(stroke
				(width 0.1)
				(type default)
			)
			(layer "B.Fab")
		)
		(fp_line
			(start -0.120396 0.3048)
			(end -0.120396 0.2794)
			(stroke
				(width 0.1)
				(type default)
			)
			(layer "B.Fab")
		)
		(fp_line
			(start -0.120396 0.2794)
			(end 0.12065 0.2794)
			(stroke
				(width 0.1)
				(type default)
			)
			(layer "B.Fab")
		)
		(fp_line
			(start -0.12065 -0.2794)
			(end -0.12065 -0.3048)
			(stroke
				(width 0.1)
				(type default)
			)
			(layer "B.Fab")
		)
		(fp_line
			(start -0.12065 -0.3048)
			(end -0.67945 -0.3048)
			(stroke
				(width 0.1)
				(type default)
			)
			(layer "B.Fab")
		)
		(fp_line
			(start -0.67945 0.3048)
			(end -0.120396 0.3048)
			(stroke
				(width 0.1)
				(type default)
			)
			(layer "B.Fab")
		)
		(fp_line
			(start -0.67945 -0.3048)
			(end -0.67945 0.3048)
			(stroke
				(width 0.1)
				(type default)
			)
			(layer "B.Fab")
		)
		(pad "1" smd circle
			(at 0.40005 0)
			(size 0 0)
			(layers "B.Cu" "B.Mask" "B.Paste")
			(net "PWRGD_CHD_CPU1_DIMM1")
		)
		(pad "2" smd circle
			(at -0.40005 0)
			(size 0 0)
			(layers "B.Cu" "B.Mask" "B.Paste")
			(net "PWRGD_FAIL_CPU1_CD")
		)
	)
	(footprint ""
		(layer "B.Cu")
		(at 135.489442 -343.927938 -90)
		(property "Reference" "PR287"
			(at 0 0 90)
			(layer "B.SilkS")
			(hide yes)
			(effects
				(font
					(size 1.27 1.27)
				)
				(justify mirror)
			)
		)
		(property "Value" ""
			(at 0 0 90)
			(layer "B.Fab")
			(effects
				(font
					(size 1.27 1.27)
				)
				(justify mirror)
			)
		)
		(duplicate_pad_numbers_are_jumpers no)
		(fp_line
			(start -0.7874 0.4064)
			(end 0.7874 0.4064)
			(stroke
				(width 0.1524)
				(type default)
			)
			(layer "B.SilkS")
		)
		(fp_line
			(start 0.7874 0.4064)
			(end 0.7874 -0.4064)
			(stroke
				(width 0.1524)
				(type default)
			)
			(layer "B.SilkS")
		)
		(fp_line
			(start -0.7874 -0.4064)
			(end -0.7874 0.4064)
			(stroke
				(width 0.1524)
				(type default)
			)
			(layer "B.SilkS")
		)
		(fp_line
			(start 0.7874 -0.4064)
			(end -0.7874 -0.4064)
			(stroke
				(width 0.1524)
				(type default)
			)
			(layer "B.SilkS")
		)
		(fp_line
			(start -0.67945 0.3048)
			(end -0.120396 0.3048)
			(stroke
				(width 0.1)
				(type default)
			)
			(layer "B.Fab")
		)
		(fp_line
			(start -0.120396 0.3048)
			(end -0.120396 0.2794)
			(stroke
				(width 0.1)
				(type default)
			)
			(layer "B.Fab")
		)
		(fp_line
			(start 0.12065 0.3048)
			(end 0.67945 0.3048)
			(stroke
				(width 0.1)
				(type default)
			)
			(layer "B.Fab")
		)
		(fp_line
			(start 0.67945 0.3048)
			(end 0.67945 -0.305054)
			(stroke
				(width 0.1)
				(type default)
			)
			(layer "B.Fab")
		)
		(fp_line
			(start -0.120396 0.2794)
			(end 0.12065 0.2794)
			(stroke
				(width 0.1)
				(type default)
			)
			(layer "B.Fab")
		)
		(fp_line
			(start 0.12065 0.2794)
			(end 0.12065 0.3048)
			(stroke
				(width 0.1)
				(type default)
			)
			(layer "B.Fab")
		)
		(fp_line
			(start -0.12065 -0.2794)
			(end -0.12065 -0.3048)
			(stroke
				(width 0.1)
				(type default)
			)
			(layer "B.Fab")
		)
		(fp_line
			(start 0.12065 -0.2794)
			(end -0.12065 -0.2794)
			(stroke
				(width 0.1)
				(type default)
			)
			(layer "B.Fab")
		)
		(fp_line
			(start -0.67945 -0.3048)
			(end -0.67945 0.3048)
			(stroke
				(width 0.1)
				(type default)
			)
			(layer "B.Fab")
		)
		(fp_line
			(start -0.12065 -0.3048)
			(end -0.67945 -0.3048)
			(stroke
				(width 0.1)
				(type default)
			)
			(layer "B.Fab")
		)
		(fp_line
			(start 0.12065 -0.305054)
			(end 0.12065 -0.2794)
			(stroke
				(width 0.1)
				(type default)
			)
			(layer "B.Fab")
		)
		(fp_line
			(start 0.67945 -0.305054)
			(end 0.12065 -0.305054)
			(stroke
				(width 0.1)
				(type default)
			)
			(layer "B.Fab")
		)
		(pad "1" smd circle
			(at 0.40005 0 90)
			(size 0 0)
			(layers "B.Cu" "B.Mask" "B.Paste")
			(net "PVCCIN_CPU1_PVCC")
		)
		(pad "2" smd circle
			(at -0.40005 0 90)
			(size 0 0)
			(layers "B.Cu" "B.Mask" "B.Paste")
			(net "PVCCIN_CPU1_VDD8")
		)
	)
	(footprint ""
		(layer "B.Cu")
		(at 188.981588 -316.866778 90)
		(property "Reference" "R3904"
			(at 0 0 90)
			(layer "B.SilkS")
			(hide yes)
			(effects
				(font
					(size 1.27 1.27)
				)
				(justify mirror)
			)
		)
		(property "Value" ""
			(at 0 0 90)
			(layer "B.Fab")
			(effects
				(font
					(size 1.27 1.27)
				)
				(justify mirror)
			)
		)
		(duplicate_pad_numbers_are_jumpers no)
		(fp_line
			(start 0.7874 -0.4064)
			(end -0.7874 -0.4064)
			(stroke
				(width 0.1524)
				(type default)
			)
			(layer "B.SilkS")
		)
		(fp_line
			(start -0.7874 -0.4064)
			(end -0.7874 0.4064)
			(stroke
				(width 0.1524)
				(type default)
			)
			(layer "B.SilkS")
		)
		(fp_line
			(start 0.7874 0.4064)
			(end 0.7874 -0.4064)
			(stroke
				(width 0.1524)
				(type default)
			)
			(layer "B.SilkS")
		)
		(fp_line
			(start -0.7874 0.4064)
			(end 0.7874 0.4064)
			(stroke
				(width 0.1524)
				(type default)
			)
			(layer "B.SilkS")
		)
		(fp_line
			(start 0.67945 -0.305054)
			(end 0.12065 -0.305054)
			(stroke
				(width 0.1)
				(type default)
			)
			(layer "B.Fab")
		)
		(fp_line
			(start 0.12065 -0.305054)
			(end 0.12065 -0.2794)
			(stroke
				(width 0.1)
				(type default)
			)
			(layer "B.Fab")
		)
		(fp_line
			(start -0.12065 -0.3048)
			(end -0.67945 -0.3048)
			(stroke
				(width 0.1)
				(type default)
			)
			(layer "B.Fab")
		)
		(fp_line
			(start -0.67945 -0.3048)
			(end -0.67945 0.3048)
			(stroke
				(width 0.1)
				(type default)
			)
			(layer "B.Fab")
		)
		(fp_line
			(start 0.12065 -0.2794)
			(end -0.12065 -0.2794)
			(stroke
				(width 0.1)
				(type default)
			)
			(layer "B.Fab")
		)
		(fp_line
			(start -0.12065 -0.2794)
			(end -0.12065 -0.3048)
			(stroke
				(width 0.1)
				(type default)
			)
			(layer "B.Fab")
		)
		(fp_line
			(start 0.12065 0.2794)
			(end 0.12065 0.3048)
			(stroke
				(width 0.1)
				(type default)
			)
			(layer "B.Fab")
		)
		(fp_line
			(start -0.120396 0.2794)
			(end 0.12065 0.2794)
			(stroke
				(width 0.1)
				(type default)
			)
			(layer "B.Fab")
		)
		(fp_line
			(start 0.67945 0.3048)
			(end 0.67945 -0.305054)
			(stroke
				(width 0.1)
				(type default)
			)
			(layer "B.Fab")
		)
		(fp_line
			(start 0.12065 0.3048)
			(end 0.67945 0.3048)
			(stroke
				(width 0.1)
				(type default)
			)
			(layer "B.Fab")
		)
		(fp_line
			(start -0.120396 0.3048)
			(end -0.120396 0.2794)
			(stroke
				(width 0.1)
				(type default)
			)
			(layer "B.Fab")
		)
		(fp_line
			(start -0.67945 0.3048)
			(end -0.120396 0.3048)
			(stroke
				(width 0.1)
				(type default)
			)
			(layer "B.Fab")
		)
		(pad "1" smd circle
			(at 0.40005 0 270)
			(size 0 0)
			(layers "B.Cu" "B.Mask" "B.Paste")
			(net "I3C_SPD_DDREFGH_CPU1_LVC1_SCL_5")
		)
		(pad "2" smd circle
			(at -0.40005 0 270)
			(size 0 0)
			(layers "B.Cu" "B.Mask" "B.Paste")
			(net "I3C_SPD_DDREFGH_CPU1_LVC1_SCL")
		)
	)
	(footprint ""
		(layer "B.Cu")
		(at 90.410284 -184.01665 90)
		(property "Reference" "R1007"
			(at 0 0 90)
			(layer "B.SilkS")
			(hide yes)
			(effects
				(font
					(size 1.27 1.27)
				)
				(justify mirror)
			)
		)
		(property "Value" ""
			(at 0 0 90)
			(layer "B.Fab")
			(effects
				(font
					(size 1.27 1.27)
				)
				(justify mirror)
			)
		)
		(duplicate_pad_numbers_are_jumpers no)
		(fp_line
			(start 0.7874 -0.4064)
			(end -0.7874 -0.4064)
			(stroke
				(width 0.1524)
				(type default)
			)
			(layer "B.SilkS")
		)
		(fp_line
			(start -0.7874 -0.4064)
			(end -0.7874 0.4064)
			(stroke
				(width 0.1524)
				(type default)
			)
			(layer "B.SilkS")
		)
		(fp_line
			(start 0.7874 0.4064)
			(end 0.7874 -0.4064)
			(stroke
				(width 0.1524)
				(type default)
			)
			(layer "B.SilkS")
		)
		(fp_line
			(start -0.7874 0.4064)
			(end 0.7874 0.4064)
			(stroke
				(width 0.1524)
				(type default)
			)
			(layer "B.SilkS")
		)
		(fp_line
			(start 0.67945 -0.305054)
			(end 0.12065 -0.305054)
			(stroke
				(width 0.1)
				(type default)
			)
			(layer "B.Fab")
		)
		(fp_line
			(start 0.12065 -0.305054)
			(end 0.12065 -0.2794)
			(stroke
				(width 0.1)
				(type default)
			)
			(layer "B.Fab")
		)
		(fp_line
			(start -0.12065 -0.3048)
			(end -0.67945 -0.3048)
			(stroke
				(width 0.1)
				(type default)
			)
			(layer "B.Fab")
		)
		(fp_line
			(start -0.67945 -0.3048)
			(end -0.67945 0.3048)
			(stroke
				(width 0.1)
				(type default)
			)
			(layer "B.Fab")
		)
		(fp_line
			(start 0.12065 -0.2794)
			(end -0.12065 -0.2794)
			(stroke
				(width 0.1)
				(type default)
			)
			(layer "B.Fab")
		)
		(fp_line
			(start -0.12065 -0.2794)
			(end -0.12065 -0.3048)
			(stroke
				(width 0.1)
				(type default)
			)
			(layer "B.Fab")
		)
		(fp_line
			(start 0.12065 0.2794)
			(end 0.12065 0.3048)
			(stroke
				(width 0.1)
				(type default)
			)
			(layer "B.Fab")
		)
		(fp_line
			(start -0.120396 0.2794)
			(end 0.12065 0.2794)
			(stroke
				(width 0.1)
				(type default)
			)
			(layer "B.Fab")
		)
		(fp_line
			(start 0.67945 0.3048)
			(end 0.67945 -0.305054)
			(stroke
				(width 0.1)
				(type default)
			)
			(layer "B.Fab")
		)
		(fp_line
			(start 0.12065 0.3048)
			(end 0.67945 0.3048)
			(stroke
				(width 0.1)
				(type default)
			)
			(layer "B.Fab")
		)
		(fp_line
			(start -0.120396 0.3048)
			(end -0.120396 0.2794)
			(stroke
				(width 0.1)
				(type default)
			)
			(layer "B.Fab")
		)
		(fp_line
			(start -0.67945 0.3048)
			(end -0.120396 0.3048)
			(stroke
				(width 0.1)
				(type default)
			)
			(layer "B.Fab")
		)
		(pad "1" smd circle
			(at 0.40005 0 270)
			(size 0 0)
			(layers "B.Cu" "B.Mask" "B.Paste")
			(net "PVNN_TERM_CPU1")
		)
		(pad "2" smd circle
			(at -0.40005 0 270)
			(size 0 0)
			(layers "B.Cu" "B.Mask" "B.Paste")
			(net "FM_PEHPCPU1_ALERT_N")
		)
	)
	(footprint ""
		(layer "B.Cu")
		(at 156.1465 -194.55511 -90)
		(property "Reference" "R70"
			(at 0 0 90)
			(layer "B.SilkS")
			(hide yes)
			(effects
				(font
					(size 1.27 1.27)
				)
				(justify mirror)
			)
		)
		(property "Value" ""
			(at 0 0 90)
			(layer "B.Fab")
			(effects
				(font
					(size 1.27 1.27)
				)
				(justify mirror)
			)
		)
		(duplicate_pad_numbers_are_jumpers no)
		(fp_line
			(start -0.7874 0.4064)
			(end 0.7874 0.4064)
			(stroke
				(width 0.1524)
				(type default)
			)
			(layer "B.SilkS")
		)
		(fp_line
			(start 0.7874 0.4064)
			(end 0.7874 -0.4064)
			(stroke
				(width 0.1524)
				(type default)
			)
			(layer "B.SilkS")
		)
		(fp_line
			(start -0.7874 -0.4064)
			(end -0.7874 0.4064)
			(stroke
				(width 0.1524)
				(type default)
			)
			(layer "B.SilkS")
		)
		(fp_line
			(start 0.7874 -0.4064)
			(end -0.7874 -0.4064)
			(stroke
				(width 0.1524)
				(type default)
			)
			(layer "B.SilkS")
		)
		(fp_line
			(start -0.67945 0.3048)
			(end -0.120396 0.3048)
			(stroke
				(width 0.1)
				(type default)
			)
			(layer "B.Fab")
		)
		(fp_line
			(start -0.120396 0.3048)
			(end -0.120396 0.2794)
			(stroke
				(width 0.1)
				(type default)
			)
			(layer "B.Fab")
		)
		(fp_line
			(start 0.12065 0.3048)
			(end 0.67945 0.3048)
			(stroke
				(width 0.1)
				(type default)
			)
			(layer "B.Fab")
		)
		(fp_line
			(start 0.67945 0.3048)
			(end 0.67945 -0.305054)
			(stroke
				(width 0.1)
				(type default)
			)
			(layer "B.Fab")
		)
		(fp_line
			(start -0.120396 0.2794)
			(end 0.12065 0.2794)
			(stroke
				(width 0.1)
				(type default)
			)
			(layer "B.Fab")
		)
		(fp_line
			(start 0.12065 0.2794)
			(end 0.12065 0.3048)
			(stroke
				(width 0.1)
				(type default)
			)
			(layer "B.Fab")
		)
		(fp_line
			(start -0.12065 -0.2794)
			(end -0.12065 -0.3048)
			(stroke
				(width 0.1)
				(type default)
			)
			(layer "B.Fab")
		)
		(fp_line
			(start 0.12065 -0.2794)
			(end -0.12065 -0.2794)
			(stroke
				(width 0.1)
				(type default)
			)
			(layer "B.Fab")
		)
		(fp_line
			(start -0.67945 -0.3048)
			(end -0.67945 0.3048)
			(stroke
				(width 0.1)
				(type default)
			)
			(layer "B.Fab")
		)
		(fp_line
			(start -0.12065 -0.3048)
			(end -0.67945 -0.3048)
			(stroke
				(width 0.1)
				(type default)
			)
			(layer "B.Fab")
		)
		(fp_line
			(start 0.12065 -0.305054)
			(end 0.12065 -0.2794)
			(stroke
				(width 0.1)
				(type default)
			)
			(layer "B.Fab")
		)
		(fp_line
			(start 0.67945 -0.305054)
			(end 0.12065 -0.305054)
			(stroke
				(width 0.1)
				(type default)
			)
			(layer "B.Fab")
		)
		(pad "1" smd circle
			(at 0.40005 0 90)
			(size 0 0)
			(layers "B.Cu" "B.Mask" "B.Paste")
			(net "PWRGD_PLT_AUX_CPU1_LVT3")
		)
		(pad "2" smd circle
			(at -0.40005 0 90)
			(size 0 0)
			(layers "B.Cu" "B.Mask" "B.Paste")
			(net "GND")
		)
	)
	(footprint ""
		(layer "B.Cu")
		(at 296.183558 -194.26555 90)
		(property "Reference" "R175"
			(at 0 0 90)
			(layer "B.SilkS")
			(hide yes)
			(effects
				(font
					(size 1.27 1.27)
				)
				(justify mirror)
			)
		)
		(property "Value" ""
			(at 0 0 90)
			(layer "B.Fab")
			(effects
				(font
					(size 1.27 1.27)
				)
				(justify mirror)
			)
		)
		(duplicate_pad_numbers_are_jumpers no)
		(fp_line
			(start 0.7874 -0.4064)
			(end -0.7874 -0.4064)
			(stroke
				(width 0.1524)
				(type default)
			)
			(layer "B.SilkS")
		)
		(fp_line
			(start -0.7874 -0.4064)
			(end -0.7874 0.4064)
			(stroke
				(width 0.1524)
				(type default)
			)
			(layer "B.SilkS")
		)
		(fp_line
			(start 0.7874 0.4064)
			(end 0.7874 -0.4064)
			(stroke
				(width 0.1524)
				(type default)
			)
			(layer "B.SilkS")
		)
		(fp_line
			(start -0.7874 0.4064)
			(end 0.7874 0.4064)
			(stroke
				(width 0.1524)
				(type default)
			)
			(layer "B.SilkS")
		)
		(fp_line
			(start 0.67945 -0.305054)
			(end 0.12065 -0.305054)
			(stroke
				(width 0.1)
				(type default)
			)
			(layer "B.Fab")
		)
		(fp_line
			(start 0.12065 -0.305054)
			(end 0.12065 -0.2794)
			(stroke
				(width 0.1)
				(type default)
			)
			(layer "B.Fab")
		)
		(fp_line
			(start -0.12065 -0.3048)
			(end -0.67945 -0.3048)
			(stroke
				(width 0.1)
				(type default)
			)
			(layer "B.Fab")
		)
		(fp_line
			(start -0.67945 -0.3048)
			(end -0.67945 0.3048)
			(stroke
				(width 0.1)
				(type default)
			)
			(layer "B.Fab")
		)
		(fp_line
			(start 0.12065 -0.2794)
			(end -0.12065 -0.2794)
			(stroke
				(width 0.1)
				(type default)
			)
			(layer "B.Fab")
		)
		(fp_line
			(start -0.12065 -0.2794)
			(end -0.12065 -0.3048)
			(stroke
				(width 0.1)
				(type default)
			)
			(layer "B.Fab")
		)
		(fp_line
			(start 0.12065 0.2794)
			(end 0.12065 0.3048)
			(stroke
				(width 0.1)
				(type default)
			)
			(layer "B.Fab")
		)
		(fp_line
			(start -0.120396 0.2794)
			(end 0.12065 0.2794)
			(stroke
				(width 0.1)
				(type default)
			)
			(layer "B.Fab")
		)
		(fp_line
			(start 0.67945 0.3048)
			(end 0.67945 -0.305054)
			(stroke
				(width 0.1)
				(type default)
			)
			(layer "B.Fab")
		)
		(fp_line
			(start 0.12065 0.3048)
			(end 0.67945 0.3048)
			(stroke
				(width 0.1)
				(type default)
			)
			(layer "B.Fab")
		)
		(fp_line
			(start -0.120396 0.3048)
			(end -0.120396 0.2794)
			(stroke
				(width 0.1)
				(type default)
			)
			(layer "B.Fab")
		)
		(fp_line
			(start -0.67945 0.3048)
			(end -0.120396 0.3048)
			(stroke
				(width 0.1)
				(type default)
			)
			(layer "B.Fab")
		)
		(pad "1" smd circle
			(at 0.40005 0 270)
			(size 0 0)
			(layers "B.Cu" "B.Mask" "B.Paste")
			(net "PWRGD_DRAMPWRGD_CPU0_AB_LVC1_R2")
		)
		(pad "2" smd circle
			(at -0.40005 0 270)
			(size 0 0)
			(layers "B.Cu" "B.Mask" "B.Paste")
			(net "PVCCD_HV_CPU0")
		)
	)
	(footprint ""
		(layer "B.Cu")
		(at 343.050368 -30.636972)
		(property "Reference" "R1309"
			(at 0 0 0)
			(layer "B.SilkS")
			(hide yes)
			(effects
				(font
					(size 1.27 1.27)
				)
				(justify mirror)
			)
		)
		(property "Value" ""
			(at 0 0 0)
			(layer "B.Fab")
			(effects
				(font
					(size 1.27 1.27)
				)
				(justify mirror)
			)
		)
		(duplicate_pad_numbers_are_jumpers no)
		(fp_line
			(start -0.7874 -0.4064)
			(end -0.7874 0.4064)
			(stroke
				(width 0.1524)
				(type default)
			)
			(layer "B.SilkS")
		)
		(fp_line
			(start -0.7874 0.4064)
			(end 0.7874 0.4064)
			(stroke
				(width 0.1524)
				(type default)
			)
			(layer "B.SilkS")
		)
		(fp_line
			(start 0.7874 -0.4064)
			(end -0.7874 -0.4064)
			(stroke
				(width 0.1524)
				(type default)
			)
			(layer "B.SilkS")
		)
		(fp_line
			(start 0.7874 0.4064)
			(end 0.7874 -0.4064)
			(stroke
				(width 0.1524)
				(type default)
			)
			(layer "B.SilkS")
		)
		(fp_line
			(start -0.67945 -0.3048)
			(end -0.67945 0.3048)
			(stroke
				(width 0.1)
				(type default)
			)
			(layer "B.Fab")
		)
		(fp_line
			(start -0.67945 0.3048)
			(end -0.120396 0.3048)
			(stroke
				(width 0.1)
				(type default)
			)
			(layer "B.Fab")
		)
		(fp_line
			(start -0.12065 -0.3048)
			(end -0.67945 -0.3048)
			(stroke
				(width 0.1)
				(type default)
			)
			(layer "B.Fab")
		)
		(fp_line
			(start -0.12065 -0.2794)
			(end -0.12065 -0.3048)
			(stroke
				(width 0.1)
				(type default)
			)
			(layer "B.Fab")
		)
		(fp_line
			(start -0.120396 0.2794)
			(end 0.12065 0.2794)
			(stroke
				(width 0.1)
				(type default)
			)
			(layer "B.Fab")
		)
		(fp_line
			(start -0.120396 0.3048)
			(end -0.120396 0.2794)
			(stroke
				(width 0.1)
				(type default)
			)
			(layer "B.Fab")
		)
		(fp_line
			(start 0.12065 -0.305054)
			(end 0.12065 -0.2794)
			(stroke
				(width 0.1)
				(type default)
			)
			(layer "B.Fab")
		)
		(fp_line
			(start 0.12065 -0.2794)
			(end -0.12065 -0.2794)
			(stroke
				(width 0.1)
				(type default)
			)
			(layer "B.Fab")
		)
		(fp_line
			(start 0.12065 0.2794)
			(end 0.12065 0.3048)
			(stroke
				(width 0.1)
				(type default)
			)
			(layer "B.Fab")
		)
		(fp_line
			(start 0.12065 0.3048)
			(end 0.67945 0.3048)
			(stroke
				(width 0.1)
				(type default)
			)
			(layer "B.Fab")
		)
		(fp_line
			(start 0.67945 -0.305054)
			(end 0.12065 -0.305054)
			(stroke
				(width 0.1)
				(type default)
			)
			(layer "B.Fab")
		)
		(fp_line
			(start 0.67945 0.3048)
			(end 0.67945 -0.305054)
			(stroke
				(width 0.1)
				(type default)
			)
			(layer "B.Fab")
		)
		(pad "1" smd circle
			(at 0.40005 0 180)
			(size 0 0)
			(layers "B.Cu" "B.Mask" "B.Paste")
			(net "IRQ_SMI_ACTIVE_N")
		)
		(pad "2" smd circle
			(at -0.40005 0 180)
			(size 0 0)
			(layers "B.Cu" "B.Mask" "B.Paste")
			(net "IRQ_SMI_ACTIVE_BMC_N")
		)
	)
	(footprint ""
		(layer "B.Cu")
		(at 423.683938 -135.769096 180)
		(property "Reference" "PR4220"
			(at 0 0 0)
			(layer "B.SilkS")
			(hide yes)
			(effects
				(font
					(size 1.27 1.27)
				)
				(justify mirror)
			)
		)
		(property "Value" ""
			(at 0 0 0)
			(layer "B.Fab")
			(effects
				(font
					(size 1.27 1.27)
				)
				(justify mirror)
			)
		)
		(duplicate_pad_numbers_are_jumpers no)
		(fp_line
			(start 0.7874 0.4064)
			(end 0.7874 -0.4064)
			(stroke
				(width 0.1524)
				(type default)
			)
			(layer "B.SilkS")
		)
		(fp_line
			(start 0.7874 -0.4064)
			(end -0.7874 -0.4064)
			(stroke
				(width 0.1524)
				(type default)
			)
			(layer "B.SilkS")
		)
		(fp_line
			(start -0.7874 0.4064)
			(end 0.7874 0.4064)
			(stroke
				(width 0.1524)
				(type default)
			)
			(layer "B.SilkS")
		)
		(fp_line
			(start -0.7874 -0.4064)
			(end -0.7874 0.4064)
			(stroke
				(width 0.1524)
				(type default)
			)
			(layer "B.SilkS")
		)
		(fp_line
			(start 0.67945 0.3048)
			(end 0.67945 -0.305054)
			(stroke
				(width 0.1)
				(type default)
			)
			(layer "B.Fab")
		)
		(fp_line
			(start 0.67945 -0.305054)
			(end 0.12065 -0.305054)
			(stroke
				(width 0.1)
				(type default)
			)
			(layer "B.Fab")
		)
		(fp_line
			(start 0.12065 0.3048)
			(end 0.67945 0.3048)
			(stroke
				(width 0.1)
				(type default)
			)
			(layer "B.Fab")
		)
		(fp_line
			(start 0.12065 0.2794)
			(end 0.12065 0.3048)
			(stroke
				(width 0.1)
				(type default)
			)
			(layer "B.Fab")
		)
		(fp_line
			(start 0.12065 -0.2794)
			(end -0.12065 -0.2794)
			(stroke
				(width 0.1)
				(type default)
			)
			(layer "B.Fab")
		)
		(fp_line
			(start 0.12065 -0.305054)
			(end 0.12065 -0.2794)
			(stroke
				(width 0.1)
				(type default)
			)
			(layer "B.Fab")
		)
		(fp_line
			(start -0.120396 0.3048)
			(end -0.120396 0.2794)
			(stroke
				(width 0.1)
				(type default)
			)
			(layer "B.Fab")
		)
		(fp_line
			(start -0.120396 0.2794)
			(end 0.12065 0.2794)
			(stroke
				(width 0.1)
				(type default)
			)
			(layer "B.Fab")
		)
		(fp_line
			(start -0.12065 -0.2794)
			(end -0.12065 -0.3048)
			(stroke
				(width 0.1)
				(type default)
			)
			(layer "B.Fab")
		)
		(fp_line
			(start -0.12065 -0.3048)
			(end -0.67945 -0.3048)
			(stroke
				(width 0.1)
				(type default)
			)
			(layer "B.Fab")
		)
		(fp_line
			(start -0.67945 0.3048)
			(end -0.120396 0.3048)
			(stroke
				(width 0.1)
				(type default)
			)
			(layer "B.Fab")
		)
		(fp_line
			(start -0.67945 -0.3048)
			(end -0.67945 0.3048)
			(stroke
				(width 0.1)
				(type default)
			)
			(layer "B.Fab")
		)
		(pad "1" smd circle
			(at 0.40005 0)
			(size 0 0)
			(layers "B.Cu" "B.Mask" "B.Paste")
			(net "PVCCINFAON_CPU0_CSPIN")
		)
		(pad "2" smd circle
			(at -0.40005 0)
			(size 0 0)
			(layers "B.Cu" "B.Mask" "B.Paste")
			(net "GND")
		)
	)
	(footprint ""
		(layer "B.Cu")
		(at 182.871618 -18.710148 90)
		(property "Reference" "R3239"
			(at 0 0 90)
			(layer "B.SilkS")
			(hide yes)
			(effects
				(font
					(size 1.27 1.27)
				)
				(justify mirror)
			)
		)
		(property "Value" ""
			(at 0 0 90)
			(layer "B.Fab")
			(effects
				(font
					(size 1.27 1.27)
				)
				(justify mirror)
			)
		)
		(duplicate_pad_numbers_are_jumpers no)
		(fp_line
			(start 0.7874 -0.4064)
			(end -0.7874 -0.4064)
			(stroke
				(width 0.1524)
				(type default)
			)
			(layer "B.SilkS")
		)
		(fp_line
			(start -0.7874 -0.4064)
			(end -0.7874 0.4064)
			(stroke
				(width 0.1524)
				(type default)
			)
			(layer "B.SilkS")
		)
		(fp_line
			(start 0.7874 0.4064)
			(end 0.7874 -0.4064)
			(stroke
				(width 0.1524)
				(type default)
			)
			(layer "B.SilkS")
		)
		(fp_line
			(start -0.7874 0.4064)
			(end 0.7874 0.4064)
			(stroke
				(width 0.1524)
				(type default)
			)
			(layer "B.SilkS")
		)
		(fp_line
			(start 0.67945 -0.305054)
			(end 0.12065 -0.305054)
			(stroke
				(width 0.1)
				(type default)
			)
			(layer "B.Fab")
		)
		(fp_line
			(start 0.12065 -0.305054)
			(end 0.12065 -0.2794)
			(stroke
				(width 0.1)
				(type default)
			)
			(layer "B.Fab")
		)
		(fp_line
			(start -0.12065 -0.3048)
			(end -0.67945 -0.3048)
			(stroke
				(width 0.1)
				(type default)
			)
			(layer "B.Fab")
		)
		(fp_line
			(start -0.67945 -0.3048)
			(end -0.67945 0.3048)
			(stroke
				(width 0.1)
				(type default)
			)
			(layer "B.Fab")
		)
		(fp_line
			(start 0.12065 -0.2794)
			(end -0.12065 -0.2794)
			(stroke
				(width 0.1)
				(type default)
			)
			(layer "B.Fab")
		)
		(fp_line
			(start -0.12065 -0.2794)
			(end -0.12065 -0.3048)
			(stroke
				(width 0.1)
				(type default)
			)
			(layer "B.Fab")
		)
		(fp_line
			(start 0.12065 0.2794)
			(end 0.12065 0.3048)
			(stroke
				(width 0.1)
				(type default)
			)
			(layer "B.Fab")
		)
		(fp_line
			(start -0.120396 0.2794)
			(end 0.12065 0.2794)
			(stroke
				(width 0.1)
				(type default)
			)
			(layer "B.Fab")
		)
		(fp_line
			(start 0.67945 0.3048)
			(end 0.67945 -0.305054)
			(stroke
				(width 0.1)
				(type default)
			)
			(layer "B.Fab")
		)
		(fp_line
			(start 0.12065 0.3048)
			(end 0.67945 0.3048)
			(stroke
				(width 0.1)
				(type default)
			)
			(layer "B.Fab")
		)
		(fp_line
			(start -0.120396 0.3048)
			(end -0.120396 0.2794)
			(stroke
				(width 0.1)
				(type default)
			)
			(layer "B.Fab")
		)
		(fp_line
			(start -0.67945 0.3048)
			(end -0.120396 0.3048)
			(stroke
				(width 0.1)
				(type default)
			)
			(layer "B.Fab")
		)
		(pad "1" smd circle
			(at 0.40005 0 270)
			(size 0 0)
			(layers "B.Cu" "B.Mask" "B.Paste")
			(net "SMB_OCP_SFF_3V3AUX_SDA")
		)
		(pad "2" smd circle
			(at -0.40005 0 270)
			(size 0 0)
			(layers "B.Cu" "B.Mask" "B.Paste")
			(net "SMB_OCP_SFF_3V3AUX_SDA_R0")
		)
	)
	(footprint ""
		(layer "B.Cu")
		(at 186.055254 -19.417792 -90)
		(property "Reference" "R2257"
			(at 0 0 90)
			(layer "B.SilkS")
			(hide yes)
			(effects
				(font
					(size 1.27 1.27)
				)
				(justify mirror)
			)
		)
		(property "Value" ""
			(at 0 0 90)
			(layer "B.Fab")
			(effects
				(font
					(size 1.27 1.27)
				)
				(justify mirror)
			)
		)
		(duplicate_pad_numbers_are_jumpers no)
		(fp_line
			(start -0.7874 0.4064)
			(end 0.7874 0.4064)
			(stroke
				(width 0.1524)
				(type default)
			)
			(layer "B.SilkS")
		)
		(fp_line
			(start 0.7874 0.4064)
			(end 0.7874 -0.154686)
			(stroke
				(width 0.1524)
				(type default)
			)
			(layer "B.SilkS")
		)
		(fp_line
			(start -0.7874 -0.131826)
			(end -0.7874 0.4064)
			(stroke
				(width 0.1524)
				(type default)
			)
			(layer "B.SilkS")
		)
		(fp_line
			(start 0.534924 -0.4064)
			(end -0.318516 -0.4064)
			(stroke
				(width 0.1524)
				(type default)
			)
			(layer "B.SilkS")
		)
		(fp_line
			(start -0.67945 0.3048)
			(end -0.120396 0.3048)
			(stroke
				(width 0.1)
				(type default)
			)
			(layer "B.Fab")
		)
		(fp_line
			(start -0.120396 0.3048)
			(end -0.120396 0.2794)
			(stroke
				(width 0.1)
				(type default)
			)
			(layer "B.Fab")
		)
		(fp_line
			(start 0.12065 0.3048)
			(end 0.67945 0.3048)
			(stroke
				(width 0.1)
				(type default)
			)
			(layer "B.Fab")
		)
		(fp_line
			(start 0.67945 0.3048)
			(end 0.67945 -0.305054)
			(stroke
				(width 0.1)
				(type default)
			)
			(layer "B.Fab")
		)
		(fp_line
			(start -0.120396 0.2794)
			(end 0.12065 0.2794)
			(stroke
				(width 0.1)
				(type default)
			)
			(layer "B.Fab")
		)
		(fp_line
			(start 0.12065 0.2794)
			(end 0.12065 0.3048)
			(stroke
				(width 0.1)
				(type default)
			)
			(layer "B.Fab")
		)
		(fp_line
			(start -0.12065 -0.2794)
			(end -0.12065 -0.3048)
			(stroke
				(width 0.1)
				(type default)
			)
			(layer "B.Fab")
		)
		(fp_line
			(start 0.12065 -0.2794)
			(end -0.12065 -0.2794)
			(stroke
				(width 0.1)
				(type default)
			)
			(layer "B.Fab")
		)
		(fp_line
			(start -0.67945 -0.3048)
			(end -0.67945 0.3048)
			(stroke
				(width 0.1)
				(type default)
			)
			(layer "B.Fab")
		)
		(fp_line
			(start -0.12065 -0.3048)
			(end -0.67945 -0.3048)
			(stroke
				(width 0.1)
				(type default)
			)
			(layer "B.Fab")
		)
		(fp_line
			(start 0.12065 -0.305054)
			(end 0.12065 -0.2794)
			(stroke
				(width 0.1)
				(type default)
			)
			(layer "B.Fab")
		)
		(fp_line
			(start 0.67945 -0.305054)
			(end 0.12065 -0.305054)
			(stroke
				(width 0.1)
				(type default)
			)
			(layer "B.Fab")
		)
		(pad "1" smd circle
			(at 0.40005 0 90)
			(size 0 0)
			(layers "B.Cu" "B.Mask" "B.Paste")
			(net "USB2_7_R_DN")
		)
		(pad "2" smd circle
			(at -0.40005 0 90)
			(size 0 0)
			(layers "B.Cu" "B.Mask" "B.Paste")
			(net "USB2_7_DN")
		)
	)
	(footprint ""
		(layer "B.Cu")
		(at 369.117372 -184.400952 90)
		(property "Reference" "R965"
			(at 0 0 90)
			(layer "B.SilkS")
			(hide yes)
			(effects
				(font
					(size 1.27 1.27)
				)
				(justify mirror)
			)
		)
		(property "Value" ""
			(at 0 0 90)
			(layer "B.Fab")
			(effects
				(font
					(size 1.27 1.27)
				)
				(justify mirror)
			)
		)
		(duplicate_pad_numbers_are_jumpers no)
		(fp_line
			(start 0.7874 -0.4064)
			(end -0.7874 -0.4064)
			(stroke
				(width 0.1524)
				(type default)
			)
			(layer "B.SilkS")
		)
		(fp_line
			(start -0.7874 -0.4064)
			(end -0.7874 0.4064)
			(stroke
				(width 0.1524)
				(type default)
			)
			(layer "B.SilkS")
		)
		(fp_line
			(start 0.7874 0.4064)
			(end 0.7874 -0.4064)
			(stroke
				(width 0.1524)
				(type default)
			)
			(layer "B.SilkS")
		)
		(fp_line
			(start -0.7874 0.4064)
			(end 0.7874 0.4064)
			(stroke
				(width 0.1524)
				(type default)
			)
			(layer "B.SilkS")
		)
		(fp_line
			(start 0.67945 -0.305054)
			(end 0.12065 -0.305054)
			(stroke
				(width 0.1)
				(type default)
			)
			(layer "B.Fab")
		)
		(fp_line
			(start 0.12065 -0.305054)
			(end 0.12065 -0.2794)
			(stroke
				(width 0.1)
				(type default)
			)
			(layer "B.Fab")
		)
		(fp_line
			(start -0.12065 -0.3048)
			(end -0.67945 -0.3048)
			(stroke
				(width 0.1)
				(type default)
			)
			(layer "B.Fab")
		)
		(fp_line
			(start -0.67945 -0.3048)
			(end -0.67945 0.3048)
			(stroke
				(width 0.1)
				(type default)
			)
			(layer "B.Fab")
		)
		(fp_line
			(start 0.12065 -0.2794)
			(end -0.12065 -0.2794)
			(stroke
				(width 0.1)
				(type default)
			)
			(layer "B.Fab")
		)
		(fp_line
			(start -0.12065 -0.2794)
			(end -0.12065 -0.3048)
			(stroke
				(width 0.1)
				(type default)
			)
			(layer "B.Fab")
		)
		(fp_line
			(start 0.12065 0.2794)
			(end 0.12065 0.3048)
			(stroke
				(width 0.1)
				(type default)
			)
			(layer "B.Fab")
		)
		(fp_line
			(start -0.120396 0.2794)
			(end 0.12065 0.2794)
			(stroke
				(width 0.1)
				(type default)
			)
			(layer "B.Fab")
		)
		(fp_line
			(start 0.67945 0.3048)
			(end 0.67945 -0.305054)
			(stroke
				(width 0.1)
				(type default)
			)
			(layer "B.Fab")
		)
		(fp_line
			(start 0.12065 0.3048)
			(end 0.67945 0.3048)
			(stroke
				(width 0.1)
				(type default)
			)
			(layer "B.Fab")
		)
		(fp_line
			(start -0.120396 0.3048)
			(end -0.120396 0.2794)
			(stroke
				(width 0.1)
				(type default)
			)
			(layer "B.Fab")
		)
		(fp_line
			(start -0.67945 0.3048)
			(end -0.120396 0.3048)
			(stroke
				(width 0.1)
				(type default)
			)
			(layer "B.Fab")
		)
		(pad "1" smd circle
			(at 0.40005 0 270)
			(size 0 0)
			(layers "B.Cu" "B.Mask" "B.Paste")
			(net "P3V3_AUX")
		)
		(pad "2" smd circle
			(at -0.40005 0 270)
			(size 0 0)
			(layers "B.Cu" "B.Mask" "B.Paste")
			(net "SMB_PEHPCPU0_LVC3_SCL")
		)
	)
	(footprint ""
		(layer "B.Cu")
		(at 256.55397 -55.436262 180)
		(property "Reference" "R3941"
			(at 0 0 0)
			(layer "B.SilkS")
			(hide yes)
			(effects
				(font
					(size 1.27 1.27)
				)
				(justify mirror)
			)
		)
		(property "Value" ""
			(at 0 0 0)
			(layer "B.Fab")
			(effects
				(font
					(size 1.27 1.27)
				)
				(justify mirror)
			)
		)
		(duplicate_pad_numbers_are_jumpers no)
		(fp_line
			(start 0.7874 0.4064)
			(end 0.7874 -0.4064)
			(stroke
				(width 0.1524)
				(type default)
			)
			(layer "B.SilkS")
		)
		(fp_line
			(start 0.7874 -0.4064)
			(end -0.7874 -0.4064)
			(stroke
				(width 0.1524)
				(type default)
			)
			(layer "B.SilkS")
		)
		(fp_line
			(start -0.7874 0.4064)
			(end 0.7874 0.4064)
			(stroke
				(width 0.1524)
				(type default)
			)
			(layer "B.SilkS")
		)
		(fp_line
			(start -0.7874 -0.4064)
			(end -0.7874 0.4064)
			(stroke
				(width 0.1524)
				(type default)
			)
			(layer "B.SilkS")
		)
		(fp_line
			(start 0.67945 0.3048)
			(end 0.67945 -0.305054)
			(stroke
				(width 0.1)
				(type default)
			)
			(layer "B.Fab")
		)
		(fp_line
			(start 0.67945 -0.305054)
			(end 0.12065 -0.305054)
			(stroke
				(width 0.1)
				(type default)
			)
			(layer "B.Fab")
		)
		(fp_line
			(start 0.12065 0.3048)
			(end 0.67945 0.3048)
			(stroke
				(width 0.1)
				(type default)
			)
			(layer "B.Fab")
		)
		(fp_line
			(start 0.12065 0.2794)
			(end 0.12065 0.3048)
			(stroke
				(width 0.1)
				(type default)
			)
			(layer "B.Fab")
		)
		(fp_line
			(start 0.12065 -0.2794)
			(end -0.12065 -0.2794)
			(stroke
				(width 0.1)
				(type default)
			)
			(layer "B.Fab")
		)
		(fp_line
			(start 0.12065 -0.305054)
			(end 0.12065 -0.2794)
			(stroke
				(width 0.1)
				(type default)
			)
			(layer "B.Fab")
		)
		(fp_line
			(start -0.120396 0.3048)
			(end -0.120396 0.2794)
			(stroke
				(width 0.1)
				(type default)
			)
			(layer "B.Fab")
		)
		(fp_line
			(start -0.120396 0.2794)
			(end 0.12065 0.2794)
			(stroke
				(width 0.1)
				(type default)
			)
			(layer "B.Fab")
		)
		(fp_line
			(start -0.12065 -0.2794)
			(end -0.12065 -0.3048)
			(stroke
				(width 0.1)
				(type default)
			)
			(layer "B.Fab")
		)
		(fp_line
			(start -0.12065 -0.3048)
			(end -0.67945 -0.3048)
			(stroke
				(width 0.1)
				(type default)
			)
			(layer "B.Fab")
		)
		(fp_line
			(start -0.67945 0.3048)
			(end -0.120396 0.3048)
			(stroke
				(width 0.1)
				(type default)
			)
			(layer "B.Fab")
		)
		(fp_line
			(start -0.67945 -0.3048)
			(end -0.67945 0.3048)
			(stroke
				(width 0.1)
				(type default)
			)
			(layer "B.Fab")
		)
		(pad "1" smd rect
			(at 0.40005 0 180)
			(size 0.4572 0.508)
			(layers "B.Cu" "B.Mask" "B.Paste")
			(net "P12V_E1S_0_ISENSE_MAM_TIC")
		)
		(pad "2" smd rect
			(at -0.40005 0 180)
			(size 0.4572 0.508)
			(layers "B.Cu" "B.Mask" "B.Paste")
			(net "P12V_E1S_0_ISENSE_TIC")
		)
	)
	(footprint ""
		(layer "B.Cu")
		(at 19.760946 -319.268856 180)
		(property "Reference" "R900"
			(at 0 0 0)
			(layer "B.SilkS")
			(hide yes)
			(effects
				(font
					(size 1.27 1.27)
				)
				(justify mirror)
			)
		)
		(property "Value" ""
			(at 0 0 0)
			(layer "B.Fab")
			(effects
				(font
					(size 1.27 1.27)
				)
				(justify mirror)
			)
		)
		(duplicate_pad_numbers_are_jumpers no)
		(fp_line
			(start 0.7874 0.4064)
			(end 0.7874 -0.4064)
			(stroke
				(width 0.1524)
				(type default)
			)
			(layer "B.SilkS")
		)
		(fp_line
			(start 0.7874 -0.4064)
			(end -0.7874 -0.4064)
			(stroke
				(width 0.1524)
				(type default)
			)
			(layer "B.SilkS")
		)
		(fp_line
			(start -0.7874 0.4064)
			(end 0.7874 0.4064)
			(stroke
				(width 0.1524)
				(type default)
			)
			(layer "B.SilkS")
		)
		(fp_line
			(start -0.7874 -0.4064)
			(end -0.7874 0.4064)
			(stroke
				(width 0.1524)
				(type default)
			)
			(layer "B.SilkS")
		)
		(fp_line
			(start 0.67945 0.3048)
			(end 0.67945 -0.305054)
			(stroke
				(width 0.1)
				(type default)
			)
			(layer "B.Fab")
		)
		(fp_line
			(start 0.67945 -0.305054)
			(end 0.12065 -0.305054)
			(stroke
				(width 0.1)
				(type default)
			)
			(layer "B.Fab")
		)
		(fp_line
			(start 0.12065 0.3048)
			(end 0.67945 0.3048)
			(stroke
				(width 0.1)
				(type default)
			)
			(layer "B.Fab")
		)
		(fp_line
			(start 0.12065 0.2794)
			(end 0.12065 0.3048)
			(stroke
				(width 0.1)
				(type default)
			)
			(layer "B.Fab")
		)
		(fp_line
			(start 0.12065 -0.2794)
			(end -0.12065 -0.2794)
			(stroke
				(width 0.1)
				(type default)
			)
			(layer "B.Fab")
		)
		(fp_line
			(start 0.12065 -0.305054)
			(end 0.12065 -0.2794)
			(stroke
				(width 0.1)
				(type default)
			)
			(layer "B.Fab")
		)
		(fp_line
			(start -0.120396 0.3048)
			(end -0.120396 0.2794)
			(stroke
				(width 0.1)
				(type default)
			)
			(layer "B.Fab")
		)
		(fp_line
			(start -0.120396 0.2794)
			(end 0.12065 0.2794)
			(stroke
				(width 0.1)
				(type default)
			)
			(layer "B.Fab")
		)
		(fp_line
			(start -0.12065 -0.2794)
			(end -0.12065 -0.3048)
			(stroke
				(width 0.1)
				(type default)
			)
			(layer "B.Fab")
		)
		(fp_line
			(start -0.12065 -0.3048)
			(end -0.67945 -0.3048)
			(stroke
				(width 0.1)
				(type default)
			)
			(layer "B.Fab")
		)
		(fp_line
			(start -0.67945 0.3048)
			(end -0.120396 0.3048)
			(stroke
				(width 0.1)
				(type default)
			)
			(layer "B.Fab")
		)
		(fp_line
			(start -0.67945 -0.3048)
			(end -0.67945 0.3048)
			(stroke
				(width 0.1)
				(type default)
			)
			(layer "B.Fab")
		)
		(pad "1" smd circle
			(at 0.40005 0)
			(size 0 0)
			(layers "B.Cu" "B.Mask" "B.Paste")
			(net "PWRGD_CHD_CPU1_DIMM2")
		)
		(pad "2" smd circle
			(at -0.40005 0)
			(size 0 0)
			(layers "B.Cu" "B.Mask" "B.Paste")
			(net "PWRGD_FAIL_CPU1_CD")
		)
	)
	(footprint ""
		(layer "B.Cu")
		(at 189.232286 -193.615056 -90)
		(property "Reference" "R819"
			(at 0 0 90)
			(layer "B.SilkS")
			(hide yes)
			(effects
				(font
					(size 1.27 1.27)
				)
				(justify mirror)
			)
		)
		(property "Value" ""
			(at 0 0 90)
			(layer "B.Fab")
			(effects
				(font
					(size 1.27 1.27)
				)
				(justify mirror)
			)
		)
		(duplicate_pad_numbers_are_jumpers no)
		(fp_line
			(start -0.7874 0.4064)
			(end 0.7874 0.4064)
			(stroke
				(width 0.1524)
				(type default)
			)
			(layer "B.SilkS")
		)
		(fp_line
			(start 0.7874 0.4064)
			(end 0.7874 -0.4064)
			(stroke
				(width 0.1524)
				(type default)
			)
			(layer "B.SilkS")
		)
		(fp_line
			(start -0.7874 -0.4064)
			(end -0.7874 0.4064)
			(stroke
				(width 0.1524)
				(type default)
			)
			(layer "B.SilkS")
		)
		(fp_line
			(start 0.7874 -0.4064)
			(end -0.7874 -0.4064)
			(stroke
				(width 0.1524)
				(type default)
			)
			(layer "B.SilkS")
		)
		(fp_line
			(start -0.67945 0.3048)
			(end -0.120396 0.3048)
			(stroke
				(width 0.1)
				(type default)
			)
			(layer "B.Fab")
		)
		(fp_line
			(start -0.120396 0.3048)
			(end -0.120396 0.2794)
			(stroke
				(width 0.1)
				(type default)
			)
			(layer "B.Fab")
		)
		(fp_line
			(start 0.12065 0.3048)
			(end 0.67945 0.3048)
			(stroke
				(width 0.1)
				(type default)
			)
			(layer "B.Fab")
		)
		(fp_line
			(start 0.67945 0.3048)
			(end 0.67945 -0.305054)
			(stroke
				(width 0.1)
				(type default)
			)
			(layer "B.Fab")
		)
		(fp_line
			(start -0.120396 0.2794)
			(end 0.12065 0.2794)
			(stroke
				(width 0.1)
				(type default)
			)
			(layer "B.Fab")
		)
		(fp_line
			(start 0.12065 0.2794)
			(end 0.12065 0.3048)
			(stroke
				(width 0.1)
				(type default)
			)
			(layer "B.Fab")
		)
		(fp_line
			(start -0.12065 -0.2794)
			(end -0.12065 -0.3048)
			(stroke
				(width 0.1)
				(type default)
			)
			(layer "B.Fab")
		)
		(fp_line
			(start 0.12065 -0.2794)
			(end -0.12065 -0.2794)
			(stroke
				(width 0.1)
				(type default)
			)
			(layer "B.Fab")
		)
		(fp_line
			(start -0.67945 -0.3048)
			(end -0.67945 0.3048)
			(stroke
				(width 0.1)
				(type default)
			)
			(layer "B.Fab")
		)
		(fp_line
			(start -0.12065 -0.3048)
			(end -0.67945 -0.3048)
			(stroke
				(width 0.1)
				(type default)
			)
			(layer "B.Fab")
		)
		(fp_line
			(start 0.12065 -0.305054)
			(end 0.12065 -0.2794)
			(stroke
				(width 0.1)
				(type default)
			)
			(layer "B.Fab")
		)
		(fp_line
			(start 0.67945 -0.305054)
			(end 0.12065 -0.305054)
			(stroke
				(width 0.1)
				(type default)
			)
			(layer "B.Fab")
		)
		(pad "1" smd circle
			(at 0.40005 0 90)
			(size 0 0)
			(layers "B.Cu" "B.Mask" "B.Paste")
			(net "PVCCD_HV_CPU1")
		)
		(pad "2" smd circle
			(at -0.40005 0 90)
			(size 0 0)
			(layers "B.Cu" "B.Mask" "B.Paste")
			(net "RST_M_GH_CPU1_FPGA_N")
		)
	)
	(footprint ""
		(layer "B.Cu")
		(at 391.416032 -337.85048)
		(property "Reference" "C1397"
			(at 0 0 0)
			(layer "B.SilkS")
			(hide yes)
			(effects
				(font
					(size 1.27 1.27)
				)
				(justify mirror)
			)
		)
		(property "Value" ""
			(at 0 0 0)
			(layer "B.Fab")
			(effects
				(font
					(size 1.27 1.27)
				)
				(justify mirror)
			)
		)
		(duplicate_pad_numbers_are_jumpers no)
		(fp_line
			(start -1.524 -0.762)
			(end -1.524 0.762)
			(stroke
				(width 0.1524)
				(type default)
			)
			(layer "B.SilkS")
		)
		(fp_line
			(start -1.524 0.762)
			(end 1.524 0.762)
			(stroke
				(width 0.1524)
				(type default)
			)
			(layer "B.SilkS")
		)
		(fp_line
			(start 1.524 -0.762)
			(end -1.524 -0.762)
			(stroke
				(width 0.1524)
				(type default)
			)
			(layer "B.SilkS")
		)
		(fp_line
			(start 1.524 0.762)
			(end 1.524 -0.762)
			(stroke
				(width 0.1524)
				(type default)
			)
			(layer "B.SilkS")
		)
		(fp_line
			(start -1.1049 -0.724916)
			(end 1.1049 -0.724916)
			(stroke
				(width 0.1)
				(type default)
			)
			(layer "B.Fab")
		)
		(fp_line
			(start -1.1049 0.724916)
			(end -1.1049 -0.724916)
			(stroke
				(width 0.1)
				(type default)
			)
			(layer "B.Fab")
		)
		(fp_line
			(start 1.1049 -0.724916)
			(end 1.1049 0.724916)
			(stroke
				(width 0.1)
				(type default)
			)
			(layer "B.Fab")
		)
		(fp_line
			(start 1.1049 0.724916)
			(end -1.1049 0.724916)
			(stroke
				(width 0.1)
				(type default)
			)
			(layer "B.Fab")
		)
		(pad "1" smd rect
			(at 0.889 0)
			(size 1.016 1.27)
			(layers "B.Cu" "B.Mask" "B.Paste")
			(net "PVPP_HBM_CPU0")
		)
		(pad "2" smd rect
			(at -0.889 0)
			(size 1.016 1.27)
			(layers "B.Cu" "B.Mask" "B.Paste")
			(net "GND")
		)
	)
	(footprint ""
		(layer "B.Cu")
		(at 36.488624 -407.077164 180)
		(property "Reference" "R5236"
			(at 0 0 0)
			(layer "B.SilkS")
			(hide yes)
			(effects
				(font
					(size 1.27 1.27)
				)
				(justify mirror)
			)
		)
		(property "Value" ""
			(at 0 0 0)
			(layer "B.Fab")
			(effects
				(font
					(size 1.27 1.27)
				)
				(justify mirror)
			)
		)
		(duplicate_pad_numbers_are_jumpers no)
		(fp_line
			(start 0.7874 0.4064)
			(end 0.7874 -0.028956)
			(stroke
				(width 0.1524)
				(type default)
			)
			(layer "B.SilkS")
		)
		(fp_line
			(start 0.529844 -0.4064)
			(end -0.407416 -0.4064)
			(stroke
				(width 0.1524)
				(type default)
			)
			(layer "B.SilkS")
		)
		(fp_line
			(start -0.7874 0.4064)
			(end 0.7874 0.4064)
			(stroke
				(width 0.1524)
				(type default)
			)
			(layer "B.SilkS")
		)
		(fp_line
			(start -0.7874 -0.105156)
			(end -0.7874 0.4064)
			(stroke
				(width 0.1524)
				(type default)
			)
			(layer "B.SilkS")
		)
		(fp_line
			(start 0.67945 0.3048)
			(end 0.67945 -0.305054)
			(stroke
				(width 0.1)
				(type default)
			)
			(layer "B.Fab")
		)
		(fp_line
			(start 0.67945 -0.305054)
			(end 0.12065 -0.305054)
			(stroke
				(width 0.1)
				(type default)
			)
			(layer "B.Fab")
		)
		(fp_line
			(start 0.12065 0.3048)
			(end 0.67945 0.3048)
			(stroke
				(width 0.1)
				(type default)
			)
			(layer "B.Fab")
		)
		(fp_line
			(start 0.12065 0.2794)
			(end 0.12065 0.3048)
			(stroke
				(width 0.1)
				(type default)
			)
			(layer "B.Fab")
		)
		(fp_line
			(start 0.12065 -0.2794)
			(end -0.12065 -0.2794)
			(stroke
				(width 0.1)
				(type default)
			)
			(layer "B.Fab")
		)
		(fp_line
			(start 0.12065 -0.305054)
			(end 0.12065 -0.2794)
			(stroke
				(width 0.1)
				(type default)
			)
			(layer "B.Fab")
		)
		(fp_line
			(start -0.120396 0.3048)
			(end -0.120396 0.2794)
			(stroke
				(width 0.1)
				(type default)
			)
			(layer "B.Fab")
		)
		(fp_line
			(start -0.120396 0.2794)
			(end 0.12065 0.2794)
			(stroke
				(width 0.1)
				(type default)
			)
			(layer "B.Fab")
		)
		(fp_line
			(start -0.12065 -0.2794)
			(end -0.12065 -0.3048)
			(stroke
				(width 0.1)
				(type default)
			)
			(layer "B.Fab")
		)
		(fp_line
			(start -0.12065 -0.3048)
			(end -0.67945 -0.3048)
			(stroke
				(width 0.1)
				(type default)
			)
			(layer "B.Fab")
		)
		(fp_line
			(start -0.67945 0.3048)
			(end -0.120396 0.3048)
			(stroke
				(width 0.1)
				(type default)
			)
			(layer "B.Fab")
		)
		(fp_line
			(start -0.67945 -0.3048)
			(end -0.67945 0.3048)
			(stroke
				(width 0.1)
				(type default)
			)
			(layer "B.Fab")
		)
		(pad "1" smd circle
			(at 0.40005 0)
			(size 0 0)
			(layers "B.Cu" "B.Mask" "B.Paste")
			(net "USB2_HUB_BUF_SWB_R_DN")
		)
		(pad "2" smd circle
			(at -0.40005 0)
			(size 0 0)
			(layers "B.Cu" "B.Mask" "B.Paste")
			(net "USB2_HUB_BUF_SWB_DN")
		)
	)
	(footprint ""
		(layer "B.Cu")
		(at 232.003854 -121.616216 -90)
		(property "Reference" "L4"
			(at 0 0 90)
			(layer "B.SilkS")
			(hide yes)
			(effects
				(font
					(size 1.27 1.27)
				)
				(justify mirror)
			)
		)
		(property "Value" ""
			(at 0 0 90)
			(layer "B.Fab")
			(effects
				(font
					(size 1.27 1.27)
				)
				(justify mirror)
			)
		)
		(duplicate_pad_numbers_are_jumpers no)
		(fp_line
			(start -1.27 0.5842)
			(end 1.27 0.5842)
			(stroke
				(width 0.1524)
				(type default)
			)
			(layer "B.SilkS")
		)
		(fp_line
			(start -1.27 0.5842)
			(end -1.27 -0.5842)
			(stroke
				(width 0.1524)
				(type default)
			)
			(layer "B.SilkS")
		)
		(fp_line
			(start -0.127 0.5842)
			(end -0.127 -0.5842)
			(stroke
				(width 0.1524)
				(type default)
			)
			(layer "B.SilkS")
		)
		(fp_line
			(start 0.127 0.5842)
			(end 0.127 -0.5842)
			(stroke
				(width 0.1524)
				(type default)
			)
			(layer "B.SilkS")
		)
		(fp_line
			(start 1.27 0.5842)
			(end 1.27 -0.5842)
			(stroke
				(width 0.1524)
				(type default)
			)
			(layer "B.SilkS")
		)
		(fp_line
			(start 1.27 -0.5588)
			(end 1.27 -0.5842)
			(stroke
				(width 0.1524)
				(type default)
			)
			(layer "B.SilkS")
		)
		(fp_line
			(start 1.27 -0.5842)
			(end -1.27 -0.5842)
			(stroke
				(width 0.1524)
				(type default)
			)
			(layer "B.SilkS")
		)
		(fp_line
			(start -0.9144 0.508)
			(end 0.9144 0.508)
			(stroke
				(width 0.1)
				(type default)
			)
			(layer "B.Fab")
		)
		(fp_line
			(start 0.9144 0.508)
			(end 0.9144 0.406654)
			(stroke
				(width 0.1)
				(type default)
			)
			(layer "B.Fab")
		)
		(fp_line
			(start 0.9144 0.406654)
			(end 1.194308 0.406654)
			(stroke
				(width 0.1)
				(type default)
			)
			(layer "B.Fab")
		)
		(fp_line
			(start 1.194308 0.406654)
			(end 1.194308 -0.406654)
			(stroke
				(width 0.1)
				(type default)
			)
			(layer "B.Fab")
		)
		(fp_line
			(start -1.1938 0.4064)
			(end -0.9144 0.4064)
			(stroke
				(width 0.1)
				(type default)
			)
			(layer "B.Fab")
		)
		(fp_line
			(start -0.9144 0.4064)
			(end -0.9144 0.508)
			(stroke
				(width 0.1)
				(type default)
			)
			(layer "B.Fab")
		)
		(fp_line
			(start -1.1938 -0.406654)
			(end -1.1938 0.4064)
			(stroke
				(width 0.1)
				(type default)
			)
			(layer "B.Fab")
		)
		(fp_line
			(start -0.9144 -0.406654)
			(end -1.1938 -0.406654)
			(stroke
				(width 0.1)
				(type default)
			)
			(layer "B.Fab")
		)
		(fp_line
			(start 0.9144 -0.406654)
			(end 0.9144 -0.508)
			(stroke
				(width 0.1)
				(type default)
			)
			(layer "B.Fab")
		)
		(fp_line
			(start 1.194308 -0.406654)
			(end 0.9144 -0.406654)
			(stroke
				(width 0.1)
				(type default)
			)
			(layer "B.Fab")
		)
		(fp_line
			(start -0.9144 -0.508)
			(end -0.9144 -0.406654)
			(stroke
				(width 0.1)
				(type default)
			)
			(layer "B.Fab")
		)
		(fp_line
			(start 0.9144 -0.508)
			(end -0.9144 -0.508)
			(stroke
				(width 0.1)
				(type default)
			)
			(layer "B.Fab")
		)
		(pad "1" smd rect
			(at 0.7366 0 180)
			(size 0.7112 0.8128)
			(layers "B.Cu" "B.Mask" "B.Paste")
			(net "P3V3")
		)
		(pad "2" smd rect
			(at -0.7366 0 180)
			(size 0.7112 0.8128)
			(layers "B.Cu" "B.Mask" "B.Paste")
			(net "P3V3_DB2000_FB_VDD")
		)
	)
	(footprint ""
		(layer "B.Cu")
		(at 65.90411 -17.941544)
		(property "Reference" "C1830"
			(at 0 0 0)
			(layer "B.SilkS")
			(hide yes)
			(effects
				(font
					(size 1.27 1.27)
				)
				(justify mirror)
			)
		)
		(property "Value" ""
			(at 0 0 0)
			(layer "B.Fab")
			(effects
				(font
					(size 1.27 1.27)
				)
				(justify mirror)
			)
		)
		(duplicate_pad_numbers_are_jumpers no)
		(fp_line
			(start -1.524 -0.762)
			(end -1.524 0.762)
			(stroke
				(width 0.1524)
				(type default)
			)
			(layer "B.SilkS")
		)
		(fp_line
			(start -1.524 0.762)
			(end 1.524 0.762)
			(stroke
				(width 0.1524)
				(type default)
			)
			(layer "B.SilkS")
		)
		(fp_line
			(start 1.524 -0.762)
			(end -1.524 -0.762)
			(stroke
				(width 0.1524)
				(type default)
			)
			(layer "B.SilkS")
		)
		(fp_line
			(start 1.524 0.762)
			(end 1.524 -0.762)
			(stroke
				(width 0.1524)
				(type default)
			)
			(layer "B.SilkS")
		)
		(fp_line
			(start -1.1049 -0.724916)
			(end 1.1049 -0.724916)
			(stroke
				(width 0.1)
				(type default)
			)
			(layer "B.Fab")
		)
		(fp_line
			(start -1.1049 0.724916)
			(end -1.1049 -0.724916)
			(stroke
				(width 0.1)
				(type default)
			)
			(layer "B.Fab")
		)
		(fp_line
			(start 1.1049 -0.724916)
			(end 1.1049 0.724916)
			(stroke
				(width 0.1)
				(type default)
			)
			(layer "B.Fab")
		)
		(fp_line
			(start 1.1049 0.724916)
			(end -1.1049 0.724916)
			(stroke
				(width 0.1)
				(type default)
			)
			(layer "B.Fab")
		)
		(pad "1" smd rect
			(at 0.889 0)
			(size 1.016 1.27)
			(layers "B.Cu" "B.Mask" "B.Paste")
			(net "P12V_OCP_V3_2")
		)
		(pad "2" smd rect
			(at -0.889 0)
			(size 1.016 1.27)
			(layers "B.Cu" "B.Mask" "B.Paste")
			(net "GND")
		)
	)
	(footprint ""
		(layer "B.Cu")
		(at 34.848546 -321.554856 -90)
		(property "Reference" "C66"
			(at 0 0 90)
			(layer "B.SilkS")
			(hide yes)
			(effects
				(font
					(size 1.27 1.27)
				)
				(justify mirror)
			)
		)
		(property "Value" ""
			(at 0 0 90)
			(layer "B.Fab")
			(effects
				(font
					(size 1.27 1.27)
				)
				(justify mirror)
			)
		)
		(duplicate_pad_numbers_are_jumpers no)
		(fp_line
			(start -1.524 0.762)
			(end 1.524 0.762)
			(stroke
				(width 0.1524)
				(type default)
			)
			(layer "B.SilkS")
		)
		(fp_line
			(start 1.524 0.762)
			(end 1.524 -0.762)
			(stroke
				(width 0.1524)
				(type default)
			)
			(layer "B.SilkS")
		)
		(fp_line
			(start -1.524 -0.762)
			(end -1.524 0.762)
			(stroke
				(width 0.1524)
				(type default)
			)
			(layer "B.SilkS")
		)
		(fp_line
			(start 1.524 -0.762)
			(end -1.524 -0.762)
			(stroke
				(width 0.1524)
				(type default)
			)
			(layer "B.SilkS")
		)
		(fp_line
			(start -1.1049 0.724916)
			(end -1.1049 -0.724916)
			(stroke
				(width 0.1)
				(type default)
			)
			(layer "B.Fab")
		)
		(fp_line
			(start 1.1049 0.724916)
			(end -1.1049 0.724916)
			(stroke
				(width 0.1)
				(type default)
			)
			(layer "B.Fab")
		)
		(fp_line
			(start -1.1049 -0.724916)
			(end 1.1049 -0.724916)
			(stroke
				(width 0.1)
				(type default)
			)
			(layer "B.Fab")
		)
		(fp_line
			(start 1.1049 -0.724916)
			(end 1.1049 0.724916)
			(stroke
				(width 0.1)
				(type default)
			)
			(layer "B.Fab")
		)
		(pad "1" smd rect
			(at 0.889 0 270)
			(size 1.016 1.27)
			(layers "B.Cu" "B.Mask" "B.Paste")
			(net "P12V_S3_AUX_CPU1_NVDIMM")
		)
		(pad "2" smd rect
			(at -0.889 0 270)
			(size 1.016 1.27)
			(layers "B.Cu" "B.Mask" "B.Paste")
			(net "GND")
		)
	)
	(footprint ""
		(layer "B.Cu")
		(at 337.552284 -33.72612 90)
		(property "Reference" "R3325"
			(at 0 0 90)
			(layer "B.SilkS")
			(hide yes)
			(effects
				(font
					(size 1.27 1.27)
				)
				(justify mirror)
			)
		)
		(property "Value" ""
			(at 0 0 90)
			(layer "B.Fab")
			(effects
				(font
					(size 1.27 1.27)
				)
				(justify mirror)
			)
		)
		(duplicate_pad_numbers_are_jumpers no)
		(fp_line
			(start 0.7874 -0.4064)
			(end -0.7874 -0.4064)
			(stroke
				(width 0.1524)
				(type default)
			)
			(layer "B.SilkS")
		)
		(fp_line
			(start -0.7874 -0.4064)
			(end -0.7874 0.4064)
			(stroke
				(width 0.1524)
				(type default)
			)
			(layer "B.SilkS")
		)
		(fp_line
			(start 0.7874 0.4064)
			(end 0.7874 -0.4064)
			(stroke
				(width 0.1524)
				(type default)
			)
			(layer "B.SilkS")
		)
		(fp_line
			(start -0.7874 0.4064)
			(end 0.7874 0.4064)
			(stroke
				(width 0.1524)
				(type default)
			)
			(layer "B.SilkS")
		)
		(fp_line
			(start 0.67945 -0.305054)
			(end 0.12065 -0.305054)
			(stroke
				(width 0.1)
				(type default)
			)
			(layer "B.Fab")
		)
		(fp_line
			(start 0.12065 -0.305054)
			(end 0.12065 -0.2794)
			(stroke
				(width 0.1)
				(type default)
			)
			(layer "B.Fab")
		)
		(fp_line
			(start -0.12065 -0.3048)
			(end -0.67945 -0.3048)
			(stroke
				(width 0.1)
				(type default)
			)
			(layer "B.Fab")
		)
		(fp_line
			(start -0.67945 -0.3048)
			(end -0.67945 0.3048)
			(stroke
				(width 0.1)
				(type default)
			)
			(layer "B.Fab")
		)
		(fp_line
			(start 0.12065 -0.2794)
			(end -0.12065 -0.2794)
			(stroke
				(width 0.1)
				(type default)
			)
			(layer "B.Fab")
		)
		(fp_line
			(start -0.12065 -0.2794)
			(end -0.12065 -0.3048)
			(stroke
				(width 0.1)
				(type default)
			)
			(layer "B.Fab")
		)
		(fp_line
			(start 0.12065 0.2794)
			(end 0.12065 0.3048)
			(stroke
				(width 0.1)
				(type default)
			)
			(layer "B.Fab")
		)
		(fp_line
			(start -0.120396 0.2794)
			(end 0.12065 0.2794)
			(stroke
				(width 0.1)
				(type default)
			)
			(layer "B.Fab")
		)
		(fp_line
			(start 0.67945 0.3048)
			(end 0.67945 -0.305054)
			(stroke
				(width 0.1)
				(type default)
			)
			(layer "B.Fab")
		)
		(fp_line
			(start 0.12065 0.3048)
			(end 0.67945 0.3048)
			(stroke
				(width 0.1)
				(type default)
			)
			(layer "B.Fab")
		)
		(fp_line
			(start -0.120396 0.3048)
			(end -0.120396 0.2794)
			(stroke
				(width 0.1)
				(type default)
			)
			(layer "B.Fab")
		)
		(fp_line
			(start -0.67945 0.3048)
			(end -0.120396 0.3048)
			(stroke
				(width 0.1)
				(type default)
			)
			(layer "B.Fab")
		)
		(pad "1" smd circle
			(at 0.40005 0 270)
			(size 0 0)
			(layers "B.Cu" "B.Mask" "B.Paste")
			(net "FM_PCH_SPKR")
		)
		(pad "2" smd circle
			(at -0.40005 0 270)
			(size 0 0)
			(layers "B.Cu" "B.Mask" "B.Paste")
			(net "GND")
		)
	)
	(footprint ""
		(layer "B.Cu")
		(at 155.38704 -189.34938 -90)
		(property "Reference" "R91"
			(at 0 0 90)
			(layer "B.SilkS")
			(hide yes)
			(effects
				(font
					(size 1.27 1.27)
				)
				(justify mirror)
			)
		)
		(property "Value" ""
			(at 0 0 90)
			(layer "B.Fab")
			(effects
				(font
					(size 1.27 1.27)
				)
				(justify mirror)
			)
		)
		(duplicate_pad_numbers_are_jumpers no)
		(fp_line
			(start -0.7874 0.4064)
			(end 0.7874 0.4064)
			(stroke
				(width 0.1524)
				(type default)
			)
			(layer "B.SilkS")
		)
		(fp_line
			(start 0.7874 0.4064)
			(end 0.7874 -0.4064)
			(stroke
				(width 0.1524)
				(type default)
			)
			(layer "B.SilkS")
		)
		(fp_line
			(start -0.7874 -0.4064)
			(end -0.7874 0.4064)
			(stroke
				(width 0.1524)
				(type default)
			)
			(layer "B.SilkS")
		)
		(fp_line
			(start 0.7874 -0.4064)
			(end -0.7874 -0.4064)
			(stroke
				(width 0.1524)
				(type default)
			)
			(layer "B.SilkS")
		)
		(fp_line
			(start -0.67945 0.3048)
			(end -0.120396 0.3048)
			(stroke
				(width 0.1)
				(type default)
			)
			(layer "B.Fab")
		)
		(fp_line
			(start -0.120396 0.3048)
			(end -0.120396 0.2794)
			(stroke
				(width 0.1)
				(type default)
			)
			(layer "B.Fab")
		)
		(fp_line
			(start 0.12065 0.3048)
			(end 0.67945 0.3048)
			(stroke
				(width 0.1)
				(type default)
			)
			(layer "B.Fab")
		)
		(fp_line
			(start 0.67945 0.3048)
			(end 0.67945 -0.305054)
			(stroke
				(width 0.1)
				(type default)
			)
			(layer "B.Fab")
		)
		(fp_line
			(start -0.120396 0.2794)
			(end 0.12065 0.2794)
			(stroke
				(width 0.1)
				(type default)
			)
			(layer "B.Fab")
		)
		(fp_line
			(start 0.12065 0.2794)
			(end 0.12065 0.3048)
			(stroke
				(width 0.1)
				(type default)
			)
			(layer "B.Fab")
		)
		(fp_line
			(start -0.12065 -0.2794)
			(end -0.12065 -0.3048)
			(stroke
				(width 0.1)
				(type default)
			)
			(layer "B.Fab")
		)
		(fp_line
			(start 0.12065 -0.2794)
			(end -0.12065 -0.2794)
			(stroke
				(width 0.1)
				(type default)
			)
			(layer "B.Fab")
		)
		(fp_line
			(start -0.67945 -0.3048)
			(end -0.67945 0.3048)
			(stroke
				(width 0.1)
				(type default)
			)
			(layer "B.Fab")
		)
		(fp_line
			(start -0.12065 -0.3048)
			(end -0.67945 -0.3048)
			(stroke
				(width 0.1)
				(type default)
			)
			(layer "B.Fab")
		)
		(fp_line
			(start 0.12065 -0.305054)
			(end 0.12065 -0.2794)
			(stroke
				(width 0.1)
				(type default)
			)
			(layer "B.Fab")
		)
		(fp_line
			(start 0.67945 -0.305054)
			(end 0.12065 -0.305054)
			(stroke
				(width 0.1)
				(type default)
			)
			(layer "B.Fab")
		)
		(pad "1" smd circle
			(at 0.40005 0 90)
			(size 0 0)
			(layers "B.Cu" "B.Mask" "B.Paste")
			(net "PVNN_TERM_CPU1")
		)
		(pad "2" smd circle
			(at -0.40005 0 90)
			(size 0 0)
			(layers "B.Cu" "B.Mask" "B.Paste")
			(net "PU_CPU1_UPI1_AC_COUPLING")
		)
	)
	(footprint ""
		(layer "B.Cu")
		(at 278.724614 -319.263776 180)
		(property "Reference" "C17"
			(at 0 0 0)
			(layer "B.SilkS")
			(hide yes)
			(effects
				(font
					(size 1.27 1.27)
				)
				(justify mirror)
			)
		)
		(property "Value" ""
			(at 0 0 0)
			(layer "B.Fab")
			(effects
				(font
					(size 1.27 1.27)
				)
				(justify mirror)
			)
		)
		(duplicate_pad_numbers_are_jumpers no)
		(fp_line
			(start 0.7874 0.4064)
			(end 0.7874 -0.4064)
			(stroke
				(width 0.1524)
				(type default)
			)
			(layer "B.SilkS")
		)
		(fp_line
			(start 0.7874 -0.4064)
			(end -0.7874 -0.4064)
			(stroke
				(width 0.1524)
				(type default)
			)
			(layer "B.SilkS")
		)
		(fp_line
			(start -0.7874 0.4064)
			(end 0.7874 0.4064)
			(stroke
				(width 0.1524)
				(type default)
			)
			(layer "B.SilkS")
		)
		(fp_line
			(start -0.7874 -0.4064)
			(end -0.7874 0.4064)
			(stroke
				(width 0.1524)
				(type default)
			)
			(layer "B.SilkS")
		)
		(fp_line
			(start 0.67945 0.3048)
			(end 0.67945 -0.305054)
			(stroke
				(width 0.1)
				(type default)
			)
			(layer "B.Fab")
		)
		(fp_line
			(start 0.67945 -0.305054)
			(end 0.12065 -0.305054)
			(stroke
				(width 0.1)
				(type default)
			)
			(layer "B.Fab")
		)
		(fp_line
			(start 0.12065 0.3048)
			(end 0.67945 0.3048)
			(stroke
				(width 0.1)
				(type default)
			)
			(layer "B.Fab")
		)
		(fp_line
			(start 0.12065 0.2794)
			(end 0.12065 0.3048)
			(stroke
				(width 0.1)
				(type default)
			)
			(layer "B.Fab")
		)
		(fp_line
			(start 0.12065 -0.2794)
			(end -0.12065 -0.2794)
			(stroke
				(width 0.1)
				(type default)
			)
			(layer "B.Fab")
		)
		(fp_line
			(start 0.12065 -0.305054)
			(end 0.12065 -0.2794)
			(stroke
				(width 0.1)
				(type default)
			)
			(layer "B.Fab")
		)
		(fp_line
			(start -0.120396 0.3048)
			(end -0.120396 0.2794)
			(stroke
				(width 0.1)
				(type default)
			)
			(layer "B.Fab")
		)
		(fp_line
			(start -0.120396 0.2794)
			(end 0.12065 0.2794)
			(stroke
				(width 0.1)
				(type default)
			)
			(layer "B.Fab")
		)
		(fp_line
			(start -0.12065 -0.2794)
			(end -0.12065 -0.3048)
			(stroke
				(width 0.1)
				(type default)
			)
			(layer "B.Fab")
		)
		(fp_line
			(start -0.12065 -0.3048)
			(end -0.67945 -0.3048)
			(stroke
				(width 0.1)
				(type default)
			)
			(layer "B.Fab")
		)
		(fp_line
			(start -0.67945 0.3048)
			(end -0.120396 0.3048)
			(stroke
				(width 0.1)
				(type default)
			)
			(layer "B.Fab")
		)
		(fp_line
			(start -0.67945 -0.3048)
			(end -0.67945 0.3048)
			(stroke
				(width 0.1)
				(type default)
			)
			(layer "B.Fab")
		)
		(pad "1" smd circle
			(at 0.40005 0)
			(size 0 0)
			(layers "B.Cu" "B.Mask" "B.Paste")
			(net "P3V3_AUX")
		)
		(pad "2" smd circle
			(at -0.40005 0)
			(size 0 0)
			(layers "B.Cu" "B.Mask" "B.Paste")
			(net "GND")
		)
	)
	(footprint ""
		(layer "B.Cu")
		(at 291.004498 -400.999452 -90)
		(property "Reference" "PR2521"
			(at 0 0 90)
			(layer "B.SilkS")
			(hide yes)
			(effects
				(font
					(size 1.27 1.27)
				)
				(justify mirror)
			)
		)
		(property "Value" ""
			(at 0 0 90)
			(layer "B.Fab")
			(effects
				(font
					(size 1.27 1.27)
				)
				(justify mirror)
			)
		)
		(duplicate_pad_numbers_are_jumpers no)
		(fp_line
			(start -0.7874 0.4064)
			(end 0.7874 0.4064)
			(stroke
				(width 0.1524)
				(type default)
			)
			(layer "B.SilkS")
		)
		(fp_line
			(start 0.7874 0.4064)
			(end 0.7874 -0.4064)
			(stroke
				(width 0.1524)
				(type default)
			)
			(layer "B.SilkS")
		)
		(fp_line
			(start -0.7874 -0.4064)
			(end -0.7874 0.4064)
			(stroke
				(width 0.1524)
				(type default)
			)
			(layer "B.SilkS")
		)
		(fp_line
			(start 0.7874 -0.4064)
			(end -0.7874 -0.4064)
			(stroke
				(width 0.1524)
				(type default)
			)
			(layer "B.SilkS")
		)
		(fp_line
			(start -0.67945 0.3048)
			(end -0.120396 0.3048)
			(stroke
				(width 0.1)
				(type default)
			)
			(layer "B.Fab")
		)
		(fp_line
			(start -0.120396 0.3048)
			(end -0.120396 0.2794)
			(stroke
				(width 0.1)
				(type default)
			)
			(layer "B.Fab")
		)
		(fp_line
			(start 0.12065 0.3048)
			(end 0.67945 0.3048)
			(stroke
				(width 0.1)
				(type default)
			)
			(layer "B.Fab")
		)
		(fp_line
			(start 0.67945 0.3048)
			(end 0.67945 -0.305054)
			(stroke
				(width 0.1)
				(type default)
			)
			(layer "B.Fab")
		)
		(fp_line
			(start -0.120396 0.2794)
			(end 0.12065 0.2794)
			(stroke
				(width 0.1)
				(type default)
			)
			(layer "B.Fab")
		)
		(fp_line
			(start 0.12065 0.2794)
			(end 0.12065 0.3048)
			(stroke
				(width 0.1)
				(type default)
			)
			(layer "B.Fab")
		)
		(fp_line
			(start -0.12065 -0.2794)
			(end -0.12065 -0.3048)
			(stroke
				(width 0.1)
				(type default)
			)
			(layer "B.Fab")
		)
		(fp_line
			(start 0.12065 -0.2794)
			(end -0.12065 -0.2794)
			(stroke
				(width 0.1)
				(type default)
			)
			(layer "B.Fab")
		)
		(fp_line
			(start -0.67945 -0.3048)
			(end -0.67945 0.3048)
			(stroke
				(width 0.1)
				(type default)
			)
			(layer "B.Fab")
		)
		(fp_line
			(start -0.12065 -0.3048)
			(end -0.67945 -0.3048)
			(stroke
				(width 0.1)
				(type default)
			)
			(layer "B.Fab")
		)
		(fp_line
			(start 0.12065 -0.305054)
			(end 0.12065 -0.2794)
			(stroke
				(width 0.1)
				(type default)
			)
			(layer "B.Fab")
		)
		(fp_line
			(start 0.67945 -0.305054)
			(end 0.12065 -0.305054)
			(stroke
				(width 0.1)
				(type default)
			)
			(layer "B.Fab")
		)
		(pad "1" smd circle
			(at 0.40005 0 90)
			(size 0 0)
			(layers "B.Cu" "B.Mask" "B.Paste")
			(net "P12V_HSC_SENSE2_P")
		)
		(pad "2" smd circle
			(at -0.40005 0 90)
			(size 0 0)
			(layers "B.Cu" "B.Mask" "B.Paste")
			(net "P12V_HSC_SENSE2_R2_P")
		)
	)
	(footprint ""
		(layer "B.Cu")
		(at 176.955704 -114.575336)
		(property "Reference" "C1907"
			(at 0 0 0)
			(layer "B.SilkS")
			(hide yes)
			(effects
				(font
					(size 1.27 1.27)
				)
				(justify mirror)
			)
		)
		(property "Value" ""
			(at 0 0 0)
			(layer "B.Fab")
			(effects
				(font
					(size 1.27 1.27)
				)
				(justify mirror)
			)
		)
		(duplicate_pad_numbers_are_jumpers no)
		(fp_line
			(start -0.69215 -0.2921)
			(end -0.69215 0.2921)
			(stroke
				(width 0.1524)
				(type default)
			)
			(layer "B.SilkS")
		)
		(fp_line
			(start -0.69215 0.2921)
			(end 0.69215 0.2921)
			(stroke
				(width 0.1524)
				(type default)
			)
			(layer "B.SilkS")
		)
		(fp_line
			(start 0.69215 -0.2921)
			(end -0.69215 -0.2921)
			(stroke
				(width 0.1524)
				(type default)
			)
			(layer "B.SilkS")
		)
		(fp_line
			(start 0.69215 0.2921)
			(end 0.69215 -0.2921)
			(stroke
				(width 0.1524)
				(type default)
			)
			(layer "B.SilkS")
		)
		(fp_line
			(start -0.51435 -0.2794)
			(end -0.51435 0.2794)
			(stroke
				(width 0.1)
				(type default)
			)
			(layer "B.Fab")
		)
		(fp_line
			(start -0.51435 0.2794)
			(end 0.51435 0.2794)
			(stroke
				(width 0.1)
				(type default)
			)
			(layer "B.Fab")
		)
		(fp_line
			(start 0.51435 -0.2794)
			(end -0.51435 -0.2794)
			(stroke
				(width 0.1)
				(type default)
			)
			(layer "B.Fab")
		)
		(fp_line
			(start 0.51435 0.2794)
			(end 0.51435 -0.2794)
			(stroke
				(width 0.1)
				(type default)
			)
			(layer "B.Fab")
		)
		(pad "1" smd circle
			(at 0.40005 0 180)
			(size 0 0)
			(layers "B.Cu" "B.Mask" "B.Paste")
			(net "VCC_PLD_CORE")
		)
		(pad "2" smd circle
			(at -0.40005 0 180)
			(size 0 0)
			(layers "B.Cu" "B.Mask" "B.Paste")
			(net "GND")
		)
		(zone
			(layer "B.Cu")
			(hatch none 0.5)
			(connect_pads
				(clearance 0)
			)
			(min_thickness 0.25)
			(keepout
				(tracks not_allowed)
				(vias allowed)
				(pads allowed)
				(copperpour not_allowed)
				(footprints allowed)
			)
			(placement
				(enabled no)
				(sheetname "")
			)
			(fill
				(thermal_gap 0.5)
				(thermal_bridge_width 0.5)
				(island_removal_mode 0)
			)
			(polygon
				(pts
					(xy 177.146204 -114.487706) (xy 177.054764 -114.42954) (xy 176.855374 -114.42954) (xy 176.765204 -114.487706)
					(xy 176.765204 -114.662966) (xy 176.855374 -114.721386) (xy 177.054764 -114.721386) (xy 177.146204 -114.66322)
				)
			)
		)
	)
	(footprint ""
		(layer "B.Cu")
		(at 359.960418 -294.009826)
		(property "Reference" "C374"
			(at 0 0 0)
			(layer "B.SilkS")
			(hide yes)
			(effects
				(font
					(size 1.27 1.27)
				)
				(justify mirror)
			)
		)
		(property "Value" ""
			(at 0 0 0)
			(layer "B.Fab")
			(effects
				(font
					(size 1.27 1.27)
				)
				(justify mirror)
			)
		)
		(duplicate_pad_numbers_are_jumpers no)
		(fp_line
			(start -1.524 -0.762)
			(end -1.524 0.762)
			(stroke
				(width 0.1524)
				(type default)
			)
			(layer "B.SilkS")
		)
		(fp_line
			(start -1.524 0.762)
			(end 1.524 0.762)
			(stroke
				(width 0.1524)
				(type default)
			)
			(layer "B.SilkS")
		)
		(fp_line
			(start 1.524 -0.762)
			(end -1.524 -0.762)
			(stroke
				(width 0.1524)
				(type default)
			)
			(layer "B.SilkS")
		)
		(fp_line
			(start 1.524 0.762)
			(end 1.524 -0.762)
			(stroke
				(width 0.1524)
				(type default)
			)
			(layer "B.SilkS")
		)
		(fp_line
			(start -1.1049 -0.724916)
			(end 1.1049 -0.724916)
			(stroke
				(width 0.1)
				(type default)
			)
			(layer "B.Fab")
		)
		(fp_line
			(start -1.1049 0.724916)
			(end -1.1049 -0.724916)
			(stroke
				(width 0.1)
				(type default)
			)
			(layer "B.Fab")
		)
		(fp_line
			(start 1.1049 -0.724916)
			(end 1.1049 0.724916)
			(stroke
				(width 0.1)
				(type default)
			)
			(layer "B.Fab")
		)
		(fp_line
			(start 1.1049 0.724916)
			(end -1.1049 0.724916)
			(stroke
				(width 0.1)
				(type default)
			)
			(layer "B.Fab")
		)
		(pad "1" smd rect
			(at 0.889 0)
			(size 1.016 1.27)
			(layers "B.Cu" "B.Mask" "B.Paste")
			(net "PVCCIN_CPU0")
		)
		(pad "2" smd rect
			(at -0.889 0)
			(size 1.016 1.27)
			(layers "B.Cu" "B.Mask" "B.Paste")
			(net "GND")
		)
	)
	(footprint ""
		(layer "B.Cu")
		(at 250.30303 -44.979082 90)
		(property "Reference" "R3958"
			(at 0 0 90)
			(layer "B.SilkS")
			(hide yes)
			(effects
				(font
					(size 1.27 1.27)
				)
				(justify mirror)
			)
		)
		(property "Value" ""
			(at 0 0 90)
			(layer "B.Fab")
			(effects
				(font
					(size 1.27 1.27)
				)
				(justify mirror)
			)
		)
		(duplicate_pad_numbers_are_jumpers no)
		(fp_line
			(start 0.7874 -0.4064)
			(end -0.7874 -0.4064)
			(stroke
				(width 0.1524)
				(type default)
			)
			(layer "B.SilkS")
		)
		(fp_line
			(start -0.7874 -0.4064)
			(end -0.7874 0.4064)
			(stroke
				(width 0.1524)
				(type default)
			)
			(layer "B.SilkS")
		)
		(fp_line
			(start 0.7874 0.4064)
			(end 0.7874 -0.4064)
			(stroke
				(width 0.1524)
				(type default)
			)
			(layer "B.SilkS")
		)
		(fp_line
			(start -0.7874 0.4064)
			(end 0.7874 0.4064)
			(stroke
				(width 0.1524)
				(type default)
			)
			(layer "B.SilkS")
		)
		(fp_line
			(start 0.67945 -0.305054)
			(end 0.12065 -0.305054)
			(stroke
				(width 0.1)
				(type default)
			)
			(layer "B.Fab")
		)
		(fp_line
			(start 0.12065 -0.305054)
			(end 0.12065 -0.2794)
			(stroke
				(width 0.1)
				(type default)
			)
			(layer "B.Fab")
		)
		(fp_line
			(start -0.12065 -0.3048)
			(end -0.67945 -0.3048)
			(stroke
				(width 0.1)
				(type default)
			)
			(layer "B.Fab")
		)
		(fp_line
			(start -0.67945 -0.3048)
			(end -0.67945 0.3048)
			(stroke
				(width 0.1)
				(type default)
			)
			(layer "B.Fab")
		)
		(fp_line
			(start 0.12065 -0.2794)
			(end -0.12065 -0.2794)
			(stroke
				(width 0.1)
				(type default)
			)
			(layer "B.Fab")
		)
		(fp_line
			(start -0.12065 -0.2794)
			(end -0.12065 -0.3048)
			(stroke
				(width 0.1)
				(type default)
			)
			(layer "B.Fab")
		)
		(fp_line
			(start 0.12065 0.2794)
			(end 0.12065 0.3048)
			(stroke
				(width 0.1)
				(type default)
			)
			(layer "B.Fab")
		)
		(fp_line
			(start -0.120396 0.2794)
			(end 0.12065 0.2794)
			(stroke
				(width 0.1)
				(type default)
			)
			(layer "B.Fab")
		)
		(fp_line
			(start 0.67945 0.3048)
			(end 0.67945 -0.305054)
			(stroke
				(width 0.1)
				(type default)
			)
			(layer "B.Fab")
		)
		(fp_line
			(start 0.12065 0.3048)
			(end 0.67945 0.3048)
			(stroke
				(width 0.1)
				(type default)
			)
			(layer "B.Fab")
		)
		(fp_line
			(start -0.120396 0.3048)
			(end -0.120396 0.2794)
			(stroke
				(width 0.1)
				(type default)
			)
			(layer "B.Fab")
		)
		(fp_line
			(start -0.67945 0.3048)
			(end -0.120396 0.3048)
			(stroke
				(width 0.1)
				(type default)
			)
			(layer "B.Fab")
		)
		(pad "1" smd circle
			(at 0.40005 0 270)
			(size 0 0)
			(layers "B.Cu" "B.Mask" "B.Paste")
			(net "P12V_E1S_UV_0_R")
		)
		(pad "2" smd circle
			(at -0.40005 0 270)
			(size 0 0)
			(layers "B.Cu" "B.Mask" "B.Paste")
			(net "P12V_E1S_UV_0")
		)
	)
	(footprint ""
		(layer "B.Cu")
		(at 369.477036 -187.181744)
		(property "Reference" "U28"
			(at -0.760476 -4.318254 0)
			(unlocked yes)
			(layer "B.SilkS")
			(effects
				(font
					(size 0.7874 0.5842)
					(thickness 0.1524)
				)
				(justify left mirror)
			)
		)
		(property "Value" ""
			(at 0 0 0)
			(layer "B.Fab")
			(effects
				(font
					(size 1.27 1.27)
				)
				(justify mirror)
			)
		)
		(duplicate_pad_numbers_are_jumpers no)
		(fp_line
			(start -1.463548 -1.549908)
			(end -1.463548 1.549908)
			(stroke
				(width 0.1524)
				(type default)
			)
			(layer "B.SilkS")
		)
		(fp_line
			(start -1.463548 1.549908)
			(end 1.463548 1.549908)
			(stroke
				(width 0.1524)
				(type default)
			)
			(layer "B.SilkS")
		)
		(fp_line
			(start -0.762 -1.549908)
			(end -1.463548 -1.549908)
			(stroke
				(width 0.1524)
				(type default)
			)
			(layer "B.SilkS")
		)
		(fp_line
			(start 0 -0.762)
			(end -0.762 -1.549908)
			(stroke
				(width 0.1524)
				(type default)
			)
			(layer "B.SilkS")
		)
		(fp_line
			(start 0.787908 -1.549908)
			(end 0 -0.762)
			(stroke
				(width 0.1524)
				(type default)
			)
			(layer "B.SilkS")
		)
		(fp_line
			(start 1.463548 -1.549908)
			(end 0.787908 -1.549908)
			(stroke
				(width 0.1524)
				(type default)
			)
			(layer "B.SilkS")
		)
		(fp_line
			(start 1.463548 1.549908)
			(end 1.463548 -1.549908)
			(stroke
				(width 0.1524)
				(type default)
			)
			(layer "B.SilkS")
		)
		(fp_poly
			(pts
				(xy 2.848356 -2.227326) (xy 3.360674 -1.878584) (xy 2.7559 -1.54051)
			)
			(stroke
				(width 0)
				(type default)
			)
			(fill yes)
			(layer "B.SilkS")
		)
		(fp_line
			(start -1.549908 -1.549908)
			(end -1.549908 1.549908)
			(stroke
				(width 0.1)
				(type default)
			)
			(layer "B.Fab")
		)
		(fp_line
			(start -1.549908 1.549908)
			(end 1.549908 1.549908)
			(stroke
				(width 0.1)
				(type default)
			)
			(layer "B.Fab")
		)
		(fp_line
			(start 1.549908 -1.549908)
			(end -1.549908 -1.549908)
			(stroke
				(width 0.1)
				(type default)
			)
			(layer "B.Fab")
		)
		(fp_line
			(start 1.549908 1.549908)
			(end 1.549908 -1.549908)
			(stroke
				(width 0.1)
				(type default)
			)
			(layer "B.Fab")
		)
		(fp_poly
			(pts
				(xy 3.4798 -1.359916) (xy 2.86004 -1.050036) (xy 3.4798 -0.740156)
			)
			(stroke
				(width 0)
				(type default)
			)
			(fill yes)
			(layer "B.Fab")
		)
		(pad "1" smd rect
			(at 2.175002 -1.050036 90)
			(size 0.6096 1.1684)
			(layers "B.Cu" "B.Mask" "B.Paste")
			(net "PVNN_TERM_CPU0")
		)
		(pad "2" smd rect
			(at 2.175002 -0.32512 90)
			(size 0.4318 1.1684)
			(layers "B.Cu" "B.Mask" "B.Paste")
			(net "SMB_PEHPCPU0_GTL_R_SCL")
		)
		(pad "3" smd rect
			(at 2.175002 0.32512 90)
			(size 0.4318 1.1684)
			(layers "B.Cu" "B.Mask" "B.Paste")
			(net "SMB_PEHPCPU0_GTL_R_SDA")
		)
		(pad "4" smd rect
			(at 2.175002 1.050036 90)
			(size 0.6096 1.1684)
			(layers "B.Cu" "B.Mask" "B.Paste")
			(net "GND")
		)
		(pad "5" smd rect
			(at -2.175002 1.050036 90)
			(size 0.6096 1.1684)
			(layers "B.Cu" "B.Mask" "B.Paste")
			(net "TP_SMB_PEHPCPU0_EN")
		)
		(pad "6" smd rect
			(at -2.175002 0.32512 90)
			(size 0.4318 1.1684)
			(layers "B.Cu" "B.Mask" "B.Paste")
			(net "SMB_PEHPCPU0_LVC3_SDA_R0")
		)
		(pad "7" smd rect
			(at -2.175002 -0.32512 90)
			(size 0.4318 1.1684)
			(layers "B.Cu" "B.Mask" "B.Paste")
			(net "SMB_PEHPCPU0_LVC3_SCL_R0")
		)
		(pad "8" smd rect
			(at -2.175002 -1.050036 90)
			(size 0.6096 1.1684)
			(layers "B.Cu" "B.Mask" "B.Paste")
			(net "P3V3_AUX")
		)
	)
	(footprint ""
		(layer "B.Cu")
		(at 111.310928 -210.194144)
		(property "Reference" "C455"
			(at 0 0 0)
			(layer "B.SilkS")
			(hide yes)
			(effects
				(font
					(size 1.27 1.27)
				)
				(justify mirror)
			)
		)
		(property "Value" ""
			(at 0 0 0)
			(layer "B.Fab")
			(effects
				(font
					(size 1.27 1.27)
				)
				(justify mirror)
			)
		)
		(duplicate_pad_numbers_are_jumpers no)
		(fp_line
			(start -1.524 -0.762)
			(end -1.524 0.762)
			(stroke
				(width 0.1524)
				(type default)
			)
			(layer "B.SilkS")
		)
		(fp_line
			(start -1.524 0.762)
			(end 1.524 0.762)
			(stroke
				(width 0.1524)
				(type default)
			)
			(layer "B.SilkS")
		)
		(fp_line
			(start 1.524 -0.762)
			(end -1.524 -0.762)
			(stroke
				(width 0.1524)
				(type default)
			)
			(layer "B.SilkS")
		)
		(fp_line
			(start 1.524 0.762)
			(end 1.524 -0.762)
			(stroke
				(width 0.1524)
				(type default)
			)
			(layer "B.SilkS")
		)
		(fp_line
			(start -1.1049 -0.724916)
			(end 1.1049 -0.724916)
			(stroke
				(width 0.1)
				(type default)
			)
			(layer "B.Fab")
		)
		(fp_line
			(start -1.1049 0.724916)
			(end -1.1049 -0.724916)
			(stroke
				(width 0.1)
				(type default)
			)
			(layer "B.Fab")
		)
		(fp_line
			(start 1.1049 -0.724916)
			(end 1.1049 0.724916)
			(stroke
				(width 0.1)
				(type default)
			)
			(layer "B.Fab")
		)
		(fp_line
			(start 1.1049 0.724916)
			(end -1.1049 0.724916)
			(stroke
				(width 0.1)
				(type default)
			)
			(layer "B.Fab")
		)
		(pad "1" smd rect
			(at 0.889 0)
			(size 1.016 1.27)
			(layers "B.Cu" "B.Mask" "B.Paste")
			(net "PVCCD_HV_CPU1")
		)
		(pad "2" smd rect
			(at -0.889 0)
			(size 1.016 1.27)
			(layers "B.Cu" "B.Mask" "B.Paste")
			(net "GND")
		)
	)
	(footprint ""
		(layer "B.Cu")
		(at 205.434438 -110.47095 -90)
		(property "Reference" "R128"
			(at 0 0 90)
			(layer "B.SilkS")
			(hide yes)
			(effects
				(font
					(size 1.27 1.27)
				)
				(justify mirror)
			)
		)
		(property "Value" ""
			(at 0 0 90)
			(layer "B.Fab")
			(effects
				(font
					(size 1.27 1.27)
				)
				(justify mirror)
			)
		)
		(duplicate_pad_numbers_are_jumpers no)
		(fp_line
			(start -0.7874 0.4064)
			(end 0.7874 0.4064)
			(stroke
				(width 0.1524)
				(type default)
			)
			(layer "B.SilkS")
		)
		(fp_line
			(start 0.7874 0.4064)
			(end 0.7874 -0.4064)
			(stroke
				(width 0.1524)
				(type default)
			)
			(layer "B.SilkS")
		)
		(fp_line
			(start -0.7874 -0.4064)
			(end -0.7874 0.4064)
			(stroke
				(width 0.1524)
				(type default)
			)
			(layer "B.SilkS")
		)
		(fp_line
			(start 0.7874 -0.4064)
			(end -0.7874 -0.4064)
			(stroke
				(width 0.1524)
				(type default)
			)
			(layer "B.SilkS")
		)
		(fp_line
			(start -0.67945 0.3048)
			(end -0.120396 0.3048)
			(stroke
				(width 0.1)
				(type default)
			)
			(layer "B.Fab")
		)
		(fp_line
			(start -0.120396 0.3048)
			(end -0.120396 0.2794)
			(stroke
				(width 0.1)
				(type default)
			)
			(layer "B.Fab")
		)
		(fp_line
			(start 0.12065 0.3048)
			(end 0.67945 0.3048)
			(stroke
				(width 0.1)
				(type default)
			)
			(layer "B.Fab")
		)
		(fp_line
			(start 0.67945 0.3048)
			(end 0.67945 -0.305054)
			(stroke
				(width 0.1)
				(type default)
			)
			(layer "B.Fab")
		)
		(fp_line
			(start -0.120396 0.2794)
			(end 0.12065 0.2794)
			(stroke
				(width 0.1)
				(type default)
			)
			(layer "B.Fab")
		)
		(fp_line
			(start 0.12065 0.2794)
			(end 0.12065 0.3048)
			(stroke
				(width 0.1)
				(type default)
			)
			(layer "B.Fab")
		)
		(fp_line
			(start -0.12065 -0.2794)
			(end -0.12065 -0.3048)
			(stroke
				(width 0.1)
				(type default)
			)
			(layer "B.Fab")
		)
		(fp_line
			(start 0.12065 -0.2794)
			(end -0.12065 -0.2794)
			(stroke
				(width 0.1)
				(type default)
			)
			(layer "B.Fab")
		)
		(fp_line
			(start -0.67945 -0.3048)
			(end -0.67945 0.3048)
			(stroke
				(width 0.1)
				(type default)
			)
			(layer "B.Fab")
		)
		(fp_line
			(start -0.12065 -0.3048)
			(end -0.67945 -0.3048)
			(stroke
				(width 0.1)
				(type default)
			)
			(layer "B.Fab")
		)
		(fp_line
			(start 0.12065 -0.305054)
			(end 0.12065 -0.2794)
			(stroke
				(width 0.1)
				(type default)
			)
			(layer "B.Fab")
		)
		(fp_line
			(start 0.67945 -0.305054)
			(end 0.12065 -0.305054)
			(stroke
				(width 0.1)
				(type default)
			)
			(layer "B.Fab")
		)
		(pad "1" smd circle
			(at 0.40005 0 90)
			(size 0 0)
			(layers "B.Cu" "B.Mask" "B.Paste")
			(net "PWRGD_DRAMPWRGD_CPU1_GH_R_LVC1")
		)
		(pad "2" smd circle
			(at -0.40005 0 90)
			(size 0 0)
			(layers "B.Cu" "B.Mask" "B.Paste")
			(net "PWRGD_DRAMPWRGD_CPU1_GH_LVC1_R2")
		)
	)
	(footprint ""
		(layer "B.Cu")
		(at 192.795906 -72.804528)
		(property "Reference" "C1827"
			(at 0 0 0)
			(layer "B.SilkS")
			(hide yes)
			(effects
				(font
					(size 1.27 1.27)
				)
				(justify mirror)
			)
		)
		(property "Value" ""
			(at 0 0 0)
			(layer "B.Fab")
			(effects
				(font
					(size 1.27 1.27)
				)
				(justify mirror)
			)
		)
		(duplicate_pad_numbers_are_jumpers no)
		(fp_line
			(start -0.7874 -0.4064)
			(end -0.7874 0.4064)
			(stroke
				(width 0.1524)
				(type default)
			)
			(layer "B.SilkS")
		)
		(fp_line
			(start -0.7874 0.4064)
			(end 0.7874 0.4064)
			(stroke
				(width 0.1524)
				(type default)
			)
			(layer "B.SilkS")
		)
		(fp_line
			(start 0.7874 -0.4064)
			(end -0.7874 -0.4064)
			(stroke
				(width 0.1524)
				(type default)
			)
			(layer "B.SilkS")
		)
		(fp_line
			(start 0.7874 0.4064)
			(end 0.7874 -0.4064)
			(stroke
				(width 0.1524)
				(type default)
			)
			(layer "B.SilkS")
		)
		(fp_line
			(start -0.67945 -0.3048)
			(end -0.67945 0.3048)
			(stroke
				(width 0.1)
				(type default)
			)
			(layer "B.Fab")
		)
		(fp_line
			(start -0.67945 0.3048)
			(end -0.120396 0.3048)
			(stroke
				(width 0.1)
				(type default)
			)
			(layer "B.Fab")
		)
		(fp_line
			(start -0.12065 -0.3048)
			(end -0.67945 -0.3048)
			(stroke
				(width 0.1)
				(type default)
			)
			(layer "B.Fab")
		)
		(fp_line
			(start -0.12065 -0.2794)
			(end -0.12065 -0.3048)
			(stroke
				(width 0.1)
				(type default)
			)
			(layer "B.Fab")
		)
		(fp_line
			(start -0.120396 0.2794)
			(end 0.12065 0.2794)
			(stroke
				(width 0.1)
				(type default)
			)
			(layer "B.Fab")
		)
		(fp_line
			(start -0.120396 0.3048)
			(end -0.120396 0.2794)
			(stroke
				(width 0.1)
				(type default)
			)
			(layer "B.Fab")
		)
		(fp_line
			(start 0.12065 -0.305054)
			(end 0.12065 -0.2794)
			(stroke
				(width 0.1)
				(type default)
			)
			(layer "B.Fab")
		)
		(fp_line
			(start 0.12065 -0.2794)
			(end -0.12065 -0.2794)
			(stroke
				(width 0.1)
				(type default)
			)
			(layer "B.Fab")
		)
		(fp_line
			(start 0.12065 0.2794)
			(end 0.12065 0.3048)
			(stroke
				(width 0.1)
				(type default)
			)
			(layer "B.Fab")
		)
		(fp_line
			(start 0.12065 0.3048)
			(end 0.67945 0.3048)
			(stroke
				(width 0.1)
				(type default)
			)
			(layer "B.Fab")
		)
		(fp_line
			(start 0.67945 -0.305054)
			(end 0.12065 -0.305054)
			(stroke
				(width 0.1)
				(type default)
			)
			(layer "B.Fab")
		)
		(fp_line
			(start 0.67945 0.3048)
			(end 0.67945 -0.305054)
			(stroke
				(width 0.1)
				(type default)
			)
			(layer "B.Fab")
		)
		(pad "1" smd circle
			(at 0.40005 0 180)
			(size 0 0)
			(layers "B.Cu" "B.Mask" "B.Paste")
			(net "P3V3_AUX")
		)
		(pad "2" smd circle
			(at -0.40005 0 180)
			(size 0 0)
			(layers "B.Cu" "B.Mask" "B.Paste")
			(net "GND")
		)
	)
	(footprint ""
		(layer "B.Cu")
		(at 340.879938 -44.364402 -149.993)
		(property "Reference" "R495"
			(at 0 0 30.007)
			(layer "B.SilkS")
			(hide yes)
			(effects
				(font
					(size 1.27 1.27)
				)
				(justify mirror)
			)
		)
		(property "Value" ""
			(at 0 0 30.007)
			(layer "B.Fab")
			(effects
				(font
					(size 1.27 1.27)
				)
				(justify mirror)
			)
		)
		(duplicate_pad_numbers_are_jumpers no)
		(fp_line
			(start 0.787502 0.406396)
			(end 0.787346 -0.406469)
			(stroke
				(width 0.1524)
				(type default)
			)
			(layer "B.SilkS")
		)
		(fp_line
			(start 0.787346 -0.406469)
			(end -0.787502 -0.406396)
			(stroke
				(width 0.1524)
				(type default)
			)
			(layer "B.SilkS")
		)
		(fp_line
			(start -0.787346 0.406469)
			(end 0.787502 0.406396)
			(stroke
				(width 0.1524)
				(type default)
			)
			(layer "B.SilkS")
		)
		(fp_line
			(start -0.787502 -0.406396)
			(end -0.787346 0.406469)
			(stroke
				(width 0.1524)
				(type default)
			)
			(layer "B.SilkS")
		)
		(fp_line
			(start 0.67959 0.304771)
			(end 0.679513 -0.305075)
			(stroke
				(width 0.1)
				(type default)
			)
			(layer "B.Fab")
		)
		(fp_line
			(start 0.679513 -0.305075)
			(end 0.120769 -0.30511)
			(stroke
				(width 0.1)
				(type default)
			)
			(layer "B.Fab")
		)
		(fp_line
			(start 0.120499 0.304828)
			(end 0.67959 0.304771)
			(stroke
				(width 0.1)
				(type default)
			)
			(layer "B.Fab")
		)
		(fp_line
			(start 0.120552 0.279341)
			(end 0.120499 0.304828)
			(stroke
				(width 0.1)
				(type default)
			)
			(layer "B.Fab")
		)
		(fp_line
			(start -0.120295 0.304798)
			(end -0.120368 0.27953)
			(stroke
				(width 0.1)
				(type default)
			)
			(layer "B.Fab")
		)
		(fp_line
			(start -0.120368 0.27953)
			(end 0.120552 0.279341)
			(stroke
				(width 0.1)
				(type default)
			)
			(layer "B.Fab")
		)
		(fp_line
			(start 0.120588 -0.279403)
			(end -0.120552 -0.279341)
			(stroke
				(width 0.1)
				(type default)
			)
			(layer "B.Fab")
		)
		(fp_line
			(start 0.120769 -0.30511)
			(end 0.120588 -0.279403)
			(stroke
				(width 0.1)
				(type default)
			)
			(layer "B.Fab")
		)
		(fp_line
			(start -0.120552 -0.279341)
			(end -0.120499 -0.304828)
			(stroke
				(width 0.1)
				(type default)
			)
			(layer "B.Fab")
		)
		(fp_line
			(start -0.120499 -0.304828)
			(end -0.67959 -0.304771)
			(stroke
				(width 0.1)
				(type default)
			)
			(layer "B.Fab")
		)
		(fp_line
			(start -0.679386 0.304855)
			(end -0.120295 0.304798)
			(stroke
				(width 0.1)
				(type default)
			)
			(layer "B.Fab")
		)
		(fp_line
			(start -0.67959 -0.304771)
			(end -0.679386 0.304855)
			(stroke
				(width 0.1)
				(type default)
			)
			(layer "B.Fab")
		)
		(pad "1" smd circle
			(at 0.40005 0 30.007)
			(size 0 0)
			(layers "B.Cu" "B.Mask" "B.Paste")
			(net "PCH_PCIEUP_RCOMPP")
		)
		(pad "2" smd circle
			(at -0.40005 0 30.007)
			(size 0 0)
			(layers "B.Cu" "B.Mask" "B.Paste")
			(net "PCH_PCIEUP_RCOMPN")
		)
	)
	(footprint ""
		(layer "B.Cu")
		(at 372.41988 -43.144948)
		(property "Reference" "R2508"
			(at 0 0 0)
			(layer "B.SilkS")
			(hide yes)
			(effects
				(font
					(size 1.27 1.27)
				)
				(justify mirror)
			)
		)
		(property "Value" ""
			(at 0 0 0)
			(layer "B.Fab")
			(effects
				(font
					(size 1.27 1.27)
				)
				(justify mirror)
			)
		)
		(duplicate_pad_numbers_are_jumpers no)
		(fp_line
			(start -0.7874 -0.4064)
			(end -0.7874 0.4064)
			(stroke
				(width 0.1524)
				(type default)
			)
			(layer "B.SilkS")
		)
		(fp_line
			(start -0.7874 0.4064)
			(end 0.7874 0.4064)
			(stroke
				(width 0.1524)
				(type default)
			)
			(layer "B.SilkS")
		)
		(fp_line
			(start 0.7874 -0.4064)
			(end -0.7874 -0.4064)
			(stroke
				(width 0.1524)
				(type default)
			)
			(layer "B.SilkS")
		)
		(fp_line
			(start 0.7874 0.4064)
			(end 0.7874 -0.4064)
			(stroke
				(width 0.1524)
				(type default)
			)
			(layer "B.SilkS")
		)
		(fp_line
			(start -0.67945 -0.3048)
			(end -0.67945 0.3048)
			(stroke
				(width 0.1)
				(type default)
			)
			(layer "B.Fab")
		)
		(fp_line
			(start -0.67945 0.3048)
			(end -0.120396 0.3048)
			(stroke
				(width 0.1)
				(type default)
			)
			(layer "B.Fab")
		)
		(fp_line
			(start -0.12065 -0.3048)
			(end -0.67945 -0.3048)
			(stroke
				(width 0.1)
				(type default)
			)
			(layer "B.Fab")
		)
		(fp_line
			(start -0.12065 -0.2794)
			(end -0.12065 -0.3048)
			(stroke
				(width 0.1)
				(type default)
			)
			(layer "B.Fab")
		)
		(fp_line
			(start -0.120396 0.2794)
			(end 0.12065 0.2794)
			(stroke
				(width 0.1)
				(type default)
			)
			(layer "B.Fab")
		)
		(fp_line
			(start -0.120396 0.3048)
			(end -0.120396 0.2794)
			(stroke
				(width 0.1)
				(type default)
			)
			(layer "B.Fab")
		)
		(fp_line
			(start 0.12065 -0.305054)
			(end 0.12065 -0.2794)
			(stroke
				(width 0.1)
				(type default)
			)
			(layer "B.Fab")
		)
		(fp_line
			(start 0.12065 -0.2794)
			(end -0.12065 -0.2794)
			(stroke
				(width 0.1)
				(type default)
			)
			(layer "B.Fab")
		)
		(fp_line
			(start 0.12065 0.2794)
			(end 0.12065 0.3048)
			(stroke
				(width 0.1)
				(type default)
			)
			(layer "B.Fab")
		)
		(fp_line
			(start 0.12065 0.3048)
			(end 0.67945 0.3048)
			(stroke
				(width 0.1)
				(type default)
			)
			(layer "B.Fab")
		)
		(fp_line
			(start 0.67945 -0.305054)
			(end 0.12065 -0.305054)
			(stroke
				(width 0.1)
				(type default)
			)
			(layer "B.Fab")
		)
		(fp_line
			(start 0.67945 0.3048)
			(end 0.67945 -0.305054)
			(stroke
				(width 0.1)
				(type default)
			)
			(layer "B.Fab")
		)
		(pad "1" smd circle
			(at 0.40005 0 180)
			(size 0 0)
			(layers "B.Cu" "B.Mask" "B.Paste")
			(net "P3V3_AUX")
		)
		(pad "2" smd circle
			(at -0.40005 0 180)
			(size 0 0)
			(layers "B.Cu" "B.Mask" "B.Paste")
			(net "FM_M2_SSD0_E7_PEDET")
		)
	)
	(footprint ""
		(layer "B.Cu")
		(at 179.9082 -106.76255 -90)
		(property "Reference" "C1899"
			(at 0 0 90)
			(layer "B.SilkS")
			(hide yes)
			(effects
				(font
					(size 1.27 1.27)
				)
				(justify mirror)
			)
		)
		(property "Value" ""
			(at 0 0 90)
			(layer "B.Fab")
			(effects
				(font
					(size 1.27 1.27)
				)
				(justify mirror)
			)
		)
		(duplicate_pad_numbers_are_jumpers no)
		(fp_line
			(start -0.69215 0.2921)
			(end 0.69215 0.2921)
			(stroke
				(width 0.1524)
				(type default)
			)
			(layer "B.SilkS")
		)
		(fp_line
			(start 0.69215 0.2921)
			(end 0.69215 -0.2921)
			(stroke
				(width 0.1524)
				(type default)
			)
			(layer "B.SilkS")
		)
		(fp_line
			(start -0.69215 -0.2921)
			(end -0.69215 0.2921)
			(stroke
				(width 0.1524)
				(type default)
			)
			(layer "B.SilkS")
		)
		(fp_line
			(start 0.69215 -0.2921)
			(end -0.69215 -0.2921)
			(stroke
				(width 0.1524)
				(type default)
			)
			(layer "B.SilkS")
		)
		(fp_line
			(start -0.51435 0.2794)
			(end 0.51435 0.2794)
			(stroke
				(width 0.1)
				(type default)
			)
			(layer "B.Fab")
		)
		(fp_line
			(start 0.51435 0.2794)
			(end 0.51435 -0.2794)
			(stroke
				(width 0.1)
				(type default)
			)
			(layer "B.Fab")
		)
		(fp_line
			(start -0.51435 -0.2794)
			(end -0.51435 0.2794)
			(stroke
				(width 0.1)
				(type default)
			)
			(layer "B.Fab")
		)
		(fp_line
			(start 0.51435 -0.2794)
			(end -0.51435 -0.2794)
			(stroke
				(width 0.1)
				(type default)
			)
			(layer "B.Fab")
		)
		(pad "1" smd circle
			(at 0.40005 0 90)
			(size 0 0)
			(layers "B.Cu" "B.Mask" "B.Paste")
			(net "P3V3_AUX_FPGA_VCCIO4")
		)
		(pad "2" smd circle
			(at -0.40005 0 90)
			(size 0 0)
			(layers "B.Cu" "B.Mask" "B.Paste")
			(net "GND")
		)
		(zone
			(layer "B.Cu")
			(hatch none 0.5)
			(connect_pads
				(clearance 0)
			)
			(min_thickness 0.25)
			(keepout
				(tracks not_allowed)
				(vias allowed)
				(pads allowed)
				(copperpour not_allowed)
				(footprints allowed)
			)
			(placement
				(enabled no)
				(sheetname "")
			)
			(fill
				(thermal_gap 0.5)
				(thermal_bridge_width 0.5)
				(island_removal_mode 0)
			)
			(polygon
				(pts
					(xy 179.82057 -106.57205) (xy 179.762404 -106.66349) (xy 179.762404 -106.86288) (xy 179.82057 -106.95305)
					(xy 179.99583 -106.95305) (xy 180.05425 -106.86288) (xy 180.05425 -106.66349) (xy 179.996084 -106.57205)
				)
			)
		)
	)
	(footprint ""
		(layer "B.Cu")
		(at 336.494882 -188.393578)
		(property "Reference" "R679"
			(at 0 0 0)
			(layer "B.SilkS")
			(hide yes)
			(effects
				(font
					(size 1.27 1.27)
				)
				(justify mirror)
			)
		)
		(property "Value" ""
			(at 0 0 0)
			(layer "B.Fab")
			(effects
				(font
					(size 1.27 1.27)
				)
				(justify mirror)
			)
		)
		(duplicate_pad_numbers_are_jumpers no)
		(fp_line
			(start -0.7874 -0.4064)
			(end -0.7874 0.4064)
			(stroke
				(width 0.1524)
				(type default)
			)
			(layer "B.SilkS")
		)
		(fp_line
			(start -0.7874 0.4064)
			(end 0.7874 0.4064)
			(stroke
				(width 0.1524)
				(type default)
			)
			(layer "B.SilkS")
		)
		(fp_line
			(start 0.7874 -0.4064)
			(end -0.7874 -0.4064)
			(stroke
				(width 0.1524)
				(type default)
			)
			(layer "B.SilkS")
		)
		(fp_line
			(start 0.7874 0.4064)
			(end 0.7874 -0.4064)
			(stroke
				(width 0.1524)
				(type default)
			)
			(layer "B.SilkS")
		)
		(fp_line
			(start -0.67945 -0.3048)
			(end -0.67945 0.3048)
			(stroke
				(width 0.1)
				(type default)
			)
			(layer "B.Fab")
		)
		(fp_line
			(start -0.67945 0.3048)
			(end -0.120396 0.3048)
			(stroke
				(width 0.1)
				(type default)
			)
			(layer "B.Fab")
		)
		(fp_line
			(start -0.12065 -0.3048)
			(end -0.67945 -0.3048)
			(stroke
				(width 0.1)
				(type default)
			)
			(layer "B.Fab")
		)
		(fp_line
			(start -0.12065 -0.2794)
			(end -0.12065 -0.3048)
			(stroke
				(width 0.1)
				(type default)
			)
			(layer "B.Fab")
		)
		(fp_line
			(start -0.120396 0.2794)
			(end 0.12065 0.2794)
			(stroke
				(width 0.1)
				(type default)
			)
			(layer "B.Fab")
		)
		(fp_line
			(start -0.120396 0.3048)
			(end -0.120396 0.2794)
			(stroke
				(width 0.1)
				(type default)
			)
			(layer "B.Fab")
		)
		(fp_line
			(start 0.12065 -0.305054)
			(end 0.12065 -0.2794)
			(stroke
				(width 0.1)
				(type default)
			)
			(layer "B.Fab")
		)
		(fp_line
			(start 0.12065 -0.2794)
			(end -0.12065 -0.2794)
			(stroke
				(width 0.1)
				(type default)
			)
			(layer "B.Fab")
		)
		(fp_line
			(start 0.12065 0.2794)
			(end 0.12065 0.3048)
			(stroke
				(width 0.1)
				(type default)
			)
			(layer "B.Fab")
		)
		(fp_line
			(start 0.12065 0.3048)
			(end 0.67945 0.3048)
			(stroke
				(width 0.1)
				(type default)
			)
			(layer "B.Fab")
		)
		(fp_line
			(start 0.67945 -0.305054)
			(end 0.12065 -0.305054)
			(stroke
				(width 0.1)
				(type default)
			)
			(layer "B.Fab")
		)
		(fp_line
			(start 0.67945 0.3048)
			(end 0.67945 -0.305054)
			(stroke
				(width 0.1)
				(type default)
			)
			(layer "B.Fab")
		)
		(pad "1" smd circle
			(at 0.40005 0 180)
			(size 0 0)
			(layers "B.Cu" "B.Mask" "B.Paste")
			(net "PVNN_TERM_CPU0")
		)
		(pad "2" smd circle
			(at -0.40005 0 180)
			(size 0 0)
			(layers "B.Cu" "B.Mask" "B.Paste")
			(net "I3C_SPD_DDRABCD_CPU0_SCL")
		)
	)
	(footprint ""
		(layer "B.Cu")
		(at 160.83788 -122.646948)
		(property "Reference" "R1412"
			(at 0 0 0)
			(layer "B.SilkS")
			(hide yes)
			(effects
				(font
					(size 1.27 1.27)
				)
				(justify mirror)
			)
		)
		(property "Value" ""
			(at 0 0 0)
			(layer "B.Fab")
			(effects
				(font
					(size 1.27 1.27)
				)
				(justify mirror)
			)
		)
		(duplicate_pad_numbers_are_jumpers no)
		(fp_line
			(start -0.7874 -0.4064)
			(end -0.7874 0.4064)
			(stroke
				(width 0.1524)
				(type default)
			)
			(layer "B.SilkS")
		)
		(fp_line
			(start -0.7874 0.4064)
			(end 0.7874 0.4064)
			(stroke
				(width 0.1524)
				(type default)
			)
			(layer "B.SilkS")
		)
		(fp_line
			(start 0.7874 -0.4064)
			(end -0.7874 -0.4064)
			(stroke
				(width 0.1524)
				(type default)
			)
			(layer "B.SilkS")
		)
		(fp_line
			(start 0.7874 0.4064)
			(end 0.7874 -0.4064)
			(stroke
				(width 0.1524)
				(type default)
			)
			(layer "B.SilkS")
		)
		(fp_line
			(start -0.67945 -0.3048)
			(end -0.67945 0.3048)
			(stroke
				(width 0.1)
				(type default)
			)
			(layer "B.Fab")
		)
		(fp_line
			(start -0.67945 0.3048)
			(end -0.120396 0.3048)
			(stroke
				(width 0.1)
				(type default)
			)
			(layer "B.Fab")
		)
		(fp_line
			(start -0.12065 -0.3048)
			(end -0.67945 -0.3048)
			(stroke
				(width 0.1)
				(type default)
			)
			(layer "B.Fab")
		)
		(fp_line
			(start -0.12065 -0.2794)
			(end -0.12065 -0.3048)
			(stroke
				(width 0.1)
				(type default)
			)
			(layer "B.Fab")
		)
		(fp_line
			(start -0.120396 0.2794)
			(end 0.12065 0.2794)
			(stroke
				(width 0.1)
				(type default)
			)
			(layer "B.Fab")
		)
		(fp_line
			(start -0.120396 0.3048)
			(end -0.120396 0.2794)
			(stroke
				(width 0.1)
				(type default)
			)
			(layer "B.Fab")
		)
		(fp_line
			(start 0.12065 -0.305054)
			(end 0.12065 -0.2794)
			(stroke
				(width 0.1)
				(type default)
			)
			(layer "B.Fab")
		)
		(fp_line
			(start 0.12065 -0.2794)
			(end -0.12065 -0.2794)
			(stroke
				(width 0.1)
				(type default)
			)
			(layer "B.Fab")
		)
		(fp_line
			(start 0.12065 0.2794)
			(end 0.12065 0.3048)
			(stroke
				(width 0.1)
				(type default)
			)
			(layer "B.Fab")
		)
		(fp_line
			(start 0.12065 0.3048)
			(end 0.67945 0.3048)
			(stroke
				(width 0.1)
				(type default)
			)
			(layer "B.Fab")
		)
		(fp_line
			(start 0.67945 -0.305054)
			(end 0.12065 -0.305054)
			(stroke
				(width 0.1)
				(type default)
			)
			(layer "B.Fab")
		)
		(fp_line
			(start 0.67945 0.3048)
			(end 0.67945 -0.305054)
			(stroke
				(width 0.1)
				(type default)
			)
			(layer "B.Fab")
		)
		(pad "1" smd circle
			(at 0.40005 0 180)
			(size 0 0)
			(layers "B.Cu" "B.Mask" "B.Paste")
			(net "FM_PVCCFA_EHV_FIVRA_CPU1_R_EN")
		)
		(pad "2" smd circle
			(at -0.40005 0 180)
			(size 0 0)
			(layers "B.Cu" "B.Mask" "B.Paste")
			(net "GND")
		)
	)
	(footprint ""
		(layer "B.Cu")
		(at 301.356014 -319.263776 180)
		(property "Reference" "C2"
			(at 0 0 0)
			(layer "B.SilkS")
			(hide yes)
			(effects
				(font
					(size 1.27 1.27)
				)
				(justify mirror)
			)
		)
		(property "Value" ""
			(at 0 0 0)
			(layer "B.Fab")
			(effects
				(font
					(size 1.27 1.27)
				)
				(justify mirror)
			)
		)
		(duplicate_pad_numbers_are_jumpers no)
		(fp_line
			(start 0.7874 0.4064)
			(end 0.7874 -0.4064)
			(stroke
				(width 0.1524)
				(type default)
			)
			(layer "B.SilkS")
		)
		(fp_line
			(start 0.7874 -0.4064)
			(end -0.7874 -0.4064)
			(stroke
				(width 0.1524)
				(type default)
			)
			(layer "B.SilkS")
		)
		(fp_line
			(start -0.7874 0.4064)
			(end 0.7874 0.4064)
			(stroke
				(width 0.1524)
				(type default)
			)
			(layer "B.SilkS")
		)
		(fp_line
			(start -0.7874 -0.4064)
			(end -0.7874 0.4064)
			(stroke
				(width 0.1524)
				(type default)
			)
			(layer "B.SilkS")
		)
		(fp_line
			(start 0.67945 0.3048)
			(end 0.67945 -0.305054)
			(stroke
				(width 0.1)
				(type default)
			)
			(layer "B.Fab")
		)
		(fp_line
			(start 0.67945 -0.305054)
			(end 0.12065 -0.305054)
			(stroke
				(width 0.1)
				(type default)
			)
			(layer "B.Fab")
		)
		(fp_line
			(start 0.12065 0.3048)
			(end 0.67945 0.3048)
			(stroke
				(width 0.1)
				(type default)
			)
			(layer "B.Fab")
		)
		(fp_line
			(start 0.12065 0.2794)
			(end 0.12065 0.3048)
			(stroke
				(width 0.1)
				(type default)
			)
			(layer "B.Fab")
		)
		(fp_line
			(start 0.12065 -0.2794)
			(end -0.12065 -0.2794)
			(stroke
				(width 0.1)
				(type default)
			)
			(layer "B.Fab")
		)
		(fp_line
			(start 0.12065 -0.305054)
			(end 0.12065 -0.2794)
			(stroke
				(width 0.1)
				(type default)
			)
			(layer "B.Fab")
		)
		(fp_line
			(start -0.120396 0.3048)
			(end -0.120396 0.2794)
			(stroke
				(width 0.1)
				(type default)
			)
			(layer "B.Fab")
		)
		(fp_line
			(start -0.120396 0.2794)
			(end 0.12065 0.2794)
			(stroke
				(width 0.1)
				(type default)
			)
			(layer "B.Fab")
		)
		(fp_line
			(start -0.12065 -0.2794)
			(end -0.12065 -0.3048)
			(stroke
				(width 0.1)
				(type default)
			)
			(layer "B.Fab")
		)
		(fp_line
			(start -0.12065 -0.3048)
			(end -0.67945 -0.3048)
			(stroke
				(width 0.1)
				(type default)
			)
			(layer "B.Fab")
		)
		(fp_line
			(start -0.67945 0.3048)
			(end -0.120396 0.3048)
			(stroke
				(width 0.1)
				(type default)
			)
			(layer "B.Fab")
		)
		(fp_line
			(start -0.67945 -0.3048)
			(end -0.67945 0.3048)
			(stroke
				(width 0.1)
				(type default)
			)
			(layer "B.Fab")
		)
		(pad "1" smd circle
			(at 0.40005 0)
			(size 0 0)
			(layers "B.Cu" "B.Mask" "B.Paste")
			(net "P3V3_AUX")
		)
		(pad "2" smd circle
			(at -0.40005 0)
			(size 0 0)
			(layers "B.Cu" "B.Mask" "B.Paste")
			(net "GND")
		)
	)
	(footprint ""
		(layer "B.Cu")
		(at 106.437938 -236.008164)
		(property "Reference" "C1353"
			(at 0 0 0)
			(layer "B.SilkS")
			(hide yes)
			(effects
				(font
					(size 1.27 1.27)
				)
				(justify mirror)
			)
		)
		(property "Value" ""
			(at 0 0 0)
			(layer "B.Fab")
			(effects
				(font
					(size 1.27 1.27)
				)
				(justify mirror)
			)
		)
		(duplicate_pad_numbers_are_jumpers no)
		(fp_line
			(start -0.7874 -0.4064)
			(end -0.7874 0.4064)
			(stroke
				(width 0.1524)
				(type default)
			)
			(layer "B.SilkS")
		)
		(fp_line
			(start -0.7874 0.4064)
			(end 0.7874 0.4064)
			(stroke
				(width 0.1524)
				(type default)
			)
			(layer "B.SilkS")
		)
		(fp_line
			(start 0.7874 -0.4064)
			(end -0.7874 -0.4064)
			(stroke
				(width 0.1524)
				(type default)
			)
			(layer "B.SilkS")
		)
		(fp_line
			(start 0.7874 0.4064)
			(end 0.7874 -0.4064)
			(stroke
				(width 0.1524)
				(type default)
			)
			(layer "B.SilkS")
		)
		(fp_line
			(start -0.67945 -0.3048)
			(end -0.67945 0.3048)
			(stroke
				(width 0.1)
				(type default)
			)
			(layer "B.Fab")
		)
		(fp_line
			(start -0.67945 0.3048)
			(end -0.120396 0.3048)
			(stroke
				(width 0.1)
				(type default)
			)
			(layer "B.Fab")
		)
		(fp_line
			(start -0.12065 -0.3048)
			(end -0.67945 -0.3048)
			(stroke
				(width 0.1)
				(type default)
			)
			(layer "B.Fab")
		)
		(fp_line
			(start -0.12065 -0.2794)
			(end -0.12065 -0.3048)
			(stroke
				(width 0.1)
				(type default)
			)
			(layer "B.Fab")
		)
		(fp_line
			(start -0.120396 0.2794)
			(end 0.12065 0.2794)
			(stroke
				(width 0.1)
				(type default)
			)
			(layer "B.Fab")
		)
		(fp_line
			(start -0.120396 0.3048)
			(end -0.120396 0.2794)
			(stroke
				(width 0.1)
				(type default)
			)
			(layer "B.Fab")
		)
		(fp_line
			(start 0.12065 -0.305054)
			(end 0.12065 -0.2794)
			(stroke
				(width 0.1)
				(type default)
			)
			(layer "B.Fab")
		)
		(fp_line
			(start 0.12065 -0.2794)
			(end -0.12065 -0.2794)
			(stroke
				(width 0.1)
				(type default)
			)
			(layer "B.Fab")
		)
		(fp_line
			(start 0.12065 0.2794)
			(end 0.12065 0.3048)
			(stroke
				(width 0.1)
				(type default)
			)
			(layer "B.Fab")
		)
		(fp_line
			(start 0.12065 0.3048)
			(end 0.67945 0.3048)
			(stroke
				(width 0.1)
				(type default)
			)
			(layer "B.Fab")
		)
		(fp_line
			(start 0.67945 -0.305054)
			(end 0.12065 -0.305054)
			(stroke
				(width 0.1)
				(type default)
			)
			(layer "B.Fab")
		)
		(fp_line
			(start 0.67945 0.3048)
			(end 0.67945 -0.305054)
			(stroke
				(width 0.1)
				(type default)
			)
			(layer "B.Fab")
		)
		(pad "1" smd circle
			(at 0.40005 0 180)
			(size 0 0)
			(layers "B.Cu" "B.Mask" "B.Paste")
			(net "PVNN_MAIN_CPU1")
		)
		(pad "2" smd circle
			(at -0.40005 0 180)
			(size 0 0)
			(layers "B.Cu" "B.Mask" "B.Paste")
			(net "GND")
		)
	)
	(footprint ""
		(layer "B.Cu")
		(at 118.137178 -241.14379 -90)
		(property "Reference" "C337"
			(at 0 0 90)
			(layer "B.SilkS")
			(hide yes)
			(effects
				(font
					(size 1.27 1.27)
				)
				(justify mirror)
			)
		)
		(property "Value" ""
			(at 0 0 90)
			(layer "B.Fab")
			(effects
				(font
					(size 1.27 1.27)
				)
				(justify mirror)
			)
		)
		(duplicate_pad_numbers_are_jumpers no)
		(fp_line
			(start -1.524 0.762)
			(end 1.524 0.762)
			(stroke
				(width 0.1524)
				(type default)
			)
			(layer "B.SilkS")
		)
		(fp_line
			(start 1.524 0.762)
			(end 1.524 -0.762)
			(stroke
				(width 0.1524)
				(type default)
			)
			(layer "B.SilkS")
		)
		(fp_line
			(start -1.524 -0.762)
			(end -1.524 0.762)
			(stroke
				(width 0.1524)
				(type default)
			)
			(layer "B.SilkS")
		)
		(fp_line
			(start 1.524 -0.762)
			(end -1.524 -0.762)
			(stroke
				(width 0.1524)
				(type default)
			)
			(layer "B.SilkS")
		)
		(fp_line
			(start -1.1049 0.724916)
			(end -1.1049 -0.724916)
			(stroke
				(width 0.1)
				(type default)
			)
			(layer "B.Fab")
		)
		(fp_line
			(start 1.1049 0.724916)
			(end -1.1049 0.724916)
			(stroke
				(width 0.1)
				(type default)
			)
			(layer "B.Fab")
		)
		(fp_line
			(start -1.1049 -0.724916)
			(end 1.1049 -0.724916)
			(stroke
				(width 0.1)
				(type default)
			)
			(layer "B.Fab")
		)
		(fp_line
			(start 1.1049 -0.724916)
			(end 1.1049 0.724916)
			(stroke
				(width 0.1)
				(type default)
			)
			(layer "B.Fab")
		)
		(pad "1" smd rect
			(at 0.889 0 270)
			(size 1.016 1.27)
			(layers "B.Cu" "B.Mask" "B.Paste")
			(net "PVCCIN_CPU1")
		)
		(pad "2" smd rect
			(at -0.889 0 270)
			(size 1.016 1.27)
			(layers "B.Cu" "B.Mask" "B.Paste")
			(net "GND")
		)
	)
	(footprint ""
		(layer "B.Cu")
		(at 45.018706 -344.935556 -90)
		(property "Reference" "PC1207_P1_4"
			(at 0 0 90)
			(layer "B.SilkS")
			(hide yes)
			(effects
				(font
					(size 1.27 1.27)
				)
				(justify mirror)
			)
		)
		(property "Value" ""
			(at 0 0 90)
			(layer "B.Fab")
			(effects
				(font
					(size 1.27 1.27)
				)
				(justify mirror)
			)
		)
		(duplicate_pad_numbers_are_jumpers no)
		(fp_line
			(start -1.524 0.762)
			(end 1.524 0.762)
			(stroke
				(width 0.1524)
				(type default)
			)
			(layer "B.SilkS")
		)
		(fp_line
			(start 1.524 0.762)
			(end 1.524 -0.762)
			(stroke
				(width 0.1524)
				(type default)
			)
			(layer "B.SilkS")
		)
		(fp_line
			(start -1.524 -0.762)
			(end -1.524 0.762)
			(stroke
				(width 0.1524)
				(type default)
			)
			(layer "B.SilkS")
		)
		(fp_line
			(start 1.524 -0.762)
			(end -1.524 -0.762)
			(stroke
				(width 0.1524)
				(type default)
			)
			(layer "B.SilkS")
		)
		(fp_line
			(start -1.1049 0.724916)
			(end -1.1049 -0.724916)
			(stroke
				(width 0.1)
				(type default)
			)
			(layer "B.Fab")
		)
		(fp_line
			(start 1.1049 0.724916)
			(end -1.1049 0.724916)
			(stroke
				(width 0.1)
				(type default)
			)
			(layer "B.Fab")
		)
		(fp_line
			(start -1.1049 -0.724916)
			(end 1.1049 -0.724916)
			(stroke
				(width 0.1)
				(type default)
			)
			(layer "B.Fab")
		)
		(fp_line
			(start 1.1049 -0.724916)
			(end 1.1049 0.724916)
			(stroke
				(width 0.1)
				(type default)
			)
			(layer "B.Fab")
		)
		(pad "1" smd rect
			(at 0.889 0 270)
			(size 1.016 1.27)
			(layers "B.Cu" "B.Mask" "B.Paste")
			(net "PVCCFA_EHV_FIVRA_CPU1")
		)
		(pad "2" smd rect
			(at -0.889 0 270)
			(size 1.016 1.27)
			(layers "B.Cu" "B.Mask" "B.Paste")
			(net "GND")
		)
	)
	(footprint ""
		(layer "B.Cu")
		(at 456.003406 -319.232026 180)
		(property "Reference" "R2735"
			(at 0 0 0)
			(layer "B.SilkS")
			(hide yes)
			(effects
				(font
					(size 1.27 1.27)
				)
				(justify mirror)
			)
		)
		(property "Value" ""
			(at 0 0 0)
			(layer "B.Fab")
			(effects
				(font
					(size 1.27 1.27)
				)
				(justify mirror)
			)
		)
		(duplicate_pad_numbers_are_jumpers no)
		(fp_line
			(start 0.7874 0.4064)
			(end 0.7874 -0.4064)
			(stroke
				(width 0.1524)
				(type default)
			)
			(layer "B.SilkS")
		)
		(fp_line
			(start 0.7874 -0.4064)
			(end -0.7874 -0.4064)
			(stroke
				(width 0.1524)
				(type default)
			)
			(layer "B.SilkS")
		)
		(fp_line
			(start -0.7874 0.4064)
			(end 0.7874 0.4064)
			(stroke
				(width 0.1524)
				(type default)
			)
			(layer "B.SilkS")
		)
		(fp_line
			(start -0.7874 -0.4064)
			(end -0.7874 0.4064)
			(stroke
				(width 0.1524)
				(type default)
			)
			(layer "B.SilkS")
		)
		(fp_line
			(start 0.67945 0.3048)
			(end 0.67945 -0.305054)
			(stroke
				(width 0.1)
				(type default)
			)
			(layer "B.Fab")
		)
		(fp_line
			(start 0.67945 -0.305054)
			(end 0.12065 -0.305054)
			(stroke
				(width 0.1)
				(type default)
			)
			(layer "B.Fab")
		)
		(fp_line
			(start 0.12065 0.3048)
			(end 0.67945 0.3048)
			(stroke
				(width 0.1)
				(type default)
			)
			(layer "B.Fab")
		)
		(fp_line
			(start 0.12065 0.2794)
			(end 0.12065 0.3048)
			(stroke
				(width 0.1)
				(type default)
			)
			(layer "B.Fab")
		)
		(fp_line
			(start 0.12065 -0.2794)
			(end -0.12065 -0.2794)
			(stroke
				(width 0.1)
				(type default)
			)
			(layer "B.Fab")
		)
		(fp_line
			(start 0.12065 -0.305054)
			(end 0.12065 -0.2794)
			(stroke
				(width 0.1)
				(type default)
			)
			(layer "B.Fab")
		)
		(fp_line
			(start -0.120396 0.3048)
			(end -0.120396 0.2794)
			(stroke
				(width 0.1)
				(type default)
			)
			(layer "B.Fab")
		)
		(fp_line
			(start -0.120396 0.2794)
			(end 0.12065 0.2794)
			(stroke
				(width 0.1)
				(type default)
			)
			(layer "B.Fab")
		)
		(fp_line
			(start -0.12065 -0.2794)
			(end -0.12065 -0.3048)
			(stroke
				(width 0.1)
				(type default)
			)
			(layer "B.Fab")
		)
		(fp_line
			(start -0.12065 -0.3048)
			(end -0.67945 -0.3048)
			(stroke
				(width 0.1)
				(type default)
			)
			(layer "B.Fab")
		)
		(fp_line
			(start -0.67945 0.3048)
			(end -0.120396 0.3048)
			(stroke
				(width 0.1)
				(type default)
			)
			(layer "B.Fab")
		)
		(fp_line
			(start -0.67945 -0.3048)
			(end -0.67945 0.3048)
			(stroke
				(width 0.1)
				(type default)
			)
			(layer "B.Fab")
		)
		(pad "1" smd circle
			(at 0.40005 0)
			(size 0 0)
			(layers "B.Cu" "B.Mask" "B.Paste")
			(net "PWRGD_CHH_CPU0_DIMM2")
		)
		(pad "2" smd circle
			(at -0.40005 0)
			(size 0 0)
			(layers "B.Cu" "B.Mask" "B.Paste")
			(net "PWRGD_FAIL_CPU0_GH")
		)
	)
	(footprint ""
		(layer "B.Cu")
		(at 293.812214 -319.263776 180)
		(property "Reference" "C11"
			(at 0 0 0)
			(layer "B.SilkS")
			(hide yes)
			(effects
				(font
					(size 1.27 1.27)
				)
				(justify mirror)
			)
		)
		(property "Value" ""
			(at 0 0 0)
			(layer "B.Fab")
			(effects
				(font
					(size 1.27 1.27)
				)
				(justify mirror)
			)
		)
		(duplicate_pad_numbers_are_jumpers no)
		(fp_line
			(start 0.7874 0.4064)
			(end 0.7874 -0.4064)
			(stroke
				(width 0.1524)
				(type default)
			)
			(layer "B.SilkS")
		)
		(fp_line
			(start 0.7874 -0.4064)
			(end -0.7874 -0.4064)
			(stroke
				(width 0.1524)
				(type default)
			)
			(layer "B.SilkS")
		)
		(fp_line
			(start -0.7874 0.4064)
			(end 0.7874 0.4064)
			(stroke
				(width 0.1524)
				(type default)
			)
			(layer "B.SilkS")
		)
		(fp_line
			(start -0.7874 -0.4064)
			(end -0.7874 0.4064)
			(stroke
				(width 0.1524)
				(type default)
			)
			(layer "B.SilkS")
		)
		(fp_line
			(start 0.67945 0.3048)
			(end 0.67945 -0.305054)
			(stroke
				(width 0.1)
				(type default)
			)
			(layer "B.Fab")
		)
		(fp_line
			(start 0.67945 -0.305054)
			(end 0.12065 -0.305054)
			(stroke
				(width 0.1)
				(type default)
			)
			(layer "B.Fab")
		)
		(fp_line
			(start 0.12065 0.3048)
			(end 0.67945 0.3048)
			(stroke
				(width 0.1)
				(type default)
			)
			(layer "B.Fab")
		)
		(fp_line
			(start 0.12065 0.2794)
			(end 0.12065 0.3048)
			(stroke
				(width 0.1)
				(type default)
			)
			(layer "B.Fab")
		)
		(fp_line
			(start 0.12065 -0.2794)
			(end -0.12065 -0.2794)
			(stroke
				(width 0.1)
				(type default)
			)
			(layer "B.Fab")
		)
		(fp_line
			(start 0.12065 -0.305054)
			(end 0.12065 -0.2794)
			(stroke
				(width 0.1)
				(type default)
			)
			(layer "B.Fab")
		)
		(fp_line
			(start -0.120396 0.3048)
			(end -0.120396 0.2794)
			(stroke
				(width 0.1)
				(type default)
			)
			(layer "B.Fab")
		)
		(fp_line
			(start -0.120396 0.2794)
			(end 0.12065 0.2794)
			(stroke
				(width 0.1)
				(type default)
			)
			(layer "B.Fab")
		)
		(fp_line
			(start -0.12065 -0.2794)
			(end -0.12065 -0.3048)
			(stroke
				(width 0.1)
				(type default)
			)
			(layer "B.Fab")
		)
		(fp_line
			(start -0.12065 -0.3048)
			(end -0.67945 -0.3048)
			(stroke
				(width 0.1)
				(type default)
			)
			(layer "B.Fab")
		)
		(fp_line
			(start -0.67945 0.3048)
			(end -0.120396 0.3048)
			(stroke
				(width 0.1)
				(type default)
			)
			(layer "B.Fab")
		)
		(fp_line
			(start -0.67945 -0.3048)
			(end -0.67945 0.3048)
			(stroke
				(width 0.1)
				(type default)
			)
			(layer "B.Fab")
		)
		(pad "1" smd circle
			(at 0.40005 0)
			(size 0 0)
			(layers "B.Cu" "B.Mask" "B.Paste")
			(net "P3V3_AUX")
		)
		(pad "2" smd circle
			(at -0.40005 0)
			(size 0 0)
			(layers "B.Cu" "B.Mask" "B.Paste")
			(net "GND")
		)
	)
	(footprint ""
		(layer "B.Cu")
		(at 175.44288 -123.948698 -90)
		(property "Reference" "C1939"
			(at 0 0 90)
			(layer "B.SilkS")
			(hide yes)
			(effects
				(font
					(size 1.27 1.27)
				)
				(justify mirror)
			)
		)
		(property "Value" ""
			(at 0 0 90)
			(layer "B.Fab")
			(effects
				(font
					(size 1.27 1.27)
				)
				(justify mirror)
			)
		)
		(duplicate_pad_numbers_are_jumpers no)
		(fp_line
			(start -0.7874 0.4064)
			(end 0.7874 0.4064)
			(stroke
				(width 0.1524)
				(type default)
			)
			(layer "B.SilkS")
		)
		(fp_line
			(start 0.7874 0.4064)
			(end 0.7874 -0.4064)
			(stroke
				(width 0.1524)
				(type default)
			)
			(layer "B.SilkS")
		)
		(fp_line
			(start -0.7874 -0.4064)
			(end -0.7874 0.4064)
			(stroke
				(width 0.1524)
				(type default)
			)
			(layer "B.SilkS")
		)
		(fp_line
			(start 0.7874 -0.4064)
			(end -0.7874 -0.4064)
			(stroke
				(width 0.1524)
				(type default)
			)
			(layer "B.SilkS")
		)
		(fp_line
			(start -0.67945 0.3048)
			(end -0.120396 0.3048)
			(stroke
				(width 0.1)
				(type default)
			)
			(layer "B.Fab")
		)
		(fp_line
			(start -0.120396 0.3048)
			(end -0.120396 0.2794)
			(stroke
				(width 0.1)
				(type default)
			)
			(layer "B.Fab")
		)
		(fp_line
			(start 0.12065 0.3048)
			(end 0.67945 0.3048)
			(stroke
				(width 0.1)
				(type default)
			)
			(layer "B.Fab")
		)
		(fp_line
			(start 0.67945 0.3048)
			(end 0.67945 -0.305054)
			(stroke
				(width 0.1)
				(type default)
			)
			(layer "B.Fab")
		)
		(fp_line
			(start -0.120396 0.2794)
			(end 0.12065 0.2794)
			(stroke
				(width 0.1)
				(type default)
			)
			(layer "B.Fab")
		)
		(fp_line
			(start 0.12065 0.2794)
			(end 0.12065 0.3048)
			(stroke
				(width 0.1)
				(type default)
			)
			(layer "B.Fab")
		)
		(fp_line
			(start -0.12065 -0.2794)
			(end -0.12065 -0.3048)
			(stroke
				(width 0.1)
				(type default)
			)
			(layer "B.Fab")
		)
		(fp_line
			(start 0.12065 -0.2794)
			(end -0.12065 -0.2794)
			(stroke
				(width 0.1)
				(type default)
			)
			(layer "B.Fab")
		)
		(fp_line
			(start -0.67945 -0.3048)
			(end -0.67945 0.3048)
			(stroke
				(width 0.1)
				(type default)
			)
			(layer "B.Fab")
		)
		(fp_line
			(start -0.12065 -0.3048)
			(end -0.67945 -0.3048)
			(stroke
				(width 0.1)
				(type default)
			)
			(layer "B.Fab")
		)
		(fp_line
			(start 0.12065 -0.305054)
			(end 0.12065 -0.2794)
			(stroke
				(width 0.1)
				(type default)
			)
			(layer "B.Fab")
		)
		(fp_line
			(start 0.67945 -0.305054)
			(end 0.12065 -0.305054)
			(stroke
				(width 0.1)
				(type default)
			)
			(layer "B.Fab")
		)
		(pad "1" smd circle
			(at 0.40005 0 90)
			(size 0 0)
			(layers "B.Cu" "B.Mask" "B.Paste")
			(net "P3V3_AUX_FPGA_VCCIO1")
		)
		(pad "2" smd circle
			(at -0.40005 0 90)
			(size 0 0)
			(layers "B.Cu" "B.Mask" "B.Paste")
			(net "GND")
		)
	)
	(footprint ""
		(layer "B.Cu")
		(at 359.43032 -358.522016)
		(property "Reference" "PR451"
			(at 0 0 0)
			(layer "B.SilkS")
			(hide yes)
			(effects
				(font
					(size 1.27 1.27)
				)
				(justify mirror)
			)
		)
		(property "Value" ""
			(at 0 0 0)
			(layer "B.Fab")
			(effects
				(font
					(size 1.27 1.27)
				)
				(justify mirror)
			)
		)
		(duplicate_pad_numbers_are_jumpers no)
		(fp_line
			(start -0.7874 -0.4064)
			(end -0.7874 0.4064)
			(stroke
				(width 0.1524)
				(type default)
			)
			(layer "B.SilkS")
		)
		(fp_line
			(start -0.7874 0.4064)
			(end 0.7874 0.4064)
			(stroke
				(width 0.1524)
				(type default)
			)
			(layer "B.SilkS")
		)
		(fp_line
			(start 0.7874 -0.4064)
			(end -0.7874 -0.4064)
			(stroke
				(width 0.1524)
				(type default)
			)
			(layer "B.SilkS")
		)
		(fp_line
			(start 0.7874 0.4064)
			(end 0.7874 -0.4064)
			(stroke
				(width 0.1524)
				(type default)
			)
			(layer "B.SilkS")
		)
		(fp_line
			(start -0.67945 -0.3048)
			(end -0.67945 0.3048)
			(stroke
				(width 0.1)
				(type default)
			)
			(layer "B.Fab")
		)
		(fp_line
			(start -0.67945 0.3048)
			(end -0.120396 0.3048)
			(stroke
				(width 0.1)
				(type default)
			)
			(layer "B.Fab")
		)
		(fp_line
			(start -0.12065 -0.3048)
			(end -0.67945 -0.3048)
			(stroke
				(width 0.1)
				(type default)
			)
			(layer "B.Fab")
		)
		(fp_line
			(start -0.12065 -0.2794)
			(end -0.12065 -0.3048)
			(stroke
				(width 0.1)
				(type default)
			)
			(layer "B.Fab")
		)
		(fp_line
			(start -0.120396 0.2794)
			(end 0.12065 0.2794)
			(stroke
				(width 0.1)
				(type default)
			)
			(layer "B.Fab")
		)
		(fp_line
			(start -0.120396 0.3048)
			(end -0.120396 0.2794)
			(stroke
				(width 0.1)
				(type default)
			)
			(layer "B.Fab")
		)
		(fp_line
			(start 0.12065 -0.305054)
			(end 0.12065 -0.2794)
			(stroke
				(width 0.1)
				(type default)
			)
			(layer "B.Fab")
		)
		(fp_line
			(start 0.12065 -0.2794)
			(end -0.12065 -0.2794)
			(stroke
				(width 0.1)
				(type default)
			)
			(layer "B.Fab")
		)
		(fp_line
			(start 0.12065 0.2794)
			(end 0.12065 0.3048)
			(stroke
				(width 0.1)
				(type default)
			)
			(layer "B.Fab")
		)
		(fp_line
			(start 0.12065 0.3048)
			(end 0.67945 0.3048)
			(stroke
				(width 0.1)
				(type default)
			)
			(layer "B.Fab")
		)
		(fp_line
			(start 0.67945 -0.305054)
			(end 0.12065 -0.305054)
			(stroke
				(width 0.1)
				(type default)
			)
			(layer "B.Fab")
		)
		(fp_line
			(start 0.67945 0.3048)
			(end 0.67945 -0.305054)
			(stroke
				(width 0.1)
				(type default)
			)
			(layer "B.Fab")
		)
		(pad "1" smd circle
			(at 0.40005 0 180)
			(size 0 0)
			(layers "B.Cu" "B.Mask" "B.Paste")
			(net "PVCCFA_EHV_FIVRA_CPU0_BTSEN")
		)
		(pad "2" smd circle
			(at -0.40005 0 180)
			(size 0 0)
			(layers "B.Cu" "B.Mask" "B.Paste")
			(net "GND")
		)
	)
	(footprint ""
		(layer "B.Cu")
		(at 179.758848 -406.903682)
		(property "Reference" "R1117"
			(at 0 0 0)
			(layer "B.SilkS")
			(hide yes)
			(effects
				(font
					(size 1.27 1.27)
				)
				(justify mirror)
			)
		)
		(property "Value" ""
			(at 0 0 0)
			(layer "B.Fab")
			(effects
				(font
					(size 1.27 1.27)
				)
				(justify mirror)
			)
		)
		(duplicate_pad_numbers_are_jumpers no)
		(fp_line
			(start -0.7874 -0.4064)
			(end -0.7874 0.4064)
			(stroke
				(width 0.1524)
				(type default)
			)
			(layer "B.SilkS")
		)
		(fp_line
			(start -0.7874 0.4064)
			(end 0.7874 0.4064)
			(stroke
				(width 0.1524)
				(type default)
			)
			(layer "B.SilkS")
		)
		(fp_line
			(start 0.7874 -0.4064)
			(end -0.7874 -0.4064)
			(stroke
				(width 0.1524)
				(type default)
			)
			(layer "B.SilkS")
		)
		(fp_line
			(start 0.7874 0.4064)
			(end 0.7874 -0.4064)
			(stroke
				(width 0.1524)
				(type default)
			)
			(layer "B.SilkS")
		)
		(fp_line
			(start -0.67945 -0.3048)
			(end -0.67945 0.3048)
			(stroke
				(width 0.1)
				(type default)
			)
			(layer "B.Fab")
		)
		(fp_line
			(start -0.67945 0.3048)
			(end -0.120396 0.3048)
			(stroke
				(width 0.1)
				(type default)
			)
			(layer "B.Fab")
		)
		(fp_line
			(start -0.12065 -0.3048)
			(end -0.67945 -0.3048)
			(stroke
				(width 0.1)
				(type default)
			)
			(layer "B.Fab")
		)
		(fp_line
			(start -0.12065 -0.2794)
			(end -0.12065 -0.3048)
			(stroke
				(width 0.1)
				(type default)
			)
			(layer "B.Fab")
		)
		(fp_line
			(start -0.120396 0.2794)
			(end 0.12065 0.2794)
			(stroke
				(width 0.1)
				(type default)
			)
			(layer "B.Fab")
		)
		(fp_line
			(start -0.120396 0.3048)
			(end -0.120396 0.2794)
			(stroke
				(width 0.1)
				(type default)
			)
			(layer "B.Fab")
		)
		(fp_line
			(start 0.12065 -0.305054)
			(end 0.12065 -0.2794)
			(stroke
				(width 0.1)
				(type default)
			)
			(layer "B.Fab")
		)
		(fp_line
			(start 0.12065 -0.2794)
			(end -0.12065 -0.2794)
			(stroke
				(width 0.1)
				(type default)
			)
			(layer "B.Fab")
		)
		(fp_line
			(start 0.12065 0.2794)
			(end 0.12065 0.3048)
			(stroke
				(width 0.1)
				(type default)
			)
			(layer "B.Fab")
		)
		(fp_line
			(start 0.12065 0.3048)
			(end 0.67945 0.3048)
			(stroke
				(width 0.1)
				(type default)
			)
			(layer "B.Fab")
		)
		(fp_line
			(start 0.67945 -0.305054)
			(end 0.12065 -0.305054)
			(stroke
				(width 0.1)
				(type default)
			)
			(layer "B.Fab")
		)
		(fp_line
			(start 0.67945 0.3048)
			(end 0.67945 -0.305054)
			(stroke
				(width 0.1)
				(type default)
			)
			(layer "B.Fab")
		)
		(pad "1" smd circle
			(at 0.40005 0 180)
			(size 0 0)
			(layers "B.Cu" "B.Mask" "B.Paste")
			(net "MB0_P12V_STBY_PWRGD")
		)
		(pad "2" smd circle
			(at -0.40005 0 180)
			(size 0 0)
			(layers "B.Cu" "B.Mask" "B.Paste")
			(net "AGND_HSC")
		)
	)
	(footprint ""
		(layer "B.Cu")
		(at 261.694168 -103.101902)
		(property "Reference" "L14"
			(at 0 0 0)
			(layer "B.SilkS")
			(hide yes)
			(effects
				(font
					(size 1.27 1.27)
				)
				(justify mirror)
			)
		)
		(property "Value" ""
			(at 0 0 0)
			(layer "B.Fab")
			(effects
				(font
					(size 1.27 1.27)
				)
				(justify mirror)
			)
		)
		(duplicate_pad_numbers_are_jumpers no)
		(fp_line
			(start -1.63576 -0.8128)
			(end -1.63576 0.8128)
			(stroke
				(width 0.1524)
				(type default)
			)
			(layer "B.SilkS")
		)
		(fp_line
			(start -1.63576 0.8128)
			(end 1.63576 0.8128)
			(stroke
				(width 0.1524)
				(type default)
			)
			(layer "B.SilkS")
		)
		(fp_line
			(start 1.63576 -0.8128)
			(end -1.63576 -0.8128)
			(stroke
				(width 0.1524)
				(type default)
			)
			(layer "B.SilkS")
		)
		(fp_line
			(start 1.63576 -0.8128)
			(end 1.63576 0.8128)
			(stroke
				(width 0.1524)
				(type default)
			)
			(layer "B.SilkS")
		)
		(fp_line
			(start -1.560576 -0.738632)
			(end 1.56083 -0.738632)
			(stroke
				(width 0.1)
				(type default)
			)
			(layer "B.Fab")
		)
		(fp_line
			(start -1.560576 0.7366)
			(end -1.560576 -0.738632)
			(stroke
				(width 0.1)
				(type default)
			)
			(layer "B.Fab")
		)
		(fp_line
			(start -1.524 0.7366)
			(end -1.560576 0.7366)
			(stroke
				(width 0.1)
				(type default)
			)
			(layer "B.Fab")
		)
		(fp_line
			(start 1.524 0.7366)
			(end -1.524 0.7366)
			(stroke
				(width 0.1)
				(type default)
			)
			(layer "B.Fab")
		)
		(fp_line
			(start 1.56083 -0.738632)
			(end 1.56083 0.7366)
			(stroke
				(width 0.1)
				(type default)
			)
			(layer "B.Fab")
		)
		(fp_line
			(start 1.56083 0.7366)
			(end 1.524 0.7366)
			(stroke
				(width 0.1)
				(type default)
			)
			(layer "B.Fab")
		)
		(pad "1" smd rect
			(at 0.94996 0)
			(size 1.1176 1.3716)
			(layers "B.Cu" "B.Mask" "B.Paste")
			(net "P3V3_AUX")
		)
		(pad "2" smd rect
			(at -0.94996 0)
			(size 1.1176 1.3716)
			(layers "B.Cu" "B.Mask" "B.Paste")
			(net "P3V3_AUX_CLK_GEN_VDDMXCK_CK440")
		)
	)
	(footprint ""
		(layer "B.Cu")
		(at 105.11536 -417.399216 180)
		(property "Reference" "L19"
			(at 0 0 0)
			(layer "B.SilkS")
			(hide yes)
			(effects
				(font
					(size 1.27 1.27)
				)
				(justify mirror)
			)
		)
		(property "Value" ""
			(at 0 0 0)
			(layer "B.Fab")
			(effects
				(font
					(size 1.27 1.27)
				)
				(justify mirror)
			)
		)
		(duplicate_pad_numbers_are_jumpers no)
		(fp_line
			(start 1.63576 -0.8128)
			(end 1.63576 0.8128)
			(stroke
				(width 0.1524)
				(type default)
			)
			(layer "B.SilkS")
		)
		(fp_line
			(start 1.63576 -0.8128)
			(end -1.63576 -0.8128)
			(stroke
				(width 0.1524)
				(type default)
			)
			(layer "B.SilkS")
		)
		(fp_line
			(start -1.63576 0.8128)
			(end 1.63576 0.8128)
			(stroke
				(width 0.1524)
				(type default)
			)
			(layer "B.SilkS")
		)
		(fp_line
			(start -1.63576 -0.8128)
			(end -1.63576 0.8128)
			(stroke
				(width 0.1524)
				(type default)
			)
			(layer "B.SilkS")
		)
		(fp_line
			(start 1.56083 0.7366)
			(end 1.524 0.7366)
			(stroke
				(width 0.1)
				(type default)
			)
			(layer "B.Fab")
		)
		(fp_line
			(start 1.56083 -0.738632)
			(end 1.56083 0.7366)
			(stroke
				(width 0.1)
				(type default)
			)
			(layer "B.Fab")
		)
		(fp_line
			(start 1.524 0.7366)
			(end -1.524 0.7366)
			(stroke
				(width 0.1)
				(type default)
			)
			(layer "B.Fab")
		)
		(fp_line
			(start -1.524 0.7366)
			(end -1.560576 0.7366)
			(stroke
				(width 0.1)
				(type default)
			)
			(layer "B.Fab")
		)
		(fp_line
			(start -1.560576 0.7366)
			(end -1.560576 -0.738632)
			(stroke
				(width 0.1)
				(type default)
			)
			(layer "B.Fab")
		)
		(fp_line
			(start -1.560576 -0.738632)
			(end 1.56083 -0.738632)
			(stroke
				(width 0.1)
				(type default)
			)
			(layer "B.Fab")
		)
		(pad "1" smd rect
			(at 0.94996 0 180)
			(size 1.1176 1.3716)
			(layers "B.Cu" "B.Mask" "B.Paste")
			(net "P3V3")
		)
		(pad "2" smd rect
			(at -0.94996 0 180)
			(size 1.1176 1.3716)
			(layers "B.Cu" "B.Mask" "B.Paste")
			(net "P3V3_9ZXL045")
		)
	)
	(footprint ""
		(layer "B.Cu")
		(at 350.158812 -337.853782)
		(property "Reference" "PR154"
			(at 0 0 0)
			(layer "B.SilkS")
			(hide yes)
			(effects
				(font
					(size 1.27 1.27)
				)
				(justify mirror)
			)
		)
		(property "Value" ""
			(at 0 0 0)
			(layer "B.Fab")
			(effects
				(font
					(size 1.27 1.27)
				)
				(justify mirror)
			)
		)
		(duplicate_pad_numbers_are_jumpers no)
		(fp_line
			(start -0.7874 -0.4064)
			(end -0.7874 0.4064)
			(stroke
				(width 0.1524)
				(type default)
			)
			(layer "B.SilkS")
		)
		(fp_line
			(start -0.7874 0.4064)
			(end 0.7874 0.4064)
			(stroke
				(width 0.1524)
				(type default)
			)
			(layer "B.SilkS")
		)
		(fp_line
			(start 0.7874 -0.4064)
			(end -0.7874 -0.4064)
			(stroke
				(width 0.1524)
				(type default)
			)
			(layer "B.SilkS")
		)
		(fp_line
			(start 0.7874 0.4064)
			(end 0.7874 -0.4064)
			(stroke
				(width 0.1524)
				(type default)
			)
			(layer "B.SilkS")
		)
		(fp_line
			(start -0.67945 -0.3048)
			(end -0.67945 0.3048)
			(stroke
				(width 0.1)
				(type default)
			)
			(layer "B.Fab")
		)
		(fp_line
			(start -0.67945 0.3048)
			(end -0.120396 0.3048)
			(stroke
				(width 0.1)
				(type default)
			)
			(layer "B.Fab")
		)
		(fp_line
			(start -0.12065 -0.3048)
			(end -0.67945 -0.3048)
			(stroke
				(width 0.1)
				(type default)
			)
			(layer "B.Fab")
		)
		(fp_line
			(start -0.12065 -0.2794)
			(end -0.12065 -0.3048)
			(stroke
				(width 0.1)
				(type default)
			)
			(layer "B.Fab")
		)
		(fp_line
			(start -0.120396 0.2794)
			(end 0.12065 0.2794)
			(stroke
				(width 0.1)
				(type default)
			)
			(layer "B.Fab")
		)
		(fp_line
			(start -0.120396 0.3048)
			(end -0.120396 0.2794)
			(stroke
				(width 0.1)
				(type default)
			)
			(layer "B.Fab")
		)
		(fp_line
			(start 0.12065 -0.305054)
			(end 0.12065 -0.2794)
			(stroke
				(width 0.1)
				(type default)
			)
			(layer "B.Fab")
		)
		(fp_line
			(start 0.12065 -0.2794)
			(end -0.12065 -0.2794)
			(stroke
				(width 0.1)
				(type default)
			)
			(layer "B.Fab")
		)
		(fp_line
			(start 0.12065 0.2794)
			(end 0.12065 0.3048)
			(stroke
				(width 0.1)
				(type default)
			)
			(layer "B.Fab")
		)
		(fp_line
			(start 0.12065 0.3048)
			(end 0.67945 0.3048)
			(stroke
				(width 0.1)
				(type default)
			)
			(layer "B.Fab")
		)
		(fp_line
			(start 0.67945 -0.305054)
			(end 0.12065 -0.305054)
			(stroke
				(width 0.1)
				(type default)
			)
			(layer "B.Fab")
		)
		(fp_line
			(start 0.67945 0.3048)
			(end 0.67945 -0.305054)
			(stroke
				(width 0.1)
				(type default)
			)
			(layer "B.Fab")
		)
		(pad "1" smd circle
			(at 0.40005 0 180)
			(size 0 0)
			(layers "B.Cu" "B.Mask" "B.Paste")
			(net "PVCCIN_CPU0_VOS2")
		)
		(pad "2" smd circle
			(at -0.40005 0 180)
			(size 0 0)
			(layers "B.Cu" "B.Mask" "B.Paste")
			(net "PVCCIN_CPU0")
		)
	)
	(footprint ""
		(layer "B.Cu")
		(at 449.526914 -8.344916 -90)
		(property "Reference" "R415"
			(at 0 0 90)
			(layer "B.SilkS")
			(hide yes)
			(effects
				(font
					(size 1.27 1.27)
				)
				(justify mirror)
			)
		)
		(property "Value" ""
			(at 0 0 90)
			(layer "B.Fab")
			(effects
				(font
					(size 1.27 1.27)
				)
				(justify mirror)
			)
		)
		(duplicate_pad_numbers_are_jumpers no)
		(fp_line
			(start -0.7874 0.4064)
			(end 0.7874 0.4064)
			(stroke
				(width 0.1524)
				(type default)
			)
			(layer "B.SilkS")
		)
		(fp_line
			(start 0.7874 0.4064)
			(end 0.7874 -0.4064)
			(stroke
				(width 0.1524)
				(type default)
			)
			(layer "B.SilkS")
		)
		(fp_line
			(start -0.7874 -0.4064)
			(end -0.7874 0.4064)
			(stroke
				(width 0.1524)
				(type default)
			)
			(layer "B.SilkS")
		)
		(fp_line
			(start 0.7874 -0.4064)
			(end -0.7874 -0.4064)
			(stroke
				(width 0.1524)
				(type default)
			)
			(layer "B.SilkS")
		)
		(fp_line
			(start -0.67945 0.3048)
			(end -0.120396 0.3048)
			(stroke
				(width 0.1)
				(type default)
			)
			(layer "B.Fab")
		)
		(fp_line
			(start -0.120396 0.3048)
			(end -0.120396 0.2794)
			(stroke
				(width 0.1)
				(type default)
			)
			(layer "B.Fab")
		)
		(fp_line
			(start 0.12065 0.3048)
			(end 0.67945 0.3048)
			(stroke
				(width 0.1)
				(type default)
			)
			(layer "B.Fab")
		)
		(fp_line
			(start 0.67945 0.3048)
			(end 0.67945 -0.305054)
			(stroke
				(width 0.1)
				(type default)
			)
			(layer "B.Fab")
		)
		(fp_line
			(start -0.120396 0.2794)
			(end 0.12065 0.2794)
			(stroke
				(width 0.1)
				(type default)
			)
			(layer "B.Fab")
		)
		(fp_line
			(start 0.12065 0.2794)
			(end 0.12065 0.3048)
			(stroke
				(width 0.1)
				(type default)
			)
			(layer "B.Fab")
		)
		(fp_line
			(start -0.12065 -0.2794)
			(end -0.12065 -0.3048)
			(stroke
				(width 0.1)
				(type default)
			)
			(layer "B.Fab")
		)
		(fp_line
			(start 0.12065 -0.2794)
			(end -0.12065 -0.2794)
			(stroke
				(width 0.1)
				(type default)
			)
			(layer "B.Fab")
		)
		(fp_line
			(start -0.67945 -0.3048)
			(end -0.67945 0.3048)
			(stroke
				(width 0.1)
				(type default)
			)
			(layer "B.Fab")
		)
		(fp_line
			(start -0.12065 -0.3048)
			(end -0.67945 -0.3048)
			(stroke
				(width 0.1)
				(type default)
			)
			(layer "B.Fab")
		)
		(fp_line
			(start 0.12065 -0.305054)
			(end 0.12065 -0.2794)
			(stroke
				(width 0.1)
				(type default)
			)
			(layer "B.Fab")
		)
		(fp_line
			(start 0.67945 -0.305054)
			(end 0.12065 -0.305054)
			(stroke
				(width 0.1)
				(type default)
			)
			(layer "B.Fab")
		)
		(pad "1" smd circle
			(at 0.40005 0 90)
			(size 0 0)
			(layers "B.Cu" "B.Mask" "B.Paste")
			(net "OCP_SFF_ID1")
		)
		(pad "2" smd circle
			(at -0.40005 0 90)
			(size 0 0)
			(layers "B.Cu" "B.Mask" "B.Paste")
			(net "GND")
		)
	)
	(footprint ""
		(layer "B.Cu")
		(at 113.677954 -326.99706 -90)
		(property "Reference" "PC1990"
			(at 0 0 90)
			(layer "B.SilkS")
			(hide yes)
			(effects
				(font
					(size 1.27 1.27)
				)
				(justify mirror)
			)
		)
		(property "Value" ""
			(at 0 0 90)
			(layer "B.Fab")
			(effects
				(font
					(size 1.27 1.27)
				)
				(justify mirror)
			)
		)
		(duplicate_pad_numbers_are_jumpers no)
		(fp_line
			(start -4.533392 2.249932)
			(end 4.533392 2.249932)
			(stroke
				(width 0.1524)
				(type default)
			)
			(layer "B.SilkS")
		)
		(fp_line
			(start 4.533392 2.249932)
			(end 4.533392 -2.249932)
			(stroke
				(width 0.1524)
				(type default)
			)
			(layer "B.SilkS")
		)
		(fp_line
			(start -4.533392 -2.249932)
			(end -4.533392 2.249932)
			(stroke
				(width 0.1524)
				(type default)
			)
			(layer "B.SilkS")
		)
		(fp_line
			(start 4.533392 -2.249932)
			(end -4.533392 -2.249932)
			(stroke
				(width 0.1524)
				(type default)
			)
			(layer "B.SilkS")
		)
		(fp_rect
			(start 5.39242 2.326132)
			(end 4.533392 -2.326132)
			(stroke
				(width 0)
				(type default)
			)
			(fill yes)
			(layer "B.SilkS")
		)
		(fp_line
			(start -3.750056 2.249932)
			(end 3.750056 2.249932)
			(stroke
				(width 0.1)
				(type default)
			)
			(layer "B.Fab")
		)
		(fp_line
			(start 3.750056 2.249932)
			(end 3.750056 -2.249932)
			(stroke
				(width 0.1)
				(type default)
			)
			(layer "B.Fab")
		)
		(fp_line
			(start -3.750056 -2.249932)
			(end -3.750056 2.249932)
			(stroke
				(width 0.1)
				(type default)
			)
			(layer "B.Fab")
		)
		(fp_line
			(start 3.750056 -2.249932)
			(end -3.750056 -2.249932)
			(stroke
				(width 0.1)
				(type default)
			)
			(layer "B.Fab")
		)
		(fp_text user "-"
			(at -4.719828 1.309624 270)
			(unlocked yes)
			(layer "B.SilkS")
			(effects
				(font
					(size 1.905 1.4224)
					(thickness 0.1524)
				)
				(justify left mirror)
			)
		)
		(fp_text user "+"
			(at 6.322314 0.786384 180)
			(unlocked yes)
			(layer "B.SilkS")
			(effects
				(font
					(size 1.905 1.4224)
					(thickness 0.1524)
				)
				(justify left mirror)
			)
		)
		(fp_text user "+"
			(at 6.322314 0.786384 180)
			(unlocked yes)
			(layer "B.Fab")
			(effects
				(font
					(size 1.905 1.4224)
					(thickness 0.1524)
				)
				(justify left mirror)
			)
		)
		(fp_text user "-"
			(at -4.8514 -0.14605 270)
			(unlocked yes)
			(layer "B.Fab")
			(effects
				(font
					(size 1.905 1.4224)
					(thickness 0.1524)
				)
				(justify left mirror)
			)
		)
		(pad "1" smd rect
			(at 3.199892 0 90)
			(size 2.413 2.8194)
			(layers "B.Cu" "B.Mask" "B.Paste")
			(net "PVCCIN_CPU1")
		)
		(pad "2" smd rect
			(at -3.199892 0 90)
			(size 2.413 2.8194)
			(layers "B.Cu" "B.Mask" "B.Paste")
			(net "GND")
		)
	)
	(footprint ""
		(layer "B.Cu")
		(at 293.812214 -321.549776 -90)
		(property "Reference" "C12"
			(at 0 0 90)
			(layer "B.SilkS")
			(hide yes)
			(effects
				(font
					(size 1.27 1.27)
				)
				(justify mirror)
			)
		)
		(property "Value" ""
			(at 0 0 90)
			(layer "B.Fab")
			(effects
				(font
					(size 1.27 1.27)
				)
				(justify mirror)
			)
		)
		(duplicate_pad_numbers_are_jumpers no)
		(fp_line
			(start -1.524 0.762)
			(end 1.524 0.762)
			(stroke
				(width 0.1524)
				(type default)
			)
			(layer "B.SilkS")
		)
		(fp_line
			(start 1.524 0.762)
			(end 1.524 -0.762)
			(stroke
				(width 0.1524)
				(type default)
			)
			(layer "B.SilkS")
		)
		(fp_line
			(start -1.524 -0.762)
			(end -1.524 0.762)
			(stroke
				(width 0.1524)
				(type default)
			)
			(layer "B.SilkS")
		)
		(fp_line
			(start 1.524 -0.762)
			(end -1.524 -0.762)
			(stroke
				(width 0.1524)
				(type default)
			)
			(layer "B.SilkS")
		)
		(fp_line
			(start -1.1049 0.724916)
			(end -1.1049 -0.724916)
			(stroke
				(width 0.1)
				(type default)
			)
			(layer "B.Fab")
		)
		(fp_line
			(start 1.1049 0.724916)
			(end -1.1049 0.724916)
			(stroke
				(width 0.1)
				(type default)
			)
			(layer "B.Fab")
		)
		(fp_line
			(start -1.1049 -0.724916)
			(end 1.1049 -0.724916)
			(stroke
				(width 0.1)
				(type default)
			)
			(layer "B.Fab")
		)
		(fp_line
			(start 1.1049 -0.724916)
			(end 1.1049 0.724916)
			(stroke
				(width 0.1)
				(type default)
			)
			(layer "B.Fab")
		)
		(pad "1" smd rect
			(at 0.889 0 270)
			(size 1.016 1.27)
			(layers "B.Cu" "B.Mask" "B.Paste")
			(net "P12V_S3_AUX_CPU0_NVDIMM")
		)
		(pad "2" smd rect
			(at -0.889 0 270)
			(size 1.016 1.27)
			(layers "B.Cu" "B.Mask" "B.Paste")
			(net "GND")
		)
	)
	(footprint ""
		(layer "B.Cu")
		(at 31.94304 -166.25316 90)
		(property "Reference" "PC814"
			(at 0 0 90)
			(layer "B.SilkS")
			(hide yes)
			(effects
				(font
					(size 1.27 1.27)
				)
				(justify mirror)
			)
		)
		(property "Value" ""
			(at 0 0 90)
			(layer "B.Fab")
			(effects
				(font
					(size 1.27 1.27)
				)
				(justify mirror)
			)
		)
		(duplicate_pad_numbers_are_jumpers no)
		(fp_line
			(start 0.7874 -0.4064)
			(end -0.7874 -0.4064)
			(stroke
				(width 0.1524)
				(type default)
			)
			(layer "B.SilkS")
		)
		(fp_line
			(start -0.7874 -0.4064)
			(end -0.7874 0.4064)
			(stroke
				(width 0.1524)
				(type default)
			)
			(layer "B.SilkS")
		)
		(fp_line
			(start 0.7874 0.4064)
			(end 0.7874 -0.4064)
			(stroke
				(width 0.1524)
				(type default)
			)
			(layer "B.SilkS")
		)
		(fp_line
			(start -0.7874 0.4064)
			(end 0.7874 0.4064)
			(stroke
				(width 0.1524)
				(type default)
			)
			(layer "B.SilkS")
		)
		(fp_line
			(start 0.67945 -0.305054)
			(end 0.12065 -0.305054)
			(stroke
				(width 0.1)
				(type default)
			)
			(layer "B.Fab")
		)
		(fp_line
			(start 0.12065 -0.305054)
			(end 0.12065 -0.2794)
			(stroke
				(width 0.1)
				(type default)
			)
			(layer "B.Fab")
		)
		(fp_line
			(start -0.12065 -0.3048)
			(end -0.67945 -0.3048)
			(stroke
				(width 0.1)
				(type default)
			)
			(layer "B.Fab")
		)
		(fp_line
			(start -0.67945 -0.3048)
			(end -0.67945 0.3048)
			(stroke
				(width 0.1)
				(type default)
			)
			(layer "B.Fab")
		)
		(fp_line
			(start 0.12065 -0.2794)
			(end -0.12065 -0.2794)
			(stroke
				(width 0.1)
				(type default)
			)
			(layer "B.Fab")
		)
		(fp_line
			(start -0.12065 -0.2794)
			(end -0.12065 -0.3048)
			(stroke
				(width 0.1)
				(type default)
			)
			(layer "B.Fab")
		)
		(fp_line
			(start 0.12065 0.2794)
			(end 0.12065 0.3048)
			(stroke
				(width 0.1)
				(type default)
			)
			(layer "B.Fab")
		)
		(fp_line
			(start -0.120396 0.2794)
			(end 0.12065 0.2794)
			(stroke
				(width 0.1)
				(type default)
			)
			(layer "B.Fab")
		)
		(fp_line
			(start 0.67945 0.3048)
			(end 0.67945 -0.305054)
			(stroke
				(width 0.1)
				(type default)
			)
			(layer "B.Fab")
		)
		(fp_line
			(start 0.12065 0.3048)
			(end 0.67945 0.3048)
			(stroke
				(width 0.1)
				(type default)
			)
			(layer "B.Fab")
		)
		(fp_line
			(start -0.120396 0.3048)
			(end -0.120396 0.2794)
			(stroke
				(width 0.1)
				(type default)
			)
			(layer "B.Fab")
		)
		(fp_line
			(start -0.67945 0.3048)
			(end -0.120396 0.3048)
			(stroke
				(width 0.1)
				(type default)
			)
			(layer "B.Fab")
		)
		(pad "1" smd circle
			(at 0.40005 0 270)
			(size 0 0)
			(layers "B.Cu" "B.Mask" "B.Paste")
			(net "PVCCD_HV_CPU1_ISENSE_N")
		)
		(pad "2" smd circle
			(at -0.40005 0 270)
			(size 0 0)
			(layers "B.Cu" "B.Mask" "B.Paste")
			(net "PVCCD_HV_CPU1_ISENSE_P")
		)
	)
	(footprint ""
		(layer "B.Cu")
		(at 434.00472 -44.1325 -90)
		(property "Reference" "R4679"
			(at 0 0 90)
			(layer "B.SilkS")
			(hide yes)
			(effects
				(font
					(size 1.27 1.27)
				)
				(justify mirror)
			)
		)
		(property "Value" ""
			(at 0 0 90)
			(layer "B.Fab")
			(effects
				(font
					(size 1.27 1.27)
				)
				(justify mirror)
			)
		)
		(duplicate_pad_numbers_are_jumpers no)
		(fp_line
			(start -0.7874 0.4064)
			(end 0.7874 0.4064)
			(stroke
				(width 0.1524)
				(type default)
			)
			(layer "B.SilkS")
		)
		(fp_line
			(start 0.7874 0.4064)
			(end 0.7874 -0.4064)
			(stroke
				(width 0.1524)
				(type default)
			)
			(layer "B.SilkS")
		)
		(fp_line
			(start -0.7874 -0.4064)
			(end -0.7874 0.4064)
			(stroke
				(width 0.1524)
				(type default)
			)
			(layer "B.SilkS")
		)
		(fp_line
			(start 0.7874 -0.4064)
			(end -0.7874 -0.4064)
			(stroke
				(width 0.1524)
				(type default)
			)
			(layer "B.SilkS")
		)
		(fp_line
			(start -0.67945 0.3048)
			(end -0.120396 0.3048)
			(stroke
				(width 0.1)
				(type default)
			)
			(layer "B.Fab")
		)
		(fp_line
			(start -0.120396 0.3048)
			(end -0.120396 0.2794)
			(stroke
				(width 0.1)
				(type default)
			)
			(layer "B.Fab")
		)
		(fp_line
			(start 0.12065 0.3048)
			(end 0.67945 0.3048)
			(stroke
				(width 0.1)
				(type default)
			)
			(layer "B.Fab")
		)
		(fp_line
			(start 0.67945 0.3048)
			(end 0.67945 -0.305054)
			(stroke
				(width 0.1)
				(type default)
			)
			(layer "B.Fab")
		)
		(fp_line
			(start -0.120396 0.2794)
			(end 0.12065 0.2794)
			(stroke
				(width 0.1)
				(type default)
			)
			(layer "B.Fab")
		)
		(fp_line
			(start 0.12065 0.2794)
			(end 0.12065 0.3048)
			(stroke
				(width 0.1)
				(type default)
			)
			(layer "B.Fab")
		)
		(fp_line
			(start -0.12065 -0.2794)
			(end -0.12065 -0.3048)
			(stroke
				(width 0.1)
				(type default)
			)
			(layer "B.Fab")
		)
		(fp_line
			(start 0.12065 -0.2794)
			(end -0.12065 -0.2794)
			(stroke
				(width 0.1)
				(type default)
			)
			(layer "B.Fab")
		)
		(fp_line
			(start -0.67945 -0.3048)
			(end -0.67945 0.3048)
			(stroke
				(width 0.1)
				(type default)
			)
			(layer "B.Fab")
		)
		(fp_line
			(start -0.12065 -0.3048)
			(end -0.67945 -0.3048)
			(stroke
				(width 0.1)
				(type default)
			)
			(layer "B.Fab")
		)
		(fp_line
			(start 0.12065 -0.305054)
			(end 0.12065 -0.2794)
			(stroke
				(width 0.1)
				(type default)
			)
			(layer "B.Fab")
		)
		(fp_line
			(start 0.67945 -0.305054)
			(end 0.12065 -0.305054)
			(stroke
				(width 0.1)
				(type default)
			)
			(layer "B.Fab")
		)
		(pad "1" smd circle
			(at 0.40005 0 90)
			(size 0 0)
			(layers "B.Cu" "B.Mask" "B.Paste")
			(net "P5V")
		)
		(pad "2" smd circle
			(at -0.40005 0 90)
			(size 0 0)
			(layers "B.Cu" "B.Mask" "B.Paste")
			(net "PWRGD_P5V")
		)
	)
	(footprint ""
		(layer "B.Cu")
		(at 316.55004 -193.53911 90)
		(property "Reference" "R340"
			(at 0 0 90)
			(layer "B.SilkS")
			(hide yes)
			(effects
				(font
					(size 1.27 1.27)
				)
				(justify mirror)
			)
		)
		(property "Value" ""
			(at 0 0 90)
			(layer "B.Fab")
			(effects
				(font
					(size 1.27 1.27)
				)
				(justify mirror)
			)
		)
		(duplicate_pad_numbers_are_jumpers no)
		(fp_line
			(start 0.7874 -0.4064)
			(end -0.7874 -0.4064)
			(stroke
				(width 0.1524)
				(type default)
			)
			(layer "B.SilkS")
		)
		(fp_line
			(start -0.7874 -0.4064)
			(end -0.7874 0.4064)
			(stroke
				(width 0.1524)
				(type default)
			)
			(layer "B.SilkS")
		)
		(fp_line
			(start 0.7874 0.4064)
			(end 0.7874 -0.4064)
			(stroke
				(width 0.1524)
				(type default)
			)
			(layer "B.SilkS")
		)
		(fp_line
			(start -0.7874 0.4064)
			(end 0.7874 0.4064)
			(stroke
				(width 0.1524)
				(type default)
			)
			(layer "B.SilkS")
		)
		(fp_line
			(start 0.67945 -0.305054)
			(end 0.12065 -0.305054)
			(stroke
				(width 0.1)
				(type default)
			)
			(layer "B.Fab")
		)
		(fp_line
			(start 0.12065 -0.305054)
			(end 0.12065 -0.2794)
			(stroke
				(width 0.1)
				(type default)
			)
			(layer "B.Fab")
		)
		(fp_line
			(start -0.12065 -0.3048)
			(end -0.67945 -0.3048)
			(stroke
				(width 0.1)
				(type default)
			)
			(layer "B.Fab")
		)
		(fp_line
			(start -0.67945 -0.3048)
			(end -0.67945 0.3048)
			(stroke
				(width 0.1)
				(type default)
			)
			(layer "B.Fab")
		)
		(fp_line
			(start 0.12065 -0.2794)
			(end -0.12065 -0.2794)
			(stroke
				(width 0.1)
				(type default)
			)
			(layer "B.Fab")
		)
		(fp_line
			(start -0.12065 -0.2794)
			(end -0.12065 -0.3048)
			(stroke
				(width 0.1)
				(type default)
			)
			(layer "B.Fab")
		)
		(fp_line
			(start 0.12065 0.2794)
			(end 0.12065 0.3048)
			(stroke
				(width 0.1)
				(type default)
			)
			(layer "B.Fab")
		)
		(fp_line
			(start -0.120396 0.2794)
			(end 0.12065 0.2794)
			(stroke
				(width 0.1)
				(type default)
			)
			(layer "B.Fab")
		)
		(fp_line
			(start 0.67945 0.3048)
			(end 0.67945 -0.305054)
			(stroke
				(width 0.1)
				(type default)
			)
			(layer "B.Fab")
		)
		(fp_line
			(start 0.12065 0.3048)
			(end 0.67945 0.3048)
			(stroke
				(width 0.1)
				(type default)
			)
			(layer "B.Fab")
		)
		(fp_line
			(start -0.120396 0.3048)
			(end -0.120396 0.2794)
			(stroke
				(width 0.1)
				(type default)
			)
			(layer "B.Fab")
		)
		(fp_line
			(start -0.67945 0.3048)
			(end -0.120396 0.3048)
			(stroke
				(width 0.1)
				(type default)
			)
			(layer "B.Fab")
		)
		(pad "1" smd circle
			(at 0.40005 0 270)
			(size 0 0)
			(layers "B.Cu" "B.Mask" "B.Paste")
			(net "H_CPU0_ERR1_LVC1_R_N")
		)
		(pad "2" smd circle
			(at -0.40005 0 270)
			(size 0 0)
			(layers "B.Cu" "B.Mask" "B.Paste")
			(net "H_CPU_ERR1_LVC1_R_N")
		)
	)
	(footprint ""
		(layer "B.Cu")
		(at 178.1556 -115.775486 90)
		(property "Reference" "C1927"
			(at 0 0 90)
			(layer "B.SilkS")
			(hide yes)
			(effects
				(font
					(size 1.27 1.27)
				)
				(justify mirror)
			)
		)
		(property "Value" ""
			(at 0 0 90)
			(layer "B.Fab")
			(effects
				(font
					(size 1.27 1.27)
				)
				(justify mirror)
			)
		)
		(duplicate_pad_numbers_are_jumpers no)
		(fp_line
			(start 0.69215 -0.2921)
			(end -0.69215 -0.2921)
			(stroke
				(width 0.1524)
				(type default)
			)
			(layer "B.SilkS")
		)
		(fp_line
			(start -0.69215 -0.2921)
			(end -0.69215 0.2921)
			(stroke
				(width 0.1524)
				(type default)
			)
			(layer "B.SilkS")
		)
		(fp_line
			(start 0.69215 0.2921)
			(end 0.69215 -0.2921)
			(stroke
				(width 0.1524)
				(type default)
			)
			(layer "B.SilkS")
		)
		(fp_line
			(start -0.69215 0.2921)
			(end 0.69215 0.2921)
			(stroke
				(width 0.1524)
				(type default)
			)
			(layer "B.SilkS")
		)
		(fp_line
			(start 0.51435 -0.2794)
			(end -0.51435 -0.2794)
			(stroke
				(width 0.1)
				(type default)
			)
			(layer "B.Fab")
		)
		(fp_line
			(start -0.51435 -0.2794)
			(end -0.51435 0.2794)
			(stroke
				(width 0.1)
				(type default)
			)
			(layer "B.Fab")
		)
		(fp_line
			(start 0.51435 0.2794)
			(end 0.51435 -0.2794)
			(stroke
				(width 0.1)
				(type default)
			)
			(layer "B.Fab")
		)
		(fp_line
			(start -0.51435 0.2794)
			(end 0.51435 0.2794)
			(stroke
				(width 0.1)
				(type default)
			)
			(layer "B.Fab")
		)
		(pad "1" smd circle
			(at 0.40005 0 270)
			(size 0 0)
			(layers "B.Cu" "B.Mask" "B.Paste")
			(net "P3V3_AUX_FPGA_VCCIO1")
		)
		(pad "2" smd circle
			(at -0.40005 0 270)
			(size 0 0)
			(layers "B.Cu" "B.Mask" "B.Paste")
			(net "GND")
		)
		(zone
			(layer "B.Cu")
			(hatch none 0.5)
			(connect_pads
				(clearance 0)
			)
			(min_thickness 0.25)
			(keepout
				(tracks not_allowed)
				(vias allowed)
				(pads allowed)
				(copperpour not_allowed)
				(footprints allowed)
			)
			(placement
				(enabled no)
				(sheetname "")
			)
			(fill
				(thermal_gap 0.5)
				(thermal_bridge_width 0.5)
				(island_removal_mode 0)
			)
			(polygon
				(pts
					(xy 178.24323 -115.965986) (xy 178.301396 -115.874546) (xy 178.301396 -115.675156) (xy 178.24323 -115.584986)
					(xy 178.06797 -115.584986) (xy 178.00955 -115.675156) (xy 178.00955 -115.874546) (xy 178.067716 -115.965986)
				)
			)
		)
	)
	(footprint ""
		(layer "B.Cu")
		(at 160.83788 -109.489748)
		(property "Reference" "R1440"
			(at 0 0 0)
			(layer "B.SilkS")
			(hide yes)
			(effects
				(font
					(size 1.27 1.27)
				)
				(justify mirror)
			)
		)
		(property "Value" ""
			(at 0 0 0)
			(layer "B.Fab")
			(effects
				(font
					(size 1.27 1.27)
				)
				(justify mirror)
			)
		)
		(duplicate_pad_numbers_are_jumpers no)
		(fp_line
			(start -0.7874 -0.4064)
			(end -0.7874 0.4064)
			(stroke
				(width 0.1524)
				(type default)
			)
			(layer "B.SilkS")
		)
		(fp_line
			(start -0.7874 0.4064)
			(end 0.7874 0.4064)
			(stroke
				(width 0.1524)
				(type default)
			)
			(layer "B.SilkS")
		)
		(fp_line
			(start 0.7874 -0.4064)
			(end -0.7874 -0.4064)
			(stroke
				(width 0.1524)
				(type default)
			)
			(layer "B.SilkS")
		)
		(fp_line
			(start 0.7874 0.4064)
			(end 0.7874 -0.4064)
			(stroke
				(width 0.1524)
				(type default)
			)
			(layer "B.SilkS")
		)
		(fp_line
			(start -0.67945 -0.3048)
			(end -0.67945 0.3048)
			(stroke
				(width 0.1)
				(type default)
			)
			(layer "B.Fab")
		)
		(fp_line
			(start -0.67945 0.3048)
			(end -0.120396 0.3048)
			(stroke
				(width 0.1)
				(type default)
			)
			(layer "B.Fab")
		)
		(fp_line
			(start -0.12065 -0.3048)
			(end -0.67945 -0.3048)
			(stroke
				(width 0.1)
				(type default)
			)
			(layer "B.Fab")
		)
		(fp_line
			(start -0.12065 -0.2794)
			(end -0.12065 -0.3048)
			(stroke
				(width 0.1)
				(type default)
			)
			(layer "B.Fab")
		)
		(fp_line
			(start -0.120396 0.2794)
			(end 0.12065 0.2794)
			(stroke
				(width 0.1)
				(type default)
			)
			(layer "B.Fab")
		)
		(fp_line
			(start -0.120396 0.3048)
			(end -0.120396 0.2794)
			(stroke
				(width 0.1)
				(type default)
			)
			(layer "B.Fab")
		)
		(fp_line
			(start 0.12065 -0.305054)
			(end 0.12065 -0.2794)
			(stroke
				(width 0.1)
				(type default)
			)
			(layer "B.Fab")
		)
		(fp_line
			(start 0.12065 -0.2794)
			(end -0.12065 -0.2794)
			(stroke
				(width 0.1)
				(type default)
			)
			(layer "B.Fab")
		)
		(fp_line
			(start 0.12065 0.2794)
			(end 0.12065 0.3048)
			(stroke
				(width 0.1)
				(type default)
			)
			(layer "B.Fab")
		)
		(fp_line
			(start 0.12065 0.3048)
			(end 0.67945 0.3048)
			(stroke
				(width 0.1)
				(type default)
			)
			(layer "B.Fab")
		)
		(fp_line
			(start 0.67945 -0.305054)
			(end 0.12065 -0.305054)
			(stroke
				(width 0.1)
				(type default)
			)
			(layer "B.Fab")
		)
		(fp_line
			(start 0.67945 0.3048)
			(end 0.67945 -0.305054)
			(stroke
				(width 0.1)
				(type default)
			)
			(layer "B.Fab")
		)
		(pad "1" smd circle
			(at 0.40005 0 180)
			(size 0 0)
			(layers "B.Cu" "B.Mask" "B.Paste")
			(net "JTAG_PLD_TDO_R")
		)
		(pad "2" smd circle
			(at -0.40005 0 180)
			(size 0 0)
			(layers "B.Cu" "B.Mask" "B.Paste")
			(net "P3V3_AUX")
		)
	)
	(footprint ""
		(layer "B.Cu")
		(at 164.64788 -115.026948 180)
		(property "Reference" "R3505"
			(at 0 0 0)
			(layer "B.SilkS")
			(hide yes)
			(effects
				(font
					(size 1.27 1.27)
				)
				(justify mirror)
			)
		)
		(property "Value" ""
			(at 0 0 0)
			(layer "B.Fab")
			(effects
				(font
					(size 1.27 1.27)
				)
				(justify mirror)
			)
		)
		(duplicate_pad_numbers_are_jumpers no)
		(fp_line
			(start 0.7874 0.4064)
			(end 0.7874 -0.4064)
			(stroke
				(width 0.1524)
				(type default)
			)
			(layer "B.SilkS")
		)
		(fp_line
			(start 0.7874 -0.4064)
			(end -0.7874 -0.4064)
			(stroke
				(width 0.1524)
				(type default)
			)
			(layer "B.SilkS")
		)
		(fp_line
			(start -0.7874 0.4064)
			(end 0.7874 0.4064)
			(stroke
				(width 0.1524)
				(type default)
			)
			(layer "B.SilkS")
		)
		(fp_line
			(start -0.7874 -0.4064)
			(end -0.7874 0.4064)
			(stroke
				(width 0.1524)
				(type default)
			)
			(layer "B.SilkS")
		)
		(fp_line
			(start 0.67945 0.3048)
			(end 0.67945 -0.305054)
			(stroke
				(width 0.1)
				(type default)
			)
			(layer "B.Fab")
		)
		(fp_line
			(start 0.67945 -0.305054)
			(end 0.12065 -0.305054)
			(stroke
				(width 0.1)
				(type default)
			)
			(layer "B.Fab")
		)
		(fp_line
			(start 0.12065 0.3048)
			(end 0.67945 0.3048)
			(stroke
				(width 0.1)
				(type default)
			)
			(layer "B.Fab")
		)
		(fp_line
			(start 0.12065 0.2794)
			(end 0.12065 0.3048)
			(stroke
				(width 0.1)
				(type default)
			)
			(layer "B.Fab")
		)
		(fp_line
			(start 0.12065 -0.2794)
			(end -0.12065 -0.2794)
			(stroke
				(width 0.1)
				(type default)
			)
			(layer "B.Fab")
		)
		(fp_line
			(start 0.12065 -0.305054)
			(end 0.12065 -0.2794)
			(stroke
				(width 0.1)
				(type default)
			)
			(layer "B.Fab")
		)
		(fp_line
			(start -0.120396 0.3048)
			(end -0.120396 0.2794)
			(stroke
				(width 0.1)
				(type default)
			)
			(layer "B.Fab")
		)
		(fp_line
			(start -0.120396 0.2794)
			(end 0.12065 0.2794)
			(stroke
				(width 0.1)
				(type default)
			)
			(layer "B.Fab")
		)
		(fp_line
			(start -0.12065 -0.2794)
			(end -0.12065 -0.3048)
			(stroke
				(width 0.1)
				(type default)
			)
			(layer "B.Fab")
		)
		(fp_line
			(start -0.12065 -0.3048)
			(end -0.67945 -0.3048)
			(stroke
				(width 0.1)
				(type default)
			)
			(layer "B.Fab")
		)
		(fp_line
			(start -0.67945 0.3048)
			(end -0.120396 0.3048)
			(stroke
				(width 0.1)
				(type default)
			)
			(layer "B.Fab")
		)
		(fp_line
			(start -0.67945 -0.3048)
			(end -0.67945 0.3048)
			(stroke
				(width 0.1)
				(type default)
			)
			(layer "B.Fab")
		)
		(pad "1" smd circle
			(at 0.40005 0)
			(size 0 0)
			(layers "B.Cu" "B.Mask" "B.Paste")
			(net "GPU_FPGA_EROT_FATALERR_ISO_N")
		)
		(pad "2" smd circle
			(at -0.40005 0)
			(size 0 0)
			(layers "B.Cu" "B.Mask" "B.Paste")
			(net "GPU_FPGA_EROT_FATALERR_ISO_R_N")
		)
	)
	(footprint ""
		(layer "B.Cu")
		(at 133.069838 -328.298048 -90)
		(property "Reference" "PC522_P1_5"
			(at 0 0 90)
			(layer "B.SilkS")
			(hide yes)
			(effects
				(font
					(size 1.27 1.27)
				)
				(justify mirror)
			)
		)
		(property "Value" ""
			(at 0 0 90)
			(layer "B.Fab")
			(effects
				(font
					(size 1.27 1.27)
				)
				(justify mirror)
			)
		)
		(duplicate_pad_numbers_are_jumpers no)
		(fp_line
			(start -1.524 0.762)
			(end 1.524 0.762)
			(stroke
				(width 0.1524)
				(type default)
			)
			(layer "B.SilkS")
		)
		(fp_line
			(start 1.524 0.762)
			(end 1.524 -0.762)
			(stroke
				(width 0.1524)
				(type default)
			)
			(layer "B.SilkS")
		)
		(fp_line
			(start -1.524 -0.762)
			(end -1.524 0.762)
			(stroke
				(width 0.1524)
				(type default)
			)
			(layer "B.SilkS")
		)
		(fp_line
			(start 1.524 -0.762)
			(end -1.524 -0.762)
			(stroke
				(width 0.1524)
				(type default)
			)
			(layer "B.SilkS")
		)
		(fp_line
			(start -1.1049 0.724916)
			(end -1.1049 -0.724916)
			(stroke
				(width 0.1)
				(type default)
			)
			(layer "B.Fab")
		)
		(fp_line
			(start 1.1049 0.724916)
			(end -1.1049 0.724916)
			(stroke
				(width 0.1)
				(type default)
			)
			(layer "B.Fab")
		)
		(fp_line
			(start -1.1049 -0.724916)
			(end 1.1049 -0.724916)
			(stroke
				(width 0.1)
				(type default)
			)
			(layer "B.Fab")
		)
		(fp_line
			(start 1.1049 -0.724916)
			(end 1.1049 0.724916)
			(stroke
				(width 0.1)
				(type default)
			)
			(layer "B.Fab")
		)
		(pad "1" smd rect
			(at 0.889 0 270)
			(size 1.016 1.27)
			(layers "B.Cu" "B.Mask" "B.Paste")
			(net "PVCCIN_CPU1")
		)
		(pad "2" smd rect
			(at -0.889 0 270)
			(size 1.016 1.27)
			(layers "B.Cu" "B.Mask" "B.Paste")
			(net "GND")
		)
	)
	(footprint ""
		(layer "B.Cu")
		(at 495.90833 -148.094192 -90)
		(property "Reference" "X32"
			(at 3.666236 3.151378 270)
			(unlocked yes)
			(layer "B.SilkS")
			(effects
				(font
					(size 0.7874 0.5842)
					(thickness 0.1524)
				)
				(justify left mirror)
			)
		)
		(property "Value" ""
			(at 0 0 90)
			(layer "B.Fab")
			(effects
				(font
					(size 1.27 1.27)
				)
				(justify mirror)
			)
		)
		(property "Device Type" "TP_TDR_4P_FTS_TH-TP_TDR_4P_DIPA"
			(at -1.30175 1.27 180)
			(unlocked yes)
			(layer "B.Fab")
			(hide yes)
			(effects
				(font
					(size 0.635 0.4064)
					(thickness 0.1524)
				)
				(justify mirror)
			)
		)
		(property "User Part Number" "N_A"
			(at -1.30175 1.27 180)
			(unlocked yes)
			(layer "Cmts.User")
			(hide yes)
			(effects
				(font
					(size 0.635 0.4064)
					(thickness 0.1524)
				)
				(justify mirror)
			)
		)
		(duplicate_pad_numbers_are_jumpers no)
		(fp_line
			(start -2.54 3.81)
			(end -2.54 3.6703)
			(stroke
				(width 0.1524)
				(type default)
			)
			(layer "B.SilkS")
		)
		(fp_line
			(start 0 3.81)
			(end -2.54 3.81)
			(stroke
				(width 0.1524)
				(type default)
			)
			(layer "B.SilkS")
		)
		(fp_line
			(start 0 3.175)
			(end 0 3.81)
			(stroke
				(width 0.1524)
				(type default)
			)
			(layer "B.SilkS")
		)
		(fp_line
			(start -2.54 1.4097)
			(end -2.54 1.1303)
			(stroke
				(width 0.1524)
				(type default)
			)
			(layer "B.SilkS")
		)
		(fp_line
			(start 0 0.635)
			(end 0 1.905)
			(stroke
				(width 0.1524)
				(type default)
			)
			(layer "B.SilkS")
		)
		(fp_line
			(start -2.54 -1.1303)
			(end -2.54 -1.27)
			(stroke
				(width 0.1524)
				(type default)
			)
			(layer "B.SilkS")
		)
		(fp_line
			(start -2.54 -1.27)
			(end 0 -1.27)
			(stroke
				(width 0.1524)
				(type default)
			)
			(layer "B.SilkS")
		)
		(fp_line
			(start 0 -1.27)
			(end 0 -0.635)
			(stroke
				(width 0.1524)
				(type default)
			)
			(layer "B.SilkS")
		)
		(fp_poly
			(pts
				(xy 2.981706 -0.88646) (xy 2.981706 0.63754) (xy 1.457706 -0.12446)
			)
			(stroke
				(width 0)
				(type default)
			)
			(fill yes)
			(layer "B.SilkS")
		)
		(fp_line
			(start -2.54 3.81)
			(end -2.54 -1.27)
			(stroke
				(width 0.1)
				(type default)
			)
			(layer "B.Fab")
		)
		(fp_line
			(start 0 3.81)
			(end -2.54 3.81)
			(stroke
				(width 0.1)
				(type default)
			)
			(layer "B.Fab")
		)
		(fp_line
			(start -2.54 -1.27)
			(end 0 -1.27)
			(stroke
				(width 0.1)
				(type default)
			)
			(layer "B.Fab")
		)
		(fp_line
			(start 0 -1.27)
			(end 0 3.81)
			(stroke
				(width 0.1)
				(type default)
			)
			(layer "B.Fab")
		)
		(fp_poly
			(pts
				(xy 0.761746 0) (xy 2.285746 -0.762) (xy 2.285746 0.762)
			)
			(stroke
				(width 0)
				(type default)
			)
			(fill yes)
			(layer "B.Fab")
		)
		(pad "1" thru_hole circle
			(at 0 0 90)
			(size 1.0033 1.0033)
			(drill 0.249936)
			(layers "*.Cu" "*.Mask")
			(remove_unused_layers no)
			(net "TDR_DIFF_100_IN6_DN")
			(clearance 0.10795)
			(padstack
				(mode front_inner_back)
				(layer "Inner"
					(shape circle)
					(size 0.8001 0.8001)
					(clearance 0.1524)
				)
				(layer "B.Cu"
					(shape circle)
					(size 1.0033 1.0033)
					(thermal_gap 0.10795)
					(clearance 0.10795)
				)
			)
		)
		(pad "2" thru_hole circle
			(at -2.54 0 90)
			(size 1.9939 1.9939)
			(drill 0.249936)
			(layers "*.Cu" "*.Mask")
			(remove_unused_layers no)
			(net "T1_GND")
			(clearance 0.10795)
			(padstack
				(mode front_inner_back)
				(layer "Inner"
					(shape circle)
					(size 0.8001 0.8001)
					(clearance 0.1524)
				)
				(layer "B.Cu"
					(shape circle)
					(size 1.9939 1.9939)
					(thermal_gap 0.10795)
					(clearance 0.10795)
				)
			)
		)
		(pad "3" thru_hole circle
			(at -2.54 2.54 90)
			(size 1.9939 1.9939)
			(drill 0.249936)
			(layers "*.Cu" "*.Mask")
			(remove_unused_layers no)
			(net "T1_GND")
			(clearance 0.10795)
			(padstack
				(mode front_inner_back)
				(layer "Inner"
					(shape circle)
					(size 0.8001 0.8001)
					(clearance 0.1524)
				)
				(layer "B.Cu"
					(shape circle)
					(size 1.9939 1.9939)
					(thermal_gap 0.10795)
					(clearance 0.10795)
				)
			)
		)
		(pad "4" thru_hole circle
			(at 0 2.54 90)
			(size 1.0033 1.0033)
			(drill 0.249936)
			(layers "*.Cu" "*.Mask")
			(remove_unused_layers no)
			(net "TDR_DIFF_100_IN6_DP")
			(clearance 0.10795)
			(padstack
				(mode front_inner_back)
				(layer "Inner"
					(shape circle)
					(size 0.8001 0.8001)
					(clearance 0.1524)
				)
				(layer "B.Cu"
					(shape circle)
					(size 1.0033 1.0033)
					(thermal_gap 0.10795)
					(clearance 0.10795)
				)
			)
		)
	)
	(footprint ""
		(layer "B.Cu")
		(at 261.655814 -100.91547 180)
		(property "Reference" "C1310"
			(at 0 0 0)
			(layer "B.SilkS")
			(hide yes)
			(effects
				(font
					(size 1.27 1.27)
				)
				(justify mirror)
			)
		)
		(property "Value" ""
			(at 0 0 0)
			(layer "B.Fab")
			(effects
				(font
					(size 1.27 1.27)
				)
				(justify mirror)
			)
		)
		(duplicate_pad_numbers_are_jumpers no)
		(fp_line
			(start 1.2954 0.5842)
			(end 1.2954 -0.5842)
			(stroke
				(width 0.1524)
				(type default)
			)
			(layer "B.SilkS")
		)
		(fp_line
			(start 1.2954 -0.5842)
			(end -1.2954 -0.5842)
			(stroke
				(width 0.1524)
				(type default)
			)
			(layer "B.SilkS")
		)
		(fp_line
			(start 0 -0.5842)
			(end 0 0.5842)
			(stroke
				(width 0.1524)
				(type default)
			)
			(layer "B.SilkS")
		)
		(fp_line
			(start -1.2954 0.5842)
			(end 1.2954 0.5842)
			(stroke
				(width 0.1524)
				(type default)
			)
			(layer "B.SilkS")
		)
		(fp_line
			(start -1.2954 -0.5842)
			(end -1.2954 0.5842)
			(stroke
				(width 0.1524)
				(type default)
			)
			(layer "B.SilkS")
		)
		(fp_line
			(start 1.1938 0.4064)
			(end 1.1938 -0.4064)
			(stroke
				(width 0.1)
				(type default)
			)
			(layer "B.Fab")
		)
		(fp_line
			(start 1.1938 -0.4064)
			(end 0.8636 -0.4064)
			(stroke
				(width 0.1)
				(type default)
			)
			(layer "B.Fab")
		)
		(fp_line
			(start 0.8636 0.4572)
			(end 0.8636 0.4064)
			(stroke
				(width 0.1)
				(type default)
			)
			(layer "B.Fab")
		)
		(fp_line
			(start 0.8636 0.4064)
			(end 1.1938 0.4064)
			(stroke
				(width 0.1)
				(type default)
			)
			(layer "B.Fab")
		)
		(fp_line
			(start 0.8636 -0.4064)
			(end 0.8636 -0.4572)
			(stroke
				(width 0.1)
				(type default)
			)
			(layer "B.Fab")
		)
		(fp_line
			(start 0.8636 -0.4572)
			(end -0.8636 -0.4572)
			(stroke
				(width 0.1)
				(type default)
			)
			(layer "B.Fab")
		)
		(fp_line
			(start -0.8636 0.4572)
			(end 0.8636 0.4572)
			(stroke
				(width 0.1)
				(type default)
			)
			(layer "B.Fab")
		)
		(fp_line
			(start -0.8636 0.4064)
			(end -0.8636 0.4572)
			(stroke
				(width 0.1)
				(type default)
			)
			(layer "B.Fab")
		)
		(fp_line
			(start -0.8636 -0.4064)
			(end -1.1938 -0.4064)
			(stroke
				(width 0.1)
				(type default)
			)
			(layer "B.Fab")
		)
		(fp_line
			(start -0.8636 -0.4572)
			(end -0.8636 -0.4064)
			(stroke
				(width 0.1)
				(type default)
			)
			(layer "B.Fab")
		)
		(fp_line
			(start -1.1938 0.4064)
			(end -0.8636 0.4064)
			(stroke
				(width 0.1)
				(type default)
			)
			(layer "B.Fab")
		)
		(fp_line
			(start -1.1938 -0.4064)
			(end -1.1938 0.4064)
			(stroke
				(width 0.1)
				(type default)
			)
			(layer "B.Fab")
		)
		(pad "1" smd rect
			(at 0.7366 0 90)
			(size 0.7112 0.8128)
			(layers "B.Cu" "B.Mask" "B.Paste")
			(net "P3V3_AUX_CLK_GEN_VDDMXCK_CK440")
		)
		(pad "2" smd rect
			(at -0.7366 0 90)
			(size 0.7112 0.8128)
			(layers "B.Cu" "B.Mask" "B.Paste")
			(net "GND")
		)
	)
	(footprint ""
		(layer "B.Cu")
		(at 414.255712 -193.08953 -90)
		(property "Reference" "R320"
			(at 0 0 90)
			(layer "B.SilkS")
			(hide yes)
			(effects
				(font
					(size 1.27 1.27)
				)
				(justify mirror)
			)
		)
		(property "Value" ""
			(at 0 0 90)
			(layer "B.Fab")
			(effects
				(font
					(size 1.27 1.27)
				)
				(justify mirror)
			)
		)
		(duplicate_pad_numbers_are_jumpers no)
		(fp_line
			(start -0.7874 0.4064)
			(end 0.7874 0.4064)
			(stroke
				(width 0.1524)
				(type default)
			)
			(layer "B.SilkS")
		)
		(fp_line
			(start 0.7874 0.4064)
			(end 0.7874 -0.4064)
			(stroke
				(width 0.1524)
				(type default)
			)
			(layer "B.SilkS")
		)
		(fp_line
			(start -0.7874 -0.4064)
			(end -0.7874 0.4064)
			(stroke
				(width 0.1524)
				(type default)
			)
			(layer "B.SilkS")
		)
		(fp_line
			(start 0.7874 -0.4064)
			(end -0.7874 -0.4064)
			(stroke
				(width 0.1524)
				(type default)
			)
			(layer "B.SilkS")
		)
		(fp_line
			(start -0.67945 0.3048)
			(end -0.120396 0.3048)
			(stroke
				(width 0.1)
				(type default)
			)
			(layer "B.Fab")
		)
		(fp_line
			(start -0.120396 0.3048)
			(end -0.120396 0.2794)
			(stroke
				(width 0.1)
				(type default)
			)
			(layer "B.Fab")
		)
		(fp_line
			(start 0.12065 0.3048)
			(end 0.67945 0.3048)
			(stroke
				(width 0.1)
				(type default)
			)
			(layer "B.Fab")
		)
		(fp_line
			(start 0.67945 0.3048)
			(end 0.67945 -0.305054)
			(stroke
				(width 0.1)
				(type default)
			)
			(layer "B.Fab")
		)
		(fp_line
			(start -0.120396 0.2794)
			(end 0.12065 0.2794)
			(stroke
				(width 0.1)
				(type default)
			)
			(layer "B.Fab")
		)
		(fp_line
			(start 0.12065 0.2794)
			(end 0.12065 0.3048)
			(stroke
				(width 0.1)
				(type default)
			)
			(layer "B.Fab")
		)
		(fp_line
			(start -0.12065 -0.2794)
			(end -0.12065 -0.3048)
			(stroke
				(width 0.1)
				(type default)
			)
			(layer "B.Fab")
		)
		(fp_line
			(start 0.12065 -0.2794)
			(end -0.12065 -0.2794)
			(stroke
				(width 0.1)
				(type default)
			)
			(layer "B.Fab")
		)
		(fp_line
			(start -0.67945 -0.3048)
			(end -0.67945 0.3048)
			(stroke
				(width 0.1)
				(type default)
			)
			(layer "B.Fab")
		)
		(fp_line
			(start -0.12065 -0.3048)
			(end -0.67945 -0.3048)
			(stroke
				(width 0.1)
				(type default)
			)
			(layer "B.Fab")
		)
		(fp_line
			(start 0.12065 -0.305054)
			(end 0.12065 -0.2794)
			(stroke
				(width 0.1)
				(type default)
			)
			(layer "B.Fab")
		)
		(fp_line
			(start 0.67945 -0.305054)
			(end 0.12065 -0.305054)
			(stroke
				(width 0.1)
				(type default)
			)
			(layer "B.Fab")
		)
		(pad "1" smd circle
			(at 0.40005 0 90)
			(size 0 0)
			(layers "B.Cu" "B.Mask" "B.Paste")
			(net "P3V3_AUX")
		)
		(pad "2" smd circle
			(at -0.40005 0 90)
			(size 0 0)
			(layers "B.Cu" "B.Mask" "B.Paste")
			(net "PU_S3M_CPU0_CPLD_CONFD")
		)
	)
	(footprint ""
		(layer "B.Cu")
		(at 213.525354 -314.550044 90)
		(property "Reference" "R2505"
			(at 0 0 90)
			(layer "B.SilkS")
			(hide yes)
			(effects
				(font
					(size 1.27 1.27)
				)
				(justify mirror)
			)
		)
		(property "Value" ""
			(at 0 0 90)
			(layer "B.Fab")
			(effects
				(font
					(size 1.27 1.27)
				)
				(justify mirror)
			)
		)
		(duplicate_pad_numbers_are_jumpers no)
		(fp_line
			(start 0.7874 -0.4064)
			(end -0.7874 -0.4064)
			(stroke
				(width 0.1524)
				(type default)
			)
			(layer "B.SilkS")
		)
		(fp_line
			(start -0.7874 -0.4064)
			(end -0.7874 0.4064)
			(stroke
				(width 0.1524)
				(type default)
			)
			(layer "B.SilkS")
		)
		(fp_line
			(start 0.7874 0.4064)
			(end 0.7874 -0.4064)
			(stroke
				(width 0.1524)
				(type default)
			)
			(layer "B.SilkS")
		)
		(fp_line
			(start -0.7874 0.4064)
			(end 0.7874 0.4064)
			(stroke
				(width 0.1524)
				(type default)
			)
			(layer "B.SilkS")
		)
		(fp_line
			(start 0.67945 -0.305054)
			(end 0.12065 -0.305054)
			(stroke
				(width 0.1)
				(type default)
			)
			(layer "B.Fab")
		)
		(fp_line
			(start 0.12065 -0.305054)
			(end 0.12065 -0.2794)
			(stroke
				(width 0.1)
				(type default)
			)
			(layer "B.Fab")
		)
		(fp_line
			(start -0.12065 -0.3048)
			(end -0.67945 -0.3048)
			(stroke
				(width 0.1)
				(type default)
			)
			(layer "B.Fab")
		)
		(fp_line
			(start -0.67945 -0.3048)
			(end -0.67945 0.3048)
			(stroke
				(width 0.1)
				(type default)
			)
			(layer "B.Fab")
		)
		(fp_line
			(start 0.12065 -0.2794)
			(end -0.12065 -0.2794)
			(stroke
				(width 0.1)
				(type default)
			)
			(layer "B.Fab")
		)
		(fp_line
			(start -0.12065 -0.2794)
			(end -0.12065 -0.3048)
			(stroke
				(width 0.1)
				(type default)
			)
			(layer "B.Fab")
		)
		(fp_line
			(start 0.12065 0.2794)
			(end 0.12065 0.3048)
			(stroke
				(width 0.1)
				(type default)
			)
			(layer "B.Fab")
		)
		(fp_line
			(start -0.120396 0.2794)
			(end 0.12065 0.2794)
			(stroke
				(width 0.1)
				(type default)
			)
			(layer "B.Fab")
		)
		(fp_line
			(start 0.67945 0.3048)
			(end 0.67945 -0.305054)
			(stroke
				(width 0.1)
				(type default)
			)
			(layer "B.Fab")
		)
		(fp_line
			(start 0.12065 0.3048)
			(end 0.67945 0.3048)
			(stroke
				(width 0.1)
				(type default)
			)
			(layer "B.Fab")
		)
		(fp_line
			(start -0.120396 0.3048)
			(end -0.120396 0.2794)
			(stroke
				(width 0.1)
				(type default)
			)
			(layer "B.Fab")
		)
		(fp_line
			(start -0.67945 0.3048)
			(end -0.120396 0.3048)
			(stroke
				(width 0.1)
				(type default)
			)
			(layer "B.Fab")
		)
		(pad "1" smd circle
			(at 0.40005 0 270)
			(size 0 0)
			(layers "B.Cu" "B.Mask" "B.Paste")
			(net "PWRGD_FAIL_CPU1_GH_R1")
		)
		(pad "2" smd circle
			(at -0.40005 0 270)
			(size 0 0)
			(layers "B.Cu" "B.Mask" "B.Paste")
			(net "PWRGD_FAIL_CPU1_GH_R")
		)
	)
	(footprint ""
		(layer "B.Cu")
		(at 237.837472 -128.518158 180)
		(property "Reference" "C207"
			(at 0 0 0)
			(layer "B.SilkS")
			(hide yes)
			(effects
				(font
					(size 1.27 1.27)
				)
				(justify mirror)
			)
		)
		(property "Value" ""
			(at 0 0 0)
			(layer "B.Fab")
			(effects
				(font
					(size 1.27 1.27)
				)
				(justify mirror)
			)
		)
		(duplicate_pad_numbers_are_jumpers no)
		(fp_line
			(start 0.7874 0.4064)
			(end 0.7874 -0.4064)
			(stroke
				(width 0.1524)
				(type default)
			)
			(layer "B.SilkS")
		)
		(fp_line
			(start 0.7874 -0.4064)
			(end -0.7874 -0.4064)
			(stroke
				(width 0.1524)
				(type default)
			)
			(layer "B.SilkS")
		)
		(fp_line
			(start -0.7874 0.4064)
			(end 0.7874 0.4064)
			(stroke
				(width 0.1524)
				(type default)
			)
			(layer "B.SilkS")
		)
		(fp_line
			(start -0.7874 -0.4064)
			(end -0.7874 0.4064)
			(stroke
				(width 0.1524)
				(type default)
			)
			(layer "B.SilkS")
		)
		(fp_line
			(start 0.67945 0.3048)
			(end 0.67945 -0.305054)
			(stroke
				(width 0.1)
				(type default)
			)
			(layer "B.Fab")
		)
		(fp_line
			(start 0.67945 -0.305054)
			(end 0.12065 -0.305054)
			(stroke
				(width 0.1)
				(type default)
			)
			(layer "B.Fab")
		)
		(fp_line
			(start 0.12065 0.3048)
			(end 0.67945 0.3048)
			(stroke
				(width 0.1)
				(type default)
			)
			(layer "B.Fab")
		)
		(fp_line
			(start 0.12065 0.2794)
			(end 0.12065 0.3048)
			(stroke
				(width 0.1)
				(type default)
			)
			(layer "B.Fab")
		)
		(fp_line
			(start 0.12065 -0.2794)
			(end -0.12065 -0.2794)
			(stroke
				(width 0.1)
				(type default)
			)
			(layer "B.Fab")
		)
		(fp_line
			(start 0.12065 -0.305054)
			(end 0.12065 -0.2794)
			(stroke
				(width 0.1)
				(type default)
			)
			(layer "B.Fab")
		)
		(fp_line
			(start -0.120396 0.3048)
			(end -0.120396 0.2794)
			(stroke
				(width 0.1)
				(type default)
			)
			(layer "B.Fab")
		)
		(fp_line
			(start -0.120396 0.2794)
			(end 0.12065 0.2794)
			(stroke
				(width 0.1)
				(type default)
			)
			(layer "B.Fab")
		)
		(fp_line
			(start -0.12065 -0.2794)
			(end -0.12065 -0.3048)
			(stroke
				(width 0.1)
				(type default)
			)
			(layer "B.Fab")
		)
		(fp_line
			(start -0.12065 -0.3048)
			(end -0.67945 -0.3048)
			(stroke
				(width 0.1)
				(type default)
			)
			(layer "B.Fab")
		)
		(fp_line
			(start -0.67945 0.3048)
			(end -0.120396 0.3048)
			(stroke
				(width 0.1)
				(type default)
			)
			(layer "B.Fab")
		)
		(fp_line
			(start -0.67945 -0.3048)
			(end -0.67945 0.3048)
			(stroke
				(width 0.1)
				(type default)
			)
			(layer "B.Fab")
		)
		(pad "1" smd circle
			(at 0.40005 0)
			(size 0 0)
			(layers "B.Cu" "B.Mask" "B.Paste")
			(net "P3V3_DB2000_VDD")
		)
		(pad "2" smd circle
			(at -0.40005 0)
			(size 0 0)
			(layers "B.Cu" "B.Mask" "B.Paste")
			(net "GND")
		)
	)
	(footprint ""
		(layer "B.Cu")
		(at 404.002748 -58.79846)
		(property "Reference" "R778"
			(at 0 0 0)
			(layer "B.SilkS")
			(hide yes)
			(effects
				(font
					(size 1.27 1.27)
				)
				(justify mirror)
			)
		)
		(property "Value" ""
			(at 0 0 0)
			(layer "B.Fab")
			(effects
				(font
					(size 1.27 1.27)
				)
				(justify mirror)
			)
		)
		(duplicate_pad_numbers_are_jumpers no)
		(fp_line
			(start -0.7874 -0.4064)
			(end -0.7874 0.4064)
			(stroke
				(width 0.1524)
				(type default)
			)
			(layer "B.SilkS")
		)
		(fp_line
			(start -0.7874 0.4064)
			(end 0.7874 0.4064)
			(stroke
				(width 0.1524)
				(type default)
			)
			(layer "B.SilkS")
		)
		(fp_line
			(start 0.7874 -0.4064)
			(end -0.7874 -0.4064)
			(stroke
				(width 0.1524)
				(type default)
			)
			(layer "B.SilkS")
		)
		(fp_line
			(start 0.7874 0.4064)
			(end 0.7874 -0.4064)
			(stroke
				(width 0.1524)
				(type default)
			)
			(layer "B.SilkS")
		)
		(fp_line
			(start -0.67945 -0.3048)
			(end -0.67945 0.3048)
			(stroke
				(width 0.1)
				(type default)
			)
			(layer "B.Fab")
		)
		(fp_line
			(start -0.67945 0.3048)
			(end -0.120396 0.3048)
			(stroke
				(width 0.1)
				(type default)
			)
			(layer "B.Fab")
		)
		(fp_line
			(start -0.12065 -0.3048)
			(end -0.67945 -0.3048)
			(stroke
				(width 0.1)
				(type default)
			)
			(layer "B.Fab")
		)
		(fp_line
			(start -0.12065 -0.2794)
			(end -0.12065 -0.3048)
			(stroke
				(width 0.1)
				(type default)
			)
			(layer "B.Fab")
		)
		(fp_line
			(start -0.120396 0.2794)
			(end 0.12065 0.2794)
			(stroke
				(width 0.1)
				(type default)
			)
			(layer "B.Fab")
		)
		(fp_line
			(start -0.120396 0.3048)
			(end -0.120396 0.2794)
			(stroke
				(width 0.1)
				(type default)
			)
			(layer "B.Fab")
		)
		(fp_line
			(start 0.12065 -0.305054)
			(end 0.12065 -0.2794)
			(stroke
				(width 0.1)
				(type default)
			)
			(layer "B.Fab")
		)
		(fp_line
			(start 0.12065 -0.2794)
			(end -0.12065 -0.2794)
			(stroke
				(width 0.1)
				(type default)
			)
			(layer "B.Fab")
		)
		(fp_line
			(start 0.12065 0.2794)
			(end 0.12065 0.3048)
			(stroke
				(width 0.1)
				(type default)
			)
			(layer "B.Fab")
		)
		(fp_line
			(start 0.12065 0.3048)
			(end 0.67945 0.3048)
			(stroke
				(width 0.1)
				(type default)
			)
			(layer "B.Fab")
		)
		(fp_line
			(start 0.67945 -0.305054)
			(end 0.12065 -0.305054)
			(stroke
				(width 0.1)
				(type default)
			)
			(layer "B.Fab")
		)
		(fp_line
			(start 0.67945 0.3048)
			(end 0.67945 -0.305054)
			(stroke
				(width 0.1)
				(type default)
			)
			(layer "B.Fab")
		)
		(pad "1" smd circle
			(at 0.40005 0 180)
			(size 0 0)
			(layers "B.Cu" "B.Mask" "B.Paste")
			(net "P3V3_AUX")
		)
		(pad "2" smd circle
			(at -0.40005 0 180)
			(size 0 0)
			(layers "B.Cu" "B.Mask" "B.Paste")
			(net "JTAG_DBP_BOOT_HALT_N")
		)
	)
	(footprint ""
		(layer "B.Cu")
		(at 329.170538 -186.36615 90)
		(property "Reference" "R297"
			(at 0 0 90)
			(layer "B.SilkS")
			(hide yes)
			(effects
				(font
					(size 1.27 1.27)
				)
				(justify mirror)
			)
		)
		(property "Value" ""
			(at 0 0 90)
			(layer "B.Fab")
			(effects
				(font
					(size 1.27 1.27)
				)
				(justify mirror)
			)
		)
		(duplicate_pad_numbers_are_jumpers no)
		(fp_line
			(start 0.7874 -0.4064)
			(end -0.7874 -0.4064)
			(stroke
				(width 0.1524)
				(type default)
			)
			(layer "B.SilkS")
		)
		(fp_line
			(start -0.7874 -0.4064)
			(end -0.7874 0.4064)
			(stroke
				(width 0.1524)
				(type default)
			)
			(layer "B.SilkS")
		)
		(fp_line
			(start 0.7874 0.4064)
			(end 0.7874 -0.4064)
			(stroke
				(width 0.1524)
				(type default)
			)
			(layer "B.SilkS")
		)
		(fp_line
			(start -0.7874 0.4064)
			(end 0.7874 0.4064)
			(stroke
				(width 0.1524)
				(type default)
			)
			(layer "B.SilkS")
		)
		(fp_line
			(start 0.67945 -0.305054)
			(end 0.12065 -0.305054)
			(stroke
				(width 0.1)
				(type default)
			)
			(layer "B.Fab")
		)
		(fp_line
			(start 0.12065 -0.305054)
			(end 0.12065 -0.2794)
			(stroke
				(width 0.1)
				(type default)
			)
			(layer "B.Fab")
		)
		(fp_line
			(start -0.12065 -0.3048)
			(end -0.67945 -0.3048)
			(stroke
				(width 0.1)
				(type default)
			)
			(layer "B.Fab")
		)
		(fp_line
			(start -0.67945 -0.3048)
			(end -0.67945 0.3048)
			(stroke
				(width 0.1)
				(type default)
			)
			(layer "B.Fab")
		)
		(fp_line
			(start 0.12065 -0.2794)
			(end -0.12065 -0.2794)
			(stroke
				(width 0.1)
				(type default)
			)
			(layer "B.Fab")
		)
		(fp_line
			(start -0.12065 -0.2794)
			(end -0.12065 -0.3048)
			(stroke
				(width 0.1)
				(type default)
			)
			(layer "B.Fab")
		)
		(fp_line
			(start 0.12065 0.2794)
			(end 0.12065 0.3048)
			(stroke
				(width 0.1)
				(type default)
			)
			(layer "B.Fab")
		)
		(fp_line
			(start -0.120396 0.2794)
			(end 0.12065 0.2794)
			(stroke
				(width 0.1)
				(type default)
			)
			(layer "B.Fab")
		)
		(fp_line
			(start 0.67945 0.3048)
			(end 0.67945 -0.305054)
			(stroke
				(width 0.1)
				(type default)
			)
			(layer "B.Fab")
		)
		(fp_line
			(start 0.12065 0.3048)
			(end 0.67945 0.3048)
			(stroke
				(width 0.1)
				(type default)
			)
			(layer "B.Fab")
		)
		(fp_line
			(start -0.120396 0.3048)
			(end -0.120396 0.2794)
			(stroke
				(width 0.1)
				(type default)
			)
			(layer "B.Fab")
		)
		(fp_line
			(start -0.67945 0.3048)
			(end -0.120396 0.3048)
			(stroke
				(width 0.1)
				(type default)
			)
			(layer "B.Fab")
		)
		(pad "1" smd circle
			(at 0.40005 0 270)
			(size 0 0)
			(layers "B.Cu" "B.Mask" "B.Paste")
			(net "H_CPU0_CATERR_LVC1_R_N")
		)
		(pad "2" smd circle
			(at -0.40005 0 270)
			(size 0 0)
			(layers "B.Cu" "B.Mask" "B.Paste")
			(net "H_CPU_CATERR_LVC1_R_N")
		)
	)
	(footprint ""
		(layer "B.Cu")
		(at 118.18112 -252.17628 -90)
		(property "Reference" "C351"
			(at 0 0 90)
			(layer "B.SilkS")
			(hide yes)
			(effects
				(font
					(size 1.27 1.27)
				)
				(justify mirror)
			)
		)
		(property "Value" ""
			(at 0 0 90)
			(layer "B.Fab")
			(effects
				(font
					(size 1.27 1.27)
				)
				(justify mirror)
			)
		)
		(duplicate_pad_numbers_are_jumpers no)
		(fp_line
			(start -1.524 0.762)
			(end 1.524 0.762)
			(stroke
				(width 0.1524)
				(type default)
			)
			(layer "B.SilkS")
		)
		(fp_line
			(start 1.524 0.762)
			(end 1.524 -0.762)
			(stroke
				(width 0.1524)
				(type default)
			)
			(layer "B.SilkS")
		)
		(fp_line
			(start -1.524 -0.762)
			(end -1.524 0.762)
			(stroke
				(width 0.1524)
				(type default)
			)
			(layer "B.SilkS")
		)
		(fp_line
			(start 1.524 -0.762)
			(end -1.524 -0.762)
			(stroke
				(width 0.1524)
				(type default)
			)
			(layer "B.SilkS")
		)
		(fp_line
			(start -1.1049 0.724916)
			(end -1.1049 -0.724916)
			(stroke
				(width 0.1)
				(type default)
			)
			(layer "B.Fab")
		)
		(fp_line
			(start 1.1049 0.724916)
			(end -1.1049 0.724916)
			(stroke
				(width 0.1)
				(type default)
			)
			(layer "B.Fab")
		)
		(fp_line
			(start -1.1049 -0.724916)
			(end 1.1049 -0.724916)
			(stroke
				(width 0.1)
				(type default)
			)
			(layer "B.Fab")
		)
		(fp_line
			(start 1.1049 -0.724916)
			(end 1.1049 0.724916)
			(stroke
				(width 0.1)
				(type default)
			)
			(layer "B.Fab")
		)
		(pad "1" smd rect
			(at 0.889 0 270)
			(size 1.016 1.27)
			(layers "B.Cu" "B.Mask" "B.Paste")
			(net "PVCCIN_CPU1")
		)
		(pad "2" smd rect
			(at -0.889 0 270)
			(size 1.016 1.27)
			(layers "B.Cu" "B.Mask" "B.Paste")
			(net "GND")
		)
	)
	(footprint ""
		(layer "B.Cu")
		(at 70.369684 -183.303926 90)
		(property "Reference" "R53"
			(at 0 0 90)
			(layer "B.SilkS")
			(hide yes)
			(effects
				(font
					(size 1.27 1.27)
				)
				(justify mirror)
			)
		)
		(property "Value" ""
			(at 0 0 90)
			(layer "B.Fab")
			(effects
				(font
					(size 1.27 1.27)
				)
				(justify mirror)
			)
		)
		(duplicate_pad_numbers_are_jumpers no)
		(fp_line
			(start 0.7874 -0.4064)
			(end -0.7874 -0.4064)
			(stroke
				(width 0.1524)
				(type default)
			)
			(layer "B.SilkS")
		)
		(fp_line
			(start -0.7874 -0.4064)
			(end -0.7874 0.4064)
			(stroke
				(width 0.1524)
				(type default)
			)
			(layer "B.SilkS")
		)
		(fp_line
			(start 0.7874 0.4064)
			(end 0.7874 -0.4064)
			(stroke
				(width 0.1524)
				(type default)
			)
			(layer "B.SilkS")
		)
		(fp_line
			(start -0.7874 0.4064)
			(end 0.7874 0.4064)
			(stroke
				(width 0.1524)
				(type default)
			)
			(layer "B.SilkS")
		)
		(fp_line
			(start 0.67945 -0.305054)
			(end 0.12065 -0.305054)
			(stroke
				(width 0.1)
				(type default)
			)
			(layer "B.Fab")
		)
		(fp_line
			(start 0.12065 -0.305054)
			(end 0.12065 -0.2794)
			(stroke
				(width 0.1)
				(type default)
			)
			(layer "B.Fab")
		)
		(fp_line
			(start -0.12065 -0.3048)
			(end -0.67945 -0.3048)
			(stroke
				(width 0.1)
				(type default)
			)
			(layer "B.Fab")
		)
		(fp_line
			(start -0.67945 -0.3048)
			(end -0.67945 0.3048)
			(stroke
				(width 0.1)
				(type default)
			)
			(layer "B.Fab")
		)
		(fp_line
			(start 0.12065 -0.2794)
			(end -0.12065 -0.2794)
			(stroke
				(width 0.1)
				(type default)
			)
			(layer "B.Fab")
		)
		(fp_line
			(start -0.12065 -0.2794)
			(end -0.12065 -0.3048)
			(stroke
				(width 0.1)
				(type default)
			)
			(layer "B.Fab")
		)
		(fp_line
			(start 0.12065 0.2794)
			(end 0.12065 0.3048)
			(stroke
				(width 0.1)
				(type default)
			)
			(layer "B.Fab")
		)
		(fp_line
			(start -0.120396 0.2794)
			(end 0.12065 0.2794)
			(stroke
				(width 0.1)
				(type default)
			)
			(layer "B.Fab")
		)
		(fp_line
			(start 0.67945 0.3048)
			(end 0.67945 -0.305054)
			(stroke
				(width 0.1)
				(type default)
			)
			(layer "B.Fab")
		)
		(fp_line
			(start 0.12065 0.3048)
			(end 0.67945 0.3048)
			(stroke
				(width 0.1)
				(type default)
			)
			(layer "B.Fab")
		)
		(fp_line
			(start -0.120396 0.3048)
			(end -0.120396 0.2794)
			(stroke
				(width 0.1)
				(type default)
			)
			(layer "B.Fab")
		)
		(fp_line
			(start -0.67945 0.3048)
			(end -0.120396 0.3048)
			(stroke
				(width 0.1)
				(type default)
			)
			(layer "B.Fab")
		)
		(pad "1" smd circle
			(at 0.40005 0 270)
			(size 0 0)
			(layers "B.Cu" "B.Mask" "B.Paste")
			(net "DBP_CPU1_HOOK8_MBP2_GTL_QS_R_N")
		)
		(pad "2" smd circle
			(at -0.40005 0 270)
			(size 0 0)
			(layers "B.Cu" "B.Mask" "B.Paste")
			(net "DBP_CPU_HOOK8_MBP2_GTL_QS_N")
		)
	)
	(footprint ""
		(layer "B.Cu")
		(at 182.245 -20.970748 180)
		(property "Reference" "R4513"
			(at 0 0 0)
			(layer "B.SilkS")
			(hide yes)
			(effects
				(font
					(size 1.27 1.27)
				)
				(justify mirror)
			)
		)
		(property "Value" ""
			(at 0 0 0)
			(layer "B.Fab")
			(effects
				(font
					(size 1.27 1.27)
				)
				(justify mirror)
			)
		)
		(duplicate_pad_numbers_are_jumpers no)
		(fp_line
			(start 0.7874 0.4064)
			(end 0.7874 -0.4064)
			(stroke
				(width 0.1524)
				(type default)
			)
			(layer "B.SilkS")
		)
		(fp_line
			(start 0.7874 -0.4064)
			(end -0.7874 -0.4064)
			(stroke
				(width 0.1524)
				(type default)
			)
			(layer "B.SilkS")
		)
		(fp_line
			(start -0.7874 0.4064)
			(end 0.7874 0.4064)
			(stroke
				(width 0.1524)
				(type default)
			)
			(layer "B.SilkS")
		)
		(fp_line
			(start -0.7874 -0.4064)
			(end -0.7874 0.4064)
			(stroke
				(width 0.1524)
				(type default)
			)
			(layer "B.SilkS")
		)
		(fp_line
			(start 0.67945 0.3048)
			(end 0.67945 -0.305054)
			(stroke
				(width 0.1)
				(type default)
			)
			(layer "B.Fab")
		)
		(fp_line
			(start 0.67945 -0.305054)
			(end 0.12065 -0.305054)
			(stroke
				(width 0.1)
				(type default)
			)
			(layer "B.Fab")
		)
		(fp_line
			(start 0.12065 0.3048)
			(end 0.67945 0.3048)
			(stroke
				(width 0.1)
				(type default)
			)
			(layer "B.Fab")
		)
		(fp_line
			(start 0.12065 0.2794)
			(end 0.12065 0.3048)
			(stroke
				(width 0.1)
				(type default)
			)
			(layer "B.Fab")
		)
		(fp_line
			(start 0.12065 -0.2794)
			(end -0.12065 -0.2794)
			(stroke
				(width 0.1)
				(type default)
			)
			(layer "B.Fab")
		)
		(fp_line
			(start 0.12065 -0.305054)
			(end 0.12065 -0.2794)
			(stroke
				(width 0.1)
				(type default)
			)
			(layer "B.Fab")
		)
		(fp_line
			(start -0.120396 0.3048)
			(end -0.120396 0.2794)
			(stroke
				(width 0.1)
				(type default)
			)
			(layer "B.Fab")
		)
		(fp_line
			(start -0.120396 0.2794)
			(end 0.12065 0.2794)
			(stroke
				(width 0.1)
				(type default)
			)
			(layer "B.Fab")
		)
		(fp_line
			(start -0.12065 -0.2794)
			(end -0.12065 -0.3048)
			(stroke
				(width 0.1)
				(type default)
			)
			(layer "B.Fab")
		)
		(fp_line
			(start -0.12065 -0.3048)
			(end -0.67945 -0.3048)
			(stroke
				(width 0.1)
				(type default)
			)
			(layer "B.Fab")
		)
		(fp_line
			(start -0.67945 0.3048)
			(end -0.120396 0.3048)
			(stroke
				(width 0.1)
				(type default)
			)
			(layer "B.Fab")
		)
		(fp_line
			(start -0.67945 -0.3048)
			(end -0.67945 0.3048)
			(stroke
				(width 0.1)
				(type default)
			)
			(layer "B.Fab")
		)
		(pad "1" smd circle
			(at 0.40005 0)
			(size 0 0)
			(layers "B.Cu" "B.Mask" "B.Paste")
			(net "SMB_HOST_3V3AUX_SDA")
		)
		(pad "2" smd circle
			(at -0.40005 0)
			(size 0 0)
			(layers "B.Cu" "B.Mask" "B.Paste")
			(net "SMB_HOST_3V3AUX_SDA_R5")
		)
	)
	(footprint ""
		(layer "B.Cu")
		(at 9.99363 -318.6176)
		(property "Reference" "R48"
			(at 0 0 0)
			(layer "B.SilkS")
			(hide yes)
			(effects
				(font
					(size 1.27 1.27)
				)
				(justify mirror)
			)
		)
		(property "Value" ""
			(at 0 0 0)
			(layer "B.Fab")
			(effects
				(font
					(size 1.27 1.27)
				)
				(justify mirror)
			)
		)
		(duplicate_pad_numbers_are_jumpers no)
		(fp_line
			(start -0.7874 -0.4064)
			(end -0.7874 0.4064)
			(stroke
				(width 0.1524)
				(type default)
			)
			(layer "B.SilkS")
		)
		(fp_line
			(start -0.7874 0.4064)
			(end 0.7874 0.4064)
			(stroke
				(width 0.1524)
				(type default)
			)
			(layer "B.SilkS")
		)
		(fp_line
			(start 0.7874 -0.4064)
			(end -0.7874 -0.4064)
			(stroke
				(width 0.1524)
				(type default)
			)
			(layer "B.SilkS")
		)
		(fp_line
			(start 0.7874 0.4064)
			(end 0.7874 -0.4064)
			(stroke
				(width 0.1524)
				(type default)
			)
			(layer "B.SilkS")
		)
		(fp_line
			(start -0.67945 -0.3048)
			(end -0.67945 0.3048)
			(stroke
				(width 0.1)
				(type default)
			)
			(layer "B.Fab")
		)
		(fp_line
			(start -0.67945 0.3048)
			(end -0.120396 0.3048)
			(stroke
				(width 0.1)
				(type default)
			)
			(layer "B.Fab")
		)
		(fp_line
			(start -0.12065 -0.3048)
			(end -0.67945 -0.3048)
			(stroke
				(width 0.1)
				(type default)
			)
			(layer "B.Fab")
		)
		(fp_line
			(start -0.12065 -0.2794)
			(end -0.12065 -0.3048)
			(stroke
				(width 0.1)
				(type default)
			)
			(layer "B.Fab")
		)
		(fp_line
			(start -0.120396 0.2794)
			(end 0.12065 0.2794)
			(stroke
				(width 0.1)
				(type default)
			)
			(layer "B.Fab")
		)
		(fp_line
			(start -0.120396 0.3048)
			(end -0.120396 0.2794)
			(stroke
				(width 0.1)
				(type default)
			)
			(layer "B.Fab")
		)
		(fp_line
			(start 0.12065 -0.305054)
			(end 0.12065 -0.2794)
			(stroke
				(width 0.1)
				(type default)
			)
			(layer "B.Fab")
		)
		(fp_line
			(start 0.12065 -0.2794)
			(end -0.12065 -0.2794)
			(stroke
				(width 0.1)
				(type default)
			)
			(layer "B.Fab")
		)
		(fp_line
			(start 0.12065 0.2794)
			(end 0.12065 0.3048)
			(stroke
				(width 0.1)
				(type default)
			)
			(layer "B.Fab")
		)
		(fp_line
			(start 0.12065 0.3048)
			(end 0.67945 0.3048)
			(stroke
				(width 0.1)
				(type default)
			)
			(layer "B.Fab")
		)
		(fp_line
			(start 0.67945 -0.305054)
			(end 0.12065 -0.305054)
			(stroke
				(width 0.1)
				(type default)
			)
			(layer "B.Fab")
		)
		(fp_line
			(start 0.67945 0.3048)
			(end 0.67945 -0.305054)
			(stroke
				(width 0.1)
				(type default)
			)
			(layer "B.Fab")
		)
		(pad "1" smd circle
			(at 0.40005 0 180)
			(size 0 0)
			(layers "B.Cu" "B.Mask" "B.Paste")
			(net "PD_CHD_CPU1_DIMM1_SAA")
		)
		(pad "2" smd circle
			(at -0.40005 0 180)
			(size 0 0)
			(layers "B.Cu" "B.Mask" "B.Paste")
			(net "GND")
		)
	)
	(footprint ""
		(layer "B.Cu")
		(at 278.724614 -321.549776 -90)
		(property "Reference" "C19"
			(at 0 0 90)
			(layer "B.SilkS")
			(hide yes)
			(effects
				(font
					(size 1.27 1.27)
				)
				(justify mirror)
			)
		)
		(property "Value" ""
			(at 0 0 90)
			(layer "B.Fab")
			(effects
				(font
					(size 1.27 1.27)
				)
				(justify mirror)
			)
		)
		(duplicate_pad_numbers_are_jumpers no)
		(fp_line
			(start -1.524 0.762)
			(end 1.524 0.762)
			(stroke
				(width 0.1524)
				(type default)
			)
			(layer "B.SilkS")
		)
		(fp_line
			(start 1.524 0.762)
			(end 1.524 -0.762)
			(stroke
				(width 0.1524)
				(type default)
			)
			(layer "B.SilkS")
		)
		(fp_line
			(start -1.524 -0.762)
			(end -1.524 0.762)
			(stroke
				(width 0.1524)
				(type default)
			)
			(layer "B.SilkS")
		)
		(fp_line
			(start 1.524 -0.762)
			(end -1.524 -0.762)
			(stroke
				(width 0.1524)
				(type default)
			)
			(layer "B.SilkS")
		)
		(fp_line
			(start -1.1049 0.724916)
			(end -1.1049 -0.724916)
			(stroke
				(width 0.1)
				(type default)
			)
			(layer "B.Fab")
		)
		(fp_line
			(start 1.1049 0.724916)
			(end -1.1049 0.724916)
			(stroke
				(width 0.1)
				(type default)
			)
			(layer "B.Fab")
		)
		(fp_line
			(start -1.1049 -0.724916)
			(end 1.1049 -0.724916)
			(stroke
				(width 0.1)
				(type default)
			)
			(layer "B.Fab")
		)
		(fp_line
			(start 1.1049 -0.724916)
			(end 1.1049 0.724916)
			(stroke
				(width 0.1)
				(type default)
			)
			(layer "B.Fab")
		)
		(pad "1" smd rect
			(at 0.889 0 270)
			(size 1.016 1.27)
			(layers "B.Cu" "B.Mask" "B.Paste")
			(net "P12V_S3_AUX_CPU0_NVDIMM")
		)
		(pad "2" smd rect
			(at -0.889 0 270)
			(size 1.016 1.27)
			(layers "B.Cu" "B.Mask" "B.Paste")
			(net "GND")
		)
	)
	(footprint ""
		(layer "B.Cu")
		(at 369.522502 -210.19389 180)
		(property "Reference" "C528"
			(at 0 0 0)
			(layer "B.SilkS")
			(hide yes)
			(effects
				(font
					(size 1.27 1.27)
				)
				(justify mirror)
			)
		)
		(property "Value" ""
			(at 0 0 0)
			(layer "B.Fab")
			(effects
				(font
					(size 1.27 1.27)
				)
				(justify mirror)
			)
		)
		(duplicate_pad_numbers_are_jumpers no)
		(fp_line
			(start 1.524 0.762)
			(end 1.524 -0.762)
			(stroke
				(width 0.1524)
				(type default)
			)
			(layer "B.SilkS")
		)
		(fp_line
			(start 1.524 -0.762)
			(end -1.524 -0.762)
			(stroke
				(width 0.1524)
				(type default)
			)
			(layer "B.SilkS")
		)
		(fp_line
			(start -1.524 0.762)
			(end 1.524 0.762)
			(stroke
				(width 0.1524)
				(type default)
			)
			(layer "B.SilkS")
		)
		(fp_line
			(start -1.524 -0.762)
			(end -1.524 0.762)
			(stroke
				(width 0.1524)
				(type default)
			)
			(layer "B.SilkS")
		)
		(fp_line
			(start 1.1049 0.724916)
			(end -1.1049 0.724916)
			(stroke
				(width 0.1)
				(type default)
			)
			(layer "B.Fab")
		)
		(fp_line
			(start 1.1049 -0.724916)
			(end 1.1049 0.724916)
			(stroke
				(width 0.1)
				(type default)
			)
			(layer "B.Fab")
		)
		(fp_line
			(start -1.1049 0.724916)
			(end -1.1049 -0.724916)
			(stroke
				(width 0.1)
				(type default)
			)
			(layer "B.Fab")
		)
		(fp_line
			(start -1.1049 -0.724916)
			(end 1.1049 -0.724916)
			(stroke
				(width 0.1)
				(type default)
			)
			(layer "B.Fab")
		)
		(pad "1" smd rect
			(at 0.889 0 180)
			(size 1.016 1.27)
			(layers "B.Cu" "B.Mask" "B.Paste")
			(net "PVCCINFAON_CPU0")
		)
		(pad "2" smd rect
			(at -0.889 0 180)
			(size 1.016 1.27)
			(layers "B.Cu" "B.Mask" "B.Paste")
			(net "GND")
		)
	)
	(footprint ""
		(layer "B.Cu")
		(at 369.485418 -294.009826 180)
		(property "Reference" "C383"
			(at 0 0 0)
			(layer "B.SilkS")
			(hide yes)
			(effects
				(font
					(size 1.27 1.27)
				)
				(justify mirror)
			)
		)
		(property "Value" ""
			(at 0 0 0)
			(layer "B.Fab")
			(effects
				(font
					(size 1.27 1.27)
				)
				(justify mirror)
			)
		)
		(duplicate_pad_numbers_are_jumpers no)
		(fp_line
			(start 1.524 0.762)
			(end 1.524 -0.762)
			(stroke
				(width 0.1524)
				(type default)
			)
			(layer "B.SilkS")
		)
		(fp_line
			(start 1.524 -0.762)
			(end -1.524 -0.762)
			(stroke
				(width 0.1524)
				(type default)
			)
			(layer "B.SilkS")
		)
		(fp_line
			(start -1.524 0.762)
			(end 1.524 0.762)
			(stroke
				(width 0.1524)
				(type default)
			)
			(layer "B.SilkS")
		)
		(fp_line
			(start -1.524 -0.762)
			(end -1.524 0.762)
			(stroke
				(width 0.1524)
				(type default)
			)
			(layer "B.SilkS")
		)
		(fp_line
			(start 1.1049 0.724916)
			(end -1.1049 0.724916)
			(stroke
				(width 0.1)
				(type default)
			)
			(layer "B.Fab")
		)
		(fp_line
			(start 1.1049 -0.724916)
			(end 1.1049 0.724916)
			(stroke
				(width 0.1)
				(type default)
			)
			(layer "B.Fab")
		)
		(fp_line
			(start -1.1049 0.724916)
			(end -1.1049 -0.724916)
			(stroke
				(width 0.1)
				(type default)
			)
			(layer "B.Fab")
		)
		(fp_line
			(start -1.1049 -0.724916)
			(end 1.1049 -0.724916)
			(stroke
				(width 0.1)
				(type default)
			)
			(layer "B.Fab")
		)
		(pad "1" smd rect
			(at 0.889 0 180)
			(size 1.016 1.27)
			(layers "B.Cu" "B.Mask" "B.Paste")
			(net "PVCCIN_CPU0")
		)
		(pad "2" smd rect
			(at -0.889 0 180)
			(size 1.016 1.27)
			(layers "B.Cu" "B.Mask" "B.Paste")
			(net "GND")
		)
	)
	(footprint ""
		(layer "B.Cu")
		(at 121.545604 -296.05478 180)
		(property "Reference" "C354"
			(at 0 0 0)
			(layer "B.SilkS")
			(hide yes)
			(effects
				(font
					(size 1.27 1.27)
				)
				(justify mirror)
			)
		)
		(property "Value" ""
			(at 0 0 0)
			(layer "B.Fab")
			(effects
				(font
					(size 1.27 1.27)
				)
				(justify mirror)
			)
		)
		(duplicate_pad_numbers_are_jumpers no)
		(fp_line
			(start 1.524 0.762)
			(end 1.524 -0.762)
			(stroke
				(width 0.1524)
				(type default)
			)
			(layer "B.SilkS")
		)
		(fp_line
			(start 1.524 -0.762)
			(end -1.524 -0.762)
			(stroke
				(width 0.1524)
				(type default)
			)
			(layer "B.SilkS")
		)
		(fp_line
			(start -1.524 0.762)
			(end 1.524 0.762)
			(stroke
				(width 0.1524)
				(type default)
			)
			(layer "B.SilkS")
		)
		(fp_line
			(start -1.524 -0.762)
			(end -1.524 0.762)
			(stroke
				(width 0.1524)
				(type default)
			)
			(layer "B.SilkS")
		)
		(fp_line
			(start 1.1049 0.724916)
			(end -1.1049 0.724916)
			(stroke
				(width 0.1)
				(type default)
			)
			(layer "B.Fab")
		)
		(fp_line
			(start 1.1049 -0.724916)
			(end 1.1049 0.724916)
			(stroke
				(width 0.1)
				(type default)
			)
			(layer "B.Fab")
		)
		(fp_line
			(start -1.1049 0.724916)
			(end -1.1049 -0.724916)
			(stroke
				(width 0.1)
				(type default)
			)
			(layer "B.Fab")
		)
		(fp_line
			(start -1.1049 -0.724916)
			(end 1.1049 -0.724916)
			(stroke
				(width 0.1)
				(type default)
			)
			(layer "B.Fab")
		)
		(pad "1" smd rect
			(at 0.889 0 180)
			(size 1.016 1.27)
			(layers "B.Cu" "B.Mask" "B.Paste")
			(net "PVCCIN_CPU1")
		)
		(pad "2" smd rect
			(at -0.889 0 180)
			(size 1.016 1.27)
			(layers "B.Cu" "B.Mask" "B.Paste")
			(net "GND")
		)
	)
	(footprint ""
		(layer "B.Cu")
		(at 243.003832 -97.552764 -90)
		(property "Reference" "C1309"
			(at 0 0 90)
			(layer "B.SilkS")
			(hide yes)
			(effects
				(font
					(size 1.27 1.27)
				)
				(justify mirror)
			)
		)
		(property "Value" ""
			(at 0 0 90)
			(layer "B.Fab")
			(effects
				(font
					(size 1.27 1.27)
				)
				(justify mirror)
			)
		)
		(duplicate_pad_numbers_are_jumpers no)
		(fp_line
			(start -1.2954 0.5842)
			(end 1.2954 0.5842)
			(stroke
				(width 0.1524)
				(type default)
			)
			(layer "B.SilkS")
		)
		(fp_line
			(start 1.2954 0.5842)
			(end 1.2954 -0.5842)
			(stroke
				(width 0.1524)
				(type default)
			)
			(layer "B.SilkS")
		)
		(fp_line
			(start -1.2954 -0.5842)
			(end -1.2954 0.5842)
			(stroke
				(width 0.1524)
				(type default)
			)
			(layer "B.SilkS")
		)
		(fp_line
			(start 0 -0.5842)
			(end 0 0.5842)
			(stroke
				(width 0.1524)
				(type default)
			)
			(layer "B.SilkS")
		)
		(fp_line
			(start 1.2954 -0.5842)
			(end -1.2954 -0.5842)
			(stroke
				(width 0.1524)
				(type default)
			)
			(layer "B.SilkS")
		)
		(fp_line
			(start -0.8636 0.4572)
			(end 0.8636 0.4572)
			(stroke
				(width 0.1)
				(type default)
			)
			(layer "B.Fab")
		)
		(fp_line
			(start 0.8636 0.4572)
			(end 0.8636 0.4064)
			(stroke
				(width 0.1)
				(type default)
			)
			(layer "B.Fab")
		)
		(fp_line
			(start -1.1938 0.4064)
			(end -0.8636 0.4064)
			(stroke
				(width 0.1)
				(type default)
			)
			(layer "B.Fab")
		)
		(fp_line
			(start -0.8636 0.4064)
			(end -0.8636 0.4572)
			(stroke
				(width 0.1)
				(type default)
			)
			(layer "B.Fab")
		)
		(fp_line
			(start 0.8636 0.4064)
			(end 1.1938 0.4064)
			(stroke
				(width 0.1)
				(type default)
			)
			(layer "B.Fab")
		)
		(fp_line
			(start 1.1938 0.4064)
			(end 1.1938 -0.4064)
			(stroke
				(width 0.1)
				(type default)
			)
			(layer "B.Fab")
		)
		(fp_line
			(start -1.1938 -0.4064)
			(end -1.1938 0.4064)
			(stroke
				(width 0.1)
				(type default)
			)
			(layer "B.Fab")
		)
		(fp_line
			(start -0.8636 -0.4064)
			(end -1.1938 -0.4064)
			(stroke
				(width 0.1)
				(type default)
			)
			(layer "B.Fab")
		)
		(fp_line
			(start 0.8636 -0.4064)
			(end 0.8636 -0.4572)
			(stroke
				(width 0.1)
				(type default)
			)
			(layer "B.Fab")
		)
		(fp_line
			(start 1.1938 -0.4064)
			(end 0.8636 -0.4064)
			(stroke
				(width 0.1)
				(type default)
			)
			(layer "B.Fab")
		)
		(fp_line
			(start -0.8636 -0.4572)
			(end -0.8636 -0.4064)
			(stroke
				(width 0.1)
				(type default)
			)
			(layer "B.Fab")
		)
		(fp_line
			(start 0.8636 -0.4572)
			(end -0.8636 -0.4572)
			(stroke
				(width 0.1)
				(type default)
			)
			(layer "B.Fab")
		)
		(pad "1" smd rect
			(at 0.7366 0 180)
			(size 0.7112 0.8128)
			(layers "B.Cu" "B.Mask" "B.Paste")
			(net "P3V3_AUX_CLK_GEN_VDDXTAL_CK440")
		)
		(pad "2" smd rect
			(at -0.7366 0 180)
			(size 0.7112 0.8128)
			(layers "B.Cu" "B.Mask" "B.Paste")
			(net "GND")
		)
	)
	(footprint ""
		(layer "B.Cu")
		(at 193.60388 -103.685848 180)
		(property "Reference" "R1435"
			(at 0 0 0)
			(layer "B.SilkS")
			(hide yes)
			(effects
				(font
					(size 1.27 1.27)
				)
				(justify mirror)
			)
		)
		(property "Value" ""
			(at 0 0 0)
			(layer "B.Fab")
			(effects
				(font
					(size 1.27 1.27)
				)
				(justify mirror)
			)
		)
		(duplicate_pad_numbers_are_jumpers no)
		(fp_line
			(start 0.7874 0.4064)
			(end 0.7874 -0.4064)
			(stroke
				(width 0.1524)
				(type default)
			)
			(layer "B.SilkS")
		)
		(fp_line
			(start 0.7874 -0.4064)
			(end -0.7874 -0.4064)
			(stroke
				(width 0.1524)
				(type default)
			)
			(layer "B.SilkS")
		)
		(fp_line
			(start -0.7874 0.4064)
			(end 0.7874 0.4064)
			(stroke
				(width 0.1524)
				(type default)
			)
			(layer "B.SilkS")
		)
		(fp_line
			(start -0.7874 -0.4064)
			(end -0.7874 0.4064)
			(stroke
				(width 0.1524)
				(type default)
			)
			(layer "B.SilkS")
		)
		(fp_line
			(start 0.67945 0.3048)
			(end 0.67945 -0.305054)
			(stroke
				(width 0.1)
				(type default)
			)
			(layer "B.Fab")
		)
		(fp_line
			(start 0.67945 -0.305054)
			(end 0.12065 -0.305054)
			(stroke
				(width 0.1)
				(type default)
			)
			(layer "B.Fab")
		)
		(fp_line
			(start 0.12065 0.3048)
			(end 0.67945 0.3048)
			(stroke
				(width 0.1)
				(type default)
			)
			(layer "B.Fab")
		)
		(fp_line
			(start 0.12065 0.2794)
			(end 0.12065 0.3048)
			(stroke
				(width 0.1)
				(type default)
			)
			(layer "B.Fab")
		)
		(fp_line
			(start 0.12065 -0.2794)
			(end -0.12065 -0.2794)
			(stroke
				(width 0.1)
				(type default)
			)
			(layer "B.Fab")
		)
		(fp_line
			(start 0.12065 -0.305054)
			(end 0.12065 -0.2794)
			(stroke
				(width 0.1)
				(type default)
			)
			(layer "B.Fab")
		)
		(fp_line
			(start -0.120396 0.3048)
			(end -0.120396 0.2794)
			(stroke
				(width 0.1)
				(type default)
			)
			(layer "B.Fab")
		)
		(fp_line
			(start -0.120396 0.2794)
			(end 0.12065 0.2794)
			(stroke
				(width 0.1)
				(type default)
			)
			(layer "B.Fab")
		)
		(fp_line
			(start -0.12065 -0.2794)
			(end -0.12065 -0.3048)
			(stroke
				(width 0.1)
				(type default)
			)
			(layer "B.Fab")
		)
		(fp_line
			(start -0.12065 -0.3048)
			(end -0.67945 -0.3048)
			(stroke
				(width 0.1)
				(type default)
			)
			(layer "B.Fab")
		)
		(fp_line
			(start -0.67945 0.3048)
			(end -0.120396 0.3048)
			(stroke
				(width 0.1)
				(type default)
			)
			(layer "B.Fab")
		)
		(fp_line
			(start -0.67945 -0.3048)
			(end -0.67945 0.3048)
			(stroke
				(width 0.1)
				(type default)
			)
			(layer "B.Fab")
		)
		(pad "1" smd circle
			(at 0.40005 0)
			(size 0 0)
			(layers "B.Cu" "B.Mask" "B.Paste")
			(net "FM_ADR_TRIGGER_N")
		)
		(pad "2" smd circle
			(at -0.40005 0)
			(size 0 0)
			(layers "B.Cu" "B.Mask" "B.Paste")
			(net "P3V3_AUX")
		)
	)
	(footprint ""
		(layer "B.Cu")
		(at 187.04052 -358.11587 180)
		(property "Reference" "PC1684"
			(at 0 0 0)
			(layer "B.SilkS")
			(hide yes)
			(effects
				(font
					(size 1.27 1.27)
				)
				(justify mirror)
			)
		)
		(property "Value" ""
			(at 0 0 0)
			(layer "B.Fab")
			(effects
				(font
					(size 1.27 1.27)
				)
				(justify mirror)
			)
		)
		(duplicate_pad_numbers_are_jumpers no)
		(fp_line
			(start 1.524 0.762)
			(end 1.524 -0.762)
			(stroke
				(width 0.1524)
				(type default)
			)
			(layer "B.SilkS")
		)
		(fp_line
			(start 1.524 -0.762)
			(end -1.524 -0.762)
			(stroke
				(width 0.1524)
				(type default)
			)
			(layer "B.SilkS")
		)
		(fp_line
			(start -1.524 0.762)
			(end 1.524 0.762)
			(stroke
				(width 0.1524)
				(type default)
			)
			(layer "B.SilkS")
		)
		(fp_line
			(start -1.524 -0.762)
			(end -1.524 0.762)
			(stroke
				(width 0.1524)
				(type default)
			)
			(layer "B.SilkS")
		)
		(fp_line
			(start 1.1049 0.724916)
			(end -1.1049 0.724916)
			(stroke
				(width 0.1)
				(type default)
			)
			(layer "B.Fab")
		)
		(fp_line
			(start 1.1049 -0.724916)
			(end 1.1049 0.724916)
			(stroke
				(width 0.1)
				(type default)
			)
			(layer "B.Fab")
		)
		(fp_line
			(start -1.1049 0.724916)
			(end -1.1049 -0.724916)
			(stroke
				(width 0.1)
				(type default)
			)
			(layer "B.Fab")
		)
		(fp_line
			(start -1.1049 -0.724916)
			(end 1.1049 -0.724916)
			(stroke
				(width 0.1)
				(type default)
			)
			(layer "B.Fab")
		)
		(pad "1" smd rect
			(at 0.889 0 180)
			(size 1.016 1.27)
			(layers "B.Cu" "B.Mask" "B.Paste")
			(net "SW_P12V_PVCCFA_EHV_FIVRA_CPU1_R")
		)
		(pad "2" smd rect
			(at -0.889 0 180)
			(size 1.016 1.27)
			(layers "B.Cu" "B.Mask" "B.Paste")
			(net "GND")
		)
	)
	(footprint ""
		(layer "B.Cu")
		(at 350.319848 -54.435756 90)
		(property "Reference" "C1273"
			(at 0 0 90)
			(layer "B.SilkS")
			(hide yes)
			(effects
				(font
					(size 1.27 1.27)
				)
				(justify mirror)
			)
		)
		(property "Value" ""
			(at 0 0 90)
			(layer "B.Fab")
			(effects
				(font
					(size 1.27 1.27)
				)
				(justify mirror)
			)
		)
		(duplicate_pad_numbers_are_jumpers no)
		(fp_line
			(start 1.524 -0.762)
			(end -1.524 -0.762)
			(stroke
				(width 0.1524)
				(type default)
			)
			(layer "B.SilkS")
		)
		(fp_line
			(start -1.524 -0.762)
			(end -1.524 0.762)
			(stroke
				(width 0.1524)
				(type default)
			)
			(layer "B.SilkS")
		)
		(fp_line
			(start 1.524 0.762)
			(end 1.524 -0.762)
			(stroke
				(width 0.1524)
				(type default)
			)
			(layer "B.SilkS")
		)
		(fp_line
			(start -1.524 0.762)
			(end 1.524 0.762)
			(stroke
				(width 0.1524)
				(type default)
			)
			(layer "B.SilkS")
		)
		(fp_line
			(start 1.1049 -0.724916)
			(end 1.1049 0.724916)
			(stroke
				(width 0.1)
				(type default)
			)
			(layer "B.Fab")
		)
		(fp_line
			(start -1.1049 -0.724916)
			(end 1.1049 -0.724916)
			(stroke
				(width 0.1)
				(type default)
			)
			(layer "B.Fab")
		)
		(fp_line
			(start 1.1049 0.724916)
			(end -1.1049 0.724916)
			(stroke
				(width 0.1)
				(type default)
			)
			(layer "B.Fab")
		)
		(fp_line
			(start -1.1049 0.724916)
			(end -1.1049 -0.724916)
			(stroke
				(width 0.1)
				(type default)
			)
			(layer "B.Fab")
		)
		(pad "1" smd rect
			(at 0.889 0 90)
			(size 1.016 1.27)
			(layers "B.Cu" "B.Mask" "B.Paste")
			(net "P1V8_PCH_PLL_AUX")
		)
		(pad "2" smd rect
			(at -0.889 0 90)
			(size 1.016 1.27)
			(layers "B.Cu" "B.Mask" "B.Paste")
			(net "GND")
		)
	)
	(footprint ""
		(layer "B.Cu")
		(at 66.150744 -14.26464)
		(property "Reference" "C1839"
			(at 0 0 0)
			(layer "B.SilkS")
			(hide yes)
			(effects
				(font
					(size 1.27 1.27)
				)
				(justify mirror)
			)
		)
		(property "Value" ""
			(at 0 0 0)
			(layer "B.Fab")
			(effects
				(font
					(size 1.27 1.27)
				)
				(justify mirror)
			)
		)
		(duplicate_pad_numbers_are_jumpers no)
		(fp_line
			(start -0.7874 -0.4064)
			(end -0.7874 0.4064)
			(stroke
				(width 0.1524)
				(type default)
			)
			(layer "B.SilkS")
		)
		(fp_line
			(start -0.7874 0.4064)
			(end 0.7874 0.4064)
			(stroke
				(width 0.1524)
				(type default)
			)
			(layer "B.SilkS")
		)
		(fp_line
			(start 0.7874 -0.4064)
			(end -0.7874 -0.4064)
			(stroke
				(width 0.1524)
				(type default)
			)
			(layer "B.SilkS")
		)
		(fp_line
			(start 0.7874 0.4064)
			(end 0.7874 -0.4064)
			(stroke
				(width 0.1524)
				(type default)
			)
			(layer "B.SilkS")
		)
		(fp_line
			(start -0.67945 -0.3048)
			(end -0.67945 0.3048)
			(stroke
				(width 0.1)
				(type default)
			)
			(layer "B.Fab")
		)
		(fp_line
			(start -0.67945 0.3048)
			(end -0.120396 0.3048)
			(stroke
				(width 0.1)
				(type default)
			)
			(layer "B.Fab")
		)
		(fp_line
			(start -0.12065 -0.3048)
			(end -0.67945 -0.3048)
			(stroke
				(width 0.1)
				(type default)
			)
			(layer "B.Fab")
		)
		(fp_line
			(start -0.12065 -0.2794)
			(end -0.12065 -0.3048)
			(stroke
				(width 0.1)
				(type default)
			)
			(layer "B.Fab")
		)
		(fp_line
			(start -0.120396 0.2794)
			(end 0.12065 0.2794)
			(stroke
				(width 0.1)
				(type default)
			)
			(layer "B.Fab")
		)
		(fp_line
			(start -0.120396 0.3048)
			(end -0.120396 0.2794)
			(stroke
				(width 0.1)
				(type default)
			)
			(layer "B.Fab")
		)
		(fp_line
			(start 0.12065 -0.305054)
			(end 0.12065 -0.2794)
			(stroke
				(width 0.1)
				(type default)
			)
			(layer "B.Fab")
		)
		(fp_line
			(start 0.12065 -0.2794)
			(end -0.12065 -0.2794)
			(stroke
				(width 0.1)
				(type default)
			)
			(layer "B.Fab")
		)
		(fp_line
			(start 0.12065 0.2794)
			(end 0.12065 0.3048)
			(stroke
				(width 0.1)
				(type default)
			)
			(layer "B.Fab")
		)
		(fp_line
			(start 0.12065 0.3048)
			(end 0.67945 0.3048)
			(stroke
				(width 0.1)
				(type default)
			)
			(layer "B.Fab")
		)
		(fp_line
			(start 0.67945 -0.305054)
			(end 0.12065 -0.305054)
			(stroke
				(width 0.1)
				(type default)
			)
			(layer "B.Fab")
		)
		(fp_line
			(start 0.67945 0.3048)
			(end 0.67945 -0.305054)
			(stroke
				(width 0.1)
				(type default)
			)
			(layer "B.Fab")
		)
		(pad "1" smd circle
			(at 0.40005 0 180)
			(size 0 0)
			(layers "B.Cu" "B.Mask" "B.Paste")
			(net "P12V_OCP_V3_2")
		)
		(pad "2" smd circle
			(at -0.40005 0 180)
			(size 0 0)
			(layers "B.Cu" "B.Mask" "B.Paste")
			(net "GND")
		)
	)
	(footprint ""
		(layer "B.Cu")
		(at 144.50187 -27.843988 180)
		(property "Reference" "R4465"
			(at 0 0 0)
			(layer "B.SilkS")
			(hide yes)
			(effects
				(font
					(size 1.27 1.27)
				)
				(justify mirror)
			)
		)
		(property "Value" ""
			(at 0 0 0)
			(layer "B.Fab")
			(effects
				(font
					(size 1.27 1.27)
				)
				(justify mirror)
			)
		)
		(duplicate_pad_numbers_are_jumpers no)
		(fp_line
			(start 0.7874 0.4064)
			(end 0.7874 -0.4064)
			(stroke
				(width 0.1524)
				(type default)
			)
			(layer "B.SilkS")
		)
		(fp_line
			(start 0.7874 -0.4064)
			(end -0.7874 -0.4064)
			(stroke
				(width 0.1524)
				(type default)
			)
			(layer "B.SilkS")
		)
		(fp_line
			(start -0.7874 0.4064)
			(end 0.7874 0.4064)
			(stroke
				(width 0.1524)
				(type default)
			)
			(layer "B.SilkS")
		)
		(fp_line
			(start -0.7874 -0.4064)
			(end -0.7874 0.4064)
			(stroke
				(width 0.1524)
				(type default)
			)
			(layer "B.SilkS")
		)
		(fp_line
			(start 0.67945 0.3048)
			(end 0.67945 -0.305054)
			(stroke
				(width 0.1)
				(type default)
			)
			(layer "B.Fab")
		)
		(fp_line
			(start 0.67945 -0.305054)
			(end 0.12065 -0.305054)
			(stroke
				(width 0.1)
				(type default)
			)
			(layer "B.Fab")
		)
		(fp_line
			(start 0.12065 0.3048)
			(end 0.67945 0.3048)
			(stroke
				(width 0.1)
				(type default)
			)
			(layer "B.Fab")
		)
		(fp_line
			(start 0.12065 0.2794)
			(end 0.12065 0.3048)
			(stroke
				(width 0.1)
				(type default)
			)
			(layer "B.Fab")
		)
		(fp_line
			(start 0.12065 -0.2794)
			(end -0.12065 -0.2794)
			(stroke
				(width 0.1)
				(type default)
			)
			(layer "B.Fab")
		)
		(fp_line
			(start 0.12065 -0.305054)
			(end 0.12065 -0.2794)
			(stroke
				(width 0.1)
				(type default)
			)
			(layer "B.Fab")
		)
		(fp_line
			(start -0.120396 0.3048)
			(end -0.120396 0.2794)
			(stroke
				(width 0.1)
				(type default)
			)
			(layer "B.Fab")
		)
		(fp_line
			(start -0.120396 0.2794)
			(end 0.12065 0.2794)
			(stroke
				(width 0.1)
				(type default)
			)
			(layer "B.Fab")
		)
		(fp_line
			(start -0.12065 -0.2794)
			(end -0.12065 -0.3048)
			(stroke
				(width 0.1)
				(type default)
			)
			(layer "B.Fab")
		)
		(fp_line
			(start -0.12065 -0.3048)
			(end -0.67945 -0.3048)
			(stroke
				(width 0.1)
				(type default)
			)
			(layer "B.Fab")
		)
		(fp_line
			(start -0.67945 0.3048)
			(end -0.120396 0.3048)
			(stroke
				(width 0.1)
				(type default)
			)
			(layer "B.Fab")
		)
		(fp_line
			(start -0.67945 -0.3048)
			(end -0.67945 0.3048)
			(stroke
				(width 0.1)
				(type default)
			)
			(layer "B.Fab")
		)
		(pad "1" smd circle
			(at 0.40005 0)
			(size 0 0)
			(layers "B.Cu" "B.Mask" "B.Paste")
			(net "PD_USB_HUB_2_EQ")
		)
		(pad "2" smd circle
			(at -0.40005 0)
			(size 0 0)
			(layers "B.Cu" "B.Mask" "B.Paste")
			(net "GND")
		)
	)
	(footprint ""
		(layer "B.Cu")
		(at 164.64788 -107.025948)
		(property "Reference" "R1853"
			(at 0 0 0)
			(layer "B.SilkS")
			(hide yes)
			(effects
				(font
					(size 1.27 1.27)
				)
				(justify mirror)
			)
		)
		(property "Value" ""
			(at 0 0 0)
			(layer "B.Fab")
			(effects
				(font
					(size 1.27 1.27)
				)
				(justify mirror)
			)
		)
		(duplicate_pad_numbers_are_jumpers no)
		(fp_line
			(start -0.7874 -0.4064)
			(end -0.7874 0.4064)
			(stroke
				(width 0.1524)
				(type default)
			)
			(layer "B.SilkS")
		)
		(fp_line
			(start -0.7874 0.4064)
			(end 0.7874 0.4064)
			(stroke
				(width 0.1524)
				(type default)
			)
			(layer "B.SilkS")
		)
		(fp_line
			(start 0.7874 -0.4064)
			(end -0.7874 -0.4064)
			(stroke
				(width 0.1524)
				(type default)
			)
			(layer "B.SilkS")
		)
		(fp_line
			(start 0.7874 0.4064)
			(end 0.7874 -0.4064)
			(stroke
				(width 0.1524)
				(type default)
			)
			(layer "B.SilkS")
		)
		(fp_line
			(start -0.67945 -0.3048)
			(end -0.67945 0.3048)
			(stroke
				(width 0.1)
				(type default)
			)
			(layer "B.Fab")
		)
		(fp_line
			(start -0.67945 0.3048)
			(end -0.120396 0.3048)
			(stroke
				(width 0.1)
				(type default)
			)
			(layer "B.Fab")
		)
		(fp_line
			(start -0.12065 -0.3048)
			(end -0.67945 -0.3048)
			(stroke
				(width 0.1)
				(type default)
			)
			(layer "B.Fab")
		)
		(fp_line
			(start -0.12065 -0.2794)
			(end -0.12065 -0.3048)
			(stroke
				(width 0.1)
				(type default)
			)
			(layer "B.Fab")
		)
		(fp_line
			(start -0.120396 0.2794)
			(end 0.12065 0.2794)
			(stroke
				(width 0.1)
				(type default)
			)
			(layer "B.Fab")
		)
		(fp_line
			(start -0.120396 0.3048)
			(end -0.120396 0.2794)
			(stroke
				(width 0.1)
				(type default)
			)
			(layer "B.Fab")
		)
		(fp_line
			(start 0.12065 -0.305054)
			(end 0.12065 -0.2794)
			(stroke
				(width 0.1)
				(type default)
			)
			(layer "B.Fab")
		)
		(fp_line
			(start 0.12065 -0.2794)
			(end -0.12065 -0.2794)
			(stroke
				(width 0.1)
				(type default)
			)
			(layer "B.Fab")
		)
		(fp_line
			(start 0.12065 0.2794)
			(end 0.12065 0.3048)
			(stroke
				(width 0.1)
				(type default)
			)
			(layer "B.Fab")
		)
		(fp_line
			(start 0.12065 0.3048)
			(end 0.67945 0.3048)
			(stroke
				(width 0.1)
				(type default)
			)
			(layer "B.Fab")
		)
		(fp_line
			(start 0.67945 -0.305054)
			(end 0.12065 -0.305054)
			(stroke
				(width 0.1)
				(type default)
			)
			(layer "B.Fab")
		)
		(fp_line
			(start 0.67945 0.3048)
			(end 0.67945 -0.305054)
			(stroke
				(width 0.1)
				(type default)
			)
			(layer "B.Fab")
		)
		(pad "1" smd circle
			(at 0.40005 0 180)
			(size 0 0)
			(layers "B.Cu" "B.Mask" "B.Paste")
			(net "VIRTUAL_RESEAT_FPGA_R_N")
		)
		(pad "2" smd circle
			(at -0.40005 0 180)
			(size 0 0)
			(layers "B.Cu" "B.Mask" "B.Paste")
			(net "VIRTUAL_RESEAT_FPGA_N")
		)
	)
	(footprint ""
		(layer "B.Cu")
		(at 368.767868 -324.911466 -90)
		(property "Reference" "PC290_P0_4"
			(at 0 0 90)
			(layer "B.SilkS")
			(hide yes)
			(effects
				(font
					(size 1.27 1.27)
				)
				(justify mirror)
			)
		)
		(property "Value" ""
			(at 0 0 90)
			(layer "B.Fab")
			(effects
				(font
					(size 1.27 1.27)
				)
				(justify mirror)
			)
		)
		(duplicate_pad_numbers_are_jumpers no)
		(fp_line
			(start -1.524 0.762)
			(end 1.524 0.762)
			(stroke
				(width 0.1524)
				(type default)
			)
			(layer "B.SilkS")
		)
		(fp_line
			(start 1.524 0.762)
			(end 1.524 -0.762)
			(stroke
				(width 0.1524)
				(type default)
			)
			(layer "B.SilkS")
		)
		(fp_line
			(start -1.524 -0.762)
			(end -1.524 0.762)
			(stroke
				(width 0.1524)
				(type default)
			)
			(layer "B.SilkS")
		)
		(fp_line
			(start 1.524 -0.762)
			(end -1.524 -0.762)
			(stroke
				(width 0.1524)
				(type default)
			)
			(layer "B.SilkS")
		)
		(fp_line
			(start -1.1049 0.724916)
			(end -1.1049 -0.724916)
			(stroke
				(width 0.1)
				(type default)
			)
			(layer "B.Fab")
		)
		(fp_line
			(start 1.1049 0.724916)
			(end -1.1049 0.724916)
			(stroke
				(width 0.1)
				(type default)
			)
			(layer "B.Fab")
		)
		(fp_line
			(start -1.1049 -0.724916)
			(end 1.1049 -0.724916)
			(stroke
				(width 0.1)
				(type default)
			)
			(layer "B.Fab")
		)
		(fp_line
			(start 1.1049 -0.724916)
			(end 1.1049 0.724916)
			(stroke
				(width 0.1)
				(type default)
			)
			(layer "B.Fab")
		)
		(pad "1" smd rect
			(at 0.889 0 270)
			(size 1.016 1.27)
			(layers "B.Cu" "B.Mask" "B.Paste")
			(net "PVCCIN_CPU0")
		)
		(pad "2" smd rect
			(at -0.889 0 270)
			(size 1.016 1.27)
			(layers "B.Cu" "B.Mask" "B.Paste")
			(net "GND")
		)
	)
	(footprint ""
		(layer "B.Cu")
		(at 358.861868 -334.703166 -90)
		(property "Reference" "PR147"
			(at 0 0 90)
			(layer "B.SilkS")
			(hide yes)
			(effects
				(font
					(size 1.27 1.27)
				)
				(justify mirror)
			)
		)
		(property "Value" ""
			(at 0 0 90)
			(layer "B.Fab")
			(effects
				(font
					(size 1.27 1.27)
				)
				(justify mirror)
			)
		)
		(duplicate_pad_numbers_are_jumpers no)
		(fp_line
			(start -0.7874 0.4064)
			(end 0.7874 0.4064)
			(stroke
				(width 0.1524)
				(type default)
			)
			(layer "B.SilkS")
		)
		(fp_line
			(start 0.7874 0.4064)
			(end 0.7874 -0.4064)
			(stroke
				(width 0.1524)
				(type default)
			)
			(layer "B.SilkS")
		)
		(fp_line
			(start -0.7874 -0.4064)
			(end -0.7874 0.4064)
			(stroke
				(width 0.1524)
				(type default)
			)
			(layer "B.SilkS")
		)
		(fp_line
			(start 0.7874 -0.4064)
			(end -0.7874 -0.4064)
			(stroke
				(width 0.1524)
				(type default)
			)
			(layer "B.SilkS")
		)
		(fp_line
			(start -0.67945 0.3048)
			(end -0.120396 0.3048)
			(stroke
				(width 0.1)
				(type default)
			)
			(layer "B.Fab")
		)
		(fp_line
			(start -0.120396 0.3048)
			(end -0.120396 0.2794)
			(stroke
				(width 0.1)
				(type default)
			)
			(layer "B.Fab")
		)
		(fp_line
			(start 0.12065 0.3048)
			(end 0.67945 0.3048)
			(stroke
				(width 0.1)
				(type default)
			)
			(layer "B.Fab")
		)
		(fp_line
			(start 0.67945 0.3048)
			(end 0.67945 -0.305054)
			(stroke
				(width 0.1)
				(type default)
			)
			(layer "B.Fab")
		)
		(fp_line
			(start -0.120396 0.2794)
			(end 0.12065 0.2794)
			(stroke
				(width 0.1)
				(type default)
			)
			(layer "B.Fab")
		)
		(fp_line
			(start 0.12065 0.2794)
			(end 0.12065 0.3048)
			(stroke
				(width 0.1)
				(type default)
			)
			(layer "B.Fab")
		)
		(fp_line
			(start -0.12065 -0.2794)
			(end -0.12065 -0.3048)
			(stroke
				(width 0.1)
				(type default)
			)
			(layer "B.Fab")
		)
		(fp_line
			(start 0.12065 -0.2794)
			(end -0.12065 -0.2794)
			(stroke
				(width 0.1)
				(type default)
			)
			(layer "B.Fab")
		)
		(fp_line
			(start -0.67945 -0.3048)
			(end -0.67945 0.3048)
			(stroke
				(width 0.1)
				(type default)
			)
			(layer "B.Fab")
		)
		(fp_line
			(start -0.12065 -0.3048)
			(end -0.67945 -0.3048)
			(stroke
				(width 0.1)
				(type default)
			)
			(layer "B.Fab")
		)
		(fp_line
			(start 0.12065 -0.305054)
			(end 0.12065 -0.2794)
			(stroke
				(width 0.1)
				(type default)
			)
			(layer "B.Fab")
		)
		(fp_line
			(start 0.67945 -0.305054)
			(end 0.12065 -0.305054)
			(stroke
				(width 0.1)
				(type default)
			)
			(layer "B.Fab")
		)
		(pad "1" smd circle
			(at 0.40005 0 90)
			(size 0 0)
			(layers "B.Cu" "B.Mask" "B.Paste")
			(net "PVCCIN_CPU0_PVCC")
		)
		(pad "2" smd circle
			(at -0.40005 0 90)
			(size 0 0)
			(layers "B.Cu" "B.Mask" "B.Paste")
			(net "PVCCIN_CPU0_VDD3")
		)
	)
	(footprint ""
		(layer "B.Cu")
		(at 193.38036 -119.344948 180)
		(property "Reference" "R2244"
			(at 0 0 0)
			(layer "B.SilkS")
			(hide yes)
			(effects
				(font
					(size 1.27 1.27)
				)
				(justify mirror)
			)
		)
		(property "Value" ""
			(at 0 0 0)
			(layer "B.Fab")
			(effects
				(font
					(size 1.27 1.27)
				)
				(justify mirror)
			)
		)
		(duplicate_pad_numbers_are_jumpers no)
		(fp_line
			(start 0.7874 0.4064)
			(end 0.7874 -0.4064)
			(stroke
				(width 0.1524)
				(type default)
			)
			(layer "B.SilkS")
		)
		(fp_line
			(start 0.7874 -0.4064)
			(end -0.7874 -0.4064)
			(stroke
				(width 0.1524)
				(type default)
			)
			(layer "B.SilkS")
		)
		(fp_line
			(start -0.7874 0.4064)
			(end 0.7874 0.4064)
			(stroke
				(width 0.1524)
				(type default)
			)
			(layer "B.SilkS")
		)
		(fp_line
			(start -0.7874 -0.4064)
			(end -0.7874 0.4064)
			(stroke
				(width 0.1524)
				(type default)
			)
			(layer "B.SilkS")
		)
		(fp_line
			(start 0.67945 0.3048)
			(end 0.67945 -0.305054)
			(stroke
				(width 0.1)
				(type default)
			)
			(layer "B.Fab")
		)
		(fp_line
			(start 0.67945 -0.305054)
			(end 0.12065 -0.305054)
			(stroke
				(width 0.1)
				(type default)
			)
			(layer "B.Fab")
		)
		(fp_line
			(start 0.12065 0.3048)
			(end 0.67945 0.3048)
			(stroke
				(width 0.1)
				(type default)
			)
			(layer "B.Fab")
		)
		(fp_line
			(start 0.12065 0.2794)
			(end 0.12065 0.3048)
			(stroke
				(width 0.1)
				(type default)
			)
			(layer "B.Fab")
		)
		(fp_line
			(start 0.12065 -0.2794)
			(end -0.12065 -0.2794)
			(stroke
				(width 0.1)
				(type default)
			)
			(layer "B.Fab")
		)
		(fp_line
			(start 0.12065 -0.305054)
			(end 0.12065 -0.2794)
			(stroke
				(width 0.1)
				(type default)
			)
			(layer "B.Fab")
		)
		(fp_line
			(start -0.120396 0.3048)
			(end -0.120396 0.2794)
			(stroke
				(width 0.1)
				(type default)
			)
			(layer "B.Fab")
		)
		(fp_line
			(start -0.120396 0.2794)
			(end 0.12065 0.2794)
			(stroke
				(width 0.1)
				(type default)
			)
			(layer "B.Fab")
		)
		(fp_line
			(start -0.12065 -0.2794)
			(end -0.12065 -0.3048)
			(stroke
				(width 0.1)
				(type default)
			)
			(layer "B.Fab")
		)
		(fp_line
			(start -0.12065 -0.3048)
			(end -0.67945 -0.3048)
			(stroke
				(width 0.1)
				(type default)
			)
			(layer "B.Fab")
		)
		(fp_line
			(start -0.67945 0.3048)
			(end -0.120396 0.3048)
			(stroke
				(width 0.1)
				(type default)
			)
			(layer "B.Fab")
		)
		(fp_line
			(start -0.67945 -0.3048)
			(end -0.67945 0.3048)
			(stroke
				(width 0.1)
				(type default)
			)
			(layer "B.Fab")
		)
		(pad "1" smd circle
			(at 0.40005 0)
			(size 0 0)
			(layers "B.Cu" "B.Mask" "B.Paste")
			(net "ROT_P1_RST_IND_N_R")
		)
		(pad "2" smd circle
			(at -0.40005 0)
			(size 0 0)
			(layers "B.Cu" "B.Mask" "B.Paste")
			(net "P3V3_AUX")
		)
	)
	(footprint ""
		(layer "B.Cu")
		(at 63.104268 -195.810378 -90)
		(property "Reference" "R4299"
			(at 0 0 90)
			(layer "B.SilkS")
			(hide yes)
			(effects
				(font
					(size 1.27 1.27)
				)
				(justify mirror)
			)
		)
		(property "Value" ""
			(at 0 0 90)
			(layer "B.Fab")
			(effects
				(font
					(size 1.27 1.27)
				)
				(justify mirror)
			)
		)
		(duplicate_pad_numbers_are_jumpers no)
		(fp_line
			(start -0.7874 0.4064)
			(end 0.7874 0.4064)
			(stroke
				(width 0.1524)
				(type default)
			)
			(layer "B.SilkS")
		)
		(fp_line
			(start 0.7874 0.4064)
			(end 0.7874 -0.4064)
			(stroke
				(width 0.1524)
				(type default)
			)
			(layer "B.SilkS")
		)
		(fp_line
			(start -0.7874 -0.4064)
			(end -0.7874 0.4064)
			(stroke
				(width 0.1524)
				(type default)
			)
			(layer "B.SilkS")
		)
		(fp_line
			(start 0.7874 -0.4064)
			(end -0.7874 -0.4064)
			(stroke
				(width 0.1524)
				(type default)
			)
			(layer "B.SilkS")
		)
		(fp_line
			(start -0.67945 0.3048)
			(end -0.120396 0.3048)
			(stroke
				(width 0.1)
				(type default)
			)
			(layer "B.Fab")
		)
		(fp_line
			(start -0.120396 0.3048)
			(end -0.120396 0.2794)
			(stroke
				(width 0.1)
				(type default)
			)
			(layer "B.Fab")
		)
		(fp_line
			(start 0.12065 0.3048)
			(end 0.67945 0.3048)
			(stroke
				(width 0.1)
				(type default)
			)
			(layer "B.Fab")
		)
		(fp_line
			(start 0.67945 0.3048)
			(end 0.67945 -0.305054)
			(stroke
				(width 0.1)
				(type default)
			)
			(layer "B.Fab")
		)
		(fp_line
			(start -0.120396 0.2794)
			(end 0.12065 0.2794)
			(stroke
				(width 0.1)
				(type default)
			)
			(layer "B.Fab")
		)
		(fp_line
			(start 0.12065 0.2794)
			(end 0.12065 0.3048)
			(stroke
				(width 0.1)
				(type default)
			)
			(layer "B.Fab")
		)
		(fp_line
			(start -0.12065 -0.2794)
			(end -0.12065 -0.3048)
			(stroke
				(width 0.1)
				(type default)
			)
			(layer "B.Fab")
		)
		(fp_line
			(start 0.12065 -0.2794)
			(end -0.12065 -0.2794)
			(stroke
				(width 0.1)
				(type default)
			)
			(layer "B.Fab")
		)
		(fp_line
			(start -0.67945 -0.3048)
			(end -0.67945 0.3048)
			(stroke
				(width 0.1)
				(type default)
			)
			(layer "B.Fab")
		)
		(fp_line
			(start -0.12065 -0.3048)
			(end -0.67945 -0.3048)
			(stroke
				(width 0.1)
				(type default)
			)
			(layer "B.Fab")
		)
		(fp_line
			(start 0.12065 -0.305054)
			(end 0.12065 -0.2794)
			(stroke
				(width 0.1)
				(type default)
			)
			(layer "B.Fab")
		)
		(fp_line
			(start 0.67945 -0.305054)
			(end 0.12065 -0.305054)
			(stroke
				(width 0.1)
				(type default)
			)
			(layer "B.Fab")
		)
		(pad "1" smd circle
			(at 0.40005 0 90)
			(size 0 0)
			(layers "B.Cu" "B.Mask" "B.Paste")
			(net "PWRGD_DRAMPWRGD_CPU1_AB_LVC1_R2")
		)
		(pad "2" smd circle
			(at -0.40005 0 90)
			(size 0 0)
			(layers "B.Cu" "B.Mask" "B.Paste")
			(net "PWRGD_DRAMPWRGD_CPU1_AB_LVC1_R")
		)
	)
	(footprint ""
		(layer "B.Cu")
		(at 334.931258 -58.465466 -90)
		(property "Reference" "C1197"
			(at 0 0 90)
			(layer "B.SilkS")
			(hide yes)
			(effects
				(font
					(size 1.27 1.27)
				)
				(justify mirror)
			)
		)
		(property "Value" ""
			(at 0 0 90)
			(layer "B.Fab")
			(effects
				(font
					(size 1.27 1.27)
				)
				(justify mirror)
			)
		)
		(duplicate_pad_numbers_are_jumpers no)
		(fp_line
			(start -1.2954 0.5842)
			(end 1.2954 0.5842)
			(stroke
				(width 0.1524)
				(type default)
			)
			(layer "B.SilkS")
		)
		(fp_line
			(start 1.2954 0.5842)
			(end 1.2954 -0.5842)
			(stroke
				(width 0.1524)
				(type default)
			)
			(layer "B.SilkS")
		)
		(fp_line
			(start -1.2954 -0.5842)
			(end -1.2954 0.5842)
			(stroke
				(width 0.1524)
				(type default)
			)
			(layer "B.SilkS")
		)
		(fp_line
			(start 0 -0.5842)
			(end 0 0.5842)
			(stroke
				(width 0.1524)
				(type default)
			)
			(layer "B.SilkS")
		)
		(fp_line
			(start 1.2954 -0.5842)
			(end -1.2954 -0.5842)
			(stroke
				(width 0.1524)
				(type default)
			)
			(layer "B.SilkS")
		)
		(fp_line
			(start -0.8636 0.4572)
			(end 0.8636 0.4572)
			(stroke
				(width 0.1)
				(type default)
			)
			(layer "B.Fab")
		)
		(fp_line
			(start 0.8636 0.4572)
			(end 0.8636 0.4064)
			(stroke
				(width 0.1)
				(type default)
			)
			(layer "B.Fab")
		)
		(fp_line
			(start -1.1938 0.4064)
			(end -0.8636 0.4064)
			(stroke
				(width 0.1)
				(type default)
			)
			(layer "B.Fab")
		)
		(fp_line
			(start -0.8636 0.4064)
			(end -0.8636 0.4572)
			(stroke
				(width 0.1)
				(type default)
			)
			(layer "B.Fab")
		)
		(fp_line
			(start 0.8636 0.4064)
			(end 1.1938 0.4064)
			(stroke
				(width 0.1)
				(type default)
			)
			(layer "B.Fab")
		)
		(fp_line
			(start 1.1938 0.4064)
			(end 1.1938 -0.4064)
			(stroke
				(width 0.1)
				(type default)
			)
			(layer "B.Fab")
		)
		(fp_line
			(start -1.1938 -0.4064)
			(end -1.1938 0.4064)
			(stroke
				(width 0.1)
				(type default)
			)
			(layer "B.Fab")
		)
		(fp_line
			(start -0.8636 -0.4064)
			(end -1.1938 -0.4064)
			(stroke
				(width 0.1)
				(type default)
			)
			(layer "B.Fab")
		)
		(fp_line
			(start 0.8636 -0.4064)
			(end 0.8636 -0.4572)
			(stroke
				(width 0.1)
				(type default)
			)
			(layer "B.Fab")
		)
		(fp_line
			(start 1.1938 -0.4064)
			(end 0.8636 -0.4064)
			(stroke
				(width 0.1)
				(type default)
			)
			(layer "B.Fab")
		)
		(fp_line
			(start -0.8636 -0.4572)
			(end -0.8636 -0.4064)
			(stroke
				(width 0.1)
				(type default)
			)
			(layer "B.Fab")
		)
		(fp_line
			(start 0.8636 -0.4572)
			(end -0.8636 -0.4572)
			(stroke
				(width 0.1)
				(type default)
			)
			(layer "B.Fab")
		)
		(pad "1" smd rect
			(at 0.7366 0 180)
			(size 0.7112 0.8128)
			(layers "B.Cu" "B.Mask" "B.Paste")
			(net "P1V8_PCH_AUX")
		)
		(pad "2" smd rect
			(at -0.7366 0 180)
			(size 0.7112 0.8128)
			(layers "B.Cu" "B.Mask" "B.Paste")
			(net "GND")
		)
	)
	(footprint ""
		(layer "B.Cu")
		(at 434.209444 -180.971698 -90)
		(property "Reference" "R1652"
			(at 0 0 90)
			(layer "B.SilkS")
			(hide yes)
			(effects
				(font
					(size 1.27 1.27)
				)
				(justify mirror)
			)
		)
		(property "Value" ""
			(at 0 0 90)
			(layer "B.Fab")
			(effects
				(font
					(size 1.27 1.27)
				)
				(justify mirror)
			)
		)
		(duplicate_pad_numbers_are_jumpers no)
		(fp_line
			(start -0.7874 0.4064)
			(end 0.7874 0.4064)
			(stroke
				(width 0.1524)
				(type default)
			)
			(layer "B.SilkS")
		)
		(fp_line
			(start 0.7874 0.4064)
			(end 0.7874 -0.4064)
			(stroke
				(width 0.1524)
				(type default)
			)
			(layer "B.SilkS")
		)
		(fp_line
			(start -0.7874 -0.4064)
			(end -0.7874 0.4064)
			(stroke
				(width 0.1524)
				(type default)
			)
			(layer "B.SilkS")
		)
		(fp_line
			(start 0.7874 -0.4064)
			(end -0.7874 -0.4064)
			(stroke
				(width 0.1524)
				(type default)
			)
			(layer "B.SilkS")
		)
		(fp_line
			(start -0.67945 0.3048)
			(end -0.120396 0.3048)
			(stroke
				(width 0.1)
				(type default)
			)
			(layer "B.Fab")
		)
		(fp_line
			(start -0.120396 0.3048)
			(end -0.120396 0.2794)
			(stroke
				(width 0.1)
				(type default)
			)
			(layer "B.Fab")
		)
		(fp_line
			(start 0.12065 0.3048)
			(end 0.67945 0.3048)
			(stroke
				(width 0.1)
				(type default)
			)
			(layer "B.Fab")
		)
		(fp_line
			(start 0.67945 0.3048)
			(end 0.67945 -0.305054)
			(stroke
				(width 0.1)
				(type default)
			)
			(layer "B.Fab")
		)
		(fp_line
			(start -0.120396 0.2794)
			(end 0.12065 0.2794)
			(stroke
				(width 0.1)
				(type default)
			)
			(layer "B.Fab")
		)
		(fp_line
			(start 0.12065 0.2794)
			(end 0.12065 0.3048)
			(stroke
				(width 0.1)
				(type default)
			)
			(layer "B.Fab")
		)
		(fp_line
			(start -0.12065 -0.2794)
			(end -0.12065 -0.3048)
			(stroke
				(width 0.1)
				(type default)
			)
			(layer "B.Fab")
		)
		(fp_line
			(start 0.12065 -0.2794)
			(end -0.12065 -0.2794)
			(stroke
				(width 0.1)
				(type default)
			)
			(layer "B.Fab")
		)
		(fp_line
			(start -0.67945 -0.3048)
			(end -0.67945 0.3048)
			(stroke
				(width 0.1)
				(type default)
			)
			(layer "B.Fab")
		)
		(fp_line
			(start -0.12065 -0.3048)
			(end -0.67945 -0.3048)
			(stroke
				(width 0.1)
				(type default)
			)
			(layer "B.Fab")
		)
		(fp_line
			(start 0.12065 -0.305054)
			(end 0.12065 -0.2794)
			(stroke
				(width 0.1)
				(type default)
			)
			(layer "B.Fab")
		)
		(fp_line
			(start 0.67945 -0.305054)
			(end 0.12065 -0.305054)
			(stroke
				(width 0.1)
				(type default)
			)
			(layer "B.Fab")
		)
		(pad "1" smd circle
			(at 0.40005 0 90)
			(size 0 0)
			(layers "B.Cu" "B.Mask" "B.Paste")
			(net "PWRGD_PVNN_MAIN_CPU0_R")
		)
		(pad "2" smd circle
			(at -0.40005 0 90)
			(size 0 0)
			(layers "B.Cu" "B.Mask" "B.Paste")
			(net "PWRGD_PVNN_MAIN_CPU0")
		)
	)
	(footprint ""
		(layer "B.Cu")
		(at 408.124152 -193.08953 -90)
		(property "Reference" "R279"
			(at 0 0 90)
			(layer "B.SilkS")
			(hide yes)
			(effects
				(font
					(size 1.27 1.27)
				)
				(justify mirror)
			)
		)
		(property "Value" ""
			(at 0 0 90)
			(layer "B.Fab")
			(effects
				(font
					(size 1.27 1.27)
				)
				(justify mirror)
			)
		)
		(duplicate_pad_numbers_are_jumpers no)
		(fp_line
			(start -0.7874 0.4064)
			(end 0.7874 0.4064)
			(stroke
				(width 0.1524)
				(type default)
			)
			(layer "B.SilkS")
		)
		(fp_line
			(start 0.7874 0.4064)
			(end 0.7874 -0.4064)
			(stroke
				(width 0.1524)
				(type default)
			)
			(layer "B.SilkS")
		)
		(fp_line
			(start -0.7874 -0.4064)
			(end -0.7874 0.4064)
			(stroke
				(width 0.1524)
				(type default)
			)
			(layer "B.SilkS")
		)
		(fp_line
			(start 0.7874 -0.4064)
			(end -0.7874 -0.4064)
			(stroke
				(width 0.1524)
				(type default)
			)
			(layer "B.SilkS")
		)
		(fp_line
			(start -0.67945 0.3048)
			(end -0.120396 0.3048)
			(stroke
				(width 0.1)
				(type default)
			)
			(layer "B.Fab")
		)
		(fp_line
			(start -0.120396 0.3048)
			(end -0.120396 0.2794)
			(stroke
				(width 0.1)
				(type default)
			)
			(layer "B.Fab")
		)
		(fp_line
			(start 0.12065 0.3048)
			(end 0.67945 0.3048)
			(stroke
				(width 0.1)
				(type default)
			)
			(layer "B.Fab")
		)
		(fp_line
			(start 0.67945 0.3048)
			(end 0.67945 -0.305054)
			(stroke
				(width 0.1)
				(type default)
			)
			(layer "B.Fab")
		)
		(fp_line
			(start -0.120396 0.2794)
			(end 0.12065 0.2794)
			(stroke
				(width 0.1)
				(type default)
			)
			(layer "B.Fab")
		)
		(fp_line
			(start 0.12065 0.2794)
			(end 0.12065 0.3048)
			(stroke
				(width 0.1)
				(type default)
			)
			(layer "B.Fab")
		)
		(fp_line
			(start -0.12065 -0.2794)
			(end -0.12065 -0.3048)
			(stroke
				(width 0.1)
				(type default)
			)
			(layer "B.Fab")
		)
		(fp_line
			(start 0.12065 -0.2794)
			(end -0.12065 -0.2794)
			(stroke
				(width 0.1)
				(type default)
			)
			(layer "B.Fab")
		)
		(fp_line
			(start -0.67945 -0.3048)
			(end -0.67945 0.3048)
			(stroke
				(width 0.1)
				(type default)
			)
			(layer "B.Fab")
		)
		(fp_line
			(start -0.12065 -0.3048)
			(end -0.67945 -0.3048)
			(stroke
				(width 0.1)
				(type default)
			)
			(layer "B.Fab")
		)
		(fp_line
			(start 0.12065 -0.305054)
			(end 0.12065 -0.2794)
			(stroke
				(width 0.1)
				(type default)
			)
			(layer "B.Fab")
		)
		(fp_line
			(start 0.67945 -0.305054)
			(end 0.12065 -0.305054)
			(stroke
				(width 0.1)
				(type default)
			)
			(layer "B.Fab")
		)
		(pad "1" smd circle
			(at 0.40005 0 90)
			(size 0 0)
			(layers "B.Cu" "B.Mask" "B.Paste")
			(net "PVNN_TERM_CPU0")
		)
		(pad "2" smd circle
			(at -0.40005 0 90)
			(size 0 0)
			(layers "B.Cu" "B.Mask" "B.Paste")
			(net "PU_CPU0_SOCKET_ID0")
		)
	)
	(footprint ""
		(layer "B.Cu")
		(at 416.080956 -318.730376)
		(property "Reference" "R34"
			(at 0 0 0)
			(layer "B.SilkS")
			(hide yes)
			(effects
				(font
					(size 1.27 1.27)
				)
				(justify mirror)
			)
		)
		(property "Value" ""
			(at 0 0 0)
			(layer "B.Fab")
			(effects
				(font
					(size 1.27 1.27)
				)
				(justify mirror)
			)
		)
		(duplicate_pad_numbers_are_jumpers no)
		(fp_line
			(start -0.7874 -0.4064)
			(end -0.7874 0.4064)
			(stroke
				(width 0.1524)
				(type default)
			)
			(layer "B.SilkS")
		)
		(fp_line
			(start -0.7874 0.4064)
			(end 0.7874 0.4064)
			(stroke
				(width 0.1524)
				(type default)
			)
			(layer "B.SilkS")
		)
		(fp_line
			(start 0.7874 -0.4064)
			(end -0.7874 -0.4064)
			(stroke
				(width 0.1524)
				(type default)
			)
			(layer "B.SilkS")
		)
		(fp_line
			(start 0.7874 0.4064)
			(end 0.7874 -0.4064)
			(stroke
				(width 0.1524)
				(type default)
			)
			(layer "B.SilkS")
		)
		(fp_line
			(start -0.67945 -0.3048)
			(end -0.67945 0.3048)
			(stroke
				(width 0.1)
				(type default)
			)
			(layer "B.Fab")
		)
		(fp_line
			(start -0.67945 0.3048)
			(end -0.120396 0.3048)
			(stroke
				(width 0.1)
				(type default)
			)
			(layer "B.Fab")
		)
		(fp_line
			(start -0.12065 -0.3048)
			(end -0.67945 -0.3048)
			(stroke
				(width 0.1)
				(type default)
			)
			(layer "B.Fab")
		)
		(fp_line
			(start -0.12065 -0.2794)
			(end -0.12065 -0.3048)
			(stroke
				(width 0.1)
				(type default)
			)
			(layer "B.Fab")
		)
		(fp_line
			(start -0.120396 0.2794)
			(end 0.12065 0.2794)
			(stroke
				(width 0.1)
				(type default)
			)
			(layer "B.Fab")
		)
		(fp_line
			(start -0.120396 0.3048)
			(end -0.120396 0.2794)
			(stroke
				(width 0.1)
				(type default)
			)
			(layer "B.Fab")
		)
		(fp_line
			(start 0.12065 -0.305054)
			(end 0.12065 -0.2794)
			(stroke
				(width 0.1)
				(type default)
			)
			(layer "B.Fab")
		)
		(fp_line
			(start 0.12065 -0.2794)
			(end -0.12065 -0.2794)
			(stroke
				(width 0.1)
				(type default)
			)
			(layer "B.Fab")
		)
		(fp_line
			(start 0.12065 0.2794)
			(end 0.12065 0.3048)
			(stroke
				(width 0.1)
				(type default)
			)
			(layer "B.Fab")
		)
		(fp_line
			(start 0.12065 0.3048)
			(end 0.67945 0.3048)
			(stroke
				(width 0.1)
				(type default)
			)
			(layer "B.Fab")
		)
		(fp_line
			(start 0.67945 -0.305054)
			(end 0.12065 -0.305054)
			(stroke
				(width 0.1)
				(type default)
			)
			(layer "B.Fab")
		)
		(fp_line
			(start 0.67945 0.3048)
			(end 0.67945 -0.305054)
			(stroke
				(width 0.1)
				(type default)
			)
			(layer "B.Fab")
		)
		(pad "1" smd circle
			(at 0.40005 0 180)
			(size 0 0)
			(layers "B.Cu" "B.Mask" "B.Paste")
			(net "PD_CHE_CPU0_DIMM1_SAA")
		)
		(pad "2" smd circle
			(at -0.40005 0 180)
			(size 0 0)
			(layers "B.Cu" "B.Mask" "B.Paste")
			(net "GND")
		)
	)
	(footprint ""
		(layer "B.Cu")
		(at 435.05628 -44.14012 90)
		(property "Reference" "R4682"
			(at 0 0 90)
			(layer "B.SilkS")
			(hide yes)
			(effects
				(font
					(size 1.27 1.27)
				)
				(justify mirror)
			)
		)
		(property "Value" ""
			(at 0 0 90)
			(layer "B.Fab")
			(effects
				(font
					(size 1.27 1.27)
				)
				(justify mirror)
			)
		)
		(duplicate_pad_numbers_are_jumpers no)
		(fp_line
			(start 0.7874 -0.4064)
			(end -0.7874 -0.4064)
			(stroke
				(width 0.1524)
				(type default)
			)
			(layer "B.SilkS")
		)
		(fp_line
			(start -0.7874 -0.4064)
			(end -0.7874 0.4064)
			(stroke
				(width 0.1524)
				(type default)
			)
			(layer "B.SilkS")
		)
		(fp_line
			(start 0.7874 0.4064)
			(end 0.7874 -0.4064)
			(stroke
				(width 0.1524)
				(type default)
			)
			(layer "B.SilkS")
		)
		(fp_line
			(start -0.7874 0.4064)
			(end 0.7874 0.4064)
			(stroke
				(width 0.1524)
				(type default)
			)
			(layer "B.SilkS")
		)
		(fp_line
			(start 0.67945 -0.305054)
			(end 0.12065 -0.305054)
			(stroke
				(width 0.1)
				(type default)
			)
			(layer "B.Fab")
		)
		(fp_line
			(start 0.12065 -0.305054)
			(end 0.12065 -0.2794)
			(stroke
				(width 0.1)
				(type default)
			)
			(layer "B.Fab")
		)
		(fp_line
			(start -0.12065 -0.3048)
			(end -0.67945 -0.3048)
			(stroke
				(width 0.1)
				(type default)
			)
			(layer "B.Fab")
		)
		(fp_line
			(start -0.67945 -0.3048)
			(end -0.67945 0.3048)
			(stroke
				(width 0.1)
				(type default)
			)
			(layer "B.Fab")
		)
		(fp_line
			(start 0.12065 -0.2794)
			(end -0.12065 -0.2794)
			(stroke
				(width 0.1)
				(type default)
			)
			(layer "B.Fab")
		)
		(fp_line
			(start -0.12065 -0.2794)
			(end -0.12065 -0.3048)
			(stroke
				(width 0.1)
				(type default)
			)
			(layer "B.Fab")
		)
		(fp_line
			(start 0.12065 0.2794)
			(end 0.12065 0.3048)
			(stroke
				(width 0.1)
				(type default)
			)
			(layer "B.Fab")
		)
		(fp_line
			(start -0.120396 0.2794)
			(end 0.12065 0.2794)
			(stroke
				(width 0.1)
				(type default)
			)
			(layer "B.Fab")
		)
		(fp_line
			(start 0.67945 0.3048)
			(end 0.67945 -0.305054)
			(stroke
				(width 0.1)
				(type default)
			)
			(layer "B.Fab")
		)
		(fp_line
			(start 0.12065 0.3048)
			(end 0.67945 0.3048)
			(stroke
				(width 0.1)
				(type default)
			)
			(layer "B.Fab")
		)
		(fp_line
			(start -0.120396 0.3048)
			(end -0.120396 0.2794)
			(stroke
				(width 0.1)
				(type default)
			)
			(layer "B.Fab")
		)
		(fp_line
			(start -0.67945 0.3048)
			(end -0.120396 0.3048)
			(stroke
				(width 0.1)
				(type default)
			)
			(layer "B.Fab")
		)
		(pad "1" smd circle
			(at 0.40005 0 270)
			(size 0 0)
			(layers "B.Cu" "B.Mask" "B.Paste")
			(net "PWRGD_P5V")
		)
		(pad "2" smd circle
			(at -0.40005 0 270)
			(size 0 0)
			(layers "B.Cu" "B.Mask" "B.Paste")
			(net "GND")
		)
	)
	(footprint ""
		(layer "B.Cu")
		(at 346.44076 -58.38317 45)
		(property "Reference" "C157"
			(at 0 0 45)
			(layer "B.SilkS")
			(hide yes)
			(effects
				(font
					(size 1.27 1.27)
				)
				(justify mirror)
			)
		)
		(property "Value" ""
			(at 0 0 45)
			(layer "B.Fab")
			(effects
				(font
					(size 1.27 1.27)
				)
				(justify mirror)
			)
		)
		(duplicate_pad_numbers_are_jumpers no)
		(fp_line
			(start -0.299941 -0.15015)
			(end -0.299941 0.15015)
			(stroke
				(width 0.1)
				(type default)
			)
			(layer "B.Fab")
		)
		(fp_line
			(start -0.299941 0.15015)
			(end 0.299941 0.15015)
			(stroke
				(width 0.1)
				(type default)
			)
			(layer "B.Fab")
		)
		(fp_line
			(start 0.299941 -0.15015)
			(end -0.299941 -0.15015)
			(stroke
				(width 0.1)
				(type default)
			)
			(layer "B.Fab")
		)
		(fp_line
			(start 0.299941 0.15015)
			(end 0.299941 -0.15015)
			(stroke
				(width 0.1)
				(type default)
			)
			(layer "B.Fab")
		)
		(pad "1" smd rect
			(at 0.266699 0 225)
			(size 0.3048 0.381)
			(layers "B.Cu" "B.Mask" "B.Paste")
			(net "DMI_CPU0_PCH_RX_C_DN<6>")
		)
		(pad "2" smd rect
			(at -0.266699 0 225)
			(size 0.3048 0.381)
			(layers "B.Cu" "B.Mask" "B.Paste")
			(net "DMI_CPU0_PCH_RX_DN<6>")
		)
	)
	(footprint ""
		(layer "B.Cu")
		(at 260.157214 -319.263776 180)
		(property "Reference" "R2731"
			(at 0 0 0)
			(layer "B.SilkS")
			(hide yes)
			(effects
				(font
					(size 1.27 1.27)
				)
				(justify mirror)
			)
		)
		(property "Value" ""
			(at 0 0 0)
			(layer "B.Fab")
			(effects
				(font
					(size 1.27 1.27)
				)
				(justify mirror)
			)
		)
		(duplicate_pad_numbers_are_jumpers no)
		(fp_line
			(start 0.7874 0.4064)
			(end 0.7874 -0.4064)
			(stroke
				(width 0.1524)
				(type default)
			)
			(layer "B.SilkS")
		)
		(fp_line
			(start 0.7874 -0.4064)
			(end -0.7874 -0.4064)
			(stroke
				(width 0.1524)
				(type default)
			)
			(layer "B.SilkS")
		)
		(fp_line
			(start -0.7874 0.4064)
			(end 0.7874 0.4064)
			(stroke
				(width 0.1524)
				(type default)
			)
			(layer "B.SilkS")
		)
		(fp_line
			(start -0.7874 -0.4064)
			(end -0.7874 0.4064)
			(stroke
				(width 0.1524)
				(type default)
			)
			(layer "B.SilkS")
		)
		(fp_line
			(start 0.67945 0.3048)
			(end 0.67945 -0.305054)
			(stroke
				(width 0.1)
				(type default)
			)
			(layer "B.Fab")
		)
		(fp_line
			(start 0.67945 -0.305054)
			(end 0.12065 -0.305054)
			(stroke
				(width 0.1)
				(type default)
			)
			(layer "B.Fab")
		)
		(fp_line
			(start 0.12065 0.3048)
			(end 0.67945 0.3048)
			(stroke
				(width 0.1)
				(type default)
			)
			(layer "B.Fab")
		)
		(fp_line
			(start 0.12065 0.2794)
			(end 0.12065 0.3048)
			(stroke
				(width 0.1)
				(type default)
			)
			(layer "B.Fab")
		)
		(fp_line
			(start 0.12065 -0.2794)
			(end -0.12065 -0.2794)
			(stroke
				(width 0.1)
				(type default)
			)
			(layer "B.Fab")
		)
		(fp_line
			(start 0.12065 -0.305054)
			(end 0.12065 -0.2794)
			(stroke
				(width 0.1)
				(type default)
			)
			(layer "B.Fab")
		)
		(fp_line
			(start -0.120396 0.3048)
			(end -0.120396 0.2794)
			(stroke
				(width 0.1)
				(type default)
			)
			(layer "B.Fab")
		)
		(fp_line
			(start -0.120396 0.2794)
			(end 0.12065 0.2794)
			(stroke
				(width 0.1)
				(type default)
			)
			(layer "B.Fab")
		)
		(fp_line
			(start -0.12065 -0.2794)
			(end -0.12065 -0.3048)
			(stroke
				(width 0.1)
				(type default)
			)
			(layer "B.Fab")
		)
		(fp_line
			(start -0.12065 -0.3048)
			(end -0.67945 -0.3048)
			(stroke
				(width 0.1)
				(type default)
			)
			(layer "B.Fab")
		)
		(fp_line
			(start -0.67945 0.3048)
			(end -0.120396 0.3048)
			(stroke
				(width 0.1)
				(type default)
			)
			(layer "B.Fab")
		)
		(fp_line
			(start -0.67945 -0.3048)
			(end -0.67945 0.3048)
			(stroke
				(width 0.1)
				(type default)
			)
			(layer "B.Fab")
		)
		(pad "1" smd circle
			(at 0.40005 0)
			(size 0 0)
			(layers "B.Cu" "B.Mask" "B.Paste")
			(net "PWRGD_CHD_CPU0_DIMM1")
		)
		(pad "2" smd circle
			(at -0.40005 0)
			(size 0 0)
			(layers "B.Cu" "B.Mask" "B.Paste")
			(net "PWRGD_FAIL_CPU0_CD")
		)
	)
	(footprint ""
		(layer "B.Cu")
		(at 299.129958 -193.67373 90)
		(property "Reference" "R177"
			(at 0 0 90)
			(layer "B.SilkS")
			(hide yes)
			(effects
				(font
					(size 1.27 1.27)
				)
				(justify mirror)
			)
		)
		(property "Value" ""
			(at 0 0 90)
			(layer "B.Fab")
			(effects
				(font
					(size 1.27 1.27)
				)
				(justify mirror)
			)
		)
		(duplicate_pad_numbers_are_jumpers no)
		(fp_line
			(start 0.7874 -0.4064)
			(end -0.7874 -0.4064)
			(stroke
				(width 0.1524)
				(type default)
			)
			(layer "B.SilkS")
		)
		(fp_line
			(start -0.7874 -0.4064)
			(end -0.7874 0.4064)
			(stroke
				(width 0.1524)
				(type default)
			)
			(layer "B.SilkS")
		)
		(fp_line
			(start 0.7874 0.4064)
			(end 0.7874 -0.4064)
			(stroke
				(width 0.1524)
				(type default)
			)
			(layer "B.SilkS")
		)
		(fp_line
			(start -0.7874 0.4064)
			(end 0.7874 0.4064)
			(stroke
				(width 0.1524)
				(type default)
			)
			(layer "B.SilkS")
		)
		(fp_line
			(start 0.67945 -0.305054)
			(end 0.12065 -0.305054)
			(stroke
				(width 0.1)
				(type default)
			)
			(layer "B.Fab")
		)
		(fp_line
			(start 0.12065 -0.305054)
			(end 0.12065 -0.2794)
			(stroke
				(width 0.1)
				(type default)
			)
			(layer "B.Fab")
		)
		(fp_line
			(start -0.12065 -0.3048)
			(end -0.67945 -0.3048)
			(stroke
				(width 0.1)
				(type default)
			)
			(layer "B.Fab")
		)
		(fp_line
			(start -0.67945 -0.3048)
			(end -0.67945 0.3048)
			(stroke
				(width 0.1)
				(type default)
			)
			(layer "B.Fab")
		)
		(fp_line
			(start 0.12065 -0.2794)
			(end -0.12065 -0.2794)
			(stroke
				(width 0.1)
				(type default)
			)
			(layer "B.Fab")
		)
		(fp_line
			(start -0.12065 -0.2794)
			(end -0.12065 -0.3048)
			(stroke
				(width 0.1)
				(type default)
			)
			(layer "B.Fab")
		)
		(fp_line
			(start 0.12065 0.2794)
			(end 0.12065 0.3048)
			(stroke
				(width 0.1)
				(type default)
			)
			(layer "B.Fab")
		)
		(fp_line
			(start -0.120396 0.2794)
			(end 0.12065 0.2794)
			(stroke
				(width 0.1)
				(type default)
			)
			(layer "B.Fab")
		)
		(fp_line
			(start 0.67945 0.3048)
			(end 0.67945 -0.305054)
			(stroke
				(width 0.1)
				(type default)
			)
			(layer "B.Fab")
		)
		(fp_line
			(start 0.12065 0.3048)
			(end 0.67945 0.3048)
			(stroke
				(width 0.1)
				(type default)
			)
			(layer "B.Fab")
		)
		(fp_line
			(start -0.120396 0.3048)
			(end -0.120396 0.2794)
			(stroke
				(width 0.1)
				(type default)
			)
			(layer "B.Fab")
		)
		(fp_line
			(start -0.67945 0.3048)
			(end -0.120396 0.3048)
			(stroke
				(width 0.1)
				(type default)
			)
			(layer "B.Fab")
		)
		(pad "1" smd circle
			(at 0.40005 0 270)
			(size 0 0)
			(layers "B.Cu" "B.Mask" "B.Paste")
			(net "PWRGD_DRAMPWRGD_CPU0_CD_LVC1_R2")
		)
		(pad "2" smd circle
			(at -0.40005 0 270)
			(size 0 0)
			(layers "B.Cu" "B.Mask" "B.Paste")
			(net "PVCCD_HV_CPU0")
		)
	)
	(footprint ""
		(layer "B.Cu")
		(at 248.943368 -105.256584 -90)
		(property "Reference" "R1484"
			(at 0 0 90)
			(layer "B.SilkS")
			(hide yes)
			(effects
				(font
					(size 1.27 1.27)
				)
				(justify mirror)
			)
		)
		(property "Value" ""
			(at 0 0 90)
			(layer "B.Fab")
			(effects
				(font
					(size 1.27 1.27)
				)
				(justify mirror)
			)
		)
		(duplicate_pad_numbers_are_jumpers no)
		(fp_line
			(start -0.7874 0.4064)
			(end 0.7874 0.4064)
			(stroke
				(width 0.1524)
				(type default)
			)
			(layer "B.SilkS")
		)
		(fp_line
			(start 0.7874 0.4064)
			(end 0.7874 -0.4064)
			(stroke
				(width 0.1524)
				(type default)
			)
			(layer "B.SilkS")
		)
		(fp_line
			(start -0.7874 -0.4064)
			(end -0.7874 0.4064)
			(stroke
				(width 0.1524)
				(type default)
			)
			(layer "B.SilkS")
		)
		(fp_line
			(start 0.7874 -0.4064)
			(end -0.7874 -0.4064)
			(stroke
				(width 0.1524)
				(type default)
			)
			(layer "B.SilkS")
		)
		(fp_line
			(start -0.67945 0.3048)
			(end -0.120396 0.3048)
			(stroke
				(width 0.1)
				(type default)
			)
			(layer "B.Fab")
		)
		(fp_line
			(start -0.120396 0.3048)
			(end -0.120396 0.2794)
			(stroke
				(width 0.1)
				(type default)
			)
			(layer "B.Fab")
		)
		(fp_line
			(start 0.12065 0.3048)
			(end 0.67945 0.3048)
			(stroke
				(width 0.1)
				(type default)
			)
			(layer "B.Fab")
		)
		(fp_line
			(start 0.67945 0.3048)
			(end 0.67945 -0.305054)
			(stroke
				(width 0.1)
				(type default)
			)
			(layer "B.Fab")
		)
		(fp_line
			(start -0.120396 0.2794)
			(end 0.12065 0.2794)
			(stroke
				(width 0.1)
				(type default)
			)
			(layer "B.Fab")
		)
		(fp_line
			(start 0.12065 0.2794)
			(end 0.12065 0.3048)
			(stroke
				(width 0.1)
				(type default)
			)
			(layer "B.Fab")
		)
		(fp_line
			(start -0.12065 -0.2794)
			(end -0.12065 -0.3048)
			(stroke
				(width 0.1)
				(type default)
			)
			(layer "B.Fab")
		)
		(fp_line
			(start 0.12065 -0.2794)
			(end -0.12065 -0.2794)
			(stroke
				(width 0.1)
				(type default)
			)
			(layer "B.Fab")
		)
		(fp_line
			(start -0.67945 -0.3048)
			(end -0.67945 0.3048)
			(stroke
				(width 0.1)
				(type default)
			)
			(layer "B.Fab")
		)
		(fp_line
			(start -0.12065 -0.3048)
			(end -0.67945 -0.3048)
			(stroke
				(width 0.1)
				(type default)
			)
			(layer "B.Fab")
		)
		(fp_line
			(start 0.12065 -0.305054)
			(end 0.12065 -0.2794)
			(stroke
				(width 0.1)
				(type default)
			)
			(layer "B.Fab")
		)
		(fp_line
			(start 0.67945 -0.305054)
			(end 0.12065 -0.305054)
			(stroke
				(width 0.1)
				(type default)
			)
			(layer "B.Fab")
		)
		(pad "1" smd circle
			(at 0.40005 0 90)
			(size 0 0)
			(layers "B.Cu" "B.Mask" "B.Paste")
			(net "FM_CK440Q_DEV_25M_EN")
		)
		(pad "2" smd circle
			(at -0.40005 0 90)
			(size 0 0)
			(layers "B.Cu" "B.Mask" "B.Paste")
			(net "GND")
		)
	)
	(footprint ""
		(layer "B.Cu")
		(at 200.031858 -192.95237)
		(property "Reference" "R740"
			(at 0 0 0)
			(layer "B.SilkS")
			(hide yes)
			(effects
				(font
					(size 1.27 1.27)
				)
				(justify mirror)
			)
		)
		(property "Value" ""
			(at 0 0 0)
			(layer "B.Fab")
			(effects
				(font
					(size 1.27 1.27)
				)
				(justify mirror)
			)
		)
		(duplicate_pad_numbers_are_jumpers no)
		(fp_line
			(start -0.7874 -0.4064)
			(end -0.7874 0.4064)
			(stroke
				(width 0.1524)
				(type default)
			)
			(layer "B.SilkS")
		)
		(fp_line
			(start -0.7874 0.4064)
			(end 0.7874 0.4064)
			(stroke
				(width 0.1524)
				(type default)
			)
			(layer "B.SilkS")
		)
		(fp_line
			(start 0.7874 -0.4064)
			(end -0.7874 -0.4064)
			(stroke
				(width 0.1524)
				(type default)
			)
			(layer "B.SilkS")
		)
		(fp_line
			(start 0.7874 0.4064)
			(end 0.7874 -0.4064)
			(stroke
				(width 0.1524)
				(type default)
			)
			(layer "B.SilkS")
		)
		(fp_line
			(start -0.67945 -0.3048)
			(end -0.67945 0.3048)
			(stroke
				(width 0.1)
				(type default)
			)
			(layer "B.Fab")
		)
		(fp_line
			(start -0.67945 0.3048)
			(end -0.120396 0.3048)
			(stroke
				(width 0.1)
				(type default)
			)
			(layer "B.Fab")
		)
		(fp_line
			(start -0.12065 -0.3048)
			(end -0.67945 -0.3048)
			(stroke
				(width 0.1)
				(type default)
			)
			(layer "B.Fab")
		)
		(fp_line
			(start -0.12065 -0.2794)
			(end -0.12065 -0.3048)
			(stroke
				(width 0.1)
				(type default)
			)
			(layer "B.Fab")
		)
		(fp_line
			(start -0.120396 0.2794)
			(end 0.12065 0.2794)
			(stroke
				(width 0.1)
				(type default)
			)
			(layer "B.Fab")
		)
		(fp_line
			(start -0.120396 0.3048)
			(end -0.120396 0.2794)
			(stroke
				(width 0.1)
				(type default)
			)
			(layer "B.Fab")
		)
		(fp_line
			(start 0.12065 -0.305054)
			(end 0.12065 -0.2794)
			(stroke
				(width 0.1)
				(type default)
			)
			(layer "B.Fab")
		)
		(fp_line
			(start 0.12065 -0.2794)
			(end -0.12065 -0.2794)
			(stroke
				(width 0.1)
				(type default)
			)
			(layer "B.Fab")
		)
		(fp_line
			(start 0.12065 0.2794)
			(end 0.12065 0.3048)
			(stroke
				(width 0.1)
				(type default)
			)
			(layer "B.Fab")
		)
		(fp_line
			(start 0.12065 0.3048)
			(end 0.67945 0.3048)
			(stroke
				(width 0.1)
				(type default)
			)
			(layer "B.Fab")
		)
		(fp_line
			(start 0.67945 -0.305054)
			(end 0.12065 -0.305054)
			(stroke
				(width 0.1)
				(type default)
			)
			(layer "B.Fab")
		)
		(fp_line
			(start 0.67945 0.3048)
			(end 0.67945 -0.305054)
			(stroke
				(width 0.1)
				(type default)
			)
			(layer "B.Fab")
		)
		(pad "1" smd circle
			(at 0.40005 0 180)
			(size 0 0)
			(layers "B.Cu" "B.Mask" "B.Paste")
			(net "P3V3_AUX")
		)
		(pad "2" smd circle
			(at -0.40005 0 180)
			(size 0 0)
			(layers "B.Cu" "B.Mask" "B.Paste")
			(net "FM_CPU0_SKTOCC_N")
		)
	)
	(footprint ""
		(layer "B.Cu")
		(at 172.2247 -13.762228 90)
		(property "Reference" "R3858"
			(at 0 0 90)
			(layer "B.SilkS")
			(hide yes)
			(effects
				(font
					(size 1.27 1.27)
				)
				(justify mirror)
			)
		)
		(property "Value" ""
			(at 0 0 90)
			(layer "B.Fab")
			(effects
				(font
					(size 1.27 1.27)
				)
				(justify mirror)
			)
		)
		(duplicate_pad_numbers_are_jumpers no)
		(fp_line
			(start 0.7874 -0.4064)
			(end -0.7874 -0.4064)
			(stroke
				(width 0.1524)
				(type default)
			)
			(layer "B.SilkS")
		)
		(fp_line
			(start -0.7874 -0.4064)
			(end -0.7874 0.4064)
			(stroke
				(width 0.1524)
				(type default)
			)
			(layer "B.SilkS")
		)
		(fp_line
			(start 0.7874 0.4064)
			(end 0.7874 -0.4064)
			(stroke
				(width 0.1524)
				(type default)
			)
			(layer "B.SilkS")
		)
		(fp_line
			(start -0.7874 0.4064)
			(end 0.7874 0.4064)
			(stroke
				(width 0.1524)
				(type default)
			)
			(layer "B.SilkS")
		)
		(fp_line
			(start 0.67945 -0.305054)
			(end 0.12065 -0.305054)
			(stroke
				(width 0.1)
				(type default)
			)
			(layer "B.Fab")
		)
		(fp_line
			(start 0.12065 -0.305054)
			(end 0.12065 -0.2794)
			(stroke
				(width 0.1)
				(type default)
			)
			(layer "B.Fab")
		)
		(fp_line
			(start -0.12065 -0.3048)
			(end -0.67945 -0.3048)
			(stroke
				(width 0.1)
				(type default)
			)
			(layer "B.Fab")
		)
		(fp_line
			(start -0.67945 -0.3048)
			(end -0.67945 0.3048)
			(stroke
				(width 0.1)
				(type default)
			)
			(layer "B.Fab")
		)
		(fp_line
			(start 0.12065 -0.2794)
			(end -0.12065 -0.2794)
			(stroke
				(width 0.1)
				(type default)
			)
			(layer "B.Fab")
		)
		(fp_line
			(start -0.12065 -0.2794)
			(end -0.12065 -0.3048)
			(stroke
				(width 0.1)
				(type default)
			)
			(layer "B.Fab")
		)
		(fp_line
			(start 0.12065 0.2794)
			(end 0.12065 0.3048)
			(stroke
				(width 0.1)
				(type default)
			)
			(layer "B.Fab")
		)
		(fp_line
			(start -0.120396 0.2794)
			(end 0.12065 0.2794)
			(stroke
				(width 0.1)
				(type default)
			)
			(layer "B.Fab")
		)
		(fp_line
			(start 0.67945 0.3048)
			(end 0.67945 -0.305054)
			(stroke
				(width 0.1)
				(type default)
			)
			(layer "B.Fab")
		)
		(fp_line
			(start 0.12065 0.3048)
			(end 0.67945 0.3048)
			(stroke
				(width 0.1)
				(type default)
			)
			(layer "B.Fab")
		)
		(fp_line
			(start -0.120396 0.3048)
			(end -0.120396 0.2794)
			(stroke
				(width 0.1)
				(type default)
			)
			(layer "B.Fab")
		)
		(fp_line
			(start -0.67945 0.3048)
			(end -0.120396 0.3048)
			(stroke
				(width 0.1)
				(type default)
			)
			(layer "B.Fab")
		)
		(pad "1" smd circle
			(at 0.40005 0 270)
			(size 0 0)
			(layers "B.Cu" "B.Mask" "B.Paste")
			(net "SMB_OCP_V3_2_3V3AUX_SDA")
		)
		(pad "2" smd circle
			(at -0.40005 0 270)
			(size 0 0)
			(layers "B.Cu" "B.Mask" "B.Paste")
			(net "SMB_OCP_V3_2_3V3AUX_SDA_R0")
		)
	)
	(footprint ""
		(layer "B.Cu")
		(at 401.832318 -229.12451 -90)
		(property "Reference" "R10"
			(at 0 0 90)
			(layer "B.SilkS")
			(hide yes)
			(effects
				(font
					(size 1.27 1.27)
				)
				(justify mirror)
			)
		)
		(property "Value" ""
			(at 0 0 90)
			(layer "B.Fab")
			(effects
				(font
					(size 1.27 1.27)
				)
				(justify mirror)
			)
		)
		(duplicate_pad_numbers_are_jumpers no)
		(fp_line
			(start -0.7874 0.4064)
			(end 0.7874 0.4064)
			(stroke
				(width 0.1524)
				(type default)
			)
			(layer "B.SilkS")
		)
		(fp_line
			(start 0.7874 0.4064)
			(end 0.7874 -0.4064)
			(stroke
				(width 0.1524)
				(type default)
			)
			(layer "B.SilkS")
		)
		(fp_line
			(start -0.7874 -0.4064)
			(end -0.7874 0.4064)
			(stroke
				(width 0.1524)
				(type default)
			)
			(layer "B.SilkS")
		)
		(fp_line
			(start 0.7874 -0.4064)
			(end -0.7874 -0.4064)
			(stroke
				(width 0.1524)
				(type default)
			)
			(layer "B.SilkS")
		)
		(fp_line
			(start -0.67945 0.3048)
			(end -0.120396 0.3048)
			(stroke
				(width 0.1)
				(type default)
			)
			(layer "B.Fab")
		)
		(fp_line
			(start -0.120396 0.3048)
			(end -0.120396 0.2794)
			(stroke
				(width 0.1)
				(type default)
			)
			(layer "B.Fab")
		)
		(fp_line
			(start 0.12065 0.3048)
			(end 0.67945 0.3048)
			(stroke
				(width 0.1)
				(type default)
			)
			(layer "B.Fab")
		)
		(fp_line
			(start 0.67945 0.3048)
			(end 0.67945 -0.305054)
			(stroke
				(width 0.1)
				(type default)
			)
			(layer "B.Fab")
		)
		(fp_line
			(start -0.120396 0.2794)
			(end 0.12065 0.2794)
			(stroke
				(width 0.1)
				(type default)
			)
			(layer "B.Fab")
		)
		(fp_line
			(start 0.12065 0.2794)
			(end 0.12065 0.3048)
			(stroke
				(width 0.1)
				(type default)
			)
			(layer "B.Fab")
		)
		(fp_line
			(start -0.12065 -0.2794)
			(end -0.12065 -0.3048)
			(stroke
				(width 0.1)
				(type default)
			)
			(layer "B.Fab")
		)
		(fp_line
			(start 0.12065 -0.2794)
			(end -0.12065 -0.2794)
			(stroke
				(width 0.1)
				(type default)
			)
			(layer "B.Fab")
		)
		(fp_line
			(start -0.67945 -0.3048)
			(end -0.67945 0.3048)
			(stroke
				(width 0.1)
				(type default)
			)
			(layer "B.Fab")
		)
		(fp_line
			(start -0.12065 -0.3048)
			(end -0.67945 -0.3048)
			(stroke
				(width 0.1)
				(type default)
			)
			(layer "B.Fab")
		)
		(fp_line
			(start 0.12065 -0.305054)
			(end 0.12065 -0.2794)
			(stroke
				(width 0.1)
				(type default)
			)
			(layer "B.Fab")
		)
		(fp_line
			(start 0.67945 -0.305054)
			(end 0.12065 -0.305054)
			(stroke
				(width 0.1)
				(type default)
			)
			(layer "B.Fab")
		)
		(pad "1" smd circle
			(at 0.40005 0 90)
			(size 0 0)
			(layers "B.Cu" "B.Mask" "B.Paste")
			(net "H_CPU0_PMSYNC_PCH_R")
		)
		(pad "2" smd circle
			(at -0.40005 0 90)
			(size 0 0)
			(layers "B.Cu" "B.Mask" "B.Paste")
			(net "H_CPU0_PMSYNC_PCH")
		)
	)
	(footprint ""
		(layer "B.Cu")
		(at 235.30052 -249.220228 -90)
		(property "Reference" "C2258"
			(at 0 0 90)
			(layer "B.SilkS")
			(hide yes)
			(effects
				(font
					(size 1.27 1.27)
				)
				(justify mirror)
			)
		)
		(property "Value" ""
			(at 0 0 90)
			(layer "B.Fab")
			(effects
				(font
					(size 1.27 1.27)
				)
				(justify mirror)
			)
		)
		(duplicate_pad_numbers_are_jumpers no)
		(fp_line
			(start -0.7874 0.4064)
			(end 0.7874 0.4064)
			(stroke
				(width 0.1524)
				(type default)
			)
			(layer "B.SilkS")
		)
		(fp_line
			(start 0.7874 0.4064)
			(end 0.7874 -0.4064)
			(stroke
				(width 0.1524)
				(type default)
			)
			(layer "B.SilkS")
		)
		(fp_line
			(start -0.7874 -0.4064)
			(end -0.7874 0.4064)
			(stroke
				(width 0.1524)
				(type default)
			)
			(layer "B.SilkS")
		)
		(fp_line
			(start 0.7874 -0.4064)
			(end -0.7874 -0.4064)
			(stroke
				(width 0.1524)
				(type default)
			)
			(layer "B.SilkS")
		)
		(fp_line
			(start -0.67945 0.3048)
			(end -0.120396 0.3048)
			(stroke
				(width 0.1)
				(type default)
			)
			(layer "B.Fab")
		)
		(fp_line
			(start -0.120396 0.3048)
			(end -0.120396 0.2794)
			(stroke
				(width 0.1)
				(type default)
			)
			(layer "B.Fab")
		)
		(fp_line
			(start 0.12065 0.3048)
			(end 0.67945 0.3048)
			(stroke
				(width 0.1)
				(type default)
			)
			(layer "B.Fab")
		)
		(fp_line
			(start 0.67945 0.3048)
			(end 0.67945 -0.305054)
			(stroke
				(width 0.1)
				(type default)
			)
			(layer "B.Fab")
		)
		(fp_line
			(start -0.120396 0.2794)
			(end 0.12065 0.2794)
			(stroke
				(width 0.1)
				(type default)
			)
			(layer "B.Fab")
		)
		(fp_line
			(start 0.12065 0.2794)
			(end 0.12065 0.3048)
			(stroke
				(width 0.1)
				(type default)
			)
			(layer "B.Fab")
		)
		(fp_line
			(start -0.12065 -0.2794)
			(end -0.12065 -0.3048)
			(stroke
				(width 0.1)
				(type default)
			)
			(layer "B.Fab")
		)
		(fp_line
			(start 0.12065 -0.2794)
			(end -0.12065 -0.2794)
			(stroke
				(width 0.1)
				(type default)
			)
			(layer "B.Fab")
		)
		(fp_line
			(start -0.67945 -0.3048)
			(end -0.67945 0.3048)
			(stroke
				(width 0.1)
				(type default)
			)
			(layer "B.Fab")
		)
		(fp_line
			(start -0.12065 -0.3048)
			(end -0.67945 -0.3048)
			(stroke
				(width 0.1)
				(type default)
			)
			(layer "B.Fab")
		)
		(fp_line
			(start 0.12065 -0.305054)
			(end 0.12065 -0.2794)
			(stroke
				(width 0.1)
				(type default)
			)
			(layer "B.Fab")
		)
		(fp_line
			(start 0.67945 -0.305054)
			(end 0.12065 -0.305054)
			(stroke
				(width 0.1)
				(type default)
			)
			(layer "B.Fab")
		)
		(pad "1" smd circle
			(at 0.40005 0 90)
			(size 0 0)
			(layers "B.Cu" "B.Mask" "B.Paste")
			(net "VFG3P3_CLK_GEN")
		)
		(pad "2" smd circle
			(at -0.40005 0 90)
			(size 0 0)
			(layers "B.Cu" "B.Mask" "B.Paste")
			(net "GND")
		)
	)
	(footprint ""
		(layer "B.Cu")
		(at 8.153146 -319.268856 180)
		(property "Reference" "C68"
			(at 0 0 0)
			(layer "B.SilkS")
			(hide yes)
			(effects
				(font
					(size 1.27 1.27)
				)
				(justify mirror)
			)
		)
		(property "Value" ""
			(at 0 0 0)
			(layer "B.Fab")
			(effects
				(font
					(size 1.27 1.27)
				)
				(justify mirror)
			)
		)
		(duplicate_pad_numbers_are_jumpers no)
		(fp_line
			(start 0.7874 0.4064)
			(end 0.7874 -0.4064)
			(stroke
				(width 0.1524)
				(type default)
			)
			(layer "B.SilkS")
		)
		(fp_line
			(start 0.7874 -0.4064)
			(end -0.7874 -0.4064)
			(stroke
				(width 0.1524)
				(type default)
			)
			(layer "B.SilkS")
		)
		(fp_line
			(start -0.7874 0.4064)
			(end 0.7874 0.4064)
			(stroke
				(width 0.1524)
				(type default)
			)
			(layer "B.SilkS")
		)
		(fp_line
			(start -0.7874 -0.4064)
			(end -0.7874 0.4064)
			(stroke
				(width 0.1524)
				(type default)
			)
			(layer "B.SilkS")
		)
		(fp_line
			(start 0.67945 0.3048)
			(end 0.67945 -0.305054)
			(stroke
				(width 0.1)
				(type default)
			)
			(layer "B.Fab")
		)
		(fp_line
			(start 0.67945 -0.305054)
			(end 0.12065 -0.305054)
			(stroke
				(width 0.1)
				(type default)
			)
			(layer "B.Fab")
		)
		(fp_line
			(start 0.12065 0.3048)
			(end 0.67945 0.3048)
			(stroke
				(width 0.1)
				(type default)
			)
			(layer "B.Fab")
		)
		(fp_line
			(start 0.12065 0.2794)
			(end 0.12065 0.3048)
			(stroke
				(width 0.1)
				(type default)
			)
			(layer "B.Fab")
		)
		(fp_line
			(start 0.12065 -0.2794)
			(end -0.12065 -0.2794)
			(stroke
				(width 0.1)
				(type default)
			)
			(layer "B.Fab")
		)
		(fp_line
			(start 0.12065 -0.305054)
			(end 0.12065 -0.2794)
			(stroke
				(width 0.1)
				(type default)
			)
			(layer "B.Fab")
		)
		(fp_line
			(start -0.120396 0.3048)
			(end -0.120396 0.2794)
			(stroke
				(width 0.1)
				(type default)
			)
			(layer "B.Fab")
		)
		(fp_line
			(start -0.120396 0.2794)
			(end 0.12065 0.2794)
			(stroke
				(width 0.1)
				(type default)
			)
			(layer "B.Fab")
		)
		(fp_line
			(start -0.12065 -0.2794)
			(end -0.12065 -0.3048)
			(stroke
				(width 0.1)
				(type default)
			)
			(layer "B.Fab")
		)
		(fp_line
			(start -0.12065 -0.3048)
			(end -0.67945 -0.3048)
			(stroke
				(width 0.1)
				(type default)
			)
			(layer "B.Fab")
		)
		(fp_line
			(start -0.67945 0.3048)
			(end -0.120396 0.3048)
			(stroke
				(width 0.1)
				(type default)
			)
			(layer "B.Fab")
		)
		(fp_line
			(start -0.67945 -0.3048)
			(end -0.67945 0.3048)
			(stroke
				(width 0.1)
				(type default)
			)
			(layer "B.Fab")
		)
		(pad "1" smd circle
			(at 0.40005 0)
			(size 0 0)
			(layers "B.Cu" "B.Mask" "B.Paste")
			(net "P3V3_AUX")
		)
		(pad "2" smd circle
			(at -0.40005 0)
			(size 0 0)
			(layers "B.Cu" "B.Mask" "B.Paste")
			(net "GND")
		)
	)
	(footprint ""
		(layer "B.Cu")
		(at 312.592974 -317.06566 90)
		(property "Reference" "R2490"
			(at 0 0 90)
			(layer "B.SilkS")
			(hide yes)
			(effects
				(font
					(size 1.27 1.27)
				)
				(justify mirror)
			)
		)
		(property "Value" ""
			(at 0 0 90)
			(layer "B.Fab")
			(effects
				(font
					(size 1.27 1.27)
				)
				(justify mirror)
			)
		)
		(duplicate_pad_numbers_are_jumpers no)
		(fp_line
			(start 0.7874 -0.4064)
			(end -0.7874 -0.4064)
			(stroke
				(width 0.1524)
				(type default)
			)
			(layer "B.SilkS")
		)
		(fp_line
			(start -0.7874 -0.4064)
			(end -0.7874 0.4064)
			(stroke
				(width 0.1524)
				(type default)
			)
			(layer "B.SilkS")
		)
		(fp_line
			(start 0.7874 0.4064)
			(end 0.7874 -0.4064)
			(stroke
				(width 0.1524)
				(type default)
			)
			(layer "B.SilkS")
		)
		(fp_line
			(start -0.7874 0.4064)
			(end 0.7874 0.4064)
			(stroke
				(width 0.1524)
				(type default)
			)
			(layer "B.SilkS")
		)
		(fp_line
			(start 0.67945 -0.305054)
			(end 0.12065 -0.305054)
			(stroke
				(width 0.1)
				(type default)
			)
			(layer "B.Fab")
		)
		(fp_line
			(start 0.12065 -0.305054)
			(end 0.12065 -0.2794)
			(stroke
				(width 0.1)
				(type default)
			)
			(layer "B.Fab")
		)
		(fp_line
			(start -0.12065 -0.3048)
			(end -0.67945 -0.3048)
			(stroke
				(width 0.1)
				(type default)
			)
			(layer "B.Fab")
		)
		(fp_line
			(start -0.67945 -0.3048)
			(end -0.67945 0.3048)
			(stroke
				(width 0.1)
				(type default)
			)
			(layer "B.Fab")
		)
		(fp_line
			(start 0.12065 -0.2794)
			(end -0.12065 -0.2794)
			(stroke
				(width 0.1)
				(type default)
			)
			(layer "B.Fab")
		)
		(fp_line
			(start -0.12065 -0.2794)
			(end -0.12065 -0.3048)
			(stroke
				(width 0.1)
				(type default)
			)
			(layer "B.Fab")
		)
		(fp_line
			(start 0.12065 0.2794)
			(end 0.12065 0.3048)
			(stroke
				(width 0.1)
				(type default)
			)
			(layer "B.Fab")
		)
		(fp_line
			(start -0.120396 0.2794)
			(end 0.12065 0.2794)
			(stroke
				(width 0.1)
				(type default)
			)
			(layer "B.Fab")
		)
		(fp_line
			(start 0.67945 0.3048)
			(end 0.67945 -0.305054)
			(stroke
				(width 0.1)
				(type default)
			)
			(layer "B.Fab")
		)
		(fp_line
			(start 0.12065 0.3048)
			(end 0.67945 0.3048)
			(stroke
				(width 0.1)
				(type default)
			)
			(layer "B.Fab")
		)
		(fp_line
			(start -0.120396 0.3048)
			(end -0.120396 0.2794)
			(stroke
				(width 0.1)
				(type default)
			)
			(layer "B.Fab")
		)
		(fp_line
			(start -0.67945 0.3048)
			(end -0.120396 0.3048)
			(stroke
				(width 0.1)
				(type default)
			)
			(layer "B.Fab")
		)
		(pad "1" smd circle
			(at 0.40005 0 270)
			(size 0 0)
			(layers "B.Cu" "B.Mask" "B.Paste")
			(net "PWRGD_FAIL_CPU0_AB")
		)
		(pad "2" smd circle
			(at -0.40005 0 270)
			(size 0 0)
			(layers "B.Cu" "B.Mask" "B.Paste")
			(net "PWRGD_FAIL_CPU0_AB_R1")
		)
	)
	(footprint ""
		(layer "B.Cu")
		(at 125.052836 -25.774142 180)
		(property "Reference" "C1097"
			(at 0 0 0)
			(layer "B.SilkS")
			(hide yes)
			(effects
				(font
					(size 1.27 1.27)
				)
				(justify mirror)
			)
		)
		(property "Value" ""
			(at 0 0 0)
			(layer "B.Fab")
			(effects
				(font
					(size 1.27 1.27)
				)
				(justify mirror)
			)
		)
		(duplicate_pad_numbers_are_jumpers no)
		(fp_line
			(start 0.299974 0.150114)
			(end 0.299974 -0.150114)
			(stroke
				(width 0.1)
				(type default)
			)
			(layer "B.Fab")
		)
		(fp_line
			(start 0.299974 -0.150114)
			(end -0.299974 -0.150114)
			(stroke
				(width 0.1)
				(type default)
			)
			(layer "B.Fab")
		)
		(fp_line
			(start -0.299974 0.150114)
			(end 0.299974 0.150114)
			(stroke
				(width 0.1)
				(type default)
			)
			(layer "B.Fab")
		)
		(fp_line
			(start -0.299974 -0.150114)
			(end -0.299974 0.150114)
			(stroke
				(width 0.1)
				(type default)
			)
			(layer "B.Fab")
		)
		(pad "1" smd rect
			(at 0.2667 0)
			(size 0.3048 0.381)
			(layers "B.Cu" "B.Mask" "B.Paste")
			(net "USB3_PCH_TX_DN<4>")
		)
		(pad "2" smd rect
			(at -0.2667 0)
			(size 0.3048 0.381)
			(layers "B.Cu" "B.Mask" "B.Paste")
			(net "USB3_PCH_TX_C_DN<4>")
		)
	)
	(footprint ""
		(layer "B.Cu")
		(at 420.698422 -132.632704)
		(property "Reference" "PR130"
			(at 0 0 0)
			(layer "B.SilkS")
			(hide yes)
			(effects
				(font
					(size 1.27 1.27)
				)
				(justify mirror)
			)
		)
		(property "Value" ""
			(at 0 0 0)
			(layer "B.Fab")
			(effects
				(font
					(size 1.27 1.27)
				)
				(justify mirror)
			)
		)
		(duplicate_pad_numbers_are_jumpers no)
		(fp_line
			(start -0.7874 -0.4064)
			(end -0.7874 0.4064)
			(stroke
				(width 0.1524)
				(type default)
			)
			(layer "B.SilkS")
		)
		(fp_line
			(start -0.7874 0.4064)
			(end 0.7874 0.4064)
			(stroke
				(width 0.1524)
				(type default)
			)
			(layer "B.SilkS")
		)
		(fp_line
			(start 0.7874 -0.4064)
			(end -0.7874 -0.4064)
			(stroke
				(width 0.1524)
				(type default)
			)
			(layer "B.SilkS")
		)
		(fp_line
			(start 0.7874 0.4064)
			(end 0.7874 -0.4064)
			(stroke
				(width 0.1524)
				(type default)
			)
			(layer "B.SilkS")
		)
		(fp_line
			(start -0.67945 -0.3048)
			(end -0.67945 0.3048)
			(stroke
				(width 0.1)
				(type default)
			)
			(layer "B.Fab")
		)
		(fp_line
			(start -0.67945 0.3048)
			(end -0.120396 0.3048)
			(stroke
				(width 0.1)
				(type default)
			)
			(layer "B.Fab")
		)
		(fp_line
			(start -0.12065 -0.3048)
			(end -0.67945 -0.3048)
			(stroke
				(width 0.1)
				(type default)
			)
			(layer "B.Fab")
		)
		(fp_line
			(start -0.12065 -0.2794)
			(end -0.12065 -0.3048)
			(stroke
				(width 0.1)
				(type default)
			)
			(layer "B.Fab")
		)
		(fp_line
			(start -0.120396 0.2794)
			(end 0.12065 0.2794)
			(stroke
				(width 0.1)
				(type default)
			)
			(layer "B.Fab")
		)
		(fp_line
			(start -0.120396 0.3048)
			(end -0.120396 0.2794)
			(stroke
				(width 0.1)
				(type default)
			)
			(layer "B.Fab")
		)
		(fp_line
			(start 0.12065 -0.305054)
			(end 0.12065 -0.2794)
			(stroke
				(width 0.1)
				(type default)
			)
			(layer "B.Fab")
		)
		(fp_line
			(start 0.12065 -0.2794)
			(end -0.12065 -0.2794)
			(stroke
				(width 0.1)
				(type default)
			)
			(layer "B.Fab")
		)
		(fp_line
			(start 0.12065 0.2794)
			(end 0.12065 0.3048)
			(stroke
				(width 0.1)
				(type default)
			)
			(layer "B.Fab")
		)
		(fp_line
			(start 0.12065 0.3048)
			(end 0.67945 0.3048)
			(stroke
				(width 0.1)
				(type default)
			)
			(layer "B.Fab")
		)
		(fp_line
			(start 0.67945 -0.305054)
			(end 0.12065 -0.305054)
			(stroke
				(width 0.1)
				(type default)
			)
			(layer "B.Fab")
		)
		(fp_line
			(start 0.67945 0.3048)
			(end 0.67945 -0.305054)
			(stroke
				(width 0.1)
				(type default)
			)
			(layer "B.Fab")
		)
		(pad "1" smd circle
			(at 0.40005 0 180)
			(size 0 0)
			(layers "B.Cu" "B.Mask" "B.Paste")
			(net "PVCCINFAON_CPU0_VCC")
		)
		(pad "2" smd circle
			(at -0.40005 0 180)
			(size 0 0)
			(layers "B.Cu" "B.Mask" "B.Paste")
			(net "P3V3_AUX")
		)
	)
	(footprint ""
		(layer "B.Cu")
		(at 49.682908 -193.25971 -90)
		(property "Reference" "R259"
			(at 0 0 90)
			(layer "B.SilkS")
			(hide yes)
			(effects
				(font
					(size 1.27 1.27)
				)
				(justify mirror)
			)
		)
		(property "Value" ""
			(at 0 0 90)
			(layer "B.Fab")
			(effects
				(font
					(size 1.27 1.27)
				)
				(justify mirror)
			)
		)
		(duplicate_pad_numbers_are_jumpers no)
		(fp_line
			(start -0.7874 0.4064)
			(end 0.7874 0.4064)
			(stroke
				(width 0.1524)
				(type default)
			)
			(layer "B.SilkS")
		)
		(fp_line
			(start 0.7874 0.4064)
			(end 0.7874 -0.4064)
			(stroke
				(width 0.1524)
				(type default)
			)
			(layer "B.SilkS")
		)
		(fp_line
			(start -0.7874 -0.4064)
			(end -0.7874 0.4064)
			(stroke
				(width 0.1524)
				(type default)
			)
			(layer "B.SilkS")
		)
		(fp_line
			(start 0.7874 -0.4064)
			(end -0.7874 -0.4064)
			(stroke
				(width 0.1524)
				(type default)
			)
			(layer "B.SilkS")
		)
		(fp_line
			(start -0.67945 0.3048)
			(end -0.120396 0.3048)
			(stroke
				(width 0.1)
				(type default)
			)
			(layer "B.Fab")
		)
		(fp_line
			(start -0.120396 0.3048)
			(end -0.120396 0.2794)
			(stroke
				(width 0.1)
				(type default)
			)
			(layer "B.Fab")
		)
		(fp_line
			(start 0.12065 0.3048)
			(end 0.67945 0.3048)
			(stroke
				(width 0.1)
				(type default)
			)
			(layer "B.Fab")
		)
		(fp_line
			(start 0.67945 0.3048)
			(end 0.67945 -0.305054)
			(stroke
				(width 0.1)
				(type default)
			)
			(layer "B.Fab")
		)
		(fp_line
			(start -0.120396 0.2794)
			(end 0.12065 0.2794)
			(stroke
				(width 0.1)
				(type default)
			)
			(layer "B.Fab")
		)
		(fp_line
			(start 0.12065 0.2794)
			(end 0.12065 0.3048)
			(stroke
				(width 0.1)
				(type default)
			)
			(layer "B.Fab")
		)
		(fp_line
			(start -0.12065 -0.2794)
			(end -0.12065 -0.3048)
			(stroke
				(width 0.1)
				(type default)
			)
			(layer "B.Fab")
		)
		(fp_line
			(start 0.12065 -0.2794)
			(end -0.12065 -0.2794)
			(stroke
				(width 0.1)
				(type default)
			)
			(layer "B.Fab")
		)
		(fp_line
			(start -0.67945 -0.3048)
			(end -0.67945 0.3048)
			(stroke
				(width 0.1)
				(type default)
			)
			(layer "B.Fab")
		)
		(fp_line
			(start -0.12065 -0.3048)
			(end -0.67945 -0.3048)
			(stroke
				(width 0.1)
				(type default)
			)
			(layer "B.Fab")
		)
		(fp_line
			(start 0.12065 -0.305054)
			(end 0.12065 -0.2794)
			(stroke
				(width 0.1)
				(type default)
			)
			(layer "B.Fab")
		)
		(fp_line
			(start 0.67945 -0.305054)
			(end 0.12065 -0.305054)
			(stroke
				(width 0.1)
				(type default)
			)
			(layer "B.Fab")
		)
		(pad "1" smd circle
			(at 0.40005 0 90)
			(size 0 0)
			(layers "B.Cu" "B.Mask" "B.Paste")
			(net "PVNN_TERM_CPU1")
		)
		(pad "2" smd circle
			(at -0.40005 0 90)
			(size 0 0)
			(layers "B.Cu" "B.Mask" "B.Paste")
			(net "FM_S3M_CPU1_LVC1_GPIO_2")
		)
	)
	(footprint ""
		(layer "B.Cu")
		(at 268.668246 -193.503296 -90)
		(property "Reference" "C623"
			(at 0 0 90)
			(layer "B.SilkS")
			(hide yes)
			(effects
				(font
					(size 1.27 1.27)
				)
				(justify mirror)
			)
		)
		(property "Value" ""
			(at 0 0 90)
			(layer "B.Fab")
			(effects
				(font
					(size 1.27 1.27)
				)
				(justify mirror)
			)
		)
		(duplicate_pad_numbers_are_jumpers no)
		(fp_line
			(start -0.7874 0.4064)
			(end 0.7874 0.4064)
			(stroke
				(width 0.1524)
				(type default)
			)
			(layer "B.SilkS")
		)
		(fp_line
			(start 0.7874 0.4064)
			(end 0.7874 -0.4064)
			(stroke
				(width 0.1524)
				(type default)
			)
			(layer "B.SilkS")
		)
		(fp_line
			(start -0.7874 -0.4064)
			(end -0.7874 0.4064)
			(stroke
				(width 0.1524)
				(type default)
			)
			(layer "B.SilkS")
		)
		(fp_line
			(start 0.7874 -0.4064)
			(end -0.7874 -0.4064)
			(stroke
				(width 0.1524)
				(type default)
			)
			(layer "B.SilkS")
		)
		(fp_line
			(start -0.67945 0.3048)
			(end -0.120396 0.3048)
			(stroke
				(width 0.1)
				(type default)
			)
			(layer "B.Fab")
		)
		(fp_line
			(start -0.120396 0.3048)
			(end -0.120396 0.2794)
			(stroke
				(width 0.1)
				(type default)
			)
			(layer "B.Fab")
		)
		(fp_line
			(start 0.12065 0.3048)
			(end 0.67945 0.3048)
			(stroke
				(width 0.1)
				(type default)
			)
			(layer "B.Fab")
		)
		(fp_line
			(start 0.67945 0.3048)
			(end 0.67945 -0.305054)
			(stroke
				(width 0.1)
				(type default)
			)
			(layer "B.Fab")
		)
		(fp_line
			(start -0.120396 0.2794)
			(end 0.12065 0.2794)
			(stroke
				(width 0.1)
				(type default)
			)
			(layer "B.Fab")
		)
		(fp_line
			(start 0.12065 0.2794)
			(end 0.12065 0.3048)
			(stroke
				(width 0.1)
				(type default)
			)
			(layer "B.Fab")
		)
		(fp_line
			(start -0.12065 -0.2794)
			(end -0.12065 -0.3048)
			(stroke
				(width 0.1)
				(type default)
			)
			(layer "B.Fab")
		)
		(fp_line
			(start 0.12065 -0.2794)
			(end -0.12065 -0.2794)
			(stroke
				(width 0.1)
				(type default)
			)
			(layer "B.Fab")
		)
		(fp_line
			(start -0.67945 -0.3048)
			(end -0.67945 0.3048)
			(stroke
				(width 0.1)
				(type default)
			)
			(layer "B.Fab")
		)
		(fp_line
			(start -0.12065 -0.3048)
			(end -0.67945 -0.3048)
			(stroke
				(width 0.1)
				(type default)
			)
			(layer "B.Fab")
		)
		(fp_line
			(start 0.12065 -0.305054)
			(end 0.12065 -0.2794)
			(stroke
				(width 0.1)
				(type default)
			)
			(layer "B.Fab")
		)
		(fp_line
			(start 0.67945 -0.305054)
			(end 0.12065 -0.305054)
			(stroke
				(width 0.1)
				(type default)
			)
			(layer "B.Fab")
		)
		(pad "1" smd circle
			(at 0.40005 0 90)
			(size 0 0)
			(layers "B.Cu" "B.Mask" "B.Paste")
			(net "RST_PLD_CPU0_DRAM_CD_N")
		)
		(pad "2" smd circle
			(at -0.40005 0 90)
			(size 0 0)
			(layers "B.Cu" "B.Mask" "B.Paste")
			(net "GND")
		)
	)
	(footprint ""
		(layer "B.Cu")
		(at 149.099524 -189.963298 180)
		(property "Reference" "R291"
			(at 0 0 0)
			(layer "B.SilkS")
			(hide yes)
			(effects
				(font
					(size 1.27 1.27)
				)
				(justify mirror)
			)
		)
		(property "Value" ""
			(at 0 0 0)
			(layer "B.Fab")
			(effects
				(font
					(size 1.27 1.27)
				)
				(justify mirror)
			)
		)
		(duplicate_pad_numbers_are_jumpers no)
		(fp_line
			(start 0.7874 0.4064)
			(end 0.7874 -0.4064)
			(stroke
				(width 0.1524)
				(type default)
			)
			(layer "B.SilkS")
		)
		(fp_line
			(start 0.7874 -0.4064)
			(end -0.7874 -0.4064)
			(stroke
				(width 0.1524)
				(type default)
			)
			(layer "B.SilkS")
		)
		(fp_line
			(start -0.7874 0.4064)
			(end 0.7874 0.4064)
			(stroke
				(width 0.1524)
				(type default)
			)
			(layer "B.SilkS")
		)
		(fp_line
			(start -0.7874 -0.4064)
			(end -0.7874 0.4064)
			(stroke
				(width 0.1524)
				(type default)
			)
			(layer "B.SilkS")
		)
		(fp_line
			(start 0.67945 0.3048)
			(end 0.67945 -0.305054)
			(stroke
				(width 0.1)
				(type default)
			)
			(layer "B.Fab")
		)
		(fp_line
			(start 0.67945 -0.305054)
			(end 0.12065 -0.305054)
			(stroke
				(width 0.1)
				(type default)
			)
			(layer "B.Fab")
		)
		(fp_line
			(start 0.12065 0.3048)
			(end 0.67945 0.3048)
			(stroke
				(width 0.1)
				(type default)
			)
			(layer "B.Fab")
		)
		(fp_line
			(start 0.12065 0.2794)
			(end 0.12065 0.3048)
			(stroke
				(width 0.1)
				(type default)
			)
			(layer "B.Fab")
		)
		(fp_line
			(start 0.12065 -0.2794)
			(end -0.12065 -0.2794)
			(stroke
				(width 0.1)
				(type default)
			)
			(layer "B.Fab")
		)
		(fp_line
			(start 0.12065 -0.305054)
			(end 0.12065 -0.2794)
			(stroke
				(width 0.1)
				(type default)
			)
			(layer "B.Fab")
		)
		(fp_line
			(start -0.120396 0.3048)
			(end -0.120396 0.2794)
			(stroke
				(width 0.1)
				(type default)
			)
			(layer "B.Fab")
		)
		(fp_line
			(start -0.120396 0.2794)
			(end 0.12065 0.2794)
			(stroke
				(width 0.1)
				(type default)
			)
			(layer "B.Fab")
		)
		(fp_line
			(start -0.12065 -0.2794)
			(end -0.12065 -0.3048)
			(stroke
				(width 0.1)
				(type default)
			)
			(layer "B.Fab")
		)
		(fp_line
			(start -0.12065 -0.3048)
			(end -0.67945 -0.3048)
			(stroke
				(width 0.1)
				(type default)
			)
			(layer "B.Fab")
		)
		(fp_line
			(start -0.67945 0.3048)
			(end -0.120396 0.3048)
			(stroke
				(width 0.1)
				(type default)
			)
			(layer "B.Fab")
		)
		(fp_line
			(start -0.67945 -0.3048)
			(end -0.67945 0.3048)
			(stroke
				(width 0.1)
				(type default)
			)
			(layer "B.Fab")
		)
		(pad "1" smd circle
			(at 0.40005 0)
			(size 0 0)
			(layers "B.Cu" "B.Mask" "B.Paste")
			(net "GND")
		)
		(pad "2" smd circle
			(at -0.40005 0)
			(size 0 0)
			(layers "B.Cu" "B.Mask" "B.Paste")
			(net "PD_CPU1_ENH_MCECC_DIS")
		)
	)
	(footprint ""
		(layer "B.Cu")
		(at 375.197116 -338.098892 -90)
		(property "Reference" "PR141"
			(at 0 0 90)
			(layer "B.SilkS")
			(hide yes)
			(effects
				(font
					(size 1.27 1.27)
				)
				(justify mirror)
			)
		)
		(property "Value" ""
			(at 0 0 90)
			(layer "B.Fab")
			(effects
				(font
					(size 1.27 1.27)
				)
				(justify mirror)
			)
		)
		(duplicate_pad_numbers_are_jumpers no)
		(fp_line
			(start -0.7874 0.4064)
			(end 0.7874 0.4064)
			(stroke
				(width 0.1524)
				(type default)
			)
			(layer "B.SilkS")
		)
		(fp_line
			(start 0.7874 0.4064)
			(end 0.7874 -0.4064)
			(stroke
				(width 0.1524)
				(type default)
			)
			(layer "B.SilkS")
		)
		(fp_line
			(start -0.7874 -0.4064)
			(end -0.7874 0.4064)
			(stroke
				(width 0.1524)
				(type default)
			)
			(layer "B.SilkS")
		)
		(fp_line
			(start 0.7874 -0.4064)
			(end -0.7874 -0.4064)
			(stroke
				(width 0.1524)
				(type default)
			)
			(layer "B.SilkS")
		)
		(fp_line
			(start -0.67945 0.3048)
			(end -0.120396 0.3048)
			(stroke
				(width 0.1)
				(type default)
			)
			(layer "B.Fab")
		)
		(fp_line
			(start -0.120396 0.3048)
			(end -0.120396 0.2794)
			(stroke
				(width 0.1)
				(type default)
			)
			(layer "B.Fab")
		)
		(fp_line
			(start 0.12065 0.3048)
			(end 0.67945 0.3048)
			(stroke
				(width 0.1)
				(type default)
			)
			(layer "B.Fab")
		)
		(fp_line
			(start 0.67945 0.3048)
			(end 0.67945 -0.305054)
			(stroke
				(width 0.1)
				(type default)
			)
			(layer "B.Fab")
		)
		(fp_line
			(start -0.120396 0.2794)
			(end 0.12065 0.2794)
			(stroke
				(width 0.1)
				(type default)
			)
			(layer "B.Fab")
		)
		(fp_line
			(start 0.12065 0.2794)
			(end 0.12065 0.3048)
			(stroke
				(width 0.1)
				(type default)
			)
			(layer "B.Fab")
		)
		(fp_line
			(start -0.12065 -0.2794)
			(end -0.12065 -0.3048)
			(stroke
				(width 0.1)
				(type default)
			)
			(layer "B.Fab")
		)
		(fp_line
			(start 0.12065 -0.2794)
			(end -0.12065 -0.2794)
			(stroke
				(width 0.1)
				(type default)
			)
			(layer "B.Fab")
		)
		(fp_line
			(start -0.67945 -0.3048)
			(end -0.67945 0.3048)
			(stroke
				(width 0.1)
				(type default)
			)
			(layer "B.Fab")
		)
		(fp_line
			(start -0.12065 -0.3048)
			(end -0.67945 -0.3048)
			(stroke
				(width 0.1)
				(type default)
			)
			(layer "B.Fab")
		)
		(fp_line
			(start 0.12065 -0.305054)
			(end 0.12065 -0.2794)
			(stroke
				(width 0.1)
				(type default)
			)
			(layer "B.Fab")
		)
		(fp_line
			(start 0.67945 -0.305054)
			(end 0.12065 -0.305054)
			(stroke
				(width 0.1)
				(type default)
			)
			(layer "B.Fab")
		)
		(pad "1" smd circle
			(at 0.40005 0 90)
			(size 0 0)
			(layers "B.Cu" "B.Mask" "B.Paste")
			(net "PVCCIN_CPU0_PVCC")
		)
		(pad "2" smd circle
			(at -0.40005 0 90)
			(size 0 0)
			(layers "B.Cu" "B.Mask" "B.Paste")
			(net "PVCCIN_CPU0_VDD5")
		)
	)
	(footprint ""
		(layer "B.Cu")
		(at 157.02788 -117.566948 180)
		(property "Reference" "R1757"
			(at 0 0 0)
			(layer "B.SilkS")
			(hide yes)
			(effects
				(font
					(size 1.27 1.27)
				)
				(justify mirror)
			)
		)
		(property "Value" ""
			(at 0 0 0)
			(layer "B.Fab")
			(effects
				(font
					(size 1.27 1.27)
				)
				(justify mirror)
			)
		)
		(duplicate_pad_numbers_are_jumpers no)
		(fp_line
			(start 0.7874 0.4064)
			(end 0.7874 -0.4064)
			(stroke
				(width 0.1524)
				(type default)
			)
			(layer "B.SilkS")
		)
		(fp_line
			(start 0.7874 -0.4064)
			(end -0.7874 -0.4064)
			(stroke
				(width 0.1524)
				(type default)
			)
			(layer "B.SilkS")
		)
		(fp_line
			(start -0.7874 0.4064)
			(end 0.7874 0.4064)
			(stroke
				(width 0.1524)
				(type default)
			)
			(layer "B.SilkS")
		)
		(fp_line
			(start -0.7874 -0.4064)
			(end -0.7874 0.4064)
			(stroke
				(width 0.1524)
				(type default)
			)
			(layer "B.SilkS")
		)
		(fp_line
			(start 0.67945 0.3048)
			(end 0.67945 -0.305054)
			(stroke
				(width 0.1)
				(type default)
			)
			(layer "B.Fab")
		)
		(fp_line
			(start 0.67945 -0.305054)
			(end 0.12065 -0.305054)
			(stroke
				(width 0.1)
				(type default)
			)
			(layer "B.Fab")
		)
		(fp_line
			(start 0.12065 0.3048)
			(end 0.67945 0.3048)
			(stroke
				(width 0.1)
				(type default)
			)
			(layer "B.Fab")
		)
		(fp_line
			(start 0.12065 0.2794)
			(end 0.12065 0.3048)
			(stroke
				(width 0.1)
				(type default)
			)
			(layer "B.Fab")
		)
		(fp_line
			(start 0.12065 -0.2794)
			(end -0.12065 -0.2794)
			(stroke
				(width 0.1)
				(type default)
			)
			(layer "B.Fab")
		)
		(fp_line
			(start 0.12065 -0.305054)
			(end 0.12065 -0.2794)
			(stroke
				(width 0.1)
				(type default)
			)
			(layer "B.Fab")
		)
		(fp_line
			(start -0.120396 0.3048)
			(end -0.120396 0.2794)
			(stroke
				(width 0.1)
				(type default)
			)
			(layer "B.Fab")
		)
		(fp_line
			(start -0.120396 0.2794)
			(end 0.12065 0.2794)
			(stroke
				(width 0.1)
				(type default)
			)
			(layer "B.Fab")
		)
		(fp_line
			(start -0.12065 -0.2794)
			(end -0.12065 -0.3048)
			(stroke
				(width 0.1)
				(type default)
			)
			(layer "B.Fab")
		)
		(fp_line
			(start -0.12065 -0.3048)
			(end -0.67945 -0.3048)
			(stroke
				(width 0.1)
				(type default)
			)
			(layer "B.Fab")
		)
		(fp_line
			(start -0.67945 0.3048)
			(end -0.120396 0.3048)
			(stroke
				(width 0.1)
				(type default)
			)
			(layer "B.Fab")
		)
		(fp_line
			(start -0.67945 -0.3048)
			(end -0.67945 0.3048)
			(stroke
				(width 0.1)
				(type default)
			)
			(layer "B.Fab")
		)
		(pad "1" smd circle
			(at 0.40005 0)
			(size 0 0)
			(layers "B.Cu" "B.Mask" "B.Paste")
			(net "SGPIO_DI_1")
		)
		(pad "2" smd circle
			(at -0.40005 0)
			(size 0 0)
			(layers "B.Cu" "B.Mask" "B.Paste")
			(net "SGPIO_BMC_DIN_R")
		)
	)
	(footprint ""
		(layer "B.Cu")
		(at 267.336016 -318.937894 90)
		(property "Reference" "R884"
			(at 0 0 90)
			(layer "B.SilkS")
			(hide yes)
			(effects
				(font
					(size 1.27 1.27)
				)
				(justify mirror)
			)
		)
		(property "Value" ""
			(at 0 0 90)
			(layer "B.Fab")
			(effects
				(font
					(size 1.27 1.27)
				)
				(justify mirror)
			)
		)
		(duplicate_pad_numbers_are_jumpers no)
		(fp_line
			(start 0.7874 -0.4064)
			(end -0.7874 -0.4064)
			(stroke
				(width 0.1524)
				(type default)
			)
			(layer "B.SilkS")
		)
		(fp_line
			(start -0.7874 -0.4064)
			(end -0.7874 0.4064)
			(stroke
				(width 0.1524)
				(type default)
			)
			(layer "B.SilkS")
		)
		(fp_line
			(start 0.7874 0.4064)
			(end 0.7874 -0.4064)
			(stroke
				(width 0.1524)
				(type default)
			)
			(layer "B.SilkS")
		)
		(fp_line
			(start -0.7874 0.4064)
			(end 0.7874 0.4064)
			(stroke
				(width 0.1524)
				(type default)
			)
			(layer "B.SilkS")
		)
		(fp_line
			(start 0.67945 -0.305054)
			(end 0.12065 -0.305054)
			(stroke
				(width 0.1)
				(type default)
			)
			(layer "B.Fab")
		)
		(fp_line
			(start 0.12065 -0.305054)
			(end 0.12065 -0.2794)
			(stroke
				(width 0.1)
				(type default)
			)
			(layer "B.Fab")
		)
		(fp_line
			(start -0.12065 -0.3048)
			(end -0.67945 -0.3048)
			(stroke
				(width 0.1)
				(type default)
			)
			(layer "B.Fab")
		)
		(fp_line
			(start -0.67945 -0.3048)
			(end -0.67945 0.3048)
			(stroke
				(width 0.1)
				(type default)
			)
			(layer "B.Fab")
		)
		(fp_line
			(start 0.12065 -0.2794)
			(end -0.12065 -0.2794)
			(stroke
				(width 0.1)
				(type default)
			)
			(layer "B.Fab")
		)
		(fp_line
			(start -0.12065 -0.2794)
			(end -0.12065 -0.3048)
			(stroke
				(width 0.1)
				(type default)
			)
			(layer "B.Fab")
		)
		(fp_line
			(start 0.12065 0.2794)
			(end 0.12065 0.3048)
			(stroke
				(width 0.1)
				(type default)
			)
			(layer "B.Fab")
		)
		(fp_line
			(start -0.120396 0.2794)
			(end 0.12065 0.2794)
			(stroke
				(width 0.1)
				(type default)
			)
			(layer "B.Fab")
		)
		(fp_line
			(start 0.67945 0.3048)
			(end 0.67945 -0.305054)
			(stroke
				(width 0.1)
				(type default)
			)
			(layer "B.Fab")
		)
		(fp_line
			(start 0.12065 0.3048)
			(end 0.67945 0.3048)
			(stroke
				(width 0.1)
				(type default)
			)
			(layer "B.Fab")
		)
		(fp_line
			(start -0.120396 0.3048)
			(end -0.120396 0.2794)
			(stroke
				(width 0.1)
				(type default)
			)
			(layer "B.Fab")
		)
		(fp_line
			(start -0.67945 0.3048)
			(end -0.120396 0.3048)
			(stroke
				(width 0.1)
				(type default)
			)
			(layer "B.Fab")
		)
		(pad "1" smd circle
			(at 0.40005 0 270)
			(size 0 0)
			(layers "B.Cu" "B.Mask" "B.Paste")
			(net "PWRGD_CHD_CPU0_DIMM2")
		)
		(pad "2" smd circle
			(at -0.40005 0 270)
			(size 0 0)
			(layers "B.Cu" "B.Mask" "B.Paste")
			(net "PWRGD_FAIL_CPU0_CD")
		)
	)
	(footprint ""
		(layer "B.Cu")
		(at 376.493532 -72.531224 180)
		(property "Reference" "PC1241"
			(at 0 0 0)
			(layer "B.SilkS")
			(hide yes)
			(effects
				(font
					(size 1.27 1.27)
				)
				(justify mirror)
			)
		)
		(property "Value" ""
			(at 0 0 0)
			(layer "B.Fab")
			(effects
				(font
					(size 1.27 1.27)
				)
				(justify mirror)
			)
		)
		(duplicate_pad_numbers_are_jumpers no)
		(fp_line
			(start 1.524 0.762)
			(end 1.524 -0.762)
			(stroke
				(width 0.1524)
				(type default)
			)
			(layer "B.SilkS")
		)
		(fp_line
			(start 1.524 -0.762)
			(end -1.524 -0.762)
			(stroke
				(width 0.1524)
				(type default)
			)
			(layer "B.SilkS")
		)
		(fp_line
			(start -1.524 0.762)
			(end 1.524 0.762)
			(stroke
				(width 0.1524)
				(type default)
			)
			(layer "B.SilkS")
		)
		(fp_line
			(start -1.524 -0.762)
			(end -1.524 0.762)
			(stroke
				(width 0.1524)
				(type default)
			)
			(layer "B.SilkS")
		)
		(fp_line
			(start 1.1049 0.724916)
			(end -1.1049 0.724916)
			(stroke
				(width 0.1)
				(type default)
			)
			(layer "B.Fab")
		)
		(fp_line
			(start 1.1049 -0.724916)
			(end 1.1049 0.724916)
			(stroke
				(width 0.1)
				(type default)
			)
			(layer "B.Fab")
		)
		(fp_line
			(start -1.1049 0.724916)
			(end -1.1049 -0.724916)
			(stroke
				(width 0.1)
				(type default)
			)
			(layer "B.Fab")
		)
		(fp_line
			(start -1.1049 -0.724916)
			(end 1.1049 -0.724916)
			(stroke
				(width 0.1)
				(type default)
			)
			(layer "B.Fab")
		)
		(pad "1" smd rect
			(at 0.889 0 180)
			(size 1.016 1.27)
			(layers "B.Cu" "B.Mask" "B.Paste")
			(net "P1V8_PCH_AUX")
		)
		(pad "2" smd rect
			(at -0.889 0 180)
			(size 1.016 1.27)
			(layers "B.Cu" "B.Mask" "B.Paste")
			(net "GND")
		)
	)
	(footprint ""
		(layer "B.Cu")
		(at 119.95912 -252.17628 -90)
		(property "Reference" "C353"
			(at 0 0 90)
			(layer "B.SilkS")
			(hide yes)
			(effects
				(font
					(size 1.27 1.27)
				)
				(justify mirror)
			)
		)
		(property "Value" ""
			(at 0 0 90)
			(layer "B.Fab")
			(effects
				(font
					(size 1.27 1.27)
				)
				(justify mirror)
			)
		)
		(duplicate_pad_numbers_are_jumpers no)
		(fp_line
			(start -1.524 0.762)
			(end 1.524 0.762)
			(stroke
				(width 0.1524)
				(type default)
			)
			(layer "B.SilkS")
		)
		(fp_line
			(start 1.524 0.762)
			(end 1.524 -0.762)
			(stroke
				(width 0.1524)
				(type default)
			)
			(layer "B.SilkS")
		)
		(fp_line
			(start -1.524 -0.762)
			(end -1.524 0.762)
			(stroke
				(width 0.1524)
				(type default)
			)
			(layer "B.SilkS")
		)
		(fp_line
			(start 1.524 -0.762)
			(end -1.524 -0.762)
			(stroke
				(width 0.1524)
				(type default)
			)
			(layer "B.SilkS")
		)
		(fp_line
			(start -1.1049 0.724916)
			(end -1.1049 -0.724916)
			(stroke
				(width 0.1)
				(type default)
			)
			(layer "B.Fab")
		)
		(fp_line
			(start 1.1049 0.724916)
			(end -1.1049 0.724916)
			(stroke
				(width 0.1)
				(type default)
			)
			(layer "B.Fab")
		)
		(fp_line
			(start -1.1049 -0.724916)
			(end 1.1049 -0.724916)
			(stroke
				(width 0.1)
				(type default)
			)
			(layer "B.Fab")
		)
		(fp_line
			(start 1.1049 -0.724916)
			(end 1.1049 0.724916)
			(stroke
				(width 0.1)
				(type default)
			)
			(layer "B.Fab")
		)
		(pad "1" smd rect
			(at 0.889 0 270)
			(size 1.016 1.27)
			(layers "B.Cu" "B.Mask" "B.Paste")
			(net "PVCCIN_CPU1")
		)
		(pad "2" smd rect
			(at -0.889 0 270)
			(size 1.016 1.27)
			(layers "B.Cu" "B.Mask" "B.Paste")
			(net "GND")
		)
	)
	(footprint ""
		(layer "B.Cu")
		(at 317.756032 -39.358062 -135)
		(property "Reference" "R697"
			(at 0 0 45)
			(layer "B.SilkS")
			(hide yes)
			(effects
				(font
					(size 1.27 1.27)
				)
				(justify mirror)
			)
		)
		(property "Value" ""
			(at 0 0 45)
			(layer "B.Fab")
			(effects
				(font
					(size 1.27 1.27)
				)
				(justify mirror)
			)
		)
		(duplicate_pad_numbers_are_jumpers no)
		(fp_line
			(start 0.787389 0.406267)
			(end 0.787389 -0.406267)
			(stroke
				(width 0.1524)
				(type default)
			)
			(layer "B.SilkS")
		)
		(fp_line
			(start 0.787389 -0.406267)
			(end -0.787389 -0.406267)
			(stroke
				(width 0.1524)
				(type default)
			)
			(layer "B.SilkS")
		)
		(fp_line
			(start -0.787389 0.406267)
			(end 0.787389 0.406267)
			(stroke
				(width 0.1524)
				(type default)
			)
			(layer "B.SilkS")
		)
		(fp_line
			(start -0.787389 -0.406267)
			(end -0.787389 0.406267)
			(stroke
				(width 0.1524)
				(type default)
			)
			(layer "B.SilkS")
		)
		(fp_line
			(start 0.679446 0.30479)
			(end 0.679446 -0.305149)
			(stroke
				(width 0.1)
				(type default)
			)
			(layer "B.Fab")
		)
		(fp_line
			(start 0.120515 0.30479)
			(end 0.679446 0.30479)
			(stroke
				(width 0.1)
				(type default)
			)
			(layer "B.Fab")
		)
		(fp_line
			(start 0.120695 0.279466)
			(end 0.120515 0.30479)
			(stroke
				(width 0.1)
				(type default)
			)
			(layer "B.Fab")
		)
		(fp_line
			(start 0.679446 -0.305149)
			(end 0.120695 -0.304969)
			(stroke
				(width 0.1)
				(type default)
			)
			(layer "B.Fab")
		)
		(fp_line
			(start -0.120515 0.30479)
			(end -0.120335 0.279466)
			(stroke
				(width 0.1)
				(type default)
			)
			(layer "B.Fab")
		)
		(fp_line
			(start -0.120335 0.279466)
			(end 0.120695 0.279466)
			(stroke
				(width 0.1)
				(type default)
			)
			(layer "B.Fab")
		)
		(fp_line
			(start 0.120695 -0.279466)
			(end -0.120695 -0.279466)
			(stroke
				(width 0.1)
				(type default)
			)
			(layer "B.Fab")
		)
		(fp_line
			(start 0.120695 -0.304969)
			(end 0.120695 -0.279466)
			(stroke
				(width 0.1)
				(type default)
			)
			(layer "B.Fab")
		)
		(fp_line
			(start -0.679446 0.30479)
			(end -0.120515 0.30479)
			(stroke
				(width 0.1)
				(type default)
			)
			(layer "B.Fab")
		)
		(fp_line
			(start -0.120695 -0.279466)
			(end -0.120515 -0.30479)
			(stroke
				(width 0.1)
				(type default)
			)
			(layer "B.Fab")
		)
		(fp_line
			(start -0.120515 -0.30479)
			(end -0.679446 -0.30479)
			(stroke
				(width 0.1)
				(type default)
			)
			(layer "B.Fab")
		)
		(fp_line
			(start -0.679446 -0.30479)
			(end -0.679446 0.30479)
			(stroke
				(width 0.1)
				(type default)
			)
			(layer "B.Fab")
		)
		(pad "1" smd circle
			(at 0.40005 0 45)
			(size 0 0)
			(layers "B.Cu" "B.Mask" "B.Paste")
			(net "FM_BMC_RSTBTN_OUT_N")
		)
		(pad "2" smd circle
			(at -0.40005 0 45)
			(size 0 0)
			(layers "B.Cu" "B.Mask" "B.Paste")
			(net "RST_PCH_RSTBTN_R_N")
		)
	)
	(footprint ""
		(layer "B.Cu")
		(at 8.19277 -112.04702)
		(property "Reference" "C5232"
			(at 0 0 0)
			(layer "B.SilkS")
			(hide yes)
			(effects
				(font
					(size 1.27 1.27)
				)
				(justify mirror)
			)
		)
		(property "Value" ""
			(at 0 0 0)
			(layer "B.Fab")
			(effects
				(font
					(size 1.27 1.27)
				)
				(justify mirror)
			)
		)
		(duplicate_pad_numbers_are_jumpers no)
		(fp_line
			(start -0.7874 -0.4064)
			(end -0.7874 0.4064)
			(stroke
				(width 0.1524)
				(type default)
			)
			(layer "B.SilkS")
		)
		(fp_line
			(start -0.7874 0.4064)
			(end 0.7874 0.4064)
			(stroke
				(width 0.1524)
				(type default)
			)
			(layer "B.SilkS")
		)
		(fp_line
			(start 0.7874 -0.4064)
			(end -0.7874 -0.4064)
			(stroke
				(width 0.1524)
				(type default)
			)
			(layer "B.SilkS")
		)
		(fp_line
			(start 0.7874 0.4064)
			(end 0.7874 -0.4064)
			(stroke
				(width 0.1524)
				(type default)
			)
			(layer "B.SilkS")
		)
		(fp_line
			(start -0.67945 -0.3048)
			(end -0.67945 0.3048)
			(stroke
				(width 0.1)
				(type default)
			)
			(layer "B.Fab")
		)
		(fp_line
			(start -0.67945 0.3048)
			(end -0.120396 0.3048)
			(stroke
				(width 0.1)
				(type default)
			)
			(layer "B.Fab")
		)
		(fp_line
			(start -0.12065 -0.3048)
			(end -0.67945 -0.3048)
			(stroke
				(width 0.1)
				(type default)
			)
			(layer "B.Fab")
		)
		(fp_line
			(start -0.12065 -0.2794)
			(end -0.12065 -0.3048)
			(stroke
				(width 0.1)
				(type default)
			)
			(layer "B.Fab")
		)
		(fp_line
			(start -0.120396 0.2794)
			(end 0.12065 0.2794)
			(stroke
				(width 0.1)
				(type default)
			)
			(layer "B.Fab")
		)
		(fp_line
			(start -0.120396 0.3048)
			(end -0.120396 0.2794)
			(stroke
				(width 0.1)
				(type default)
			)
			(layer "B.Fab")
		)
		(fp_line
			(start 0.12065 -0.305054)
			(end 0.12065 -0.2794)
			(stroke
				(width 0.1)
				(type default)
			)
			(layer "B.Fab")
		)
		(fp_line
			(start 0.12065 -0.2794)
			(end -0.12065 -0.2794)
			(stroke
				(width 0.1)
				(type default)
			)
			(layer "B.Fab")
		)
		(fp_line
			(start 0.12065 0.2794)
			(end 0.12065 0.3048)
			(stroke
				(width 0.1)
				(type default)
			)
			(layer "B.Fab")
		)
		(fp_line
			(start 0.12065 0.3048)
			(end 0.67945 0.3048)
			(stroke
				(width 0.1)
				(type default)
			)
			(layer "B.Fab")
		)
		(fp_line
			(start 0.67945 -0.305054)
			(end 0.12065 -0.305054)
			(stroke
				(width 0.1)
				(type default)
			)
			(layer "B.Fab")
		)
		(fp_line
			(start 0.67945 0.3048)
			(end 0.67945 -0.305054)
			(stroke
				(width 0.1)
				(type default)
			)
			(layer "B.Fab")
		)
		(pad "1" smd circle
			(at 0.40005 0 180)
			(size 0 0)
			(layers "B.Cu" "B.Mask" "B.Paste")
			(net "PD_U5201_RSTN")
		)
		(pad "2" smd circle
			(at -0.40005 0 180)
			(size 0 0)
			(layers "B.Cu" "B.Mask" "B.Paste")
			(net "GND")
		)
	)
	(footprint ""
		(layer "B.Cu")
		(at 369.52174 -212.049614 180)
		(property "Reference" "C531"
			(at 0 0 0)
			(layer "B.SilkS")
			(hide yes)
			(effects
				(font
					(size 1.27 1.27)
				)
				(justify mirror)
			)
		)
		(property "Value" ""
			(at 0 0 0)
			(layer "B.Fab")
			(effects
				(font
					(size 1.27 1.27)
				)
				(justify mirror)
			)
		)
		(duplicate_pad_numbers_are_jumpers no)
		(fp_line
			(start 1.524 0.762)
			(end 1.524 -0.762)
			(stroke
				(width 0.1524)
				(type default)
			)
			(layer "B.SilkS")
		)
		(fp_line
			(start 1.524 -0.762)
			(end -1.524 -0.762)
			(stroke
				(width 0.1524)
				(type default)
			)
			(layer "B.SilkS")
		)
		(fp_line
			(start -1.524 0.762)
			(end 1.524 0.762)
			(stroke
				(width 0.1524)
				(type default)
			)
			(layer "B.SilkS")
		)
		(fp_line
			(start -1.524 -0.762)
			(end -1.524 0.762)
			(stroke
				(width 0.1524)
				(type default)
			)
			(layer "B.SilkS")
		)
		(fp_line
			(start 1.1049 0.724916)
			(end -1.1049 0.724916)
			(stroke
				(width 0.1)
				(type default)
			)
			(layer "B.Fab")
		)
		(fp_line
			(start 1.1049 -0.724916)
			(end 1.1049 0.724916)
			(stroke
				(width 0.1)
				(type default)
			)
			(layer "B.Fab")
		)
		(fp_line
			(start -1.1049 0.724916)
			(end -1.1049 -0.724916)
			(stroke
				(width 0.1)
				(type default)
			)
			(layer "B.Fab")
		)
		(fp_line
			(start -1.1049 -0.724916)
			(end 1.1049 -0.724916)
			(stroke
				(width 0.1)
				(type default)
			)
			(layer "B.Fab")
		)
		(pad "1" smd rect
			(at 0.889 0 180)
			(size 1.016 1.27)
			(layers "B.Cu" "B.Mask" "B.Paste")
			(net "PVCCINFAON_CPU0")
		)
		(pad "2" smd rect
			(at -0.889 0 180)
			(size 1.016 1.27)
			(layers "B.Cu" "B.Mask" "B.Paste")
			(net "GND")
		)
	)
	(footprint ""
		(layer "B.Cu")
		(at 143.748252 -334.334866)
		(property "Reference" "C1437"
			(at 0 0 0)
			(layer "B.SilkS")
			(hide yes)
			(effects
				(font
					(size 1.27 1.27)
				)
				(justify mirror)
			)
		)
		(property "Value" ""
			(at 0 0 0)
			(layer "B.Fab")
			(effects
				(font
					(size 1.27 1.27)
				)
				(justify mirror)
			)
		)
		(duplicate_pad_numbers_are_jumpers no)
		(fp_line
			(start -0.299974 -0.150114)
			(end -0.299974 0.150114)
			(stroke
				(width 0.1)
				(type default)
			)
			(layer "B.Fab")
		)
		(fp_line
			(start -0.299974 0.150114)
			(end 0.299974 0.150114)
			(stroke
				(width 0.1)
				(type default)
			)
			(layer "B.Fab")
		)
		(fp_line
			(start 0.299974 -0.150114)
			(end -0.299974 -0.150114)
			(stroke
				(width 0.1)
				(type default)
			)
			(layer "B.Fab")
		)
		(fp_line
			(start 0.299974 0.150114)
			(end 0.299974 -0.150114)
			(stroke
				(width 0.1)
				(type default)
			)
			(layer "B.Fab")
		)
		(pad "1" smd rect
			(at 0.2667 0 180)
			(size 0.3048 0.381)
			(layers "B.Cu" "B.Mask" "B.Paste")
			(net "PVPP_HBM_CPU1")
		)
		(pad "2" smd rect
			(at -0.2667 0 180)
			(size 0.3048 0.381)
			(layers "B.Cu" "B.Mask" "B.Paste")
			(net "GND")
		)
	)
	(footprint ""
		(layer "B.Cu")
		(at 438.686956 -318.603376)
		(property "Reference" "R39"
			(at 0 0 0)
			(layer "B.SilkS")
			(hide yes)
			(effects
				(font
					(size 1.27 1.27)
				)
				(justify mirror)
			)
		)
		(property "Value" ""
			(at 0 0 0)
			(layer "B.Fab")
			(effects
				(font
					(size 1.27 1.27)
				)
				(justify mirror)
			)
		)
		(duplicate_pad_numbers_are_jumpers no)
		(fp_line
			(start -0.7874 -0.4064)
			(end -0.7874 0.4064)
			(stroke
				(width 0.1524)
				(type default)
			)
			(layer "B.SilkS")
		)
		(fp_line
			(start -0.7874 0.4064)
			(end 0.7874 0.4064)
			(stroke
				(width 0.1524)
				(type default)
			)
			(layer "B.SilkS")
		)
		(fp_line
			(start 0.7874 -0.4064)
			(end -0.7874 -0.4064)
			(stroke
				(width 0.1524)
				(type default)
			)
			(layer "B.SilkS")
		)
		(fp_line
			(start 0.7874 0.4064)
			(end 0.7874 -0.4064)
			(stroke
				(width 0.1524)
				(type default)
			)
			(layer "B.SilkS")
		)
		(fp_line
			(start -0.67945 -0.3048)
			(end -0.67945 0.3048)
			(stroke
				(width 0.1)
				(type default)
			)
			(layer "B.Fab")
		)
		(fp_line
			(start -0.67945 0.3048)
			(end -0.120396 0.3048)
			(stroke
				(width 0.1)
				(type default)
			)
			(layer "B.Fab")
		)
		(fp_line
			(start -0.12065 -0.3048)
			(end -0.67945 -0.3048)
			(stroke
				(width 0.1)
				(type default)
			)
			(layer "B.Fab")
		)
		(fp_line
			(start -0.12065 -0.2794)
			(end -0.12065 -0.3048)
			(stroke
				(width 0.1)
				(type default)
			)
			(layer "B.Fab")
		)
		(fp_line
			(start -0.120396 0.2794)
			(end 0.12065 0.2794)
			(stroke
				(width 0.1)
				(type default)
			)
			(layer "B.Fab")
		)
		(fp_line
			(start -0.120396 0.3048)
			(end -0.120396 0.2794)
			(stroke
				(width 0.1)
				(type default)
			)
			(layer "B.Fab")
		)
		(fp_line
			(start 0.12065 -0.305054)
			(end 0.12065 -0.2794)
			(stroke
				(width 0.1)
				(type default)
			)
			(layer "B.Fab")
		)
		(fp_line
			(start 0.12065 -0.2794)
			(end -0.12065 -0.2794)
			(stroke
				(width 0.1)
				(type default)
			)
			(layer "B.Fab")
		)
		(fp_line
			(start 0.12065 0.2794)
			(end 0.12065 0.3048)
			(stroke
				(width 0.1)
				(type default)
			)
			(layer "B.Fab")
		)
		(fp_line
			(start 0.12065 0.3048)
			(end 0.67945 0.3048)
			(stroke
				(width 0.1)
				(type default)
			)
			(layer "B.Fab")
		)
		(fp_line
			(start 0.67945 -0.305054)
			(end 0.12065 -0.305054)
			(stroke
				(width 0.1)
				(type default)
			)
			(layer "B.Fab")
		)
		(fp_line
			(start 0.67945 0.3048)
			(end 0.67945 -0.305054)
			(stroke
				(width 0.1)
				(type default)
			)
			(layer "B.Fab")
		)
		(pad "1" smd circle
			(at 0.40005 0 180)
			(size 0 0)
			(layers "B.Cu" "B.Mask" "B.Paste")
			(net "PD_CHG_CPU0_DIMM2_SAA")
		)
		(pad "2" smd circle
			(at -0.40005 0 180)
			(size 0 0)
			(layers "B.Cu" "B.Mask" "B.Paste")
			(net "GND")
		)
	)
	(footprint ""
		(layer "B.Cu")
		(at 115.195604 -296.05478 180)
		(property "Reference" "C350"
			(at 0 0 0)
			(layer "B.SilkS")
			(hide yes)
			(effects
				(font
					(size 1.27 1.27)
				)
				(justify mirror)
			)
		)
		(property "Value" ""
			(at 0 0 0)
			(layer "B.Fab")
			(effects
				(font
					(size 1.27 1.27)
				)
				(justify mirror)
			)
		)
		(duplicate_pad_numbers_are_jumpers no)
		(fp_line
			(start 1.524 0.762)
			(end 1.524 -0.762)
			(stroke
				(width 0.1524)
				(type default)
			)
			(layer "B.SilkS")
		)
		(fp_line
			(start 1.524 -0.762)
			(end -1.524 -0.762)
			(stroke
				(width 0.1524)
				(type default)
			)
			(layer "B.SilkS")
		)
		(fp_line
			(start -1.524 0.762)
			(end 1.524 0.762)
			(stroke
				(width 0.1524)
				(type default)
			)
			(layer "B.SilkS")
		)
		(fp_line
			(start -1.524 -0.762)
			(end -1.524 0.762)
			(stroke
				(width 0.1524)
				(type default)
			)
			(layer "B.SilkS")
		)
		(fp_line
			(start 1.1049 0.724916)
			(end -1.1049 0.724916)
			(stroke
				(width 0.1)
				(type default)
			)
			(layer "B.Fab")
		)
		(fp_line
			(start 1.1049 -0.724916)
			(end 1.1049 0.724916)
			(stroke
				(width 0.1)
				(type default)
			)
			(layer "B.Fab")
		)
		(fp_line
			(start -1.1049 0.724916)
			(end -1.1049 -0.724916)
			(stroke
				(width 0.1)
				(type default)
			)
			(layer "B.Fab")
		)
		(fp_line
			(start -1.1049 -0.724916)
			(end 1.1049 -0.724916)
			(stroke
				(width 0.1)
				(type default)
			)
			(layer "B.Fab")
		)
		(pad "1" smd rect
			(at 0.889 0 180)
			(size 1.016 1.27)
			(layers "B.Cu" "B.Mask" "B.Paste")
			(net "PVCCIN_CPU1")
		)
		(pad "2" smd rect
			(at -0.889 0 180)
			(size 1.016 1.27)
			(layers "B.Cu" "B.Mask" "B.Paste")
			(net "GND")
		)
	)
	(footprint ""
		(layer "B.Cu")
		(at 200.608946 -321.554856 -90)
		(property "Reference" "C83"
			(at 0 0 90)
			(layer "B.SilkS")
			(hide yes)
			(effects
				(font
					(size 1.27 1.27)
				)
				(justify mirror)
			)
		)
		(property "Value" ""
			(at 0 0 90)
			(layer "B.Fab")
			(effects
				(font
					(size 1.27 1.27)
				)
				(justify mirror)
			)
		)
		(duplicate_pad_numbers_are_jumpers no)
		(fp_line
			(start -1.524 0.762)
			(end 1.524 0.762)
			(stroke
				(width 0.1524)
				(type default)
			)
			(layer "B.SilkS")
		)
		(fp_line
			(start 1.524 0.762)
			(end 1.524 -0.762)
			(stroke
				(width 0.1524)
				(type default)
			)
			(layer "B.SilkS")
		)
		(fp_line
			(start -1.524 -0.762)
			(end -1.524 0.762)
			(stroke
				(width 0.1524)
				(type default)
			)
			(layer "B.SilkS")
		)
		(fp_line
			(start 1.524 -0.762)
			(end -1.524 -0.762)
			(stroke
				(width 0.1524)
				(type default)
			)
			(layer "B.SilkS")
		)
		(fp_line
			(start -1.1049 0.724916)
			(end -1.1049 -0.724916)
			(stroke
				(width 0.1)
				(type default)
			)
			(layer "B.Fab")
		)
		(fp_line
			(start 1.1049 0.724916)
			(end -1.1049 0.724916)
			(stroke
				(width 0.1)
				(type default)
			)
			(layer "B.Fab")
		)
		(fp_line
			(start -1.1049 -0.724916)
			(end 1.1049 -0.724916)
			(stroke
				(width 0.1)
				(type default)
			)
			(layer "B.Fab")
		)
		(fp_line
			(start 1.1049 -0.724916)
			(end 1.1049 0.724916)
			(stroke
				(width 0.1)
				(type default)
			)
			(layer "B.Fab")
		)
		(pad "1" smd rect
			(at 0.889 0 270)
			(size 1.016 1.27)
			(layers "B.Cu" "B.Mask" "B.Paste")
			(net "P12V_S3_AUX_CPU1_NVDIMM")
		)
		(pad "2" smd rect
			(at -0.889 0 270)
			(size 1.016 1.27)
			(layers "B.Cu" "B.Mask" "B.Paste")
			(net "GND")
		)
	)
	(footprint ""
		(layer "B.Cu")
		(at 69.772022 -318.385444 90)
		(property "Reference" "R2502"
			(at 0 0 90)
			(layer "B.SilkS")
			(hide yes)
			(effects
				(font
					(size 1.27 1.27)
				)
				(justify mirror)
			)
		)
		(property "Value" ""
			(at 0 0 90)
			(layer "B.Fab")
			(effects
				(font
					(size 1.27 1.27)
				)
				(justify mirror)
			)
		)
		(duplicate_pad_numbers_are_jumpers no)
		(fp_line
			(start 0.7874 -0.4064)
			(end -0.7874 -0.4064)
			(stroke
				(width 0.1524)
				(type default)
			)
			(layer "B.SilkS")
		)
		(fp_line
			(start -0.7874 -0.4064)
			(end -0.7874 0.4064)
			(stroke
				(width 0.1524)
				(type default)
			)
			(layer "B.SilkS")
		)
		(fp_line
			(start 0.7874 0.4064)
			(end 0.7874 -0.4064)
			(stroke
				(width 0.1524)
				(type default)
			)
			(layer "B.SilkS")
		)
		(fp_line
			(start -0.7874 0.4064)
			(end 0.7874 0.4064)
			(stroke
				(width 0.1524)
				(type default)
			)
			(layer "B.SilkS")
		)
		(fp_line
			(start 0.67945 -0.305054)
			(end 0.12065 -0.305054)
			(stroke
				(width 0.1)
				(type default)
			)
			(layer "B.Fab")
		)
		(fp_line
			(start 0.12065 -0.305054)
			(end 0.12065 -0.2794)
			(stroke
				(width 0.1)
				(type default)
			)
			(layer "B.Fab")
		)
		(fp_line
			(start -0.12065 -0.3048)
			(end -0.67945 -0.3048)
			(stroke
				(width 0.1)
				(type default)
			)
			(layer "B.Fab")
		)
		(fp_line
			(start -0.67945 -0.3048)
			(end -0.67945 0.3048)
			(stroke
				(width 0.1)
				(type default)
			)
			(layer "B.Fab")
		)
		(fp_line
			(start 0.12065 -0.2794)
			(end -0.12065 -0.2794)
			(stroke
				(width 0.1)
				(type default)
			)
			(layer "B.Fab")
		)
		(fp_line
			(start -0.12065 -0.2794)
			(end -0.12065 -0.3048)
			(stroke
				(width 0.1)
				(type default)
			)
			(layer "B.Fab")
		)
		(fp_line
			(start 0.12065 0.2794)
			(end 0.12065 0.3048)
			(stroke
				(width 0.1)
				(type default)
			)
			(layer "B.Fab")
		)
		(fp_line
			(start -0.120396 0.2794)
			(end 0.12065 0.2794)
			(stroke
				(width 0.1)
				(type default)
			)
			(layer "B.Fab")
		)
		(fp_line
			(start 0.67945 0.3048)
			(end 0.67945 -0.305054)
			(stroke
				(width 0.1)
				(type default)
			)
			(layer "B.Fab")
		)
		(fp_line
			(start 0.12065 0.3048)
			(end 0.67945 0.3048)
			(stroke
				(width 0.1)
				(type default)
			)
			(layer "B.Fab")
		)
		(fp_line
			(start -0.120396 0.3048)
			(end -0.120396 0.2794)
			(stroke
				(width 0.1)
				(type default)
			)
			(layer "B.Fab")
		)
		(fp_line
			(start -0.67945 0.3048)
			(end -0.120396 0.3048)
			(stroke
				(width 0.1)
				(type default)
			)
			(layer "B.Fab")
		)
		(pad "1" smd circle
			(at 0.40005 0 270)
			(size 0 0)
			(layers "B.Cu" "B.Mask" "B.Paste")
			(net "PWRGD_FAIL_CPU1_AB_R1")
		)
		(pad "2" smd circle
			(at -0.40005 0 270)
			(size 0 0)
			(layers "B.Cu" "B.Mask" "B.Paste")
			(net "PWRGD_FAIL_CPU1_AB_R")
		)
	)
	(footprint ""
		(layer "B.Cu")
		(at 27.0383 -125.342396)
		(property "Reference" "PR283"
			(at 0 0 0)
			(layer "B.SilkS")
			(hide yes)
			(effects
				(font
					(size 1.27 1.27)
				)
				(justify mirror)
			)
		)
		(property "Value" ""
			(at 0 0 0)
			(layer "B.Fab")
			(effects
				(font
					(size 1.27 1.27)
				)
				(justify mirror)
			)
		)
		(duplicate_pad_numbers_are_jumpers no)
		(fp_line
			(start -0.7874 -0.4064)
			(end -0.7874 0.4064)
			(stroke
				(width 0.1524)
				(type default)
			)
			(layer "B.SilkS")
		)
		(fp_line
			(start -0.7874 0.4064)
			(end 0.7874 0.4064)
			(stroke
				(width 0.1524)
				(type default)
			)
			(layer "B.SilkS")
		)
		(fp_line
			(start 0.7874 -0.4064)
			(end -0.7874 -0.4064)
			(stroke
				(width 0.1524)
				(type default)
			)
			(layer "B.SilkS")
		)
		(fp_line
			(start 0.7874 0.4064)
			(end 0.7874 -0.4064)
			(stroke
				(width 0.1524)
				(type default)
			)
			(layer "B.SilkS")
		)
		(fp_line
			(start -0.67945 -0.3048)
			(end -0.67945 0.3048)
			(stroke
				(width 0.1)
				(type default)
			)
			(layer "B.Fab")
		)
		(fp_line
			(start -0.67945 0.3048)
			(end -0.120396 0.3048)
			(stroke
				(width 0.1)
				(type default)
			)
			(layer "B.Fab")
		)
		(fp_line
			(start -0.12065 -0.3048)
			(end -0.67945 -0.3048)
			(stroke
				(width 0.1)
				(type default)
			)
			(layer "B.Fab")
		)
		(fp_line
			(start -0.12065 -0.2794)
			(end -0.12065 -0.3048)
			(stroke
				(width 0.1)
				(type default)
			)
			(layer "B.Fab")
		)
		(fp_line
			(start -0.120396 0.2794)
			(end 0.12065 0.2794)
			(stroke
				(width 0.1)
				(type default)
			)
			(layer "B.Fab")
		)
		(fp_line
			(start -0.120396 0.3048)
			(end -0.120396 0.2794)
			(stroke
				(width 0.1)
				(type default)
			)
			(layer "B.Fab")
		)
		(fp_line
			(start 0.12065 -0.305054)
			(end 0.12065 -0.2794)
			(stroke
				(width 0.1)
				(type default)
			)
			(layer "B.Fab")
		)
		(fp_line
			(start 0.12065 -0.2794)
			(end -0.12065 -0.2794)
			(stroke
				(width 0.1)
				(type default)
			)
			(layer "B.Fab")
		)
		(fp_line
			(start 0.12065 0.2794)
			(end 0.12065 0.3048)
			(stroke
				(width 0.1)
				(type default)
			)
			(layer "B.Fab")
		)
		(fp_line
			(start 0.12065 0.3048)
			(end 0.67945 0.3048)
			(stroke
				(width 0.1)
				(type default)
			)
			(layer "B.Fab")
		)
		(fp_line
			(start 0.67945 -0.305054)
			(end 0.12065 -0.305054)
			(stroke
				(width 0.1)
				(type default)
			)
			(layer "B.Fab")
		)
		(fp_line
			(start 0.67945 0.3048)
			(end 0.67945 -0.305054)
			(stroke
				(width 0.1)
				(type default)
			)
			(layer "B.Fab")
		)
		(pad "1" smd circle
			(at 0.40005 0 180)
			(size 0 0)
			(layers "B.Cu" "B.Mask" "B.Paste")
			(net "PVCCINFAON_CPU1_VCC")
		)
		(pad "2" smd circle
			(at -0.40005 0 180)
			(size 0 0)
			(layers "B.Cu" "B.Mask" "B.Paste")
			(net "P3V3_AUX")
		)
	)
	(footprint ""
		(layer "B.Cu")
		(at 297.419776 -46.40199)
		(property "Reference" "C1246"
			(at 0 0 0)
			(layer "B.SilkS")
			(hide yes)
			(effects
				(font
					(size 1.27 1.27)
				)
				(justify mirror)
			)
		)
		(property "Value" ""
			(at 0 0 0)
			(layer "B.Fab")
			(effects
				(font
					(size 1.27 1.27)
				)
				(justify mirror)
			)
		)
		(duplicate_pad_numbers_are_jumpers no)
		(fp_line
			(start -1.524 -0.762)
			(end -1.524 0.762)
			(stroke
				(width 0.1524)
				(type default)
			)
			(layer "B.SilkS")
		)
		(fp_line
			(start -1.524 0.762)
			(end 1.524 0.762)
			(stroke
				(width 0.1524)
				(type default)
			)
			(layer "B.SilkS")
		)
		(fp_line
			(start 1.524 -0.762)
			(end -1.524 -0.762)
			(stroke
				(width 0.1524)
				(type default)
			)
			(layer "B.SilkS")
		)
		(fp_line
			(start 1.524 0.762)
			(end 1.524 -0.762)
			(stroke
				(width 0.1524)
				(type default)
			)
			(layer "B.SilkS")
		)
		(fp_line
			(start -1.1049 -0.724916)
			(end 1.1049 -0.724916)
			(stroke
				(width 0.1)
				(type default)
			)
			(layer "B.Fab")
		)
		(fp_line
			(start -1.1049 0.724916)
			(end -1.1049 -0.724916)
			(stroke
				(width 0.1)
				(type default)
			)
			(layer "B.Fab")
		)
		(fp_line
			(start 1.1049 -0.724916)
			(end 1.1049 0.724916)
			(stroke
				(width 0.1)
				(type default)
			)
			(layer "B.Fab")
		)
		(fp_line
			(start 1.1049 0.724916)
			(end -1.1049 0.724916)
			(stroke
				(width 0.1)
				(type default)
			)
			(layer "B.Fab")
		)
		(pad "1" smd rect
			(at 0.889 0)
			(size 1.016 1.27)
			(layers "B.Cu" "B.Mask" "B.Paste")
			(net "P1V05_PCH_AUX")
		)
		(pad "2" smd rect
			(at -0.889 0)
			(size 1.016 1.27)
			(layers "B.Cu" "B.Mask" "B.Paste")
			(net "GND")
		)
	)
	(footprint ""
		(layer "B.Cu")
		(at 369.49888 -38.953948 180)
		(property "Reference" "R4112"
			(at 0 0 0)
			(layer "B.SilkS")
			(hide yes)
			(effects
				(font
					(size 1.27 1.27)
				)
				(justify mirror)
			)
		)
		(property "Value" ""
			(at 0 0 0)
			(layer "B.Fab")
			(effects
				(font
					(size 1.27 1.27)
				)
				(justify mirror)
			)
		)
		(duplicate_pad_numbers_are_jumpers no)
		(fp_line
			(start 0.7874 0.4064)
			(end 0.7874 -0.4064)
			(stroke
				(width 0.1524)
				(type default)
			)
			(layer "B.SilkS")
		)
		(fp_line
			(start 0.7874 -0.4064)
			(end -0.7874 -0.4064)
			(stroke
				(width 0.1524)
				(type default)
			)
			(layer "B.SilkS")
		)
		(fp_line
			(start -0.7874 0.4064)
			(end 0.7874 0.4064)
			(stroke
				(width 0.1524)
				(type default)
			)
			(layer "B.SilkS")
		)
		(fp_line
			(start -0.7874 -0.4064)
			(end -0.7874 0.4064)
			(stroke
				(width 0.1524)
				(type default)
			)
			(layer "B.SilkS")
		)
		(fp_line
			(start 0.67945 0.3048)
			(end 0.67945 -0.305054)
			(stroke
				(width 0.1)
				(type default)
			)
			(layer "B.Fab")
		)
		(fp_line
			(start 0.67945 -0.305054)
			(end 0.12065 -0.305054)
			(stroke
				(width 0.1)
				(type default)
			)
			(layer "B.Fab")
		)
		(fp_line
			(start 0.12065 0.3048)
			(end 0.67945 0.3048)
			(stroke
				(width 0.1)
				(type default)
			)
			(layer "B.Fab")
		)
		(fp_line
			(start 0.12065 0.2794)
			(end 0.12065 0.3048)
			(stroke
				(width 0.1)
				(type default)
			)
			(layer "B.Fab")
		)
		(fp_line
			(start 0.12065 -0.2794)
			(end -0.12065 -0.2794)
			(stroke
				(width 0.1)
				(type default)
			)
			(layer "B.Fab")
		)
		(fp_line
			(start 0.12065 -0.305054)
			(end 0.12065 -0.2794)
			(stroke
				(width 0.1)
				(type default)
			)
			(layer "B.Fab")
		)
		(fp_line
			(start -0.120396 0.3048)
			(end -0.120396 0.2794)
			(stroke
				(width 0.1)
				(type default)
			)
			(layer "B.Fab")
		)
		(fp_line
			(start -0.120396 0.2794)
			(end 0.12065 0.2794)
			(stroke
				(width 0.1)
				(type default)
			)
			(layer "B.Fab")
		)
		(fp_line
			(start -0.12065 -0.2794)
			(end -0.12065 -0.3048)
			(stroke
				(width 0.1)
				(type default)
			)
			(layer "B.Fab")
		)
		(fp_line
			(start -0.12065 -0.3048)
			(end -0.67945 -0.3048)
			(stroke
				(width 0.1)
				(type default)
			)
			(layer "B.Fab")
		)
		(fp_line
			(start -0.67945 0.3048)
			(end -0.120396 0.3048)
			(stroke
				(width 0.1)
				(type default)
			)
			(layer "B.Fab")
		)
		(fp_line
			(start -0.67945 -0.3048)
			(end -0.67945 0.3048)
			(stroke
				(width 0.1)
				(type default)
			)
			(layer "B.Fab")
		)
		(pad "1" smd circle
			(at 0.40005 0)
			(size 0 0)
			(layers "B.Cu" "B.Mask" "B.Paste")
			(net "PD_PCH_GPP_E_12")
		)
		(pad "2" smd circle
			(at -0.40005 0)
			(size 0 0)
			(layers "B.Cu" "B.Mask" "B.Paste")
			(net "GND")
		)
	)
	(footprint ""
		(layer "B.Cu")
		(at 218.83751 -68.38188 180)
		(property "Reference" "R3959"
			(at 0 0 0)
			(layer "B.SilkS")
			(hide yes)
			(effects
				(font
					(size 1.27 1.27)
				)
				(justify mirror)
			)
		)
		(property "Value" ""
			(at 0 0 0)
			(layer "B.Fab")
			(effects
				(font
					(size 1.27 1.27)
				)
				(justify mirror)
			)
		)
		(duplicate_pad_numbers_are_jumpers no)
		(fp_line
			(start 0.7874 0.4064)
			(end 0.7874 -0.4064)
			(stroke
				(width 0.1524)
				(type default)
			)
			(layer "B.SilkS")
		)
		(fp_line
			(start 0.7874 -0.4064)
			(end -0.7874 -0.4064)
			(stroke
				(width 0.1524)
				(type default)
			)
			(layer "B.SilkS")
		)
		(fp_line
			(start -0.7874 0.4064)
			(end 0.7874 0.4064)
			(stroke
				(width 0.1524)
				(type default)
			)
			(layer "B.SilkS")
		)
		(fp_line
			(start -0.7874 -0.4064)
			(end -0.7874 0.4064)
			(stroke
				(width 0.1524)
				(type default)
			)
			(layer "B.SilkS")
		)
		(fp_line
			(start 0.67945 0.3048)
			(end 0.67945 -0.305054)
			(stroke
				(width 0.1)
				(type default)
			)
			(layer "B.Fab")
		)
		(fp_line
			(start 0.67945 -0.305054)
			(end 0.12065 -0.305054)
			(stroke
				(width 0.1)
				(type default)
			)
			(layer "B.Fab")
		)
		(fp_line
			(start 0.12065 0.3048)
			(end 0.67945 0.3048)
			(stroke
				(width 0.1)
				(type default)
			)
			(layer "B.Fab")
		)
		(fp_line
			(start 0.12065 0.2794)
			(end 0.12065 0.3048)
			(stroke
				(width 0.1)
				(type default)
			)
			(layer "B.Fab")
		)
		(fp_line
			(start 0.12065 -0.2794)
			(end -0.12065 -0.2794)
			(stroke
				(width 0.1)
				(type default)
			)
			(layer "B.Fab")
		)
		(fp_line
			(start 0.12065 -0.305054)
			(end 0.12065 -0.2794)
			(stroke
				(width 0.1)
				(type default)
			)
			(layer "B.Fab")
		)
		(fp_line
			(start -0.120396 0.3048)
			(end -0.120396 0.2794)
			(stroke
				(width 0.1)
				(type default)
			)
			(layer "B.Fab")
		)
		(fp_line
			(start -0.120396 0.2794)
			(end 0.12065 0.2794)
			(stroke
				(width 0.1)
				(type default)
			)
			(layer "B.Fab")
		)
		(fp_line
			(start -0.12065 -0.2794)
			(end -0.12065 -0.3048)
			(stroke
				(width 0.1)
				(type default)
			)
			(layer "B.Fab")
		)
		(fp_line
			(start -0.12065 -0.3048)
			(end -0.67945 -0.3048)
			(stroke
				(width 0.1)
				(type default)
			)
			(layer "B.Fab")
		)
		(fp_line
			(start -0.67945 0.3048)
			(end -0.120396 0.3048)
			(stroke
				(width 0.1)
				(type default)
			)
			(layer "B.Fab")
		)
		(fp_line
			(start -0.67945 -0.3048)
			(end -0.67945 0.3048)
			(stroke
				(width 0.1)
				(type default)
			)
			(layer "B.Fab")
		)
		(pad "1" smd circle
			(at 0.40005 0)
			(size 0 0)
			(layers "B.Cu" "B.Mask" "B.Paste")
			(net "P3V3_E1S_UV_0_R")
		)
		(pad "2" smd circle
			(at -0.40005 0)
			(size 0 0)
			(layers "B.Cu" "B.Mask" "B.Paste")
			(net "P3V3_E1S_UV_0")
		)
	)
	(footprint ""
		(layer "B.Cu")
		(at 399.670778 -190.77559 90)
		(property "Reference" "R179"
			(at 0 0 90)
			(layer "B.SilkS")
			(hide yes)
			(effects
				(font
					(size 1.27 1.27)
				)
				(justify mirror)
			)
		)
		(property "Value" ""
			(at 0 0 90)
			(layer "B.Fab")
			(effects
				(font
					(size 1.27 1.27)
				)
				(justify mirror)
			)
		)
		(duplicate_pad_numbers_are_jumpers no)
		(fp_line
			(start 0.7874 -0.4064)
			(end -0.7874 -0.4064)
			(stroke
				(width 0.1524)
				(type default)
			)
			(layer "B.SilkS")
		)
		(fp_line
			(start -0.7874 -0.4064)
			(end -0.7874 0.4064)
			(stroke
				(width 0.1524)
				(type default)
			)
			(layer "B.SilkS")
		)
		(fp_line
			(start 0.7874 0.4064)
			(end 0.7874 -0.4064)
			(stroke
				(width 0.1524)
				(type default)
			)
			(layer "B.SilkS")
		)
		(fp_line
			(start -0.7874 0.4064)
			(end 0.7874 0.4064)
			(stroke
				(width 0.1524)
				(type default)
			)
			(layer "B.SilkS")
		)
		(fp_line
			(start 0.67945 -0.305054)
			(end 0.12065 -0.305054)
			(stroke
				(width 0.1)
				(type default)
			)
			(layer "B.Fab")
		)
		(fp_line
			(start 0.12065 -0.305054)
			(end 0.12065 -0.2794)
			(stroke
				(width 0.1)
				(type default)
			)
			(layer "B.Fab")
		)
		(fp_line
			(start -0.12065 -0.3048)
			(end -0.67945 -0.3048)
			(stroke
				(width 0.1)
				(type default)
			)
			(layer "B.Fab")
		)
		(fp_line
			(start -0.67945 -0.3048)
			(end -0.67945 0.3048)
			(stroke
				(width 0.1)
				(type default)
			)
			(layer "B.Fab")
		)
		(fp_line
			(start 0.12065 -0.2794)
			(end -0.12065 -0.2794)
			(stroke
				(width 0.1)
				(type default)
			)
			(layer "B.Fab")
		)
		(fp_line
			(start -0.12065 -0.2794)
			(end -0.12065 -0.3048)
			(stroke
				(width 0.1)
				(type default)
			)
			(layer "B.Fab")
		)
		(fp_line
			(start 0.12065 0.2794)
			(end 0.12065 0.3048)
			(stroke
				(width 0.1)
				(type default)
			)
			(layer "B.Fab")
		)
		(fp_line
			(start -0.120396 0.2794)
			(end 0.12065 0.2794)
			(stroke
				(width 0.1)
				(type default)
			)
			(layer "B.Fab")
		)
		(fp_line
			(start 0.67945 0.3048)
			(end 0.67945 -0.305054)
			(stroke
				(width 0.1)
				(type default)
			)
			(layer "B.Fab")
		)
		(fp_line
			(start 0.12065 0.3048)
			(end 0.67945 0.3048)
			(stroke
				(width 0.1)
				(type default)
			)
			(layer "B.Fab")
		)
		(fp_line
			(start -0.120396 0.3048)
			(end -0.120396 0.2794)
			(stroke
				(width 0.1)
				(type default)
			)
			(layer "B.Fab")
		)
		(fp_line
			(start -0.67945 0.3048)
			(end -0.120396 0.3048)
			(stroke
				(width 0.1)
				(type default)
			)
			(layer "B.Fab")
		)
		(pad "1" smd circle
			(at 0.40005 0 270)
			(size 0 0)
			(layers "B.Cu" "B.Mask" "B.Paste")
			(net "PWRGD_DRAMPWRGD_CPU0_EF_LVC1_R2")
		)
		(pad "2" smd circle
			(at -0.40005 0 270)
			(size 0 0)
			(layers "B.Cu" "B.Mask" "B.Paste")
			(net "PVCCD_HV_CPU0")
		)
	)
	(footprint ""
		(layer "B.Cu")
		(at 160.83788 -120.106948)
		(property "Reference" "R985"
			(at 0 0 0)
			(layer "B.SilkS")
			(hide yes)
			(effects
				(font
					(size 1.27 1.27)
				)
				(justify mirror)
			)
		)
		(property "Value" ""
			(at 0 0 0)
			(layer "B.Fab")
			(effects
				(font
					(size 1.27 1.27)
				)
				(justify mirror)
			)
		)
		(duplicate_pad_numbers_are_jumpers no)
		(fp_line
			(start -0.7874 -0.4064)
			(end -0.7874 0.4064)
			(stroke
				(width 0.1524)
				(type default)
			)
			(layer "B.SilkS")
		)
		(fp_line
			(start -0.7874 0.4064)
			(end 0.7874 0.4064)
			(stroke
				(width 0.1524)
				(type default)
			)
			(layer "B.SilkS")
		)
		(fp_line
			(start 0.7874 -0.4064)
			(end -0.7874 -0.4064)
			(stroke
				(width 0.1524)
				(type default)
			)
			(layer "B.SilkS")
		)
		(fp_line
			(start 0.7874 0.4064)
			(end 0.7874 -0.4064)
			(stroke
				(width 0.1524)
				(type default)
			)
			(layer "B.SilkS")
		)
		(fp_line
			(start -0.67945 -0.3048)
			(end -0.67945 0.3048)
			(stroke
				(width 0.1)
				(type default)
			)
			(layer "B.Fab")
		)
		(fp_line
			(start -0.67945 0.3048)
			(end -0.120396 0.3048)
			(stroke
				(width 0.1)
				(type default)
			)
			(layer "B.Fab")
		)
		(fp_line
			(start -0.12065 -0.3048)
			(end -0.67945 -0.3048)
			(stroke
				(width 0.1)
				(type default)
			)
			(layer "B.Fab")
		)
		(fp_line
			(start -0.12065 -0.2794)
			(end -0.12065 -0.3048)
			(stroke
				(width 0.1)
				(type default)
			)
			(layer "B.Fab")
		)
		(fp_line
			(start -0.120396 0.2794)
			(end 0.12065 0.2794)
			(stroke
				(width 0.1)
				(type default)
			)
			(layer "B.Fab")
		)
		(fp_line
			(start -0.120396 0.3048)
			(end -0.120396 0.2794)
			(stroke
				(width 0.1)
				(type default)
			)
			(layer "B.Fab")
		)
		(fp_line
			(start 0.12065 -0.305054)
			(end 0.12065 -0.2794)
			(stroke
				(width 0.1)
				(type default)
			)
			(layer "B.Fab")
		)
		(fp_line
			(start 0.12065 -0.2794)
			(end -0.12065 -0.2794)
			(stroke
				(width 0.1)
				(type default)
			)
			(layer "B.Fab")
		)
		(fp_line
			(start 0.12065 0.2794)
			(end 0.12065 0.3048)
			(stroke
				(width 0.1)
				(type default)
			)
			(layer "B.Fab")
		)
		(fp_line
			(start 0.12065 0.3048)
			(end 0.67945 0.3048)
			(stroke
				(width 0.1)
				(type default)
			)
			(layer "B.Fab")
		)
		(fp_line
			(start 0.67945 -0.305054)
			(end 0.12065 -0.305054)
			(stroke
				(width 0.1)
				(type default)
			)
			(layer "B.Fab")
		)
		(fp_line
			(start 0.67945 0.3048)
			(end 0.67945 -0.305054)
			(stroke
				(width 0.1)
				(type default)
			)
			(layer "B.Fab")
		)
		(pad "1" smd circle
			(at 0.40005 0 180)
			(size 0 0)
			(layers "B.Cu" "B.Mask" "B.Paste")
			(net "FM_PVCCIN_CPU1_R_EN")
		)
		(pad "2" smd circle
			(at -0.40005 0 180)
			(size 0 0)
			(layers "B.Cu" "B.Mask" "B.Paste")
			(net "FM_PVCCIN_CPU1_EN")
		)
	)
	(footprint ""
		(layer "B.Cu")
		(at 351.841308 -252.176026 -90)
		(property "Reference" "C365"
			(at 0 0 90)
			(layer "B.SilkS")
			(hide yes)
			(effects
				(font
					(size 1.27 1.27)
				)
				(justify mirror)
			)
		)
		(property "Value" ""
			(at 0 0 90)
			(layer "B.Fab")
			(effects
				(font
					(size 1.27 1.27)
				)
				(justify mirror)
			)
		)
		(duplicate_pad_numbers_are_jumpers no)
		(fp_line
			(start -1.524 0.762)
			(end 1.524 0.762)
			(stroke
				(width 0.1524)
				(type default)
			)
			(layer "B.SilkS")
		)
		(fp_line
			(start 1.524 0.762)
			(end 1.524 -0.762)
			(stroke
				(width 0.1524)
				(type default)
			)
			(layer "B.SilkS")
		)
		(fp_line
			(start -1.524 -0.762)
			(end -1.524 0.762)
			(stroke
				(width 0.1524)
				(type default)
			)
			(layer "B.SilkS")
		)
		(fp_line
			(start 1.524 -0.762)
			(end -1.524 -0.762)
			(stroke
				(width 0.1524)
				(type default)
			)
			(layer "B.SilkS")
		)
		(fp_line
			(start -1.1049 0.724916)
			(end -1.1049 -0.724916)
			(stroke
				(width 0.1)
				(type default)
			)
			(layer "B.Fab")
		)
		(fp_line
			(start 1.1049 0.724916)
			(end -1.1049 0.724916)
			(stroke
				(width 0.1)
				(type default)
			)
			(layer "B.Fab")
		)
		(fp_line
			(start -1.1049 -0.724916)
			(end 1.1049 -0.724916)
			(stroke
				(width 0.1)
				(type default)
			)
			(layer "B.Fab")
		)
		(fp_line
			(start 1.1049 -0.724916)
			(end 1.1049 0.724916)
			(stroke
				(width 0.1)
				(type default)
			)
			(layer "B.Fab")
		)
		(pad "1" smd rect
			(at 0.889 0 270)
			(size 1.016 1.27)
			(layers "B.Cu" "B.Mask" "B.Paste")
			(net "PVCCIN_CPU0")
		)
		(pad "2" smd rect
			(at -0.889 0 270)
			(size 1.016 1.27)
			(layers "B.Cu" "B.Mask" "B.Paste")
			(net "GND")
		)
	)
	(footprint ""
		(layer "B.Cu")
		(at 319.635378 -188.41339)
		(property "Reference" "R197"
			(at 0 0 0)
			(layer "B.SilkS")
			(hide yes)
			(effects
				(font
					(size 1.27 1.27)
				)
				(justify mirror)
			)
		)
		(property "Value" ""
			(at 0 0 0)
			(layer "B.Fab")
			(effects
				(font
					(size 1.27 1.27)
				)
				(justify mirror)
			)
		)
		(duplicate_pad_numbers_are_jumpers no)
		(fp_line
			(start -0.7874 -0.4064)
			(end -0.7874 0.4064)
			(stroke
				(width 0.1524)
				(type default)
			)
			(layer "B.SilkS")
		)
		(fp_line
			(start -0.7874 0.4064)
			(end 0.7874 0.4064)
			(stroke
				(width 0.1524)
				(type default)
			)
			(layer "B.SilkS")
		)
		(fp_line
			(start 0.7874 -0.4064)
			(end -0.7874 -0.4064)
			(stroke
				(width 0.1524)
				(type default)
			)
			(layer "B.SilkS")
		)
		(fp_line
			(start 0.7874 0.4064)
			(end 0.7874 -0.4064)
			(stroke
				(width 0.1524)
				(type default)
			)
			(layer "B.SilkS")
		)
		(fp_line
			(start -0.67945 -0.3048)
			(end -0.67945 0.3048)
			(stroke
				(width 0.1)
				(type default)
			)
			(layer "B.Fab")
		)
		(fp_line
			(start -0.67945 0.3048)
			(end -0.120396 0.3048)
			(stroke
				(width 0.1)
				(type default)
			)
			(layer "B.Fab")
		)
		(fp_line
			(start -0.12065 -0.3048)
			(end -0.67945 -0.3048)
			(stroke
				(width 0.1)
				(type default)
			)
			(layer "B.Fab")
		)
		(fp_line
			(start -0.12065 -0.2794)
			(end -0.12065 -0.3048)
			(stroke
				(width 0.1)
				(type default)
			)
			(layer "B.Fab")
		)
		(fp_line
			(start -0.120396 0.2794)
			(end 0.12065 0.2794)
			(stroke
				(width 0.1)
				(type default)
			)
			(layer "B.Fab")
		)
		(fp_line
			(start -0.120396 0.3048)
			(end -0.120396 0.2794)
			(stroke
				(width 0.1)
				(type default)
			)
			(layer "B.Fab")
		)
		(fp_line
			(start 0.12065 -0.305054)
			(end 0.12065 -0.2794)
			(stroke
				(width 0.1)
				(type default)
			)
			(layer "B.Fab")
		)
		(fp_line
			(start 0.12065 -0.2794)
			(end -0.12065 -0.2794)
			(stroke
				(width 0.1)
				(type default)
			)
			(layer "B.Fab")
		)
		(fp_line
			(start 0.12065 0.2794)
			(end 0.12065 0.3048)
			(stroke
				(width 0.1)
				(type default)
			)
			(layer "B.Fab")
		)
		(fp_line
			(start 0.12065 0.3048)
			(end 0.67945 0.3048)
			(stroke
				(width 0.1)
				(type default)
			)
			(layer "B.Fab")
		)
		(fp_line
			(start 0.67945 -0.305054)
			(end 0.12065 -0.305054)
			(stroke
				(width 0.1)
				(type default)
			)
			(layer "B.Fab")
		)
		(fp_line
			(start 0.67945 0.3048)
			(end 0.67945 -0.305054)
			(stroke
				(width 0.1)
				(type default)
			)
			(layer "B.Fab")
		)
		(pad "1" smd circle
			(at 0.40005 0 180)
			(size 0 0)
			(layers "B.Cu" "B.Mask" "B.Paste")
			(net "PVNN_TERM_CPU0")
		)
		(pad "2" smd circle
			(at -0.40005 0 180)
			(size 0 0)
			(layers "B.Cu" "B.Mask" "B.Paste")
			(net "H_CPU0_NMI_LVC1_N")
		)
	)
	(footprint ""
		(layer "B.Cu")
		(at 164.857938 -8.91794 -90)
		(property "Reference" "R2205"
			(at 0 0 90)
			(layer "B.SilkS")
			(hide yes)
			(effects
				(font
					(size 1.27 1.27)
				)
				(justify mirror)
			)
		)
		(property "Value" ""
			(at 0 0 90)
			(layer "B.Fab")
			(effects
				(font
					(size 1.27 1.27)
				)
				(justify mirror)
			)
		)
		(duplicate_pad_numbers_are_jumpers no)
		(fp_line
			(start -0.7874 0.4064)
			(end 0.7874 0.4064)
			(stroke
				(width 0.1524)
				(type default)
			)
			(layer "B.SilkS")
		)
		(fp_line
			(start 0.7874 0.4064)
			(end 0.7874 -0.4064)
			(stroke
				(width 0.1524)
				(type default)
			)
			(layer "B.SilkS")
		)
		(fp_line
			(start -0.7874 -0.4064)
			(end -0.7874 0.4064)
			(stroke
				(width 0.1524)
				(type default)
			)
			(layer "B.SilkS")
		)
		(fp_line
			(start 0.7874 -0.4064)
			(end -0.7874 -0.4064)
			(stroke
				(width 0.1524)
				(type default)
			)
			(layer "B.SilkS")
		)
		(fp_line
			(start -0.67945 0.3048)
			(end -0.120396 0.3048)
			(stroke
				(width 0.1)
				(type default)
			)
			(layer "B.Fab")
		)
		(fp_line
			(start -0.120396 0.3048)
			(end -0.120396 0.2794)
			(stroke
				(width 0.1)
				(type default)
			)
			(layer "B.Fab")
		)
		(fp_line
			(start 0.12065 0.3048)
			(end 0.67945 0.3048)
			(stroke
				(width 0.1)
				(type default)
			)
			(layer "B.Fab")
		)
		(fp_line
			(start 0.67945 0.3048)
			(end 0.67945 -0.305054)
			(stroke
				(width 0.1)
				(type default)
			)
			(layer "B.Fab")
		)
		(fp_line
			(start -0.120396 0.2794)
			(end 0.12065 0.2794)
			(stroke
				(width 0.1)
				(type default)
			)
			(layer "B.Fab")
		)
		(fp_line
			(start 0.12065 0.2794)
			(end 0.12065 0.3048)
			(stroke
				(width 0.1)
				(type default)
			)
			(layer "B.Fab")
		)
		(fp_line
			(start -0.12065 -0.2794)
			(end -0.12065 -0.3048)
			(stroke
				(width 0.1)
				(type default)
			)
			(layer "B.Fab")
		)
		(fp_line
			(start 0.12065 -0.2794)
			(end -0.12065 -0.2794)
			(stroke
				(width 0.1)
				(type default)
			)
			(layer "B.Fab")
		)
		(fp_line
			(start -0.67945 -0.3048)
			(end -0.67945 0.3048)
			(stroke
				(width 0.1)
				(type default)
			)
			(layer "B.Fab")
		)
		(fp_line
			(start -0.12065 -0.3048)
			(end -0.67945 -0.3048)
			(stroke
				(width 0.1)
				(type default)
			)
			(layer "B.Fab")
		)
		(fp_line
			(start 0.12065 -0.305054)
			(end 0.12065 -0.2794)
			(stroke
				(width 0.1)
				(type default)
			)
			(layer "B.Fab")
		)
		(fp_line
			(start 0.67945 -0.305054)
			(end 0.12065 -0.305054)
			(stroke
				(width 0.1)
				(type default)
			)
			(layer "B.Fab")
		)
		(pad "1" smd circle
			(at 0.40005 0 90)
			(size 0 0)
			(layers "B.Cu" "B.Mask" "B.Paste")
			(net "P3V3_AUX")
		)
		(pad "2" smd circle
			(at -0.40005 0 90)
			(size 0 0)
			(layers "B.Cu" "B.Mask" "B.Paste")
			(net "SMB_PCIE0_3V3AUX_SDA")
		)
	)
	(footprint ""
		(layer "B.Cu")
		(at 196.544946 -321.554856 -90)
		(property "Reference" "C82"
			(at 0 0 90)
			(layer "B.SilkS")
			(hide yes)
			(effects
				(font
					(size 1.27 1.27)
				)
				(justify mirror)
			)
		)
		(property "Value" ""
			(at 0 0 90)
			(layer "B.Fab")
			(effects
				(font
					(size 1.27 1.27)
				)
				(justify mirror)
			)
		)
		(duplicate_pad_numbers_are_jumpers no)
		(fp_line
			(start -1.524 0.762)
			(end 1.524 0.762)
			(stroke
				(width 0.1524)
				(type default)
			)
			(layer "B.SilkS")
		)
		(fp_line
			(start 1.524 0.762)
			(end 1.524 -0.762)
			(stroke
				(width 0.1524)
				(type default)
			)
			(layer "B.SilkS")
		)
		(fp_line
			(start -1.524 -0.762)
			(end -1.524 0.762)
			(stroke
				(width 0.1524)
				(type default)
			)
			(layer "B.SilkS")
		)
		(fp_line
			(start 1.524 -0.762)
			(end -1.524 -0.762)
			(stroke
				(width 0.1524)
				(type default)
			)
			(layer "B.SilkS")
		)
		(fp_line
			(start -1.1049 0.724916)
			(end -1.1049 -0.724916)
			(stroke
				(width 0.1)
				(type default)
			)
			(layer "B.Fab")
		)
		(fp_line
			(start 1.1049 0.724916)
			(end -1.1049 0.724916)
			(stroke
				(width 0.1)
				(type default)
			)
			(layer "B.Fab")
		)
		(fp_line
			(start -1.1049 -0.724916)
			(end 1.1049 -0.724916)
			(stroke
				(width 0.1)
				(type default)
			)
			(layer "B.Fab")
		)
		(fp_line
			(start 1.1049 -0.724916)
			(end 1.1049 0.724916)
			(stroke
				(width 0.1)
				(type default)
			)
			(layer "B.Fab")
		)
		(pad "1" smd rect
			(at 0.889 0 270)
			(size 1.016 1.27)
			(layers "B.Cu" "B.Mask" "B.Paste")
			(net "P12V_S3_AUX_CPU1_NVDIMM")
		)
		(pad "2" smd rect
			(at -0.889 0 270)
			(size 1.016 1.27)
			(layers "B.Cu" "B.Mask" "B.Paste")
			(net "GND")
		)
	)
	(footprint ""
		(layer "B.Cu")
		(at 108.019596 -324.792086 -90)
		(property "Reference" "PC575_P1_2"
			(at 0 0 90)
			(layer "B.SilkS")
			(hide yes)
			(effects
				(font
					(size 1.27 1.27)
				)
				(justify mirror)
			)
		)
		(property "Value" ""
			(at 0 0 90)
			(layer "B.Fab")
			(effects
				(font
					(size 1.27 1.27)
				)
				(justify mirror)
			)
		)
		(duplicate_pad_numbers_are_jumpers no)
		(fp_line
			(start -1.524 0.762)
			(end 1.524 0.762)
			(stroke
				(width 0.1524)
				(type default)
			)
			(layer "B.SilkS")
		)
		(fp_line
			(start 1.524 0.762)
			(end 1.524 -0.762)
			(stroke
				(width 0.1524)
				(type default)
			)
			(layer "B.SilkS")
		)
		(fp_line
			(start -1.524 -0.762)
			(end -1.524 0.762)
			(stroke
				(width 0.1524)
				(type default)
			)
			(layer "B.SilkS")
		)
		(fp_line
			(start 1.524 -0.762)
			(end -1.524 -0.762)
			(stroke
				(width 0.1524)
				(type default)
			)
			(layer "B.SilkS")
		)
		(fp_line
			(start -1.1049 0.724916)
			(end -1.1049 -0.724916)
			(stroke
				(width 0.1)
				(type default)
			)
			(layer "B.Fab")
		)
		(fp_line
			(start 1.1049 0.724916)
			(end -1.1049 0.724916)
			(stroke
				(width 0.1)
				(type default)
			)
			(layer "B.Fab")
		)
		(fp_line
			(start -1.1049 -0.724916)
			(end 1.1049 -0.724916)
			(stroke
				(width 0.1)
				(type default)
			)
			(layer "B.Fab")
		)
		(fp_line
			(start 1.1049 -0.724916)
			(end 1.1049 0.724916)
			(stroke
				(width 0.1)
				(type default)
			)
			(layer "B.Fab")
		)
		(pad "1" smd rect
			(at 0.889 0 270)
			(size 1.016 1.27)
			(layers "B.Cu" "B.Mask" "B.Paste")
			(net "PVCCIN_CPU1")
		)
		(pad "2" smd rect
			(at -0.889 0 270)
			(size 1.016 1.27)
			(layers "B.Cu" "B.Mask" "B.Paste")
			(net "GND")
		)
	)
	(footprint ""
		(layer "B.Cu")
		(at 69.342 -188.469016 -90)
		(property "Reference" "R557"
			(at 0 0 90)
			(layer "B.SilkS")
			(hide yes)
			(effects
				(font
					(size 1.27 1.27)
				)
				(justify mirror)
			)
		)
		(property "Value" ""
			(at 0 0 90)
			(layer "B.Fab")
			(effects
				(font
					(size 1.27 1.27)
				)
				(justify mirror)
			)
		)
		(duplicate_pad_numbers_are_jumpers no)
		(fp_line
			(start -0.7874 0.4064)
			(end 0.7874 0.4064)
			(stroke
				(width 0.1524)
				(type default)
			)
			(layer "B.SilkS")
		)
		(fp_line
			(start 0.7874 0.4064)
			(end 0.7874 -0.4064)
			(stroke
				(width 0.1524)
				(type default)
			)
			(layer "B.SilkS")
		)
		(fp_line
			(start -0.7874 -0.4064)
			(end -0.7874 0.4064)
			(stroke
				(width 0.1524)
				(type default)
			)
			(layer "B.SilkS")
		)
		(fp_line
			(start 0.7874 -0.4064)
			(end -0.7874 -0.4064)
			(stroke
				(width 0.1524)
				(type default)
			)
			(layer "B.SilkS")
		)
		(fp_line
			(start -0.67945 0.3048)
			(end -0.120396 0.3048)
			(stroke
				(width 0.1)
				(type default)
			)
			(layer "B.Fab")
		)
		(fp_line
			(start -0.120396 0.3048)
			(end -0.120396 0.2794)
			(stroke
				(width 0.1)
				(type default)
			)
			(layer "B.Fab")
		)
		(fp_line
			(start 0.12065 0.3048)
			(end 0.67945 0.3048)
			(stroke
				(width 0.1)
				(type default)
			)
			(layer "B.Fab")
		)
		(fp_line
			(start 0.67945 0.3048)
			(end 0.67945 -0.305054)
			(stroke
				(width 0.1)
				(type default)
			)
			(layer "B.Fab")
		)
		(fp_line
			(start -0.120396 0.2794)
			(end 0.12065 0.2794)
			(stroke
				(width 0.1)
				(type default)
			)
			(layer "B.Fab")
		)
		(fp_line
			(start 0.12065 0.2794)
			(end 0.12065 0.3048)
			(stroke
				(width 0.1)
				(type default)
			)
			(layer "B.Fab")
		)
		(fp_line
			(start -0.12065 -0.2794)
			(end -0.12065 -0.3048)
			(stroke
				(width 0.1)
				(type default)
			)
			(layer "B.Fab")
		)
		(fp_line
			(start 0.12065 -0.2794)
			(end -0.12065 -0.2794)
			(stroke
				(width 0.1)
				(type default)
			)
			(layer "B.Fab")
		)
		(fp_line
			(start -0.67945 -0.3048)
			(end -0.67945 0.3048)
			(stroke
				(width 0.1)
				(type default)
			)
			(layer "B.Fab")
		)
		(fp_line
			(start -0.12065 -0.3048)
			(end -0.67945 -0.3048)
			(stroke
				(width 0.1)
				(type default)
			)
			(layer "B.Fab")
		)
		(fp_line
			(start 0.12065 -0.305054)
			(end 0.12065 -0.2794)
			(stroke
				(width 0.1)
				(type default)
			)
			(layer "B.Fab")
		)
		(fp_line
			(start 0.67945 -0.305054)
			(end 0.12065 -0.305054)
			(stroke
				(width 0.1)
				(type default)
			)
			(layer "B.Fab")
		)
		(pad "1" smd circle
			(at 0.40005 0 90)
			(size 0 0)
			(layers "B.Cu" "B.Mask" "B.Paste")
			(net "SVID_DIO0_CPU1_R")
		)
		(pad "2" smd circle
			(at -0.40005 0 90)
			(size 0 0)
			(layers "B.Cu" "B.Mask" "B.Paste")
			(net "PVNN_TERM_CPU1")
		)
	)
	(footprint ""
		(layer "B.Cu")
		(at 477.732344 -334.559656 180)
		(property "Reference" "DB16"
			(at 2.664968 -8.458708 270)
			(unlocked yes)
			(layer "B.SilkS")
			(effects
				(font
					(size 0.7874 0.5842)
					(thickness 0.1524)
				)
				(justify left mirror)
			)
		)
		(property "Value" ""
			(at 0 0 0)
			(layer "B.Fab")
			(effects
				(font
					(size 1.27 1.27)
				)
				(justify mirror)
			)
		)
		(duplicate_pad_numbers_are_jumpers no)
		(fp_line
			(start 3.330702 -4.771136)
			(end -3.330702 -4.771136)
			(stroke
				(width 0.1524)
				(type default)
			)
			(layer "B.SilkS")
		)
		(fp_line
			(start 0 4.011168)
			(end 3.330702 -4.771136)
			(stroke
				(width 0.1524)
				(type default)
			)
			(layer "B.SilkS")
		)
		(fp_line
			(start -3.330702 -4.771136)
			(end 0 4.011168)
			(stroke
				(width 0.1524)
				(type default)
			)
			(layer "B.SilkS")
		)
		(fp_line
			(start 3.330702 -4.771136)
			(end -3.330702 -4.771136)
			(stroke
				(width 0.1)
				(type default)
			)
			(layer "B.Fab")
		)
		(fp_line
			(start 0 4.011168)
			(end 3.330702 -4.771136)
			(stroke
				(width 0.1)
				(type default)
			)
			(layer "B.Fab")
		)
		(fp_line
			(start -3.330702 -4.771136)
			(end 0 4.011168)
			(stroke
				(width 0.1)
				(type default)
			)
			(layer "B.Fab")
		)
		(pad "1" thru_hole circle
			(at 0 0)
			(size 2.159 2.159)
			(drill 1.7018)
			(layers "*.Cu" "*.Mask")
			(remove_unused_layers no)
			(net "T1_GND")
			(clearance 0.0254)
			(thermal_gap 0.0254)
		)
		(pad "2" thru_hole circle
			(at 1.27 -3.348736)
			(size 2.159 2.159)
			(drill 1.7018)
			(layers "*.Cu" "*.Mask")
			(remove_unused_layers no)
			(net "TDR_SE_50_OHM_IN6")
			(clearance 0.0254)
			(thermal_gap 0.0254)
		)
		(pad "3" thru_hole circle
			(at -1.27 -3.348736)
			(size 2.159 2.159)
			(drill 1.7018)
			(layers "*.Cu" "*.Mask")
			(remove_unused_layers no)
			(net "TDR_SE_50_OHM_IN6")
			(clearance 0.0254)
			(thermal_gap 0.0254)
		)
	)
	(footprint ""
		(layer "B.Cu")
		(at 127.8001 -18.534888 -90)
		(property "Reference" "R4287"
			(at 0 0 90)
			(layer "B.SilkS")
			(hide yes)
			(effects
				(font
					(size 1.27 1.27)
				)
				(justify mirror)
			)
		)
		(property "Value" ""
			(at 0 0 90)
			(layer "B.Fab")
			(effects
				(font
					(size 1.27 1.27)
				)
				(justify mirror)
			)
		)
		(duplicate_pad_numbers_are_jumpers no)
		(fp_line
			(start -0.7874 0.4064)
			(end 0.7874 0.4064)
			(stroke
				(width 0.1524)
				(type default)
			)
			(layer "B.SilkS")
		)
		(fp_line
			(start 0.7874 0.4064)
			(end 0.7874 -0.4064)
			(stroke
				(width 0.1524)
				(type default)
			)
			(layer "B.SilkS")
		)
		(fp_line
			(start -0.7874 -0.4064)
			(end -0.7874 0.4064)
			(stroke
				(width 0.1524)
				(type default)
			)
			(layer "B.SilkS")
		)
		(fp_line
			(start 0.7874 -0.4064)
			(end -0.7874 -0.4064)
			(stroke
				(width 0.1524)
				(type default)
			)
			(layer "B.SilkS")
		)
		(fp_line
			(start -0.67945 0.3048)
			(end -0.120396 0.3048)
			(stroke
				(width 0.1)
				(type default)
			)
			(layer "B.Fab")
		)
		(fp_line
			(start -0.120396 0.3048)
			(end -0.120396 0.2794)
			(stroke
				(width 0.1)
				(type default)
			)
			(layer "B.Fab")
		)
		(fp_line
			(start 0.12065 0.3048)
			(end 0.67945 0.3048)
			(stroke
				(width 0.1)
				(type default)
			)
			(layer "B.Fab")
		)
		(fp_line
			(start 0.67945 0.3048)
			(end 0.67945 -0.305054)
			(stroke
				(width 0.1)
				(type default)
			)
			(layer "B.Fab")
		)
		(fp_line
			(start -0.120396 0.2794)
			(end 0.12065 0.2794)
			(stroke
				(width 0.1)
				(type default)
			)
			(layer "B.Fab")
		)
		(fp_line
			(start 0.12065 0.2794)
			(end 0.12065 0.3048)
			(stroke
				(width 0.1)
				(type default)
			)
			(layer "B.Fab")
		)
		(fp_line
			(start -0.12065 -0.2794)
			(end -0.12065 -0.3048)
			(stroke
				(width 0.1)
				(type default)
			)
			(layer "B.Fab")
		)
		(fp_line
			(start 0.12065 -0.2794)
			(end -0.12065 -0.2794)
			(stroke
				(width 0.1)
				(type default)
			)
			(layer "B.Fab")
		)
		(fp_line
			(start -0.67945 -0.3048)
			(end -0.67945 0.3048)
			(stroke
				(width 0.1)
				(type default)
			)
			(layer "B.Fab")
		)
		(fp_line
			(start -0.12065 -0.3048)
			(end -0.67945 -0.3048)
			(stroke
				(width 0.1)
				(type default)
			)
			(layer "B.Fab")
		)
		(fp_line
			(start 0.12065 -0.305054)
			(end 0.12065 -0.2794)
			(stroke
				(width 0.1)
				(type default)
			)
			(layer "B.Fab")
		)
		(fp_line
			(start 0.67945 -0.305054)
			(end 0.12065 -0.305054)
			(stroke
				(width 0.1)
				(type default)
			)
			(layer "B.Fab")
		)
		(pad "1" smd circle
			(at 0.40005 0 90)
			(size 0 0)
			(layers "B.Cu" "B.Mask" "B.Paste")
			(net "P3V3_AUX")
		)
		(pad "2" smd circle
			(at -0.40005 0 90)
			(size 0 0)
			(layers "B.Cu" "B.Mask" "B.Paste")
			(net "FM_USB3_1_SWA")
		)
	)
	(footprint ""
		(layer "B.Cu")
		(at 295.699688 -367.164366 -90)
		(property "Reference" "PR1323"
			(at 0 0 90)
			(layer "B.SilkS")
			(hide yes)
			(effects
				(font
					(size 1.27 1.27)
				)
				(justify mirror)
			)
		)
		(property "Value" ""
			(at 0 0 90)
			(layer "B.Fab")
			(effects
				(font
					(size 1.27 1.27)
				)
				(justify mirror)
			)
		)
		(duplicate_pad_numbers_are_jumpers no)
		(fp_line
			(start -0.7874 0.4064)
			(end 0.7874 0.4064)
			(stroke
				(width 0.1524)
				(type default)
			)
			(layer "B.SilkS")
		)
		(fp_line
			(start 0.7874 0.4064)
			(end 0.7874 -0.4064)
			(stroke
				(width 0.1524)
				(type default)
			)
			(layer "B.SilkS")
		)
		(fp_line
			(start -0.7874 -0.4064)
			(end -0.7874 0.4064)
			(stroke
				(width 0.1524)
				(type default)
			)
			(layer "B.SilkS")
		)
		(fp_line
			(start 0.7874 -0.4064)
			(end -0.7874 -0.4064)
			(stroke
				(width 0.1524)
				(type default)
			)
			(layer "B.SilkS")
		)
		(fp_line
			(start -0.67945 0.3048)
			(end -0.120396 0.3048)
			(stroke
				(width 0.1)
				(type default)
			)
			(layer "B.Fab")
		)
		(fp_line
			(start -0.120396 0.3048)
			(end -0.120396 0.2794)
			(stroke
				(width 0.1)
				(type default)
			)
			(layer "B.Fab")
		)
		(fp_line
			(start 0.12065 0.3048)
			(end 0.67945 0.3048)
			(stroke
				(width 0.1)
				(type default)
			)
			(layer "B.Fab")
		)
		(fp_line
			(start 0.67945 0.3048)
			(end 0.67945 -0.305054)
			(stroke
				(width 0.1)
				(type default)
			)
			(layer "B.Fab")
		)
		(fp_line
			(start -0.120396 0.2794)
			(end 0.12065 0.2794)
			(stroke
				(width 0.1)
				(type default)
			)
			(layer "B.Fab")
		)
		(fp_line
			(start 0.12065 0.2794)
			(end 0.12065 0.3048)
			(stroke
				(width 0.1)
				(type default)
			)
			(layer "B.Fab")
		)
		(fp_line
			(start -0.12065 -0.2794)
			(end -0.12065 -0.3048)
			(stroke
				(width 0.1)
				(type default)
			)
			(layer "B.Fab")
		)
		(fp_line
			(start 0.12065 -0.2794)
			(end -0.12065 -0.2794)
			(stroke
				(width 0.1)
				(type default)
			)
			(layer "B.Fab")
		)
		(fp_line
			(start -0.67945 -0.3048)
			(end -0.67945 0.3048)
			(stroke
				(width 0.1)
				(type default)
			)
			(layer "B.Fab")
		)
		(fp_line
			(start -0.12065 -0.3048)
			(end -0.67945 -0.3048)
			(stroke
				(width 0.1)
				(type default)
			)
			(layer "B.Fab")
		)
		(fp_line
			(start 0.12065 -0.305054)
			(end 0.12065 -0.2794)
			(stroke
				(width 0.1)
				(type default)
			)
			(layer "B.Fab")
		)
		(fp_line
			(start 0.67945 -0.305054)
			(end 0.12065 -0.305054)
			(stroke
				(width 0.1)
				(type default)
			)
			(layer "B.Fab")
		)
		(pad "1" smd circle
			(at 0.40005 0 90)
			(size 0 0)
			(layers "B.Cu" "B.Mask" "B.Paste")
			(net "PVCCFA_EHV_FIVRA_CPU0_VOS2")
		)
		(pad "2" smd circle
			(at -0.40005 0 90)
			(size 0 0)
			(layers "B.Cu" "B.Mask" "B.Paste")
			(net "PVCCFA_EHV_FIVRA_CPU0")
		)
	)
	(footprint ""
		(layer "B.Cu")
		(at 133.5786 -28.6258 -90)
		(property "Reference" "R4636"
			(at 0 0 90)
			(layer "B.SilkS")
			(hide yes)
			(effects
				(font
					(size 1.27 1.27)
				)
				(justify mirror)
			)
		)
		(property "Value" ""
			(at 0 0 90)
			(layer "B.Fab")
			(effects
				(font
					(size 1.27 1.27)
				)
				(justify mirror)
			)
		)
		(duplicate_pad_numbers_are_jumpers no)
		(fp_line
			(start -0.7874 0.4064)
			(end 0.7874 0.4064)
			(stroke
				(width 0.1524)
				(type default)
			)
			(layer "B.SilkS")
		)
		(fp_line
			(start 0.7874 0.4064)
			(end 0.7874 -0.4064)
			(stroke
				(width 0.1524)
				(type default)
			)
			(layer "B.SilkS")
		)
		(fp_line
			(start -0.7874 -0.4064)
			(end -0.7874 0.4064)
			(stroke
				(width 0.1524)
				(type default)
			)
			(layer "B.SilkS")
		)
		(fp_line
			(start 0.7874 -0.4064)
			(end -0.7874 -0.4064)
			(stroke
				(width 0.1524)
				(type default)
			)
			(layer "B.SilkS")
		)
		(fp_line
			(start -0.67945 0.3048)
			(end -0.120396 0.3048)
			(stroke
				(width 0.1)
				(type default)
			)
			(layer "B.Fab")
		)
		(fp_line
			(start -0.120396 0.3048)
			(end -0.120396 0.2794)
			(stroke
				(width 0.1)
				(type default)
			)
			(layer "B.Fab")
		)
		(fp_line
			(start 0.12065 0.3048)
			(end 0.67945 0.3048)
			(stroke
				(width 0.1)
				(type default)
			)
			(layer "B.Fab")
		)
		(fp_line
			(start 0.67945 0.3048)
			(end 0.67945 -0.305054)
			(stroke
				(width 0.1)
				(type default)
			)
			(layer "B.Fab")
		)
		(fp_line
			(start -0.120396 0.2794)
			(end 0.12065 0.2794)
			(stroke
				(width 0.1)
				(type default)
			)
			(layer "B.Fab")
		)
		(fp_line
			(start 0.12065 0.2794)
			(end 0.12065 0.3048)
			(stroke
				(width 0.1)
				(type default)
			)
			(layer "B.Fab")
		)
		(fp_line
			(start -0.12065 -0.2794)
			(end -0.12065 -0.3048)
			(stroke
				(width 0.1)
				(type default)
			)
			(layer "B.Fab")
		)
		(fp_line
			(start 0.12065 -0.2794)
			(end -0.12065 -0.2794)
			(stroke
				(width 0.1)
				(type default)
			)
			(layer "B.Fab")
		)
		(fp_line
			(start -0.67945 -0.3048)
			(end -0.67945 0.3048)
			(stroke
				(width 0.1)
				(type default)
			)
			(layer "B.Fab")
		)
		(fp_line
			(start -0.12065 -0.3048)
			(end -0.67945 -0.3048)
			(stroke
				(width 0.1)
				(type default)
			)
			(layer "B.Fab")
		)
		(fp_line
			(start 0.12065 -0.305054)
			(end 0.12065 -0.2794)
			(stroke
				(width 0.1)
				(type default)
			)
			(layer "B.Fab")
		)
		(fp_line
			(start 0.67945 -0.305054)
			(end 0.12065 -0.305054)
			(stroke
				(width 0.1)
				(type default)
			)
			(layer "B.Fab")
		)
		(pad "1" smd circle
			(at 0.40005 0 90)
			(size 0 0)
			(layers "B.Cu" "B.Mask" "B.Paste")
			(net "USB3_PCH_RX_DP<4>")
		)
		(pad "2" smd circle
			(at -0.40005 0 90)
			(size 0 0)
			(layers "B.Cu" "B.Mask" "B.Paste")
			(net "GND")
		)
	)
	(footprint ""
		(layer "B.Cu")
		(at 317.902844 -31.523178 180)
		(property "Reference" "R1197"
			(at 0 0 0)
			(layer "B.SilkS")
			(hide yes)
			(effects
				(font
					(size 1.27 1.27)
				)
				(justify mirror)
			)
		)
		(property "Value" ""
			(at 0 0 0)
			(layer "B.Fab")
			(effects
				(font
					(size 1.27 1.27)
				)
				(justify mirror)
			)
		)
		(duplicate_pad_numbers_are_jumpers no)
		(fp_line
			(start 0.7874 0.4064)
			(end 0.7874 -0.4064)
			(stroke
				(width 0.1524)
				(type default)
			)
			(layer "B.SilkS")
		)
		(fp_line
			(start 0.7874 -0.4064)
			(end -0.7874 -0.4064)
			(stroke
				(width 0.1524)
				(type default)
			)
			(layer "B.SilkS")
		)
		(fp_line
			(start -0.7874 0.4064)
			(end 0.7874 0.4064)
			(stroke
				(width 0.1524)
				(type default)
			)
			(layer "B.SilkS")
		)
		(fp_line
			(start -0.7874 -0.4064)
			(end -0.7874 0.4064)
			(stroke
				(width 0.1524)
				(type default)
			)
			(layer "B.SilkS")
		)
		(fp_line
			(start 0.67945 0.3048)
			(end 0.67945 -0.305054)
			(stroke
				(width 0.1)
				(type default)
			)
			(layer "B.Fab")
		)
		(fp_line
			(start 0.67945 -0.305054)
			(end 0.12065 -0.305054)
			(stroke
				(width 0.1)
				(type default)
			)
			(layer "B.Fab")
		)
		(fp_line
			(start 0.12065 0.3048)
			(end 0.67945 0.3048)
			(stroke
				(width 0.1)
				(type default)
			)
			(layer "B.Fab")
		)
		(fp_line
			(start 0.12065 0.2794)
			(end 0.12065 0.3048)
			(stroke
				(width 0.1)
				(type default)
			)
			(layer "B.Fab")
		)
		(fp_line
			(start 0.12065 -0.2794)
			(end -0.12065 -0.2794)
			(stroke
				(width 0.1)
				(type default)
			)
			(layer "B.Fab")
		)
		(fp_line
			(start 0.12065 -0.305054)
			(end 0.12065 -0.2794)
			(stroke
				(width 0.1)
				(type default)
			)
			(layer "B.Fab")
		)
		(fp_line
			(start -0.120396 0.3048)
			(end -0.120396 0.2794)
			(stroke
				(width 0.1)
				(type default)
			)
			(layer "B.Fab")
		)
		(fp_line
			(start -0.120396 0.2794)
			(end 0.12065 0.2794)
			(stroke
				(width 0.1)
				(type default)
			)
			(layer "B.Fab")
		)
		(fp_line
			(start -0.12065 -0.2794)
			(end -0.12065 -0.3048)
			(stroke
				(width 0.1)
				(type default)
			)
			(layer "B.Fab")
		)
		(fp_line
			(start -0.12065 -0.3048)
			(end -0.67945 -0.3048)
			(stroke
				(width 0.1)
				(type default)
			)
			(layer "B.Fab")
		)
		(fp_line
			(start -0.67945 0.3048)
			(end -0.120396 0.3048)
			(stroke
				(width 0.1)
				(type default)
			)
			(layer "B.Fab")
		)
		(fp_line
			(start -0.67945 -0.3048)
			(end -0.67945 0.3048)
			(stroke
				(width 0.1)
				(type default)
			)
			(layer "B.Fab")
		)
		(pad "1" smd circle
			(at 0.40005 0)
			(size 0 0)
			(layers "B.Cu" "B.Mask" "B.Paste")
			(net "GND")
		)
		(pad "2" smd circle
			(at -0.40005 0)
			(size 0 0)
			(layers "B.Cu" "B.Mask" "B.Paste")
			(net "PD_SUSCLK")
		)
	)
	(footprint ""
		(layer "B.Cu")
		(at 455.66838 -382.435608)
		(property "Reference" "PR3337"
			(at 0 0 0)
			(layer "B.SilkS")
			(hide yes)
			(effects
				(font
					(size 1.27 1.27)
				)
				(justify mirror)
			)
		)
		(property "Value" ""
			(at 0 0 0)
			(layer "B.Fab")
			(effects
				(font
					(size 1.27 1.27)
				)
				(justify mirror)
			)
		)
		(duplicate_pad_numbers_are_jumpers no)
		(fp_line
			(start -0.7874 -0.4064)
			(end -0.7874 0.4064)
			(stroke
				(width 0.1524)
				(type default)
			)
			(layer "B.SilkS")
		)
		(fp_line
			(start -0.7874 0.4064)
			(end 0.7874 0.4064)
			(stroke
				(width 0.1524)
				(type default)
			)
			(layer "B.SilkS")
		)
		(fp_line
			(start 0.7874 -0.4064)
			(end -0.7874 -0.4064)
			(stroke
				(width 0.1524)
				(type default)
			)
			(layer "B.SilkS")
		)
		(fp_line
			(start 0.7874 0.4064)
			(end 0.7874 -0.4064)
			(stroke
				(width 0.1524)
				(type default)
			)
			(layer "B.SilkS")
		)
		(fp_line
			(start -0.67945 -0.3048)
			(end -0.67945 0.3048)
			(stroke
				(width 0.1)
				(type default)
			)
			(layer "B.Fab")
		)
		(fp_line
			(start -0.67945 0.3048)
			(end -0.120396 0.3048)
			(stroke
				(width 0.1)
				(type default)
			)
			(layer "B.Fab")
		)
		(fp_line
			(start -0.12065 -0.3048)
			(end -0.67945 -0.3048)
			(stroke
				(width 0.1)
				(type default)
			)
			(layer "B.Fab")
		)
		(fp_line
			(start -0.12065 -0.2794)
			(end -0.12065 -0.3048)
			(stroke
				(width 0.1)
				(type default)
			)
			(layer "B.Fab")
		)
		(fp_line
			(start -0.120396 0.2794)
			(end 0.12065 0.2794)
			(stroke
				(width 0.1)
				(type default)
			)
			(layer "B.Fab")
		)
		(fp_line
			(start -0.120396 0.3048)
			(end -0.120396 0.2794)
			(stroke
				(width 0.1)
				(type default)
			)
			(layer "B.Fab")
		)
		(fp_line
			(start 0.12065 -0.305054)
			(end 0.12065 -0.2794)
			(stroke
				(width 0.1)
				(type default)
			)
			(layer "B.Fab")
		)
		(fp_line
			(start 0.12065 -0.2794)
			(end -0.12065 -0.2794)
			(stroke
				(width 0.1)
				(type default)
			)
			(layer "B.Fab")
		)
		(fp_line
			(start 0.12065 0.2794)
			(end 0.12065 0.3048)
			(stroke
				(width 0.1)
				(type default)
			)
			(layer "B.Fab")
		)
		(fp_line
			(start 0.12065 0.3048)
			(end 0.67945 0.3048)
			(stroke
				(width 0.1)
				(type default)
			)
			(layer "B.Fab")
		)
		(fp_line
			(start 0.67945 -0.305054)
			(end 0.12065 -0.305054)
			(stroke
				(width 0.1)
				(type default)
			)
			(layer "B.Fab")
		)
		(fp_line
			(start 0.67945 0.3048)
			(end 0.67945 -0.305054)
			(stroke
				(width 0.1)
				(type default)
			)
			(layer "B.Fab")
		)
		(pad "1" smd circle
			(at 0.40005 0 180)
			(size 0 0)
			(layers "B.Cu" "B.Mask" "B.Paste")
			(net "P5V_AUX_MODE")
		)
		(pad "2" smd circle
			(at -0.40005 0 180)
			(size 0 0)
			(layers "B.Cu" "B.Mask" "B.Paste")
			(net "GND")
		)
	)
	(footprint ""
		(layer "B.Cu")
		(at 168.544494 -9.457944 -90)
		(property "Reference" "C2078"
			(at 0 0 90)
			(layer "B.SilkS")
			(hide yes)
			(effects
				(font
					(size 1.27 1.27)
				)
				(justify mirror)
			)
		)
		(property "Value" ""
			(at 0 0 90)
			(layer "B.Fab")
			(effects
				(font
					(size 1.27 1.27)
				)
				(justify mirror)
			)
		)
		(duplicate_pad_numbers_are_jumpers no)
		(fp_line
			(start -0.299974 0.150114)
			(end 0.299974 0.150114)
			(stroke
				(width 0.1)
				(type default)
			)
			(layer "B.Fab")
		)
		(fp_line
			(start 0.299974 0.150114)
			(end 0.299974 -0.150114)
			(stroke
				(width 0.1)
				(type default)
			)
			(layer "B.Fab")
		)
		(fp_line
			(start -0.299974 -0.150114)
			(end -0.299974 0.150114)
			(stroke
				(width 0.1)
				(type default)
			)
			(layer "B.Fab")
		)
		(fp_line
			(start 0.299974 -0.150114)
			(end -0.299974 -0.150114)
			(stroke
				(width 0.1)
				(type default)
			)
			(layer "B.Fab")
		)
		(pad "1" smd rect
			(at 0.2667 0 90)
			(size 0.3048 0.381)
			(layers "B.Cu" "B.Mask" "B.Paste")
			(net "P3E_PCH_BMC_TX_DN")
		)
		(pad "2" smd rect
			(at -0.2667 0 90)
			(size 0.3048 0.381)
			(layers "B.Cu" "B.Mask" "B.Paste")
			(net "P3E_PCH_BMC_TX_C_DN")
		)
		(zone
			(layer "In16.Cu")
			(hatch none 0.5)
			(connect_pads
				(clearance 0)
			)
			(min_thickness 0.25)
			(keepout
				(tracks not_allowed)
				(vias allowed)
				(pads allowed)
				(copperpour not_allowed)
				(footprints allowed)
			)
			(placement
				(enabled no)
				(sheetname "")
			)
			(fill
				(thermal_gap 0.5)
				(thermal_bridge_width 0.5)
				(island_removal_mode 0)
			)
			(polygon
				(pts
					(xy 168.303194 -9.521444) (xy 168.785794 -9.521444) (xy 168.785794 -9.927844) (xy 168.303194 -9.927844)
				)
			)
		)
		(zone
			(layer "In16.Cu")
			(hatch none 0.5)
			(connect_pads
				(clearance 0)
			)
			(min_thickness 0.25)
			(keepout
				(tracks not_allowed)
				(vias allowed)
				(pads allowed)
				(copperpour not_allowed)
				(footprints allowed)
			)
			(placement
				(enabled no)
				(sheetname "")
			)
			(fill
				(thermal_gap 0.5)
				(thermal_bridge_width 0.5)
				(island_removal_mode 0)
			)
			(polygon
				(pts
					(xy 168.303194 -8.988044) (xy 168.785794 -8.988044) (xy 168.785794 -9.394444) (xy 168.303194 -9.394444)
				)
			)
		)
	)
	(footprint ""
		(layer "B.Cu")
		(at 37.947346 -318.252856)
		(property "Reference" "R945"
			(at 0 0 0)
			(layer "B.SilkS")
			(hide yes)
			(effects
				(font
					(size 1.27 1.27)
				)
				(justify mirror)
			)
		)
		(property "Value" ""
			(at 0 0 0)
			(layer "B.Fab")
			(effects
				(font
					(size 1.27 1.27)
				)
				(justify mirror)
			)
		)
		(duplicate_pad_numbers_are_jumpers no)
		(fp_line
			(start -0.7874 -0.4064)
			(end -0.7874 0.4064)
			(stroke
				(width 0.1524)
				(type default)
			)
			(layer "B.SilkS")
		)
		(fp_line
			(start -0.7874 0.4064)
			(end 0.7874 0.4064)
			(stroke
				(width 0.1524)
				(type default)
			)
			(layer "B.SilkS")
		)
		(fp_line
			(start 0.7874 -0.4064)
			(end -0.7874 -0.4064)
			(stroke
				(width 0.1524)
				(type default)
			)
			(layer "B.SilkS")
		)
		(fp_line
			(start 0.7874 0.4064)
			(end 0.7874 -0.4064)
			(stroke
				(width 0.1524)
				(type default)
			)
			(layer "B.SilkS")
		)
		(fp_line
			(start -0.67945 -0.3048)
			(end -0.67945 0.3048)
			(stroke
				(width 0.1)
				(type default)
			)
			(layer "B.Fab")
		)
		(fp_line
			(start -0.67945 0.3048)
			(end -0.120396 0.3048)
			(stroke
				(width 0.1)
				(type default)
			)
			(layer "B.Fab")
		)
		(fp_line
			(start -0.12065 -0.3048)
			(end -0.67945 -0.3048)
			(stroke
				(width 0.1)
				(type default)
			)
			(layer "B.Fab")
		)
		(fp_line
			(start -0.12065 -0.2794)
			(end -0.12065 -0.3048)
			(stroke
				(width 0.1)
				(type default)
			)
			(layer "B.Fab")
		)
		(fp_line
			(start -0.120396 0.2794)
			(end 0.12065 0.2794)
			(stroke
				(width 0.1)
				(type default)
			)
			(layer "B.Fab")
		)
		(fp_line
			(start -0.120396 0.3048)
			(end -0.120396 0.2794)
			(stroke
				(width 0.1)
				(type default)
			)
			(layer "B.Fab")
		)
		(fp_line
			(start 0.12065 -0.305054)
			(end 0.12065 -0.2794)
			(stroke
				(width 0.1)
				(type default)
			)
			(layer "B.Fab")
		)
		(fp_line
			(start 0.12065 -0.2794)
			(end -0.12065 -0.2794)
			(stroke
				(width 0.1)
				(type default)
			)
			(layer "B.Fab")
		)
		(fp_line
			(start 0.12065 0.2794)
			(end 0.12065 0.3048)
			(stroke
				(width 0.1)
				(type default)
			)
			(layer "B.Fab")
		)
		(fp_line
			(start 0.12065 0.3048)
			(end 0.67945 0.3048)
			(stroke
				(width 0.1)
				(type default)
			)
			(layer "B.Fab")
		)
		(fp_line
			(start 0.67945 -0.305054)
			(end 0.12065 -0.305054)
			(stroke
				(width 0.1)
				(type default)
			)
			(layer "B.Fab")
		)
		(fp_line
			(start 0.67945 0.3048)
			(end 0.67945 -0.305054)
			(stroke
				(width 0.1)
				(type default)
			)
			(layer "B.Fab")
		)
		(pad "1" smd circle
			(at 0.40005 0 180)
			(size 0 0)
			(layers "B.Cu" "B.Mask" "B.Paste")
			(net "P3V3_AUX")
		)
		(pad "2" smd circle
			(at -0.40005 0 180)
			(size 0 0)
			(layers "B.Cu" "B.Mask" "B.Paste")
			(net "PWRGD_FAIL_CPU1_CD_R1")
		)
	)
	(footprint ""
		(layer "B.Cu")
		(at 433.25288 -124.932948 90)
		(property "Reference" "PR4233"
			(at 0 0 90)
			(layer "B.SilkS")
			(hide yes)
			(effects
				(font
					(size 1.27 1.27)
				)
				(justify mirror)
			)
		)
		(property "Value" ""
			(at 0 0 90)
			(layer "B.Fab")
			(effects
				(font
					(size 1.27 1.27)
				)
				(justify mirror)
			)
		)
		(duplicate_pad_numbers_are_jumpers no)
		(fp_line
			(start 0.7874 -0.4064)
			(end -0.7874 -0.4064)
			(stroke
				(width 0.1524)
				(type default)
			)
			(layer "B.SilkS")
		)
		(fp_line
			(start -0.7874 -0.4064)
			(end -0.7874 0.4064)
			(stroke
				(width 0.1524)
				(type default)
			)
			(layer "B.SilkS")
		)
		(fp_line
			(start 0.7874 0.4064)
			(end 0.7874 -0.4064)
			(stroke
				(width 0.1524)
				(type default)
			)
			(layer "B.SilkS")
		)
		(fp_line
			(start -0.7874 0.4064)
			(end 0.7874 0.4064)
			(stroke
				(width 0.1524)
				(type default)
			)
			(layer "B.SilkS")
		)
		(fp_line
			(start 0.67945 -0.305054)
			(end 0.12065 -0.305054)
			(stroke
				(width 0.1)
				(type default)
			)
			(layer "B.Fab")
		)
		(fp_line
			(start 0.12065 -0.305054)
			(end 0.12065 -0.2794)
			(stroke
				(width 0.1)
				(type default)
			)
			(layer "B.Fab")
		)
		(fp_line
			(start -0.12065 -0.3048)
			(end -0.67945 -0.3048)
			(stroke
				(width 0.1)
				(type default)
			)
			(layer "B.Fab")
		)
		(fp_line
			(start -0.67945 -0.3048)
			(end -0.67945 0.3048)
			(stroke
				(width 0.1)
				(type default)
			)
			(layer "B.Fab")
		)
		(fp_line
			(start 0.12065 -0.2794)
			(end -0.12065 -0.2794)
			(stroke
				(width 0.1)
				(type default)
			)
			(layer "B.Fab")
		)
		(fp_line
			(start -0.12065 -0.2794)
			(end -0.12065 -0.3048)
			(stroke
				(width 0.1)
				(type default)
			)
			(layer "B.Fab")
		)
		(fp_line
			(start 0.12065 0.2794)
			(end 0.12065 0.3048)
			(stroke
				(width 0.1)
				(type default)
			)
			(layer "B.Fab")
		)
		(fp_line
			(start -0.120396 0.2794)
			(end 0.12065 0.2794)
			(stroke
				(width 0.1)
				(type default)
			)
			(layer "B.Fab")
		)
		(fp_line
			(start 0.67945 0.3048)
			(end 0.67945 -0.305054)
			(stroke
				(width 0.1)
				(type default)
			)
			(layer "B.Fab")
		)
		(fp_line
			(start 0.12065 0.3048)
			(end 0.67945 0.3048)
			(stroke
				(width 0.1)
				(type default)
			)
			(layer "B.Fab")
		)
		(fp_line
			(start -0.120396 0.3048)
			(end -0.120396 0.2794)
			(stroke
				(width 0.1)
				(type default)
			)
			(layer "B.Fab")
		)
		(fp_line
			(start -0.67945 0.3048)
			(end -0.120396 0.3048)
			(stroke
				(width 0.1)
				(type default)
			)
			(layer "B.Fab")
		)
		(pad "1" smd circle
			(at 0.40005 0 270)
			(size 0 0)
			(layers "B.Cu" "B.Mask" "B.Paste")
			(net "NC_PVCCD_HV_CPU0_ACSP5")
		)
		(pad "2" smd circle
			(at -0.40005 0 270)
			(size 0 0)
			(layers "B.Cu" "B.Mask" "B.Paste")
			(net "GND")
		)
	)
	(footprint ""
		(layer "B.Cu")
		(at 174.163228 -8.904478 180)
		(property "Reference" "R3112"
			(at 0 0 0)
			(layer "B.SilkS")
			(hide yes)
			(effects
				(font
					(size 1.27 1.27)
				)
				(justify mirror)
			)
		)
		(property "Value" ""
			(at 0 0 0)
			(layer "B.Fab")
			(effects
				(font
					(size 1.27 1.27)
				)
				(justify mirror)
			)
		)
		(duplicate_pad_numbers_are_jumpers no)
		(fp_line
			(start 0.7874 0.4064)
			(end 0.7874 -0.4064)
			(stroke
				(width 0.1524)
				(type default)
			)
			(layer "B.SilkS")
		)
		(fp_line
			(start 0.7874 -0.4064)
			(end -0.7874 -0.4064)
			(stroke
				(width 0.1524)
				(type default)
			)
			(layer "B.SilkS")
		)
		(fp_line
			(start -0.7874 0.4064)
			(end 0.7874 0.4064)
			(stroke
				(width 0.1524)
				(type default)
			)
			(layer "B.SilkS")
		)
		(fp_line
			(start -0.7874 -0.4064)
			(end -0.7874 0.4064)
			(stroke
				(width 0.1524)
				(type default)
			)
			(layer "B.SilkS")
		)
		(fp_line
			(start 0.67945 0.3048)
			(end 0.67945 -0.305054)
			(stroke
				(width 0.1)
				(type default)
			)
			(layer "B.Fab")
		)
		(fp_line
			(start 0.67945 -0.305054)
			(end 0.12065 -0.305054)
			(stroke
				(width 0.1)
				(type default)
			)
			(layer "B.Fab")
		)
		(fp_line
			(start 0.12065 0.3048)
			(end 0.67945 0.3048)
			(stroke
				(width 0.1)
				(type default)
			)
			(layer "B.Fab")
		)
		(fp_line
			(start 0.12065 0.2794)
			(end 0.12065 0.3048)
			(stroke
				(width 0.1)
				(type default)
			)
			(layer "B.Fab")
		)
		(fp_line
			(start 0.12065 -0.2794)
			(end -0.12065 -0.2794)
			(stroke
				(width 0.1)
				(type default)
			)
			(layer "B.Fab")
		)
		(fp_line
			(start 0.12065 -0.305054)
			(end 0.12065 -0.2794)
			(stroke
				(width 0.1)
				(type default)
			)
			(layer "B.Fab")
		)
		(fp_line
			(start -0.120396 0.3048)
			(end -0.120396 0.2794)
			(stroke
				(width 0.1)
				(type default)
			)
			(layer "B.Fab")
		)
		(fp_line
			(start -0.120396 0.2794)
			(end 0.12065 0.2794)
			(stroke
				(width 0.1)
				(type default)
			)
			(layer "B.Fab")
		)
		(fp_line
			(start -0.12065 -0.2794)
			(end -0.12065 -0.3048)
			(stroke
				(width 0.1)
				(type default)
			)
			(layer "B.Fab")
		)
		(fp_line
			(start -0.12065 -0.3048)
			(end -0.67945 -0.3048)
			(stroke
				(width 0.1)
				(type default)
			)
			(layer "B.Fab")
		)
		(fp_line
			(start -0.67945 0.3048)
			(end -0.120396 0.3048)
			(stroke
				(width 0.1)
				(type default)
			)
			(layer "B.Fab")
		)
		(fp_line
			(start -0.67945 -0.3048)
			(end -0.67945 0.3048)
			(stroke
				(width 0.1)
				(type default)
			)
			(layer "B.Fab")
		)
		(pad "1" smd circle
			(at 0.40005 0)
			(size 0 0)
			(layers "B.Cu" "B.Mask" "B.Paste")
			(net "I3C_BMC_SWB_SCL")
		)
		(pad "2" smd circle
			(at -0.40005 0)
			(size 0 0)
			(layers "B.Cu" "B.Mask" "B.Paste")
			(net "I3C_BMC_SWB_R_SCL")
		)
	)
	(footprint ""
		(layer "B.Cu")
		(at 91.161108 -190.705232 -90)
		(property "Reference" "R742"
			(at 0 0 90)
			(layer "B.SilkS")
			(hide yes)
			(effects
				(font
					(size 1.27 1.27)
				)
				(justify mirror)
			)
		)
		(property "Value" ""
			(at 0 0 90)
			(layer "B.Fab")
			(effects
				(font
					(size 1.27 1.27)
				)
				(justify mirror)
			)
		)
		(duplicate_pad_numbers_are_jumpers no)
		(fp_line
			(start -0.7874 0.4064)
			(end 0.7874 0.4064)
			(stroke
				(width 0.1524)
				(type default)
			)
			(layer "B.SilkS")
		)
		(fp_line
			(start 0.7874 0.4064)
			(end 0.7874 -0.4064)
			(stroke
				(width 0.1524)
				(type default)
			)
			(layer "B.SilkS")
		)
		(fp_line
			(start -0.7874 -0.4064)
			(end -0.7874 0.4064)
			(stroke
				(width 0.1524)
				(type default)
			)
			(layer "B.SilkS")
		)
		(fp_line
			(start 0.7874 -0.4064)
			(end -0.7874 -0.4064)
			(stroke
				(width 0.1524)
				(type default)
			)
			(layer "B.SilkS")
		)
		(fp_line
			(start -0.67945 0.3048)
			(end -0.120396 0.3048)
			(stroke
				(width 0.1)
				(type default)
			)
			(layer "B.Fab")
		)
		(fp_line
			(start -0.120396 0.3048)
			(end -0.120396 0.2794)
			(stroke
				(width 0.1)
				(type default)
			)
			(layer "B.Fab")
		)
		(fp_line
			(start 0.12065 0.3048)
			(end 0.67945 0.3048)
			(stroke
				(width 0.1)
				(type default)
			)
			(layer "B.Fab")
		)
		(fp_line
			(start 0.67945 0.3048)
			(end 0.67945 -0.305054)
			(stroke
				(width 0.1)
				(type default)
			)
			(layer "B.Fab")
		)
		(fp_line
			(start -0.120396 0.2794)
			(end 0.12065 0.2794)
			(stroke
				(width 0.1)
				(type default)
			)
			(layer "B.Fab")
		)
		(fp_line
			(start 0.12065 0.2794)
			(end 0.12065 0.3048)
			(stroke
				(width 0.1)
				(type default)
			)
			(layer "B.Fab")
		)
		(fp_line
			(start -0.12065 -0.2794)
			(end -0.12065 -0.3048)
			(stroke
				(width 0.1)
				(type default)
			)
			(layer "B.Fab")
		)
		(fp_line
			(start 0.12065 -0.2794)
			(end -0.12065 -0.2794)
			(stroke
				(width 0.1)
				(type default)
			)
			(layer "B.Fab")
		)
		(fp_line
			(start -0.67945 -0.3048)
			(end -0.67945 0.3048)
			(stroke
				(width 0.1)
				(type default)
			)
			(layer "B.Fab")
		)
		(fp_line
			(start -0.12065 -0.3048)
			(end -0.67945 -0.3048)
			(stroke
				(width 0.1)
				(type default)
			)
			(layer "B.Fab")
		)
		(fp_line
			(start 0.12065 -0.305054)
			(end 0.12065 -0.2794)
			(stroke
				(width 0.1)
				(type default)
			)
			(layer "B.Fab")
		)
		(fp_line
			(start 0.67945 -0.305054)
			(end 0.12065 -0.305054)
			(stroke
				(width 0.1)
				(type default)
			)
			(layer "B.Fab")
		)
		(pad "1" smd circle
			(at 0.40005 0 90)
			(size 0 0)
			(layers "B.Cu" "B.Mask" "B.Paste")
			(net "PVNN_TERM_CPU1")
		)
		(pad "2" smd circle
			(at -0.40005 0 90)
			(size 0 0)
			(layers "B.Cu" "B.Mask" "B.Paste")
			(net "JTAG_CPU1_MUX_GTL_TDO")
		)
	)
	(footprint ""
		(layer "B.Cu")
		(at 436.971694 -120.841008)
		(property "Reference" "R362"
			(at 0 0 0)
			(layer "B.SilkS")
			(hide yes)
			(effects
				(font
					(size 1.27 1.27)
				)
				(justify mirror)
			)
		)
		(property "Value" ""
			(at 0 0 0)
			(layer "B.Fab")
			(effects
				(font
					(size 1.27 1.27)
				)
				(justify mirror)
			)
		)
		(duplicate_pad_numbers_are_jumpers no)
		(fp_line
			(start -0.7874 -0.4064)
			(end -0.7874 0.4064)
			(stroke
				(width 0.1524)
				(type default)
			)
			(layer "B.SilkS")
		)
		(fp_line
			(start -0.7874 0.4064)
			(end 0.7874 0.4064)
			(stroke
				(width 0.1524)
				(type default)
			)
			(layer "B.SilkS")
		)
		(fp_line
			(start 0.7874 -0.4064)
			(end -0.7874 -0.4064)
			(stroke
				(width 0.1524)
				(type default)
			)
			(layer "B.SilkS")
		)
		(fp_line
			(start 0.7874 0.4064)
			(end 0.7874 -0.4064)
			(stroke
				(width 0.1524)
				(type default)
			)
			(layer "B.SilkS")
		)
		(fp_line
			(start -0.67945 -0.3048)
			(end -0.67945 0.3048)
			(stroke
				(width 0.1)
				(type default)
			)
			(layer "B.Fab")
		)
		(fp_line
			(start -0.67945 0.3048)
			(end -0.120396 0.3048)
			(stroke
				(width 0.1)
				(type default)
			)
			(layer "B.Fab")
		)
		(fp_line
			(start -0.12065 -0.3048)
			(end -0.67945 -0.3048)
			(stroke
				(width 0.1)
				(type default)
			)
			(layer "B.Fab")
		)
		(fp_line
			(start -0.12065 -0.2794)
			(end -0.12065 -0.3048)
			(stroke
				(width 0.1)
				(type default)
			)
			(layer "B.Fab")
		)
		(fp_line
			(start -0.120396 0.2794)
			(end 0.12065 0.2794)
			(stroke
				(width 0.1)
				(type default)
			)
			(layer "B.Fab")
		)
		(fp_line
			(start -0.120396 0.3048)
			(end -0.120396 0.2794)
			(stroke
				(width 0.1)
				(type default)
			)
			(layer "B.Fab")
		)
		(fp_line
			(start 0.12065 -0.305054)
			(end 0.12065 -0.2794)
			(stroke
				(width 0.1)
				(type default)
			)
			(layer "B.Fab")
		)
		(fp_line
			(start 0.12065 -0.2794)
			(end -0.12065 -0.2794)
			(stroke
				(width 0.1)
				(type default)
			)
			(layer "B.Fab")
		)
		(fp_line
			(start 0.12065 0.2794)
			(end 0.12065 0.3048)
			(stroke
				(width 0.1)
				(type default)
			)
			(layer "B.Fab")
		)
		(fp_line
			(start 0.12065 0.3048)
			(end 0.67945 0.3048)
			(stroke
				(width 0.1)
				(type default)
			)
			(layer "B.Fab")
		)
		(fp_line
			(start 0.67945 -0.305054)
			(end 0.12065 -0.305054)
			(stroke
				(width 0.1)
				(type default)
			)
			(layer "B.Fab")
		)
		(fp_line
			(start 0.67945 0.3048)
			(end 0.67945 -0.305054)
			(stroke
				(width 0.1)
				(type default)
			)
			(layer "B.Fab")
		)
		(pad "1" smd circle
			(at 0.40005 0 180)
			(size 0 0)
			(layers "B.Cu" "B.Mask" "B.Paste")
			(net "PWRGD_PVCCD_HV_CPU0")
		)
		(pad "2" smd circle
			(at -0.40005 0 180)
			(size 0 0)
			(layers "B.Cu" "B.Mask" "B.Paste")
			(net "PWRGD_PVCCD_HV_CPU0_R")
		)
	)
	(footprint ""
		(layer "B.Cu")
		(at 319.425066 -40.970454 -135)
		(property "Reference" "R696"
			(at 0 0 45)
			(layer "B.SilkS")
			(hide yes)
			(effects
				(font
					(size 1.27 1.27)
				)
				(justify mirror)
			)
		)
		(property "Value" ""
			(at 0 0 45)
			(layer "B.Fab")
			(effects
				(font
					(size 1.27 1.27)
				)
				(justify mirror)
			)
		)
		(duplicate_pad_numbers_are_jumpers no)
		(fp_line
			(start 0.787389 0.406267)
			(end 0.787389 -0.406267)
			(stroke
				(width 0.1524)
				(type default)
			)
			(layer "B.SilkS")
		)
		(fp_line
			(start 0.787389 -0.406267)
			(end -0.787389 -0.406267)
			(stroke
				(width 0.1524)
				(type default)
			)
			(layer "B.SilkS")
		)
		(fp_line
			(start -0.787389 0.406267)
			(end 0.787389 0.406267)
			(stroke
				(width 0.1524)
				(type default)
			)
			(layer "B.SilkS")
		)
		(fp_line
			(start -0.787389 -0.406267)
			(end -0.787389 0.406267)
			(stroke
				(width 0.1524)
				(type default)
			)
			(layer "B.SilkS")
		)
		(fp_line
			(start 0.679446 0.30479)
			(end 0.679446 -0.305149)
			(stroke
				(width 0.1)
				(type default)
			)
			(layer "B.Fab")
		)
		(fp_line
			(start 0.120515 0.30479)
			(end 0.679446 0.30479)
			(stroke
				(width 0.1)
				(type default)
			)
			(layer "B.Fab")
		)
		(fp_line
			(start 0.120695 0.279466)
			(end 0.120515 0.30479)
			(stroke
				(width 0.1)
				(type default)
			)
			(layer "B.Fab")
		)
		(fp_line
			(start 0.679446 -0.305149)
			(end 0.120695 -0.304969)
			(stroke
				(width 0.1)
				(type default)
			)
			(layer "B.Fab")
		)
		(fp_line
			(start -0.120515 0.30479)
			(end -0.120335 0.279466)
			(stroke
				(width 0.1)
				(type default)
			)
			(layer "B.Fab")
		)
		(fp_line
			(start -0.120335 0.279466)
			(end 0.120695 0.279466)
			(stroke
				(width 0.1)
				(type default)
			)
			(layer "B.Fab")
		)
		(fp_line
			(start 0.120695 -0.279466)
			(end -0.120695 -0.279466)
			(stroke
				(width 0.1)
				(type default)
			)
			(layer "B.Fab")
		)
		(fp_line
			(start 0.120695 -0.304969)
			(end 0.120695 -0.279466)
			(stroke
				(width 0.1)
				(type default)
			)
			(layer "B.Fab")
		)
		(fp_line
			(start -0.679446 0.30479)
			(end -0.120515 0.30479)
			(stroke
				(width 0.1)
				(type default)
			)
			(layer "B.Fab")
		)
		(fp_line
			(start -0.120695 -0.279466)
			(end -0.120515 -0.30479)
			(stroke
				(width 0.1)
				(type default)
			)
			(layer "B.Fab")
		)
		(fp_line
			(start -0.120515 -0.30479)
			(end -0.679446 -0.30479)
			(stroke
				(width 0.1)
				(type default)
			)
			(layer "B.Fab")
		)
		(fp_line
			(start -0.679446 -0.30479)
			(end -0.679446 0.30479)
			(stroke
				(width 0.1)
				(type default)
			)
			(layer "B.Fab")
		)
		(pad "1" smd circle
			(at 0.40005 0 45)
			(size 0 0)
			(layers "B.Cu" "B.Mask" "B.Paste")
			(net "P3V3_AUX")
		)
		(pad "2" smd circle
			(at -0.40005 0 45)
			(size 0 0)
			(layers "B.Cu" "B.Mask" "B.Paste")
			(net "RST_PCH_RSTBTN_R_N")
		)
	)
	(footprint ""
		(layer "B.Cu")
		(at 191.47409 -78.25613 -90)
		(property "Reference" "R3237"
			(at 0 0 90)
			(layer "B.SilkS")
			(hide yes)
			(effects
				(font
					(size 1.27 1.27)
				)
				(justify mirror)
			)
		)
		(property "Value" ""
			(at 0 0 90)
			(layer "B.Fab")
			(effects
				(font
					(size 1.27 1.27)
				)
				(justify mirror)
			)
		)
		(duplicate_pad_numbers_are_jumpers no)
		(fp_line
			(start -0.7874 0.4064)
			(end 0.7874 0.4064)
			(stroke
				(width 0.1524)
				(type default)
			)
			(layer "B.SilkS")
		)
		(fp_line
			(start 0.7874 0.4064)
			(end 0.7874 -0.4064)
			(stroke
				(width 0.1524)
				(type default)
			)
			(layer "B.SilkS")
		)
		(fp_line
			(start -0.7874 -0.4064)
			(end -0.7874 0.4064)
			(stroke
				(width 0.1524)
				(type default)
			)
			(layer "B.SilkS")
		)
		(fp_line
			(start 0.7874 -0.4064)
			(end -0.7874 -0.4064)
			(stroke
				(width 0.1524)
				(type default)
			)
			(layer "B.SilkS")
		)
		(fp_line
			(start -0.67945 0.3048)
			(end -0.120396 0.3048)
			(stroke
				(width 0.1)
				(type default)
			)
			(layer "B.Fab")
		)
		(fp_line
			(start -0.120396 0.3048)
			(end -0.120396 0.2794)
			(stroke
				(width 0.1)
				(type default)
			)
			(layer "B.Fab")
		)
		(fp_line
			(start 0.12065 0.3048)
			(end 0.67945 0.3048)
			(stroke
				(width 0.1)
				(type default)
			)
			(layer "B.Fab")
		)
		(fp_line
			(start 0.67945 0.3048)
			(end 0.67945 -0.305054)
			(stroke
				(width 0.1)
				(type default)
			)
			(layer "B.Fab")
		)
		(fp_line
			(start -0.120396 0.2794)
			(end 0.12065 0.2794)
			(stroke
				(width 0.1)
				(type default)
			)
			(layer "B.Fab")
		)
		(fp_line
			(start 0.12065 0.2794)
			(end 0.12065 0.3048)
			(stroke
				(width 0.1)
				(type default)
			)
			(layer "B.Fab")
		)
		(fp_line
			(start -0.12065 -0.2794)
			(end -0.12065 -0.3048)
			(stroke
				(width 0.1)
				(type default)
			)
			(layer "B.Fab")
		)
		(fp_line
			(start 0.12065 -0.2794)
			(end -0.12065 -0.2794)
			(stroke
				(width 0.1)
				(type default)
			)
			(layer "B.Fab")
		)
		(fp_line
			(start -0.67945 -0.3048)
			(end -0.67945 0.3048)
			(stroke
				(width 0.1)
				(type default)
			)
			(layer "B.Fab")
		)
		(fp_line
			(start -0.12065 -0.3048)
			(end -0.67945 -0.3048)
			(stroke
				(width 0.1)
				(type default)
			)
			(layer "B.Fab")
		)
		(fp_line
			(start 0.12065 -0.305054)
			(end 0.12065 -0.2794)
			(stroke
				(width 0.1)
				(type default)
			)
			(layer "B.Fab")
		)
		(fp_line
			(start 0.67945 -0.305054)
			(end 0.12065 -0.305054)
			(stroke
				(width 0.1)
				(type default)
			)
			(layer "B.Fab")
		)
		(pad "1" smd rect
			(at 0.40005 0 270)
			(size 0.4572 0.508)
			(layers "B.Cu" "B.Mask" "B.Paste")
			(net "OCP_SFF_RBT_ARB_OUT")
		)
		(pad "2" smd rect
			(at -0.40005 0 270)
			(size 0.4572 0.508)
			(layers "B.Cu" "B.Mask" "B.Paste")
			(net "OCP_SFF_RBT_ARB_IN_R")
		)
	)
	(footprint ""
		(layer "B.Cu")
		(at 134.633208 -333.782924 -90)
		(property "Reference" "PC495_P1_8"
			(at 0 0 90)
			(layer "B.SilkS")
			(hide yes)
			(effects
				(font
					(size 1.27 1.27)
				)
				(justify mirror)
			)
		)
		(property "Value" ""
			(at 0 0 90)
			(layer "B.Fab")
			(effects
				(font
					(size 1.27 1.27)
				)
				(justify mirror)
			)
		)
		(duplicate_pad_numbers_are_jumpers no)
		(fp_line
			(start -0.7874 0.4064)
			(end 0.7874 0.4064)
			(stroke
				(width 0.1524)
				(type default)
			)
			(layer "B.SilkS")
		)
		(fp_line
			(start 0.7874 0.4064)
			(end 0.7874 -0.4064)
			(stroke
				(width 0.1524)
				(type default)
			)
			(layer "B.SilkS")
		)
		(fp_line
			(start -0.7874 -0.4064)
			(end -0.7874 0.4064)
			(stroke
				(width 0.1524)
				(type default)
			)
			(layer "B.SilkS")
		)
		(fp_line
			(start 0.7874 -0.4064)
			(end -0.7874 -0.4064)
			(stroke
				(width 0.1524)
				(type default)
			)
			(layer "B.SilkS")
		)
		(fp_line
			(start -0.67945 0.3048)
			(end -0.120396 0.3048)
			(stroke
				(width 0.1)
				(type default)
			)
			(layer "B.Fab")
		)
		(fp_line
			(start -0.120396 0.3048)
			(end -0.120396 0.2794)
			(stroke
				(width 0.1)
				(type default)
			)
			(layer "B.Fab")
		)
		(fp_line
			(start 0.12065 0.3048)
			(end 0.67945 0.3048)
			(stroke
				(width 0.1)
				(type default)
			)
			(layer "B.Fab")
		)
		(fp_line
			(start 0.67945 0.3048)
			(end 0.67945 -0.305054)
			(stroke
				(width 0.1)
				(type default)
			)
			(layer "B.Fab")
		)
		(fp_line
			(start -0.120396 0.2794)
			(end 0.12065 0.2794)
			(stroke
				(width 0.1)
				(type default)
			)
			(layer "B.Fab")
		)
		(fp_line
			(start 0.12065 0.2794)
			(end 0.12065 0.3048)
			(stroke
				(width 0.1)
				(type default)
			)
			(layer "B.Fab")
		)
		(fp_line
			(start -0.12065 -0.2794)
			(end -0.12065 -0.3048)
			(stroke
				(width 0.1)
				(type default)
			)
			(layer "B.Fab")
		)
		(fp_line
			(start 0.12065 -0.2794)
			(end -0.12065 -0.2794)
			(stroke
				(width 0.1)
				(type default)
			)
			(layer "B.Fab")
		)
		(fp_line
			(start -0.67945 -0.3048)
			(end -0.67945 0.3048)
			(stroke
				(width 0.1)
				(type default)
			)
			(layer "B.Fab")
		)
		(fp_line
			(start -0.12065 -0.3048)
			(end -0.67945 -0.3048)
			(stroke
				(width 0.1)
				(type default)
			)
			(layer "B.Fab")
		)
		(fp_line
			(start 0.12065 -0.305054)
			(end 0.12065 -0.2794)
			(stroke
				(width 0.1)
				(type default)
			)
			(layer "B.Fab")
		)
		(fp_line
			(start 0.67945 -0.305054)
			(end 0.12065 -0.305054)
			(stroke
				(width 0.1)
				(type default)
			)
			(layer "B.Fab")
		)
		(pad "1" smd circle
			(at 0.40005 0 90)
			(size 0 0)
			(layers "B.Cu" "B.Mask" "B.Paste")
			(net "PVCCIN_CPU1")
		)
		(pad "2" smd circle
			(at -0.40005 0 90)
			(size 0 0)
			(layers "B.Cu" "B.Mask" "B.Paste")
			(net "GND")
		)
	)
	(footprint ""
		(layer "B.Cu")
		(at 168.83888 -103.723948)
		(property "Reference" "C1945"
			(at 0 0 0)
			(layer "B.SilkS")
			(hide yes)
			(effects
				(font
					(size 1.27 1.27)
				)
				(justify mirror)
			)
		)
		(property "Value" ""
			(at 0 0 0)
			(layer "B.Fab")
			(effects
				(font
					(size 1.27 1.27)
				)
				(justify mirror)
			)
		)
		(duplicate_pad_numbers_are_jumpers no)
		(fp_line
			(start -0.7874 -0.4064)
			(end -0.7874 0.4064)
			(stroke
				(width 0.1524)
				(type default)
			)
			(layer "B.SilkS")
		)
		(fp_line
			(start -0.7874 0.4064)
			(end 0.7874 0.4064)
			(stroke
				(width 0.1524)
				(type default)
			)
			(layer "B.SilkS")
		)
		(fp_line
			(start 0.7874 -0.4064)
			(end -0.7874 -0.4064)
			(stroke
				(width 0.1524)
				(type default)
			)
			(layer "B.SilkS")
		)
		(fp_line
			(start 0.7874 0.4064)
			(end 0.7874 -0.4064)
			(stroke
				(width 0.1524)
				(type default)
			)
			(layer "B.SilkS")
		)
		(fp_line
			(start -0.67945 -0.3048)
			(end -0.67945 0.3048)
			(stroke
				(width 0.1)
				(type default)
			)
			(layer "B.Fab")
		)
		(fp_line
			(start -0.67945 0.3048)
			(end -0.120396 0.3048)
			(stroke
				(width 0.1)
				(type default)
			)
			(layer "B.Fab")
		)
		(fp_line
			(start -0.12065 -0.3048)
			(end -0.67945 -0.3048)
			(stroke
				(width 0.1)
				(type default)
			)
			(layer "B.Fab")
		)
		(fp_line
			(start -0.12065 -0.2794)
			(end -0.12065 -0.3048)
			(stroke
				(width 0.1)
				(type default)
			)
			(layer "B.Fab")
		)
		(fp_line
			(start -0.120396 0.2794)
			(end 0.12065 0.2794)
			(stroke
				(width 0.1)
				(type default)
			)
			(layer "B.Fab")
		)
		(fp_line
			(start -0.120396 0.3048)
			(end -0.120396 0.2794)
			(stroke
				(width 0.1)
				(type default)
			)
			(layer "B.Fab")
		)
		(fp_line
			(start 0.12065 -0.305054)
			(end 0.12065 -0.2794)
			(stroke
				(width 0.1)
				(type default)
			)
			(layer "B.Fab")
		)
		(fp_line
			(start 0.12065 -0.2794)
			(end -0.12065 -0.2794)
			(stroke
				(width 0.1)
				(type default)
			)
			(layer "B.Fab")
		)
		(fp_line
			(start 0.12065 0.2794)
			(end 0.12065 0.3048)
			(stroke
				(width 0.1)
				(type default)
			)
			(layer "B.Fab")
		)
		(fp_line
			(start 0.12065 0.3048)
			(end 0.67945 0.3048)
			(stroke
				(width 0.1)
				(type default)
			)
			(layer "B.Fab")
		)
		(fp_line
			(start 0.67945 -0.305054)
			(end 0.12065 -0.305054)
			(stroke
				(width 0.1)
				(type default)
			)
			(layer "B.Fab")
		)
		(fp_line
			(start 0.67945 0.3048)
			(end 0.67945 -0.305054)
			(stroke
				(width 0.1)
				(type default)
			)
			(layer "B.Fab")
		)
		(pad "1" smd circle
			(at 0.40005 0 180)
			(size 0 0)
			(layers "B.Cu" "B.Mask" "B.Paste")
			(net "P3V3_AUX_FPGA_VCCIO0")
		)
		(pad "2" smd circle
			(at -0.40005 0 180)
			(size 0 0)
			(layers "B.Cu" "B.Mask" "B.Paste")
			(net "GND")
		)
	)
	(footprint ""
		(layer "B.Cu")
		(at 479.84537 -116.560092 -90)
		(property "Reference" "X39"
			(at -0.279908 -2.21996 270)
			(unlocked yes)
			(layer "B.SilkS")
			(effects
				(font
					(size 0.7874 0.5842)
					(thickness 0.1524)
				)
				(justify left mirror)
			)
		)
		(property "Value" ""
			(at 0 0 90)
			(layer "B.Fab")
			(effects
				(font
					(size 1.27 1.27)
				)
				(justify mirror)
			)
		)
		(property "Device Type" "TP_TDR_4P_FTS_TH-TP_TDR_4P_DIPA"
			(at -1.30175 1.27 180)
			(unlocked yes)
			(layer "B.Fab")
			(hide yes)
			(effects
				(font
					(size 0.635 0.4064)
					(thickness 0.1524)
				)
				(justify mirror)
			)
		)
		(property "User Part Number" "N_A"
			(at -1.30175 1.27 180)
			(unlocked yes)
			(layer "Cmts.User")
			(hide yes)
			(effects
				(font
					(size 0.635 0.4064)
					(thickness 0.1524)
				)
				(justify mirror)
			)
		)
		(duplicate_pad_numbers_are_jumpers no)
		(fp_line
			(start -2.54 3.81)
			(end -2.54 3.6703)
			(stroke
				(width 0.1524)
				(type default)
			)
			(layer "B.SilkS")
		)
		(fp_line
			(start 0 3.81)
			(end -2.54 3.81)
			(stroke
				(width 0.1524)
				(type default)
			)
			(layer "B.SilkS")
		)
		(fp_line
			(start 0 3.175)
			(end 0 3.81)
			(stroke
				(width 0.1524)
				(type default)
			)
			(layer "B.SilkS")
		)
		(fp_line
			(start -2.54 1.4097)
			(end -2.54 1.1303)
			(stroke
				(width 0.1524)
				(type default)
			)
			(layer "B.SilkS")
		)
		(fp_line
			(start 0 0.635)
			(end 0 1.905)
			(stroke
				(width 0.1524)
				(type default)
			)
			(layer "B.SilkS")
		)
		(fp_line
			(start -2.54 -1.1303)
			(end -2.54 -1.27)
			(stroke
				(width 0.1524)
				(type default)
			)
			(layer "B.SilkS")
		)
		(fp_line
			(start -2.54 -1.27)
			(end 0 -1.27)
			(stroke
				(width 0.1524)
				(type default)
			)
			(layer "B.SilkS")
		)
		(fp_line
			(start 0 -1.27)
			(end 0 -0.635)
			(stroke
				(width 0.1524)
				(type default)
			)
			(layer "B.SilkS")
		)
		(fp_poly
			(pts
				(xy 0.761746 0) (xy 2.285746 -0.762) (xy 2.285746 0.762)
			)
			(stroke
				(width 0)
				(type default)
			)
			(fill yes)
			(layer "B.SilkS")
		)
		(fp_line
			(start -2.54 3.81)
			(end -2.54 -1.27)
			(stroke
				(width 0.1)
				(type default)
			)
			(layer "B.Fab")
		)
		(fp_line
			(start 0 3.81)
			(end -2.54 3.81)
			(stroke
				(width 0.1)
				(type default)
			)
			(layer "B.Fab")
		)
		(fp_line
			(start -2.54 -1.27)
			(end 0 -1.27)
			(stroke
				(width 0.1)
				(type default)
			)
			(layer "B.Fab")
		)
		(fp_line
			(start 0 -1.27)
			(end 0 3.81)
			(stroke
				(width 0.1)
				(type default)
			)
			(layer "B.Fab")
		)
		(fp_poly
			(pts
				(xy 0.761746 0) (xy 2.285746 -0.762) (xy 2.285746 0.762)
			)
			(stroke
				(width 0)
				(type default)
			)
			(fill yes)
			(layer "B.Fab")
		)
		(pad "1" thru_hole circle
			(at 0 0 90)
			(size 1.0033 1.0033)
			(drill 0.249936)
			(layers "*.Cu" "*.Mask")
			(remove_unused_layers no)
			(net "TDR_DIFF_85_NECK_IN6_DP")
			(clearance 0.10795)
			(padstack
				(mode front_inner_back)
				(layer "Inner"
					(shape circle)
					(size 0.8001 0.8001)
					(clearance 0.1524)
				)
				(layer "B.Cu"
					(shape circle)
					(size 1.0033 1.0033)
					(thermal_gap 0.10795)
					(clearance 0.10795)
				)
			)
		)
		(pad "2" thru_hole circle
			(at -2.54 0 90)
			(size 1.9939 1.9939)
			(drill 0.249936)
			(layers "*.Cu" "*.Mask")
			(remove_unused_layers no)
			(net "T1_GND")
			(clearance 0.10795)
			(padstack
				(mode front_inner_back)
				(layer "Inner"
					(shape circle)
					(size 0.8001 0.8001)
					(clearance 0.1524)
				)
				(layer "B.Cu"
					(shape circle)
					(size 1.9939 1.9939)
					(thermal_gap 0.10795)
					(clearance 0.10795)
				)
			)
		)
		(pad "3" thru_hole circle
			(at -2.54 2.54 90)
			(size 1.9939 1.9939)
			(drill 0.249936)
			(layers "*.Cu" "*.Mask")
			(remove_unused_layers no)
			(net "T1_GND")
			(clearance 0.10795)
			(padstack
				(mode front_inner_back)
				(layer "Inner"
					(shape circle)
					(size 0.8001 0.8001)
					(clearance 0.1524)
				)
				(layer "B.Cu"
					(shape circle)
					(size 1.9939 1.9939)
					(thermal_gap 0.10795)
					(clearance 0.10795)
				)
			)
		)
		(pad "4" thru_hole circle
			(at 0 2.54 90)
			(size 1.0033 1.0033)
			(drill 0.249936)
			(layers "*.Cu" "*.Mask")
			(remove_unused_layers no)
			(net "TDR_DIFF_85_NECK_IN6_DN")
			(clearance 0.10795)
			(padstack
				(mode front_inner_back)
				(layer "Inner"
					(shape circle)
					(size 0.8001 0.8001)
					(clearance 0.1524)
				)
				(layer "B.Cu"
					(shape circle)
					(size 1.0033 1.0033)
					(thermal_gap 0.10795)
					(clearance 0.10795)
				)
			)
		)
	)
	(footprint ""
		(layer "B.Cu")
		(at 297.852846 -318.988948 90)
		(property "Reference" "R880"
			(at 0 0 90)
			(layer "B.SilkS")
			(hide yes)
			(effects
				(font
					(size 1.27 1.27)
				)
				(justify mirror)
			)
		)
		(property "Value" ""
			(at 0 0 90)
			(layer "B.Fab")
			(effects
				(font
					(size 1.27 1.27)
				)
				(justify mirror)
			)
		)
		(duplicate_pad_numbers_are_jumpers no)
		(fp_line
			(start 0.7874 -0.4064)
			(end -0.7874 -0.4064)
			(stroke
				(width 0.1524)
				(type default)
			)
			(layer "B.SilkS")
		)
		(fp_line
			(start -0.7874 -0.4064)
			(end -0.7874 0.4064)
			(stroke
				(width 0.1524)
				(type default)
			)
			(layer "B.SilkS")
		)
		(fp_line
			(start 0.7874 0.4064)
			(end 0.7874 -0.4064)
			(stroke
				(width 0.1524)
				(type default)
			)
			(layer "B.SilkS")
		)
		(fp_line
			(start -0.7874 0.4064)
			(end 0.7874 0.4064)
			(stroke
				(width 0.1524)
				(type default)
			)
			(layer "B.SilkS")
		)
		(fp_line
			(start 0.67945 -0.305054)
			(end 0.12065 -0.305054)
			(stroke
				(width 0.1)
				(type default)
			)
			(layer "B.Fab")
		)
		(fp_line
			(start 0.12065 -0.305054)
			(end 0.12065 -0.2794)
			(stroke
				(width 0.1)
				(type default)
			)
			(layer "B.Fab")
		)
		(fp_line
			(start -0.12065 -0.3048)
			(end -0.67945 -0.3048)
			(stroke
				(width 0.1)
				(type default)
			)
			(layer "B.Fab")
		)
		(fp_line
			(start -0.67945 -0.3048)
			(end -0.67945 0.3048)
			(stroke
				(width 0.1)
				(type default)
			)
			(layer "B.Fab")
		)
		(fp_line
			(start 0.12065 -0.2794)
			(end -0.12065 -0.2794)
			(stroke
				(width 0.1)
				(type default)
			)
			(layer "B.Fab")
		)
		(fp_line
			(start -0.12065 -0.2794)
			(end -0.12065 -0.3048)
			(stroke
				(width 0.1)
				(type default)
			)
			(layer "B.Fab")
		)
		(fp_line
			(start 0.12065 0.2794)
			(end 0.12065 0.3048)
			(stroke
				(width 0.1)
				(type default)
			)
			(layer "B.Fab")
		)
		(fp_line
			(start -0.120396 0.2794)
			(end 0.12065 0.2794)
			(stroke
				(width 0.1)
				(type default)
			)
			(layer "B.Fab")
		)
		(fp_line
			(start 0.67945 0.3048)
			(end 0.67945 -0.305054)
			(stroke
				(width 0.1)
				(type default)
			)
			(layer "B.Fab")
		)
		(fp_line
			(start 0.12065 0.3048)
			(end 0.67945 0.3048)
			(stroke
				(width 0.1)
				(type default)
			)
			(layer "B.Fab")
		)
		(fp_line
			(start -0.120396 0.3048)
			(end -0.120396 0.2794)
			(stroke
				(width 0.1)
				(type default)
			)
			(layer "B.Fab")
		)
		(fp_line
			(start -0.67945 0.3048)
			(end -0.120396 0.3048)
			(stroke
				(width 0.1)
				(type default)
			)
			(layer "B.Fab")
		)
		(pad "1" smd circle
			(at 0.40005 0 270)
			(size 0 0)
			(layers "B.Cu" "B.Mask" "B.Paste")
			(net "PWRGD_CHB_CPU0_DIMM2")
		)
		(pad "2" smd circle
			(at -0.40005 0 270)
			(size 0 0)
			(layers "B.Cu" "B.Mask" "B.Paste")
			(net "PWRGD_FAIL_CPU0_AB")
		)
	)
	(footprint ""
		(layer "B.Cu")
		(at 318.223138 -187.90793 -90)
		(property "Reference" "R239"
			(at 0 0 90)
			(layer "B.SilkS")
			(hide yes)
			(effects
				(font
					(size 1.27 1.27)
				)
				(justify mirror)
			)
		)
		(property "Value" ""
			(at 0 0 90)
			(layer "B.Fab")
			(effects
				(font
					(size 1.27 1.27)
				)
				(justify mirror)
			)
		)
		(duplicate_pad_numbers_are_jumpers no)
		(fp_line
			(start -0.7874 0.4064)
			(end 0.7874 0.4064)
			(stroke
				(width 0.1524)
				(type default)
			)
			(layer "B.SilkS")
		)
		(fp_line
			(start 0.7874 0.4064)
			(end 0.7874 -0.4064)
			(stroke
				(width 0.1524)
				(type default)
			)
			(layer "B.SilkS")
		)
		(fp_line
			(start -0.7874 -0.4064)
			(end -0.7874 0.4064)
			(stroke
				(width 0.1524)
				(type default)
			)
			(layer "B.SilkS")
		)
		(fp_line
			(start 0.7874 -0.4064)
			(end -0.7874 -0.4064)
			(stroke
				(width 0.1524)
				(type default)
			)
			(layer "B.SilkS")
		)
		(fp_line
			(start -0.67945 0.3048)
			(end -0.120396 0.3048)
			(stroke
				(width 0.1)
				(type default)
			)
			(layer "B.Fab")
		)
		(fp_line
			(start -0.120396 0.3048)
			(end -0.120396 0.2794)
			(stroke
				(width 0.1)
				(type default)
			)
			(layer "B.Fab")
		)
		(fp_line
			(start 0.12065 0.3048)
			(end 0.67945 0.3048)
			(stroke
				(width 0.1)
				(type default)
			)
			(layer "B.Fab")
		)
		(fp_line
			(start 0.67945 0.3048)
			(end 0.67945 -0.305054)
			(stroke
				(width 0.1)
				(type default)
			)
			(layer "B.Fab")
		)
		(fp_line
			(start -0.120396 0.2794)
			(end 0.12065 0.2794)
			(stroke
				(width 0.1)
				(type default)
			)
			(layer "B.Fab")
		)
		(fp_line
			(start 0.12065 0.2794)
			(end 0.12065 0.3048)
			(stroke
				(width 0.1)
				(type default)
			)
			(layer "B.Fab")
		)
		(fp_line
			(start -0.12065 -0.2794)
			(end -0.12065 -0.3048)
			(stroke
				(width 0.1)
				(type default)
			)
			(layer "B.Fab")
		)
		(fp_line
			(start 0.12065 -0.2794)
			(end -0.12065 -0.2794)
			(stroke
				(width 0.1)
				(type default)
			)
			(layer "B.Fab")
		)
		(fp_line
			(start -0.67945 -0.3048)
			(end -0.67945 0.3048)
			(stroke
				(width 0.1)
				(type default)
			)
			(layer "B.Fab")
		)
		(fp_line
			(start -0.12065 -0.3048)
			(end -0.67945 -0.3048)
			(stroke
				(width 0.1)
				(type default)
			)
			(layer "B.Fab")
		)
		(fp_line
			(start 0.12065 -0.305054)
			(end 0.12065 -0.2794)
			(stroke
				(width 0.1)
				(type default)
			)
			(layer "B.Fab")
		)
		(fp_line
			(start 0.67945 -0.305054)
			(end 0.12065 -0.305054)
			(stroke
				(width 0.1)
				(type default)
			)
			(layer "B.Fab")
		)
		(pad "1" smd circle
			(at 0.40005 0 90)
			(size 0 0)
			(layers "B.Cu" "B.Mask" "B.Paste")
			(net "H_CPU0_PROCHOT_LVC1_R_N")
		)
		(pad "2" smd circle
			(at -0.40005 0 90)
			(size 0 0)
			(layers "B.Cu" "B.Mask" "B.Paste")
			(net "H_CPU0_PROCHOT_LVC1_N")
		)
	)
	(footprint ""
		(layer "B.Cu")
		(at 236.214666 -423.001948 90)
		(property "Reference" "R2802"
			(at 0 0 90)
			(layer "B.SilkS")
			(hide yes)
			(effects
				(font
					(size 1.27 1.27)
				)
				(justify mirror)
			)
		)
		(property "Value" ""
			(at 0 0 90)
			(layer "B.Fab")
			(effects
				(font
					(size 1.27 1.27)
				)
				(justify mirror)
			)
		)
		(duplicate_pad_numbers_are_jumpers no)
		(fp_line
			(start 0.7874 -0.4064)
			(end -0.7874 -0.4064)
			(stroke
				(width 0.1524)
				(type default)
			)
			(layer "B.SilkS")
		)
		(fp_line
			(start -0.7874 -0.4064)
			(end -0.7874 0.4064)
			(stroke
				(width 0.1524)
				(type default)
			)
			(layer "B.SilkS")
		)
		(fp_line
			(start 0.7874 0.4064)
			(end 0.7874 -0.4064)
			(stroke
				(width 0.1524)
				(type default)
			)
			(layer "B.SilkS")
		)
		(fp_line
			(start -0.7874 0.4064)
			(end 0.7874 0.4064)
			(stroke
				(width 0.1524)
				(type default)
			)
			(layer "B.SilkS")
		)
		(fp_line
			(start 0.67945 -0.305054)
			(end 0.12065 -0.305054)
			(stroke
				(width 0.1)
				(type default)
			)
			(layer "B.Fab")
		)
		(fp_line
			(start 0.12065 -0.305054)
			(end 0.12065 -0.2794)
			(stroke
				(width 0.1)
				(type default)
			)
			(layer "B.Fab")
		)
		(fp_line
			(start -0.12065 -0.3048)
			(end -0.67945 -0.3048)
			(stroke
				(width 0.1)
				(type default)
			)
			(layer "B.Fab")
		)
		(fp_line
			(start -0.67945 -0.3048)
			(end -0.67945 0.3048)
			(stroke
				(width 0.1)
				(type default)
			)
			(layer "B.Fab")
		)
		(fp_line
			(start 0.12065 -0.2794)
			(end -0.12065 -0.2794)
			(stroke
				(width 0.1)
				(type default)
			)
			(layer "B.Fab")
		)
		(fp_line
			(start -0.12065 -0.2794)
			(end -0.12065 -0.3048)
			(stroke
				(width 0.1)
				(type default)
			)
			(layer "B.Fab")
		)
		(fp_line
			(start 0.12065 0.2794)
			(end 0.12065 0.3048)
			(stroke
				(width 0.1)
				(type default)
			)
			(layer "B.Fab")
		)
		(fp_line
			(start -0.120396 0.2794)
			(end 0.12065 0.2794)
			(stroke
				(width 0.1)
				(type default)
			)
			(layer "B.Fab")
		)
		(fp_line
			(start 0.67945 0.3048)
			(end 0.67945 -0.305054)
			(stroke
				(width 0.1)
				(type default)
			)
			(layer "B.Fab")
		)
		(fp_line
			(start 0.12065 0.3048)
			(end 0.67945 0.3048)
			(stroke
				(width 0.1)
				(type default)
			)
			(layer "B.Fab")
		)
		(fp_line
			(start -0.120396 0.3048)
			(end -0.120396 0.2794)
			(stroke
				(width 0.1)
				(type default)
			)
			(layer "B.Fab")
		)
		(fp_line
			(start -0.67945 0.3048)
			(end -0.120396 0.3048)
			(stroke
				(width 0.1)
				(type default)
			)
			(layer "B.Fab")
		)
		(pad "1" smd circle
			(at 0.40005 0 270)
			(size 0 0)
			(layers "B.Cu" "B.Mask" "B.Paste")
			(net "HPDB_HSC_PWRGD_R")
		)
		(pad "2" smd circle
			(at -0.40005 0 270)
			(size 0 0)
			(layers "B.Cu" "B.Mask" "B.Paste")
			(net "HPDB_HSC_PWRGD")
		)
	)
	(footprint ""
		(layer "B.Cu")
		(at 336.878676 -330.214224 -90)
		(property "Reference" "PC2336"
			(at 0 0 90)
			(layer "B.SilkS")
			(hide yes)
			(effects
				(font
					(size 1.27 1.27)
				)
				(justify mirror)
			)
		)
		(property "Value" ""
			(at 0 0 90)
			(layer "B.Fab")
			(effects
				(font
					(size 1.27 1.27)
				)
				(justify mirror)
			)
		)
		(duplicate_pad_numbers_are_jumpers no)
		(fp_line
			(start -4.533392 2.249932)
			(end 4.533392 2.249932)
			(stroke
				(width 0.1524)
				(type default)
			)
			(layer "B.SilkS")
		)
		(fp_line
			(start 4.533392 2.249932)
			(end 4.533392 -2.249932)
			(stroke
				(width 0.1524)
				(type default)
			)
			(layer "B.SilkS")
		)
		(fp_line
			(start -4.533392 -2.249932)
			(end -4.533392 2.249932)
			(stroke
				(width 0.1524)
				(type default)
			)
			(layer "B.SilkS")
		)
		(fp_line
			(start 4.533392 -2.249932)
			(end -4.533392 -2.249932)
			(stroke
				(width 0.1524)
				(type default)
			)
			(layer "B.SilkS")
		)
		(fp_rect
			(start 5.39242 2.326132)
			(end 4.533392 -2.326132)
			(stroke
				(width 0)
				(type default)
			)
			(fill yes)
			(layer "B.SilkS")
		)
		(fp_line
			(start -3.750056 2.249932)
			(end 3.750056 2.249932)
			(stroke
				(width 0.1)
				(type default)
			)
			(layer "B.Fab")
		)
		(fp_line
			(start 3.750056 2.249932)
			(end 3.750056 -2.249932)
			(stroke
				(width 0.1)
				(type default)
			)
			(layer "B.Fab")
		)
		(fp_line
			(start -3.750056 -2.249932)
			(end -3.750056 2.249932)
			(stroke
				(width 0.1)
				(type default)
			)
			(layer "B.Fab")
		)
		(fp_line
			(start 3.750056 -2.249932)
			(end -3.750056 -2.249932)
			(stroke
				(width 0.1)
				(type default)
			)
			(layer "B.Fab")
		)
		(fp_text user "-"
			(at -4.619244 1.269746 270)
			(unlocked yes)
			(layer "B.SilkS")
			(effects
				(font
					(size 1.905 1.4224)
					(thickness 0.1524)
				)
				(justify left mirror)
			)
		)
		(fp_text user "+"
			(at 6.322314 0.786384 180)
			(unlocked yes)
			(layer "B.SilkS")
			(effects
				(font
					(size 1.905 1.4224)
					(thickness 0.1524)
				)
				(justify left mirror)
			)
		)
		(fp_text user "+"
			(at 6.322314 0.786384 180)
			(unlocked yes)
			(layer "B.Fab")
			(effects
				(font
					(size 1.905 1.4224)
					(thickness 0.1524)
				)
				(justify left mirror)
			)
		)
		(fp_text user "-"
			(at -4.8514 -0.14605 270)
			(unlocked yes)
			(layer "B.Fab")
			(effects
				(font
					(size 1.905 1.4224)
					(thickness 0.1524)
				)
				(justify left mirror)
			)
		)
		(pad "1" smd rect
			(at 3.199892 0 90)
			(size 2.413 2.8194)
			(layers "B.Cu" "B.Mask" "B.Paste")
			(net "PVCCIN_CPU0")
		)
		(pad "2" smd rect
			(at -3.199892 0 90)
			(size 2.413 2.8194)
			(layers "B.Cu" "B.Mask" "B.Paste")
			(net "GND")
		)
	)
	(footprint ""
		(layer "B.Cu")
		(at 236.89056 -249.037348)
		(property "Reference" "C2257"
			(at 0 0 0)
			(layer "B.SilkS")
			(hide yes)
			(effects
				(font
					(size 1.27 1.27)
				)
				(justify mirror)
			)
		)
		(property "Value" ""
			(at 0 0 0)
			(layer "B.Fab")
			(effects
				(font
					(size 1.27 1.27)
				)
				(justify mirror)
			)
		)
		(duplicate_pad_numbers_are_jumpers no)
		(fp_line
			(start -0.7874 -0.4064)
			(end -0.7874 0.4064)
			(stroke
				(width 0.1524)
				(type default)
			)
			(layer "B.SilkS")
		)
		(fp_line
			(start -0.7874 0.4064)
			(end 0.7874 0.4064)
			(stroke
				(width 0.1524)
				(type default)
			)
			(layer "B.SilkS")
		)
		(fp_line
			(start 0.7874 -0.4064)
			(end -0.7874 -0.4064)
			(stroke
				(width 0.1524)
				(type default)
			)
			(layer "B.SilkS")
		)
		(fp_line
			(start 0.7874 0.4064)
			(end 0.7874 -0.4064)
			(stroke
				(width 0.1524)
				(type default)
			)
			(layer "B.SilkS")
		)
		(fp_line
			(start -0.67945 -0.3048)
			(end -0.67945 0.3048)
			(stroke
				(width 0.1)
				(type default)
			)
			(layer "B.Fab")
		)
		(fp_line
			(start -0.67945 0.3048)
			(end -0.120396 0.3048)
			(stroke
				(width 0.1)
				(type default)
			)
			(layer "B.Fab")
		)
		(fp_line
			(start -0.12065 -0.3048)
			(end -0.67945 -0.3048)
			(stroke
				(width 0.1)
				(type default)
			)
			(layer "B.Fab")
		)
		(fp_line
			(start -0.12065 -0.2794)
			(end -0.12065 -0.3048)
			(stroke
				(width 0.1)
				(type default)
			)
			(layer "B.Fab")
		)
		(fp_line
			(start -0.120396 0.2794)
			(end 0.12065 0.2794)
			(stroke
				(width 0.1)
				(type default)
			)
			(layer "B.Fab")
		)
		(fp_line
			(start -0.120396 0.3048)
			(end -0.120396 0.2794)
			(stroke
				(width 0.1)
				(type default)
			)
			(layer "B.Fab")
		)
		(fp_line
			(start 0.12065 -0.305054)
			(end 0.12065 -0.2794)
			(stroke
				(width 0.1)
				(type default)
			)
			(layer "B.Fab")
		)
		(fp_line
			(start 0.12065 -0.2794)
			(end -0.12065 -0.2794)
			(stroke
				(width 0.1)
				(type default)
			)
			(layer "B.Fab")
		)
		(fp_line
			(start 0.12065 0.2794)
			(end 0.12065 0.3048)
			(stroke
				(width 0.1)
				(type default)
			)
			(layer "B.Fab")
		)
		(fp_line
			(start 0.12065 0.3048)
			(end 0.67945 0.3048)
			(stroke
				(width 0.1)
				(type default)
			)
			(layer "B.Fab")
		)
		(fp_line
			(start 0.67945 -0.305054)
			(end 0.12065 -0.305054)
			(stroke
				(width 0.1)
				(type default)
			)
			(layer "B.Fab")
		)
		(fp_line
			(start 0.67945 0.3048)
			(end 0.67945 -0.305054)
			(stroke
				(width 0.1)
				(type default)
			)
			(layer "B.Fab")
		)
		(pad "1" smd circle
			(at 0.40005 0 180)
			(size 0 0)
			(layers "B.Cu" "B.Mask" "B.Paste")
			(net "VFG3P3_CLK_GEN")
		)
		(pad "2" smd circle
			(at -0.40005 0 180)
			(size 0 0)
			(layers "B.Cu" "B.Mask" "B.Paste")
			(net "GND")
		)
	)
	(footprint ""
		(layer "B.Cu")
		(at 164.725858 -256.488946 -90)
		(property "Reference" "C482"
			(at 0 0 90)
			(layer "B.SilkS")
			(hide yes)
			(effects
				(font
					(size 1.27 1.27)
				)
				(justify mirror)
			)
		)
		(property "Value" ""
			(at 0 0 90)
			(layer "B.Fab")
			(effects
				(font
					(size 1.27 1.27)
				)
				(justify mirror)
			)
		)
		(duplicate_pad_numbers_are_jumpers no)
		(fp_line
			(start -1.524 0.762)
			(end 1.524 0.762)
			(stroke
				(width 0.1524)
				(type default)
			)
			(layer "B.SilkS")
		)
		(fp_line
			(start 1.524 0.762)
			(end 1.524 -0.762)
			(stroke
				(width 0.1524)
				(type default)
			)
			(layer "B.SilkS")
		)
		(fp_line
			(start -1.524 -0.762)
			(end -1.524 0.762)
			(stroke
				(width 0.1524)
				(type default)
			)
			(layer "B.SilkS")
		)
		(fp_line
			(start 1.524 -0.762)
			(end -1.524 -0.762)
			(stroke
				(width 0.1524)
				(type default)
			)
			(layer "B.SilkS")
		)
		(fp_line
			(start -1.1049 0.724916)
			(end -1.1049 -0.724916)
			(stroke
				(width 0.1)
				(type default)
			)
			(layer "B.Fab")
		)
		(fp_line
			(start 1.1049 0.724916)
			(end -1.1049 0.724916)
			(stroke
				(width 0.1)
				(type default)
			)
			(layer "B.Fab")
		)
		(fp_line
			(start -1.1049 -0.724916)
			(end 1.1049 -0.724916)
			(stroke
				(width 0.1)
				(type default)
			)
			(layer "B.Fab")
		)
		(fp_line
			(start 1.1049 -0.724916)
			(end 1.1049 0.724916)
			(stroke
				(width 0.1)
				(type default)
			)
			(layer "B.Fab")
		)
		(pad "1" smd rect
			(at 0.889 0 270)
			(size 1.016 1.27)
			(layers "B.Cu" "B.Mask" "B.Paste")
			(net "PVCCFA_EHV_FIVRA_CPU1")
		)
		(pad "2" smd rect
			(at -0.889 0 270)
			(size 1.016 1.27)
			(layers "B.Cu" "B.Mask" "B.Paste")
			(net "GND")
		)
	)
	(footprint ""
		(layer "B.Cu")
		(at 367.034572 -184.400952 90)
		(property "Reference" "R2478"
			(at 0 0 90)
			(layer "B.SilkS")
			(hide yes)
			(effects
				(font
					(size 1.27 1.27)
				)
				(justify mirror)
			)
		)
		(property "Value" ""
			(at 0 0 90)
			(layer "B.Fab")
			(effects
				(font
					(size 1.27 1.27)
				)
				(justify mirror)
			)
		)
		(duplicate_pad_numbers_are_jumpers no)
		(fp_line
			(start 0.7874 -0.4064)
			(end -0.7874 -0.4064)
			(stroke
				(width 0.1524)
				(type default)
			)
			(layer "B.SilkS")
		)
		(fp_line
			(start -0.7874 -0.4064)
			(end -0.7874 0.4064)
			(stroke
				(width 0.1524)
				(type default)
			)
			(layer "B.SilkS")
		)
		(fp_line
			(start 0.7874 0.4064)
			(end 0.7874 -0.4064)
			(stroke
				(width 0.1524)
				(type default)
			)
			(layer "B.SilkS")
		)
		(fp_line
			(start -0.7874 0.4064)
			(end 0.7874 0.4064)
			(stroke
				(width 0.1524)
				(type default)
			)
			(layer "B.SilkS")
		)
		(fp_line
			(start 0.67945 -0.305054)
			(end 0.12065 -0.305054)
			(stroke
				(width 0.1)
				(type default)
			)
			(layer "B.Fab")
		)
		(fp_line
			(start 0.12065 -0.305054)
			(end 0.12065 -0.2794)
			(stroke
				(width 0.1)
				(type default)
			)
			(layer "B.Fab")
		)
		(fp_line
			(start -0.12065 -0.3048)
			(end -0.67945 -0.3048)
			(stroke
				(width 0.1)
				(type default)
			)
			(layer "B.Fab")
		)
		(fp_line
			(start -0.67945 -0.3048)
			(end -0.67945 0.3048)
			(stroke
				(width 0.1)
				(type default)
			)
			(layer "B.Fab")
		)
		(fp_line
			(start 0.12065 -0.2794)
			(end -0.12065 -0.2794)
			(stroke
				(width 0.1)
				(type default)
			)
			(layer "B.Fab")
		)
		(fp_line
			(start -0.12065 -0.2794)
			(end -0.12065 -0.3048)
			(stroke
				(width 0.1)
				(type default)
			)
			(layer "B.Fab")
		)
		(fp_line
			(start 0.12065 0.2794)
			(end 0.12065 0.3048)
			(stroke
				(width 0.1)
				(type default)
			)
			(layer "B.Fab")
		)
		(fp_line
			(start -0.120396 0.2794)
			(end 0.12065 0.2794)
			(stroke
				(width 0.1)
				(type default)
			)
			(layer "B.Fab")
		)
		(fp_line
			(start 0.67945 0.3048)
			(end 0.67945 -0.305054)
			(stroke
				(width 0.1)
				(type default)
			)
			(layer "B.Fab")
		)
		(fp_line
			(start 0.12065 0.3048)
			(end 0.67945 0.3048)
			(stroke
				(width 0.1)
				(type default)
			)
			(layer "B.Fab")
		)
		(fp_line
			(start -0.120396 0.3048)
			(end -0.120396 0.2794)
			(stroke
				(width 0.1)
				(type default)
			)
			(layer "B.Fab")
		)
		(fp_line
			(start -0.67945 0.3048)
			(end -0.120396 0.3048)
			(stroke
				(width 0.1)
				(type default)
			)
			(layer "B.Fab")
		)
		(pad "1" smd circle
			(at 0.40005 0 270)
			(size 0 0)
			(layers "B.Cu" "B.Mask" "B.Paste")
			(net "SMB_PEHPCPU0_LVC3_SDA_R0")
		)
		(pad "2" smd circle
			(at -0.40005 0 270)
			(size 0 0)
			(layers "B.Cu" "B.Mask" "B.Paste")
			(net "SMB_PEHPCPU0_LVC3_SDA")
		)
	)
	(footprint ""
		(layer "B.Cu")
		(at 435.549802 -12.104116 180)
		(property "Reference" "C1238"
			(at 0 0 0)
			(layer "B.SilkS")
			(hide yes)
			(effects
				(font
					(size 1.27 1.27)
				)
				(justify mirror)
			)
		)
		(property "Value" ""
			(at 0 0 0)
			(layer "B.Fab")
			(effects
				(font
					(size 1.27 1.27)
				)
				(justify mirror)
			)
		)
		(duplicate_pad_numbers_are_jumpers no)
		(fp_line
			(start 0.7874 0.4064)
			(end 0.7874 -0.4064)
			(stroke
				(width 0.1524)
				(type default)
			)
			(layer "B.SilkS")
		)
		(fp_line
			(start 0.7874 -0.4064)
			(end -0.7874 -0.4064)
			(stroke
				(width 0.1524)
				(type default)
			)
			(layer "B.SilkS")
		)
		(fp_line
			(start -0.7874 0.4064)
			(end 0.7874 0.4064)
			(stroke
				(width 0.1524)
				(type default)
			)
			(layer "B.SilkS")
		)
		(fp_line
			(start -0.7874 -0.4064)
			(end -0.7874 0.4064)
			(stroke
				(width 0.1524)
				(type default)
			)
			(layer "B.SilkS")
		)
		(fp_line
			(start 0.67945 0.3048)
			(end 0.67945 -0.305054)
			(stroke
				(width 0.1)
				(type default)
			)
			(layer "B.Fab")
		)
		(fp_line
			(start 0.67945 -0.305054)
			(end 0.12065 -0.305054)
			(stroke
				(width 0.1)
				(type default)
			)
			(layer "B.Fab")
		)
		(fp_line
			(start 0.12065 0.3048)
			(end 0.67945 0.3048)
			(stroke
				(width 0.1)
				(type default)
			)
			(layer "B.Fab")
		)
		(fp_line
			(start 0.12065 0.2794)
			(end 0.12065 0.3048)
			(stroke
				(width 0.1)
				(type default)
			)
			(layer "B.Fab")
		)
		(fp_line
			(start 0.12065 -0.2794)
			(end -0.12065 -0.2794)
			(stroke
				(width 0.1)
				(type default)
			)
			(layer "B.Fab")
		)
		(fp_line
			(start 0.12065 -0.305054)
			(end 0.12065 -0.2794)
			(stroke
				(width 0.1)
				(type default)
			)
			(layer "B.Fab")
		)
		(fp_line
			(start -0.120396 0.3048)
			(end -0.120396 0.2794)
			(stroke
				(width 0.1)
				(type default)
			)
			(layer "B.Fab")
		)
		(fp_line
			(start -0.120396 0.2794)
			(end 0.12065 0.2794)
			(stroke
				(width 0.1)
				(type default)
			)
			(layer "B.Fab")
		)
		(fp_line
			(start -0.12065 -0.2794)
			(end -0.12065 -0.3048)
			(stroke
				(width 0.1)
				(type default)
			)
			(layer "B.Fab")
		)
		(fp_line
			(start -0.12065 -0.3048)
			(end -0.67945 -0.3048)
			(stroke
				(width 0.1)
				(type default)
			)
			(layer "B.Fab")
		)
		(fp_line
			(start -0.67945 0.3048)
			(end -0.120396 0.3048)
			(stroke
				(width 0.1)
				(type default)
			)
			(layer "B.Fab")
		)
		(fp_line
			(start -0.67945 -0.3048)
			(end -0.67945 0.3048)
			(stroke
				(width 0.1)
				(type default)
			)
			(layer "B.Fab")
		)
		(pad "1" smd circle
			(at 0.40005 0)
			(size 0 0)
			(layers "B.Cu" "B.Mask" "B.Paste")
			(net "P3V3_OCP_SFF")
		)
		(pad "2" smd circle
			(at -0.40005 0)
			(size 0 0)
			(layers "B.Cu" "B.Mask" "B.Paste")
			(net "GND")
		)
	)
	(footprint ""
		(layer "B.Cu")
		(at 326.338438 -188.89599 -90)
		(property "Reference" "R6"
			(at 0 0 90)
			(layer "B.SilkS")
			(hide yes)
			(effects
				(font
					(size 1.27 1.27)
				)
				(justify mirror)
			)
		)
		(property "Value" ""
			(at 0 0 90)
			(layer "B.Fab")
			(effects
				(font
					(size 1.27 1.27)
				)
				(justify mirror)
			)
		)
		(duplicate_pad_numbers_are_jumpers no)
		(fp_line
			(start -0.7874 0.4064)
			(end 0.7874 0.4064)
			(stroke
				(width 0.1524)
				(type default)
			)
			(layer "B.SilkS")
		)
		(fp_line
			(start 0.7874 0.4064)
			(end 0.7874 -0.4064)
			(stroke
				(width 0.1524)
				(type default)
			)
			(layer "B.SilkS")
		)
		(fp_line
			(start -0.7874 -0.4064)
			(end -0.7874 0.4064)
			(stroke
				(width 0.1524)
				(type default)
			)
			(layer "B.SilkS")
		)
		(fp_line
			(start 0.7874 -0.4064)
			(end -0.7874 -0.4064)
			(stroke
				(width 0.1524)
				(type default)
			)
			(layer "B.SilkS")
		)
		(fp_line
			(start -0.67945 0.3048)
			(end -0.120396 0.3048)
			(stroke
				(width 0.1)
				(type default)
			)
			(layer "B.Fab")
		)
		(fp_line
			(start -0.120396 0.3048)
			(end -0.120396 0.2794)
			(stroke
				(width 0.1)
				(type default)
			)
			(layer "B.Fab")
		)
		(fp_line
			(start 0.12065 0.3048)
			(end 0.67945 0.3048)
			(stroke
				(width 0.1)
				(type default)
			)
			(layer "B.Fab")
		)
		(fp_line
			(start 0.67945 0.3048)
			(end 0.67945 -0.305054)
			(stroke
				(width 0.1)
				(type default)
			)
			(layer "B.Fab")
		)
		(fp_line
			(start -0.120396 0.2794)
			(end 0.12065 0.2794)
			(stroke
				(width 0.1)
				(type default)
			)
			(layer "B.Fab")
		)
		(fp_line
			(start 0.12065 0.2794)
			(end 0.12065 0.3048)
			(stroke
				(width 0.1)
				(type default)
			)
			(layer "B.Fab")
		)
		(fp_line
			(start -0.12065 -0.2794)
			(end -0.12065 -0.3048)
			(stroke
				(width 0.1)
				(type default)
			)
			(layer "B.Fab")
		)
		(fp_line
			(start 0.12065 -0.2794)
			(end -0.12065 -0.2794)
			(stroke
				(width 0.1)
				(type default)
			)
			(layer "B.Fab")
		)
		(fp_line
			(start -0.67945 -0.3048)
			(end -0.67945 0.3048)
			(stroke
				(width 0.1)
				(type default)
			)
			(layer "B.Fab")
		)
		(fp_line
			(start -0.12065 -0.3048)
			(end -0.67945 -0.3048)
			(stroke
				(width 0.1)
				(type default)
			)
			(layer "B.Fab")
		)
		(fp_line
			(start 0.12065 -0.305054)
			(end 0.12065 -0.2794)
			(stroke
				(width 0.1)
				(type default)
			)
			(layer "B.Fab")
		)
		(fp_line
			(start 0.67945 -0.305054)
			(end 0.12065 -0.305054)
			(stroke
				(width 0.1)
				(type default)
			)
			(layer "B.Fab")
		)
		(pad "1" smd circle
			(at 0.40005 0 90)
			(size 0 0)
			(layers "B.Cu" "B.Mask" "B.Paste")
			(net "JTAG_DBP_CPU_QS_GTL_TMS")
		)
		(pad "2" smd circle
			(at -0.40005 0 90)
			(size 0 0)
			(layers "B.Cu" "B.Mask" "B.Paste")
			(net "JTAG_DBP_CPU0_QS_GTL_R_TMS")
		)
	)
	(footprint ""
		(layer "B.Cu")
		(at 356.785418 -296.054526 180)
		(property "Reference" "C390"
			(at 0 0 0)
			(layer "B.SilkS")
			(hide yes)
			(effects
				(font
					(size 1.27 1.27)
				)
				(justify mirror)
			)
		)
		(property "Value" ""
			(at 0 0 0)
			(layer "B.Fab")
			(effects
				(font
					(size 1.27 1.27)
				)
				(justify mirror)
			)
		)
		(duplicate_pad_numbers_are_jumpers no)
		(fp_line
			(start 1.524 0.762)
			(end 1.524 -0.762)
			(stroke
				(width 0.1524)
				(type default)
			)
			(layer "B.SilkS")
		)
		(fp_line
			(start 1.524 -0.762)
			(end -1.524 -0.762)
			(stroke
				(width 0.1524)
				(type default)
			)
			(layer "B.SilkS")
		)
		(fp_line
			(start -1.524 0.762)
			(end 1.524 0.762)
			(stroke
				(width 0.1524)
				(type default)
			)
			(layer "B.SilkS")
		)
		(fp_line
			(start -1.524 -0.762)
			(end -1.524 0.762)
			(stroke
				(width 0.1524)
				(type default)
			)
			(layer "B.SilkS")
		)
		(fp_line
			(start 1.1049 0.724916)
			(end -1.1049 0.724916)
			(stroke
				(width 0.1)
				(type default)
			)
			(layer "B.Fab")
		)
		(fp_line
			(start 1.1049 -0.724916)
			(end 1.1049 0.724916)
			(stroke
				(width 0.1)
				(type default)
			)
			(layer "B.Fab")
		)
		(fp_line
			(start -1.1049 0.724916)
			(end -1.1049 -0.724916)
			(stroke
				(width 0.1)
				(type default)
			)
			(layer "B.Fab")
		)
		(fp_line
			(start -1.1049 -0.724916)
			(end 1.1049 -0.724916)
			(stroke
				(width 0.1)
				(type default)
			)
			(layer "B.Fab")
		)
		(pad "1" smd rect
			(at 0.889 0 180)
			(size 1.016 1.27)
			(layers "B.Cu" "B.Mask" "B.Paste")
			(net "PVCCIN_CPU0")
		)
		(pad "2" smd rect
			(at -0.889 0 180)
			(size 1.016 1.27)
			(layers "B.Cu" "B.Mask" "B.Paste")
			(net "GND")
		)
	)
	(footprint ""
		(layer "B.Cu")
		(at 408.807158 -258.318254 -90)
		(property "Reference" "C498"
			(at 0 0 90)
			(layer "B.SilkS")
			(hide yes)
			(effects
				(font
					(size 1.27 1.27)
				)
				(justify mirror)
			)
		)
		(property "Value" ""
			(at 0 0 90)
			(layer "B.Fab")
			(effects
				(font
					(size 1.27 1.27)
				)
				(justify mirror)
			)
		)
		(duplicate_pad_numbers_are_jumpers no)
		(fp_line
			(start -1.524 0.762)
			(end 1.524 0.762)
			(stroke
				(width 0.1524)
				(type default)
			)
			(layer "B.SilkS")
		)
		(fp_line
			(start 1.524 0.762)
			(end 1.524 -0.762)
			(stroke
				(width 0.1524)
				(type default)
			)
			(layer "B.SilkS")
		)
		(fp_line
			(start -1.524 -0.762)
			(end -1.524 0.762)
			(stroke
				(width 0.1524)
				(type default)
			)
			(layer "B.SilkS")
		)
		(fp_line
			(start 1.524 -0.762)
			(end -1.524 -0.762)
			(stroke
				(width 0.1524)
				(type default)
			)
			(layer "B.SilkS")
		)
		(fp_line
			(start -1.1049 0.724916)
			(end -1.1049 -0.724916)
			(stroke
				(width 0.1)
				(type default)
			)
			(layer "B.Fab")
		)
		(fp_line
			(start 1.1049 0.724916)
			(end -1.1049 0.724916)
			(stroke
				(width 0.1)
				(type default)
			)
			(layer "B.Fab")
		)
		(fp_line
			(start -1.1049 -0.724916)
			(end 1.1049 -0.724916)
			(stroke
				(width 0.1)
				(type default)
			)
			(layer "B.Fab")
		)
		(fp_line
			(start 1.1049 -0.724916)
			(end 1.1049 0.724916)
			(stroke
				(width 0.1)
				(type default)
			)
			(layer "B.Fab")
		)
		(pad "1" smd rect
			(at 0.889 0 270)
			(size 1.016 1.27)
			(layers "B.Cu" "B.Mask" "B.Paste")
			(net "PVCCFA_EHV_FIVRA_CPU0")
		)
		(pad "2" smd rect
			(at -0.889 0 270)
			(size 1.016 1.27)
			(layers "B.Cu" "B.Mask" "B.Paste")
			(net "GND")
		)
	)
	(footprint ""
		(layer "B.Cu")
		(at 190.80988 -130.266948 -90)
		(property "Reference" "R1473"
			(at 0 0 90)
			(layer "B.SilkS")
			(hide yes)
			(effects
				(font
					(size 1.27 1.27)
				)
				(justify mirror)
			)
		)
		(property "Value" ""
			(at 0 0 90)
			(layer "B.Fab")
			(effects
				(font
					(size 1.27 1.27)
				)
				(justify mirror)
			)
		)
		(duplicate_pad_numbers_are_jumpers no)
		(fp_line
			(start -0.7874 0.4064)
			(end 0.7874 0.4064)
			(stroke
				(width 0.1524)
				(type default)
			)
			(layer "B.SilkS")
		)
		(fp_line
			(start 0.7874 0.4064)
			(end 0.7874 -0.4064)
			(stroke
				(width 0.1524)
				(type default)
			)
			(layer "B.SilkS")
		)
		(fp_line
			(start -0.7874 -0.4064)
			(end -0.7874 0.4064)
			(stroke
				(width 0.1524)
				(type default)
			)
			(layer "B.SilkS")
		)
		(fp_line
			(start 0.7874 -0.4064)
			(end -0.7874 -0.4064)
			(stroke
				(width 0.1524)
				(type default)
			)
			(layer "B.SilkS")
		)
		(fp_line
			(start -0.67945 0.3048)
			(end -0.120396 0.3048)
			(stroke
				(width 0.1)
				(type default)
			)
			(layer "B.Fab")
		)
		(fp_line
			(start -0.120396 0.3048)
			(end -0.120396 0.2794)
			(stroke
				(width 0.1)
				(type default)
			)
			(layer "B.Fab")
		)
		(fp_line
			(start 0.12065 0.3048)
			(end 0.67945 0.3048)
			(stroke
				(width 0.1)
				(type default)
			)
			(layer "B.Fab")
		)
		(fp_line
			(start 0.67945 0.3048)
			(end 0.67945 -0.305054)
			(stroke
				(width 0.1)
				(type default)
			)
			(layer "B.Fab")
		)
		(fp_line
			(start -0.120396 0.2794)
			(end 0.12065 0.2794)
			(stroke
				(width 0.1)
				(type default)
			)
			(layer "B.Fab")
		)
		(fp_line
			(start 0.12065 0.2794)
			(end 0.12065 0.3048)
			(stroke
				(width 0.1)
				(type default)
			)
			(layer "B.Fab")
		)
		(fp_line
			(start -0.12065 -0.2794)
			(end -0.12065 -0.3048)
			(stroke
				(width 0.1)
				(type default)
			)
			(layer "B.Fab")
		)
		(fp_line
			(start 0.12065 -0.2794)
			(end -0.12065 -0.2794)
			(stroke
				(width 0.1)
				(type default)
			)
			(layer "B.Fab")
		)
		(fp_line
			(start -0.67945 -0.3048)
			(end -0.67945 0.3048)
			(stroke
				(width 0.1)
				(type default)
			)
			(layer "B.Fab")
		)
		(fp_line
			(start -0.12065 -0.3048)
			(end -0.67945 -0.3048)
			(stroke
				(width 0.1)
				(type default)
			)
			(layer "B.Fab")
		)
		(fp_line
			(start 0.12065 -0.305054)
			(end 0.12065 -0.2794)
			(stroke
				(width 0.1)
				(type default)
			)
			(layer "B.Fab")
		)
		(fp_line
			(start 0.67945 -0.305054)
			(end 0.12065 -0.305054)
			(stroke
				(width 0.1)
				(type default)
			)
			(layer "B.Fab")
		)
		(pad "1" smd circle
			(at 0.40005 0 90)
			(size 0 0)
			(layers "B.Cu" "B.Mask" "B.Paste")
			(net "FM_RST_PERST_BIT1")
		)
		(pad "2" smd circle
			(at -0.40005 0 90)
			(size 0 0)
			(layers "B.Cu" "B.Mask" "B.Paste")
			(net "P3V3_AUX")
		)
	)
	(footprint ""
		(layer "B.Cu")
		(at 447.771012 -58.325512 -90)
		(property "Reference" "PC1600"
			(at 0 0 90)
			(layer "B.SilkS")
			(hide yes)
			(effects
				(font
					(size 1.27 1.27)
				)
				(justify mirror)
			)
		)
		(property "Value" ""
			(at 0 0 90)
			(layer "B.Fab")
			(effects
				(font
					(size 1.27 1.27)
				)
				(justify mirror)
			)
		)
		(duplicate_pad_numbers_are_jumpers no)
		(fp_line
			(start -1.524 0.762)
			(end 1.524 0.762)
			(stroke
				(width 0.1524)
				(type default)
			)
			(layer "B.SilkS")
		)
		(fp_line
			(start 1.524 0.762)
			(end 1.524 -0.762)
			(stroke
				(width 0.1524)
				(type default)
			)
			(layer "B.SilkS")
		)
		(fp_line
			(start -1.524 -0.762)
			(end -1.524 0.762)
			(stroke
				(width 0.1524)
				(type default)
			)
			(layer "B.SilkS")
		)
		(fp_line
			(start 1.524 -0.762)
			(end -1.524 -0.762)
			(stroke
				(width 0.1524)
				(type default)
			)
			(layer "B.SilkS")
		)
		(fp_line
			(start -1.1049 0.724916)
			(end -1.1049 -0.724916)
			(stroke
				(width 0.1)
				(type default)
			)
			(layer "B.Fab")
		)
		(fp_line
			(start 1.1049 0.724916)
			(end -1.1049 0.724916)
			(stroke
				(width 0.1)
				(type default)
			)
			(layer "B.Fab")
		)
		(fp_line
			(start -1.1049 -0.724916)
			(end 1.1049 -0.724916)
			(stroke
				(width 0.1)
				(type default)
			)
			(layer "B.Fab")
		)
		(fp_line
			(start 1.1049 -0.724916)
			(end 1.1049 0.724916)
			(stroke
				(width 0.1)
				(type default)
			)
			(layer "B.Fab")
		)
		(pad "1" smd rect
			(at 0.889 0 270)
			(size 1.016 1.27)
			(layers "B.Cu" "B.Mask" "B.Paste")
			(net "P3V3_AUX")
		)
		(pad "2" smd rect
			(at -0.889 0 270)
			(size 1.016 1.27)
			(layers "B.Cu" "B.Mask" "B.Paste")
			(net "GND")
		)
	)
	(footprint ""
		(layer "B.Cu")
		(at 326.16648 -61.758068 -90)
		(property "Reference" "R1676"
			(at 0 0 90)
			(layer "B.SilkS")
			(hide yes)
			(effects
				(font
					(size 1.27 1.27)
				)
				(justify mirror)
			)
		)
		(property "Value" ""
			(at 0 0 90)
			(layer "B.Fab")
			(effects
				(font
					(size 1.27 1.27)
				)
				(justify mirror)
			)
		)
		(duplicate_pad_numbers_are_jumpers no)
		(fp_line
			(start -0.7874 0.4064)
			(end 0.7874 0.4064)
			(stroke
				(width 0.1524)
				(type default)
			)
			(layer "B.SilkS")
		)
		(fp_line
			(start 0.7874 0.4064)
			(end 0.7874 -0.4064)
			(stroke
				(width 0.1524)
				(type default)
			)
			(layer "B.SilkS")
		)
		(fp_line
			(start -0.7874 -0.4064)
			(end -0.7874 0.4064)
			(stroke
				(width 0.1524)
				(type default)
			)
			(layer "B.SilkS")
		)
		(fp_line
			(start 0.7874 -0.4064)
			(end -0.7874 -0.4064)
			(stroke
				(width 0.1524)
				(type default)
			)
			(layer "B.SilkS")
		)
		(fp_line
			(start -0.67945 0.3048)
			(end -0.120396 0.3048)
			(stroke
				(width 0.1)
				(type default)
			)
			(layer "B.Fab")
		)
		(fp_line
			(start -0.120396 0.3048)
			(end -0.120396 0.2794)
			(stroke
				(width 0.1)
				(type default)
			)
			(layer "B.Fab")
		)
		(fp_line
			(start 0.12065 0.3048)
			(end 0.67945 0.3048)
			(stroke
				(width 0.1)
				(type default)
			)
			(layer "B.Fab")
		)
		(fp_line
			(start 0.67945 0.3048)
			(end 0.67945 -0.305054)
			(stroke
				(width 0.1)
				(type default)
			)
			(layer "B.Fab")
		)
		(fp_line
			(start -0.120396 0.2794)
			(end 0.12065 0.2794)
			(stroke
				(width 0.1)
				(type default)
			)
			(layer "B.Fab")
		)
		(fp_line
			(start 0.12065 0.2794)
			(end 0.12065 0.3048)
			(stroke
				(width 0.1)
				(type default)
			)
			(layer "B.Fab")
		)
		(fp_line
			(start -0.12065 -0.2794)
			(end -0.12065 -0.3048)
			(stroke
				(width 0.1)
				(type default)
			)
			(layer "B.Fab")
		)
		(fp_line
			(start 0.12065 -0.2794)
			(end -0.12065 -0.2794)
			(stroke
				(width 0.1)
				(type default)
			)
			(layer "B.Fab")
		)
		(fp_line
			(start -0.67945 -0.3048)
			(end -0.67945 0.3048)
			(stroke
				(width 0.1)
				(type default)
			)
			(layer "B.Fab")
		)
		(fp_line
			(start -0.12065 -0.3048)
			(end -0.67945 -0.3048)
			(stroke
				(width 0.1)
				(type default)
			)
			(layer "B.Fab")
		)
		(fp_line
			(start 0.12065 -0.305054)
			(end 0.12065 -0.2794)
			(stroke
				(width 0.1)
				(type default)
			)
			(layer "B.Fab")
		)
		(fp_line
			(start 0.67945 -0.305054)
			(end 0.12065 -0.305054)
			(stroke
				(width 0.1)
				(type default)
			)
			(layer "B.Fab")
		)
		(pad "1" smd circle
			(at 0.40005 0 90)
			(size 0 0)
			(layers "B.Cu" "B.Mask" "B.Paste")
			(net "FM_PCIE_EV_BIF_EN")
		)
		(pad "2" smd circle
			(at -0.40005 0 90)
			(size 0 0)
			(layers "B.Cu" "B.Mask" "B.Paste")
			(net "GND")
		)
	)
	(footprint ""
		(layer "B.Cu")
		(at 428.164244 -122.085862 -90)
		(property "Reference" "PC813"
			(at 0 0 90)
			(layer "B.SilkS")
			(hide yes)
			(effects
				(font
					(size 1.27 1.27)
				)
				(justify mirror)
			)
		)
		(property "Value" ""
			(at 0 0 90)
			(layer "B.Fab")
			(effects
				(font
					(size 1.27 1.27)
				)
				(justify mirror)
			)
		)
		(duplicate_pad_numbers_are_jumpers no)
		(fp_line
			(start -0.7874 0.4064)
			(end 0.7874 0.4064)
			(stroke
				(width 0.1524)
				(type default)
			)
			(layer "B.SilkS")
		)
		(fp_line
			(start 0.7874 0.4064)
			(end 0.7874 -0.4064)
			(stroke
				(width 0.1524)
				(type default)
			)
			(layer "B.SilkS")
		)
		(fp_line
			(start -0.7874 -0.4064)
			(end -0.7874 0.4064)
			(stroke
				(width 0.1524)
				(type default)
			)
			(layer "B.SilkS")
		)
		(fp_line
			(start 0.7874 -0.4064)
			(end -0.7874 -0.4064)
			(stroke
				(width 0.1524)
				(type default)
			)
			(layer "B.SilkS")
		)
		(fp_line
			(start -0.67945 0.3048)
			(end -0.120396 0.3048)
			(stroke
				(width 0.1)
				(type default)
			)
			(layer "B.Fab")
		)
		(fp_line
			(start -0.120396 0.3048)
			(end -0.120396 0.2794)
			(stroke
				(width 0.1)
				(type default)
			)
			(layer "B.Fab")
		)
		(fp_line
			(start 0.12065 0.3048)
			(end 0.67945 0.3048)
			(stroke
				(width 0.1)
				(type default)
			)
			(layer "B.Fab")
		)
		(fp_line
			(start 0.67945 0.3048)
			(end 0.67945 -0.305054)
			(stroke
				(width 0.1)
				(type default)
			)
			(layer "B.Fab")
		)
		(fp_line
			(start -0.120396 0.2794)
			(end 0.12065 0.2794)
			(stroke
				(width 0.1)
				(type default)
			)
			(layer "B.Fab")
		)
		(fp_line
			(start 0.12065 0.2794)
			(end 0.12065 0.3048)
			(stroke
				(width 0.1)
				(type default)
			)
			(layer "B.Fab")
		)
		(fp_line
			(start -0.12065 -0.2794)
			(end -0.12065 -0.3048)
			(stroke
				(width 0.1)
				(type default)
			)
			(layer "B.Fab")
		)
		(fp_line
			(start 0.12065 -0.2794)
			(end -0.12065 -0.2794)
			(stroke
				(width 0.1)
				(type default)
			)
			(layer "B.Fab")
		)
		(fp_line
			(start -0.67945 -0.3048)
			(end -0.67945 0.3048)
			(stroke
				(width 0.1)
				(type default)
			)
			(layer "B.Fab")
		)
		(fp_line
			(start -0.12065 -0.3048)
			(end -0.67945 -0.3048)
			(stroke
				(width 0.1)
				(type default)
			)
			(layer "B.Fab")
		)
		(fp_line
			(start 0.12065 -0.305054)
			(end 0.12065 -0.2794)
			(stroke
				(width 0.1)
				(type default)
			)
			(layer "B.Fab")
		)
		(fp_line
			(start 0.67945 -0.305054)
			(end 0.12065 -0.305054)
			(stroke
				(width 0.1)
				(type default)
			)
			(layer "B.Fab")
		)
		(pad "1" smd circle
			(at 0.40005 0 90)
			(size 0 0)
			(layers "B.Cu" "B.Mask" "B.Paste")
			(net "PVCCD_HV_CPU0_ISENSE_N")
		)
		(pad "2" smd circle
			(at -0.40005 0 90)
			(size 0 0)
			(layers "B.Cu" "B.Mask" "B.Paste")
			(net "PVCCD_HV_CPU0_ISENSE_P")
		)
	)
	(footprint ""
		(layer "B.Cu")
		(at 121.773442 -356.200456 180)
		(property "Reference" "R2367"
			(at 0 0 0)
			(layer "B.SilkS")
			(hide yes)
			(effects
				(font
					(size 1.27 1.27)
				)
				(justify mirror)
			)
		)
		(property "Value" ""
			(at 0 0 0)
			(layer "B.Fab")
			(effects
				(font
					(size 1.27 1.27)
				)
				(justify mirror)
			)
		)
		(duplicate_pad_numbers_are_jumpers no)
		(fp_line
			(start 0.7874 0.4064)
			(end 0.7874 -0.4064)
			(stroke
				(width 0.1524)
				(type default)
			)
			(layer "B.SilkS")
		)
		(fp_line
			(start 0.7874 -0.4064)
			(end -0.7874 -0.4064)
			(stroke
				(width 0.1524)
				(type default)
			)
			(layer "B.SilkS")
		)
		(fp_line
			(start -0.7874 0.4064)
			(end 0.7874 0.4064)
			(stroke
				(width 0.1524)
				(type default)
			)
			(layer "B.SilkS")
		)
		(fp_line
			(start -0.7874 -0.4064)
			(end -0.7874 0.4064)
			(stroke
				(width 0.1524)
				(type default)
			)
			(layer "B.SilkS")
		)
		(fp_line
			(start 0.67945 0.3048)
			(end 0.67945 -0.305054)
			(stroke
				(width 0.1)
				(type default)
			)
			(layer "B.Fab")
		)
		(fp_line
			(start 0.67945 -0.305054)
			(end 0.12065 -0.305054)
			(stroke
				(width 0.1)
				(type default)
			)
			(layer "B.Fab")
		)
		(fp_line
			(start 0.12065 0.3048)
			(end 0.67945 0.3048)
			(stroke
				(width 0.1)
				(type default)
			)
			(layer "B.Fab")
		)
		(fp_line
			(start 0.12065 0.2794)
			(end 0.12065 0.3048)
			(stroke
				(width 0.1)
				(type default)
			)
			(layer "B.Fab")
		)
		(fp_line
			(start 0.12065 -0.2794)
			(end -0.12065 -0.2794)
			(stroke
				(width 0.1)
				(type default)
			)
			(layer "B.Fab")
		)
		(fp_line
			(start 0.12065 -0.305054)
			(end 0.12065 -0.2794)
			(stroke
				(width 0.1)
				(type default)
			)
			(layer "B.Fab")
		)
		(fp_line
			(start -0.120396 0.3048)
			(end -0.120396 0.2794)
			(stroke
				(width 0.1)
				(type default)
			)
			(layer "B.Fab")
		)
		(fp_line
			(start -0.120396 0.2794)
			(end 0.12065 0.2794)
			(stroke
				(width 0.1)
				(type default)
			)
			(layer "B.Fab")
		)
		(fp_line
			(start -0.12065 -0.2794)
			(end -0.12065 -0.3048)
			(stroke
				(width 0.1)
				(type default)
			)
			(layer "B.Fab")
		)
		(fp_line
			(start -0.12065 -0.3048)
			(end -0.67945 -0.3048)
			(stroke
				(width 0.1)
				(type default)
			)
			(layer "B.Fab")
		)
		(fp_line
			(start -0.67945 0.3048)
			(end -0.120396 0.3048)
			(stroke
				(width 0.1)
				(type default)
			)
			(layer "B.Fab")
		)
		(fp_line
			(start -0.67945 -0.3048)
			(end -0.67945 0.3048)
			(stroke
				(width 0.1)
				(type default)
			)
			(layer "B.Fab")
		)
		(pad "1" smd circle
			(at 0.40005 0)
			(size 0 0)
			(layers "B.Cu" "B.Mask" "B.Paste")
			(net "P3V3_AUX")
		)
		(pad "2" smd circle
			(at -0.40005 0)
			(size 0 0)
			(layers "B.Cu" "B.Mask" "B.Paste")
			(net "FM_PVPP_HBM_CPU1_EN")
		)
	)
	(footprint ""
		(layer "B.Cu")
		(at 178.9557 -115.775486 90)
		(property "Reference" "C1918"
			(at 0 0 90)
			(layer "B.SilkS")
			(hide yes)
			(effects
				(font
					(size 1.27 1.27)
				)
				(justify mirror)
			)
		)
		(property "Value" ""
			(at 0 0 90)
			(layer "B.Fab")
			(effects
				(font
					(size 1.27 1.27)
				)
				(justify mirror)
			)
		)
		(duplicate_pad_numbers_are_jumpers no)
		(fp_line
			(start 0.69215 -0.2921)
			(end -0.69215 -0.2921)
			(stroke
				(width 0.1524)
				(type default)
			)
			(layer "B.SilkS")
		)
		(fp_line
			(start -0.69215 -0.2921)
			(end -0.69215 0.2921)
			(stroke
				(width 0.1524)
				(type default)
			)
			(layer "B.SilkS")
		)
		(fp_line
			(start 0.69215 0.2921)
			(end 0.69215 -0.2921)
			(stroke
				(width 0.1524)
				(type default)
			)
			(layer "B.SilkS")
		)
		(fp_line
			(start -0.69215 0.2921)
			(end 0.69215 0.2921)
			(stroke
				(width 0.1524)
				(type default)
			)
			(layer "B.SilkS")
		)
		(fp_line
			(start 0.51435 -0.2794)
			(end -0.51435 -0.2794)
			(stroke
				(width 0.1)
				(type default)
			)
			(layer "B.Fab")
		)
		(fp_line
			(start -0.51435 -0.2794)
			(end -0.51435 0.2794)
			(stroke
				(width 0.1)
				(type default)
			)
			(layer "B.Fab")
		)
		(fp_line
			(start 0.51435 0.2794)
			(end 0.51435 -0.2794)
			(stroke
				(width 0.1)
				(type default)
			)
			(layer "B.Fab")
		)
		(fp_line
			(start -0.51435 0.2794)
			(end 0.51435 0.2794)
			(stroke
				(width 0.1)
				(type default)
			)
			(layer "B.Fab")
		)
		(pad "1" smd circle
			(at 0.40005 0 270)
			(size 0 0)
			(layers "B.Cu" "B.Mask" "B.Paste")
			(net "P3V3_AUX_FPGA_VCCIO1")
		)
		(pad "2" smd circle
			(at -0.40005 0 270)
			(size 0 0)
			(layers "B.Cu" "B.Mask" "B.Paste")
			(net "GND")
		)
		(zone
			(layer "B.Cu")
			(hatch none 0.5)
			(connect_pads
				(clearance 0)
			)
			(min_thickness 0.25)
			(keepout
				(tracks not_allowed)
				(vias allowed)
				(pads allowed)
				(copperpour not_allowed)
				(footprints allowed)
			)
			(placement
				(enabled no)
				(sheetname "")
			)
			(fill
				(thermal_gap 0.5)
				(thermal_bridge_width 0.5)
				(island_removal_mode 0)
			)
			(polygon
				(pts
					(xy 179.04333 -115.965986) (xy 179.101496 -115.874546) (xy 179.101496 -115.675156) (xy 179.04333 -115.584986)
					(xy 178.86807 -115.584986) (xy 178.80965 -115.675156) (xy 178.80965 -115.874546) (xy 178.867816 -115.965986)
				)
			)
		)
	)
	(footprint ""
		(layer "B.Cu")
		(at 203.047346 -77.009752)
		(property "Reference" "R3209"
			(at 0 0 0)
			(layer "B.SilkS")
			(hide yes)
			(effects
				(font
					(size 1.27 1.27)
				)
				(justify mirror)
			)
		)
		(property "Value" ""
			(at 0 0 0)
			(layer "B.Fab")
			(effects
				(font
					(size 1.27 1.27)
				)
				(justify mirror)
			)
		)
		(duplicate_pad_numbers_are_jumpers no)
		(fp_line
			(start -0.7874 -0.4064)
			(end -0.7874 0.4064)
			(stroke
				(width 0.1524)
				(type default)
			)
			(layer "B.SilkS")
		)
		(fp_line
			(start -0.7874 0.4064)
			(end 0.7874 0.4064)
			(stroke
				(width 0.1524)
				(type default)
			)
			(layer "B.SilkS")
		)
		(fp_line
			(start 0.7874 -0.4064)
			(end -0.7874 -0.4064)
			(stroke
				(width 0.1524)
				(type default)
			)
			(layer "B.SilkS")
		)
		(fp_line
			(start 0.7874 0.4064)
			(end 0.7874 -0.4064)
			(stroke
				(width 0.1524)
				(type default)
			)
			(layer "B.SilkS")
		)
		(fp_line
			(start -0.67945 -0.3048)
			(end -0.67945 0.3048)
			(stroke
				(width 0.1)
				(type default)
			)
			(layer "B.Fab")
		)
		(fp_line
			(start -0.67945 0.3048)
			(end -0.120396 0.3048)
			(stroke
				(width 0.1)
				(type default)
			)
			(layer "B.Fab")
		)
		(fp_line
			(start -0.12065 -0.3048)
			(end -0.67945 -0.3048)
			(stroke
				(width 0.1)
				(type default)
			)
			(layer "B.Fab")
		)
		(fp_line
			(start -0.12065 -0.2794)
			(end -0.12065 -0.3048)
			(stroke
				(width 0.1)
				(type default)
			)
			(layer "B.Fab")
		)
		(fp_line
			(start -0.120396 0.2794)
			(end 0.12065 0.2794)
			(stroke
				(width 0.1)
				(type default)
			)
			(layer "B.Fab")
		)
		(fp_line
			(start -0.120396 0.3048)
			(end -0.120396 0.2794)
			(stroke
				(width 0.1)
				(type default)
			)
			(layer "B.Fab")
		)
		(fp_line
			(start 0.12065 -0.305054)
			(end 0.12065 -0.2794)
			(stroke
				(width 0.1)
				(type default)
			)
			(layer "B.Fab")
		)
		(fp_line
			(start 0.12065 -0.2794)
			(end -0.12065 -0.2794)
			(stroke
				(width 0.1)
				(type default)
			)
			(layer "B.Fab")
		)
		(fp_line
			(start 0.12065 0.2794)
			(end 0.12065 0.3048)
			(stroke
				(width 0.1)
				(type default)
			)
			(layer "B.Fab")
		)
		(fp_line
			(start 0.12065 0.3048)
			(end 0.67945 0.3048)
			(stroke
				(width 0.1)
				(type default)
			)
			(layer "B.Fab")
		)
		(fp_line
			(start 0.67945 -0.305054)
			(end 0.12065 -0.305054)
			(stroke
				(width 0.1)
				(type default)
			)
			(layer "B.Fab")
		)
		(fp_line
			(start 0.67945 0.3048)
			(end 0.67945 -0.305054)
			(stroke
				(width 0.1)
				(type default)
			)
			(layer "B.Fab")
		)
		(pad "1" smd circle
			(at 0.40005 0 180)
			(size 0 0)
			(layers "B.Cu" "B.Mask" "B.Paste")
			(net "OCP_V3_2_RBT_ARB_IN_R")
		)
		(pad "2" smd circle
			(at -0.40005 0 180)
			(size 0 0)
			(layers "B.Cu" "B.Mask" "B.Paste")
			(net "OCP_V3_2_RBT_ARB_IN")
		)
	)
	(footprint ""
		(layer "B.Cu")
		(at 15.69085 -316.601094 90)
		(property "Reference" "R3898"
			(at 0 0 90)
			(layer "B.SilkS")
			(hide yes)
			(effects
				(font
					(size 1.27 1.27)
				)
				(justify mirror)
			)
		)
		(property "Value" ""
			(at 0 0 90)
			(layer "B.Fab")
			(effects
				(font
					(size 1.27 1.27)
				)
				(justify mirror)
			)
		)
		(duplicate_pad_numbers_are_jumpers no)
		(fp_line
			(start 0.7874 -0.4064)
			(end -0.7874 -0.4064)
			(stroke
				(width 0.1524)
				(type default)
			)
			(layer "B.SilkS")
		)
		(fp_line
			(start -0.7874 -0.4064)
			(end -0.7874 0.4064)
			(stroke
				(width 0.1524)
				(type default)
			)
			(layer "B.SilkS")
		)
		(fp_line
			(start 0.7874 0.4064)
			(end 0.7874 -0.4064)
			(stroke
				(width 0.1524)
				(type default)
			)
			(layer "B.SilkS")
		)
		(fp_line
			(start -0.7874 0.4064)
			(end 0.7874 0.4064)
			(stroke
				(width 0.1524)
				(type default)
			)
			(layer "B.SilkS")
		)
		(fp_line
			(start 0.67945 -0.305054)
			(end 0.12065 -0.305054)
			(stroke
				(width 0.1)
				(type default)
			)
			(layer "B.Fab")
		)
		(fp_line
			(start 0.12065 -0.305054)
			(end 0.12065 -0.2794)
			(stroke
				(width 0.1)
				(type default)
			)
			(layer "B.Fab")
		)
		(fp_line
			(start -0.12065 -0.3048)
			(end -0.67945 -0.3048)
			(stroke
				(width 0.1)
				(type default)
			)
			(layer "B.Fab")
		)
		(fp_line
			(start -0.67945 -0.3048)
			(end -0.67945 0.3048)
			(stroke
				(width 0.1)
				(type default)
			)
			(layer "B.Fab")
		)
		(fp_line
			(start 0.12065 -0.2794)
			(end -0.12065 -0.2794)
			(stroke
				(width 0.1)
				(type default)
			)
			(layer "B.Fab")
		)
		(fp_line
			(start -0.12065 -0.2794)
			(end -0.12065 -0.3048)
			(stroke
				(width 0.1)
				(type default)
			)
			(layer "B.Fab")
		)
		(fp_line
			(start 0.12065 0.2794)
			(end 0.12065 0.3048)
			(stroke
				(width 0.1)
				(type default)
			)
			(layer "B.Fab")
		)
		(fp_line
			(start -0.120396 0.2794)
			(end 0.12065 0.2794)
			(stroke
				(width 0.1)
				(type default)
			)
			(layer "B.Fab")
		)
		(fp_line
			(start 0.67945 0.3048)
			(end 0.67945 -0.305054)
			(stroke
				(width 0.1)
				(type default)
			)
			(layer "B.Fab")
		)
		(fp_line
			(start 0.12065 0.3048)
			(end 0.67945 0.3048)
			(stroke
				(width 0.1)
				(type default)
			)
			(layer "B.Fab")
		)
		(fp_line
			(start -0.120396 0.3048)
			(end -0.120396 0.2794)
			(stroke
				(width 0.1)
				(type default)
			)
			(layer "B.Fab")
		)
		(fp_line
			(start -0.67945 0.3048)
			(end -0.120396 0.3048)
			(stroke
				(width 0.1)
				(type default)
			)
			(layer "B.Fab")
		)
		(pad "1" smd circle
			(at 0.40005 0 270)
			(size 0 0)
			(layers "B.Cu" "B.Mask" "B.Paste")
			(net "I3C_SPD_DDRABCD_CPU1_LVC1_SCL_7")
		)
		(pad "2" smd circle
			(at -0.40005 0 270)
			(size 0 0)
			(layers "B.Cu" "B.Mask" "B.Paste")
			(net "I3C_SPD_DDRABCD_CPU1_LVC1_SCL")
		)
	)
	(footprint ""
		(layer "B.Cu")
		(at 352.68027 -59.737752)
		(property "Reference" "R498"
			(at 0 0 0)
			(layer "B.SilkS")
			(hide yes)
			(effects
				(font
					(size 1.27 1.27)
				)
				(justify mirror)
			)
		)
		(property "Value" ""
			(at 0 0 0)
			(layer "B.Fab")
			(effects
				(font
					(size 1.27 1.27)
				)
				(justify mirror)
			)
		)
		(duplicate_pad_numbers_are_jumpers no)
		(fp_line
			(start -0.7874 -0.4064)
			(end -0.7874 0.4064)
			(stroke
				(width 0.1524)
				(type default)
			)
			(layer "B.SilkS")
		)
		(fp_line
			(start -0.7874 0.4064)
			(end 0.7874 0.4064)
			(stroke
				(width 0.1524)
				(type default)
			)
			(layer "B.SilkS")
		)
		(fp_line
			(start 0.7874 -0.4064)
			(end -0.7874 -0.4064)
			(stroke
				(width 0.1524)
				(type default)
			)
			(layer "B.SilkS")
		)
		(fp_line
			(start 0.7874 0.4064)
			(end 0.7874 -0.4064)
			(stroke
				(width 0.1524)
				(type default)
			)
			(layer "B.SilkS")
		)
		(fp_line
			(start -0.67945 -0.3048)
			(end -0.67945 0.3048)
			(stroke
				(width 0.1)
				(type default)
			)
			(layer "B.Fab")
		)
		(fp_line
			(start -0.67945 0.3048)
			(end -0.120396 0.3048)
			(stroke
				(width 0.1)
				(type default)
			)
			(layer "B.Fab")
		)
		(fp_line
			(start -0.12065 -0.3048)
			(end -0.67945 -0.3048)
			(stroke
				(width 0.1)
				(type default)
			)
			(layer "B.Fab")
		)
		(fp_line
			(start -0.12065 -0.2794)
			(end -0.12065 -0.3048)
			(stroke
				(width 0.1)
				(type default)
			)
			(layer "B.Fab")
		)
		(fp_line
			(start -0.120396 0.2794)
			(end 0.12065 0.2794)
			(stroke
				(width 0.1)
				(type default)
			)
			(layer "B.Fab")
		)
		(fp_line
			(start -0.120396 0.3048)
			(end -0.120396 0.2794)
			(stroke
				(width 0.1)
				(type default)
			)
			(layer "B.Fab")
		)
		(fp_line
			(start 0.12065 -0.305054)
			(end 0.12065 -0.2794)
			(stroke
				(width 0.1)
				(type default)
			)
			(layer "B.Fab")
		)
		(fp_line
			(start 0.12065 -0.2794)
			(end -0.12065 -0.2794)
			(stroke
				(width 0.1)
				(type default)
			)
			(layer "B.Fab")
		)
		(fp_line
			(start 0.12065 0.2794)
			(end 0.12065 0.3048)
			(stroke
				(width 0.1)
				(type default)
			)
			(layer "B.Fab")
		)
		(fp_line
			(start 0.12065 0.3048)
			(end 0.67945 0.3048)
			(stroke
				(width 0.1)
				(type default)
			)
			(layer "B.Fab")
		)
		(fp_line
			(start 0.67945 -0.305054)
			(end 0.12065 -0.305054)
			(stroke
				(width 0.1)
				(type default)
			)
			(layer "B.Fab")
		)
		(fp_line
			(start 0.67945 0.3048)
			(end 0.67945 -0.305054)
			(stroke
				(width 0.1)
				(type default)
			)
			(layer "B.Fab")
		)
		(pad "1" smd circle
			(at 0.40005 0 180)
			(size 0 0)
			(layers "B.Cu" "B.Mask" "B.Paste")
			(net "P3V3_AUX")
		)
		(pad "2" smd circle
			(at -0.40005 0 180)
			(size 0 0)
			(layers "B.Cu" "B.Mask" "B.Paste")
			(net "FM_PCH_PRSNT_N")
		)
	)
	(footprint ""
		(layer "B.Cu")
		(at 131.93522 -24.895048 180)
		(property "Reference" "C2290"
			(at 0 0 0)
			(layer "B.SilkS")
			(hide yes)
			(effects
				(font
					(size 1.27 1.27)
				)
				(justify mirror)
			)
		)
		(property "Value" ""
			(at 0 0 0)
			(layer "B.Fab")
			(effects
				(font
					(size 1.27 1.27)
				)
				(justify mirror)
			)
		)
		(duplicate_pad_numbers_are_jumpers no)
		(fp_line
			(start 0.299974 0.150114)
			(end 0.299974 -0.150114)
			(stroke
				(width 0.1)
				(type default)
			)
			(layer "B.Fab")
		)
		(fp_line
			(start 0.299974 -0.150114)
			(end -0.299974 -0.150114)
			(stroke
				(width 0.1)
				(type default)
			)
			(layer "B.Fab")
		)
		(fp_line
			(start -0.299974 0.150114)
			(end 0.299974 0.150114)
			(stroke
				(width 0.1)
				(type default)
			)
			(layer "B.Fab")
		)
		(fp_line
			(start -0.299974 -0.150114)
			(end -0.299974 0.150114)
			(stroke
				(width 0.1)
				(type default)
			)
			(layer "B.Fab")
		)
		(pad "1" smd rect
			(at 0.2667 0)
			(size 0.3048 0.381)
			(layers "B.Cu" "B.Mask" "B.Paste")
			(net "USB3_PCH_TX_BUF_DN<4>")
		)
		(pad "2" smd rect
			(at -0.2667 0)
			(size 0.3048 0.381)
			(layers "B.Cu" "B.Mask" "B.Paste")
			(net "USB3_PCH_TX_BUF_C_DN<4>")
		)
	)
	(footprint ""
		(layer "B.Cu")
		(at 73.316084 -190.719456 -90)
		(property "Reference" "R559"
			(at 0 0 90)
			(layer "B.SilkS")
			(hide yes)
			(effects
				(font
					(size 1.27 1.27)
				)
				(justify mirror)
			)
		)
		(property "Value" ""
			(at 0 0 90)
			(layer "B.Fab")
			(effects
				(font
					(size 1.27 1.27)
				)
				(justify mirror)
			)
		)
		(duplicate_pad_numbers_are_jumpers no)
		(fp_line
			(start -0.7874 0.4064)
			(end 0.7874 0.4064)
			(stroke
				(width 0.1524)
				(type default)
			)
			(layer "B.SilkS")
		)
		(fp_line
			(start 0.7874 0.4064)
			(end 0.7874 -0.4064)
			(stroke
				(width 0.1524)
				(type default)
			)
			(layer "B.SilkS")
		)
		(fp_line
			(start -0.7874 -0.4064)
			(end -0.7874 0.4064)
			(stroke
				(width 0.1524)
				(type default)
			)
			(layer "B.SilkS")
		)
		(fp_line
			(start 0.7874 -0.4064)
			(end -0.7874 -0.4064)
			(stroke
				(width 0.1524)
				(type default)
			)
			(layer "B.SilkS")
		)
		(fp_line
			(start -0.67945 0.3048)
			(end -0.120396 0.3048)
			(stroke
				(width 0.1)
				(type default)
			)
			(layer "B.Fab")
		)
		(fp_line
			(start -0.120396 0.3048)
			(end -0.120396 0.2794)
			(stroke
				(width 0.1)
				(type default)
			)
			(layer "B.Fab")
		)
		(fp_line
			(start 0.12065 0.3048)
			(end 0.67945 0.3048)
			(stroke
				(width 0.1)
				(type default)
			)
			(layer "B.Fab")
		)
		(fp_line
			(start 0.67945 0.3048)
			(end 0.67945 -0.305054)
			(stroke
				(width 0.1)
				(type default)
			)
			(layer "B.Fab")
		)
		(fp_line
			(start -0.120396 0.2794)
			(end 0.12065 0.2794)
			(stroke
				(width 0.1)
				(type default)
			)
			(layer "B.Fab")
		)
		(fp_line
			(start 0.12065 0.2794)
			(end 0.12065 0.3048)
			(stroke
				(width 0.1)
				(type default)
			)
			(layer "B.Fab")
		)
		(fp_line
			(start -0.12065 -0.2794)
			(end -0.12065 -0.3048)
			(stroke
				(width 0.1)
				(type default)
			)
			(layer "B.Fab")
		)
		(fp_line
			(start 0.12065 -0.2794)
			(end -0.12065 -0.2794)
			(stroke
				(width 0.1)
				(type default)
			)
			(layer "B.Fab")
		)
		(fp_line
			(start -0.67945 -0.3048)
			(end -0.67945 0.3048)
			(stroke
				(width 0.1)
				(type default)
			)
			(layer "B.Fab")
		)
		(fp_line
			(start -0.12065 -0.3048)
			(end -0.67945 -0.3048)
			(stroke
				(width 0.1)
				(type default)
			)
			(layer "B.Fab")
		)
		(fp_line
			(start 0.12065 -0.305054)
			(end 0.12065 -0.2794)
			(stroke
				(width 0.1)
				(type default)
			)
			(layer "B.Fab")
		)
		(fp_line
			(start 0.67945 -0.305054)
			(end 0.12065 -0.305054)
			(stroke
				(width 0.1)
				(type default)
			)
			(layer "B.Fab")
		)
		(pad "1" smd circle
			(at 0.40005 0 90)
			(size 0 0)
			(layers "B.Cu" "B.Mask" "B.Paste")
			(net "SVID_DIO1_CPU1_R")
		)
		(pad "2" smd circle
			(at -0.40005 0 90)
			(size 0 0)
			(layers "B.Cu" "B.Mask" "B.Paste")
			(net "PVNN_TERM_CPU1")
		)
	)
	(footprint ""
		(layer "B.Cu")
		(at 60.978288 -250.767596 90)
		(property "Reference" "C462"
			(at 0 0 90)
			(layer "B.SilkS")
			(hide yes)
			(effects
				(font
					(size 1.27 1.27)
				)
				(justify mirror)
			)
		)
		(property "Value" ""
			(at 0 0 90)
			(layer "B.Fab")
			(effects
				(font
					(size 1.27 1.27)
				)
				(justify mirror)
			)
		)
		(duplicate_pad_numbers_are_jumpers no)
		(fp_line
			(start 1.524 -0.762)
			(end -1.524 -0.762)
			(stroke
				(width 0.1524)
				(type default)
			)
			(layer "B.SilkS")
		)
		(fp_line
			(start -1.524 -0.762)
			(end -1.524 0.762)
			(stroke
				(width 0.1524)
				(type default)
			)
			(layer "B.SilkS")
		)
		(fp_line
			(start 1.524 0.762)
			(end 1.524 -0.762)
			(stroke
				(width 0.1524)
				(type default)
			)
			(layer "B.SilkS")
		)
		(fp_line
			(start -1.524 0.762)
			(end 1.524 0.762)
			(stroke
				(width 0.1524)
				(type default)
			)
			(layer "B.SilkS")
		)
		(fp_line
			(start 1.1049 -0.724916)
			(end 1.1049 0.724916)
			(stroke
				(width 0.1)
				(type default)
			)
			(layer "B.Fab")
		)
		(fp_line
			(start -1.1049 -0.724916)
			(end 1.1049 -0.724916)
			(stroke
				(width 0.1)
				(type default)
			)
			(layer "B.Fab")
		)
		(fp_line
			(start 1.1049 0.724916)
			(end -1.1049 0.724916)
			(stroke
				(width 0.1)
				(type default)
			)
			(layer "B.Fab")
		)
		(fp_line
			(start -1.1049 0.724916)
			(end -1.1049 -0.724916)
			(stroke
				(width 0.1)
				(type default)
			)
			(layer "B.Fab")
		)
		(pad "1" smd rect
			(at 0.889 0 90)
			(size 1.016 1.27)
			(layers "B.Cu" "B.Mask" "B.Paste")
			(net "PVCCFA_EHV_FIVRA_CPU1")
		)
		(pad "2" smd rect
			(at -0.889 0 90)
			(size 1.016 1.27)
			(layers "B.Cu" "B.Mask" "B.Paste")
			(net "GND")
		)
	)
	(footprint ""
		(layer "B.Cu")
		(at 193.065146 -321.554856 -90)
		(property "Reference" "C79"
			(at 0 0 90)
			(layer "B.SilkS")
			(hide yes)
			(effects
				(font
					(size 1.27 1.27)
				)
				(justify mirror)
			)
		)
		(property "Value" ""
			(at 0 0 90)
			(layer "B.Fab")
			(effects
				(font
					(size 1.27 1.27)
				)
				(justify mirror)
			)
		)
		(duplicate_pad_numbers_are_jumpers no)
		(fp_line
			(start -1.524 0.762)
			(end 1.524 0.762)
			(stroke
				(width 0.1524)
				(type default)
			)
			(layer "B.SilkS")
		)
		(fp_line
			(start 1.524 0.762)
			(end 1.524 -0.762)
			(stroke
				(width 0.1524)
				(type default)
			)
			(layer "B.SilkS")
		)
		(fp_line
			(start -1.524 -0.762)
			(end -1.524 0.762)
			(stroke
				(width 0.1524)
				(type default)
			)
			(layer "B.SilkS")
		)
		(fp_line
			(start 1.524 -0.762)
			(end -1.524 -0.762)
			(stroke
				(width 0.1524)
				(type default)
			)
			(layer "B.SilkS")
		)
		(fp_line
			(start -1.1049 0.724916)
			(end -1.1049 -0.724916)
			(stroke
				(width 0.1)
				(type default)
			)
			(layer "B.Fab")
		)
		(fp_line
			(start 1.1049 0.724916)
			(end -1.1049 0.724916)
			(stroke
				(width 0.1)
				(type default)
			)
			(layer "B.Fab")
		)
		(fp_line
			(start -1.1049 -0.724916)
			(end 1.1049 -0.724916)
			(stroke
				(width 0.1)
				(type default)
			)
			(layer "B.Fab")
		)
		(fp_line
			(start 1.1049 -0.724916)
			(end 1.1049 0.724916)
			(stroke
				(width 0.1)
				(type default)
			)
			(layer "B.Fab")
		)
		(pad "1" smd rect
			(at 0.889 0 270)
			(size 1.016 1.27)
			(layers "B.Cu" "B.Mask" "B.Paste")
			(net "P12V_S3_AUX_CPU1_NVDIMM")
		)
		(pad "2" smd rect
			(at -0.889 0 270)
			(size 1.016 1.27)
			(layers "B.Cu" "B.Mask" "B.Paste")
			(net "GND")
		)
	)
	(footprint ""
		(layer "B.Cu")
		(at 100.306886 -356.63759)
		(property "Reference" "R2553"
			(at 0 0 0)
			(layer "B.SilkS")
			(hide yes)
			(effects
				(font
					(size 1.27 1.27)
				)
				(justify mirror)
			)
		)
		(property "Value" ""
			(at 0 0 0)
			(layer "B.Fab")
			(effects
				(font
					(size 1.27 1.27)
				)
				(justify mirror)
			)
		)
		(duplicate_pad_numbers_are_jumpers no)
		(fp_line
			(start -0.7874 -0.4064)
			(end -0.7874 0.4064)
			(stroke
				(width 0.1524)
				(type default)
			)
			(layer "B.SilkS")
		)
		(fp_line
			(start -0.7874 0.4064)
			(end 0.7874 0.4064)
			(stroke
				(width 0.1524)
				(type default)
			)
			(layer "B.SilkS")
		)
		(fp_line
			(start 0.7874 -0.4064)
			(end -0.7874 -0.4064)
			(stroke
				(width 0.1524)
				(type default)
			)
			(layer "B.SilkS")
		)
		(fp_line
			(start 0.7874 0.4064)
			(end 0.7874 -0.4064)
			(stroke
				(width 0.1524)
				(type default)
			)
			(layer "B.SilkS")
		)
		(fp_line
			(start -0.67945 -0.3048)
			(end -0.67945 0.3048)
			(stroke
				(width 0.1)
				(type default)
			)
			(layer "B.Fab")
		)
		(fp_line
			(start -0.67945 0.3048)
			(end -0.120396 0.3048)
			(stroke
				(width 0.1)
				(type default)
			)
			(layer "B.Fab")
		)
		(fp_line
			(start -0.12065 -0.3048)
			(end -0.67945 -0.3048)
			(stroke
				(width 0.1)
				(type default)
			)
			(layer "B.Fab")
		)
		(fp_line
			(start -0.12065 -0.2794)
			(end -0.12065 -0.3048)
			(stroke
				(width 0.1)
				(type default)
			)
			(layer "B.Fab")
		)
		(fp_line
			(start -0.120396 0.2794)
			(end 0.12065 0.2794)
			(stroke
				(width 0.1)
				(type default)
			)
			(layer "B.Fab")
		)
		(fp_line
			(start -0.120396 0.3048)
			(end -0.120396 0.2794)
			(stroke
				(width 0.1)
				(type default)
			)
			(layer "B.Fab")
		)
		(fp_line
			(start 0.12065 -0.305054)
			(end 0.12065 -0.2794)
			(stroke
				(width 0.1)
				(type default)
			)
			(layer "B.Fab")
		)
		(fp_line
			(start 0.12065 -0.2794)
			(end -0.12065 -0.2794)
			(stroke
				(width 0.1)
				(type default)
			)
			(layer "B.Fab")
		)
		(fp_line
			(start 0.12065 0.2794)
			(end 0.12065 0.3048)
			(stroke
				(width 0.1)
				(type default)
			)
			(layer "B.Fab")
		)
		(fp_line
			(start 0.12065 0.3048)
			(end 0.67945 0.3048)
			(stroke
				(width 0.1)
				(type default)
			)
			(layer "B.Fab")
		)
		(fp_line
			(start 0.67945 -0.305054)
			(end 0.12065 -0.305054)
			(stroke
				(width 0.1)
				(type default)
			)
			(layer "B.Fab")
		)
		(fp_line
			(start 0.67945 0.3048)
			(end 0.67945 -0.305054)
			(stroke
				(width 0.1)
				(type default)
			)
			(layer "B.Fab")
		)
		(pad "1" smd circle
			(at 0.40005 0 180)
			(size 0 0)
			(layers "B.Cu" "B.Mask" "B.Paste")
			(net "SVID_DIO0_CPU1_R")
		)
		(pad "2" smd circle
			(at -0.40005 0 180)
			(size 0 0)
			(layers "B.Cu" "B.Mask" "B.Paste")
			(net "PVNN_TERM_CPU1")
		)
	)
	(footprint ""
		(layer "B.Cu")
		(at 118.18112 -248.49836 -90)
		(property "Reference" "C323"
			(at 0 0 90)
			(layer "B.SilkS")
			(hide yes)
			(effects
				(font
					(size 1.27 1.27)
				)
				(justify mirror)
			)
		)
		(property "Value" ""
			(at 0 0 90)
			(layer "B.Fab")
			(effects
				(font
					(size 1.27 1.27)
				)
				(justify mirror)
			)
		)
		(duplicate_pad_numbers_are_jumpers no)
		(fp_line
			(start -1.524 0.762)
			(end 1.524 0.762)
			(stroke
				(width 0.1524)
				(type default)
			)
			(layer "B.SilkS")
		)
		(fp_line
			(start 1.524 0.762)
			(end 1.524 -0.762)
			(stroke
				(width 0.1524)
				(type default)
			)
			(layer "B.SilkS")
		)
		(fp_line
			(start -1.524 -0.762)
			(end -1.524 0.762)
			(stroke
				(width 0.1524)
				(type default)
			)
			(layer "B.SilkS")
		)
		(fp_line
			(start 1.524 -0.762)
			(end -1.524 -0.762)
			(stroke
				(width 0.1524)
				(type default)
			)
			(layer "B.SilkS")
		)
		(fp_line
			(start -1.1049 0.724916)
			(end -1.1049 -0.724916)
			(stroke
				(width 0.1)
				(type default)
			)
			(layer "B.Fab")
		)
		(fp_line
			(start 1.1049 0.724916)
			(end -1.1049 0.724916)
			(stroke
				(width 0.1)
				(type default)
			)
			(layer "B.Fab")
		)
		(fp_line
			(start -1.1049 -0.724916)
			(end 1.1049 -0.724916)
			(stroke
				(width 0.1)
				(type default)
			)
			(layer "B.Fab")
		)
		(fp_line
			(start 1.1049 -0.724916)
			(end 1.1049 0.724916)
			(stroke
				(width 0.1)
				(type default)
			)
			(layer "B.Fab")
		)
		(pad "1" smd rect
			(at 0.889 0 270)
			(size 1.016 1.27)
			(layers "B.Cu" "B.Mask" "B.Paste")
			(net "PVCCIN_CPU1")
		)
		(pad "2" smd rect
			(at -0.889 0 270)
			(size 1.016 1.27)
			(layers "B.Cu" "B.Mask" "B.Paste")
			(net "GND")
		)
	)
	(footprint ""
		(layer "B.Cu")
		(at 341.272114 -30.636972 180)
		(property "Reference" "R1306"
			(at 0 0 0)
			(layer "B.SilkS")
			(hide yes)
			(effects
				(font
					(size 1.27 1.27)
				)
				(justify mirror)
			)
		)
		(property "Value" ""
			(at 0 0 0)
			(layer "B.Fab")
			(effects
				(font
					(size 1.27 1.27)
				)
				(justify mirror)
			)
		)
		(duplicate_pad_numbers_are_jumpers no)
		(fp_line
			(start 0.7874 0.4064)
			(end 0.7874 -0.4064)
			(stroke
				(width 0.1524)
				(type default)
			)
			(layer "B.SilkS")
		)
		(fp_line
			(start 0.7874 -0.4064)
			(end -0.7874 -0.4064)
			(stroke
				(width 0.1524)
				(type default)
			)
			(layer "B.SilkS")
		)
		(fp_line
			(start -0.7874 0.4064)
			(end 0.7874 0.4064)
			(stroke
				(width 0.1524)
				(type default)
			)
			(layer "B.SilkS")
		)
		(fp_line
			(start -0.7874 -0.4064)
			(end -0.7874 0.4064)
			(stroke
				(width 0.1524)
				(type default)
			)
			(layer "B.SilkS")
		)
		(fp_line
			(start 0.67945 0.3048)
			(end 0.67945 -0.305054)
			(stroke
				(width 0.1)
				(type default)
			)
			(layer "B.Fab")
		)
		(fp_line
			(start 0.67945 -0.305054)
			(end 0.12065 -0.305054)
			(stroke
				(width 0.1)
				(type default)
			)
			(layer "B.Fab")
		)
		(fp_line
			(start 0.12065 0.3048)
			(end 0.67945 0.3048)
			(stroke
				(width 0.1)
				(type default)
			)
			(layer "B.Fab")
		)
		(fp_line
			(start 0.12065 0.2794)
			(end 0.12065 0.3048)
			(stroke
				(width 0.1)
				(type default)
			)
			(layer "B.Fab")
		)
		(fp_line
			(start 0.12065 -0.2794)
			(end -0.12065 -0.2794)
			(stroke
				(width 0.1)
				(type default)
			)
			(layer "B.Fab")
		)
		(fp_line
			(start 0.12065 -0.305054)
			(end 0.12065 -0.2794)
			(stroke
				(width 0.1)
				(type default)
			)
			(layer "B.Fab")
		)
		(fp_line
			(start -0.120396 0.3048)
			(end -0.120396 0.2794)
			(stroke
				(width 0.1)
				(type default)
			)
			(layer "B.Fab")
		)
		(fp_line
			(start -0.120396 0.2794)
			(end 0.12065 0.2794)
			(stroke
				(width 0.1)
				(type default)
			)
			(layer "B.Fab")
		)
		(fp_line
			(start -0.12065 -0.2794)
			(end -0.12065 -0.3048)
			(stroke
				(width 0.1)
				(type default)
			)
			(layer "B.Fab")
		)
		(fp_line
			(start -0.12065 -0.3048)
			(end -0.67945 -0.3048)
			(stroke
				(width 0.1)
				(type default)
			)
			(layer "B.Fab")
		)
		(fp_line
			(start -0.67945 0.3048)
			(end -0.120396 0.3048)
			(stroke
				(width 0.1)
				(type default)
			)
			(layer "B.Fab")
		)
		(fp_line
			(start -0.67945 -0.3048)
			(end -0.67945 0.3048)
			(stroke
				(width 0.1)
				(type default)
			)
			(layer "B.Fab")
		)
		(pad "1" smd circle
			(at 0.40005 0)
			(size 0 0)
			(layers "B.Cu" "B.Mask" "B.Paste")
			(net "FM_PS_PWROK_DLY_R_SEL")
		)
		(pad "2" smd circle
			(at -0.40005 0)
			(size 0 0)
			(layers "B.Cu" "B.Mask" "B.Paste")
			(net "FM_PS_PWROK_DLY_SEL")
		)
	)
	(footprint ""
		(layer "B.Cu")
		(at 396.97406 -61.448188 90)
		(property "Reference" "C550"
			(at 0 0 90)
			(layer "B.SilkS")
			(hide yes)
			(effects
				(font
					(size 1.27 1.27)
				)
				(justify mirror)
			)
		)
		(property "Value" ""
			(at 0 0 90)
			(layer "B.Fab")
			(effects
				(font
					(size 1.27 1.27)
				)
				(justify mirror)
			)
		)
		(duplicate_pad_numbers_are_jumpers no)
		(fp_line
			(start 0.7874 -0.4064)
			(end -0.7874 -0.4064)
			(stroke
				(width 0.1524)
				(type default)
			)
			(layer "B.SilkS")
		)
		(fp_line
			(start -0.7874 -0.4064)
			(end -0.7874 0.4064)
			(stroke
				(width 0.1524)
				(type default)
			)
			(layer "B.SilkS")
		)
		(fp_line
			(start 0.7874 0.4064)
			(end 0.7874 -0.4064)
			(stroke
				(width 0.1524)
				(type default)
			)
			(layer "B.SilkS")
		)
		(fp_line
			(start -0.7874 0.4064)
			(end 0.7874 0.4064)
			(stroke
				(width 0.1524)
				(type default)
			)
			(layer "B.SilkS")
		)
		(fp_line
			(start 0.67945 -0.305054)
			(end 0.12065 -0.305054)
			(stroke
				(width 0.1)
				(type default)
			)
			(layer "B.Fab")
		)
		(fp_line
			(start 0.12065 -0.305054)
			(end 0.12065 -0.2794)
			(stroke
				(width 0.1)
				(type default)
			)
			(layer "B.Fab")
		)
		(fp_line
			(start -0.12065 -0.3048)
			(end -0.67945 -0.3048)
			(stroke
				(width 0.1)
				(type default)
			)
			(layer "B.Fab")
		)
		(fp_line
			(start -0.67945 -0.3048)
			(end -0.67945 0.3048)
			(stroke
				(width 0.1)
				(type default)
			)
			(layer "B.Fab")
		)
		(fp_line
			(start 0.12065 -0.2794)
			(end -0.12065 -0.2794)
			(stroke
				(width 0.1)
				(type default)
			)
			(layer "B.Fab")
		)
		(fp_line
			(start -0.12065 -0.2794)
			(end -0.12065 -0.3048)
			(stroke
				(width 0.1)
				(type default)
			)
			(layer "B.Fab")
		)
		(fp_line
			(start 0.12065 0.2794)
			(end 0.12065 0.3048)
			(stroke
				(width 0.1)
				(type default)
			)
			(layer "B.Fab")
		)
		(fp_line
			(start -0.120396 0.2794)
			(end 0.12065 0.2794)
			(stroke
				(width 0.1)
				(type default)
			)
			(layer "B.Fab")
		)
		(fp_line
			(start 0.67945 0.3048)
			(end 0.67945 -0.305054)
			(stroke
				(width 0.1)
				(type default)
			)
			(layer "B.Fab")
		)
		(fp_line
			(start 0.12065 0.3048)
			(end 0.67945 0.3048)
			(stroke
				(width 0.1)
				(type default)
			)
			(layer "B.Fab")
		)
		(fp_line
			(start -0.120396 0.3048)
			(end -0.120396 0.2794)
			(stroke
				(width 0.1)
				(type default)
			)
			(layer "B.Fab")
		)
		(fp_line
			(start -0.67945 0.3048)
			(end -0.120396 0.3048)
			(stroke
				(width 0.1)
				(type default)
			)
			(layer "B.Fab")
		)
		(pad "1" smd circle
			(at 0.40005 0 270)
			(size 0 0)
			(layers "B.Cu" "B.Mask" "B.Paste")
			(net "P1V8_PCH_AUX")
		)
		(pad "2" smd circle
			(at -0.40005 0 270)
			(size 0 0)
			(layers "B.Cu" "B.Mask" "B.Paste")
			(net "GND")
		)
	)
	(footprint ""
		(layer "B.Cu")
		(at 166.165784 -316.592458 90)
		(property "Reference" "R3899"
			(at 0 0 90)
			(layer "B.SilkS")
			(hide yes)
			(effects
				(font
					(size 1.27 1.27)
				)
				(justify mirror)
			)
		)
		(property "Value" ""
			(at 0 0 90)
			(layer "B.Fab")
			(effects
				(font
					(size 1.27 1.27)
				)
				(justify mirror)
			)
		)
		(duplicate_pad_numbers_are_jumpers no)
		(fp_line
			(start 0.7874 -0.4064)
			(end -0.7874 -0.4064)
			(stroke
				(width 0.1524)
				(type default)
			)
			(layer "B.SilkS")
		)
		(fp_line
			(start -0.7874 -0.4064)
			(end -0.7874 0.4064)
			(stroke
				(width 0.1524)
				(type default)
			)
			(layer "B.SilkS")
		)
		(fp_line
			(start 0.7874 0.4064)
			(end 0.7874 -0.4064)
			(stroke
				(width 0.1524)
				(type default)
			)
			(layer "B.SilkS")
		)
		(fp_line
			(start -0.7874 0.4064)
			(end 0.7874 0.4064)
			(stroke
				(width 0.1524)
				(type default)
			)
			(layer "B.SilkS")
		)
		(fp_line
			(start 0.67945 -0.305054)
			(end 0.12065 -0.305054)
			(stroke
				(width 0.1)
				(type default)
			)
			(layer "B.Fab")
		)
		(fp_line
			(start 0.12065 -0.305054)
			(end 0.12065 -0.2794)
			(stroke
				(width 0.1)
				(type default)
			)
			(layer "B.Fab")
		)
		(fp_line
			(start -0.12065 -0.3048)
			(end -0.67945 -0.3048)
			(stroke
				(width 0.1)
				(type default)
			)
			(layer "B.Fab")
		)
		(fp_line
			(start -0.67945 -0.3048)
			(end -0.67945 0.3048)
			(stroke
				(width 0.1)
				(type default)
			)
			(layer "B.Fab")
		)
		(fp_line
			(start 0.12065 -0.2794)
			(end -0.12065 -0.2794)
			(stroke
				(width 0.1)
				(type default)
			)
			(layer "B.Fab")
		)
		(fp_line
			(start -0.12065 -0.2794)
			(end -0.12065 -0.3048)
			(stroke
				(width 0.1)
				(type default)
			)
			(layer "B.Fab")
		)
		(fp_line
			(start 0.12065 0.2794)
			(end 0.12065 0.3048)
			(stroke
				(width 0.1)
				(type default)
			)
			(layer "B.Fab")
		)
		(fp_line
			(start -0.120396 0.2794)
			(end 0.12065 0.2794)
			(stroke
				(width 0.1)
				(type default)
			)
			(layer "B.Fab")
		)
		(fp_line
			(start 0.67945 0.3048)
			(end 0.67945 -0.305054)
			(stroke
				(width 0.1)
				(type default)
			)
			(layer "B.Fab")
		)
		(fp_line
			(start 0.12065 0.3048)
			(end 0.67945 0.3048)
			(stroke
				(width 0.1)
				(type default)
			)
			(layer "B.Fab")
		)
		(fp_line
			(start -0.120396 0.3048)
			(end -0.120396 0.2794)
			(stroke
				(width 0.1)
				(type default)
			)
			(layer "B.Fab")
		)
		(fp_line
			(start -0.67945 0.3048)
			(end -0.120396 0.3048)
			(stroke
				(width 0.1)
				(type default)
			)
			(layer "B.Fab")
		)
		(pad "1" smd circle
			(at 0.40005 0 270)
			(size 0 0)
			(layers "B.Cu" "B.Mask" "B.Paste")
			(net "I3C_SPD_DDREFGH_CPU1_LVC1_SCL_R")
		)
		(pad "2" smd circle
			(at -0.40005 0 270)
			(size 0 0)
			(layers "B.Cu" "B.Mask" "B.Paste")
			(net "I3C_SPD_DDREFGH_CPU1_LVC1_SCL")
		)
	)
	(footprint ""
		(layer "B.Cu")
		(at 180.26888 -123.154948 180)
		(property "Reference" "C1943"
			(at 0 0 0)
			(layer "B.SilkS")
			(hide yes)
			(effects
				(font
					(size 1.27 1.27)
				)
				(justify mirror)
			)
		)
		(property "Value" ""
			(at 0 0 0)
			(layer "B.Fab")
			(effects
				(font
					(size 1.27 1.27)
				)
				(justify mirror)
			)
		)
		(duplicate_pad_numbers_are_jumpers no)
		(fp_line
			(start 0.7874 0.4064)
			(end 0.7874 -0.4064)
			(stroke
				(width 0.1524)
				(type default)
			)
			(layer "B.SilkS")
		)
		(fp_line
			(start 0.7874 -0.4064)
			(end -0.7874 -0.4064)
			(stroke
				(width 0.1524)
				(type default)
			)
			(layer "B.SilkS")
		)
		(fp_line
			(start -0.7874 0.4064)
			(end 0.7874 0.4064)
			(stroke
				(width 0.1524)
				(type default)
			)
			(layer "B.SilkS")
		)
		(fp_line
			(start -0.7874 -0.4064)
			(end -0.7874 0.4064)
			(stroke
				(width 0.1524)
				(type default)
			)
			(layer "B.SilkS")
		)
		(fp_line
			(start 0.67945 0.3048)
			(end 0.67945 -0.305054)
			(stroke
				(width 0.1)
				(type default)
			)
			(layer "B.Fab")
		)
		(fp_line
			(start 0.67945 -0.305054)
			(end 0.12065 -0.305054)
			(stroke
				(width 0.1)
				(type default)
			)
			(layer "B.Fab")
		)
		(fp_line
			(start 0.12065 0.3048)
			(end 0.67945 0.3048)
			(stroke
				(width 0.1)
				(type default)
			)
			(layer "B.Fab")
		)
		(fp_line
			(start 0.12065 0.2794)
			(end 0.12065 0.3048)
			(stroke
				(width 0.1)
				(type default)
			)
			(layer "B.Fab")
		)
		(fp_line
			(start 0.12065 -0.2794)
			(end -0.12065 -0.2794)
			(stroke
				(width 0.1)
				(type default)
			)
			(layer "B.Fab")
		)
		(fp_line
			(start 0.12065 -0.305054)
			(end 0.12065 -0.2794)
			(stroke
				(width 0.1)
				(type default)
			)
			(layer "B.Fab")
		)
		(fp_line
			(start -0.120396 0.3048)
			(end -0.120396 0.2794)
			(stroke
				(width 0.1)
				(type default)
			)
			(layer "B.Fab")
		)
		(fp_line
			(start -0.120396 0.2794)
			(end 0.12065 0.2794)
			(stroke
				(width 0.1)
				(type default)
			)
			(layer "B.Fab")
		)
		(fp_line
			(start -0.12065 -0.2794)
			(end -0.12065 -0.3048)
			(stroke
				(width 0.1)
				(type default)
			)
			(layer "B.Fab")
		)
		(fp_line
			(start -0.12065 -0.3048)
			(end -0.67945 -0.3048)
			(stroke
				(width 0.1)
				(type default)
			)
			(layer "B.Fab")
		)
		(fp_line
			(start -0.67945 0.3048)
			(end -0.120396 0.3048)
			(stroke
				(width 0.1)
				(type default)
			)
			(layer "B.Fab")
		)
		(fp_line
			(start -0.67945 -0.3048)
			(end -0.67945 0.3048)
			(stroke
				(width 0.1)
				(type default)
			)
			(layer "B.Fab")
		)
		(pad "1" smd circle
			(at 0.40005 0)
			(size 0 0)
			(layers "B.Cu" "B.Mask" "B.Paste")
			(net "VCC_PLD_CORE")
		)
		(pad "2" smd circle
			(at -0.40005 0)
			(size 0 0)
			(layers "B.Cu" "B.Mask" "B.Paste")
			(net "GND")
		)
	)
	(footprint ""
		(layer "B.Cu")
		(at 177.355754 -115.775486 90)
		(property "Reference" "C1930"
			(at 0 0 90)
			(layer "B.SilkS")
			(hide yes)
			(effects
				(font
					(size 1.27 1.27)
				)
				(justify mirror)
			)
		)
		(property "Value" ""
			(at 0 0 90)
			(layer "B.Fab")
			(effects
				(font
					(size 1.27 1.27)
				)
				(justify mirror)
			)
		)
		(duplicate_pad_numbers_are_jumpers no)
		(fp_line
			(start 0.69215 -0.2921)
			(end -0.69215 -0.2921)
			(stroke
				(width 0.1524)
				(type default)
			)
			(layer "B.SilkS")
		)
		(fp_line
			(start -0.69215 -0.2921)
			(end -0.69215 0.2921)
			(stroke
				(width 0.1524)
				(type default)
			)
			(layer "B.SilkS")
		)
		(fp_line
			(start 0.69215 0.2921)
			(end 0.69215 -0.2921)
			(stroke
				(width 0.1524)
				(type default)
			)
			(layer "B.SilkS")
		)
		(fp_line
			(start -0.69215 0.2921)
			(end 0.69215 0.2921)
			(stroke
				(width 0.1524)
				(type default)
			)
			(layer "B.SilkS")
		)
		(fp_line
			(start 0.51435 -0.2794)
			(end -0.51435 -0.2794)
			(stroke
				(width 0.1)
				(type default)
			)
			(layer "B.Fab")
		)
		(fp_line
			(start -0.51435 -0.2794)
			(end -0.51435 0.2794)
			(stroke
				(width 0.1)
				(type default)
			)
			(layer "B.Fab")
		)
		(fp_line
			(start 0.51435 0.2794)
			(end 0.51435 -0.2794)
			(stroke
				(width 0.1)
				(type default)
			)
			(layer "B.Fab")
		)
		(fp_line
			(start -0.51435 0.2794)
			(end 0.51435 0.2794)
			(stroke
				(width 0.1)
				(type default)
			)
			(layer "B.Fab")
		)
		(pad "1" smd circle
			(at 0.40005 0 270)
			(size 0 0)
			(layers "B.Cu" "B.Mask" "B.Paste")
			(net "P3V3_AUX_FPGA_VCCIO1")
		)
		(pad "2" smd circle
			(at -0.40005 0 270)
			(size 0 0)
			(layers "B.Cu" "B.Mask" "B.Paste")
			(net "GND")
		)
		(zone
			(layer "B.Cu")
			(hatch none 0.5)
			(connect_pads
				(clearance 0)
			)
			(min_thickness 0.25)
			(keepout
				(tracks not_allowed)
				(vias allowed)
				(pads allowed)
				(copperpour not_allowed)
				(footprints allowed)
			)
			(placement
				(enabled no)
				(sheetname "")
			)
			(fill
				(thermal_gap 0.5)
				(thermal_bridge_width 0.5)
				(island_removal_mode 0)
			)
			(polygon
				(pts
					(xy 177.443384 -115.965986) (xy 177.50155 -115.874546) (xy 177.50155 -115.675156) (xy 177.443384 -115.584986)
					(xy 177.268124 -115.584986) (xy 177.209704 -115.675156) (xy 177.209704 -115.874546) (xy 177.26787 -115.965986)
				)
			)
		)
	)
	(footprint ""
		(layer "B.Cu")
		(at 317.56604 -193.53911 90)
		(property "Reference" "R344"
			(at 0 0 90)
			(layer "B.SilkS")
			(hide yes)
			(effects
				(font
					(size 1.27 1.27)
				)
				(justify mirror)
			)
		)
		(property "Value" ""
			(at 0 0 90)
			(layer "B.Fab")
			(effects
				(font
					(size 1.27 1.27)
				)
				(justify mirror)
			)
		)
		(duplicate_pad_numbers_are_jumpers no)
		(fp_line
			(start 0.7874 -0.4064)
			(end -0.7874 -0.4064)
			(stroke
				(width 0.1524)
				(type default)
			)
			(layer "B.SilkS")
		)
		(fp_line
			(start -0.7874 -0.4064)
			(end -0.7874 0.4064)
			(stroke
				(width 0.1524)
				(type default)
			)
			(layer "B.SilkS")
		)
		(fp_line
			(start 0.7874 0.4064)
			(end 0.7874 -0.4064)
			(stroke
				(width 0.1524)
				(type default)
			)
			(layer "B.SilkS")
		)
		(fp_line
			(start -0.7874 0.4064)
			(end 0.7874 0.4064)
			(stroke
				(width 0.1524)
				(type default)
			)
			(layer "B.SilkS")
		)
		(fp_line
			(start 0.67945 -0.305054)
			(end 0.12065 -0.305054)
			(stroke
				(width 0.1)
				(type default)
			)
			(layer "B.Fab")
		)
		(fp_line
			(start 0.12065 -0.305054)
			(end 0.12065 -0.2794)
			(stroke
				(width 0.1)
				(type default)
			)
			(layer "B.Fab")
		)
		(fp_line
			(start -0.12065 -0.3048)
			(end -0.67945 -0.3048)
			(stroke
				(width 0.1)
				(type default)
			)
			(layer "B.Fab")
		)
		(fp_line
			(start -0.67945 -0.3048)
			(end -0.67945 0.3048)
			(stroke
				(width 0.1)
				(type default)
			)
			(layer "B.Fab")
		)
		(fp_line
			(start 0.12065 -0.2794)
			(end -0.12065 -0.2794)
			(stroke
				(width 0.1)
				(type default)
			)
			(layer "B.Fab")
		)
		(fp_line
			(start -0.12065 -0.2794)
			(end -0.12065 -0.3048)
			(stroke
				(width 0.1)
				(type default)
			)
			(layer "B.Fab")
		)
		(fp_line
			(start 0.12065 0.2794)
			(end 0.12065 0.3048)
			(stroke
				(width 0.1)
				(type default)
			)
			(layer "B.Fab")
		)
		(fp_line
			(start -0.120396 0.2794)
			(end 0.12065 0.2794)
			(stroke
				(width 0.1)
				(type default)
			)
			(layer "B.Fab")
		)
		(fp_line
			(start 0.67945 0.3048)
			(end 0.67945 -0.305054)
			(stroke
				(width 0.1)
				(type default)
			)
			(layer "B.Fab")
		)
		(fp_line
			(start 0.12065 0.3048)
			(end 0.67945 0.3048)
			(stroke
				(width 0.1)
				(type default)
			)
			(layer "B.Fab")
		)
		(fp_line
			(start -0.120396 0.3048)
			(end -0.120396 0.2794)
			(stroke
				(width 0.1)
				(type default)
			)
			(layer "B.Fab")
		)
		(fp_line
			(start -0.67945 0.3048)
			(end -0.120396 0.3048)
			(stroke
				(width 0.1)
				(type default)
			)
			(layer "B.Fab")
		)
		(pad "1" smd circle
			(at 0.40005 0 270)
			(size 0 0)
			(layers "B.Cu" "B.Mask" "B.Paste")
			(net "H_CPU0_ERR2_LVC1_R_N")
		)
		(pad "2" smd circle
			(at -0.40005 0 270)
			(size 0 0)
			(layers "B.Cu" "B.Mask" "B.Paste")
			(net "H_CPU_ERR2_LVC1_R_N")
		)
	)
	(footprint ""
		(layer "B.Cu")
		(at 302.35144 -47.137828 180)
		(property "Reference" "C1198"
			(at 0 0 0)
			(layer "B.SilkS")
			(hide yes)
			(effects
				(font
					(size 1.27 1.27)
				)
				(justify mirror)
			)
		)
		(property "Value" ""
			(at 0 0 0)
			(layer "B.Fab")
			(effects
				(font
					(size 1.27 1.27)
				)
				(justify mirror)
			)
		)
		(duplicate_pad_numbers_are_jumpers no)
		(fp_line
			(start 1.2954 0.5842)
			(end 1.2954 -0.5842)
			(stroke
				(width 0.1524)
				(type default)
			)
			(layer "B.SilkS")
		)
		(fp_line
			(start 1.2954 -0.5842)
			(end -1.2954 -0.5842)
			(stroke
				(width 0.1524)
				(type default)
			)
			(layer "B.SilkS")
		)
		(fp_line
			(start 0 -0.5842)
			(end 0 0.5842)
			(stroke
				(width 0.1524)
				(type default)
			)
			(layer "B.SilkS")
		)
		(fp_line
			(start -1.2954 0.5842)
			(end 1.2954 0.5842)
			(stroke
				(width 0.1524)
				(type default)
			)
			(layer "B.SilkS")
		)
		(fp_line
			(start -1.2954 -0.5842)
			(end -1.2954 0.5842)
			(stroke
				(width 0.1524)
				(type default)
			)
			(layer "B.SilkS")
		)
		(fp_line
			(start 1.1938 0.4064)
			(end 1.1938 -0.4064)
			(stroke
				(width 0.1)
				(type default)
			)
			(layer "B.Fab")
		)
		(fp_line
			(start 1.1938 -0.4064)
			(end 0.8636 -0.4064)
			(stroke
				(width 0.1)
				(type default)
			)
			(layer "B.Fab")
		)
		(fp_line
			(start 0.8636 0.4572)
			(end 0.8636 0.4064)
			(stroke
				(width 0.1)
				(type default)
			)
			(layer "B.Fab")
		)
		(fp_line
			(start 0.8636 0.4064)
			(end 1.1938 0.4064)
			(stroke
				(width 0.1)
				(type default)
			)
			(layer "B.Fab")
		)
		(fp_line
			(start 0.8636 -0.4064)
			(end 0.8636 -0.4572)
			(stroke
				(width 0.1)
				(type default)
			)
			(layer "B.Fab")
		)
		(fp_line
			(start 0.8636 -0.4572)
			(end -0.8636 -0.4572)
			(stroke
				(width 0.1)
				(type default)
			)
			(layer "B.Fab")
		)
		(fp_line
			(start -0.8636 0.4572)
			(end 0.8636 0.4572)
			(stroke
				(width 0.1)
				(type default)
			)
			(layer "B.Fab")
		)
		(fp_line
			(start -0.8636 0.4064)
			(end -0.8636 0.4572)
			(stroke
				(width 0.1)
				(type default)
			)
			(layer "B.Fab")
		)
		(fp_line
			(start -0.8636 -0.4064)
			(end -1.1938 -0.4064)
			(stroke
				(width 0.1)
				(type default)
			)
			(layer "B.Fab")
		)
		(fp_line
			(start -0.8636 -0.4572)
			(end -0.8636 -0.4064)
			(stroke
				(width 0.1)
				(type default)
			)
			(layer "B.Fab")
		)
		(fp_line
			(start -1.1938 0.4064)
			(end -0.8636 0.4064)
			(stroke
				(width 0.1)
				(type default)
			)
			(layer "B.Fab")
		)
		(fp_line
			(start -1.1938 -0.4064)
			(end -1.1938 0.4064)
			(stroke
				(width 0.1)
				(type default)
			)
			(layer "B.Fab")
		)
		(pad "1" smd rect
			(at 0.7366 0 90)
			(size 0.7112 0.8128)
			(layers "B.Cu" "B.Mask" "B.Paste")
			(net "P1V05_PCH_AUX")
		)
		(pad "2" smd rect
			(at -0.7366 0 90)
			(size 0.7112 0.8128)
			(layers "B.Cu" "B.Mask" "B.Paste")
			(net "GND")
		)
	)
	(footprint ""
		(layer "B.Cu")
		(at 114.822224 -337.607402 -90)
		(property "Reference" "PC538_P1_3"
			(at 0 0 90)
			(layer "B.SilkS")
			(hide yes)
			(effects
				(font
					(size 1.27 1.27)
				)
				(justify mirror)
			)
		)
		(property "Value" ""
			(at 0 0 90)
			(layer "B.Fab")
			(effects
				(font
					(size 1.27 1.27)
				)
				(justify mirror)
			)
		)
		(duplicate_pad_numbers_are_jumpers no)
		(fp_line
			(start -1.524 0.762)
			(end 1.524 0.762)
			(stroke
				(width 0.1524)
				(type default)
			)
			(layer "B.SilkS")
		)
		(fp_line
			(start 1.524 0.762)
			(end 1.524 -0.762)
			(stroke
				(width 0.1524)
				(type default)
			)
			(layer "B.SilkS")
		)
		(fp_line
			(start -1.524 -0.762)
			(end -1.524 0.762)
			(stroke
				(width 0.1524)
				(type default)
			)
			(layer "B.SilkS")
		)
		(fp_line
			(start 1.524 -0.762)
			(end -1.524 -0.762)
			(stroke
				(width 0.1524)
				(type default)
			)
			(layer "B.SilkS")
		)
		(fp_line
			(start -1.1049 0.724916)
			(end -1.1049 -0.724916)
			(stroke
				(width 0.1)
				(type default)
			)
			(layer "B.Fab")
		)
		(fp_line
			(start 1.1049 0.724916)
			(end -1.1049 0.724916)
			(stroke
				(width 0.1)
				(type default)
			)
			(layer "B.Fab")
		)
		(fp_line
			(start -1.1049 -0.724916)
			(end 1.1049 -0.724916)
			(stroke
				(width 0.1)
				(type default)
			)
			(layer "B.Fab")
		)
		(fp_line
			(start 1.1049 -0.724916)
			(end 1.1049 0.724916)
			(stroke
				(width 0.1)
				(type default)
			)
			(layer "B.Fab")
		)
		(pad "1" smd rect
			(at 0.889 0 270)
			(size 1.016 1.27)
			(layers "B.Cu" "B.Mask" "B.Paste")
			(net "SW_P12V_PVCCIN_CPU1_FLT")
		)
		(pad "2" smd rect
			(at -0.889 0 270)
			(size 1.016 1.27)
			(layers "B.Cu" "B.Mask" "B.Paste")
			(net "GND")
		)
	)
	(footprint ""
		(layer "B.Cu")
		(at 426.892212 -122.57786 180)
		(property "Reference" "PR1380"
			(at 0 0 0)
			(layer "B.SilkS")
			(hide yes)
			(effects
				(font
					(size 1.27 1.27)
				)
				(justify mirror)
			)
		)
		(property "Value" ""
			(at 0 0 0)
			(layer "B.Fab")
			(effects
				(font
					(size 1.27 1.27)
				)
				(justify mirror)
			)
		)
		(duplicate_pad_numbers_are_jumpers no)
		(fp_line
			(start 0.7874 0.4064)
			(end 0.7874 -0.4064)
			(stroke
				(width 0.1524)
				(type default)
			)
			(layer "B.SilkS")
		)
		(fp_line
			(start 0.7874 -0.4064)
			(end -0.7874 -0.4064)
			(stroke
				(width 0.1524)
				(type default)
			)
			(layer "B.SilkS")
		)
		(fp_line
			(start -0.7874 0.4064)
			(end 0.7874 0.4064)
			(stroke
				(width 0.1524)
				(type default)
			)
			(layer "B.SilkS")
		)
		(fp_line
			(start -0.7874 -0.4064)
			(end -0.7874 0.4064)
			(stroke
				(width 0.1524)
				(type default)
			)
			(layer "B.SilkS")
		)
		(fp_line
			(start 0.67945 0.3048)
			(end 0.67945 -0.305054)
			(stroke
				(width 0.1)
				(type default)
			)
			(layer "B.Fab")
		)
		(fp_line
			(start 0.67945 -0.305054)
			(end 0.12065 -0.305054)
			(stroke
				(width 0.1)
				(type default)
			)
			(layer "B.Fab")
		)
		(fp_line
			(start 0.12065 0.3048)
			(end 0.67945 0.3048)
			(stroke
				(width 0.1)
				(type default)
			)
			(layer "B.Fab")
		)
		(fp_line
			(start 0.12065 0.2794)
			(end 0.12065 0.3048)
			(stroke
				(width 0.1)
				(type default)
			)
			(layer "B.Fab")
		)
		(fp_line
			(start 0.12065 -0.2794)
			(end -0.12065 -0.2794)
			(stroke
				(width 0.1)
				(type default)
			)
			(layer "B.Fab")
		)
		(fp_line
			(start 0.12065 -0.305054)
			(end 0.12065 -0.2794)
			(stroke
				(width 0.1)
				(type default)
			)
			(layer "B.Fab")
		)
		(fp_line
			(start -0.120396 0.3048)
			(end -0.120396 0.2794)
			(stroke
				(width 0.1)
				(type default)
			)
			(layer "B.Fab")
		)
		(fp_line
			(start -0.120396 0.2794)
			(end 0.12065 0.2794)
			(stroke
				(width 0.1)
				(type default)
			)
			(layer "B.Fab")
		)
		(fp_line
			(start -0.12065 -0.2794)
			(end -0.12065 -0.3048)
			(stroke
				(width 0.1)
				(type default)
			)
			(layer "B.Fab")
		)
		(fp_line
			(start -0.12065 -0.3048)
			(end -0.67945 -0.3048)
			(stroke
				(width 0.1)
				(type default)
			)
			(layer "B.Fab")
		)
		(fp_line
			(start -0.67945 0.3048)
			(end -0.120396 0.3048)
			(stroke
				(width 0.1)
				(type default)
			)
			(layer "B.Fab")
		)
		(fp_line
			(start -0.67945 -0.3048)
			(end -0.67945 0.3048)
			(stroke
				(width 0.1)
				(type default)
			)
			(layer "B.Fab")
		)
		(pad "1" smd circle
			(at 0.40005 0)
			(size 0 0)
			(layers "B.Cu" "B.Mask" "B.Paste")
			(net "P12V_AUX_CPU0_DIMM_ISEN_P")
		)
		(pad "2" smd circle
			(at -0.40005 0)
			(size 0 0)
			(layers "B.Cu" "B.Mask" "B.Paste")
			(net "PVCCD_HV_CPU0_ISENSE_P")
		)
	)
	(footprint ""
		(layer "B.Cu")
		(at 430.600104 -135.510778)
		(property "Reference" "R2393"
			(at 0 0 0)
			(layer "B.SilkS")
			(hide yes)
			(effects
				(font
					(size 1.27 1.27)
				)
				(justify mirror)
			)
		)
		(property "Value" ""
			(at 0 0 0)
			(layer "B.Fab")
			(effects
				(font
					(size 1.27 1.27)
				)
				(justify mirror)
			)
		)
		(duplicate_pad_numbers_are_jumpers no)
		(fp_line
			(start -0.7874 -0.4064)
			(end -0.7874 0.4064)
			(stroke
				(width 0.1524)
				(type default)
			)
			(layer "B.SilkS")
		)
		(fp_line
			(start -0.7874 0.4064)
			(end 0.7874 0.4064)
			(stroke
				(width 0.1524)
				(type default)
			)
			(layer "B.SilkS")
		)
		(fp_line
			(start 0.7874 -0.4064)
			(end -0.7874 -0.4064)
			(stroke
				(width 0.1524)
				(type default)
			)
			(layer "B.SilkS")
		)
		(fp_line
			(start 0.7874 0.4064)
			(end 0.7874 -0.4064)
			(stroke
				(width 0.1524)
				(type default)
			)
			(layer "B.SilkS")
		)
		(fp_line
			(start -0.67945 -0.3048)
			(end -0.67945 0.3048)
			(stroke
				(width 0.1)
				(type default)
			)
			(layer "B.Fab")
		)
		(fp_line
			(start -0.67945 0.3048)
			(end -0.120396 0.3048)
			(stroke
				(width 0.1)
				(type default)
			)
			(layer "B.Fab")
		)
		(fp_line
			(start -0.12065 -0.3048)
			(end -0.67945 -0.3048)
			(stroke
				(width 0.1)
				(type default)
			)
			(layer "B.Fab")
		)
		(fp_line
			(start -0.12065 -0.2794)
			(end -0.12065 -0.3048)
			(stroke
				(width 0.1)
				(type default)
			)
			(layer "B.Fab")
		)
		(fp_line
			(start -0.120396 0.2794)
			(end 0.12065 0.2794)
			(stroke
				(width 0.1)
				(type default)
			)
			(layer "B.Fab")
		)
		(fp_line
			(start -0.120396 0.3048)
			(end -0.120396 0.2794)
			(stroke
				(width 0.1)
				(type default)
			)
			(layer "B.Fab")
		)
		(fp_line
			(start 0.12065 -0.305054)
			(end 0.12065 -0.2794)
			(stroke
				(width 0.1)
				(type default)
			)
			(layer "B.Fab")
		)
		(fp_line
			(start 0.12065 -0.2794)
			(end -0.12065 -0.2794)
			(stroke
				(width 0.1)
				(type default)
			)
			(layer "B.Fab")
		)
		(fp_line
			(start 0.12065 0.2794)
			(end 0.12065 0.3048)
			(stroke
				(width 0.1)
				(type default)
			)
			(layer "B.Fab")
		)
		(fp_line
			(start 0.12065 0.3048)
			(end 0.67945 0.3048)
			(stroke
				(width 0.1)
				(type default)
			)
			(layer "B.Fab")
		)
		(fp_line
			(start 0.67945 -0.305054)
			(end 0.12065 -0.305054)
			(stroke
				(width 0.1)
				(type default)
			)
			(layer "B.Fab")
		)
		(fp_line
			(start 0.67945 0.3048)
			(end 0.67945 -0.305054)
			(stroke
				(width 0.1)
				(type default)
			)
			(layer "B.Fab")
		)
		(pad "1" smd circle
			(at 0.40005 0 180)
			(size 0 0)
			(layers "B.Cu" "B.Mask" "B.Paste")
			(net "P3V3_AUX")
		)
		(pad "2" smd circle
			(at -0.40005 0 180)
			(size 0 0)
			(layers "B.Cu" "B.Mask" "B.Paste")
			(net "PVCCINFAON_CPU0_PIN_ALERT")
		)
	)
	(footprint ""
		(layer "B.Cu")
		(at 280.852118 -319.120774 -90)
		(property "Reference" "R31"
			(at 0 0 90)
			(layer "B.SilkS")
			(hide yes)
			(effects
				(font
					(size 1.27 1.27)
				)
				(justify mirror)
			)
		)
		(property "Value" ""
			(at 0 0 90)
			(layer "B.Fab")
			(effects
				(font
					(size 1.27 1.27)
				)
				(justify mirror)
			)
		)
		(duplicate_pad_numbers_are_jumpers no)
		(fp_line
			(start -0.7874 0.4064)
			(end 0.7874 0.4064)
			(stroke
				(width 0.1524)
				(type default)
			)
			(layer "B.SilkS")
		)
		(fp_line
			(start 0.7874 0.4064)
			(end 0.7874 -0.4064)
			(stroke
				(width 0.1524)
				(type default)
			)
			(layer "B.SilkS")
		)
		(fp_line
			(start -0.7874 -0.4064)
			(end -0.7874 0.4064)
			(stroke
				(width 0.1524)
				(type default)
			)
			(layer "B.SilkS")
		)
		(fp_line
			(start 0.7874 -0.4064)
			(end -0.7874 -0.4064)
			(stroke
				(width 0.1524)
				(type default)
			)
			(layer "B.SilkS")
		)
		(fp_line
			(start -0.67945 0.3048)
			(end -0.120396 0.3048)
			(stroke
				(width 0.1)
				(type default)
			)
			(layer "B.Fab")
		)
		(fp_line
			(start -0.120396 0.3048)
			(end -0.120396 0.2794)
			(stroke
				(width 0.1)
				(type default)
			)
			(layer "B.Fab")
		)
		(fp_line
			(start 0.12065 0.3048)
			(end 0.67945 0.3048)
			(stroke
				(width 0.1)
				(type default)
			)
			(layer "B.Fab")
		)
		(fp_line
			(start 0.67945 0.3048)
			(end 0.67945 -0.305054)
			(stroke
				(width 0.1)
				(type default)
			)
			(layer "B.Fab")
		)
		(fp_line
			(start -0.120396 0.2794)
			(end 0.12065 0.2794)
			(stroke
				(width 0.1)
				(type default)
			)
			(layer "B.Fab")
		)
		(fp_line
			(start 0.12065 0.2794)
			(end 0.12065 0.3048)
			(stroke
				(width 0.1)
				(type default)
			)
			(layer "B.Fab")
		)
		(fp_line
			(start -0.12065 -0.2794)
			(end -0.12065 -0.3048)
			(stroke
				(width 0.1)
				(type default)
			)
			(layer "B.Fab")
		)
		(fp_line
			(start 0.12065 -0.2794)
			(end -0.12065 -0.2794)
			(stroke
				(width 0.1)
				(type default)
			)
			(layer "B.Fab")
		)
		(fp_line
			(start -0.67945 -0.3048)
			(end -0.67945 0.3048)
			(stroke
				(width 0.1)
				(type default)
			)
			(layer "B.Fab")
		)
		(fp_line
			(start -0.12065 -0.3048)
			(end -0.67945 -0.3048)
			(stroke
				(width 0.1)
				(type default)
			)
			(layer "B.Fab")
		)
		(fp_line
			(start 0.12065 -0.305054)
			(end 0.12065 -0.2794)
			(stroke
				(width 0.1)
				(type default)
			)
			(layer "B.Fab")
		)
		(fp_line
			(start 0.67945 -0.305054)
			(end 0.12065 -0.305054)
			(stroke
				(width 0.1)
				(type default)
			)
			(layer "B.Fab")
		)
		(pad "1" smd circle
			(at 0.40005 0 90)
			(size 0 0)
			(layers "B.Cu" "B.Mask" "B.Paste")
			(net "PD_CHC_CPU0_DIMM2_SAA")
		)
		(pad "2" smd circle
			(at -0.40005 0 90)
			(size 0 0)
			(layers "B.Cu" "B.Mask" "B.Paste")
			(net "GND")
		)
	)
	(footprint ""
		(layer "B.Cu")
		(at 304.138584 -151.719534 -90)
		(property "Reference" "R685"
			(at 0 0 90)
			(layer "B.SilkS")
			(hide yes)
			(effects
				(font
					(size 1.27 1.27)
				)
				(justify mirror)
			)
		)
		(property "Value" ""
			(at 0 0 90)
			(layer "B.Fab")
			(effects
				(font
					(size 1.27 1.27)
				)
				(justify mirror)
			)
		)
		(duplicate_pad_numbers_are_jumpers no)
		(fp_line
			(start -0.7874 0.4064)
			(end 0.7874 0.4064)
			(stroke
				(width 0.1524)
				(type default)
			)
			(layer "B.SilkS")
		)
		(fp_line
			(start 0.7874 0.4064)
			(end 0.7874 -0.4064)
			(stroke
				(width 0.1524)
				(type default)
			)
			(layer "B.SilkS")
		)
		(fp_line
			(start -0.7874 -0.4064)
			(end -0.7874 0.4064)
			(stroke
				(width 0.1524)
				(type default)
			)
			(layer "B.SilkS")
		)
		(fp_line
			(start 0.7874 -0.4064)
			(end -0.7874 -0.4064)
			(stroke
				(width 0.1524)
				(type default)
			)
			(layer "B.SilkS")
		)
		(fp_line
			(start -0.67945 0.3048)
			(end -0.120396 0.3048)
			(stroke
				(width 0.1)
				(type default)
			)
			(layer "B.Fab")
		)
		(fp_line
			(start -0.120396 0.3048)
			(end -0.120396 0.2794)
			(stroke
				(width 0.1)
				(type default)
			)
			(layer "B.Fab")
		)
		(fp_line
			(start 0.12065 0.3048)
			(end 0.67945 0.3048)
			(stroke
				(width 0.1)
				(type default)
			)
			(layer "B.Fab")
		)
		(fp_line
			(start 0.67945 0.3048)
			(end 0.67945 -0.305054)
			(stroke
				(width 0.1)
				(type default)
			)
			(layer "B.Fab")
		)
		(fp_line
			(start -0.120396 0.2794)
			(end 0.12065 0.2794)
			(stroke
				(width 0.1)
				(type default)
			)
			(layer "B.Fab")
		)
		(fp_line
			(start 0.12065 0.2794)
			(end 0.12065 0.3048)
			(stroke
				(width 0.1)
				(type default)
			)
			(layer "B.Fab")
		)
		(fp_line
			(start -0.12065 -0.2794)
			(end -0.12065 -0.3048)
			(stroke
				(width 0.1)
				(type default)
			)
			(layer "B.Fab")
		)
		(fp_line
			(start 0.12065 -0.2794)
			(end -0.12065 -0.2794)
			(stroke
				(width 0.1)
				(type default)
			)
			(layer "B.Fab")
		)
		(fp_line
			(start -0.67945 -0.3048)
			(end -0.67945 0.3048)
			(stroke
				(width 0.1)
				(type default)
			)
			(layer "B.Fab")
		)
		(fp_line
			(start -0.12065 -0.3048)
			(end -0.67945 -0.3048)
			(stroke
				(width 0.1)
				(type default)
			)
			(layer "B.Fab")
		)
		(fp_line
			(start 0.12065 -0.305054)
			(end 0.12065 -0.2794)
			(stroke
				(width 0.1)
				(type default)
			)
			(layer "B.Fab")
		)
		(fp_line
			(start 0.67945 -0.305054)
			(end 0.12065 -0.305054)
			(stroke
				(width 0.1)
				(type default)
			)
			(layer "B.Fab")
		)
		(pad "1" smd circle
			(at 0.40005 0 90)
			(size 0 0)
			(layers "B.Cu" "B.Mask" "B.Paste")
			(net "I3C_SPD_DDREFGH_CPU0_R_SDA")
		)
		(pad "2" smd circle
			(at -0.40005 0 90)
			(size 0 0)
			(layers "B.Cu" "B.Mask" "B.Paste")
			(net "I3C_SPD_DDREFGH_CPU0_LVC1_R_SDA")
		)
	)
	(footprint ""
		(layer "B.Cu")
		(at 188.46546 -104.823768)
		(property "Reference" "R1416"
			(at 0 0 0)
			(layer "B.SilkS")
			(hide yes)
			(effects
				(font
					(size 1.27 1.27)
				)
				(justify mirror)
			)
		)
		(property "Value" ""
			(at 0 0 0)
			(layer "B.Fab")
			(effects
				(font
					(size 1.27 1.27)
				)
				(justify mirror)
			)
		)
		(duplicate_pad_numbers_are_jumpers no)
		(fp_line
			(start -0.7874 -0.4064)
			(end -0.7874 0.4064)
			(stroke
				(width 0.1524)
				(type default)
			)
			(layer "B.SilkS")
		)
		(fp_line
			(start -0.7874 0.4064)
			(end 0.7874 0.4064)
			(stroke
				(width 0.1524)
				(type default)
			)
			(layer "B.SilkS")
		)
		(fp_line
			(start 0.7874 -0.4064)
			(end -0.7874 -0.4064)
			(stroke
				(width 0.1524)
				(type default)
			)
			(layer "B.SilkS")
		)
		(fp_line
			(start 0.7874 0.4064)
			(end 0.7874 -0.4064)
			(stroke
				(width 0.1524)
				(type default)
			)
			(layer "B.SilkS")
		)
		(fp_line
			(start -0.67945 -0.3048)
			(end -0.67945 0.3048)
			(stroke
				(width 0.1)
				(type default)
			)
			(layer "B.Fab")
		)
		(fp_line
			(start -0.67945 0.3048)
			(end -0.120396 0.3048)
			(stroke
				(width 0.1)
				(type default)
			)
			(layer "B.Fab")
		)
		(fp_line
			(start -0.12065 -0.3048)
			(end -0.67945 -0.3048)
			(stroke
				(width 0.1)
				(type default)
			)
			(layer "B.Fab")
		)
		(fp_line
			(start -0.12065 -0.2794)
			(end -0.12065 -0.3048)
			(stroke
				(width 0.1)
				(type default)
			)
			(layer "B.Fab")
		)
		(fp_line
			(start -0.120396 0.2794)
			(end 0.12065 0.2794)
			(stroke
				(width 0.1)
				(type default)
			)
			(layer "B.Fab")
		)
		(fp_line
			(start -0.120396 0.3048)
			(end -0.120396 0.2794)
			(stroke
				(width 0.1)
				(type default)
			)
			(layer "B.Fab")
		)
		(fp_line
			(start 0.12065 -0.305054)
			(end 0.12065 -0.2794)
			(stroke
				(width 0.1)
				(type default)
			)
			(layer "B.Fab")
		)
		(fp_line
			(start 0.12065 -0.2794)
			(end -0.12065 -0.2794)
			(stroke
				(width 0.1)
				(type default)
			)
			(layer "B.Fab")
		)
		(fp_line
			(start 0.12065 0.2794)
			(end 0.12065 0.3048)
			(stroke
				(width 0.1)
				(type default)
			)
			(layer "B.Fab")
		)
		(fp_line
			(start 0.12065 0.3048)
			(end 0.67945 0.3048)
			(stroke
				(width 0.1)
				(type default)
			)
			(layer "B.Fab")
		)
		(fp_line
			(start 0.67945 -0.305054)
			(end 0.12065 -0.305054)
			(stroke
				(width 0.1)
				(type default)
			)
			(layer "B.Fab")
		)
		(fp_line
			(start 0.67945 0.3048)
			(end 0.67945 -0.305054)
			(stroke
				(width 0.1)
				(type default)
			)
			(layer "B.Fab")
		)
		(pad "1" smd circle
			(at 0.40005 0 180)
			(size 0 0)
			(layers "B.Cu" "B.Mask" "B.Paste")
			(net "RST_CPU1_LVC1_R_N")
		)
		(pad "2" smd circle
			(at -0.40005 0 180)
			(size 0 0)
			(layers "B.Cu" "B.Mask" "B.Paste")
			(net "GND")
		)
	)
	(footprint ""
		(layer "B.Cu")
		(at 388.989824 -342.936576 90)
		(property "Reference" "PC238_P0_8"
			(at 0 0 90)
			(layer "B.SilkS")
			(hide yes)
			(effects
				(font
					(size 1.27 1.27)
				)
				(justify mirror)
			)
		)
		(property "Value" ""
			(at 0 0 90)
			(layer "B.Fab")
			(effects
				(font
					(size 1.27 1.27)
				)
				(justify mirror)
			)
		)
		(duplicate_pad_numbers_are_jumpers no)
		(fp_line
			(start 1.524 -0.762)
			(end -1.524 -0.762)
			(stroke
				(width 0.1524)
				(type default)
			)
			(layer "B.SilkS")
		)
		(fp_line
			(start -1.524 -0.762)
			(end -1.524 0.762)
			(stroke
				(width 0.1524)
				(type default)
			)
			(layer "B.SilkS")
		)
		(fp_line
			(start 1.524 0.762)
			(end 1.524 -0.762)
			(stroke
				(width 0.1524)
				(type default)
			)
			(layer "B.SilkS")
		)
		(fp_line
			(start -1.524 0.762)
			(end 1.524 0.762)
			(stroke
				(width 0.1524)
				(type default)
			)
			(layer "B.SilkS")
		)
		(fp_line
			(start 1.1049 -0.724916)
			(end 1.1049 0.724916)
			(stroke
				(width 0.1)
				(type default)
			)
			(layer "B.Fab")
		)
		(fp_line
			(start -1.1049 -0.724916)
			(end 1.1049 -0.724916)
			(stroke
				(width 0.1)
				(type default)
			)
			(layer "B.Fab")
		)
		(fp_line
			(start 1.1049 0.724916)
			(end -1.1049 0.724916)
			(stroke
				(width 0.1)
				(type default)
			)
			(layer "B.Fab")
		)
		(fp_line
			(start -1.1049 0.724916)
			(end -1.1049 -0.724916)
			(stroke
				(width 0.1)
				(type default)
			)
			(layer "B.Fab")
		)
		(pad "1" smd rect
			(at 0.889 0 90)
			(size 1.016 1.27)
			(layers "B.Cu" "B.Mask" "B.Paste")
			(net "SW_P12V_PVCCIN_CPU0_FLT")
		)
		(pad "2" smd rect
			(at -0.889 0 90)
			(size 1.016 1.27)
			(layers "B.Cu" "B.Mask" "B.Paste")
			(net "GND")
		)
	)
	(footprint ""
		(layer "B.Cu")
		(at 245.96217 -128.330452 90)
		(property "Reference" "R569"
			(at 0 0 90)
			(layer "B.SilkS")
			(hide yes)
			(effects
				(font
					(size 1.27 1.27)
				)
				(justify mirror)
			)
		)
		(property "Value" ""
			(at 0 0 90)
			(layer "B.Fab")
			(effects
				(font
					(size 1.27 1.27)
				)
				(justify mirror)
			)
		)
		(duplicate_pad_numbers_are_jumpers no)
		(fp_line
			(start 0.7874 -0.4064)
			(end -0.7874 -0.4064)
			(stroke
				(width 0.1524)
				(type default)
			)
			(layer "B.SilkS")
		)
		(fp_line
			(start -0.7874 -0.4064)
			(end -0.7874 0.4064)
			(stroke
				(width 0.1524)
				(type default)
			)
			(layer "B.SilkS")
		)
		(fp_line
			(start 0.7874 0.4064)
			(end 0.7874 -0.4064)
			(stroke
				(width 0.1524)
				(type default)
			)
			(layer "B.SilkS")
		)
		(fp_line
			(start -0.7874 0.4064)
			(end 0.7874 0.4064)
			(stroke
				(width 0.1524)
				(type default)
			)
			(layer "B.SilkS")
		)
		(fp_line
			(start 0.67945 -0.305054)
			(end 0.12065 -0.305054)
			(stroke
				(width 0.1)
				(type default)
			)
			(layer "B.Fab")
		)
		(fp_line
			(start 0.12065 -0.305054)
			(end 0.12065 -0.2794)
			(stroke
				(width 0.1)
				(type default)
			)
			(layer "B.Fab")
		)
		(fp_line
			(start -0.12065 -0.3048)
			(end -0.67945 -0.3048)
			(stroke
				(width 0.1)
				(type default)
			)
			(layer "B.Fab")
		)
		(fp_line
			(start -0.67945 -0.3048)
			(end -0.67945 0.3048)
			(stroke
				(width 0.1)
				(type default)
			)
			(layer "B.Fab")
		)
		(fp_line
			(start 0.12065 -0.2794)
			(end -0.12065 -0.2794)
			(stroke
				(width 0.1)
				(type default)
			)
			(layer "B.Fab")
		)
		(fp_line
			(start -0.12065 -0.2794)
			(end -0.12065 -0.3048)
			(stroke
				(width 0.1)
				(type default)
			)
			(layer "B.Fab")
		)
		(fp_line
			(start 0.12065 0.2794)
			(end 0.12065 0.3048)
			(stroke
				(width 0.1)
				(type default)
			)
			(layer "B.Fab")
		)
		(fp_line
			(start -0.120396 0.2794)
			(end 0.12065 0.2794)
			(stroke
				(width 0.1)
				(type default)
			)
			(layer "B.Fab")
		)
		(fp_line
			(start 0.67945 0.3048)
			(end 0.67945 -0.305054)
			(stroke
				(width 0.1)
				(type default)
			)
			(layer "B.Fab")
		)
		(fp_line
			(start 0.12065 0.3048)
			(end 0.67945 0.3048)
			(stroke
				(width 0.1)
				(type default)
			)
			(layer "B.Fab")
		)
		(fp_line
			(start -0.120396 0.3048)
			(end -0.120396 0.2794)
			(stroke
				(width 0.1)
				(type default)
			)
			(layer "B.Fab")
		)
		(fp_line
			(start -0.67945 0.3048)
			(end -0.120396 0.3048)
			(stroke
				(width 0.1)
				(type default)
			)
			(layer "B.Fab")
		)
		(pad "1" smd circle
			(at 0.40005 0 270)
			(size 0 0)
			(layers "B.Cu" "B.Mask" "B.Paste")
			(net "P3V3")
		)
		(pad "2" smd circle
			(at -0.40005 0 270)
			(size 0 0)
			(layers "B.Cu" "B.Mask" "B.Paste")
			(net "PD_DB2000_SMB_SA0")
		)
	)
	(footprint ""
		(layer "B.Cu")
		(at 71.385684 -188.458856 90)
		(property "Reference" "R59"
			(at 0 0 90)
			(layer "B.SilkS")
			(hide yes)
			(effects
				(font
					(size 1.27 1.27)
				)
				(justify mirror)
			)
		)
		(property "Value" ""
			(at 0 0 90)
			(layer "B.Fab")
			(effects
				(font
					(size 1.27 1.27)
				)
				(justify mirror)
			)
		)
		(duplicate_pad_numbers_are_jumpers no)
		(fp_line
			(start 0.7874 -0.4064)
			(end -0.7874 -0.4064)
			(stroke
				(width 0.1524)
				(type default)
			)
			(layer "B.SilkS")
		)
		(fp_line
			(start -0.7874 -0.4064)
			(end -0.7874 0.4064)
			(stroke
				(width 0.1524)
				(type default)
			)
			(layer "B.SilkS")
		)
		(fp_line
			(start 0.7874 0.4064)
			(end 0.7874 -0.4064)
			(stroke
				(width 0.1524)
				(type default)
			)
			(layer "B.SilkS")
		)
		(fp_line
			(start -0.7874 0.4064)
			(end 0.7874 0.4064)
			(stroke
				(width 0.1524)
				(type default)
			)
			(layer "B.SilkS")
		)
		(fp_line
			(start 0.67945 -0.305054)
			(end 0.12065 -0.305054)
			(stroke
				(width 0.1)
				(type default)
			)
			(layer "B.Fab")
		)
		(fp_line
			(start 0.12065 -0.305054)
			(end 0.12065 -0.2794)
			(stroke
				(width 0.1)
				(type default)
			)
			(layer "B.Fab")
		)
		(fp_line
			(start -0.12065 -0.3048)
			(end -0.67945 -0.3048)
			(stroke
				(width 0.1)
				(type default)
			)
			(layer "B.Fab")
		)
		(fp_line
			(start -0.67945 -0.3048)
			(end -0.67945 0.3048)
			(stroke
				(width 0.1)
				(type default)
			)
			(layer "B.Fab")
		)
		(fp_line
			(start 0.12065 -0.2794)
			(end -0.12065 -0.2794)
			(stroke
				(width 0.1)
				(type default)
			)
			(layer "B.Fab")
		)
		(fp_line
			(start -0.12065 -0.2794)
			(end -0.12065 -0.3048)
			(stroke
				(width 0.1)
				(type default)
			)
			(layer "B.Fab")
		)
		(fp_line
			(start 0.12065 0.2794)
			(end 0.12065 0.3048)
			(stroke
				(width 0.1)
				(type default)
			)
			(layer "B.Fab")
		)
		(fp_line
			(start -0.120396 0.2794)
			(end 0.12065 0.2794)
			(stroke
				(width 0.1)
				(type default)
			)
			(layer "B.Fab")
		)
		(fp_line
			(start 0.67945 0.3048)
			(end 0.67945 -0.305054)
			(stroke
				(width 0.1)
				(type default)
			)
			(layer "B.Fab")
		)
		(fp_line
			(start 0.12065 0.3048)
			(end 0.67945 0.3048)
			(stroke
				(width 0.1)
				(type default)
			)
			(layer "B.Fab")
		)
		(fp_line
			(start -0.120396 0.3048)
			(end -0.120396 0.2794)
			(stroke
				(width 0.1)
				(type default)
			)
			(layer "B.Fab")
		)
		(fp_line
			(start -0.67945 0.3048)
			(end -0.120396 0.3048)
			(stroke
				(width 0.1)
				(type default)
			)
			(layer "B.Fab")
		)
		(pad "1" smd circle
			(at 0.40005 0 270)
			(size 0 0)
			(layers "B.Cu" "B.Mask" "B.Paste")
			(net "SVID_CLK1_CPU1")
		)
		(pad "2" smd circle
			(at -0.40005 0 270)
			(size 0 0)
			(layers "B.Cu" "B.Mask" "B.Paste")
			(net "SVID_CLK1_CPU1_R")
		)
	)
	(footprint ""
		(layer "B.Cu")
		(at 354.446586 -235.916724)
		(property "Reference" "C1362"
			(at 0 0 0)
			(layer "B.SilkS")
			(hide yes)
			(effects
				(font
					(size 1.27 1.27)
				)
				(justify mirror)
			)
		)
		(property "Value" ""
			(at 0 0 0)
			(layer "B.Fab")
			(effects
				(font
					(size 1.27 1.27)
				)
				(justify mirror)
			)
		)
		(duplicate_pad_numbers_are_jumpers no)
		(fp_line
			(start -0.7874 -0.4064)
			(end -0.7874 0.4064)
			(stroke
				(width 0.1524)
				(type default)
			)
			(layer "B.SilkS")
		)
		(fp_line
			(start -0.7874 0.4064)
			(end 0.7874 0.4064)
			(stroke
				(width 0.1524)
				(type default)
			)
			(layer "B.SilkS")
		)
		(fp_line
			(start 0.7874 -0.4064)
			(end -0.7874 -0.4064)
			(stroke
				(width 0.1524)
				(type default)
			)
			(layer "B.SilkS")
		)
		(fp_line
			(start 0.7874 0.4064)
			(end 0.7874 -0.4064)
			(stroke
				(width 0.1524)
				(type default)
			)
			(layer "B.SilkS")
		)
		(fp_line
			(start -0.67945 -0.3048)
			(end -0.67945 0.3048)
			(stroke
				(width 0.1)
				(type default)
			)
			(layer "B.Fab")
		)
		(fp_line
			(start -0.67945 0.3048)
			(end -0.120396 0.3048)
			(stroke
				(width 0.1)
				(type default)
			)
			(layer "B.Fab")
		)
		(fp_line
			(start -0.12065 -0.3048)
			(end -0.67945 -0.3048)
			(stroke
				(width 0.1)
				(type default)
			)
			(layer "B.Fab")
		)
		(fp_line
			(start -0.12065 -0.2794)
			(end -0.12065 -0.3048)
			(stroke
				(width 0.1)
				(type default)
			)
			(layer "B.Fab")
		)
		(fp_line
			(start -0.120396 0.2794)
			(end 0.12065 0.2794)
			(stroke
				(width 0.1)
				(type default)
			)
			(layer "B.Fab")
		)
		(fp_line
			(start -0.120396 0.3048)
			(end -0.120396 0.2794)
			(stroke
				(width 0.1)
				(type default)
			)
			(layer "B.Fab")
		)
		(fp_line
			(start 0.12065 -0.305054)
			(end 0.12065 -0.2794)
			(stroke
				(width 0.1)
				(type default)
			)
			(layer "B.Fab")
		)
		(fp_line
			(start 0.12065 -0.2794)
			(end -0.12065 -0.2794)
			(stroke
				(width 0.1)
				(type default)
			)
			(layer "B.Fab")
		)
		(fp_line
			(start 0.12065 0.2794)
			(end 0.12065 0.3048)
			(stroke
				(width 0.1)
				(type default)
			)
			(layer "B.Fab")
		)
		(fp_line
			(start 0.12065 0.3048)
			(end 0.67945 0.3048)
			(stroke
				(width 0.1)
				(type default)
			)
			(layer "B.Fab")
		)
		(fp_line
			(start 0.67945 -0.305054)
			(end 0.12065 -0.305054)
			(stroke
				(width 0.1)
				(type default)
			)
			(layer "B.Fab")
		)
		(fp_line
			(start 0.67945 0.3048)
			(end 0.67945 -0.305054)
			(stroke
				(width 0.1)
				(type default)
			)
			(layer "B.Fab")
		)
		(pad "1" smd circle
			(at 0.40005 0 180)
			(size 0 0)
			(layers "B.Cu" "B.Mask" "B.Paste")
			(net "PVNN_MAIN_CPU0")
		)
		(pad "2" smd circle
			(at -0.40005 0 180)
			(size 0 0)
			(layers "B.Cu" "B.Mask" "B.Paste")
			(net "GND")
		)
	)
	(footprint ""
		(layer "B.Cu")
		(at 186.158886 -193.599816 -90)
		(property "Reference" "R818"
			(at 0 0 90)
			(layer "B.SilkS")
			(hide yes)
			(effects
				(font
					(size 1.27 1.27)
				)
				(justify mirror)
			)
		)
		(property "Value" ""
			(at 0 0 90)
			(layer "B.Fab")
			(effects
				(font
					(size 1.27 1.27)
				)
				(justify mirror)
			)
		)
		(duplicate_pad_numbers_are_jumpers no)
		(fp_line
			(start -0.7874 0.4064)
			(end 0.7874 0.4064)
			(stroke
				(width 0.1524)
				(type default)
			)
			(layer "B.SilkS")
		)
		(fp_line
			(start 0.7874 0.4064)
			(end 0.7874 -0.4064)
			(stroke
				(width 0.1524)
				(type default)
			)
			(layer "B.SilkS")
		)
		(fp_line
			(start -0.7874 -0.4064)
			(end -0.7874 0.4064)
			(stroke
				(width 0.1524)
				(type default)
			)
			(layer "B.SilkS")
		)
		(fp_line
			(start 0.7874 -0.4064)
			(end -0.7874 -0.4064)
			(stroke
				(width 0.1524)
				(type default)
			)
			(layer "B.SilkS")
		)
		(fp_line
			(start -0.67945 0.3048)
			(end -0.120396 0.3048)
			(stroke
				(width 0.1)
				(type default)
			)
			(layer "B.Fab")
		)
		(fp_line
			(start -0.120396 0.3048)
			(end -0.120396 0.2794)
			(stroke
				(width 0.1)
				(type default)
			)
			(layer "B.Fab")
		)
		(fp_line
			(start 0.12065 0.3048)
			(end 0.67945 0.3048)
			(stroke
				(width 0.1)
				(type default)
			)
			(layer "B.Fab")
		)
		(fp_line
			(start 0.67945 0.3048)
			(end 0.67945 -0.305054)
			(stroke
				(width 0.1)
				(type default)
			)
			(layer "B.Fab")
		)
		(fp_line
			(start -0.120396 0.2794)
			(end 0.12065 0.2794)
			(stroke
				(width 0.1)
				(type default)
			)
			(layer "B.Fab")
		)
		(fp_line
			(start 0.12065 0.2794)
			(end 0.12065 0.3048)
			(stroke
				(width 0.1)
				(type default)
			)
			(layer "B.Fab")
		)
		(fp_line
			(start -0.12065 -0.2794)
			(end -0.12065 -0.3048)
			(stroke
				(width 0.1)
				(type default)
			)
			(layer "B.Fab")
		)
		(fp_line
			(start 0.12065 -0.2794)
			(end -0.12065 -0.2794)
			(stroke
				(width 0.1)
				(type default)
			)
			(layer "B.Fab")
		)
		(fp_line
			(start -0.67945 -0.3048)
			(end -0.67945 0.3048)
			(stroke
				(width 0.1)
				(type default)
			)
			(layer "B.Fab")
		)
		(fp_line
			(start -0.12065 -0.3048)
			(end -0.67945 -0.3048)
			(stroke
				(width 0.1)
				(type default)
			)
			(layer "B.Fab")
		)
		(fp_line
			(start 0.12065 -0.305054)
			(end 0.12065 -0.2794)
			(stroke
				(width 0.1)
				(type default)
			)
			(layer "B.Fab")
		)
		(fp_line
			(start 0.67945 -0.305054)
			(end 0.12065 -0.305054)
			(stroke
				(width 0.1)
				(type default)
			)
			(layer "B.Fab")
		)
		(pad "1" smd circle
			(at 0.40005 0 90)
			(size 0 0)
			(layers "B.Cu" "B.Mask" "B.Paste")
			(net "RST_PLD_CPU1_DRAM_EF_N")
		)
		(pad "2" smd circle
			(at -0.40005 0 90)
			(size 0 0)
			(layers "B.Cu" "B.Mask" "B.Paste")
			(net "RST_M_EF_CPU1_FPGA_N")
		)
	)
	(footprint ""
		(layer "B.Cu")
		(at 212.612478 -193.42989)
		(property "Reference" "U22"
			(at 0.09398 2.04089 0)
			(unlocked yes)
			(layer "B.SilkS")
			(effects
				(font
					(size 0.7874 0.5842)
					(thickness 0.1524)
				)
				(justify mirror)
			)
		)
		(property "Value" ""
			(at 0 0 0)
			(layer "B.Fab")
			(effects
				(font
					(size 1.27 1.27)
				)
				(justify mirror)
			)
		)
		(duplicate_pad_numbers_are_jumpers no)
		(fp_line
			(start -1.7272 -1.1176)
			(end -1.7272 1.1176)
			(stroke
				(width 0.1524)
				(type default)
			)
			(layer "B.SilkS")
		)
		(fp_line
			(start -1.7272 -1.1176)
			(end -0.254 -1.1176)
			(stroke
				(width 0.1524)
				(type default)
			)
			(layer "B.SilkS")
		)
		(fp_line
			(start -1.7272 1.1176)
			(end 1.7272 1.1176)
			(stroke
				(width 0.1524)
				(type default)
			)
			(layer "B.SilkS")
		)
		(fp_line
			(start -0.254 -1.1176)
			(end 0 -0.7366)
			(stroke
				(width 0.1524)
				(type default)
			)
			(layer "B.SilkS")
		)
		(fp_line
			(start 0 -0.7366)
			(end 0.254 -1.1176)
			(stroke
				(width 0.1524)
				(type default)
			)
			(layer "B.SilkS")
		)
		(fp_line
			(start 0.254 -1.1176)
			(end 1.7272 -1.1176)
			(stroke
				(width 0.1524)
				(type default)
			)
			(layer "B.SilkS")
		)
		(fp_line
			(start 1.7272 1.1176)
			(end 1.7272 -1.1176)
			(stroke
				(width 0.1524)
				(type default)
			)
			(layer "B.SilkS")
		)
		(fp_poly
			(pts
				(xy 1.86436 -0.898906) (xy 2.177542 -1.05537) (xy 2.177542 -0.742442)
			)
			(stroke
				(width 0)
				(type default)
			)
			(fill yes)
			(layer "B.SilkS")
		)
		(fp_line
			(start -1.5748 -1.1176)
			(end 1.5748 -1.1176)
			(stroke
				(width 0.1)
				(type default)
			)
			(layer "B.Fab")
		)
		(fp_line
			(start -1.5748 1.1176)
			(end -1.5748 -1.1176)
			(stroke
				(width 0.1)
				(type default)
			)
			(layer "B.Fab")
		)
		(fp_line
			(start 1.5748 -1.1176)
			(end 1.5748 1.1176)
			(stroke
				(width 0.1)
				(type default)
			)
			(layer "B.Fab")
		)
		(fp_line
			(start 1.5748 1.1176)
			(end -1.5748 1.1176)
			(stroke
				(width 0.1)
				(type default)
			)
			(layer "B.Fab")
		)
		(fp_poly
			(pts
				(xy 1.9558 -0.649986) (xy 2.7178 -0.268986) (xy 2.7178 -1.030986)
			)
			(stroke
				(width 0)
				(type default)
			)
			(fill yes)
			(layer "B.Fab")
		)
		(pad "1" smd rect
			(at 0.999998 -0.649986 270)
			(size 0.3556 1.1176)
			(layers "B.Cu" "B.Mask" "B.Paste")
			(net "JTAG_CPU0_MUX_GTL_TDO")
		)
		(pad "2" smd rect
			(at 0.999998 0 270)
			(size 0.3556 1.1176)
			(layers "B.Cu" "B.Mask" "B.Paste")
			(net "GND")
		)
		(pad "3" smd rect
			(at 0.999998 0.649986 270)
			(size 0.3556 1.1176)
			(layers "B.Cu" "B.Mask" "B.Paste")
			(net "JTAG_CPU1_MUX_GTL_TDO")
		)
		(pad "4" smd rect
			(at -0.999998 0.649986 270)
			(size 0.3556 1.1176)
			(layers "B.Cu" "B.Mask" "B.Paste")
			(net "JTAG_MUX_QS_GTL_TDO")
		)
		(pad "5" smd rect
			(at -0.999998 0 270)
			(size 0.3556 1.1176)
			(layers "B.Cu" "B.Mask" "B.Paste")
			(net "P3V3_AUX")
		)
		(pad "6" smd rect
			(at -0.999998 -0.649986 270)
			(size 0.3556 1.1176)
			(layers "B.Cu" "B.Mask" "B.Paste")
			(net "FM_CPU1_SKTOCC_N")
		)
	)
	(footprint ""
		(layer "B.Cu")
		(at 158.825946 -321.554856 -90)
		(property "Reference" "C91"
			(at 0 0 90)
			(layer "B.SilkS")
			(hide yes)
			(effects
				(font
					(size 1.27 1.27)
				)
				(justify mirror)
			)
		)
		(property "Value" ""
			(at 0 0 90)
			(layer "B.Fab")
			(effects
				(font
					(size 1.27 1.27)
				)
				(justify mirror)
			)
		)
		(duplicate_pad_numbers_are_jumpers no)
		(fp_line
			(start -1.524 0.762)
			(end 1.524 0.762)
			(stroke
				(width 0.1524)
				(type default)
			)
			(layer "B.SilkS")
		)
		(fp_line
			(start 1.524 0.762)
			(end 1.524 -0.762)
			(stroke
				(width 0.1524)
				(type default)
			)
			(layer "B.SilkS")
		)
		(fp_line
			(start -1.524 -0.762)
			(end -1.524 0.762)
			(stroke
				(width 0.1524)
				(type default)
			)
			(layer "B.SilkS")
		)
		(fp_line
			(start 1.524 -0.762)
			(end -1.524 -0.762)
			(stroke
				(width 0.1524)
				(type default)
			)
			(layer "B.SilkS")
		)
		(fp_line
			(start -1.1049 0.724916)
			(end -1.1049 -0.724916)
			(stroke
				(width 0.1)
				(type default)
			)
			(layer "B.Fab")
		)
		(fp_line
			(start 1.1049 0.724916)
			(end -1.1049 0.724916)
			(stroke
				(width 0.1)
				(type default)
			)
			(layer "B.Fab")
		)
		(fp_line
			(start -1.1049 -0.724916)
			(end 1.1049 -0.724916)
			(stroke
				(width 0.1)
				(type default)
			)
			(layer "B.Fab")
		)
		(fp_line
			(start 1.1049 -0.724916)
			(end 1.1049 0.724916)
			(stroke
				(width 0.1)
				(type default)
			)
			(layer "B.Fab")
		)
		(pad "1" smd rect
			(at 0.889 0 270)
			(size 1.016 1.27)
			(layers "B.Cu" "B.Mask" "B.Paste")
			(net "P12V_S3_AUX_CPU1_NVDIMM")
		)
		(pad "2" smd rect
			(at -0.889 0 270)
			(size 1.016 1.27)
			(layers "B.Cu" "B.Mask" "B.Paste")
			(net "GND")
		)
	)
	(footprint ""
		(layer "B.Cu")
		(at 204.133958 -194.03441)
		(property "Reference" "C539"
			(at 0 0 0)
			(layer "B.SilkS")
			(hide yes)
			(effects
				(font
					(size 1.27 1.27)
				)
				(justify mirror)
			)
		)
		(property "Value" ""
			(at 0 0 0)
			(layer "B.Fab")
			(effects
				(font
					(size 1.27 1.27)
				)
				(justify mirror)
			)
		)
		(duplicate_pad_numbers_are_jumpers no)
		(fp_line
			(start -0.7874 -0.4064)
			(end -0.7874 0.4064)
			(stroke
				(width 0.1524)
				(type default)
			)
			(layer "B.SilkS")
		)
		(fp_line
			(start -0.7874 0.4064)
			(end 0.7874 0.4064)
			(stroke
				(width 0.1524)
				(type default)
			)
			(layer "B.SilkS")
		)
		(fp_line
			(start 0.7874 -0.4064)
			(end -0.7874 -0.4064)
			(stroke
				(width 0.1524)
				(type default)
			)
			(layer "B.SilkS")
		)
		(fp_line
			(start 0.7874 0.4064)
			(end 0.7874 -0.4064)
			(stroke
				(width 0.1524)
				(type default)
			)
			(layer "B.SilkS")
		)
		(fp_line
			(start -0.67945 -0.3048)
			(end -0.67945 0.3048)
			(stroke
				(width 0.1)
				(type default)
			)
			(layer "B.Fab")
		)
		(fp_line
			(start -0.67945 0.3048)
			(end -0.120396 0.3048)
			(stroke
				(width 0.1)
				(type default)
			)
			(layer "B.Fab")
		)
		(fp_line
			(start -0.12065 -0.3048)
			(end -0.67945 -0.3048)
			(stroke
				(width 0.1)
				(type default)
			)
			(layer "B.Fab")
		)
		(fp_line
			(start -0.12065 -0.2794)
			(end -0.12065 -0.3048)
			(stroke
				(width 0.1)
				(type default)
			)
			(layer "B.Fab")
		)
		(fp_line
			(start -0.120396 0.2794)
			(end 0.12065 0.2794)
			(stroke
				(width 0.1)
				(type default)
			)
			(layer "B.Fab")
		)
		(fp_line
			(start -0.120396 0.3048)
			(end -0.120396 0.2794)
			(stroke
				(width 0.1)
				(type default)
			)
			(layer "B.Fab")
		)
		(fp_line
			(start 0.12065 -0.305054)
			(end 0.12065 -0.2794)
			(stroke
				(width 0.1)
				(type default)
			)
			(layer "B.Fab")
		)
		(fp_line
			(start 0.12065 -0.2794)
			(end -0.12065 -0.2794)
			(stroke
				(width 0.1)
				(type default)
			)
			(layer "B.Fab")
		)
		(fp_line
			(start 0.12065 0.2794)
			(end 0.12065 0.3048)
			(stroke
				(width 0.1)
				(type default)
			)
			(layer "B.Fab")
		)
		(fp_line
			(start 0.12065 0.3048)
			(end 0.67945 0.3048)
			(stroke
				(width 0.1)
				(type default)
			)
			(layer "B.Fab")
		)
		(fp_line
			(start 0.67945 -0.305054)
			(end 0.12065 -0.305054)
			(stroke
				(width 0.1)
				(type default)
			)
			(layer "B.Fab")
		)
		(fp_line
			(start 0.67945 0.3048)
			(end 0.67945 -0.305054)
			(stroke
				(width 0.1)
				(type default)
			)
			(layer "B.Fab")
		)
		(pad "1" smd circle
			(at 0.40005 0 180)
			(size 0 0)
			(layers "B.Cu" "B.Mask" "B.Paste")
			(net "P3V3_AUX")
		)
		(pad "2" smd circle
			(at -0.40005 0 180)
			(size 0 0)
			(layers "B.Cu" "B.Mask" "B.Paste")
			(net "GND")
		)
	)
	(footprint ""
		(layer "B.Cu")
		(at 109.944154 -411.438598 -90)
		(property "Reference" "C2336"
			(at 0 0 90)
			(layer "B.SilkS")
			(hide yes)
			(effects
				(font
					(size 1.27 1.27)
				)
				(justify mirror)
			)
		)
		(property "Value" ""
			(at 0 0 90)
			(layer "B.Fab")
			(effects
				(font
					(size 1.27 1.27)
				)
				(justify mirror)
			)
		)
		(duplicate_pad_numbers_are_jumpers no)
		(fp_line
			(start -0.7874 0.4064)
			(end 0.7874 0.4064)
			(stroke
				(width 0.1524)
				(type default)
			)
			(layer "B.SilkS")
		)
		(fp_line
			(start 0.7874 0.4064)
			(end 0.7874 -0.4064)
			(stroke
				(width 0.1524)
				(type default)
			)
			(layer "B.SilkS")
		)
		(fp_line
			(start -0.7874 -0.4064)
			(end -0.7874 0.4064)
			(stroke
				(width 0.1524)
				(type default)
			)
			(layer "B.SilkS")
		)
		(fp_line
			(start 0.7874 -0.4064)
			(end -0.7874 -0.4064)
			(stroke
				(width 0.1524)
				(type default)
			)
			(layer "B.SilkS")
		)
		(fp_line
			(start -0.67945 0.3048)
			(end -0.120396 0.3048)
			(stroke
				(width 0.1)
				(type default)
			)
			(layer "B.Fab")
		)
		(fp_line
			(start -0.120396 0.3048)
			(end -0.120396 0.2794)
			(stroke
				(width 0.1)
				(type default)
			)
			(layer "B.Fab")
		)
		(fp_line
			(start 0.12065 0.3048)
			(end 0.67945 0.3048)
			(stroke
				(width 0.1)
				(type default)
			)
			(layer "B.Fab")
		)
		(fp_line
			(start 0.67945 0.3048)
			(end 0.67945 -0.305054)
			(stroke
				(width 0.1)
				(type default)
			)
			(layer "B.Fab")
		)
		(fp_line
			(start -0.120396 0.2794)
			(end 0.12065 0.2794)
			(stroke
				(width 0.1)
				(type default)
			)
			(layer "B.Fab")
		)
		(fp_line
			(start 0.12065 0.2794)
			(end 0.12065 0.3048)
			(stroke
				(width 0.1)
				(type default)
			)
			(layer "B.Fab")
		)
		(fp_line
			(start -0.12065 -0.2794)
			(end -0.12065 -0.3048)
			(stroke
				(width 0.1)
				(type default)
			)
			(layer "B.Fab")
		)
		(fp_line
			(start 0.12065 -0.2794)
			(end -0.12065 -0.2794)
			(stroke
				(width 0.1)
				(type default)
			)
			(layer "B.Fab")
		)
		(fp_line
			(start -0.67945 -0.3048)
			(end -0.67945 0.3048)
			(stroke
				(width 0.1)
				(type default)
			)
			(layer "B.Fab")
		)
		(fp_line
			(start -0.12065 -0.3048)
			(end -0.67945 -0.3048)
			(stroke
				(width 0.1)
				(type default)
			)
			(layer "B.Fab")
		)
		(fp_line
			(start 0.12065 -0.305054)
			(end 0.12065 -0.2794)
			(stroke
				(width 0.1)
				(type default)
			)
			(layer "B.Fab")
		)
		(fp_line
			(start 0.67945 -0.305054)
			(end 0.12065 -0.305054)
			(stroke
				(width 0.1)
				(type default)
			)
			(layer "B.Fab")
		)
		(pad "1" smd circle
			(at 0.40005 0 90)
			(size 0 0)
			(layers "B.Cu" "B.Mask" "B.Paste")
			(net "P3V3_9ZXL045_VDD")
		)
		(pad "2" smd circle
			(at -0.40005 0 90)
			(size 0 0)
			(layers "B.Cu" "B.Mask" "B.Paste")
			(net "GND")
		)
	)
	(footprint ""
		(layer "B.Cu")
		(at 175.273208 -198.114158)
		(property "Reference" "R268"
			(at 0 0 0)
			(layer "B.SilkS")
			(hide yes)
			(effects
				(font
					(size 1.27 1.27)
				)
				(justify mirror)
			)
		)
		(property "Value" ""
			(at 0 0 0)
			(layer "B.Fab")
			(effects
				(font
					(size 1.27 1.27)
				)
				(justify mirror)
			)
		)
		(duplicate_pad_numbers_are_jumpers no)
		(fp_line
			(start -0.7874 -0.4064)
			(end -0.7874 0.4064)
			(stroke
				(width 0.1524)
				(type default)
			)
			(layer "B.SilkS")
		)
		(fp_line
			(start -0.7874 0.4064)
			(end 0.7874 0.4064)
			(stroke
				(width 0.1524)
				(type default)
			)
			(layer "B.SilkS")
		)
		(fp_line
			(start 0.7874 -0.4064)
			(end -0.7874 -0.4064)
			(stroke
				(width 0.1524)
				(type default)
			)
			(layer "B.SilkS")
		)
		(fp_line
			(start 0.7874 0.4064)
			(end 0.7874 -0.4064)
			(stroke
				(width 0.1524)
				(type default)
			)
			(layer "B.SilkS")
		)
		(fp_line
			(start -0.67945 -0.3048)
			(end -0.67945 0.3048)
			(stroke
				(width 0.1)
				(type default)
			)
			(layer "B.Fab")
		)
		(fp_line
			(start -0.67945 0.3048)
			(end -0.120396 0.3048)
			(stroke
				(width 0.1)
				(type default)
			)
			(layer "B.Fab")
		)
		(fp_line
			(start -0.12065 -0.3048)
			(end -0.67945 -0.3048)
			(stroke
				(width 0.1)
				(type default)
			)
			(layer "B.Fab")
		)
		(fp_line
			(start -0.12065 -0.2794)
			(end -0.12065 -0.3048)
			(stroke
				(width 0.1)
				(type default)
			)
			(layer "B.Fab")
		)
		(fp_line
			(start -0.120396 0.2794)
			(end 0.12065 0.2794)
			(stroke
				(width 0.1)
				(type default)
			)
			(layer "B.Fab")
		)
		(fp_line
			(start -0.120396 0.3048)
			(end -0.120396 0.2794)
			(stroke
				(width 0.1)
				(type default)
			)
			(layer "B.Fab")
		)
		(fp_line
			(start 0.12065 -0.305054)
			(end 0.12065 -0.2794)
			(stroke
				(width 0.1)
				(type default)
			)
			(layer "B.Fab")
		)
		(fp_line
			(start 0.12065 -0.2794)
			(end -0.12065 -0.2794)
			(stroke
				(width 0.1)
				(type default)
			)
			(layer "B.Fab")
		)
		(fp_line
			(start 0.12065 0.2794)
			(end 0.12065 0.3048)
			(stroke
				(width 0.1)
				(type default)
			)
			(layer "B.Fab")
		)
		(fp_line
			(start 0.12065 0.3048)
			(end 0.67945 0.3048)
			(stroke
				(width 0.1)
				(type default)
			)
			(layer "B.Fab")
		)
		(fp_line
			(start 0.67945 -0.305054)
			(end 0.12065 -0.305054)
			(stroke
				(width 0.1)
				(type default)
			)
			(layer "B.Fab")
		)
		(fp_line
			(start 0.67945 0.3048)
			(end 0.67945 -0.305054)
			(stroke
				(width 0.1)
				(type default)
			)
			(layer "B.Fab")
		)
		(pad "1" smd circle
			(at 0.40005 0 180)
			(size 0 0)
			(layers "B.Cu" "B.Mask" "B.Paste")
			(net "PVNN_TERM_CPU1")
		)
		(pad "2" smd circle
			(at -0.40005 0 180)
			(size 0 0)
			(layers "B.Cu" "B.Mask" "B.Paste")
			(net "PU_CPU1_LEGACY_SKT")
		)
	)
	(footprint ""
		(layer "B.Cu")
		(at 117.529102 -324.792086 -90)
		(property "Reference" "PC542_P1_3"
			(at 0 0 90)
			(layer "B.SilkS")
			(hide yes)
			(effects
				(font
					(size 1.27 1.27)
				)
				(justify mirror)
			)
		)
		(property "Value" ""
			(at 0 0 90)
			(layer "B.Fab")
			(effects
				(font
					(size 1.27 1.27)
				)
				(justify mirror)
			)
		)
		(duplicate_pad_numbers_are_jumpers no)
		(fp_line
			(start -1.524 0.762)
			(end 1.524 0.762)
			(stroke
				(width 0.1524)
				(type default)
			)
			(layer "B.SilkS")
		)
		(fp_line
			(start 1.524 0.762)
			(end 1.524 -0.762)
			(stroke
				(width 0.1524)
				(type default)
			)
			(layer "B.SilkS")
		)
		(fp_line
			(start -1.524 -0.762)
			(end -1.524 0.762)
			(stroke
				(width 0.1524)
				(type default)
			)
			(layer "B.SilkS")
		)
		(fp_line
			(start 1.524 -0.762)
			(end -1.524 -0.762)
			(stroke
				(width 0.1524)
				(type default)
			)
			(layer "B.SilkS")
		)
		(fp_line
			(start -1.1049 0.724916)
			(end -1.1049 -0.724916)
			(stroke
				(width 0.1)
				(type default)
			)
			(layer "B.Fab")
		)
		(fp_line
			(start 1.1049 0.724916)
			(end -1.1049 0.724916)
			(stroke
				(width 0.1)
				(type default)
			)
			(layer "B.Fab")
		)
		(fp_line
			(start -1.1049 -0.724916)
			(end 1.1049 -0.724916)
			(stroke
				(width 0.1)
				(type default)
			)
			(layer "B.Fab")
		)
		(fp_line
			(start 1.1049 -0.724916)
			(end 1.1049 0.724916)
			(stroke
				(width 0.1)
				(type default)
			)
			(layer "B.Fab")
		)
		(pad "1" smd rect
			(at 0.889 0 270)
			(size 1.016 1.27)
			(layers "B.Cu" "B.Mask" "B.Paste")
			(net "PVCCIN_CPU1")
		)
		(pad "2" smd rect
			(at -0.889 0 270)
			(size 1.016 1.27)
			(layers "B.Cu" "B.Mask" "B.Paste")
			(net "GND")
		)
	)
	(footprint ""
		(layer "B.Cu")
		(at 155.074112 -38.579552 180)
		(property "Reference" "C2320"
			(at 0 0 0)
			(layer "B.SilkS")
			(hide yes)
			(effects
				(font
					(size 1.27 1.27)
				)
				(justify mirror)
			)
		)
		(property "Value" ""
			(at 0 0 0)
			(layer "B.Fab")
			(effects
				(font
					(size 1.27 1.27)
				)
				(justify mirror)
			)
		)
		(duplicate_pad_numbers_are_jumpers no)
		(fp_line
			(start 0.7874 0.4064)
			(end 0.7874 -0.4064)
			(stroke
				(width 0.1524)
				(type default)
			)
			(layer "B.SilkS")
		)
		(fp_line
			(start 0.7874 -0.4064)
			(end -0.7874 -0.4064)
			(stroke
				(width 0.1524)
				(type default)
			)
			(layer "B.SilkS")
		)
		(fp_line
			(start -0.7874 0.4064)
			(end 0.7874 0.4064)
			(stroke
				(width 0.1524)
				(type default)
			)
			(layer "B.SilkS")
		)
		(fp_line
			(start -0.7874 -0.4064)
			(end -0.7874 0.4064)
			(stroke
				(width 0.1524)
				(type default)
			)
			(layer "B.SilkS")
		)
		(fp_line
			(start 0.67945 0.3048)
			(end 0.67945 -0.305054)
			(stroke
				(width 0.1)
				(type default)
			)
			(layer "B.Fab")
		)
		(fp_line
			(start 0.67945 -0.305054)
			(end 0.12065 -0.305054)
			(stroke
				(width 0.1)
				(type default)
			)
			(layer "B.Fab")
		)
		(fp_line
			(start 0.12065 0.3048)
			(end 0.67945 0.3048)
			(stroke
				(width 0.1)
				(type default)
			)
			(layer "B.Fab")
		)
		(fp_line
			(start 0.12065 0.2794)
			(end 0.12065 0.3048)
			(stroke
				(width 0.1)
				(type default)
			)
			(layer "B.Fab")
		)
		(fp_line
			(start 0.12065 -0.2794)
			(end -0.12065 -0.2794)
			(stroke
				(width 0.1)
				(type default)
			)
			(layer "B.Fab")
		)
		(fp_line
			(start 0.12065 -0.305054)
			(end 0.12065 -0.2794)
			(stroke
				(width 0.1)
				(type default)
			)
			(layer "B.Fab")
		)
		(fp_line
			(start -0.120396 0.3048)
			(end -0.120396 0.2794)
			(stroke
				(width 0.1)
				(type default)
			)
			(layer "B.Fab")
		)
		(fp_line
			(start -0.120396 0.2794)
			(end 0.12065 0.2794)
			(stroke
				(width 0.1)
				(type default)
			)
			(layer "B.Fab")
		)
		(fp_line
			(start -0.12065 -0.2794)
			(end -0.12065 -0.3048)
			(stroke
				(width 0.1)
				(type default)
			)
			(layer "B.Fab")
		)
		(fp_line
			(start -0.12065 -0.3048)
			(end -0.67945 -0.3048)
			(stroke
				(width 0.1)
				(type default)
			)
			(layer "B.Fab")
		)
		(fp_line
			(start -0.67945 0.3048)
			(end -0.120396 0.3048)
			(stroke
				(width 0.1)
				(type default)
			)
			(layer "B.Fab")
		)
		(fp_line
			(start -0.67945 -0.3048)
			(end -0.67945 0.3048)
			(stroke
				(width 0.1)
				(type default)
			)
			(layer "B.Fab")
		)
		(pad "1" smd circle
			(at 0.40005 0)
			(size 0 0)
			(layers "B.Cu" "B.Mask" "B.Paste")
			(net "P3V3_AUX_USB_HUB_2")
		)
		(pad "2" smd circle
			(at -0.40005 0)
			(size 0 0)
			(layers "B.Cu" "B.Mask" "B.Paste")
			(net "GND")
		)
	)
	(footprint ""
		(layer "B.Cu")
		(at 154.21102 -227.427536 180)
		(property "Reference" "R962"
			(at 0 0 0)
			(layer "B.SilkS")
			(hide yes)
			(effects
				(font
					(size 1.27 1.27)
				)
				(justify mirror)
			)
		)
		(property "Value" ""
			(at 0 0 0)
			(layer "B.Fab")
			(effects
				(font
					(size 1.27 1.27)
				)
				(justify mirror)
			)
		)
		(duplicate_pad_numbers_are_jumpers no)
		(fp_line
			(start 0.7874 0.4064)
			(end 0.7874 -0.4064)
			(stroke
				(width 0.1524)
				(type default)
			)
			(layer "B.SilkS")
		)
		(fp_line
			(start 0.7874 -0.4064)
			(end -0.7874 -0.4064)
			(stroke
				(width 0.1524)
				(type default)
			)
			(layer "B.SilkS")
		)
		(fp_line
			(start -0.7874 0.4064)
			(end 0.7874 0.4064)
			(stroke
				(width 0.1524)
				(type default)
			)
			(layer "B.SilkS")
		)
		(fp_line
			(start -0.7874 -0.4064)
			(end -0.7874 0.4064)
			(stroke
				(width 0.1524)
				(type default)
			)
			(layer "B.SilkS")
		)
		(fp_line
			(start 0.67945 0.3048)
			(end 0.67945 -0.305054)
			(stroke
				(width 0.1)
				(type default)
			)
			(layer "B.Fab")
		)
		(fp_line
			(start 0.67945 -0.305054)
			(end 0.12065 -0.305054)
			(stroke
				(width 0.1)
				(type default)
			)
			(layer "B.Fab")
		)
		(fp_line
			(start 0.12065 0.3048)
			(end 0.67945 0.3048)
			(stroke
				(width 0.1)
				(type default)
			)
			(layer "B.Fab")
		)
		(fp_line
			(start 0.12065 0.2794)
			(end 0.12065 0.3048)
			(stroke
				(width 0.1)
				(type default)
			)
			(layer "B.Fab")
		)
		(fp_line
			(start 0.12065 -0.2794)
			(end -0.12065 -0.2794)
			(stroke
				(width 0.1)
				(type default)
			)
			(layer "B.Fab")
		)
		(fp_line
			(start 0.12065 -0.305054)
			(end 0.12065 -0.2794)
			(stroke
				(width 0.1)
				(type default)
			)
			(layer "B.Fab")
		)
		(fp_line
			(start -0.120396 0.3048)
			(end -0.120396 0.2794)
			(stroke
				(width 0.1)
				(type default)
			)
			(layer "B.Fab")
		)
		(fp_line
			(start -0.120396 0.2794)
			(end 0.12065 0.2794)
			(stroke
				(width 0.1)
				(type default)
			)
			(layer "B.Fab")
		)
		(fp_line
			(start -0.12065 -0.2794)
			(end -0.12065 -0.3048)
			(stroke
				(width 0.1)
				(type default)
			)
			(layer "B.Fab")
		)
		(fp_line
			(start -0.12065 -0.3048)
			(end -0.67945 -0.3048)
			(stroke
				(width 0.1)
				(type default)
			)
			(layer "B.Fab")
		)
		(fp_line
			(start -0.67945 0.3048)
			(end -0.120396 0.3048)
			(stroke
				(width 0.1)
				(type default)
			)
			(layer "B.Fab")
		)
		(fp_line
			(start -0.67945 -0.3048)
			(end -0.67945 0.3048)
			(stroke
				(width 0.1)
				(type default)
			)
			(layer "B.Fab")
		)
		(pad "1" smd circle
			(at 0.40005 0)
			(size 0 0)
			(layers "B.Cu" "B.Mask" "B.Paste")
			(net "SMB_PEHPCPU1_GTL_SDA")
		)
		(pad "2" smd circle
			(at -0.40005 0)
			(size 0 0)
			(layers "B.Cu" "B.Mask" "B.Paste")
			(net "SMB_PEHPCPU1_GTL_R_SDA")
		)
	)
	(footprint ""
		(layer "B.Cu")
		(at 304.138584 -153.501344 -90)
		(property "Reference" "R684"
			(at 0 0 90)
			(layer "B.SilkS")
			(hide yes)
			(effects
				(font
					(size 1.27 1.27)
				)
				(justify mirror)
			)
		)
		(property "Value" ""
			(at 0 0 90)
			(layer "B.Fab")
			(effects
				(font
					(size 1.27 1.27)
				)
				(justify mirror)
			)
		)
		(duplicate_pad_numbers_are_jumpers no)
		(fp_line
			(start -0.7874 0.4064)
			(end 0.7874 0.4064)
			(stroke
				(width 0.1524)
				(type default)
			)
			(layer "B.SilkS")
		)
		(fp_line
			(start 0.7874 0.4064)
			(end 0.7874 -0.4064)
			(stroke
				(width 0.1524)
				(type default)
			)
			(layer "B.SilkS")
		)
		(fp_line
			(start -0.7874 -0.4064)
			(end -0.7874 0.4064)
			(stroke
				(width 0.1524)
				(type default)
			)
			(layer "B.SilkS")
		)
		(fp_line
			(start 0.7874 -0.4064)
			(end -0.7874 -0.4064)
			(stroke
				(width 0.1524)
				(type default)
			)
			(layer "B.SilkS")
		)
		(fp_line
			(start -0.67945 0.3048)
			(end -0.120396 0.3048)
			(stroke
				(width 0.1)
				(type default)
			)
			(layer "B.Fab")
		)
		(fp_line
			(start -0.120396 0.3048)
			(end -0.120396 0.2794)
			(stroke
				(width 0.1)
				(type default)
			)
			(layer "B.Fab")
		)
		(fp_line
			(start 0.12065 0.3048)
			(end 0.67945 0.3048)
			(stroke
				(width 0.1)
				(type default)
			)
			(layer "B.Fab")
		)
		(fp_line
			(start 0.67945 0.3048)
			(end 0.67945 -0.305054)
			(stroke
				(width 0.1)
				(type default)
			)
			(layer "B.Fab")
		)
		(fp_line
			(start -0.120396 0.2794)
			(end 0.12065 0.2794)
			(stroke
				(width 0.1)
				(type default)
			)
			(layer "B.Fab")
		)
		(fp_line
			(start 0.12065 0.2794)
			(end 0.12065 0.3048)
			(stroke
				(width 0.1)
				(type default)
			)
			(layer "B.Fab")
		)
		(fp_line
			(start -0.12065 -0.2794)
			(end -0.12065 -0.3048)
			(stroke
				(width 0.1)
				(type default)
			)
			(layer "B.Fab")
		)
		(fp_line
			(start 0.12065 -0.2794)
			(end -0.12065 -0.2794)
			(stroke
				(width 0.1)
				(type default)
			)
			(layer "B.Fab")
		)
		(fp_line
			(start -0.67945 -0.3048)
			(end -0.67945 0.3048)
			(stroke
				(width 0.1)
				(type default)
			)
			(layer "B.Fab")
		)
		(fp_line
			(start -0.12065 -0.3048)
			(end -0.67945 -0.3048)
			(stroke
				(width 0.1)
				(type default)
			)
			(layer "B.Fab")
		)
		(fp_line
			(start 0.12065 -0.305054)
			(end 0.12065 -0.2794)
			(stroke
				(width 0.1)
				(type default)
			)
			(layer "B.Fab")
		)
		(fp_line
			(start 0.67945 -0.305054)
			(end 0.12065 -0.305054)
			(stroke
				(width 0.1)
				(type default)
			)
			(layer "B.Fab")
		)
		(pad "1" smd circle
			(at 0.40005 0 90)
			(size 0 0)
			(layers "B.Cu" "B.Mask" "B.Paste")
			(net "I3C_SPD_DDREFGH_CPU0_R_SCL")
		)
		(pad "2" smd circle
			(at -0.40005 0 90)
			(size 0 0)
			(layers "B.Cu" "B.Mask" "B.Paste")
			(net "I3C_SPD_DDREFGH_CPU0_LVC1_R_SCL")
		)
	)
	(footprint ""
		(layer "B.Cu")
		(at 267.652246 -193.503296 -90)
		(property "Reference" "R707"
			(at 0 0 90)
			(layer "B.SilkS")
			(hide yes)
			(effects
				(font
					(size 1.27 1.27)
				)
				(justify mirror)
			)
		)
		(property "Value" ""
			(at 0 0 90)
			(layer "B.Fab")
			(effects
				(font
					(size 1.27 1.27)
				)
				(justify mirror)
			)
		)
		(duplicate_pad_numbers_are_jumpers no)
		(fp_line
			(start -0.7874 0.4064)
			(end 0.7874 0.4064)
			(stroke
				(width 0.1524)
				(type default)
			)
			(layer "B.SilkS")
		)
		(fp_line
			(start 0.7874 0.4064)
			(end 0.7874 -0.4064)
			(stroke
				(width 0.1524)
				(type default)
			)
			(layer "B.SilkS")
		)
		(fp_line
			(start -0.7874 -0.4064)
			(end -0.7874 0.4064)
			(stroke
				(width 0.1524)
				(type default)
			)
			(layer "B.SilkS")
		)
		(fp_line
			(start 0.7874 -0.4064)
			(end -0.7874 -0.4064)
			(stroke
				(width 0.1524)
				(type default)
			)
			(layer "B.SilkS")
		)
		(fp_line
			(start -0.67945 0.3048)
			(end -0.120396 0.3048)
			(stroke
				(width 0.1)
				(type default)
			)
			(layer "B.Fab")
		)
		(fp_line
			(start -0.120396 0.3048)
			(end -0.120396 0.2794)
			(stroke
				(width 0.1)
				(type default)
			)
			(layer "B.Fab")
		)
		(fp_line
			(start 0.12065 0.3048)
			(end 0.67945 0.3048)
			(stroke
				(width 0.1)
				(type default)
			)
			(layer "B.Fab")
		)
		(fp_line
			(start 0.67945 0.3048)
			(end 0.67945 -0.305054)
			(stroke
				(width 0.1)
				(type default)
			)
			(layer "B.Fab")
		)
		(fp_line
			(start -0.120396 0.2794)
			(end 0.12065 0.2794)
			(stroke
				(width 0.1)
				(type default)
			)
			(layer "B.Fab")
		)
		(fp_line
			(start 0.12065 0.2794)
			(end 0.12065 0.3048)
			(stroke
				(width 0.1)
				(type default)
			)
			(layer "B.Fab")
		)
		(fp_line
			(start -0.12065 -0.2794)
			(end -0.12065 -0.3048)
			(stroke
				(width 0.1)
				(type default)
			)
			(layer "B.Fab")
		)
		(fp_line
			(start 0.12065 -0.2794)
			(end -0.12065 -0.2794)
			(stroke
				(width 0.1)
				(type default)
			)
			(layer "B.Fab")
		)
		(fp_line
			(start -0.67945 -0.3048)
			(end -0.67945 0.3048)
			(stroke
				(width 0.1)
				(type default)
			)
			(layer "B.Fab")
		)
		(fp_line
			(start -0.12065 -0.3048)
			(end -0.67945 -0.3048)
			(stroke
				(width 0.1)
				(type default)
			)
			(layer "B.Fab")
		)
		(fp_line
			(start 0.12065 -0.305054)
			(end 0.12065 -0.2794)
			(stroke
				(width 0.1)
				(type default)
			)
			(layer "B.Fab")
		)
		(fp_line
			(start 0.67945 -0.305054)
			(end 0.12065 -0.305054)
			(stroke
				(width 0.1)
				(type default)
			)
			(layer "B.Fab")
		)
		(pad "1" smd circle
			(at 0.40005 0 90)
			(size 0 0)
			(layers "B.Cu" "B.Mask" "B.Paste")
			(net "RST_PLD_CPU0_DRAM_CD_N")
		)
		(pad "2" smd circle
			(at -0.40005 0 90)
			(size 0 0)
			(layers "B.Cu" "B.Mask" "B.Paste")
			(net "GND")
		)
	)
	(footprint ""
		(layer "B.Cu")
		(at 243.496084 -397.067024 180)
		(property "Reference" "PR2537"
			(at 0 0 0)
			(layer "B.SilkS")
			(hide yes)
			(effects
				(font
					(size 1.27 1.27)
				)
				(justify mirror)
			)
		)
		(property "Value" ""
			(at 0 0 0)
			(layer "B.Fab")
			(effects
				(font
					(size 1.27 1.27)
				)
				(justify mirror)
			)
		)
		(duplicate_pad_numbers_are_jumpers no)
		(fp_line
			(start 0.7874 0.4064)
			(end 0.7874 -0.4064)
			(stroke
				(width 0.1524)
				(type default)
			)
			(layer "B.SilkS")
		)
		(fp_line
			(start 0.7874 -0.4064)
			(end -0.7874 -0.4064)
			(stroke
				(width 0.1524)
				(type default)
			)
			(layer "B.SilkS")
		)
		(fp_line
			(start -0.7874 0.4064)
			(end 0.7874 0.4064)
			(stroke
				(width 0.1524)
				(type default)
			)
			(layer "B.SilkS")
		)
		(fp_line
			(start -0.7874 -0.4064)
			(end -0.7874 0.4064)
			(stroke
				(width 0.1524)
				(type default)
			)
			(layer "B.SilkS")
		)
		(fp_line
			(start 0.67945 0.3048)
			(end 0.67945 -0.305054)
			(stroke
				(width 0.1)
				(type default)
			)
			(layer "B.Fab")
		)
		(fp_line
			(start 0.67945 -0.305054)
			(end 0.12065 -0.305054)
			(stroke
				(width 0.1)
				(type default)
			)
			(layer "B.Fab")
		)
		(fp_line
			(start 0.12065 0.3048)
			(end 0.67945 0.3048)
			(stroke
				(width 0.1)
				(type default)
			)
			(layer "B.Fab")
		)
		(fp_line
			(start 0.12065 0.2794)
			(end 0.12065 0.3048)
			(stroke
				(width 0.1)
				(type default)
			)
			(layer "B.Fab")
		)
		(fp_line
			(start 0.12065 -0.2794)
			(end -0.12065 -0.2794)
			(stroke
				(width 0.1)
				(type default)
			)
			(layer "B.Fab")
		)
		(fp_line
			(start 0.12065 -0.305054)
			(end 0.12065 -0.2794)
			(stroke
				(width 0.1)
				(type default)
			)
			(layer "B.Fab")
		)
		(fp_line
			(start -0.120396 0.3048)
			(end -0.120396 0.2794)
			(stroke
				(width 0.1)
				(type default)
			)
			(layer "B.Fab")
		)
		(fp_line
			(start -0.120396 0.2794)
			(end 0.12065 0.2794)
			(stroke
				(width 0.1)
				(type default)
			)
			(layer "B.Fab")
		)
		(fp_line
			(start -0.12065 -0.2794)
			(end -0.12065 -0.3048)
			(stroke
				(width 0.1)
				(type default)
			)
			(layer "B.Fab")
		)
		(fp_line
			(start -0.12065 -0.3048)
			(end -0.67945 -0.3048)
			(stroke
				(width 0.1)
				(type default)
			)
			(layer "B.Fab")
		)
		(fp_line
			(start -0.67945 0.3048)
			(end -0.120396 0.3048)
			(stroke
				(width 0.1)
				(type default)
			)
			(layer "B.Fab")
		)
		(fp_line
			(start -0.67945 -0.3048)
			(end -0.67945 0.3048)
			(stroke
				(width 0.1)
				(type default)
			)
			(layer "B.Fab")
		)
		(pad "1" smd circle
			(at 0.40005 0)
			(size 0 0)
			(layers "B.Cu" "B.Mask" "B.Paste")
			(net "P12V_AUX")
		)
		(pad "2" smd circle
			(at -0.40005 0)
			(size 0 0)
			(layers "B.Cu" "B.Mask" "B.Paste")
			(net "P12V_HSC_GATE_RC")
		)
	)
	(footprint ""
		(layer "B.Cu")
		(at 318.262254 -65.048892)
		(property "Reference" "C1184"
			(at 0 0 0)
			(layer "B.SilkS")
			(hide yes)
			(effects
				(font
					(size 1.27 1.27)
				)
				(justify mirror)
			)
		)
		(property "Value" ""
			(at 0 0 0)
			(layer "B.Fab")
			(effects
				(font
					(size 1.27 1.27)
				)
				(justify mirror)
			)
		)
		(duplicate_pad_numbers_are_jumpers no)
		(fp_line
			(start -1.2954 -0.5842)
			(end -1.2954 0.5842)
			(stroke
				(width 0.1524)
				(type default)
			)
			(layer "B.SilkS")
		)
		(fp_line
			(start -1.2954 0.5842)
			(end 1.2954 0.5842)
			(stroke
				(width 0.1524)
				(type default)
			)
			(layer "B.SilkS")
		)
		(fp_line
			(start 0 -0.5842)
			(end 0 0.5842)
			(stroke
				(width 0.1524)
				(type default)
			)
			(layer "B.SilkS")
		)
		(fp_line
			(start 1.2954 -0.5842)
			(end -1.2954 -0.5842)
			(stroke
				(width 0.1524)
				(type default)
			)
			(layer "B.SilkS")
		)
		(fp_line
			(start 1.2954 0.5842)
			(end 1.2954 -0.5842)
			(stroke
				(width 0.1524)
				(type default)
			)
			(layer "B.SilkS")
		)
		(fp_line
			(start -1.1938 -0.4064)
			(end -1.1938 0.4064)
			(stroke
				(width 0.1)
				(type default)
			)
			(layer "B.Fab")
		)
		(fp_line
			(start -1.1938 0.4064)
			(end -0.8636 0.4064)
			(stroke
				(width 0.1)
				(type default)
			)
			(layer "B.Fab")
		)
		(fp_line
			(start -0.8636 -0.4572)
			(end -0.8636 -0.4064)
			(stroke
				(width 0.1)
				(type default)
			)
			(layer "B.Fab")
		)
		(fp_line
			(start -0.8636 -0.4064)
			(end -1.1938 -0.4064)
			(stroke
				(width 0.1)
				(type default)
			)
			(layer "B.Fab")
		)
		(fp_line
			(start -0.8636 0.4064)
			(end -0.8636 0.4572)
			(stroke
				(width 0.1)
				(type default)
			)
			(layer "B.Fab")
		)
		(fp_line
			(start -0.8636 0.4572)
			(end 0.8636 0.4572)
			(stroke
				(width 0.1)
				(type default)
			)
			(layer "B.Fab")
		)
		(fp_line
			(start 0.8636 -0.4572)
			(end -0.8636 -0.4572)
			(stroke
				(width 0.1)
				(type default)
			)
			(layer "B.Fab")
		)
		(fp_line
			(start 0.8636 -0.4064)
			(end 0.8636 -0.4572)
			(stroke
				(width 0.1)
				(type default)
			)
			(layer "B.Fab")
		)
		(fp_line
			(start 0.8636 0.4064)
			(end 1.1938 0.4064)
			(stroke
				(width 0.1)
				(type default)
			)
			(layer "B.Fab")
		)
		(fp_line
			(start 0.8636 0.4572)
			(end 0.8636 0.4064)
			(stroke
				(width 0.1)
				(type default)
			)
			(layer "B.Fab")
		)
		(fp_line
			(start 1.1938 -0.4064)
			(end 0.8636 -0.4064)
			(stroke
				(width 0.1)
				(type default)
			)
			(layer "B.Fab")
		)
		(fp_line
			(start 1.1938 0.4064)
			(end 1.1938 -0.4064)
			(stroke
				(width 0.1)
				(type default)
			)
			(layer "B.Fab")
		)
		(pad "1" smd rect
			(at 0.7366 0 270)
			(size 0.7112 0.8128)
			(layers "B.Cu" "B.Mask" "B.Paste")
			(net "P3V3_AUX")
		)
		(pad "2" smd rect
			(at -0.7366 0 270)
			(size 0.7112 0.8128)
			(layers "B.Cu" "B.Mask" "B.Paste")
			(net "GND")
		)
	)
	(footprint ""
		(layer "B.Cu")
		(at 425.555156 -318.908176 90)
		(property "Reference" "R2733"
			(at 0 0 90)
			(layer "B.SilkS")
			(hide yes)
			(effects
				(font
					(size 1.27 1.27)
				)
				(justify mirror)
			)
		)
		(property "Value" ""
			(at 0 0 90)
			(layer "B.Fab")
			(effects
				(font
					(size 1.27 1.27)
				)
				(justify mirror)
			)
		)
		(duplicate_pad_numbers_are_jumpers no)
		(fp_line
			(start 0.7874 -0.4064)
			(end -0.7874 -0.4064)
			(stroke
				(width 0.1524)
				(type default)
			)
			(layer "B.SilkS")
		)
		(fp_line
			(start -0.7874 -0.4064)
			(end -0.7874 0.4064)
			(stroke
				(width 0.1524)
				(type default)
			)
			(layer "B.SilkS")
		)
		(fp_line
			(start 0.7874 0.4064)
			(end 0.7874 -0.4064)
			(stroke
				(width 0.1524)
				(type default)
			)
			(layer "B.SilkS")
		)
		(fp_line
			(start -0.7874 0.4064)
			(end 0.7874 0.4064)
			(stroke
				(width 0.1524)
				(type default)
			)
			(layer "B.SilkS")
		)
		(fp_line
			(start 0.67945 -0.305054)
			(end 0.12065 -0.305054)
			(stroke
				(width 0.1)
				(type default)
			)
			(layer "B.Fab")
		)
		(fp_line
			(start 0.12065 -0.305054)
			(end 0.12065 -0.2794)
			(stroke
				(width 0.1)
				(type default)
			)
			(layer "B.Fab")
		)
		(fp_line
			(start -0.12065 -0.3048)
			(end -0.67945 -0.3048)
			(stroke
				(width 0.1)
				(type default)
			)
			(layer "B.Fab")
		)
		(fp_line
			(start -0.67945 -0.3048)
			(end -0.67945 0.3048)
			(stroke
				(width 0.1)
				(type default)
			)
			(layer "B.Fab")
		)
		(fp_line
			(start 0.12065 -0.2794)
			(end -0.12065 -0.2794)
			(stroke
				(width 0.1)
				(type default)
			)
			(layer "B.Fab")
		)
		(fp_line
			(start -0.12065 -0.2794)
			(end -0.12065 -0.3048)
			(stroke
				(width 0.1)
				(type default)
			)
			(layer "B.Fab")
		)
		(fp_line
			(start 0.12065 0.2794)
			(end 0.12065 0.3048)
			(stroke
				(width 0.1)
				(type default)
			)
			(layer "B.Fab")
		)
		(fp_line
			(start -0.120396 0.2794)
			(end 0.12065 0.2794)
			(stroke
				(width 0.1)
				(type default)
			)
			(layer "B.Fab")
		)
		(fp_line
			(start 0.67945 0.3048)
			(end 0.67945 -0.305054)
			(stroke
				(width 0.1)
				(type default)
			)
			(layer "B.Fab")
		)
		(fp_line
			(start 0.12065 0.3048)
			(end 0.67945 0.3048)
			(stroke
				(width 0.1)
				(type default)
			)
			(layer "B.Fab")
		)
		(fp_line
			(start -0.120396 0.3048)
			(end -0.120396 0.2794)
			(stroke
				(width 0.1)
				(type default)
			)
			(layer "B.Fab")
		)
		(fp_line
			(start -0.67945 0.3048)
			(end -0.120396 0.3048)
			(stroke
				(width 0.1)
				(type default)
			)
			(layer "B.Fab")
		)
		(pad "1" smd circle
			(at 0.40005 0 270)
			(size 0 0)
			(layers "B.Cu" "B.Mask" "B.Paste")
			(net "PWRGD_CHF_CPU0_DIMM2")
		)
		(pad "2" smd circle
			(at -0.40005 0 270)
			(size 0 0)
			(layers "B.Cu" "B.Mask" "B.Paste")
			(net "PWRGD_FAIL_CPU0_EF")
		)
	)
	(footprint ""
		(layer "B.Cu")
		(at 365.429038 -180.99405)
		(property "Reference" "R1002"
			(at 0 0 0)
			(layer "B.SilkS")
			(hide yes)
			(effects
				(font
					(size 1.27 1.27)
				)
				(justify mirror)
			)
		)
		(property "Value" ""
			(at 0 0 0)
			(layer "B.Fab")
			(effects
				(font
					(size 1.27 1.27)
				)
				(justify mirror)
			)
		)
		(duplicate_pad_numbers_are_jumpers no)
		(fp_line
			(start -0.7874 -0.4064)
			(end -0.7874 0.4064)
			(stroke
				(width 0.1524)
				(type default)
			)
			(layer "B.SilkS")
		)
		(fp_line
			(start -0.7874 0.4064)
			(end 0.7874 0.4064)
			(stroke
				(width 0.1524)
				(type default)
			)
			(layer "B.SilkS")
		)
		(fp_line
			(start 0.7874 -0.4064)
			(end -0.7874 -0.4064)
			(stroke
				(width 0.1524)
				(type default)
			)
			(layer "B.SilkS")
		)
		(fp_line
			(start 0.7874 0.4064)
			(end 0.7874 -0.4064)
			(stroke
				(width 0.1524)
				(type default)
			)
			(layer "B.SilkS")
		)
		(fp_line
			(start -0.67945 -0.3048)
			(end -0.67945 0.3048)
			(stroke
				(width 0.1)
				(type default)
			)
			(layer "B.Fab")
		)
		(fp_line
			(start -0.67945 0.3048)
			(end -0.120396 0.3048)
			(stroke
				(width 0.1)
				(type default)
			)
			(layer "B.Fab")
		)
		(fp_line
			(start -0.12065 -0.3048)
			(end -0.67945 -0.3048)
			(stroke
				(width 0.1)
				(type default)
			)
			(layer "B.Fab")
		)
		(fp_line
			(start -0.12065 -0.2794)
			(end -0.12065 -0.3048)
			(stroke
				(width 0.1)
				(type default)
			)
			(layer "B.Fab")
		)
		(fp_line
			(start -0.120396 0.2794)
			(end 0.12065 0.2794)
			(stroke
				(width 0.1)
				(type default)
			)
			(layer "B.Fab")
		)
		(fp_line
			(start -0.120396 0.3048)
			(end -0.120396 0.2794)
			(stroke
				(width 0.1)
				(type default)
			)
			(layer "B.Fab")
		)
		(fp_line
			(start 0.12065 -0.305054)
			(end 0.12065 -0.2794)
			(stroke
				(width 0.1)
				(type default)
			)
			(layer "B.Fab")
		)
		(fp_line
			(start 0.12065 -0.2794)
			(end -0.12065 -0.2794)
			(stroke
				(width 0.1)
				(type default)
			)
			(layer "B.Fab")
		)
		(fp_line
			(start 0.12065 0.2794)
			(end 0.12065 0.3048)
			(stroke
				(width 0.1)
				(type default)
			)
			(layer "B.Fab")
		)
		(fp_line
			(start 0.12065 0.3048)
			(end 0.67945 0.3048)
			(stroke
				(width 0.1)
				(type default)
			)
			(layer "B.Fab")
		)
		(fp_line
			(start 0.67945 -0.305054)
			(end 0.12065 -0.305054)
			(stroke
				(width 0.1)
				(type default)
			)
			(layer "B.Fab")
		)
		(fp_line
			(start 0.67945 0.3048)
			(end 0.67945 -0.305054)
			(stroke
				(width 0.1)
				(type default)
			)
			(layer "B.Fab")
		)
		(pad "1" smd circle
			(at 0.40005 0 180)
			(size 0 0)
			(layers "B.Cu" "B.Mask" "B.Paste")
			(net "P3V3")
		)
		(pad "2" smd circle
			(at -0.40005 0 180)
			(size 0 0)
			(layers "B.Cu" "B.Mask" "B.Paste")
			(net "FM_SMB_CPU0_ALERT_R1")
		)
	)
	(footprint ""
		(layer "B.Cu")
		(at 117.904514 -336.192368 -90)
		(property "Reference" "PR301"
			(at 0 0 90)
			(layer "B.SilkS")
			(hide yes)
			(effects
				(font
					(size 1.27 1.27)
				)
				(justify mirror)
			)
		)
		(property "Value" ""
			(at 0 0 90)
			(layer "B.Fab")
			(effects
				(font
					(size 1.27 1.27)
				)
				(justify mirror)
			)
		)
		(duplicate_pad_numbers_are_jumpers no)
		(fp_line
			(start -0.7874 0.4064)
			(end 0.7874 0.4064)
			(stroke
				(width 0.1524)
				(type default)
			)
			(layer "B.SilkS")
		)
		(fp_line
			(start 0.7874 0.4064)
			(end 0.7874 -0.4064)
			(stroke
				(width 0.1524)
				(type default)
			)
			(layer "B.SilkS")
		)
		(fp_line
			(start -0.7874 -0.4064)
			(end -0.7874 0.4064)
			(stroke
				(width 0.1524)
				(type default)
			)
			(layer "B.SilkS")
		)
		(fp_line
			(start 0.7874 -0.4064)
			(end -0.7874 -0.4064)
			(stroke
				(width 0.1524)
				(type default)
			)
			(layer "B.SilkS")
		)
		(fp_line
			(start -0.67945 0.3048)
			(end -0.120396 0.3048)
			(stroke
				(width 0.1)
				(type default)
			)
			(layer "B.Fab")
		)
		(fp_line
			(start -0.120396 0.3048)
			(end -0.120396 0.2794)
			(stroke
				(width 0.1)
				(type default)
			)
			(layer "B.Fab")
		)
		(fp_line
			(start 0.12065 0.3048)
			(end 0.67945 0.3048)
			(stroke
				(width 0.1)
				(type default)
			)
			(layer "B.Fab")
		)
		(fp_line
			(start 0.67945 0.3048)
			(end 0.67945 -0.305054)
			(stroke
				(width 0.1)
				(type default)
			)
			(layer "B.Fab")
		)
		(fp_line
			(start -0.120396 0.2794)
			(end 0.12065 0.2794)
			(stroke
				(width 0.1)
				(type default)
			)
			(layer "B.Fab")
		)
		(fp_line
			(start 0.12065 0.2794)
			(end 0.12065 0.3048)
			(stroke
				(width 0.1)
				(type default)
			)
			(layer "B.Fab")
		)
		(fp_line
			(start -0.12065 -0.2794)
			(end -0.12065 -0.3048)
			(stroke
				(width 0.1)
				(type default)
			)
			(layer "B.Fab")
		)
		(fp_line
			(start 0.12065 -0.2794)
			(end -0.12065 -0.2794)
			(stroke
				(width 0.1)
				(type default)
			)
			(layer "B.Fab")
		)
		(fp_line
			(start -0.67945 -0.3048)
			(end -0.67945 0.3048)
			(stroke
				(width 0.1)
				(type default)
			)
			(layer "B.Fab")
		)
		(fp_line
			(start -0.12065 -0.3048)
			(end -0.67945 -0.3048)
			(stroke
				(width 0.1)
				(type default)
			)
			(layer "B.Fab")
		)
		(fp_line
			(start 0.12065 -0.305054)
			(end 0.12065 -0.2794)
			(stroke
				(width 0.1)
				(type default)
			)
			(layer "B.Fab")
		)
		(fp_line
			(start 0.67945 -0.305054)
			(end 0.12065 -0.305054)
			(stroke
				(width 0.1)
				(type default)
			)
			(layer "B.Fab")
		)
		(pad "1" smd circle
			(at 0.40005 0 90)
			(size 0 0)
			(layers "B.Cu" "B.Mask" "B.Paste")
			(net "PVCCIN_CPU1_VOS4")
		)
		(pad "2" smd circle
			(at -0.40005 0 90)
			(size 0 0)
			(layers "B.Cu" "B.Mask" "B.Paste")
			(net "PVCCIN_CPU1")
		)
	)
	(footprint ""
		(layer "B.Cu")
		(at 263.2583 -419.164008 90)
		(property "Reference" "PD16"
			(at 4.59994 4.264152 90)
			(unlocked yes)
			(layer "B.SilkS")
			(effects
				(font
					(size 0.7874 0.5842)
					(thickness 0.1524)
				)
				(justify left mirror)
			)
		)
		(property "Value" ""
			(at 0 0 90)
			(layer "B.Fab")
			(effects
				(font
					(size 1.27 1.27)
				)
				(justify mirror)
			)
		)
		(duplicate_pad_numbers_are_jumpers no)
		(fp_line
			(start 4.664456 -3.109976)
			(end -4.743704 -3.109976)
			(stroke
				(width 0.1524)
				(type default)
			)
			(layer "B.SilkS")
		)
		(fp_line
			(start -4.183126 -3.109976)
			(end -4.794504 -3.109976)
			(stroke
				(width 0.1524)
				(type default)
			)
			(layer "B.SilkS")
		)
		(fp_line
			(start -4.511802 -3.109976)
			(end -4.207002 -3.109976)
			(stroke
				(width 0.1524)
				(type default)
			)
			(layer "B.SilkS")
		)
		(fp_line
			(start -4.6101 -3.109976)
			(end -4.283202 -3.109976)
			(stroke
				(width 0.1524)
				(type default)
			)
			(layer "B.SilkS")
		)
		(fp_line
			(start -4.695444 -3.109976)
			(end -4.695444 3.109976)
			(stroke
				(width 0.1524)
				(type default)
			)
			(layer "B.SilkS")
		)
		(fp_line
			(start -4.70535 -3.109976)
			(end -4.70535 3.109976)
			(stroke
				(width 0.1524)
				(type default)
			)
			(layer "B.SilkS")
		)
		(fp_line
			(start -4.70535 -3.109976)
			(end -4.70535 3.109976)
			(stroke
				(width 0.1524)
				(type default)
			)
			(layer "B.SilkS")
		)
		(fp_line
			(start -4.70535 -3.109976)
			(end -4.70535 3.109976)
			(stroke
				(width 0.1524)
				(type default)
			)
			(layer "B.SilkS")
		)
		(fp_line
			(start -4.805426 -3.109976)
			(end -4.805426 3.109976)
			(stroke
				(width 0.1524)
				(type default)
			)
			(layer "B.SilkS")
		)
		(fp_line
			(start -4.932426 -3.109976)
			(end -4.932426 3.109976)
			(stroke
				(width 0.1524)
				(type default)
			)
			(layer "B.SilkS")
		)
		(fp_line
			(start -5.008626 -3.109976)
			(end -5.008626 3.109976)
			(stroke
				(width 0.1524)
				(type default)
			)
			(layer "B.SilkS")
		)
		(fp_line
			(start -5.110226 -3.109976)
			(end -5.110226 3.109976)
			(stroke
				(width 0.1524)
				(type default)
			)
			(layer "B.SilkS")
		)
		(fp_line
			(start -5.211826 -3.109976)
			(end -5.211826 3.109976)
			(stroke
				(width 0.1524)
				(type default)
			)
			(layer "B.SilkS")
		)
		(fp_line
			(start -5.262626 -3.109976)
			(end -5.262626 3.109976)
			(stroke
				(width 0.1524)
				(type default)
			)
			(layer "B.SilkS")
		)
		(fp_line
			(start -5.313426 -3.109976)
			(end -5.313426 3.109976)
			(stroke
				(width 0.1524)
				(type default)
			)
			(layer "B.SilkS")
		)
		(fp_line
			(start -5.4102 -3.109976)
			(end -4.783074 -3.109976)
			(stroke
				(width 0.1524)
				(type default)
			)
			(layer "B.SilkS")
		)
		(fp_line
			(start 0.508 -1.016)
			(end -0.762 0)
			(stroke
				(width 0.1524)
				(type default)
			)
			(layer "B.SilkS")
		)
		(fp_line
			(start 1.0668 0)
			(end 0.6096 0)
			(stroke
				(width 0.1524)
				(type default)
			)
			(layer "B.SilkS")
		)
		(fp_line
			(start -0.762 0)
			(end -1.2192 0)
			(stroke
				(width 0.1524)
				(type default)
			)
			(layer "B.SilkS")
		)
		(fp_line
			(start -0.762 0)
			(end 0.508 1.016)
			(stroke
				(width 0.1524)
				(type default)
			)
			(layer "B.SilkS")
		)
		(fp_line
			(start 0.508 1.016)
			(end 0.508 -1.016)
			(stroke
				(width 0.1524)
				(type default)
			)
			(layer "B.SilkS")
		)
		(fp_line
			(start -0.762 1.27)
			(end -0.762 -1.27)
			(stroke
				(width 0.1524)
				(type default)
			)
			(layer "B.SilkS")
		)
		(fp_line
			(start -4.715002 3.035554)
			(end -4.7117 2.984754)
			(stroke
				(width 0.1524)
				(type default)
			)
			(layer "B.SilkS")
		)
		(fp_line
			(start 4.664456 3.109976)
			(end 4.664456 -3.109976)
			(stroke
				(width 0.1524)
				(type default)
			)
			(layer "B.SilkS")
		)
		(fp_line
			(start -4.156202 3.109976)
			(end -4.183126 3.109976)
			(stroke
				(width 0.1524)
				(type default)
			)
			(layer "B.SilkS")
		)
		(fp_line
			(start -4.743704 3.109976)
			(end -4.6101 3.109976)
			(stroke
				(width 0.1524)
				(type default)
			)
			(layer "B.SilkS")
		)
		(fp_line
			(start -4.743704 3.109976)
			(end -5.4102 3.109976)
			(stroke
				(width 0.1524)
				(type default)
			)
			(layer "B.SilkS")
		)
		(fp_line
			(start -4.769104 3.109976)
			(end 4.664456 3.109976)
			(stroke
				(width 0.1524)
				(type default)
			)
			(layer "B.SilkS")
		)
		(fp_line
			(start -4.794504 3.109976)
			(end -3.554984 3.109976)
			(stroke
				(width 0.1524)
				(type default)
			)
			(layer "B.SilkS")
		)
		(fp_line
			(start -5.4102 3.109976)
			(end -5.4102 -3.109976)
			(stroke
				(width 0.1524)
				(type default)
			)
			(layer "B.SilkS")
		)
		(fp_line
			(start 4.065016 -3.109976)
			(end -4.065016 -3.109976)
			(stroke
				(width 0.1)
				(type default)
			)
			(layer "B.Fab")
		)
		(fp_line
			(start -4.065016 -3.109976)
			(end -4.065016 3.109976)
			(stroke
				(width 0.1)
				(type default)
			)
			(layer "B.Fab")
		)
		(fp_line
			(start 4.065016 3.109976)
			(end 4.065016 -3.109976)
			(stroke
				(width 0.1)
				(type default)
			)
			(layer "B.Fab")
		)
		(fp_line
			(start -4.065016 3.109976)
			(end 4.065016 3.109976)
			(stroke
				(width 0.1)
				(type default)
			)
			(layer "B.Fab")
		)
		(fp_text user "+"
			(at 4.5974 0.24765 270)
			(unlocked yes)
			(layer "B.SilkS")
			(effects
				(font
					(size 1.905 1.4224)
					(thickness 0.1524)
				)
				(justify left mirror)
			)
		)
		(fp_text user "-"
			(at -6.643624 0.40005 270)
			(unlocked yes)
			(layer "B.SilkS")
			(effects
				(font
					(size 1.905 1.4224)
					(thickness 0.1524)
				)
				(justify left mirror)
			)
		)
		(fp_text user "+"
			(at 4.5974 0.24765 270)
			(unlocked yes)
			(layer "B.Fab")
			(effects
				(font
					(size 1.905 1.4224)
					(thickness 0.1524)
				)
				(justify left mirror)
			)
		)
		(fp_text user "-"
			(at -6.643624 0.40005 270)
			(unlocked yes)
			(layer "B.Fab")
			(effects
				(font
					(size 1.905 1.4224)
					(thickness 0.1524)
				)
				(justify left mirror)
			)
		)
		(pad "A" smd rect
			(at 3.299968 0 90)
			(size 2.413 3.302)
			(layers "B.Cu" "B.Mask" "B.Paste")
			(net "GND")
		)
		(pad "C" smd rect
			(at -3.299968 0 90)
			(size 2.413 3.302)
			(layers "B.Cu" "B.Mask" "B.Paste")
			(net "P12V_PSU_FUSE")
		)
	)
	(footprint ""
		(layer "B.Cu")
		(at 305.533298 -152.179782 180)
		(property "Reference" "R694"
			(at 0 0 0)
			(layer "B.SilkS")
			(hide yes)
			(effects
				(font
					(size 1.27 1.27)
				)
				(justify mirror)
			)
		)
		(property "Value" ""
			(at 0 0 0)
			(layer "B.Fab")
			(effects
				(font
					(size 1.27 1.27)
				)
				(justify mirror)
			)
		)
		(duplicate_pad_numbers_are_jumpers no)
		(fp_line
			(start 0.7874 0.4064)
			(end 0.7874 -0.4064)
			(stroke
				(width 0.1524)
				(type default)
			)
			(layer "B.SilkS")
		)
		(fp_line
			(start 0.7874 -0.4064)
			(end -0.7874 -0.4064)
			(stroke
				(width 0.1524)
				(type default)
			)
			(layer "B.SilkS")
		)
		(fp_line
			(start -0.7874 0.4064)
			(end 0.7874 0.4064)
			(stroke
				(width 0.1524)
				(type default)
			)
			(layer "B.SilkS")
		)
		(fp_line
			(start -0.7874 -0.4064)
			(end -0.7874 0.4064)
			(stroke
				(width 0.1524)
				(type default)
			)
			(layer "B.SilkS")
		)
		(fp_line
			(start 0.67945 0.3048)
			(end 0.67945 -0.305054)
			(stroke
				(width 0.1)
				(type default)
			)
			(layer "B.Fab")
		)
		(fp_line
			(start 0.67945 -0.305054)
			(end 0.12065 -0.305054)
			(stroke
				(width 0.1)
				(type default)
			)
			(layer "B.Fab")
		)
		(fp_line
			(start 0.12065 0.3048)
			(end 0.67945 0.3048)
			(stroke
				(width 0.1)
				(type default)
			)
			(layer "B.Fab")
		)
		(fp_line
			(start 0.12065 0.2794)
			(end 0.12065 0.3048)
			(stroke
				(width 0.1)
				(type default)
			)
			(layer "B.Fab")
		)
		(fp_line
			(start 0.12065 -0.2794)
			(end -0.12065 -0.2794)
			(stroke
				(width 0.1)
				(type default)
			)
			(layer "B.Fab")
		)
		(fp_line
			(start 0.12065 -0.305054)
			(end 0.12065 -0.2794)
			(stroke
				(width 0.1)
				(type default)
			)
			(layer "B.Fab")
		)
		(fp_line
			(start -0.120396 0.3048)
			(end -0.120396 0.2794)
			(stroke
				(width 0.1)
				(type default)
			)
			(layer "B.Fab")
		)
		(fp_line
			(start -0.120396 0.2794)
			(end 0.12065 0.2794)
			(stroke
				(width 0.1)
				(type default)
			)
			(layer "B.Fab")
		)
		(fp_line
			(start -0.12065 -0.2794)
			(end -0.12065 -0.3048)
			(stroke
				(width 0.1)
				(type default)
			)
			(layer "B.Fab")
		)
		(fp_line
			(start -0.12065 -0.3048)
			(end -0.67945 -0.3048)
			(stroke
				(width 0.1)
				(type default)
			)
			(layer "B.Fab")
		)
		(fp_line
			(start -0.67945 0.3048)
			(end -0.120396 0.3048)
			(stroke
				(width 0.1)
				(type default)
			)
			(layer "B.Fab")
		)
		(fp_line
			(start -0.67945 -0.3048)
			(end -0.67945 0.3048)
			(stroke
				(width 0.1)
				(type default)
			)
			(layer "B.Fab")
		)
		(pad "1" smd circle
			(at 0.40005 0)
			(size 0 0)
			(layers "B.Cu" "B.Mask" "B.Paste")
			(net "I3C_SPD_DDREFGH_CPU0_LVC1_R_SDA")
		)
		(pad "2" smd circle
			(at -0.40005 0)
			(size 0 0)
			(layers "B.Cu" "B.Mask" "B.Paste")
			(net "I3C_SPD_DDREFGH_CPU0_LVC1_SDA")
		)
	)
	(footprint ""
		(layer "B.Cu")
		(at 297.942 -258.155948)
		(property "Reference" "R185"
			(at 0 0 0)
			(layer "B.SilkS")
			(hide yes)
			(effects
				(font
					(size 1.27 1.27)
				)
				(justify mirror)
			)
		)
		(property "Value" ""
			(at 0 0 0)
			(layer "B.Fab")
			(effects
				(font
					(size 1.27 1.27)
				)
				(justify mirror)
			)
		)
		(duplicate_pad_numbers_are_jumpers no)
		(fp_line
			(start -0.7874 -0.4064)
			(end -0.7874 0.4064)
			(stroke
				(width 0.1524)
				(type default)
			)
			(layer "B.SilkS")
		)
		(fp_line
			(start -0.7874 0.4064)
			(end 0.7874 0.4064)
			(stroke
				(width 0.1524)
				(type default)
			)
			(layer "B.SilkS")
		)
		(fp_line
			(start 0.7874 -0.4064)
			(end -0.7874 -0.4064)
			(stroke
				(width 0.1524)
				(type default)
			)
			(layer "B.SilkS")
		)
		(fp_line
			(start 0.7874 0.4064)
			(end 0.7874 -0.4064)
			(stroke
				(width 0.1524)
				(type default)
			)
			(layer "B.SilkS")
		)
		(fp_line
			(start -0.67945 -0.3048)
			(end -0.67945 0.3048)
			(stroke
				(width 0.1)
				(type default)
			)
			(layer "B.Fab")
		)
		(fp_line
			(start -0.67945 0.3048)
			(end -0.120396 0.3048)
			(stroke
				(width 0.1)
				(type default)
			)
			(layer "B.Fab")
		)
		(fp_line
			(start -0.12065 -0.3048)
			(end -0.67945 -0.3048)
			(stroke
				(width 0.1)
				(type default)
			)
			(layer "B.Fab")
		)
		(fp_line
			(start -0.12065 -0.2794)
			(end -0.12065 -0.3048)
			(stroke
				(width 0.1)
				(type default)
			)
			(layer "B.Fab")
		)
		(fp_line
			(start -0.120396 0.2794)
			(end 0.12065 0.2794)
			(stroke
				(width 0.1)
				(type default)
			)
			(layer "B.Fab")
		)
		(fp_line
			(start -0.120396 0.3048)
			(end -0.120396 0.2794)
			(stroke
				(width 0.1)
				(type default)
			)
			(layer "B.Fab")
		)
		(fp_line
			(start 0.12065 -0.305054)
			(end 0.12065 -0.2794)
			(stroke
				(width 0.1)
				(type default)
			)
			(layer "B.Fab")
		)
		(fp_line
			(start 0.12065 -0.2794)
			(end -0.12065 -0.2794)
			(stroke
				(width 0.1)
				(type default)
			)
			(layer "B.Fab")
		)
		(fp_line
			(start 0.12065 0.2794)
			(end 0.12065 0.3048)
			(stroke
				(width 0.1)
				(type default)
			)
			(layer "B.Fab")
		)
		(fp_line
			(start 0.12065 0.3048)
			(end 0.67945 0.3048)
			(stroke
				(width 0.1)
				(type default)
			)
			(layer "B.Fab")
		)
		(fp_line
			(start 0.67945 -0.305054)
			(end 0.12065 -0.305054)
			(stroke
				(width 0.1)
				(type default)
			)
			(layer "B.Fab")
		)
		(fp_line
			(start 0.67945 0.3048)
			(end 0.67945 -0.305054)
			(stroke
				(width 0.1)
				(type default)
			)
			(layer "B.Fab")
		)
		(pad "1" smd circle
			(at 0.40005 0 180)
			(size 0 0)
			(layers "B.Cu" "B.Mask" "B.Paste")
			(net "RST_CPU0_BUF_R_N")
		)
		(pad "2" smd circle
			(at -0.40005 0 180)
			(size 0 0)
			(layers "B.Cu" "B.Mask" "B.Paste")
			(net "PVNN_TERM_CPU0")
		)
	)
	(footprint ""
		(layer "B.Cu")
		(at 460.075788 -383.650998 180)
		(property "Reference" "R2356"
			(at 0 0 0)
			(layer "B.SilkS")
			(hide yes)
			(effects
				(font
					(size 1.27 1.27)
				)
				(justify mirror)
			)
		)
		(property "Value" ""
			(at 0 0 0)
			(layer "B.Fab")
			(effects
				(font
					(size 1.27 1.27)
				)
				(justify mirror)
			)
		)
		(duplicate_pad_numbers_are_jumpers no)
		(fp_line
			(start 0.7874 0.4064)
			(end 0.7874 -0.4064)
			(stroke
				(width 0.1524)
				(type default)
			)
			(layer "B.SilkS")
		)
		(fp_line
			(start 0.7874 -0.4064)
			(end -0.7874 -0.4064)
			(stroke
				(width 0.1524)
				(type default)
			)
			(layer "B.SilkS")
		)
		(fp_line
			(start -0.7874 0.4064)
			(end 0.7874 0.4064)
			(stroke
				(width 0.1524)
				(type default)
			)
			(layer "B.SilkS")
		)
		(fp_line
			(start -0.7874 -0.4064)
			(end -0.7874 0.4064)
			(stroke
				(width 0.1524)
				(type default)
			)
			(layer "B.SilkS")
		)
		(fp_line
			(start 0.67945 0.3048)
			(end 0.67945 -0.305054)
			(stroke
				(width 0.1)
				(type default)
			)
			(layer "B.Fab")
		)
		(fp_line
			(start 0.67945 -0.305054)
			(end 0.12065 -0.305054)
			(stroke
				(width 0.1)
				(type default)
			)
			(layer "B.Fab")
		)
		(fp_line
			(start 0.12065 0.3048)
			(end 0.67945 0.3048)
			(stroke
				(width 0.1)
				(type default)
			)
			(layer "B.Fab")
		)
		(fp_line
			(start 0.12065 0.2794)
			(end 0.12065 0.3048)
			(stroke
				(width 0.1)
				(type default)
			)
			(layer "B.Fab")
		)
		(fp_line
			(start 0.12065 -0.2794)
			(end -0.12065 -0.2794)
			(stroke
				(width 0.1)
				(type default)
			)
			(layer "B.Fab")
		)
		(fp_line
			(start 0.12065 -0.305054)
			(end 0.12065 -0.2794)
			(stroke
				(width 0.1)
				(type default)
			)
			(layer "B.Fab")
		)
		(fp_line
			(start -0.120396 0.3048)
			(end -0.120396 0.2794)
			(stroke
				(width 0.1)
				(type default)
			)
			(layer "B.Fab")
		)
		(fp_line
			(start -0.120396 0.2794)
			(end 0.12065 0.2794)
			(stroke
				(width 0.1)
				(type default)
			)
			(layer "B.Fab")
		)
		(fp_line
			(start -0.12065 -0.2794)
			(end -0.12065 -0.3048)
			(stroke
				(width 0.1)
				(type default)
			)
			(layer "B.Fab")
		)
		(fp_line
			(start -0.12065 -0.3048)
			(end -0.67945 -0.3048)
			(stroke
				(width 0.1)
				(type default)
			)
			(layer "B.Fab")
		)
		(fp_line
			(start -0.67945 0.3048)
			(end -0.120396 0.3048)
			(stroke
				(width 0.1)
				(type default)
			)
			(layer "B.Fab")
		)
		(fp_line
			(start -0.67945 -0.3048)
			(end -0.67945 0.3048)
			(stroke
				(width 0.1)
				(type default)
			)
			(layer "B.Fab")
		)
		(pad "1" smd circle
			(at 0.40005 0)
			(size 0 0)
			(layers "B.Cu" "B.Mask" "B.Paste")
			(net "P5V_AUX_VCC")
		)
		(pad "2" smd circle
			(at -0.40005 0)
			(size 0 0)
			(layers "B.Cu" "B.Mask" "B.Paste")
			(net "PWRGD_P5V_AUX_R")
		)
	)
	(footprint ""
		(layer "B.Cu")
		(at 363.135418 -294.009826 180)
		(property "Reference" "C377"
			(at 0 0 0)
			(layer "B.SilkS")
			(hide yes)
			(effects
				(font
					(size 1.27 1.27)
				)
				(justify mirror)
			)
		)
		(property "Value" ""
			(at 0 0 0)
			(layer "B.Fab")
			(effects
				(font
					(size 1.27 1.27)
				)
				(justify mirror)
			)
		)
		(duplicate_pad_numbers_are_jumpers no)
		(fp_line
			(start 1.524 0.762)
			(end 1.524 -0.762)
			(stroke
				(width 0.1524)
				(type default)
			)
			(layer "B.SilkS")
		)
		(fp_line
			(start 1.524 -0.762)
			(end -1.524 -0.762)
			(stroke
				(width 0.1524)
				(type default)
			)
			(layer "B.SilkS")
		)
		(fp_line
			(start -1.524 0.762)
			(end 1.524 0.762)
			(stroke
				(width 0.1524)
				(type default)
			)
			(layer "B.SilkS")
		)
		(fp_line
			(start -1.524 -0.762)
			(end -1.524 0.762)
			(stroke
				(width 0.1524)
				(type default)
			)
			(layer "B.SilkS")
		)
		(fp_line
			(start 1.1049 0.724916)
			(end -1.1049 0.724916)
			(stroke
				(width 0.1)
				(type default)
			)
			(layer "B.Fab")
		)
		(fp_line
			(start 1.1049 -0.724916)
			(end 1.1049 0.724916)
			(stroke
				(width 0.1)
				(type default)
			)
			(layer "B.Fab")
		)
		(fp_line
			(start -1.1049 0.724916)
			(end -1.1049 -0.724916)
			(stroke
				(width 0.1)
				(type default)
			)
			(layer "B.Fab")
		)
		(fp_line
			(start -1.1049 -0.724916)
			(end 1.1049 -0.724916)
			(stroke
				(width 0.1)
				(type default)
			)
			(layer "B.Fab")
		)
		(pad "1" smd rect
			(at 0.889 0 180)
			(size 1.016 1.27)
			(layers "B.Cu" "B.Mask" "B.Paste")
			(net "PVCCIN_CPU0")
		)
		(pad "2" smd rect
			(at -0.889 0 180)
			(size 1.016 1.27)
			(layers "B.Cu" "B.Mask" "B.Paste")
			(net "GND")
		)
	)
	(footprint ""
		(layer "B.Cu")
		(at 157.504638 -13.762228 90)
		(property "Reference" "R2413"
			(at 0 0 90)
			(layer "B.SilkS")
			(hide yes)
			(effects
				(font
					(size 1.27 1.27)
				)
				(justify mirror)
			)
		)
		(property "Value" ""
			(at 0 0 90)
			(layer "B.Fab")
			(effects
				(font
					(size 1.27 1.27)
				)
				(justify mirror)
			)
		)
		(duplicate_pad_numbers_are_jumpers no)
		(fp_line
			(start 0.7874 -0.4064)
			(end -0.7874 -0.4064)
			(stroke
				(width 0.1524)
				(type default)
			)
			(layer "B.SilkS")
		)
		(fp_line
			(start -0.7874 -0.4064)
			(end -0.7874 0.4064)
			(stroke
				(width 0.1524)
				(type default)
			)
			(layer "B.SilkS")
		)
		(fp_line
			(start 0.7874 0.4064)
			(end 0.7874 -0.4064)
			(stroke
				(width 0.1524)
				(type default)
			)
			(layer "B.SilkS")
		)
		(fp_line
			(start -0.7874 0.4064)
			(end 0.7874 0.4064)
			(stroke
				(width 0.1524)
				(type default)
			)
			(layer "B.SilkS")
		)
		(fp_line
			(start 0.67945 -0.305054)
			(end 0.12065 -0.305054)
			(stroke
				(width 0.1)
				(type default)
			)
			(layer "B.Fab")
		)
		(fp_line
			(start 0.12065 -0.305054)
			(end 0.12065 -0.2794)
			(stroke
				(width 0.1)
				(type default)
			)
			(layer "B.Fab")
		)
		(fp_line
			(start -0.12065 -0.3048)
			(end -0.67945 -0.3048)
			(stroke
				(width 0.1)
				(type default)
			)
			(layer "B.Fab")
		)
		(fp_line
			(start -0.67945 -0.3048)
			(end -0.67945 0.3048)
			(stroke
				(width 0.1)
				(type default)
			)
			(layer "B.Fab")
		)
		(fp_line
			(start 0.12065 -0.2794)
			(end -0.12065 -0.2794)
			(stroke
				(width 0.1)
				(type default)
			)
			(layer "B.Fab")
		)
		(fp_line
			(start -0.12065 -0.2794)
			(end -0.12065 -0.3048)
			(stroke
				(width 0.1)
				(type default)
			)
			(layer "B.Fab")
		)
		(fp_line
			(start 0.12065 0.2794)
			(end 0.12065 0.3048)
			(stroke
				(width 0.1)
				(type default)
			)
			(layer "B.Fab")
		)
		(fp_line
			(start -0.120396 0.2794)
			(end 0.12065 0.2794)
			(stroke
				(width 0.1)
				(type default)
			)
			(layer "B.Fab")
		)
		(fp_line
			(start 0.67945 0.3048)
			(end 0.67945 -0.305054)
			(stroke
				(width 0.1)
				(type default)
			)
			(layer "B.Fab")
		)
		(fp_line
			(start 0.12065 0.3048)
			(end 0.67945 0.3048)
			(stroke
				(width 0.1)
				(type default)
			)
			(layer "B.Fab")
		)
		(fp_line
			(start -0.120396 0.3048)
			(end -0.120396 0.2794)
			(stroke
				(width 0.1)
				(type default)
			)
			(layer "B.Fab")
		)
		(fp_line
			(start -0.67945 0.3048)
			(end -0.120396 0.3048)
			(stroke
				(width 0.1)
				(type default)
			)
			(layer "B.Fab")
		)
		(pad "1" smd circle
			(at 0.40005 0 270)
			(size 0 0)
			(layers "B.Cu" "B.Mask" "B.Paste")
			(net "SMB_2_BMC_GPU_SCL")
		)
		(pad "2" smd circle
			(at -0.40005 0 270)
			(size 0 0)
			(layers "B.Cu" "B.Mask" "B.Paste")
			(net "SMB_PCIE2_3V3AUX_SCL_R0")
		)
	)
	(footprint ""
		(layer "B.Cu")
		(at 79.836772 -331.596492 -90)
		(property "Reference" "PC498_P1_7"
			(at 0 0 90)
			(layer "B.SilkS")
			(hide yes)
			(effects
				(font
					(size 1.27 1.27)
				)
				(justify mirror)
			)
		)
		(property "Value" ""
			(at 0 0 90)
			(layer "B.Fab")
			(effects
				(font
					(size 1.27 1.27)
				)
				(justify mirror)
			)
		)
		(duplicate_pad_numbers_are_jumpers no)
		(fp_line
			(start -1.524 0.762)
			(end 1.524 0.762)
			(stroke
				(width 0.1524)
				(type default)
			)
			(layer "B.SilkS")
		)
		(fp_line
			(start 1.524 0.762)
			(end 1.524 -0.762)
			(stroke
				(width 0.1524)
				(type default)
			)
			(layer "B.SilkS")
		)
		(fp_line
			(start -1.524 -0.762)
			(end -1.524 0.762)
			(stroke
				(width 0.1524)
				(type default)
			)
			(layer "B.SilkS")
		)
		(fp_line
			(start 1.524 -0.762)
			(end -1.524 -0.762)
			(stroke
				(width 0.1524)
				(type default)
			)
			(layer "B.SilkS")
		)
		(fp_line
			(start -1.1049 0.724916)
			(end -1.1049 -0.724916)
			(stroke
				(width 0.1)
				(type default)
			)
			(layer "B.Fab")
		)
		(fp_line
			(start 1.1049 0.724916)
			(end -1.1049 0.724916)
			(stroke
				(width 0.1)
				(type default)
			)
			(layer "B.Fab")
		)
		(fp_line
			(start -1.1049 -0.724916)
			(end 1.1049 -0.724916)
			(stroke
				(width 0.1)
				(type default)
			)
			(layer "B.Fab")
		)
		(fp_line
			(start 1.1049 -0.724916)
			(end 1.1049 0.724916)
			(stroke
				(width 0.1)
				(type default)
			)
			(layer "B.Fab")
		)
		(pad "1" smd rect
			(at 0.889 0 270)
			(size 1.016 1.27)
			(layers "B.Cu" "B.Mask" "B.Paste")
			(net "PVCCIN_CPU1")
		)
		(pad "2" smd rect
			(at -0.889 0 270)
			(size 1.016 1.27)
			(layers "B.Cu" "B.Mask" "B.Paste")
			(net "GND")
		)
	)
	(footprint ""
		(layer "B.Cu")
		(at 391.408158 -336.43697)
		(property "Reference" "C1436"
			(at 0 0 0)
			(layer "B.SilkS")
			(hide yes)
			(effects
				(font
					(size 1.27 1.27)
				)
				(justify mirror)
			)
		)
		(property "Value" ""
			(at 0 0 0)
			(layer "B.Fab")
			(effects
				(font
					(size 1.27 1.27)
				)
				(justify mirror)
			)
		)
		(duplicate_pad_numbers_are_jumpers no)
		(fp_line
			(start -0.299974 -0.150114)
			(end -0.299974 0.150114)
			(stroke
				(width 0.1)
				(type default)
			)
			(layer "B.Fab")
		)
		(fp_line
			(start -0.299974 0.150114)
			(end 0.299974 0.150114)
			(stroke
				(width 0.1)
				(type default)
			)
			(layer "B.Fab")
		)
		(fp_line
			(start 0.299974 -0.150114)
			(end -0.299974 -0.150114)
			(stroke
				(width 0.1)
				(type default)
			)
			(layer "B.Fab")
		)
		(fp_line
			(start 0.299974 0.150114)
			(end 0.299974 -0.150114)
			(stroke
				(width 0.1)
				(type default)
			)
			(layer "B.Fab")
		)
		(pad "1" smd rect
			(at 0.2667 0 180)
			(size 0.3048 0.381)
			(layers "B.Cu" "B.Mask" "B.Paste")
			(net "PVPP_HBM_CPU0")
		)
		(pad "2" smd rect
			(at -0.2667 0 180)
			(size 0.3048 0.381)
			(layers "B.Cu" "B.Mask" "B.Paste")
			(net "GND")
		)
	)
	(footprint ""
		(layer "B.Cu")
		(at 349.675704 -65.09512)
		(property "Reference" "C155"
			(at 0 0 0)
			(layer "B.SilkS")
			(hide yes)
			(effects
				(font
					(size 1.27 1.27)
				)
				(justify mirror)
			)
		)
		(property "Value" ""
			(at 0 0 0)
			(layer "B.Fab")
			(effects
				(font
					(size 1.27 1.27)
				)
				(justify mirror)
			)
		)
		(duplicate_pad_numbers_are_jumpers no)
		(fp_line
			(start -0.299974 -0.150114)
			(end -0.299974 0.150114)
			(stroke
				(width 0.1)
				(type default)
			)
			(layer "B.Fab")
		)
		(fp_line
			(start -0.299974 0.150114)
			(end 0.299974 0.150114)
			(stroke
				(width 0.1)
				(type default)
			)
			(layer "B.Fab")
		)
		(fp_line
			(start 0.299974 -0.150114)
			(end -0.299974 -0.150114)
			(stroke
				(width 0.1)
				(type default)
			)
			(layer "B.Fab")
		)
		(fp_line
			(start 0.299974 0.150114)
			(end 0.299974 -0.150114)
			(stroke
				(width 0.1)
				(type default)
			)
			(layer "B.Fab")
		)
		(pad "1" smd rect
			(at 0.2667 0 180)
			(size 0.3048 0.381)
			(layers "B.Cu" "B.Mask" "B.Paste")
			(net "DMI_CPU0_PCH_RX_C_DN<7>")
		)
		(pad "2" smd rect
			(at -0.2667 0 180)
			(size 0.3048 0.381)
			(layers "B.Cu" "B.Mask" "B.Paste")
			(net "DMI_CPU0_PCH_RX_DN<7>")
		)
	)
	(footprint ""
		(layer "B.Cu")
		(at 83.478624 -184.096152 -90)
		(property "Reference" "R61"
			(at 0 0 90)
			(layer "B.SilkS")
			(hide yes)
			(effects
				(font
					(size 1.27 1.27)
				)
				(justify mirror)
			)
		)
		(property "Value" ""
			(at 0 0 90)
			(layer "B.Fab")
			(effects
				(font
					(size 1.27 1.27)
				)
				(justify mirror)
			)
		)
		(duplicate_pad_numbers_are_jumpers no)
		(fp_line
			(start -0.7874 0.4064)
			(end 0.7874 0.4064)
			(stroke
				(width 0.1524)
				(type default)
			)
			(layer "B.SilkS")
		)
		(fp_line
			(start 0.7874 0.4064)
			(end 0.7874 -0.4064)
			(stroke
				(width 0.1524)
				(type default)
			)
			(layer "B.SilkS")
		)
		(fp_line
			(start -0.7874 -0.4064)
			(end -0.7874 0.4064)
			(stroke
				(width 0.1524)
				(type default)
			)
			(layer "B.SilkS")
		)
		(fp_line
			(start 0.7874 -0.4064)
			(end -0.7874 -0.4064)
			(stroke
				(width 0.1524)
				(type default)
			)
			(layer "B.SilkS")
		)
		(fp_line
			(start -0.67945 0.3048)
			(end -0.120396 0.3048)
			(stroke
				(width 0.1)
				(type default)
			)
			(layer "B.Fab")
		)
		(fp_line
			(start -0.120396 0.3048)
			(end -0.120396 0.2794)
			(stroke
				(width 0.1)
				(type default)
			)
			(layer "B.Fab")
		)
		(fp_line
			(start 0.12065 0.3048)
			(end 0.67945 0.3048)
			(stroke
				(width 0.1)
				(type default)
			)
			(layer "B.Fab")
		)
		(fp_line
			(start 0.67945 0.3048)
			(end 0.67945 -0.305054)
			(stroke
				(width 0.1)
				(type default)
			)
			(layer "B.Fab")
		)
		(fp_line
			(start -0.120396 0.2794)
			(end 0.12065 0.2794)
			(stroke
				(width 0.1)
				(type default)
			)
			(layer "B.Fab")
		)
		(fp_line
			(start 0.12065 0.2794)
			(end 0.12065 0.3048)
			(stroke
				(width 0.1)
				(type default)
			)
			(layer "B.Fab")
		)
		(fp_line
			(start -0.12065 -0.2794)
			(end -0.12065 -0.3048)
			(stroke
				(width 0.1)
				(type default)
			)
			(layer "B.Fab")
		)
		(fp_line
			(start 0.12065 -0.2794)
			(end -0.12065 -0.2794)
			(stroke
				(width 0.1)
				(type default)
			)
			(layer "B.Fab")
		)
		(fp_line
			(start -0.67945 -0.3048)
			(end -0.67945 0.3048)
			(stroke
				(width 0.1)
				(type default)
			)
			(layer "B.Fab")
		)
		(fp_line
			(start -0.12065 -0.3048)
			(end -0.67945 -0.3048)
			(stroke
				(width 0.1)
				(type default)
			)
			(layer "B.Fab")
		)
		(fp_line
			(start 0.12065 -0.305054)
			(end 0.12065 -0.2794)
			(stroke
				(width 0.1)
				(type default)
			)
			(layer "B.Fab")
		)
		(fp_line
			(start 0.67945 -0.305054)
			(end 0.12065 -0.305054)
			(stroke
				(width 0.1)
				(type default)
			)
			(layer "B.Fab")
		)
		(pad "1" smd circle
			(at 0.40005 0 90)
			(size 0 0)
			(layers "B.Cu" "B.Mask" "B.Paste")
			(net "H_CPU_PRDY_QS_GTL_N")
		)
		(pad "2" smd circle
			(at -0.40005 0 90)
			(size 0 0)
			(layers "B.Cu" "B.Mask" "B.Paste")
			(net "H_CPU1_PRDY_QS_GTL_R_N")
		)
	)
	(footprint ""
		(layer "B.Cu")
		(at 179.87645 -408.256994 90)
		(property "Reference" "R4696"
			(at 0 0 90)
			(layer "B.SilkS")
			(hide yes)
			(effects
				(font
					(size 1.27 1.27)
				)
				(justify mirror)
			)
		)
		(property "Value" ""
			(at 0 0 90)
			(layer "B.Fab")
			(effects
				(font
					(size 1.27 1.27)
				)
				(justify mirror)
			)
		)
		(duplicate_pad_numbers_are_jumpers no)
		(fp_line
			(start 0.7874 -0.4064)
			(end -0.7874 -0.4064)
			(stroke
				(width 0.1524)
				(type default)
			)
			(layer "B.SilkS")
		)
		(fp_line
			(start -0.7874 -0.4064)
			(end -0.7874 0.4064)
			(stroke
				(width 0.1524)
				(type default)
			)
			(layer "B.SilkS")
		)
		(fp_line
			(start 0.7874 0.4064)
			(end 0.7874 -0.4064)
			(stroke
				(width 0.1524)
				(type default)
			)
			(layer "B.SilkS")
		)
		(fp_line
			(start -0.7874 0.4064)
			(end 0.7874 0.4064)
			(stroke
				(width 0.1524)
				(type default)
			)
			(layer "B.SilkS")
		)
		(fp_line
			(start 0.67945 -0.305054)
			(end 0.12065 -0.305054)
			(stroke
				(width 0.1)
				(type default)
			)
			(layer "B.Fab")
		)
		(fp_line
			(start 0.12065 -0.305054)
			(end 0.12065 -0.2794)
			(stroke
				(width 0.1)
				(type default)
			)
			(layer "B.Fab")
		)
		(fp_line
			(start -0.12065 -0.3048)
			(end -0.67945 -0.3048)
			(stroke
				(width 0.1)
				(type default)
			)
			(layer "B.Fab")
		)
		(fp_line
			(start -0.67945 -0.3048)
			(end -0.67945 0.3048)
			(stroke
				(width 0.1)
				(type default)
			)
			(layer "B.Fab")
		)
		(fp_line
			(start 0.12065 -0.2794)
			(end -0.12065 -0.2794)
			(stroke
				(width 0.1)
				(type default)
			)
			(layer "B.Fab")
		)
		(fp_line
			(start -0.12065 -0.2794)
			(end -0.12065 -0.3048)
			(stroke
				(width 0.1)
				(type default)
			)
			(layer "B.Fab")
		)
		(fp_line
			(start 0.12065 0.2794)
			(end 0.12065 0.3048)
			(stroke
				(width 0.1)
				(type default)
			)
			(layer "B.Fab")
		)
		(fp_line
			(start -0.120396 0.2794)
			(end 0.12065 0.2794)
			(stroke
				(width 0.1)
				(type default)
			)
			(layer "B.Fab")
		)
		(fp_line
			(start 0.67945 0.3048)
			(end 0.67945 -0.305054)
			(stroke
				(width 0.1)
				(type default)
			)
			(layer "B.Fab")
		)
		(fp_line
			(start 0.12065 0.3048)
			(end 0.67945 0.3048)
			(stroke
				(width 0.1)
				(type default)
			)
			(layer "B.Fab")
		)
		(fp_line
			(start -0.120396 0.3048)
			(end -0.120396 0.2794)
			(stroke
				(width 0.1)
				(type default)
			)
			(layer "B.Fab")
		)
		(fp_line
			(start -0.67945 0.3048)
			(end -0.120396 0.3048)
			(stroke
				(width 0.1)
				(type default)
			)
			(layer "B.Fab")
		)
		(pad "1" smd circle
			(at 0.40005 0 270)
			(size 0 0)
			(layers "B.Cu" "B.Mask" "B.Paste")
			(net "SMB_SML1_PMBUS_HSC_SDA")
		)
		(pad "2" smd circle
			(at -0.40005 0 270)
			(size 0 0)
			(layers "B.Cu" "B.Mask" "B.Paste")
			(net "SMB_SML1_PMBUS_HSC_MODULE_SDA")
		)
	)
	(footprint ""
		(layer "B.Cu")
		(at 456.092814 -321.549776 -90)
		(property "Reference" "C48"
			(at 0 0 90)
			(layer "B.SilkS")
			(hide yes)
			(effects
				(font
					(size 1.27 1.27)
				)
				(justify mirror)
			)
		)
		(property "Value" ""
			(at 0 0 90)
			(layer "B.Fab")
			(effects
				(font
					(size 1.27 1.27)
				)
				(justify mirror)
			)
		)
		(duplicate_pad_numbers_are_jumpers no)
		(fp_line
			(start -1.524 0.762)
			(end 1.524 0.762)
			(stroke
				(width 0.1524)
				(type default)
			)
			(layer "B.SilkS")
		)
		(fp_line
			(start 1.524 0.762)
			(end 1.524 -0.762)
			(stroke
				(width 0.1524)
				(type default)
			)
			(layer "B.SilkS")
		)
		(fp_line
			(start -1.524 -0.762)
			(end -1.524 0.762)
			(stroke
				(width 0.1524)
				(type default)
			)
			(layer "B.SilkS")
		)
		(fp_line
			(start 1.524 -0.762)
			(end -1.524 -0.762)
			(stroke
				(width 0.1524)
				(type default)
			)
			(layer "B.SilkS")
		)
		(fp_line
			(start -1.1049 0.724916)
			(end -1.1049 -0.724916)
			(stroke
				(width 0.1)
				(type default)
			)
			(layer "B.Fab")
		)
		(fp_line
			(start 1.1049 0.724916)
			(end -1.1049 0.724916)
			(stroke
				(width 0.1)
				(type default)
			)
			(layer "B.Fab")
		)
		(fp_line
			(start -1.1049 -0.724916)
			(end 1.1049 -0.724916)
			(stroke
				(width 0.1)
				(type default)
			)
			(layer "B.Fab")
		)
		(fp_line
			(start 1.1049 -0.724916)
			(end 1.1049 0.724916)
			(stroke
				(width 0.1)
				(type default)
			)
			(layer "B.Fab")
		)
		(pad "1" smd rect
			(at 0.889 0 270)
			(size 1.016 1.27)
			(layers "B.Cu" "B.Mask" "B.Paste")
			(net "P12V_S3_AUX_CPU0_NVDIMM")
		)
		(pad "2" smd rect
			(at -0.889 0 270)
			(size 1.016 1.27)
			(layers "B.Cu" "B.Mask" "B.Paste")
			(net "GND")
		)
	)
	(footprint ""
		(layer "B.Cu")
		(at 341.320628 -62.056264 90)
		(property "Reference" "C166"
			(at 0 0 90)
			(layer "B.SilkS")
			(hide yes)
			(effects
				(font
					(size 1.27 1.27)
				)
				(justify mirror)
			)
		)
		(property "Value" ""
			(at 0 0 90)
			(layer "B.Fab")
			(effects
				(font
					(size 1.27 1.27)
				)
				(justify mirror)
			)
		)
		(duplicate_pad_numbers_are_jumpers no)
		(fp_line
			(start 0.299974 -0.150114)
			(end -0.299974 -0.150114)
			(stroke
				(width 0.1)
				(type default)
			)
			(layer "B.Fab")
		)
		(fp_line
			(start -0.299974 -0.150114)
			(end -0.299974 0.150114)
			(stroke
				(width 0.1)
				(type default)
			)
			(layer "B.Fab")
		)
		(fp_line
			(start 0.299974 0.150114)
			(end 0.299974 -0.150114)
			(stroke
				(width 0.1)
				(type default)
			)
			(layer "B.Fab")
		)
		(fp_line
			(start -0.299974 0.150114)
			(end 0.299974 0.150114)
			(stroke
				(width 0.1)
				(type default)
			)
			(layer "B.Fab")
		)
		(pad "1" smd rect
			(at 0.2667 0 270)
			(size 0.3048 0.381)
			(layers "B.Cu" "B.Mask" "B.Paste")
			(net "DMI_CPU0_PCH_RX_C_DP<2>")
		)
		(pad "2" smd rect
			(at -0.2667 0 270)
			(size 0.3048 0.381)
			(layers "B.Cu" "B.Mask" "B.Paste")
			(net "DMI_CPU0_PCH_RX_DP<2>")
		)
	)
	(footprint ""
		(layer "B.Cu")
		(at 415.271712 -193.08953 -90)
		(property "Reference" "R319"
			(at 0 0 90)
			(layer "B.SilkS")
			(hide yes)
			(effects
				(font
					(size 1.27 1.27)
				)
				(justify mirror)
			)
		)
		(property "Value" ""
			(at 0 0 90)
			(layer "B.Fab")
			(effects
				(font
					(size 1.27 1.27)
				)
				(justify mirror)
			)
		)
		(duplicate_pad_numbers_are_jumpers no)
		(fp_line
			(start -0.7874 0.4064)
			(end 0.7874 0.4064)
			(stroke
				(width 0.1524)
				(type default)
			)
			(layer "B.SilkS")
		)
		(fp_line
			(start 0.7874 0.4064)
			(end 0.7874 -0.4064)
			(stroke
				(width 0.1524)
				(type default)
			)
			(layer "B.SilkS")
		)
		(fp_line
			(start -0.7874 -0.4064)
			(end -0.7874 0.4064)
			(stroke
				(width 0.1524)
				(type default)
			)
			(layer "B.SilkS")
		)
		(fp_line
			(start 0.7874 -0.4064)
			(end -0.7874 -0.4064)
			(stroke
				(width 0.1524)
				(type default)
			)
			(layer "B.SilkS")
		)
		(fp_line
			(start -0.67945 0.3048)
			(end -0.120396 0.3048)
			(stroke
				(width 0.1)
				(type default)
			)
			(layer "B.Fab")
		)
		(fp_line
			(start -0.120396 0.3048)
			(end -0.120396 0.2794)
			(stroke
				(width 0.1)
				(type default)
			)
			(layer "B.Fab")
		)
		(fp_line
			(start 0.12065 0.3048)
			(end 0.67945 0.3048)
			(stroke
				(width 0.1)
				(type default)
			)
			(layer "B.Fab")
		)
		(fp_line
			(start 0.67945 0.3048)
			(end 0.67945 -0.305054)
			(stroke
				(width 0.1)
				(type default)
			)
			(layer "B.Fab")
		)
		(fp_line
			(start -0.120396 0.2794)
			(end 0.12065 0.2794)
			(stroke
				(width 0.1)
				(type default)
			)
			(layer "B.Fab")
		)
		(fp_line
			(start 0.12065 0.2794)
			(end 0.12065 0.3048)
			(stroke
				(width 0.1)
				(type default)
			)
			(layer "B.Fab")
		)
		(fp_line
			(start -0.12065 -0.2794)
			(end -0.12065 -0.3048)
			(stroke
				(width 0.1)
				(type default)
			)
			(layer "B.Fab")
		)
		(fp_line
			(start 0.12065 -0.2794)
			(end -0.12065 -0.2794)
			(stroke
				(width 0.1)
				(type default)
			)
			(layer "B.Fab")
		)
		(fp_line
			(start -0.67945 -0.3048)
			(end -0.67945 0.3048)
			(stroke
				(width 0.1)
				(type default)
			)
			(layer "B.Fab")
		)
		(fp_line
			(start -0.12065 -0.3048)
			(end -0.67945 -0.3048)
			(stroke
				(width 0.1)
				(type default)
			)
			(layer "B.Fab")
		)
		(fp_line
			(start 0.12065 -0.305054)
			(end 0.12065 -0.2794)
			(stroke
				(width 0.1)
				(type default)
			)
			(layer "B.Fab")
		)
		(fp_line
			(start 0.67945 -0.305054)
			(end 0.12065 -0.305054)
			(stroke
				(width 0.1)
				(type default)
			)
			(layer "B.Fab")
		)
		(pad "1" smd circle
			(at 0.40005 0 90)
			(size 0 0)
			(layers "B.Cu" "B.Mask" "B.Paste")
			(net "P3V3_AUX")
		)
		(pad "2" smd circle
			(at -0.40005 0 90)
			(size 0 0)
			(layers "B.Cu" "B.Mask" "B.Paste")
			(net "PU_S3M_CPU0_CPLD_STATUS")
		)
	)
	(footprint ""
		(layer "B.Cu")
		(at 366.120934 -244.820186 -90)
		(property "Reference" "C382"
			(at 0 0 90)
			(layer "B.SilkS")
			(hide yes)
			(effects
				(font
					(size 1.27 1.27)
				)
				(justify mirror)
			)
		)
		(property "Value" ""
			(at 0 0 90)
			(layer "B.Fab")
			(effects
				(font
					(size 1.27 1.27)
				)
				(justify mirror)
			)
		)
		(duplicate_pad_numbers_are_jumpers no)
		(fp_line
			(start -1.524 0.762)
			(end 1.524 0.762)
			(stroke
				(width 0.1524)
				(type default)
			)
			(layer "B.SilkS")
		)
		(fp_line
			(start 1.524 0.762)
			(end 1.524 -0.762)
			(stroke
				(width 0.1524)
				(type default)
			)
			(layer "B.SilkS")
		)
		(fp_line
			(start -1.524 -0.762)
			(end -1.524 0.762)
			(stroke
				(width 0.1524)
				(type default)
			)
			(layer "B.SilkS")
		)
		(fp_line
			(start 1.524 -0.762)
			(end -1.524 -0.762)
			(stroke
				(width 0.1524)
				(type default)
			)
			(layer "B.SilkS")
		)
		(fp_line
			(start -1.1049 0.724916)
			(end -1.1049 -0.724916)
			(stroke
				(width 0.1)
				(type default)
			)
			(layer "B.Fab")
		)
		(fp_line
			(start 1.1049 0.724916)
			(end -1.1049 0.724916)
			(stroke
				(width 0.1)
				(type default)
			)
			(layer "B.Fab")
		)
		(fp_line
			(start -1.1049 -0.724916)
			(end 1.1049 -0.724916)
			(stroke
				(width 0.1)
				(type default)
			)
			(layer "B.Fab")
		)
		(fp_line
			(start 1.1049 -0.724916)
			(end 1.1049 0.724916)
			(stroke
				(width 0.1)
				(type default)
			)
			(layer "B.Fab")
		)
		(pad "1" smd rect
			(at 0.889 0 270)
			(size 1.016 1.27)
			(layers "B.Cu" "B.Mask" "B.Paste")
			(net "PVCCIN_CPU0")
		)
		(pad "2" smd rect
			(at -0.889 0 270)
			(size 1.016 1.27)
			(layers "B.Cu" "B.Mask" "B.Paste")
			(net "GND")
		)
	)
	(footprint ""
		(layer "B.Cu")
		(at 298.626784 -356.036372 -90)
		(property "Reference" "PC2170"
			(at 0 0 90)
			(layer "B.SilkS")
			(hide yes)
			(effects
				(font
					(size 1.27 1.27)
				)
				(justify mirror)
			)
		)
		(property "Value" ""
			(at 0 0 90)
			(layer "B.Fab")
			(effects
				(font
					(size 1.27 1.27)
				)
				(justify mirror)
			)
		)
		(duplicate_pad_numbers_are_jumpers no)
		(fp_line
			(start -4.533392 2.249932)
			(end 4.533392 2.249932)
			(stroke
				(width 0.1524)
				(type default)
			)
			(layer "B.SilkS")
		)
		(fp_line
			(start 4.533392 2.249932)
			(end 4.533392 -2.249932)
			(stroke
				(width 0.1524)
				(type default)
			)
			(layer "B.SilkS")
		)
		(fp_line
			(start -4.533392 -2.249932)
			(end -4.533392 2.249932)
			(stroke
				(width 0.1524)
				(type default)
			)
			(layer "B.SilkS")
		)
		(fp_line
			(start 4.533392 -2.249932)
			(end -4.533392 -2.249932)
			(stroke
				(width 0.1524)
				(type default)
			)
			(layer "B.SilkS")
		)
		(fp_poly
			(pts
				(xy 4.533392 -2.326132) (xy 5.39242 -2.326132) (xy 5.39242 2.326132) (xy 4.533392 2.326132)
			)
			(stroke
				(width 0)
				(type default)
			)
			(fill yes)
			(layer "B.SilkS")
		)
		(fp_line
			(start -3.750056 2.249932)
			(end 3.750056 2.249932)
			(stroke
				(width 0.1)
				(type default)
			)
			(layer "B.Fab")
		)
		(fp_line
			(start 3.750056 2.249932)
			(end 3.750056 -2.249932)
			(stroke
				(width 0.1)
				(type default)
			)
			(layer "B.Fab")
		)
		(fp_line
			(start -3.750056 -2.249932)
			(end -3.750056 2.249932)
			(stroke
				(width 0.1)
				(type default)
			)
			(layer "B.Fab")
		)
		(fp_line
			(start 3.750056 -2.249932)
			(end -3.750056 -2.249932)
			(stroke
				(width 0.1)
				(type default)
			)
			(layer "B.Fab")
		)
		(fp_text user "+"
			(at 6.322314 0.786384 180)
			(unlocked yes)
			(layer "B.SilkS")
			(effects
				(font
					(size 1.905 1.4224)
					(thickness 0.1524)
				)
				(justify left mirror)
			)
		)
		(fp_text user "-"
			(at -4.8514 -0.14605 270)
			(unlocked yes)
			(layer "B.SilkS")
			(effects
				(font
					(size 1.905 1.4224)
					(thickness 0.1524)
				)
				(justify left mirror)
			)
		)
		(fp_text user "+"
			(at 6.322314 0.786384 180)
			(unlocked yes)
			(layer "B.Fab")
			(effects
				(font
					(size 1.905 1.4224)
					(thickness 0.1524)
				)
				(justify left mirror)
			)
		)
		(fp_text user "-"
			(at -4.8514 -0.14605 270)
			(unlocked yes)
			(layer "B.Fab")
			(effects
				(font
					(size 1.905 1.4224)
					(thickness 0.1524)
				)
				(justify left mirror)
			)
		)
		(pad "1" smd rect
			(at 3.199892 0 90)
			(size 2.413 2.8194)
			(layers "B.Cu" "B.Mask" "B.Paste")
			(net "PVCCFA_EHV_FIVRA_CPU0")
		)
		(pad "2" smd rect
			(at -3.199892 0 90)
			(size 2.413 2.8194)
			(layers "B.Cu" "B.Mask" "B.Paste")
			(net "GND")
		)
	)
	(footprint ""
		(layer "B.Cu")
		(at 10.558272 -184.625996)
		(property "Reference" "R966"
			(at 0 0 0)
			(layer "B.SilkS")
			(hide yes)
			(effects
				(font
					(size 1.27 1.27)
				)
				(justify mirror)
			)
		)
		(property "Value" ""
			(at 0 0 0)
			(layer "B.Fab")
			(effects
				(font
					(size 1.27 1.27)
				)
				(justify mirror)
			)
		)
		(duplicate_pad_numbers_are_jumpers no)
		(fp_line
			(start -0.7874 -0.4064)
			(end -0.7874 0.4064)
			(stroke
				(width 0.1524)
				(type default)
			)
			(layer "B.SilkS")
		)
		(fp_line
			(start -0.7874 0.4064)
			(end 0.7874 0.4064)
			(stroke
				(width 0.1524)
				(type default)
			)
			(layer "B.SilkS")
		)
		(fp_line
			(start 0.7874 -0.4064)
			(end -0.7874 -0.4064)
			(stroke
				(width 0.1524)
				(type default)
			)
			(layer "B.SilkS")
		)
		(fp_line
			(start 0.7874 0.4064)
			(end 0.7874 -0.4064)
			(stroke
				(width 0.1524)
				(type default)
			)
			(layer "B.SilkS")
		)
		(fp_line
			(start -0.67945 -0.3048)
			(end -0.67945 0.3048)
			(stroke
				(width 0.1)
				(type default)
			)
			(layer "B.Fab")
		)
		(fp_line
			(start -0.67945 0.3048)
			(end -0.120396 0.3048)
			(stroke
				(width 0.1)
				(type default)
			)
			(layer "B.Fab")
		)
		(fp_line
			(start -0.12065 -0.3048)
			(end -0.67945 -0.3048)
			(stroke
				(width 0.1)
				(type default)
			)
			(layer "B.Fab")
		)
		(fp_line
			(start -0.12065 -0.2794)
			(end -0.12065 -0.3048)
			(stroke
				(width 0.1)
				(type default)
			)
			(layer "B.Fab")
		)
		(fp_line
			(start -0.120396 0.2794)
			(end 0.12065 0.2794)
			(stroke
				(width 0.1)
				(type default)
			)
			(layer "B.Fab")
		)
		(fp_line
			(start -0.120396 0.3048)
			(end -0.120396 0.2794)
			(stroke
				(width 0.1)
				(type default)
			)
			(layer "B.Fab")
		)
		(fp_line
			(start 0.12065 -0.305054)
			(end 0.12065 -0.2794)
			(stroke
				(width 0.1)
				(type default)
			)
			(layer "B.Fab")
		)
		(fp_line
			(start 0.12065 -0.2794)
			(end -0.12065 -0.2794)
			(stroke
				(width 0.1)
				(type default)
			)
			(layer "B.Fab")
		)
		(fp_line
			(start 0.12065 0.2794)
			(end 0.12065 0.3048)
			(stroke
				(width 0.1)
				(type default)
			)
			(layer "B.Fab")
		)
		(fp_line
			(start 0.12065 0.3048)
			(end 0.67945 0.3048)
			(stroke
				(width 0.1)
				(type default)
			)
			(layer "B.Fab")
		)
		(fp_line
			(start 0.67945 -0.305054)
			(end 0.12065 -0.305054)
			(stroke
				(width 0.1)
				(type default)
			)
			(layer "B.Fab")
		)
		(fp_line
			(start 0.67945 0.3048)
			(end 0.67945 -0.305054)
			(stroke
				(width 0.1)
				(type default)
			)
			(layer "B.Fab")
		)
		(pad "1" smd circle
			(at 0.40005 0 180)
			(size 0 0)
			(layers "B.Cu" "B.Mask" "B.Paste")
			(net "P3V3_AUX")
		)
		(pad "2" smd circle
			(at -0.40005 0 180)
			(size 0 0)
			(layers "B.Cu" "B.Mask" "B.Paste")
			(net "SMB_PEHPCPU1_LVC3_SCL")
		)
	)
	(footprint ""
		(layer "B.Cu")
		(at 70.369684 -188.458856 90)
		(property "Reference" "R55"
			(at 0 0 90)
			(layer "B.SilkS")
			(hide yes)
			(effects
				(font
					(size 1.27 1.27)
				)
				(justify mirror)
			)
		)
		(property "Value" ""
			(at 0 0 90)
			(layer "B.Fab")
			(effects
				(font
					(size 1.27 1.27)
				)
				(justify mirror)
			)
		)
		(duplicate_pad_numbers_are_jumpers no)
		(fp_line
			(start 0.7874 -0.4064)
			(end -0.7874 -0.4064)
			(stroke
				(width 0.1524)
				(type default)
			)
			(layer "B.SilkS")
		)
		(fp_line
			(start -0.7874 -0.4064)
			(end -0.7874 0.4064)
			(stroke
				(width 0.1524)
				(type default)
			)
			(layer "B.SilkS")
		)
		(fp_line
			(start 0.7874 0.4064)
			(end 0.7874 -0.4064)
			(stroke
				(width 0.1524)
				(type default)
			)
			(layer "B.SilkS")
		)
		(fp_line
			(start -0.7874 0.4064)
			(end 0.7874 0.4064)
			(stroke
				(width 0.1524)
				(type default)
			)
			(layer "B.SilkS")
		)
		(fp_line
			(start 0.67945 -0.305054)
			(end 0.12065 -0.305054)
			(stroke
				(width 0.1)
				(type default)
			)
			(layer "B.Fab")
		)
		(fp_line
			(start 0.12065 -0.305054)
			(end 0.12065 -0.2794)
			(stroke
				(width 0.1)
				(type default)
			)
			(layer "B.Fab")
		)
		(fp_line
			(start -0.12065 -0.3048)
			(end -0.67945 -0.3048)
			(stroke
				(width 0.1)
				(type default)
			)
			(layer "B.Fab")
		)
		(fp_line
			(start -0.67945 -0.3048)
			(end -0.67945 0.3048)
			(stroke
				(width 0.1)
				(type default)
			)
			(layer "B.Fab")
		)
		(fp_line
			(start 0.12065 -0.2794)
			(end -0.12065 -0.2794)
			(stroke
				(width 0.1)
				(type default)
			)
			(layer "B.Fab")
		)
		(fp_line
			(start -0.12065 -0.2794)
			(end -0.12065 -0.3048)
			(stroke
				(width 0.1)
				(type default)
			)
			(layer "B.Fab")
		)
		(fp_line
			(start 0.12065 0.2794)
			(end 0.12065 0.3048)
			(stroke
				(width 0.1)
				(type default)
			)
			(layer "B.Fab")
		)
		(fp_line
			(start -0.120396 0.2794)
			(end 0.12065 0.2794)
			(stroke
				(width 0.1)
				(type default)
			)
			(layer "B.Fab")
		)
		(fp_line
			(start 0.67945 0.3048)
			(end 0.67945 -0.305054)
			(stroke
				(width 0.1)
				(type default)
			)
			(layer "B.Fab")
		)
		(fp_line
			(start 0.12065 0.3048)
			(end 0.67945 0.3048)
			(stroke
				(width 0.1)
				(type default)
			)
			(layer "B.Fab")
		)
		(fp_line
			(start -0.120396 0.3048)
			(end -0.120396 0.2794)
			(stroke
				(width 0.1)
				(type default)
			)
			(layer "B.Fab")
		)
		(fp_line
			(start -0.67945 0.3048)
			(end -0.120396 0.3048)
			(stroke
				(width 0.1)
				(type default)
			)
			(layer "B.Fab")
		)
		(pad "1" smd circle
			(at 0.40005 0 270)
			(size 0 0)
			(layers "B.Cu" "B.Mask" "B.Paste")
			(net "SVID_DIO0_CPU1")
		)
		(pad "2" smd circle
			(at -0.40005 0 270)
			(size 0 0)
			(layers "B.Cu" "B.Mask" "B.Paste")
			(net "SVID_DIO0_CPU1_R")
		)
	)
	(footprint ""
		(layer "B.Cu")
		(at 332.543912 -31.386272 90)
		(property "Reference" "R1395"
			(at 0 0 90)
			(layer "B.SilkS")
			(hide yes)
			(effects
				(font
					(size 1.27 1.27)
				)
				(justify mirror)
			)
		)
		(property "Value" ""
			(at 0 0 90)
			(layer "B.Fab")
			(effects
				(font
					(size 1.27 1.27)
				)
				(justify mirror)
			)
		)
		(duplicate_pad_numbers_are_jumpers no)
		(fp_line
			(start 0.7874 -0.4064)
			(end -0.7874 -0.4064)
			(stroke
				(width 0.1524)
				(type default)
			)
			(layer "B.SilkS")
		)
		(fp_line
			(start -0.7874 -0.4064)
			(end -0.7874 0.4064)
			(stroke
				(width 0.1524)
				(type default)
			)
			(layer "B.SilkS")
		)
		(fp_line
			(start 0.7874 0.4064)
			(end 0.7874 -0.4064)
			(stroke
				(width 0.1524)
				(type default)
			)
			(layer "B.SilkS")
		)
		(fp_line
			(start -0.7874 0.4064)
			(end 0.7874 0.4064)
			(stroke
				(width 0.1524)
				(type default)
			)
			(layer "B.SilkS")
		)
		(fp_line
			(start 0.67945 -0.305054)
			(end 0.12065 -0.305054)
			(stroke
				(width 0.1)
				(type default)
			)
			(layer "B.Fab")
		)
		(fp_line
			(start 0.12065 -0.305054)
			(end 0.12065 -0.2794)
			(stroke
				(width 0.1)
				(type default)
			)
			(layer "B.Fab")
		)
		(fp_line
			(start -0.12065 -0.3048)
			(end -0.67945 -0.3048)
			(stroke
				(width 0.1)
				(type default)
			)
			(layer "B.Fab")
		)
		(fp_line
			(start -0.67945 -0.3048)
			(end -0.67945 0.3048)
			(stroke
				(width 0.1)
				(type default)
			)
			(layer "B.Fab")
		)
		(fp_line
			(start 0.12065 -0.2794)
			(end -0.12065 -0.2794)
			(stroke
				(width 0.1)
				(type default)
			)
			(layer "B.Fab")
		)
		(fp_line
			(start -0.12065 -0.2794)
			(end -0.12065 -0.3048)
			(stroke
				(width 0.1)
				(type default)
			)
			(layer "B.Fab")
		)
		(fp_line
			(start 0.12065 0.2794)
			(end 0.12065 0.3048)
			(stroke
				(width 0.1)
				(type default)
			)
			(layer "B.Fab")
		)
		(fp_line
			(start -0.120396 0.2794)
			(end 0.12065 0.2794)
			(stroke
				(width 0.1)
				(type default)
			)
			(layer "B.Fab")
		)
		(fp_line
			(start 0.67945 0.3048)
			(end 0.67945 -0.305054)
			(stroke
				(width 0.1)
				(type default)
			)
			(layer "B.Fab")
		)
		(fp_line
			(start 0.12065 0.3048)
			(end 0.67945 0.3048)
			(stroke
				(width 0.1)
				(type default)
			)
			(layer "B.Fab")
		)
		(fp_line
			(start -0.120396 0.3048)
			(end -0.120396 0.2794)
			(stroke
				(width 0.1)
				(type default)
			)
			(layer "B.Fab")
		)
		(fp_line
			(start -0.67945 0.3048)
			(end -0.120396 0.3048)
			(stroke
				(width 0.1)
				(type default)
			)
			(layer "B.Fab")
		)
		(pad "1" smd circle
			(at 0.40005 0 270)
			(size 0 0)
			(layers "B.Cu" "B.Mask" "B.Paste")
			(net "SPI_PCH_TPM_CS_N")
		)
		(pad "2" smd circle
			(at -0.40005 0 270)
			(size 0 0)
			(layers "B.Cu" "B.Mask" "B.Paste")
			(net "SPI_TPM_CS_N")
		)
	)
	(footprint ""
		(layer "B.Cu")
		(at 80.812132 -58.416698 90)
		(property "Reference" "R3807"
			(at 0 0 90)
			(layer "B.SilkS")
			(hide yes)
			(effects
				(font
					(size 1.27 1.27)
				)
				(justify mirror)
			)
		)
		(property "Value" ""
			(at 0 0 90)
			(layer "B.Fab")
			(effects
				(font
					(size 1.27 1.27)
				)
				(justify mirror)
			)
		)
		(duplicate_pad_numbers_are_jumpers no)
		(fp_line
			(start 0.7874 -0.4064)
			(end -0.7874 -0.4064)
			(stroke
				(width 0.1524)
				(type default)
			)
			(layer "B.SilkS")
		)
		(fp_line
			(start -0.7874 -0.4064)
			(end -0.7874 0.4064)
			(stroke
				(width 0.1524)
				(type default)
			)
			(layer "B.SilkS")
		)
		(fp_line
			(start 0.7874 0.4064)
			(end 0.7874 -0.4064)
			(stroke
				(width 0.1524)
				(type default)
			)
			(layer "B.SilkS")
		)
		(fp_line
			(start -0.7874 0.4064)
			(end 0.7874 0.4064)
			(stroke
				(width 0.1524)
				(type default)
			)
			(layer "B.SilkS")
		)
		(fp_line
			(start 0.67945 -0.305054)
			(end 0.12065 -0.305054)
			(stroke
				(width 0.1)
				(type default)
			)
			(layer "B.Fab")
		)
		(fp_line
			(start 0.12065 -0.305054)
			(end 0.12065 -0.2794)
			(stroke
				(width 0.1)
				(type default)
			)
			(layer "B.Fab")
		)
		(fp_line
			(start -0.12065 -0.3048)
			(end -0.67945 -0.3048)
			(stroke
				(width 0.1)
				(type default)
			)
			(layer "B.Fab")
		)
		(fp_line
			(start -0.67945 -0.3048)
			(end -0.67945 0.3048)
			(stroke
				(width 0.1)
				(type default)
			)
			(layer "B.Fab")
		)
		(fp_line
			(start 0.12065 -0.2794)
			(end -0.12065 -0.2794)
			(stroke
				(width 0.1)
				(type default)
			)
			(layer "B.Fab")
		)
		(fp_line
			(start -0.12065 -0.2794)
			(end -0.12065 -0.3048)
			(stroke
				(width 0.1)
				(type default)
			)
			(layer "B.Fab")
		)
		(fp_line
			(start 0.12065 0.2794)
			(end 0.12065 0.3048)
			(stroke
				(width 0.1)
				(type default)
			)
			(layer "B.Fab")
		)
		(fp_line
			(start -0.120396 0.2794)
			(end 0.12065 0.2794)
			(stroke
				(width 0.1)
				(type default)
			)
			(layer "B.Fab")
		)
		(fp_line
			(start 0.67945 0.3048)
			(end 0.67945 -0.305054)
			(stroke
				(width 0.1)
				(type default)
			)
			(layer "B.Fab")
		)
		(fp_line
			(start 0.12065 0.3048)
			(end 0.67945 0.3048)
			(stroke
				(width 0.1)
				(type default)
			)
			(layer "B.Fab")
		)
		(fp_line
			(start -0.120396 0.3048)
			(end -0.120396 0.2794)
			(stroke
				(width 0.1)
				(type default)
			)
			(layer "B.Fab")
		)
		(fp_line
			(start -0.67945 0.3048)
			(end -0.120396 0.3048)
			(stroke
				(width 0.1)
				(type default)
			)
			(layer "B.Fab")
		)
		(pad "1" smd circle
			(at 0.40005 0 270)
			(size 0 0)
			(layers "B.Cu" "B.Mask" "B.Paste")
			(net "P3V3_OCP_UV_2_R1")
		)
		(pad "2" smd circle
			(at -0.40005 0 270)
			(size 0 0)
			(layers "B.Cu" "B.Mask" "B.Paste")
			(net "P3V3_OCP_UV_2")
		)
	)
	(footprint ""
		(layer "B.Cu")
		(at 416.02914 -169.700194)
		(property "Reference" "PC197_P0_1"
			(at 0 0 0)
			(layer "B.SilkS")
			(hide yes)
			(effects
				(font
					(size 1.27 1.27)
				)
				(justify mirror)
			)
		)
		(property "Value" ""
			(at 0 0 0)
			(layer "B.Fab")
			(effects
				(font
					(size 1.27 1.27)
				)
				(justify mirror)
			)
		)
		(duplicate_pad_numbers_are_jumpers no)
		(fp_line
			(start -1.524 -0.762)
			(end -1.524 0.762)
			(stroke
				(width 0.1524)
				(type default)
			)
			(layer "B.SilkS")
		)
		(fp_line
			(start -1.524 0.762)
			(end 1.524 0.762)
			(stroke
				(width 0.1524)
				(type default)
			)
			(layer "B.SilkS")
		)
		(fp_line
			(start 1.524 -0.762)
			(end -1.524 -0.762)
			(stroke
				(width 0.1524)
				(type default)
			)
			(layer "B.SilkS")
		)
		(fp_line
			(start 1.524 0.762)
			(end 1.524 -0.762)
			(stroke
				(width 0.1524)
				(type default)
			)
			(layer "B.SilkS")
		)
		(fp_line
			(start -1.1049 -0.724916)
			(end 1.1049 -0.724916)
			(stroke
				(width 0.1)
				(type default)
			)
			(layer "B.Fab")
		)
		(fp_line
			(start -1.1049 0.724916)
			(end -1.1049 -0.724916)
			(stroke
				(width 0.1)
				(type default)
			)
			(layer "B.Fab")
		)
		(fp_line
			(start 1.1049 -0.724916)
			(end 1.1049 0.724916)
			(stroke
				(width 0.1)
				(type default)
			)
			(layer "B.Fab")
		)
		(fp_line
			(start 1.1049 0.724916)
			(end -1.1049 0.724916)
			(stroke
				(width 0.1)
				(type default)
			)
			(layer "B.Fab")
		)
		(pad "1" smd rect
			(at 0.889 0)
			(size 1.016 1.27)
			(layers "B.Cu" "B.Mask" "B.Paste")
			(net "SW_P12V_PVCCINFAON_CPU0_FLT")
		)
		(pad "2" smd rect
			(at -0.889 0)
			(size 1.016 1.27)
			(layers "B.Cu" "B.Mask" "B.Paste")
			(net "GND")
		)
	)
	(footprint ""
		(layer "B.Cu")
		(at 243.001038 -101.447854 180)
		(property "Reference" "R1525"
			(at 0 0 0)
			(layer "B.SilkS")
			(hide yes)
			(effects
				(font
					(size 1.27 1.27)
				)
				(justify mirror)
			)
		)
		(property "Value" ""
			(at 0 0 0)
			(layer "B.Fab")
			(effects
				(font
					(size 1.27 1.27)
				)
				(justify mirror)
			)
		)
		(duplicate_pad_numbers_are_jumpers no)
		(fp_line
			(start 0.7874 0.4064)
			(end 0.7874 -0.4064)
			(stroke
				(width 0.1524)
				(type default)
			)
			(layer "B.SilkS")
		)
		(fp_line
			(start 0.7874 -0.4064)
			(end -0.7874 -0.4064)
			(stroke
				(width 0.1524)
				(type default)
			)
			(layer "B.SilkS")
		)
		(fp_line
			(start -0.7874 0.4064)
			(end 0.7874 0.4064)
			(stroke
				(width 0.1524)
				(type default)
			)
			(layer "B.SilkS")
		)
		(fp_line
			(start -0.7874 -0.4064)
			(end -0.7874 0.4064)
			(stroke
				(width 0.1524)
				(type default)
			)
			(layer "B.SilkS")
		)
		(fp_line
			(start 0.67945 0.3048)
			(end 0.67945 -0.305054)
			(stroke
				(width 0.1)
				(type default)
			)
			(layer "B.Fab")
		)
		(fp_line
			(start 0.67945 -0.305054)
			(end 0.12065 -0.305054)
			(stroke
				(width 0.1)
				(type default)
			)
			(layer "B.Fab")
		)
		(fp_line
			(start 0.12065 0.3048)
			(end 0.67945 0.3048)
			(stroke
				(width 0.1)
				(type default)
			)
			(layer "B.Fab")
		)
		(fp_line
			(start 0.12065 0.2794)
			(end 0.12065 0.3048)
			(stroke
				(width 0.1)
				(type default)
			)
			(layer "B.Fab")
		)
		(fp_line
			(start 0.12065 -0.2794)
			(end -0.12065 -0.2794)
			(stroke
				(width 0.1)
				(type default)
			)
			(layer "B.Fab")
		)
		(fp_line
			(start 0.12065 -0.305054)
			(end 0.12065 -0.2794)
			(stroke
				(width 0.1)
				(type default)
			)
			(layer "B.Fab")
		)
		(fp_line
			(start -0.120396 0.3048)
			(end -0.120396 0.2794)
			(stroke
				(width 0.1)
				(type default)
			)
			(layer "B.Fab")
		)
		(fp_line
			(start -0.120396 0.2794)
			(end 0.12065 0.2794)
			(stroke
				(width 0.1)
				(type default)
			)
			(layer "B.Fab")
		)
		(fp_line
			(start -0.12065 -0.2794)
			(end -0.12065 -0.3048)
			(stroke
				(width 0.1)
				(type default)
			)
			(layer "B.Fab")
		)
		(fp_line
			(start -0.12065 -0.3048)
			(end -0.67945 -0.3048)
			(stroke
				(width 0.1)
				(type default)
			)
			(layer "B.Fab")
		)
		(fp_line
			(start -0.67945 0.3048)
			(end -0.120396 0.3048)
			(stroke
				(width 0.1)
				(type default)
			)
			(layer "B.Fab")
		)
		(fp_line
			(start -0.67945 -0.3048)
			(end -0.67945 0.3048)
			(stroke
				(width 0.1)
				(type default)
			)
			(layer "B.Fab")
		)
		(pad "1" smd circle
			(at 0.40005 0)
			(size 0 0)
			(layers "B.Cu" "B.Mask" "B.Paste")
			(net "SMB_HOST_3V3AUX_SCL_R")
		)
		(pad "2" smd circle
			(at -0.40005 0)
			(size 0 0)
			(layers "B.Cu" "B.Mask" "B.Paste")
			(net "SMB_HOST_CLK_3V3AUX_SCL")
		)
	)
	(footprint ""
		(layer "B.Cu")
		(at 416.996626 -164.582602 180)
		(property "Reference" "PR380"
			(at 0 0 0)
			(layer "B.SilkS")
			(hide yes)
			(effects
				(font
					(size 1.27 1.27)
				)
				(justify mirror)
			)
		)
		(property "Value" ""
			(at 0 0 0)
			(layer "B.Fab")
			(effects
				(font
					(size 1.27 1.27)
				)
				(justify mirror)
			)
		)
		(duplicate_pad_numbers_are_jumpers no)
		(fp_line
			(start 0.7874 0.4064)
			(end 0.7874 -0.4064)
			(stroke
				(width 0.1524)
				(type default)
			)
			(layer "B.SilkS")
		)
		(fp_line
			(start 0.7874 -0.4064)
			(end -0.7874 -0.4064)
			(stroke
				(width 0.1524)
				(type default)
			)
			(layer "B.SilkS")
		)
		(fp_line
			(start -0.7874 0.4064)
			(end 0.7874 0.4064)
			(stroke
				(width 0.1524)
				(type default)
			)
			(layer "B.SilkS")
		)
		(fp_line
			(start -0.7874 -0.4064)
			(end -0.7874 0.4064)
			(stroke
				(width 0.1524)
				(type default)
			)
			(layer "B.SilkS")
		)
		(fp_line
			(start 0.67945 0.3048)
			(end 0.67945 -0.305054)
			(stroke
				(width 0.1)
				(type default)
			)
			(layer "B.Fab")
		)
		(fp_line
			(start 0.67945 -0.305054)
			(end 0.12065 -0.305054)
			(stroke
				(width 0.1)
				(type default)
			)
			(layer "B.Fab")
		)
		(fp_line
			(start 0.12065 0.3048)
			(end 0.67945 0.3048)
			(stroke
				(width 0.1)
				(type default)
			)
			(layer "B.Fab")
		)
		(fp_line
			(start 0.12065 0.2794)
			(end 0.12065 0.3048)
			(stroke
				(width 0.1)
				(type default)
			)
			(layer "B.Fab")
		)
		(fp_line
			(start 0.12065 -0.2794)
			(end -0.12065 -0.2794)
			(stroke
				(width 0.1)
				(type default)
			)
			(layer "B.Fab")
		)
		(fp_line
			(start 0.12065 -0.305054)
			(end 0.12065 -0.2794)
			(stroke
				(width 0.1)
				(type default)
			)
			(layer "B.Fab")
		)
		(fp_line
			(start -0.120396 0.3048)
			(end -0.120396 0.2794)
			(stroke
				(width 0.1)
				(type default)
			)
			(layer "B.Fab")
		)
		(fp_line
			(start -0.120396 0.2794)
			(end 0.12065 0.2794)
			(stroke
				(width 0.1)
				(type default)
			)
			(layer "B.Fab")
		)
		(fp_line
			(start -0.12065 -0.2794)
			(end -0.12065 -0.3048)
			(stroke
				(width 0.1)
				(type default)
			)
			(layer "B.Fab")
		)
		(fp_line
			(start -0.12065 -0.3048)
			(end -0.67945 -0.3048)
			(stroke
				(width 0.1)
				(type default)
			)
			(layer "B.Fab")
		)
		(fp_line
			(start -0.67945 0.3048)
			(end -0.120396 0.3048)
			(stroke
				(width 0.1)
				(type default)
			)
			(layer "B.Fab")
		)
		(fp_line
			(start -0.67945 -0.3048)
			(end -0.67945 0.3048)
			(stroke
				(width 0.1)
				(type default)
			)
			(layer "B.Fab")
		)
		(pad "1" smd circle
			(at 0.40005 0)
			(size 0 0)
			(layers "B.Cu" "B.Mask" "B.Paste")
			(net "PVCCFA_EHV_CPU0_PVCC")
		)
		(pad "2" smd circle
			(at -0.40005 0)
			(size 0 0)
			(layers "B.Cu" "B.Mask" "B.Paste")
			(net "PVCCD_HV_CPU0_VDD1")
		)
	)
	(footprint ""
		(layer "B.Cu")
		(at 185.755788 -109.775498 180)
		(property "Reference" "C1909"
			(at 0 0 0)
			(layer "B.SilkS")
			(hide yes)
			(effects
				(font
					(size 1.27 1.27)
				)
				(justify mirror)
			)
		)
		(property "Value" ""
			(at 0 0 0)
			(layer "B.Fab")
			(effects
				(font
					(size 1.27 1.27)
				)
				(justify mirror)
			)
		)
		(duplicate_pad_numbers_are_jumpers no)
		(fp_line
			(start 0.69215 0.2921)
			(end 0.69215 -0.2921)
			(stroke
				(width 0.1524)
				(type default)
			)
			(layer "B.SilkS")
		)
		(fp_line
			(start 0.69215 -0.2921)
			(end -0.69215 -0.2921)
			(stroke
				(width 0.1524)
				(type default)
			)
			(layer "B.SilkS")
		)
		(fp_line
			(start -0.69215 0.2921)
			(end 0.69215 0.2921)
			(stroke
				(width 0.1524)
				(type default)
			)
			(layer "B.SilkS")
		)
		(fp_line
			(start -0.69215 -0.2921)
			(end -0.69215 0.2921)
			(stroke
				(width 0.1524)
				(type default)
			)
			(layer "B.SilkS")
		)
		(fp_line
			(start 0.51435 0.2794)
			(end 0.51435 -0.2794)
			(stroke
				(width 0.1)
				(type default)
			)
			(layer "B.Fab")
		)
		(fp_line
			(start 0.51435 -0.2794)
			(end -0.51435 -0.2794)
			(stroke
				(width 0.1)
				(type default)
			)
			(layer "B.Fab")
		)
		(fp_line
			(start -0.51435 0.2794)
			(end 0.51435 0.2794)
			(stroke
				(width 0.1)
				(type default)
			)
			(layer "B.Fab")
		)
		(fp_line
			(start -0.51435 -0.2794)
			(end -0.51435 0.2794)
			(stroke
				(width 0.1)
				(type default)
			)
			(layer "B.Fab")
		)
		(pad "1" smd circle
			(at 0.40005 0)
			(size 0 0)
			(layers "B.Cu" "B.Mask" "B.Paste")
			(net "P3V3_AUX_FPGA_VCCIO2")
		)
		(pad "2" smd circle
			(at -0.40005 0)
			(size 0 0)
			(layers "B.Cu" "B.Mask" "B.Paste")
			(net "GND")
		)
		(zone
			(layer "B.Cu")
			(hatch none 0.5)
			(connect_pads
				(clearance 0)
			)
			(min_thickness 0.25)
			(keepout
				(tracks not_allowed)
				(vias allowed)
				(pads allowed)
				(copperpour not_allowed)
				(footprints allowed)
			)
			(placement
				(enabled no)
				(sheetname "")
			)
			(fill
				(thermal_gap 0.5)
				(thermal_bridge_width 0.5)
				(island_removal_mode 0)
			)
			(polygon
				(pts
					(xy 185.565288 -109.863128) (xy 185.656728 -109.921294) (xy 185.856118 -109.921294) (xy 185.946288 -109.863128)
					(xy 185.946288 -109.687868) (xy 185.856118 -109.629448) (xy 185.656728 -109.629448) (xy 185.565288 -109.687614)
				)
			)
		)
	)
	(footprint ""
		(layer "B.Cu")
		(at 135.81888 -9.362948 -90)
		(property "Reference" "R3776"
			(at 0 0 90)
			(layer "B.SilkS")
			(hide yes)
			(effects
				(font
					(size 1.27 1.27)
				)
				(justify mirror)
			)
		)
		(property "Value" ""
			(at 0 0 90)
			(layer "B.Fab")
			(effects
				(font
					(size 1.27 1.27)
				)
				(justify mirror)
			)
		)
		(duplicate_pad_numbers_are_jumpers no)
		(fp_line
			(start -0.7874 0.4064)
			(end 0.7874 0.4064)
			(stroke
				(width 0.1524)
				(type default)
			)
			(layer "B.SilkS")
		)
		(fp_line
			(start 0.7874 0.4064)
			(end 0.7874 -0.4064)
			(stroke
				(width 0.1524)
				(type default)
			)
			(layer "B.SilkS")
		)
		(fp_line
			(start -0.7874 -0.4064)
			(end -0.7874 0.4064)
			(stroke
				(width 0.1524)
				(type default)
			)
			(layer "B.SilkS")
		)
		(fp_line
			(start 0.7874 -0.4064)
			(end -0.7874 -0.4064)
			(stroke
				(width 0.1524)
				(type default)
			)
			(layer "B.SilkS")
		)
		(fp_line
			(start -0.67945 0.3048)
			(end -0.120396 0.3048)
			(stroke
				(width 0.1)
				(type default)
			)
			(layer "B.Fab")
		)
		(fp_line
			(start -0.120396 0.3048)
			(end -0.120396 0.2794)
			(stroke
				(width 0.1)
				(type default)
			)
			(layer "B.Fab")
		)
		(fp_line
			(start 0.12065 0.3048)
			(end 0.67945 0.3048)
			(stroke
				(width 0.1)
				(type default)
			)
			(layer "B.Fab")
		)
		(fp_line
			(start 0.67945 0.3048)
			(end 0.67945 -0.305054)
			(stroke
				(width 0.1)
				(type default)
			)
			(layer "B.Fab")
		)
		(fp_line
			(start -0.120396 0.2794)
			(end 0.12065 0.2794)
			(stroke
				(width 0.1)
				(type default)
			)
			(layer "B.Fab")
		)
		(fp_line
			(start 0.12065 0.2794)
			(end 0.12065 0.3048)
			(stroke
				(width 0.1)
				(type default)
			)
			(layer "B.Fab")
		)
		(fp_line
			(start -0.12065 -0.2794)
			(end -0.12065 -0.3048)
			(stroke
				(width 0.1)
				(type default)
			)
			(layer "B.Fab")
		)
		(fp_line
			(start 0.12065 -0.2794)
			(end -0.12065 -0.2794)
			(stroke
				(width 0.1)
				(type default)
			)
			(layer "B.Fab")
		)
		(fp_line
			(start -0.67945 -0.3048)
			(end -0.67945 0.3048)
			(stroke
				(width 0.1)
				(type default)
			)
			(layer "B.Fab")
		)
		(fp_line
			(start -0.12065 -0.3048)
			(end -0.67945 -0.3048)
			(stroke
				(width 0.1)
				(type default)
			)
			(layer "B.Fab")
		)
		(fp_line
			(start 0.12065 -0.305054)
			(end 0.12065 -0.2794)
			(stroke
				(width 0.1)
				(type default)
			)
			(layer "B.Fab")
		)
		(fp_line
			(start 0.67945 -0.305054)
			(end 0.12065 -0.305054)
			(stroke
				(width 0.1)
				(type default)
			)
			(layer "B.Fab")
		)
		(pad "1" smd circle
			(at 0.40005 0 90)
			(size 0 0)
			(layers "B.Cu" "B.Mask" "B.Paste")
			(net "FM_UARTSW_MSB_N")
		)
		(pad "2" smd circle
			(at -0.40005 0 90)
			(size 0 0)
			(layers "B.Cu" "B.Mask" "B.Paste")
			(net "FM_UARTSW_MSB_R")
		)
	)
	(footprint ""
		(layer "B.Cu")
		(at 164.64788 -105.755948 180)
		(property "Reference" "R2663"
			(at 0 0 0)
			(layer "B.SilkS")
			(hide yes)
			(effects
				(font
					(size 1.27 1.27)
				)
				(justify mirror)
			)
		)
		(property "Value" ""
			(at 0 0 0)
			(layer "B.Fab")
			(effects
				(font
					(size 1.27 1.27)
				)
				(justify mirror)
			)
		)
		(duplicate_pad_numbers_are_jumpers no)
		(fp_line
			(start 0.7874 0.4064)
			(end 0.7874 -0.4064)
			(stroke
				(width 0.1524)
				(type default)
			)
			(layer "B.SilkS")
		)
		(fp_line
			(start 0.7874 -0.4064)
			(end -0.7874 -0.4064)
			(stroke
				(width 0.1524)
				(type default)
			)
			(layer "B.SilkS")
		)
		(fp_line
			(start -0.7874 0.4064)
			(end 0.7874 0.4064)
			(stroke
				(width 0.1524)
				(type default)
			)
			(layer "B.SilkS")
		)
		(fp_line
			(start -0.7874 -0.4064)
			(end -0.7874 0.4064)
			(stroke
				(width 0.1524)
				(type default)
			)
			(layer "B.SilkS")
		)
		(fp_line
			(start 0.67945 0.3048)
			(end 0.67945 -0.305054)
			(stroke
				(width 0.1)
				(type default)
			)
			(layer "B.Fab")
		)
		(fp_line
			(start 0.67945 -0.305054)
			(end 0.12065 -0.305054)
			(stroke
				(width 0.1)
				(type default)
			)
			(layer "B.Fab")
		)
		(fp_line
			(start 0.12065 0.3048)
			(end 0.67945 0.3048)
			(stroke
				(width 0.1)
				(type default)
			)
			(layer "B.Fab")
		)
		(fp_line
			(start 0.12065 0.2794)
			(end 0.12065 0.3048)
			(stroke
				(width 0.1)
				(type default)
			)
			(layer "B.Fab")
		)
		(fp_line
			(start 0.12065 -0.2794)
			(end -0.12065 -0.2794)
			(stroke
				(width 0.1)
				(type default)
			)
			(layer "B.Fab")
		)
		(fp_line
			(start 0.12065 -0.305054)
			(end 0.12065 -0.2794)
			(stroke
				(width 0.1)
				(type default)
			)
			(layer "B.Fab")
		)
		(fp_line
			(start -0.120396 0.3048)
			(end -0.120396 0.2794)
			(stroke
				(width 0.1)
				(type default)
			)
			(layer "B.Fab")
		)
		(fp_line
			(start -0.120396 0.2794)
			(end 0.12065 0.2794)
			(stroke
				(width 0.1)
				(type default)
			)
			(layer "B.Fab")
		)
		(fp_line
			(start -0.12065 -0.2794)
			(end -0.12065 -0.3048)
			(stroke
				(width 0.1)
				(type default)
			)
			(layer "B.Fab")
		)
		(fp_line
			(start -0.12065 -0.3048)
			(end -0.67945 -0.3048)
			(stroke
				(width 0.1)
				(type default)
			)
			(layer "B.Fab")
		)
		(fp_line
			(start -0.67945 0.3048)
			(end -0.120396 0.3048)
			(stroke
				(width 0.1)
				(type default)
			)
			(layer "B.Fab")
		)
		(fp_line
			(start -0.67945 -0.3048)
			(end -0.67945 0.3048)
			(stroke
				(width 0.1)
				(type default)
			)
			(layer "B.Fab")
		)
		(pad "1" smd circle
			(at 0.40005 0)
			(size 0 0)
			(layers "B.Cu" "B.Mask" "B.Paste")
			(net "FM_SWB_PWRGD_ISO")
		)
		(pad "2" smd circle
			(at -0.40005 0)
			(size 0 0)
			(layers "B.Cu" "B.Mask" "B.Paste")
			(net "FM_SWB_PWRGD_ISO_R")
		)
	)
	(footprint ""
		(layer "B.Cu")
		(at 169.521632 -354.571554 -90)
		(property "Reference" "PR226"
			(at 0 0 90)
			(layer "B.SilkS")
			(hide yes)
			(effects
				(font
					(size 1.27 1.27)
				)
				(justify mirror)
			)
		)
		(property "Value" ""
			(at 0 0 90)
			(layer "B.Fab")
			(effects
				(font
					(size 1.27 1.27)
				)
				(justify mirror)
			)
		)
		(duplicate_pad_numbers_are_jumpers no)
		(fp_line
			(start -0.7874 0.4064)
			(end 0.7874 0.4064)
			(stroke
				(width 0.1524)
				(type default)
			)
			(layer "B.SilkS")
		)
		(fp_line
			(start 0.7874 0.4064)
			(end 0.7874 -0.4064)
			(stroke
				(width 0.1524)
				(type default)
			)
			(layer "B.SilkS")
		)
		(fp_line
			(start -0.7874 -0.4064)
			(end -0.7874 0.4064)
			(stroke
				(width 0.1524)
				(type default)
			)
			(layer "B.SilkS")
		)
		(fp_line
			(start 0.7874 -0.4064)
			(end -0.7874 -0.4064)
			(stroke
				(width 0.1524)
				(type default)
			)
			(layer "B.SilkS")
		)
		(fp_line
			(start -0.67945 0.3048)
			(end -0.120396 0.3048)
			(stroke
				(width 0.1)
				(type default)
			)
			(layer "B.Fab")
		)
		(fp_line
			(start -0.120396 0.3048)
			(end -0.120396 0.2794)
			(stroke
				(width 0.1)
				(type default)
			)
			(layer "B.Fab")
		)
		(fp_line
			(start 0.12065 0.3048)
			(end 0.67945 0.3048)
			(stroke
				(width 0.1)
				(type default)
			)
			(layer "B.Fab")
		)
		(fp_line
			(start 0.67945 0.3048)
			(end 0.67945 -0.305054)
			(stroke
				(width 0.1)
				(type default)
			)
			(layer "B.Fab")
		)
		(fp_line
			(start -0.120396 0.2794)
			(end 0.12065 0.2794)
			(stroke
				(width 0.1)
				(type default)
			)
			(layer "B.Fab")
		)
		(fp_line
			(start 0.12065 0.2794)
			(end 0.12065 0.3048)
			(stroke
				(width 0.1)
				(type default)
			)
			(layer "B.Fab")
		)
		(fp_line
			(start -0.12065 -0.2794)
			(end -0.12065 -0.3048)
			(stroke
				(width 0.1)
				(type default)
			)
			(layer "B.Fab")
		)
		(fp_line
			(start 0.12065 -0.2794)
			(end -0.12065 -0.2794)
			(stroke
				(width 0.1)
				(type default)
			)
			(layer "B.Fab")
		)
		(fp_line
			(start -0.67945 -0.3048)
			(end -0.67945 0.3048)
			(stroke
				(width 0.1)
				(type default)
			)
			(layer "B.Fab")
		)
		(fp_line
			(start -0.12065 -0.3048)
			(end -0.67945 -0.3048)
			(stroke
				(width 0.1)
				(type default)
			)
			(layer "B.Fab")
		)
		(fp_line
			(start 0.12065 -0.305054)
			(end 0.12065 -0.2794)
			(stroke
				(width 0.1)
				(type default)
			)
			(layer "B.Fab")
		)
		(fp_line
			(start 0.67945 -0.305054)
			(end 0.12065 -0.305054)
			(stroke
				(width 0.1)
				(type default)
			)
			(layer "B.Fab")
		)
		(pad "1" smd circle
			(at 0.40005 0 90)
			(size 0 0)
			(layers "B.Cu" "B.Mask" "B.Paste")
			(net "PVCCFA_EHV_FIVRA_CPU1_PVCC1")
		)
		(pad "2" smd circle
			(at -0.40005 0 90)
			(size 0 0)
			(layers "B.Cu" "B.Mask" "B.Paste")
			(net "PVCCFA_EHV_FIVRA_CPU1_VDD1")
		)
	)
	(footprint ""
		(layer "B.Cu")
		(at 252.05563 -105.256584 -90)
		(property "Reference" "C1324"
			(at 0 0 90)
			(layer "B.SilkS")
			(hide yes)
			(effects
				(font
					(size 1.27 1.27)
				)
				(justify mirror)
			)
		)
		(property "Value" ""
			(at 0 0 90)
			(layer "B.Fab")
			(effects
				(font
					(size 1.27 1.27)
				)
				(justify mirror)
			)
		)
		(duplicate_pad_numbers_are_jumpers no)
		(fp_line
			(start -0.7874 0.4064)
			(end 0.7874 0.4064)
			(stroke
				(width 0.1524)
				(type default)
			)
			(layer "B.SilkS")
		)
		(fp_line
			(start 0.7874 0.4064)
			(end 0.7874 -0.4064)
			(stroke
				(width 0.1524)
				(type default)
			)
			(layer "B.SilkS")
		)
		(fp_line
			(start -0.7874 -0.4064)
			(end -0.7874 0.4064)
			(stroke
				(width 0.1524)
				(type default)
			)
			(layer "B.SilkS")
		)
		(fp_line
			(start 0.7874 -0.4064)
			(end -0.7874 -0.4064)
			(stroke
				(width 0.1524)
				(type default)
			)
			(layer "B.SilkS")
		)
		(fp_line
			(start -0.67945 0.3048)
			(end -0.120396 0.3048)
			(stroke
				(width 0.1)
				(type default)
			)
			(layer "B.Fab")
		)
		(fp_line
			(start -0.120396 0.3048)
			(end -0.120396 0.2794)
			(stroke
				(width 0.1)
				(type default)
			)
			(layer "B.Fab")
		)
		(fp_line
			(start 0.12065 0.3048)
			(end 0.67945 0.3048)
			(stroke
				(width 0.1)
				(type default)
			)
			(layer "B.Fab")
		)
		(fp_line
			(start 0.67945 0.3048)
			(end 0.67945 -0.305054)
			(stroke
				(width 0.1)
				(type default)
			)
			(layer "B.Fab")
		)
		(fp_line
			(start -0.120396 0.2794)
			(end 0.12065 0.2794)
			(stroke
				(width 0.1)
				(type default)
			)
			(layer "B.Fab")
		)
		(fp_line
			(start 0.12065 0.2794)
			(end 0.12065 0.3048)
			(stroke
				(width 0.1)
				(type default)
			)
			(layer "B.Fab")
		)
		(fp_line
			(start -0.12065 -0.2794)
			(end -0.12065 -0.3048)
			(stroke
				(width 0.1)
				(type default)
			)
			(layer "B.Fab")
		)
		(fp_line
			(start 0.12065 -0.2794)
			(end -0.12065 -0.2794)
			(stroke
				(width 0.1)
				(type default)
			)
			(layer "B.Fab")
		)
		(fp_line
			(start -0.67945 -0.3048)
			(end -0.67945 0.3048)
			(stroke
				(width 0.1)
				(type default)
			)
			(layer "B.Fab")
		)
		(fp_line
			(start -0.12065 -0.3048)
			(end -0.67945 -0.3048)
			(stroke
				(width 0.1)
				(type default)
			)
			(layer "B.Fab")
		)
		(fp_line
			(start 0.12065 -0.305054)
			(end 0.12065 -0.2794)
			(stroke
				(width 0.1)
				(type default)
			)
			(layer "B.Fab")
		)
		(fp_line
			(start 0.67945 -0.305054)
			(end 0.12065 -0.305054)
			(stroke
				(width 0.1)
				(type default)
			)
			(layer "B.Fab")
		)
		(pad "1" smd circle
			(at 0.40005 0 90)
			(size 0 0)
			(layers "B.Cu" "B.Mask" "B.Paste")
			(net "FM_CK440Q_DEV_25M_EN")
		)
		(pad "2" smd circle
			(at -0.40005 0 90)
			(size 0 0)
			(layers "B.Cu" "B.Mask" "B.Paste")
			(net "GND")
		)
	)
	(footprint ""
		(layer "B.Cu")
		(at 435.549802 -13.120116 180)
		(property "Reference" "C1237"
			(at 0 0 0)
			(layer "B.SilkS")
			(hide yes)
			(effects
				(font
					(size 1.27 1.27)
				)
				(justify mirror)
			)
		)
		(property "Value" ""
			(at 0 0 0)
			(layer "B.Fab")
			(effects
				(font
					(size 1.27 1.27)
				)
				(justify mirror)
			)
		)
		(duplicate_pad_numbers_are_jumpers no)
		(fp_line
			(start 0.7874 0.4064)
			(end 0.7874 -0.4064)
			(stroke
				(width 0.1524)
				(type default)
			)
			(layer "B.SilkS")
		)
		(fp_line
			(start 0.7874 -0.4064)
			(end -0.7874 -0.4064)
			(stroke
				(width 0.1524)
				(type default)
			)
			(layer "B.SilkS")
		)
		(fp_line
			(start -0.7874 0.4064)
			(end 0.7874 0.4064)
			(stroke
				(width 0.1524)
				(type default)
			)
			(layer "B.SilkS")
		)
		(fp_line
			(start -0.7874 -0.4064)
			(end -0.7874 0.4064)
			(stroke
				(width 0.1524)
				(type default)
			)
			(layer "B.SilkS")
		)
		(fp_line
			(start 0.67945 0.3048)
			(end 0.67945 -0.305054)
			(stroke
				(width 0.1)
				(type default)
			)
			(layer "B.Fab")
		)
		(fp_line
			(start 0.67945 -0.305054)
			(end 0.12065 -0.305054)
			(stroke
				(width 0.1)
				(type default)
			)
			(layer "B.Fab")
		)
		(fp_line
			(start 0.12065 0.3048)
			(end 0.67945 0.3048)
			(stroke
				(width 0.1)
				(type default)
			)
			(layer "B.Fab")
		)
		(fp_line
			(start 0.12065 0.2794)
			(end 0.12065 0.3048)
			(stroke
				(width 0.1)
				(type default)
			)
			(layer "B.Fab")
		)
		(fp_line
			(start 0.12065 -0.2794)
			(end -0.12065 -0.2794)
			(stroke
				(width 0.1)
				(type default)
			)
			(layer "B.Fab")
		)
		(fp_line
			(start 0.12065 -0.305054)
			(end 0.12065 -0.2794)
			(stroke
				(width 0.1)
				(type default)
			)
			(layer "B.Fab")
		)
		(fp_line
			(start -0.120396 0.3048)
			(end -0.120396 0.2794)
			(stroke
				(width 0.1)
				(type default)
			)
			(layer "B.Fab")
		)
		(fp_line
			(start -0.120396 0.2794)
			(end 0.12065 0.2794)
			(stroke
				(width 0.1)
				(type default)
			)
			(layer "B.Fab")
		)
		(fp_line
			(start -0.12065 -0.2794)
			(end -0.12065 -0.3048)
			(stroke
				(width 0.1)
				(type default)
			)
			(layer "B.Fab")
		)
		(fp_line
			(start -0.12065 -0.3048)
			(end -0.67945 -0.3048)
			(stroke
				(width 0.1)
				(type default)
			)
			(layer "B.Fab")
		)
		(fp_line
			(start -0.67945 0.3048)
			(end -0.120396 0.3048)
			(stroke
				(width 0.1)
				(type default)
			)
			(layer "B.Fab")
		)
		(fp_line
			(start -0.67945 -0.3048)
			(end -0.67945 0.3048)
			(stroke
				(width 0.1)
				(type default)
			)
			(layer "B.Fab")
		)
		(pad "1" smd circle
			(at 0.40005 0)
			(size 0 0)
			(layers "B.Cu" "B.Mask" "B.Paste")
			(net "P3V3_OCP_SFF")
		)
		(pad "2" smd circle
			(at -0.40005 0)
			(size 0 0)
			(layers "B.Cu" "B.Mask" "B.Paste")
			(net "GND")
		)
	)
	(footprint ""
		(layer "B.Cu")
		(at 166.386002 -251.267214 180)
		(property "Reference" "R1230"
			(at 0 0 0)
			(layer "B.SilkS")
			(hide yes)
			(effects
				(font
					(size 1.27 1.27)
				)
				(justify mirror)
			)
		)
		(property "Value" ""
			(at 0 0 0)
			(layer "B.Fab")
			(effects
				(font
					(size 1.27 1.27)
				)
				(justify mirror)
			)
		)
		(duplicate_pad_numbers_are_jumpers no)
		(fp_line
			(start 0.7874 0.4064)
			(end 0.7874 -0.4064)
			(stroke
				(width 0.1524)
				(type default)
			)
			(layer "B.SilkS")
		)
		(fp_line
			(start 0.7874 -0.4064)
			(end -0.7874 -0.4064)
			(stroke
				(width 0.1524)
				(type default)
			)
			(layer "B.SilkS")
		)
		(fp_line
			(start -0.7874 0.4064)
			(end 0.7874 0.4064)
			(stroke
				(width 0.1524)
				(type default)
			)
			(layer "B.SilkS")
		)
		(fp_line
			(start -0.7874 -0.4064)
			(end -0.7874 0.4064)
			(stroke
				(width 0.1524)
				(type default)
			)
			(layer "B.SilkS")
		)
		(fp_line
			(start 0.67945 0.3048)
			(end 0.67945 -0.305054)
			(stroke
				(width 0.1)
				(type default)
			)
			(layer "B.Fab")
		)
		(fp_line
			(start 0.67945 -0.305054)
			(end 0.12065 -0.305054)
			(stroke
				(width 0.1)
				(type default)
			)
			(layer "B.Fab")
		)
		(fp_line
			(start 0.12065 0.3048)
			(end 0.67945 0.3048)
			(stroke
				(width 0.1)
				(type default)
			)
			(layer "B.Fab")
		)
		(fp_line
			(start 0.12065 0.2794)
			(end 0.12065 0.3048)
			(stroke
				(width 0.1)
				(type default)
			)
			(layer "B.Fab")
		)
		(fp_line
			(start 0.12065 -0.2794)
			(end -0.12065 -0.2794)
			(stroke
				(width 0.1)
				(type default)
			)
			(layer "B.Fab")
		)
		(fp_line
			(start 0.12065 -0.305054)
			(end 0.12065 -0.2794)
			(stroke
				(width 0.1)
				(type default)
			)
			(layer "B.Fab")
		)
		(fp_line
			(start -0.120396 0.3048)
			(end -0.120396 0.2794)
			(stroke
				(width 0.1)
				(type default)
			)
			(layer "B.Fab")
		)
		(fp_line
			(start -0.120396 0.2794)
			(end 0.12065 0.2794)
			(stroke
				(width 0.1)
				(type default)
			)
			(layer "B.Fab")
		)
		(fp_line
			(start -0.12065 -0.2794)
			(end -0.12065 -0.3048)
			(stroke
				(width 0.1)
				(type default)
			)
			(layer "B.Fab")
		)
		(fp_line
			(start -0.12065 -0.3048)
			(end -0.67945 -0.3048)
			(stroke
				(width 0.1)
				(type default)
			)
			(layer "B.Fab")
		)
		(fp_line
			(start -0.67945 0.3048)
			(end -0.120396 0.3048)
			(stroke
				(width 0.1)
				(type default)
			)
			(layer "B.Fab")
		)
		(fp_line
			(start -0.67945 -0.3048)
			(end -0.67945 0.3048)
			(stroke
				(width 0.1)
				(type default)
			)
			(layer "B.Fab")
		)
		(pad "1" smd circle
			(at 0.40005 0)
			(size 0 0)
			(layers "B.Cu" "B.Mask" "B.Paste")
			(net "PVNN_TERM_CPU1")
		)
		(pad "2" smd circle
			(at -0.40005 0)
			(size 0 0)
			(layers "B.Cu" "B.Mask" "B.Paste")
			(net "PUD_XTAL_CPU1_MODE1")
		)
	)
	(footprint ""
		(layer "B.Cu")
		(at 334.341978 -190.82893 90)
		(property "Reference" "R22"
			(at 0 0 90)
			(layer "B.SilkS")
			(hide yes)
			(effects
				(font
					(size 1.27 1.27)
				)
				(justify mirror)
			)
		)
		(property "Value" ""
			(at 0 0 90)
			(layer "B.Fab")
			(effects
				(font
					(size 1.27 1.27)
				)
				(justify mirror)
			)
		)
		(duplicate_pad_numbers_are_jumpers no)
		(fp_line
			(start 0.7874 -0.4064)
			(end -0.7874 -0.4064)
			(stroke
				(width 0.1524)
				(type default)
			)
			(layer "B.SilkS")
		)
		(fp_line
			(start -0.7874 -0.4064)
			(end -0.7874 0.4064)
			(stroke
				(width 0.1524)
				(type default)
			)
			(layer "B.SilkS")
		)
		(fp_line
			(start 0.7874 0.4064)
			(end 0.7874 -0.4064)
			(stroke
				(width 0.1524)
				(type default)
			)
			(layer "B.SilkS")
		)
		(fp_line
			(start -0.7874 0.4064)
			(end 0.7874 0.4064)
			(stroke
				(width 0.1524)
				(type default)
			)
			(layer "B.SilkS")
		)
		(fp_line
			(start 0.67945 -0.305054)
			(end 0.12065 -0.305054)
			(stroke
				(width 0.1)
				(type default)
			)
			(layer "B.Fab")
		)
		(fp_line
			(start 0.12065 -0.305054)
			(end 0.12065 -0.2794)
			(stroke
				(width 0.1)
				(type default)
			)
			(layer "B.Fab")
		)
		(fp_line
			(start -0.12065 -0.3048)
			(end -0.67945 -0.3048)
			(stroke
				(width 0.1)
				(type default)
			)
			(layer "B.Fab")
		)
		(fp_line
			(start -0.67945 -0.3048)
			(end -0.67945 0.3048)
			(stroke
				(width 0.1)
				(type default)
			)
			(layer "B.Fab")
		)
		(fp_line
			(start 0.12065 -0.2794)
			(end -0.12065 -0.2794)
			(stroke
				(width 0.1)
				(type default)
			)
			(layer "B.Fab")
		)
		(fp_line
			(start -0.12065 -0.2794)
			(end -0.12065 -0.3048)
			(stroke
				(width 0.1)
				(type default)
			)
			(layer "B.Fab")
		)
		(fp_line
			(start 0.12065 0.2794)
			(end 0.12065 0.3048)
			(stroke
				(width 0.1)
				(type default)
			)
			(layer "B.Fab")
		)
		(fp_line
			(start -0.120396 0.2794)
			(end 0.12065 0.2794)
			(stroke
				(width 0.1)
				(type default)
			)
			(layer "B.Fab")
		)
		(fp_line
			(start 0.67945 0.3048)
			(end 0.67945 -0.305054)
			(stroke
				(width 0.1)
				(type default)
			)
			(layer "B.Fab")
		)
		(fp_line
			(start 0.12065 0.3048)
			(end 0.67945 0.3048)
			(stroke
				(width 0.1)
				(type default)
			)
			(layer "B.Fab")
		)
		(fp_line
			(start -0.120396 0.3048)
			(end -0.120396 0.2794)
			(stroke
				(width 0.1)
				(type default)
			)
			(layer "B.Fab")
		)
		(fp_line
			(start -0.67945 0.3048)
			(end -0.120396 0.3048)
			(stroke
				(width 0.1)
				(type default)
			)
			(layer "B.Fab")
		)
		(pad "1" smd circle
			(at 0.40005 0 270)
			(size 0 0)
			(layers "B.Cu" "B.Mask" "B.Paste")
			(net "DBP_CPU0_MBP0_GTL_R_N")
		)
		(pad "2" smd circle
			(at -0.40005 0 270)
			(size 0 0)
			(layers "B.Cu" "B.Mask" "B.Paste")
			(net "DBP_CPU_MBP0_GTL_N")
		)
	)
	(footprint ""
		(layer "B.Cu")
		(at 97.46996 -422.143428 -90)
		(property "Reference" "C2340"
			(at 0 0 90)
			(layer "B.SilkS")
			(hide yes)
			(effects
				(font
					(size 1.27 1.27)
				)
				(justify mirror)
			)
		)
		(property "Value" ""
			(at 0 0 90)
			(layer "B.Fab")
			(effects
				(font
					(size 1.27 1.27)
				)
				(justify mirror)
			)
		)
		(duplicate_pad_numbers_are_jumpers no)
		(fp_line
			(start -0.7874 0.4064)
			(end 0.7874 0.4064)
			(stroke
				(width 0.1524)
				(type default)
			)
			(layer "B.SilkS")
		)
		(fp_line
			(start 0.7874 0.4064)
			(end 0.7874 -0.4064)
			(stroke
				(width 0.1524)
				(type default)
			)
			(layer "B.SilkS")
		)
		(fp_line
			(start -0.7874 -0.4064)
			(end -0.7874 0.4064)
			(stroke
				(width 0.1524)
				(type default)
			)
			(layer "B.SilkS")
		)
		(fp_line
			(start 0.7874 -0.4064)
			(end -0.7874 -0.4064)
			(stroke
				(width 0.1524)
				(type default)
			)
			(layer "B.SilkS")
		)
		(fp_line
			(start -0.67945 0.3048)
			(end -0.120396 0.3048)
			(stroke
				(width 0.1)
				(type default)
			)
			(layer "B.Fab")
		)
		(fp_line
			(start -0.120396 0.3048)
			(end -0.120396 0.2794)
			(stroke
				(width 0.1)
				(type default)
			)
			(layer "B.Fab")
		)
		(fp_line
			(start 0.12065 0.3048)
			(end 0.67945 0.3048)
			(stroke
				(width 0.1)
				(type default)
			)
			(layer "B.Fab")
		)
		(fp_line
			(start 0.67945 0.3048)
			(end 0.67945 -0.305054)
			(stroke
				(width 0.1)
				(type default)
			)
			(layer "B.Fab")
		)
		(fp_line
			(start -0.120396 0.2794)
			(end 0.12065 0.2794)
			(stroke
				(width 0.1)
				(type default)
			)
			(layer "B.Fab")
		)
		(fp_line
			(start 0.12065 0.2794)
			(end 0.12065 0.3048)
			(stroke
				(width 0.1)
				(type default)
			)
			(layer "B.Fab")
		)
		(fp_line
			(start -0.12065 -0.2794)
			(end -0.12065 -0.3048)
			(stroke
				(width 0.1)
				(type default)
			)
			(layer "B.Fab")
		)
		(fp_line
			(start 0.12065 -0.2794)
			(end -0.12065 -0.2794)
			(stroke
				(width 0.1)
				(type default)
			)
			(layer "B.Fab")
		)
		(fp_line
			(start -0.67945 -0.3048)
			(end -0.67945 0.3048)
			(stroke
				(width 0.1)
				(type default)
			)
			(layer "B.Fab")
		)
		(fp_line
			(start -0.12065 -0.3048)
			(end -0.67945 -0.3048)
			(stroke
				(width 0.1)
				(type default)
			)
			(layer "B.Fab")
		)
		(fp_line
			(start 0.12065 -0.305054)
			(end 0.12065 -0.2794)
			(stroke
				(width 0.1)
				(type default)
			)
			(layer "B.Fab")
		)
		(fp_line
			(start 0.67945 -0.305054)
			(end 0.12065 -0.305054)
			(stroke
				(width 0.1)
				(type default)
			)
			(layer "B.Fab")
		)
		(pad "1" smd circle
			(at 0.40005 0 90)
			(size 0 0)
			(layers "B.Cu" "B.Mask" "B.Paste")
			(net "HGX_DETECT_N_ISO")
		)
		(pad "2" smd circle
			(at -0.40005 0 90)
			(size 0 0)
			(layers "B.Cu" "B.Mask" "B.Paste")
			(net "GND")
		)
	)
	(footprint ""
		(layer "B.Cu")
		(at 101.717348 -336.192368 -90)
		(property "Reference" "PR329"
			(at 0 0 90)
			(layer "B.SilkS")
			(hide yes)
			(effects
				(font
					(size 1.27 1.27)
				)
				(justify mirror)
			)
		)
		(property "Value" ""
			(at 0 0 90)
			(layer "B.Fab")
			(effects
				(font
					(size 1.27 1.27)
				)
				(justify mirror)
			)
		)
		(duplicate_pad_numbers_are_jumpers no)
		(fp_line
			(start -0.7874 0.4064)
			(end 0.7874 0.4064)
			(stroke
				(width 0.1524)
				(type default)
			)
			(layer "B.SilkS")
		)
		(fp_line
			(start 0.7874 0.4064)
			(end 0.7874 -0.4064)
			(stroke
				(width 0.1524)
				(type default)
			)
			(layer "B.SilkS")
		)
		(fp_line
			(start -0.7874 -0.4064)
			(end -0.7874 0.4064)
			(stroke
				(width 0.1524)
				(type default)
			)
			(layer "B.SilkS")
		)
		(fp_line
			(start 0.7874 -0.4064)
			(end -0.7874 -0.4064)
			(stroke
				(width 0.1524)
				(type default)
			)
			(layer "B.SilkS")
		)
		(fp_line
			(start -0.67945 0.3048)
			(end -0.120396 0.3048)
			(stroke
				(width 0.1)
				(type default)
			)
			(layer "B.Fab")
		)
		(fp_line
			(start -0.120396 0.3048)
			(end -0.120396 0.2794)
			(stroke
				(width 0.1)
				(type default)
			)
			(layer "B.Fab")
		)
		(fp_line
			(start 0.12065 0.3048)
			(end 0.67945 0.3048)
			(stroke
				(width 0.1)
				(type default)
			)
			(layer "B.Fab")
		)
		(fp_line
			(start 0.67945 0.3048)
			(end 0.67945 -0.305054)
			(stroke
				(width 0.1)
				(type default)
			)
			(layer "B.Fab")
		)
		(fp_line
			(start -0.120396 0.2794)
			(end 0.12065 0.2794)
			(stroke
				(width 0.1)
				(type default)
			)
			(layer "B.Fab")
		)
		(fp_line
			(start 0.12065 0.2794)
			(end 0.12065 0.3048)
			(stroke
				(width 0.1)
				(type default)
			)
			(layer "B.Fab")
		)
		(fp_line
			(start -0.12065 -0.2794)
			(end -0.12065 -0.3048)
			(stroke
				(width 0.1)
				(type default)
			)
			(layer "B.Fab")
		)
		(fp_line
			(start 0.12065 -0.2794)
			(end -0.12065 -0.2794)
			(stroke
				(width 0.1)
				(type default)
			)
			(layer "B.Fab")
		)
		(fp_line
			(start -0.67945 -0.3048)
			(end -0.67945 0.3048)
			(stroke
				(width 0.1)
				(type default)
			)
			(layer "B.Fab")
		)
		(fp_line
			(start -0.12065 -0.3048)
			(end -0.67945 -0.3048)
			(stroke
				(width 0.1)
				(type default)
			)
			(layer "B.Fab")
		)
		(fp_line
			(start 0.12065 -0.305054)
			(end 0.12065 -0.2794)
			(stroke
				(width 0.1)
				(type default)
			)
			(layer "B.Fab")
		)
		(fp_line
			(start 0.67945 -0.305054)
			(end 0.12065 -0.305054)
			(stroke
				(width 0.1)
				(type default)
			)
			(layer "B.Fab")
		)
		(pad "1" smd circle
			(at 0.40005 0 90)
			(size 0 0)
			(layers "B.Cu" "B.Mask" "B.Paste")
			(net "PVCCIN_CPU1_VOS2")
		)
		(pad "2" smd circle
			(at -0.40005 0 90)
			(size 0 0)
			(layers "B.Cu" "B.Mask" "B.Paste")
			(net "PVCCIN_CPU1")
		)
	)
	(footprint ""
		(layer "B.Cu")
		(at 367.898934 -259.531866 90)
		(property "Reference" "C522"
			(at 0 0 90)
			(layer "B.SilkS")
			(hide yes)
			(effects
				(font
					(size 1.27 1.27)
				)
				(justify mirror)
			)
		)
		(property "Value" ""
			(at 0 0 90)
			(layer "B.Fab")
			(effects
				(font
					(size 1.27 1.27)
				)
				(justify mirror)
			)
		)
		(duplicate_pad_numbers_are_jumpers no)
		(fp_line
			(start 1.524 -0.762)
			(end -1.524 -0.762)
			(stroke
				(width 0.1524)
				(type default)
			)
			(layer "B.SilkS")
		)
		(fp_line
			(start -1.524 -0.762)
			(end -1.524 0.762)
			(stroke
				(width 0.1524)
				(type default)
			)
			(layer "B.SilkS")
		)
		(fp_line
			(start 1.524 0.762)
			(end 1.524 -0.762)
			(stroke
				(width 0.1524)
				(type default)
			)
			(layer "B.SilkS")
		)
		(fp_line
			(start -1.524 0.762)
			(end 1.524 0.762)
			(stroke
				(width 0.1524)
				(type default)
			)
			(layer "B.SilkS")
		)
		(fp_line
			(start 1.1049 -0.724916)
			(end 1.1049 0.724916)
			(stroke
				(width 0.1)
				(type default)
			)
			(layer "B.Fab")
		)
		(fp_line
			(start -1.1049 -0.724916)
			(end 1.1049 -0.724916)
			(stroke
				(width 0.1)
				(type default)
			)
			(layer "B.Fab")
		)
		(fp_line
			(start 1.1049 0.724916)
			(end -1.1049 0.724916)
			(stroke
				(width 0.1)
				(type default)
			)
			(layer "B.Fab")
		)
		(fp_line
			(start -1.1049 0.724916)
			(end -1.1049 -0.724916)
			(stroke
				(width 0.1)
				(type default)
			)
			(layer "B.Fab")
		)
		(pad "1" smd rect
			(at 0.889 0 90)
			(size 1.016 1.27)
			(layers "B.Cu" "B.Mask" "B.Paste")
			(net "PVCCINFAON_CPU0")
		)
		(pad "2" smd rect
			(at -0.889 0 90)
			(size 1.016 1.27)
			(layers "B.Cu" "B.Mask" "B.Paste")
			(net "GND")
		)
	)
	(footprint ""
		(layer "B.Cu")
		(at 180.923692 -408.254708 90)
		(property "Reference" "R1714"
			(at 0 0 90)
			(layer "B.SilkS")
			(hide yes)
			(effects
				(font
					(size 1.27 1.27)
				)
				(justify mirror)
			)
		)
		(property "Value" ""
			(at 0 0 90)
			(layer "B.Fab")
			(effects
				(font
					(size 1.27 1.27)
				)
				(justify mirror)
			)
		)
		(duplicate_pad_numbers_are_jumpers no)
		(fp_line
			(start 0.7874 -0.4064)
			(end -0.7874 -0.4064)
			(stroke
				(width 0.1524)
				(type default)
			)
			(layer "B.SilkS")
		)
		(fp_line
			(start -0.7874 -0.4064)
			(end -0.7874 0.4064)
			(stroke
				(width 0.1524)
				(type default)
			)
			(layer "B.SilkS")
		)
		(fp_line
			(start 0.7874 0.4064)
			(end 0.7874 -0.4064)
			(stroke
				(width 0.1524)
				(type default)
			)
			(layer "B.SilkS")
		)
		(fp_line
			(start -0.7874 0.4064)
			(end 0.7874 0.4064)
			(stroke
				(width 0.1524)
				(type default)
			)
			(layer "B.SilkS")
		)
		(fp_line
			(start 0.67945 -0.305054)
			(end 0.12065 -0.305054)
			(stroke
				(width 0.1)
				(type default)
			)
			(layer "B.Fab")
		)
		(fp_line
			(start 0.12065 -0.305054)
			(end 0.12065 -0.2794)
			(stroke
				(width 0.1)
				(type default)
			)
			(layer "B.Fab")
		)
		(fp_line
			(start -0.12065 -0.3048)
			(end -0.67945 -0.3048)
			(stroke
				(width 0.1)
				(type default)
			)
			(layer "B.Fab")
		)
		(fp_line
			(start -0.67945 -0.3048)
			(end -0.67945 0.3048)
			(stroke
				(width 0.1)
				(type default)
			)
			(layer "B.Fab")
		)
		(fp_line
			(start 0.12065 -0.2794)
			(end -0.12065 -0.2794)
			(stroke
				(width 0.1)
				(type default)
			)
			(layer "B.Fab")
		)
		(fp_line
			(start -0.12065 -0.2794)
			(end -0.12065 -0.3048)
			(stroke
				(width 0.1)
				(type default)
			)
			(layer "B.Fab")
		)
		(fp_line
			(start 0.12065 0.2794)
			(end 0.12065 0.3048)
			(stroke
				(width 0.1)
				(type default)
			)
			(layer "B.Fab")
		)
		(fp_line
			(start -0.120396 0.2794)
			(end 0.12065 0.2794)
			(stroke
				(width 0.1)
				(type default)
			)
			(layer "B.Fab")
		)
		(fp_line
			(start 0.67945 0.3048)
			(end 0.67945 -0.305054)
			(stroke
				(width 0.1)
				(type default)
			)
			(layer "B.Fab")
		)
		(fp_line
			(start 0.12065 0.3048)
			(end 0.67945 0.3048)
			(stroke
				(width 0.1)
				(type default)
			)
			(layer "B.Fab")
		)
		(fp_line
			(start -0.120396 0.3048)
			(end -0.120396 0.2794)
			(stroke
				(width 0.1)
				(type default)
			)
			(layer "B.Fab")
		)
		(fp_line
			(start -0.67945 0.3048)
			(end -0.120396 0.3048)
			(stroke
				(width 0.1)
				(type default)
			)
			(layer "B.Fab")
		)
		(pad "1" smd circle
			(at 0.40005 0 270)
			(size 0 0)
			(layers "B.Cu" "B.Mask" "B.Paste")
			(net "SMB_SML1_PMBUS_HSC_SDA")
		)
		(pad "2" smd circle
			(at -0.40005 0 270)
			(size 0 0)
			(layers "B.Cu" "B.Mask" "B.Paste")
			(net "SMB_SML1_PMBUS_HSC_R_SDA")
		)
	)
	(footprint ""
		(layer "B.Cu")
		(at 329.134978 -28.852622 90)
		(property "Reference" "R610"
			(at 0 0 90)
			(layer "B.SilkS")
			(hide yes)
			(effects
				(font
					(size 1.27 1.27)
				)
				(justify mirror)
			)
		)
		(property "Value" ""
			(at 0 0 90)
			(layer "B.Fab")
			(effects
				(font
					(size 1.27 1.27)
				)
				(justify mirror)
			)
		)
		(duplicate_pad_numbers_are_jumpers no)
		(fp_line
			(start 0.7874 -0.4064)
			(end -0.7874 -0.4064)
			(stroke
				(width 0.1524)
				(type default)
			)
			(layer "B.SilkS")
		)
		(fp_line
			(start -0.7874 -0.4064)
			(end -0.7874 0.4064)
			(stroke
				(width 0.1524)
				(type default)
			)
			(layer "B.SilkS")
		)
		(fp_line
			(start 0.7874 0.4064)
			(end 0.7874 -0.4064)
			(stroke
				(width 0.1524)
				(type default)
			)
			(layer "B.SilkS")
		)
		(fp_line
			(start -0.7874 0.4064)
			(end 0.7874 0.4064)
			(stroke
				(width 0.1524)
				(type default)
			)
			(layer "B.SilkS")
		)
		(fp_line
			(start 0.67945 -0.305054)
			(end 0.12065 -0.305054)
			(stroke
				(width 0.1)
				(type default)
			)
			(layer "B.Fab")
		)
		(fp_line
			(start 0.12065 -0.305054)
			(end 0.12065 -0.2794)
			(stroke
				(width 0.1)
				(type default)
			)
			(layer "B.Fab")
		)
		(fp_line
			(start -0.12065 -0.3048)
			(end -0.67945 -0.3048)
			(stroke
				(width 0.1)
				(type default)
			)
			(layer "B.Fab")
		)
		(fp_line
			(start -0.67945 -0.3048)
			(end -0.67945 0.3048)
			(stroke
				(width 0.1)
				(type default)
			)
			(layer "B.Fab")
		)
		(fp_line
			(start 0.12065 -0.2794)
			(end -0.12065 -0.2794)
			(stroke
				(width 0.1)
				(type default)
			)
			(layer "B.Fab")
		)
		(fp_line
			(start -0.12065 -0.2794)
			(end -0.12065 -0.3048)
			(stroke
				(width 0.1)
				(type default)
			)
			(layer "B.Fab")
		)
		(fp_line
			(start 0.12065 0.2794)
			(end 0.12065 0.3048)
			(stroke
				(width 0.1)
				(type default)
			)
			(layer "B.Fab")
		)
		(fp_line
			(start -0.120396 0.2794)
			(end 0.12065 0.2794)
			(stroke
				(width 0.1)
				(type default)
			)
			(layer "B.Fab")
		)
		(fp_line
			(start 0.67945 0.3048)
			(end 0.67945 -0.305054)
			(stroke
				(width 0.1)
				(type default)
			)
			(layer "B.Fab")
		)
		(fp_line
			(start 0.12065 0.3048)
			(end 0.67945 0.3048)
			(stroke
				(width 0.1)
				(type default)
			)
			(layer "B.Fab")
		)
		(fp_line
			(start -0.120396 0.3048)
			(end -0.120396 0.2794)
			(stroke
				(width 0.1)
				(type default)
			)
			(layer "B.Fab")
		)
		(fp_line
			(start -0.67945 0.3048)
			(end -0.120396 0.3048)
			(stroke
				(width 0.1)
				(type default)
			)
			(layer "B.Fab")
		)
		(pad "1" smd circle
			(at 0.40005 0 270)
			(size 0 0)
			(layers "B.Cu" "B.Mask" "B.Paste")
			(net "FM_ESPI_CS_SWIZZLE")
		)
		(pad "2" smd circle
			(at -0.40005 0 270)
			(size 0 0)
			(layers "B.Cu" "B.Mask" "B.Paste")
			(net "GND")
		)
	)
	(footprint ""
		(layer "B.Cu")
		(at 25.072848 -318.633856)
		(property "Reference" "R46"
			(at 0 0 0)
			(layer "B.SilkS")
			(hide yes)
			(effects
				(font
					(size 1.27 1.27)
				)
				(justify mirror)
			)
		)
		(property "Value" ""
			(at 0 0 0)
			(layer "B.Fab")
			(effects
				(font
					(size 1.27 1.27)
				)
				(justify mirror)
			)
		)
		(duplicate_pad_numbers_are_jumpers no)
		(fp_line
			(start -0.7874 -0.4064)
			(end -0.7874 0.4064)
			(stroke
				(width 0.1524)
				(type default)
			)
			(layer "B.SilkS")
		)
		(fp_line
			(start -0.7874 0.4064)
			(end 0.7874 0.4064)
			(stroke
				(width 0.1524)
				(type default)
			)
			(layer "B.SilkS")
		)
		(fp_line
			(start 0.7874 -0.4064)
			(end -0.7874 -0.4064)
			(stroke
				(width 0.1524)
				(type default)
			)
			(layer "B.SilkS")
		)
		(fp_line
			(start 0.7874 0.4064)
			(end 0.7874 -0.4064)
			(stroke
				(width 0.1524)
				(type default)
			)
			(layer "B.SilkS")
		)
		(fp_line
			(start -0.67945 -0.3048)
			(end -0.67945 0.3048)
			(stroke
				(width 0.1)
				(type default)
			)
			(layer "B.Fab")
		)
		(fp_line
			(start -0.67945 0.3048)
			(end -0.120396 0.3048)
			(stroke
				(width 0.1)
				(type default)
			)
			(layer "B.Fab")
		)
		(fp_line
			(start -0.12065 -0.3048)
			(end -0.67945 -0.3048)
			(stroke
				(width 0.1)
				(type default)
			)
			(layer "B.Fab")
		)
		(fp_line
			(start -0.12065 -0.2794)
			(end -0.12065 -0.3048)
			(stroke
				(width 0.1)
				(type default)
			)
			(layer "B.Fab")
		)
		(fp_line
			(start -0.120396 0.2794)
			(end 0.12065 0.2794)
			(stroke
				(width 0.1)
				(type default)
			)
			(layer "B.Fab")
		)
		(fp_line
			(start -0.120396 0.3048)
			(end -0.120396 0.2794)
			(stroke
				(width 0.1)
				(type default)
			)
			(layer "B.Fab")
		)
		(fp_line
			(start 0.12065 -0.305054)
			(end 0.12065 -0.2794)
			(stroke
				(width 0.1)
				(type default)
			)
			(layer "B.Fab")
		)
		(fp_line
			(start 0.12065 -0.2794)
			(end -0.12065 -0.2794)
			(stroke
				(width 0.1)
				(type default)
			)
			(layer "B.Fab")
		)
		(fp_line
			(start 0.12065 0.2794)
			(end 0.12065 0.3048)
			(stroke
				(width 0.1)
				(type default)
			)
			(layer "B.Fab")
		)
		(fp_line
			(start 0.12065 0.3048)
			(end 0.67945 0.3048)
			(stroke
				(width 0.1)
				(type default)
			)
			(layer "B.Fab")
		)
		(fp_line
			(start 0.67945 -0.305054)
			(end 0.12065 -0.305054)
			(stroke
				(width 0.1)
				(type default)
			)
			(layer "B.Fab")
		)
		(fp_line
			(start 0.67945 0.3048)
			(end 0.67945 -0.305054)
			(stroke
				(width 0.1)
				(type default)
			)
			(layer "B.Fab")
		)
		(pad "1" smd circle
			(at 0.40005 0 180)
			(size 0 0)
			(layers "B.Cu" "B.Mask" "B.Paste")
			(net "PD_CHC_CPU1_DIMM1_SAA")
		)
		(pad "2" smd circle
			(at -0.40005 0 180)
			(size 0 0)
			(layers "B.Cu" "B.Mask" "B.Paste")
			(net "GND")
		)
	)
	(footprint ""
		(layer "B.Cu")
		(at 353.658678 -241.13871 90)
		(property "Reference" "C527"
			(at 0 0 90)
			(layer "B.SilkS")
			(hide yes)
			(effects
				(font
					(size 1.27 1.27)
				)
				(justify mirror)
			)
		)
		(property "Value" ""
			(at 0 0 90)
			(layer "B.Fab")
			(effects
				(font
					(size 1.27 1.27)
				)
				(justify mirror)
			)
		)
		(duplicate_pad_numbers_are_jumpers no)
		(fp_line
			(start 1.524 -0.762)
			(end -1.524 -0.762)
			(stroke
				(width 0.1524)
				(type default)
			)
			(layer "B.SilkS")
		)
		(fp_line
			(start -1.524 -0.762)
			(end -1.524 0.762)
			(stroke
				(width 0.1524)
				(type default)
			)
			(layer "B.SilkS")
		)
		(fp_line
			(start 1.524 0.762)
			(end 1.524 -0.762)
			(stroke
				(width 0.1524)
				(type default)
			)
			(layer "B.SilkS")
		)
		(fp_line
			(start -1.524 0.762)
			(end 1.524 0.762)
			(stroke
				(width 0.1524)
				(type default)
			)
			(layer "B.SilkS")
		)
		(fp_line
			(start 1.1049 -0.724916)
			(end 1.1049 0.724916)
			(stroke
				(width 0.1)
				(type default)
			)
			(layer "B.Fab")
		)
		(fp_line
			(start -1.1049 -0.724916)
			(end 1.1049 -0.724916)
			(stroke
				(width 0.1)
				(type default)
			)
			(layer "B.Fab")
		)
		(fp_line
			(start 1.1049 0.724916)
			(end -1.1049 0.724916)
			(stroke
				(width 0.1)
				(type default)
			)
			(layer "B.Fab")
		)
		(fp_line
			(start -1.1049 0.724916)
			(end -1.1049 -0.724916)
			(stroke
				(width 0.1)
				(type default)
			)
			(layer "B.Fab")
		)
		(pad "1" smd rect
			(at 0.889 0 90)
			(size 1.016 1.27)
			(layers "B.Cu" "B.Mask" "B.Paste")
			(net "PVCCIN_CPU0")
		)
		(pad "2" smd rect
			(at -0.889 0 90)
			(size 1.016 1.27)
			(layers "B.Cu" "B.Mask" "B.Paste")
			(net "GND")
		)
	)
	(footprint ""
		(layer "B.Cu")
		(at 450.70649 -3.871468 -90)
		(property "Reference" "R1505"
			(at 0 0 90)
			(layer "B.SilkS")
			(hide yes)
			(effects
				(font
					(size 1.27 1.27)
				)
				(justify mirror)
			)
		)
		(property "Value" ""
			(at 0 0 90)
			(layer "B.Fab")
			(effects
				(font
					(size 1.27 1.27)
				)
				(justify mirror)
			)
		)
		(duplicate_pad_numbers_are_jumpers no)
		(fp_line
			(start -0.7874 0.4064)
			(end 0.7874 0.4064)
			(stroke
				(width 0.1524)
				(type default)
			)
			(layer "B.SilkS")
		)
		(fp_line
			(start 0.7874 0.4064)
			(end 0.7874 -0.4064)
			(stroke
				(width 0.1524)
				(type default)
			)
			(layer "B.SilkS")
		)
		(fp_line
			(start -0.7874 -0.4064)
			(end -0.7874 0.4064)
			(stroke
				(width 0.1524)
				(type default)
			)
			(layer "B.SilkS")
		)
		(fp_line
			(start 0.7874 -0.4064)
			(end -0.7874 -0.4064)
			(stroke
				(width 0.1524)
				(type default)
			)
			(layer "B.SilkS")
		)
		(fp_line
			(start -0.67945 0.3048)
			(end -0.120396 0.3048)
			(stroke
				(width 0.1)
				(type default)
			)
			(layer "B.Fab")
		)
		(fp_line
			(start -0.120396 0.3048)
			(end -0.120396 0.2794)
			(stroke
				(width 0.1)
				(type default)
			)
			(layer "B.Fab")
		)
		(fp_line
			(start 0.12065 0.3048)
			(end 0.67945 0.3048)
			(stroke
				(width 0.1)
				(type default)
			)
			(layer "B.Fab")
		)
		(fp_line
			(start 0.67945 0.3048)
			(end 0.67945 -0.305054)
			(stroke
				(width 0.1)
				(type default)
			)
			(layer "B.Fab")
		)
		(fp_line
			(start -0.120396 0.2794)
			(end 0.12065 0.2794)
			(stroke
				(width 0.1)
				(type default)
			)
			(layer "B.Fab")
		)
		(fp_line
			(start 0.12065 0.2794)
			(end 0.12065 0.3048)
			(stroke
				(width 0.1)
				(type default)
			)
			(layer "B.Fab")
		)
		(fp_line
			(start -0.12065 -0.2794)
			(end -0.12065 -0.3048)
			(stroke
				(width 0.1)
				(type default)
			)
			(layer "B.Fab")
		)
		(fp_line
			(start 0.12065 -0.2794)
			(end -0.12065 -0.2794)
			(stroke
				(width 0.1)
				(type default)
			)
			(layer "B.Fab")
		)
		(fp_line
			(start -0.67945 -0.3048)
			(end -0.67945 0.3048)
			(stroke
				(width 0.1)
				(type default)
			)
			(layer "B.Fab")
		)
		(fp_line
			(start -0.12065 -0.3048)
			(end -0.67945 -0.3048)
			(stroke
				(width 0.1)
				(type default)
			)
			(layer "B.Fab")
		)
		(fp_line
			(start 0.12065 -0.305054)
			(end 0.12065 -0.2794)
			(stroke
				(width 0.1)
				(type default)
			)
			(layer "B.Fab")
		)
		(fp_line
			(start 0.67945 -0.305054)
			(end 0.12065 -0.305054)
			(stroke
				(width 0.1)
				(type default)
			)
			(layer "B.Fab")
		)
		(pad "1" smd circle
			(at 0.40005 0 90)
			(size 0 0)
			(layers "B.Cu" "B.Mask" "B.Paste")
			(net "RST_OCP_V3_1_BUF_N")
		)
		(pad "2" smd circle
			(at -0.40005 0 90)
			(size 0 0)
			(layers "B.Cu" "B.Mask" "B.Paste")
			(net "RST_PERST3_OCP_SFF_N")
		)
	)
	(footprint ""
		(layer "B.Cu")
		(at 352.730308 -237.709202 -90)
		(property "Reference" "C1406"
			(at 0 0 90)
			(layer "B.SilkS")
			(hide yes)
			(effects
				(font
					(size 1.27 1.27)
				)
				(justify mirror)
			)
		)
		(property "Value" ""
			(at 0 0 90)
			(layer "B.Fab")
			(effects
				(font
					(size 1.27 1.27)
				)
				(justify mirror)
			)
		)
		(duplicate_pad_numbers_are_jumpers no)
		(fp_line
			(start -1.2954 0.5842)
			(end 1.2954 0.5842)
			(stroke
				(width 0.1524)
				(type default)
			)
			(layer "B.SilkS")
		)
		(fp_line
			(start 1.2954 0.5842)
			(end 1.2954 -0.5842)
			(stroke
				(width 0.1524)
				(type default)
			)
			(layer "B.SilkS")
		)
		(fp_line
			(start -1.2954 -0.5842)
			(end -1.2954 0.5842)
			(stroke
				(width 0.1524)
				(type default)
			)
			(layer "B.SilkS")
		)
		(fp_line
			(start 0 -0.5842)
			(end 0 0.5842)
			(stroke
				(width 0.1524)
				(type default)
			)
			(layer "B.SilkS")
		)
		(fp_line
			(start 1.2954 -0.5842)
			(end -1.2954 -0.5842)
			(stroke
				(width 0.1524)
				(type default)
			)
			(layer "B.SilkS")
		)
		(fp_line
			(start -0.8636 0.4572)
			(end 0.8636 0.4572)
			(stroke
				(width 0.1)
				(type default)
			)
			(layer "B.Fab")
		)
		(fp_line
			(start 0.8636 0.4572)
			(end 0.8636 0.4064)
			(stroke
				(width 0.1)
				(type default)
			)
			(layer "B.Fab")
		)
		(fp_line
			(start -1.1938 0.4064)
			(end -0.8636 0.4064)
			(stroke
				(width 0.1)
				(type default)
			)
			(layer "B.Fab")
		)
		(fp_line
			(start -0.8636 0.4064)
			(end -0.8636 0.4572)
			(stroke
				(width 0.1)
				(type default)
			)
			(layer "B.Fab")
		)
		(fp_line
			(start 0.8636 0.4064)
			(end 1.1938 0.4064)
			(stroke
				(width 0.1)
				(type default)
			)
			(layer "B.Fab")
		)
		(fp_line
			(start 1.1938 0.4064)
			(end 1.1938 -0.4064)
			(stroke
				(width 0.1)
				(type default)
			)
			(layer "B.Fab")
		)
		(fp_line
			(start -1.1938 -0.4064)
			(end -1.1938 0.4064)
			(stroke
				(width 0.1)
				(type default)
			)
			(layer "B.Fab")
		)
		(fp_line
			(start -0.8636 -0.4064)
			(end -1.1938 -0.4064)
			(stroke
				(width 0.1)
				(type default)
			)
			(layer "B.Fab")
		)
		(fp_line
			(start 0.8636 -0.4064)
			(end 0.8636 -0.4572)
			(stroke
				(width 0.1)
				(type default)
			)
			(layer "B.Fab")
		)
		(fp_line
			(start 1.1938 -0.4064)
			(end 0.8636 -0.4064)
			(stroke
				(width 0.1)
				(type default)
			)
			(layer "B.Fab")
		)
		(fp_line
			(start -0.8636 -0.4572)
			(end -0.8636 -0.4064)
			(stroke
				(width 0.1)
				(type default)
			)
			(layer "B.Fab")
		)
		(fp_line
			(start 0.8636 -0.4572)
			(end -0.8636 -0.4572)
			(stroke
				(width 0.1)
				(type default)
			)
			(layer "B.Fab")
		)
		(pad "1" smd rect
			(at 0.7366 0 180)
			(size 0.7112 0.8128)
			(layers "B.Cu" "B.Mask" "B.Paste")
			(net "PVNN_MAIN_CPU0")
		)
		(pad "2" smd rect
			(at -0.7366 0 180)
			(size 0.7112 0.8128)
			(layers "B.Cu" "B.Mask" "B.Paste")
			(net "GND")
		)
	)
	(footprint ""
		(layer "B.Cu")
		(at 158.82366 -15.563088 180)
		(property "Reference" "R601"
			(at 0 0 0)
			(layer "B.SilkS")
			(hide yes)
			(effects
				(font
					(size 1.27 1.27)
				)
				(justify mirror)
			)
		)
		(property "Value" ""
			(at 0 0 0)
			(layer "B.Fab")
			(effects
				(font
					(size 1.27 1.27)
				)
				(justify mirror)
			)
		)
		(duplicate_pad_numbers_are_jumpers no)
		(fp_line
			(start 0.7874 0.4064)
			(end 0.7874 -0.4064)
			(stroke
				(width 0.1524)
				(type default)
			)
			(layer "B.SilkS")
		)
		(fp_line
			(start 0.7874 -0.4064)
			(end -0.7874 -0.4064)
			(stroke
				(width 0.1524)
				(type default)
			)
			(layer "B.SilkS")
		)
		(fp_line
			(start -0.7874 0.4064)
			(end 0.7874 0.4064)
			(stroke
				(width 0.1524)
				(type default)
			)
			(layer "B.SilkS")
		)
		(fp_line
			(start -0.7874 -0.4064)
			(end -0.7874 0.4064)
			(stroke
				(width 0.1524)
				(type default)
			)
			(layer "B.SilkS")
		)
		(fp_line
			(start 0.67945 0.3048)
			(end 0.67945 -0.305054)
			(stroke
				(width 0.1)
				(type default)
			)
			(layer "B.Fab")
		)
		(fp_line
			(start 0.67945 -0.305054)
			(end 0.12065 -0.305054)
			(stroke
				(width 0.1)
				(type default)
			)
			(layer "B.Fab")
		)
		(fp_line
			(start 0.12065 0.3048)
			(end 0.67945 0.3048)
			(stroke
				(width 0.1)
				(type default)
			)
			(layer "B.Fab")
		)
		(fp_line
			(start 0.12065 0.2794)
			(end 0.12065 0.3048)
			(stroke
				(width 0.1)
				(type default)
			)
			(layer "B.Fab")
		)
		(fp_line
			(start 0.12065 -0.2794)
			(end -0.12065 -0.2794)
			(stroke
				(width 0.1)
				(type default)
			)
			(layer "B.Fab")
		)
		(fp_line
			(start 0.12065 -0.305054)
			(end 0.12065 -0.2794)
			(stroke
				(width 0.1)
				(type default)
			)
			(layer "B.Fab")
		)
		(fp_line
			(start -0.120396 0.3048)
			(end -0.120396 0.2794)
			(stroke
				(width 0.1)
				(type default)
			)
			(layer "B.Fab")
		)
		(fp_line
			(start -0.120396 0.2794)
			(end 0.12065 0.2794)
			(stroke
				(width 0.1)
				(type default)
			)
			(layer "B.Fab")
		)
		(fp_line
			(start -0.12065 -0.2794)
			(end -0.12065 -0.3048)
			(stroke
				(width 0.1)
				(type default)
			)
			(layer "B.Fab")
		)
		(fp_line
			(start -0.12065 -0.3048)
			(end -0.67945 -0.3048)
			(stroke
				(width 0.1)
				(type default)
			)
			(layer "B.Fab")
		)
		(fp_line
			(start -0.67945 0.3048)
			(end -0.120396 0.3048)
			(stroke
				(width 0.1)
				(type default)
			)
			(layer "B.Fab")
		)
		(fp_line
			(start -0.67945 -0.3048)
			(end -0.67945 0.3048)
			(stroke
				(width 0.1)
				(type default)
			)
			(layer "B.Fab")
		)
		(pad "1" smd circle
			(at 0.40005 0)
			(size 0 0)
			(layers "B.Cu" "B.Mask" "B.Paste")
			(net "SMB_FAN_3V3AUX_SDA")
		)
		(pad "2" smd circle
			(at -0.40005 0)
			(size 0 0)
			(layers "B.Cu" "B.Mask" "B.Paste")
			(net "P3V3_AUX")
		)
	)
	(footprint ""
		(layer "B.Cu")
		(at 118.158768 -210.194144)
		(property "Reference" "C486"
			(at 0 0 0)
			(layer "B.SilkS")
			(hide yes)
			(effects
				(font
					(size 1.27 1.27)
				)
				(justify mirror)
			)
		)
		(property "Value" ""
			(at 0 0 0)
			(layer "B.Fab")
			(effects
				(font
					(size 1.27 1.27)
				)
				(justify mirror)
			)
		)
		(duplicate_pad_numbers_are_jumpers no)
		(fp_line
			(start -1.524 -0.762)
			(end -1.524 0.762)
			(stroke
				(width 0.1524)
				(type default)
			)
			(layer "B.SilkS")
		)
		(fp_line
			(start -1.524 0.762)
			(end 1.524 0.762)
			(stroke
				(width 0.1524)
				(type default)
			)
			(layer "B.SilkS")
		)
		(fp_line
			(start 1.524 -0.762)
			(end -1.524 -0.762)
			(stroke
				(width 0.1524)
				(type default)
			)
			(layer "B.SilkS")
		)
		(fp_line
			(start 1.524 0.762)
			(end 1.524 -0.762)
			(stroke
				(width 0.1524)
				(type default)
			)
			(layer "B.SilkS")
		)
		(fp_line
			(start -1.1049 -0.724916)
			(end 1.1049 -0.724916)
			(stroke
				(width 0.1)
				(type default)
			)
			(layer "B.Fab")
		)
		(fp_line
			(start -1.1049 0.724916)
			(end -1.1049 -0.724916)
			(stroke
				(width 0.1)
				(type default)
			)
			(layer "B.Fab")
		)
		(fp_line
			(start 1.1049 -0.724916)
			(end 1.1049 0.724916)
			(stroke
				(width 0.1)
				(type default)
			)
			(layer "B.Fab")
		)
		(fp_line
			(start 1.1049 0.724916)
			(end -1.1049 0.724916)
			(stroke
				(width 0.1)
				(type default)
			)
			(layer "B.Fab")
		)
		(pad "1" smd rect
			(at 0.889 0)
			(size 1.016 1.27)
			(layers "B.Cu" "B.Mask" "B.Paste")
			(net "PVCCINFAON_CPU1")
		)
		(pad "2" smd rect
			(at -0.889 0)
			(size 1.016 1.27)
			(layers "B.Cu" "B.Mask" "B.Paste")
			(net "GND")
		)
	)
	(footprint ""
		(layer "B.Cu")
		(at 245.818406 -98.092006 180)
		(property "Reference" "R912"
			(at 0 0 0)
			(layer "B.SilkS")
			(hide yes)
			(effects
				(font
					(size 1.27 1.27)
				)
				(justify mirror)
			)
		)
		(property "Value" ""
			(at 0 0 0)
			(layer "B.Fab")
			(effects
				(font
					(size 1.27 1.27)
				)
				(justify mirror)
			)
		)
		(duplicate_pad_numbers_are_jumpers no)
		(fp_line
			(start 0.7874 0.4064)
			(end 0.7874 -0.4064)
			(stroke
				(width 0.1524)
				(type default)
			)
			(layer "B.SilkS")
		)
		(fp_line
			(start 0.7874 -0.4064)
			(end -0.7874 -0.4064)
			(stroke
				(width 0.1524)
				(type default)
			)
			(layer "B.SilkS")
		)
		(fp_line
			(start -0.7874 0.4064)
			(end 0.7874 0.4064)
			(stroke
				(width 0.1524)
				(type default)
			)
			(layer "B.SilkS")
		)
		(fp_line
			(start -0.7874 -0.4064)
			(end -0.7874 0.4064)
			(stroke
				(width 0.1524)
				(type default)
			)
			(layer "B.SilkS")
		)
		(fp_line
			(start 0.67945 0.3048)
			(end 0.67945 -0.305054)
			(stroke
				(width 0.1)
				(type default)
			)
			(layer "B.Fab")
		)
		(fp_line
			(start 0.67945 -0.305054)
			(end 0.12065 -0.305054)
			(stroke
				(width 0.1)
				(type default)
			)
			(layer "B.Fab")
		)
		(fp_line
			(start 0.12065 0.3048)
			(end 0.67945 0.3048)
			(stroke
				(width 0.1)
				(type default)
			)
			(layer "B.Fab")
		)
		(fp_line
			(start 0.12065 0.2794)
			(end 0.12065 0.3048)
			(stroke
				(width 0.1)
				(type default)
			)
			(layer "B.Fab")
		)
		(fp_line
			(start 0.12065 -0.2794)
			(end -0.12065 -0.2794)
			(stroke
				(width 0.1)
				(type default)
			)
			(layer "B.Fab")
		)
		(fp_line
			(start 0.12065 -0.305054)
			(end 0.12065 -0.2794)
			(stroke
				(width 0.1)
				(type default)
			)
			(layer "B.Fab")
		)
		(fp_line
			(start -0.120396 0.3048)
			(end -0.120396 0.2794)
			(stroke
				(width 0.1)
				(type default)
			)
			(layer "B.Fab")
		)
		(fp_line
			(start -0.120396 0.2794)
			(end 0.12065 0.2794)
			(stroke
				(width 0.1)
				(type default)
			)
			(layer "B.Fab")
		)
		(fp_line
			(start -0.12065 -0.2794)
			(end -0.12065 -0.3048)
			(stroke
				(width 0.1)
				(type default)
			)
			(layer "B.Fab")
		)
		(fp_line
			(start -0.12065 -0.3048)
			(end -0.67945 -0.3048)
			(stroke
				(width 0.1)
				(type default)
			)
			(layer "B.Fab")
		)
		(fp_line
			(start -0.67945 0.3048)
			(end -0.120396 0.3048)
			(stroke
				(width 0.1)
				(type default)
			)
			(layer "B.Fab")
		)
		(fp_line
			(start -0.67945 -0.3048)
			(end -0.67945 0.3048)
			(stroke
				(width 0.1)
				(type default)
			)
			(layer "B.Fab")
		)
		(pad "1" smd circle
			(at 0.40005 0)
			(size 0 0)
			(layers "B.Cu" "B.Mask" "B.Paste")
			(net "P3V3_AUX")
		)
		(pad "2" smd circle
			(at -0.40005 0)
			(size 0 0)
			(layers "B.Cu" "B.Mask" "B.Paste")
			(net "CLK_CK440_SMB_ADDR0")
		)
	)
	(footprint ""
		(layer "B.Cu")
		(at 36.968938 -128.4097)
		(property "Reference" "R2569"
			(at 0 0 0)
			(layer "B.SilkS")
			(hide yes)
			(effects
				(font
					(size 1.27 1.27)
				)
				(justify mirror)
			)
		)
		(property "Value" ""
			(at 0 0 0)
			(layer "B.Fab")
			(effects
				(font
					(size 1.27 1.27)
				)
				(justify mirror)
			)
		)
		(duplicate_pad_numbers_are_jumpers no)
		(fp_line
			(start -0.7874 -0.4064)
			(end -0.7874 0.4064)
			(stroke
				(width 0.1524)
				(type default)
			)
			(layer "B.SilkS")
		)
		(fp_line
			(start -0.7874 0.4064)
			(end 0.7874 0.4064)
			(stroke
				(width 0.1524)
				(type default)
			)
			(layer "B.SilkS")
		)
		(fp_line
			(start 0.7874 -0.4064)
			(end -0.7874 -0.4064)
			(stroke
				(width 0.1524)
				(type default)
			)
			(layer "B.SilkS")
		)
		(fp_line
			(start 0.7874 0.4064)
			(end 0.7874 -0.4064)
			(stroke
				(width 0.1524)
				(type default)
			)
			(layer "B.SilkS")
		)
		(fp_line
			(start -0.67945 -0.3048)
			(end -0.67945 0.3048)
			(stroke
				(width 0.1)
				(type default)
			)
			(layer "B.Fab")
		)
		(fp_line
			(start -0.67945 0.3048)
			(end -0.120396 0.3048)
			(stroke
				(width 0.1)
				(type default)
			)
			(layer "B.Fab")
		)
		(fp_line
			(start -0.12065 -0.3048)
			(end -0.67945 -0.3048)
			(stroke
				(width 0.1)
				(type default)
			)
			(layer "B.Fab")
		)
		(fp_line
			(start -0.12065 -0.2794)
			(end -0.12065 -0.3048)
			(stroke
				(width 0.1)
				(type default)
			)
			(layer "B.Fab")
		)
		(fp_line
			(start -0.120396 0.2794)
			(end 0.12065 0.2794)
			(stroke
				(width 0.1)
				(type default)
			)
			(layer "B.Fab")
		)
		(fp_line
			(start -0.120396 0.3048)
			(end -0.120396 0.2794)
			(stroke
				(width 0.1)
				(type default)
			)
			(layer "B.Fab")
		)
		(fp_line
			(start 0.12065 -0.305054)
			(end 0.12065 -0.2794)
			(stroke
				(width 0.1)
				(type default)
			)
			(layer "B.Fab")
		)
		(fp_line
			(start 0.12065 -0.2794)
			(end -0.12065 -0.2794)
			(stroke
				(width 0.1)
				(type default)
			)
			(layer "B.Fab")
		)
		(fp_line
			(start 0.12065 0.2794)
			(end 0.12065 0.3048)
			(stroke
				(width 0.1)
				(type default)
			)
			(layer "B.Fab")
		)
		(fp_line
			(start 0.12065 0.3048)
			(end 0.67945 0.3048)
			(stroke
				(width 0.1)
				(type default)
			)
			(layer "B.Fab")
		)
		(fp_line
			(start 0.67945 -0.305054)
			(end 0.12065 -0.305054)
			(stroke
				(width 0.1)
				(type default)
			)
			(layer "B.Fab")
		)
		(fp_line
			(start 0.67945 0.3048)
			(end 0.67945 -0.305054)
			(stroke
				(width 0.1)
				(type default)
			)
			(layer "B.Fab")
		)
		(pad "1" smd circle
			(at 0.40005 0 180)
			(size 0 0)
			(layers "B.Cu" "B.Mask" "B.Paste")
			(net "P3V3_AUX")
		)
		(pad "2" smd circle
			(at -0.40005 0 180)
			(size 0 0)
			(layers "B.Cu" "B.Mask" "B.Paste")
			(net "PVCCINFAON_CPU1_PIN_ALERT")
		)
	)
	(footprint ""
		(layer "B.Cu")
		(at 380.808738 -337.161124 90)
		(property "Reference" "PC261_P0_5"
			(at 0 0 90)
			(layer "B.SilkS")
			(hide yes)
			(effects
				(font
					(size 1.27 1.27)
				)
				(justify mirror)
			)
		)
		(property "Value" ""
			(at 0 0 90)
			(layer "B.Fab")
			(effects
				(font
					(size 1.27 1.27)
				)
				(justify mirror)
			)
		)
		(duplicate_pad_numbers_are_jumpers no)
		(fp_line
			(start 1.524 -0.762)
			(end -1.524 -0.762)
			(stroke
				(width 0.1524)
				(type default)
			)
			(layer "B.SilkS")
		)
		(fp_line
			(start -1.524 -0.762)
			(end -1.524 0.762)
			(stroke
				(width 0.1524)
				(type default)
			)
			(layer "B.SilkS")
		)
		(fp_line
			(start 1.524 0.762)
			(end 1.524 -0.762)
			(stroke
				(width 0.1524)
				(type default)
			)
			(layer "B.SilkS")
		)
		(fp_line
			(start -1.524 0.762)
			(end 1.524 0.762)
			(stroke
				(width 0.1524)
				(type default)
			)
			(layer "B.SilkS")
		)
		(fp_line
			(start 1.1049 -0.724916)
			(end 1.1049 0.724916)
			(stroke
				(width 0.1)
				(type default)
			)
			(layer "B.Fab")
		)
		(fp_line
			(start -1.1049 -0.724916)
			(end 1.1049 -0.724916)
			(stroke
				(width 0.1)
				(type default)
			)
			(layer "B.Fab")
		)
		(fp_line
			(start 1.1049 0.724916)
			(end -1.1049 0.724916)
			(stroke
				(width 0.1)
				(type default)
			)
			(layer "B.Fab")
		)
		(fp_line
			(start -1.1049 0.724916)
			(end -1.1049 -0.724916)
			(stroke
				(width 0.1)
				(type default)
			)
			(layer "B.Fab")
		)
		(pad "1" smd rect
			(at 0.889 0 90)
			(size 1.016 1.27)
			(layers "B.Cu" "B.Mask" "B.Paste")
			(net "SW_P12V_PVCCIN_CPU0_FLT")
		)
		(pad "2" smd rect
			(at -0.889 0 90)
			(size 1.016 1.27)
			(layers "B.Cu" "B.Mask" "B.Paste")
			(net "GND")
		)
	)
	(footprint ""
		(layer "B.Cu")
		(at 125.773942 -366.723168 90)
		(property "Reference" "PC1270"
			(at 0 0 90)
			(layer "B.SilkS")
			(hide yes)
			(effects
				(font
					(size 1.27 1.27)
				)
				(justify mirror)
			)
		)
		(property "Value" ""
			(at 0 0 90)
			(layer "B.Fab")
			(effects
				(font
					(size 1.27 1.27)
				)
				(justify mirror)
			)
		)
		(duplicate_pad_numbers_are_jumpers no)
		(fp_line
			(start 1.524 -0.762)
			(end -1.524 -0.762)
			(stroke
				(width 0.1524)
				(type default)
			)
			(layer "B.SilkS")
		)
		(fp_line
			(start -1.524 -0.762)
			(end -1.524 0.762)
			(stroke
				(width 0.1524)
				(type default)
			)
			(layer "B.SilkS")
		)
		(fp_line
			(start 1.524 0.762)
			(end 1.524 -0.762)
			(stroke
				(width 0.1524)
				(type default)
			)
			(layer "B.SilkS")
		)
		(fp_line
			(start -1.524 0.762)
			(end 1.524 0.762)
			(stroke
				(width 0.1524)
				(type default)
			)
			(layer "B.SilkS")
		)
		(fp_line
			(start 1.1049 -0.724916)
			(end 1.1049 0.724916)
			(stroke
				(width 0.1)
				(type default)
			)
			(layer "B.Fab")
		)
		(fp_line
			(start -1.1049 -0.724916)
			(end 1.1049 -0.724916)
			(stroke
				(width 0.1)
				(type default)
			)
			(layer "B.Fab")
		)
		(fp_line
			(start 1.1049 0.724916)
			(end -1.1049 0.724916)
			(stroke
				(width 0.1)
				(type default)
			)
			(layer "B.Fab")
		)
		(fp_line
			(start -1.1049 0.724916)
			(end -1.1049 -0.724916)
			(stroke
				(width 0.1)
				(type default)
			)
			(layer "B.Fab")
		)
		(pad "1" smd rect
			(at 0.889 0 90)
			(size 1.016 1.27)
			(layers "B.Cu" "B.Mask" "B.Paste")
			(net "PVPP_HBM_CPU1")
		)
		(pad "2" smd rect
			(at -0.889 0 90)
			(size 1.016 1.27)
			(layers "B.Cu" "B.Mask" "B.Paste")
			(net "GND")
		)
	)
	(footprint ""
		(layer "B.Cu")
		(at 124.09678 -359.364534 -90)
		(property "Reference" "PR3336"
			(at 0 0 90)
			(layer "B.SilkS")
			(hide yes)
			(effects
				(font
					(size 1.27 1.27)
				)
				(justify mirror)
			)
		)
		(property "Value" ""
			(at 0 0 90)
			(layer "B.Fab")
			(effects
				(font
					(size 1.27 1.27)
				)
				(justify mirror)
			)
		)
		(duplicate_pad_numbers_are_jumpers no)
		(fp_line
			(start -0.7874 0.4064)
			(end 0.7874 0.4064)
			(stroke
				(width 0.1524)
				(type default)
			)
			(layer "B.SilkS")
		)
		(fp_line
			(start 0.7874 0.4064)
			(end 0.7874 -0.4064)
			(stroke
				(width 0.1524)
				(type default)
			)
			(layer "B.SilkS")
		)
		(fp_line
			(start -0.7874 -0.4064)
			(end -0.7874 0.4064)
			(stroke
				(width 0.1524)
				(type default)
			)
			(layer "B.SilkS")
		)
		(fp_line
			(start 0.7874 -0.4064)
			(end -0.7874 -0.4064)
			(stroke
				(width 0.1524)
				(type default)
			)
			(layer "B.SilkS")
		)
		(fp_line
			(start -0.67945 0.3048)
			(end -0.120396 0.3048)
			(stroke
				(width 0.1)
				(type default)
			)
			(layer "B.Fab")
		)
		(fp_line
			(start -0.120396 0.3048)
			(end -0.120396 0.2794)
			(stroke
				(width 0.1)
				(type default)
			)
			(layer "B.Fab")
		)
		(fp_line
			(start 0.12065 0.3048)
			(end 0.67945 0.3048)
			(stroke
				(width 0.1)
				(type default)
			)
			(layer "B.Fab")
		)
		(fp_line
			(start 0.67945 0.3048)
			(end 0.67945 -0.305054)
			(stroke
				(width 0.1)
				(type default)
			)
			(layer "B.Fab")
		)
		(fp_line
			(start -0.120396 0.2794)
			(end 0.12065 0.2794)
			(stroke
				(width 0.1)
				(type default)
			)
			(layer "B.Fab")
		)
		(fp_line
			(start 0.12065 0.2794)
			(end 0.12065 0.3048)
			(stroke
				(width 0.1)
				(type default)
			)
			(layer "B.Fab")
		)
		(fp_line
			(start -0.12065 -0.2794)
			(end -0.12065 -0.3048)
			(stroke
				(width 0.1)
				(type default)
			)
			(layer "B.Fab")
		)
		(fp_line
			(start 0.12065 -0.2794)
			(end -0.12065 -0.2794)
			(stroke
				(width 0.1)
				(type default)
			)
			(layer "B.Fab")
		)
		(fp_line
			(start -0.67945 -0.3048)
			(end -0.67945 0.3048)
			(stroke
				(width 0.1)
				(type default)
			)
			(layer "B.Fab")
		)
		(fp_line
			(start -0.12065 -0.3048)
			(end -0.67945 -0.3048)
			(stroke
				(width 0.1)
				(type default)
			)
			(layer "B.Fab")
		)
		(fp_line
			(start 0.12065 -0.305054)
			(end 0.12065 -0.2794)
			(stroke
				(width 0.1)
				(type default)
			)
			(layer "B.Fab")
		)
		(fp_line
			(start 0.67945 -0.305054)
			(end 0.12065 -0.305054)
			(stroke
				(width 0.1)
				(type default)
			)
			(layer "B.Fab")
		)
		(pad "1" smd circle
			(at 0.40005 0 90)
			(size 0 0)
			(layers "B.Cu" "B.Mask" "B.Paste")
			(net "PVPP_HBM_CPU1_MODE")
		)
		(pad "2" smd circle
			(at -0.40005 0 90)
			(size 0 0)
			(layers "B.Cu" "B.Mask" "B.Paste")
			(net "GND")
		)
	)
	(footprint ""
		(layer "B.Cu")
		(at 127.83566 -36.759388 90)
		(property "Reference" "R4285"
			(at 0 0 90)
			(layer "B.SilkS")
			(hide yes)
			(effects
				(font
					(size 1.27 1.27)
				)
				(justify mirror)
			)
		)
		(property "Value" ""
			(at 0 0 90)
			(layer "B.Fab")
			(effects
				(font
					(size 1.27 1.27)
				)
				(justify mirror)
			)
		)
		(duplicate_pad_numbers_are_jumpers no)
		(fp_line
			(start 0.7874 -0.4064)
			(end -0.7874 -0.4064)
			(stroke
				(width 0.1524)
				(type default)
			)
			(layer "B.SilkS")
		)
		(fp_line
			(start -0.7874 -0.4064)
			(end -0.7874 0.4064)
			(stroke
				(width 0.1524)
				(type default)
			)
			(layer "B.SilkS")
		)
		(fp_line
			(start 0.7874 0.4064)
			(end 0.7874 -0.4064)
			(stroke
				(width 0.1524)
				(type default)
			)
			(layer "B.SilkS")
		)
		(fp_line
			(start -0.7874 0.4064)
			(end 0.7874 0.4064)
			(stroke
				(width 0.1524)
				(type default)
			)
			(layer "B.SilkS")
		)
		(fp_line
			(start 0.67945 -0.305054)
			(end 0.12065 -0.305054)
			(stroke
				(width 0.1)
				(type default)
			)
			(layer "B.Fab")
		)
		(fp_line
			(start 0.12065 -0.305054)
			(end 0.12065 -0.2794)
			(stroke
				(width 0.1)
				(type default)
			)
			(layer "B.Fab")
		)
		(fp_line
			(start -0.12065 -0.3048)
			(end -0.67945 -0.3048)
			(stroke
				(width 0.1)
				(type default)
			)
			(layer "B.Fab")
		)
		(fp_line
			(start -0.67945 -0.3048)
			(end -0.67945 0.3048)
			(stroke
				(width 0.1)
				(type default)
			)
			(layer "B.Fab")
		)
		(fp_line
			(start 0.12065 -0.2794)
			(end -0.12065 -0.2794)
			(stroke
				(width 0.1)
				(type default)
			)
			(layer "B.Fab")
		)
		(fp_line
			(start -0.12065 -0.2794)
			(end -0.12065 -0.3048)
			(stroke
				(width 0.1)
				(type default)
			)
			(layer "B.Fab")
		)
		(fp_line
			(start 0.12065 0.2794)
			(end 0.12065 0.3048)
			(stroke
				(width 0.1)
				(type default)
			)
			(layer "B.Fab")
		)
		(fp_line
			(start -0.120396 0.2794)
			(end 0.12065 0.2794)
			(stroke
				(width 0.1)
				(type default)
			)
			(layer "B.Fab")
		)
		(fp_line
			(start 0.67945 0.3048)
			(end 0.67945 -0.305054)
			(stroke
				(width 0.1)
				(type default)
			)
			(layer "B.Fab")
		)
		(fp_line
			(start 0.12065 0.3048)
			(end 0.67945 0.3048)
			(stroke
				(width 0.1)
				(type default)
			)
			(layer "B.Fab")
		)
		(fp_line
			(start -0.120396 0.3048)
			(end -0.120396 0.2794)
			(stroke
				(width 0.1)
				(type default)
			)
			(layer "B.Fab")
		)
		(fp_line
			(start -0.67945 0.3048)
			(end -0.120396 0.3048)
			(stroke
				(width 0.1)
				(type default)
			)
			(layer "B.Fab")
		)
		(pad "1" smd circle
			(at 0.40005 0 270)
			(size 0 0)
			(layers "B.Cu" "B.Mask" "B.Paste")
			(net "FM_USB3_1_SWB")
		)
		(pad "2" smd circle
			(at -0.40005 0 270)
			(size 0 0)
			(layers "B.Cu" "B.Mask" "B.Paste")
			(net "GND")
		)
	)
	(footprint ""
		(layer "B.Cu")
		(at 71.385684 -190.744856 90)
		(property "Reference" "R56"
			(at 0 0 90)
			(layer "B.SilkS")
			(hide yes)
			(effects
				(font
					(size 1.27 1.27)
				)
				(justify mirror)
			)
		)
		(property "Value" ""
			(at 0 0 90)
			(layer "B.Fab")
			(effects
				(font
					(size 1.27 1.27)
				)
				(justify mirror)
			)
		)
		(duplicate_pad_numbers_are_jumpers no)
		(fp_line
			(start 0.7874 -0.4064)
			(end -0.7874 -0.4064)
			(stroke
				(width 0.1524)
				(type default)
			)
			(layer "B.SilkS")
		)
		(fp_line
			(start -0.7874 -0.4064)
			(end -0.7874 0.4064)
			(stroke
				(width 0.1524)
				(type default)
			)
			(layer "B.SilkS")
		)
		(fp_line
			(start 0.7874 0.4064)
			(end 0.7874 -0.4064)
			(stroke
				(width 0.1524)
				(type default)
			)
			(layer "B.SilkS")
		)
		(fp_line
			(start -0.7874 0.4064)
			(end 0.7874 0.4064)
			(stroke
				(width 0.1524)
				(type default)
			)
			(layer "B.SilkS")
		)
		(fp_line
			(start 0.67945 -0.305054)
			(end 0.12065 -0.305054)
			(stroke
				(width 0.1)
				(type default)
			)
			(layer "B.Fab")
		)
		(fp_line
			(start 0.12065 -0.305054)
			(end 0.12065 -0.2794)
			(stroke
				(width 0.1)
				(type default)
			)
			(layer "B.Fab")
		)
		(fp_line
			(start -0.12065 -0.3048)
			(end -0.67945 -0.3048)
			(stroke
				(width 0.1)
				(type default)
			)
			(layer "B.Fab")
		)
		(fp_line
			(start -0.67945 -0.3048)
			(end -0.67945 0.3048)
			(stroke
				(width 0.1)
				(type default)
			)
			(layer "B.Fab")
		)
		(fp_line
			(start 0.12065 -0.2794)
			(end -0.12065 -0.2794)
			(stroke
				(width 0.1)
				(type default)
			)
			(layer "B.Fab")
		)
		(fp_line
			(start -0.12065 -0.2794)
			(end -0.12065 -0.3048)
			(stroke
				(width 0.1)
				(type default)
			)
			(layer "B.Fab")
		)
		(fp_line
			(start 0.12065 0.2794)
			(end 0.12065 0.3048)
			(stroke
				(width 0.1)
				(type default)
			)
			(layer "B.Fab")
		)
		(fp_line
			(start -0.120396 0.2794)
			(end 0.12065 0.2794)
			(stroke
				(width 0.1)
				(type default)
			)
			(layer "B.Fab")
		)
		(fp_line
			(start 0.67945 0.3048)
			(end 0.67945 -0.305054)
			(stroke
				(width 0.1)
				(type default)
			)
			(layer "B.Fab")
		)
		(fp_line
			(start 0.12065 0.3048)
			(end 0.67945 0.3048)
			(stroke
				(width 0.1)
				(type default)
			)
			(layer "B.Fab")
		)
		(fp_line
			(start -0.120396 0.3048)
			(end -0.120396 0.2794)
			(stroke
				(width 0.1)
				(type default)
			)
			(layer "B.Fab")
		)
		(fp_line
			(start -0.67945 0.3048)
			(end -0.120396 0.3048)
			(stroke
				(width 0.1)
				(type default)
			)
			(layer "B.Fab")
		)
		(pad "1" smd circle
			(at 0.40005 0 270)
			(size 0 0)
			(layers "B.Cu" "B.Mask" "B.Paste")
			(net "SVID_CLK0_CPU1")
		)
		(pad "2" smd circle
			(at -0.40005 0 270)
			(size 0 0)
			(layers "B.Cu" "B.Mask" "B.Paste")
			(net "SVID_CLK0_CPU1_R")
		)
	)
	(footprint ""
		(layer "B.Cu")
		(at 330.11999 -346.808298 -90)
		(property "Reference" "PC239_P0_7"
			(at 0 0 90)
			(layer "B.SilkS")
			(hide yes)
			(effects
				(font
					(size 1.27 1.27)
				)
				(justify mirror)
			)
		)
		(property "Value" ""
			(at 0 0 90)
			(layer "B.Fab")
			(effects
				(font
					(size 1.27 1.27)
				)
				(justify mirror)
			)
		)
		(duplicate_pad_numbers_are_jumpers no)
		(fp_line
			(start -1.524 0.762)
			(end 1.524 0.762)
			(stroke
				(width 0.1524)
				(type default)
			)
			(layer "B.SilkS")
		)
		(fp_line
			(start 1.524 0.762)
			(end 1.524 -0.762)
			(stroke
				(width 0.1524)
				(type default)
			)
			(layer "B.SilkS")
		)
		(fp_line
			(start -1.524 -0.762)
			(end -1.524 0.762)
			(stroke
				(width 0.1524)
				(type default)
			)
			(layer "B.SilkS")
		)
		(fp_line
			(start 1.524 -0.762)
			(end -1.524 -0.762)
			(stroke
				(width 0.1524)
				(type default)
			)
			(layer "B.SilkS")
		)
		(fp_line
			(start -1.1049 0.724916)
			(end -1.1049 -0.724916)
			(stroke
				(width 0.1)
				(type default)
			)
			(layer "B.Fab")
		)
		(fp_line
			(start 1.1049 0.724916)
			(end -1.1049 0.724916)
			(stroke
				(width 0.1)
				(type default)
			)
			(layer "B.Fab")
		)
		(fp_line
			(start -1.1049 -0.724916)
			(end 1.1049 -0.724916)
			(stroke
				(width 0.1)
				(type default)
			)
			(layer "B.Fab")
		)
		(fp_line
			(start 1.1049 -0.724916)
			(end 1.1049 0.724916)
			(stroke
				(width 0.1)
				(type default)
			)
			(layer "B.Fab")
		)
		(pad "1" smd rect
			(at 0.889 0 270)
			(size 1.016 1.27)
			(layers "B.Cu" "B.Mask" "B.Paste")
			(net "SW_P12V_PVCCIN_CPU0_FLT")
		)
		(pad "2" smd rect
			(at -0.889 0 270)
			(size 1.016 1.27)
			(layers "B.Cu" "B.Mask" "B.Paste")
			(net "GND")
		)
	)
	(footprint ""
		(layer "B.Cu")
		(at 407.91257 -182.776368 180)
		(property "Reference" "PC205_P0_2"
			(at 0 0 0)
			(layer "B.SilkS")
			(hide yes)
			(effects
				(font
					(size 1.27 1.27)
				)
				(justify mirror)
			)
		)
		(property "Value" ""
			(at 0 0 0)
			(layer "B.Fab")
			(effects
				(font
					(size 1.27 1.27)
				)
				(justify mirror)
			)
		)
		(duplicate_pad_numbers_are_jumpers no)
		(fp_line
			(start 1.524 0.762)
			(end 1.524 -0.762)
			(stroke
				(width 0.1524)
				(type default)
			)
			(layer "B.SilkS")
		)
		(fp_line
			(start 1.524 -0.762)
			(end -1.524 -0.762)
			(stroke
				(width 0.1524)
				(type default)
			)
			(layer "B.SilkS")
		)
		(fp_line
			(start -1.524 0.762)
			(end 1.524 0.762)
			(stroke
				(width 0.1524)
				(type default)
			)
			(layer "B.SilkS")
		)
		(fp_line
			(start -1.524 -0.762)
			(end -1.524 0.762)
			(stroke
				(width 0.1524)
				(type default)
			)
			(layer "B.SilkS")
		)
		(fp_line
			(start 1.1049 0.724916)
			(end -1.1049 0.724916)
			(stroke
				(width 0.1)
				(type default)
			)
			(layer "B.Fab")
		)
		(fp_line
			(start 1.1049 -0.724916)
			(end 1.1049 0.724916)
			(stroke
				(width 0.1)
				(type default)
			)
			(layer "B.Fab")
		)
		(fp_line
			(start -1.1049 0.724916)
			(end -1.1049 -0.724916)
			(stroke
				(width 0.1)
				(type default)
			)
			(layer "B.Fab")
		)
		(fp_line
			(start -1.1049 -0.724916)
			(end 1.1049 -0.724916)
			(stroke
				(width 0.1)
				(type default)
			)
			(layer "B.Fab")
		)
		(pad "1" smd rect
			(at 0.889 0 180)
			(size 1.016 1.27)
			(layers "B.Cu" "B.Mask" "B.Paste")
			(net "PVCCINFAON_CPU0")
		)
		(pad "2" smd rect
			(at -0.889 0 180)
			(size 1.016 1.27)
			(layers "B.Cu" "B.Mask" "B.Paste")
			(net "GND")
		)
	)
	(footprint ""
		(layer "B.Cu")
		(at 365.816134 -237.709202 -90)
		(property "Reference" "C533"
			(at 0 0 90)
			(layer "B.SilkS")
			(hide yes)
			(effects
				(font
					(size 1.27 1.27)
				)
				(justify mirror)
			)
		)
		(property "Value" ""
			(at 0 0 90)
			(layer "B.Fab")
			(effects
				(font
					(size 1.27 1.27)
				)
				(justify mirror)
			)
		)
		(duplicate_pad_numbers_are_jumpers no)
		(fp_line
			(start -1.2954 0.5842)
			(end 1.2954 0.5842)
			(stroke
				(width 0.1524)
				(type default)
			)
			(layer "B.SilkS")
		)
		(fp_line
			(start 1.2954 0.5842)
			(end 1.2954 -0.5842)
			(stroke
				(width 0.1524)
				(type default)
			)
			(layer "B.SilkS")
		)
		(fp_line
			(start -1.2954 -0.5842)
			(end -1.2954 0.5842)
			(stroke
				(width 0.1524)
				(type default)
			)
			(layer "B.SilkS")
		)
		(fp_line
			(start 0 -0.5842)
			(end 0 0.5842)
			(stroke
				(width 0.1524)
				(type default)
			)
			(layer "B.SilkS")
		)
		(fp_line
			(start 1.2954 -0.5842)
			(end -1.2954 -0.5842)
			(stroke
				(width 0.1524)
				(type default)
			)
			(layer "B.SilkS")
		)
		(fp_line
			(start -0.8636 0.4572)
			(end 0.8636 0.4572)
			(stroke
				(width 0.1)
				(type default)
			)
			(layer "B.Fab")
		)
		(fp_line
			(start 0.8636 0.4572)
			(end 0.8636 0.4064)
			(stroke
				(width 0.1)
				(type default)
			)
			(layer "B.Fab")
		)
		(fp_line
			(start -1.1938 0.4064)
			(end -0.8636 0.4064)
			(stroke
				(width 0.1)
				(type default)
			)
			(layer "B.Fab")
		)
		(fp_line
			(start -0.8636 0.4064)
			(end -0.8636 0.4572)
			(stroke
				(width 0.1)
				(type default)
			)
			(layer "B.Fab")
		)
		(fp_line
			(start 0.8636 0.4064)
			(end 1.1938 0.4064)
			(stroke
				(width 0.1)
				(type default)
			)
			(layer "B.Fab")
		)
		(fp_line
			(start 1.1938 0.4064)
			(end 1.1938 -0.4064)
			(stroke
				(width 0.1)
				(type default)
			)
			(layer "B.Fab")
		)
		(fp_line
			(start -1.1938 -0.4064)
			(end -1.1938 0.4064)
			(stroke
				(width 0.1)
				(type default)
			)
			(layer "B.Fab")
		)
		(fp_line
			(start -0.8636 -0.4064)
			(end -1.1938 -0.4064)
			(stroke
				(width 0.1)
				(type default)
			)
			(layer "B.Fab")
		)
		(fp_line
			(start 0.8636 -0.4064)
			(end 0.8636 -0.4572)
			(stroke
				(width 0.1)
				(type default)
			)
			(layer "B.Fab")
		)
		(fp_line
			(start 1.1938 -0.4064)
			(end 0.8636 -0.4064)
			(stroke
				(width 0.1)
				(type default)
			)
			(layer "B.Fab")
		)
		(fp_line
			(start -0.8636 -0.4572)
			(end -0.8636 -0.4064)
			(stroke
				(width 0.1)
				(type default)
			)
			(layer "B.Fab")
		)
		(fp_line
			(start 0.8636 -0.4572)
			(end -0.8636 -0.4572)
			(stroke
				(width 0.1)
				(type default)
			)
			(layer "B.Fab")
		)
		(pad "1" smd rect
			(at 0.7366 0 180)
			(size 0.7112 0.8128)
			(layers "B.Cu" "B.Mask" "B.Paste")
			(net "PVCCINFAON_CPU0")
		)
		(pad "2" smd rect
			(at -0.7366 0 180)
			(size 0.7112 0.8128)
			(layers "B.Cu" "B.Mask" "B.Paste")
			(net "GND")
		)
	)
	(footprint ""
		(layer "B.Cu")
		(at 340.374986 -328.298048 -90)
		(property "Reference" "PC266_P0_6"
			(at 0 0 90)
			(layer "B.SilkS")
			(hide yes)
			(effects
				(font
					(size 1.27 1.27)
				)
				(justify mirror)
			)
		)
		(property "Value" ""
			(at 0 0 90)
			(layer "B.Fab")
			(effects
				(font
					(size 1.27 1.27)
				)
				(justify mirror)
			)
		)
		(duplicate_pad_numbers_are_jumpers no)
		(fp_line
			(start -1.524 0.762)
			(end 1.524 0.762)
			(stroke
				(width 0.1524)
				(type default)
			)
			(layer "B.SilkS")
		)
		(fp_line
			(start 1.524 0.762)
			(end 1.524 -0.762)
			(stroke
				(width 0.1524)
				(type default)
			)
			(layer "B.SilkS")
		)
		(fp_line
			(start -1.524 -0.762)
			(end -1.524 0.762)
			(stroke
				(width 0.1524)
				(type default)
			)
			(layer "B.SilkS")
		)
		(fp_line
			(start 1.524 -0.762)
			(end -1.524 -0.762)
			(stroke
				(width 0.1524)
				(type default)
			)
			(layer "B.SilkS")
		)
		(fp_line
			(start -1.1049 0.724916)
			(end -1.1049 -0.724916)
			(stroke
				(width 0.1)
				(type default)
			)
			(layer "B.Fab")
		)
		(fp_line
			(start 1.1049 0.724916)
			(end -1.1049 0.724916)
			(stroke
				(width 0.1)
				(type default)
			)
			(layer "B.Fab")
		)
		(fp_line
			(start -1.1049 -0.724916)
			(end 1.1049 -0.724916)
			(stroke
				(width 0.1)
				(type default)
			)
			(layer "B.Fab")
		)
		(fp_line
			(start 1.1049 -0.724916)
			(end 1.1049 0.724916)
			(stroke
				(width 0.1)
				(type default)
			)
			(layer "B.Fab")
		)
		(pad "1" smd rect
			(at 0.889 0 270)
			(size 1.016 1.27)
			(layers "B.Cu" "B.Mask" "B.Paste")
			(net "PVCCIN_CPU0")
		)
		(pad "2" smd rect
			(at -0.889 0 270)
			(size 1.016 1.27)
			(layers "B.Cu" "B.Mask" "B.Paste")
			(net "GND")
		)
	)
	(footprint ""
		(layer "B.Cu")
		(at 157.02788 -118.836948)
		(property "Reference" "R3175"
			(at 0 0 0)
			(layer "B.SilkS")
			(hide yes)
			(effects
				(font
					(size 1.27 1.27)
				)
				(justify mirror)
			)
		)
		(property "Value" ""
			(at 0 0 0)
			(layer "B.Fab")
			(effects
				(font
					(size 1.27 1.27)
				)
				(justify mirror)
			)
		)
		(duplicate_pad_numbers_are_jumpers no)
		(fp_line
			(start -0.7874 -0.4064)
			(end -0.7874 0.4064)
			(stroke
				(width 0.1524)
				(type default)
			)
			(layer "B.SilkS")
		)
		(fp_line
			(start -0.7874 0.4064)
			(end 0.7874 0.4064)
			(stroke
				(width 0.1524)
				(type default)
			)
			(layer "B.SilkS")
		)
		(fp_line
			(start 0.7874 -0.4064)
			(end -0.7874 -0.4064)
			(stroke
				(width 0.1524)
				(type default)
			)
			(layer "B.SilkS")
		)
		(fp_line
			(start 0.7874 0.4064)
			(end 0.7874 -0.4064)
			(stroke
				(width 0.1524)
				(type default)
			)
			(layer "B.SilkS")
		)
		(fp_line
			(start -0.67945 -0.3048)
			(end -0.67945 0.3048)
			(stroke
				(width 0.1)
				(type default)
			)
			(layer "B.Fab")
		)
		(fp_line
			(start -0.67945 0.3048)
			(end -0.120396 0.3048)
			(stroke
				(width 0.1)
				(type default)
			)
			(layer "B.Fab")
		)
		(fp_line
			(start -0.12065 -0.3048)
			(end -0.67945 -0.3048)
			(stroke
				(width 0.1)
				(type default)
			)
			(layer "B.Fab")
		)
		(fp_line
			(start -0.12065 -0.2794)
			(end -0.12065 -0.3048)
			(stroke
				(width 0.1)
				(type default)
			)
			(layer "B.Fab")
		)
		(fp_line
			(start -0.120396 0.2794)
			(end 0.12065 0.2794)
			(stroke
				(width 0.1)
				(type default)
			)
			(layer "B.Fab")
		)
		(fp_line
			(start -0.120396 0.3048)
			(end -0.120396 0.2794)
			(stroke
				(width 0.1)
				(type default)
			)
			(layer "B.Fab")
		)
		(fp_line
			(start 0.12065 -0.305054)
			(end 0.12065 -0.2794)
			(stroke
				(width 0.1)
				(type default)
			)
			(layer "B.Fab")
		)
		(fp_line
			(start 0.12065 -0.2794)
			(end -0.12065 -0.2794)
			(stroke
				(width 0.1)
				(type default)
			)
			(layer "B.Fab")
		)
		(fp_line
			(start 0.12065 0.2794)
			(end 0.12065 0.3048)
			(stroke
				(width 0.1)
				(type default)
			)
			(layer "B.Fab")
		)
		(fp_line
			(start 0.12065 0.3048)
			(end 0.67945 0.3048)
			(stroke
				(width 0.1)
				(type default)
			)
			(layer "B.Fab")
		)
		(fp_line
			(start 0.67945 -0.305054)
			(end 0.12065 -0.305054)
			(stroke
				(width 0.1)
				(type default)
			)
			(layer "B.Fab")
		)
		(fp_line
			(start 0.67945 0.3048)
			(end 0.67945 -0.305054)
			(stroke
				(width 0.1)
				(type default)
			)
			(layer "B.Fab")
		)
		(pad "1" smd circle
			(at 0.40005 0 180)
			(size 0 0)
			(layers "B.Cu" "B.Mask" "B.Paste")
			(net "SGPIO_OCP_V3_2_DATAOUT")
		)
		(pad "2" smd circle
			(at -0.40005 0 180)
			(size 0 0)
			(layers "B.Cu" "B.Mask" "B.Paste")
			(net "GND")
		)
	)
	(footprint ""
		(layer "B.Cu")
		(at 522.584426 -303.621948 -90)
		(property "Reference" "X11"
			(at 3.493008 2.66319 270)
			(unlocked yes)
			(layer "B.SilkS")
			(effects
				(font
					(size 0.7874 0.5842)
					(thickness 0.1524)
				)
				(justify left mirror)
			)
		)
		(property "Value" ""
			(at 0 0 90)
			(layer "B.Fab")
			(effects
				(font
					(size 1.27 1.27)
				)
				(justify mirror)
			)
		)
		(property "Device Type" "TP_TDR_4P_FTS_TH-TP_TDR_4P_DIPA"
			(at -1.30175 1.27 180)
			(unlocked yes)
			(layer "B.Fab")
			(hide yes)
			(effects
				(font
					(size 0.635 0.4064)
					(thickness 0.1524)
				)
				(justify mirror)
			)
		)
		(property "User Part Number" "N_A"
			(at -1.30175 1.27 180)
			(unlocked yes)
			(layer "Cmts.User")
			(hide yes)
			(effects
				(font
					(size 0.635 0.4064)
					(thickness 0.1524)
				)
				(justify mirror)
			)
		)
		(duplicate_pad_numbers_are_jumpers no)
		(fp_line
			(start -2.54 3.81)
			(end -2.54 3.6703)
			(stroke
				(width 0.1524)
				(type default)
			)
			(layer "B.SilkS")
		)
		(fp_line
			(start 0 3.81)
			(end -2.54 3.81)
			(stroke
				(width 0.1524)
				(type default)
			)
			(layer "B.SilkS")
		)
		(fp_line
			(start 0 3.175)
			(end 0 3.81)
			(stroke
				(width 0.1524)
				(type default)
			)
			(layer "B.SilkS")
		)
		(fp_line
			(start -2.54 1.4097)
			(end -2.54 1.1303)
			(stroke
				(width 0.1524)
				(type default)
			)
			(layer "B.SilkS")
		)
		(fp_line
			(start 0 0.635)
			(end 0 1.905)
			(stroke
				(width 0.1524)
				(type default)
			)
			(layer "B.SilkS")
		)
		(fp_line
			(start -2.54 -1.1303)
			(end -2.54 -1.27)
			(stroke
				(width 0.1524)
				(type default)
			)
			(layer "B.SilkS")
		)
		(fp_line
			(start -2.54 -1.27)
			(end 0 -1.27)
			(stroke
				(width 0.1524)
				(type default)
			)
			(layer "B.SilkS")
		)
		(fp_line
			(start 0 -1.27)
			(end 0 -0.635)
			(stroke
				(width 0.1524)
				(type default)
			)
			(layer "B.SilkS")
		)
		(fp_poly
			(pts
				(xy 2.812034 -0.762) (xy 2.812034 0.762) (xy 1.288034 0)
			)
			(stroke
				(width 0)
				(type default)
			)
			(fill yes)
			(layer "B.SilkS")
		)
		(fp_line
			(start -2.54 3.81)
			(end -2.54 -1.27)
			(stroke
				(width 0.1)
				(type default)
			)
			(layer "B.Fab")
		)
		(fp_line
			(start 0 3.81)
			(end -2.54 3.81)
			(stroke
				(width 0.1)
				(type default)
			)
			(layer "B.Fab")
		)
		(fp_line
			(start -2.54 -1.27)
			(end 0 -1.27)
			(stroke
				(width 0.1)
				(type default)
			)
			(layer "B.Fab")
		)
		(fp_line
			(start 0 -1.27)
			(end 0 3.81)
			(stroke
				(width 0.1)
				(type default)
			)
			(layer "B.Fab")
		)
		(fp_poly
			(pts
				(xy 0.761746 0) (xy 2.285746 -0.762) (xy 2.285746 0.762)
			)
			(stroke
				(width 0)
				(type default)
			)
			(fill yes)
			(layer "B.Fab")
		)
		(pad "1" thru_hole circle
			(at 0 0 90)
			(size 1.0033 1.0033)
			(drill 0.249936)
			(layers "*.Cu" "*.Mask")
			(remove_unused_layers no)
			(net "TDR_DIFF_85_IN4_DN")
			(clearance 0.10795)
			(padstack
				(mode front_inner_back)
				(layer "Inner"
					(shape circle)
					(size 0.8001 0.8001)
					(clearance 0.1524)
				)
				(layer "B.Cu"
					(shape circle)
					(size 1.0033 1.0033)
					(thermal_gap 0.10795)
					(clearance 0.10795)
				)
			)
		)
		(pad "2" thru_hole circle
			(at -2.54 0 90)
			(size 1.9939 1.9939)
			(drill 0.249936)
			(layers "*.Cu" "*.Mask")
			(remove_unused_layers no)
			(net "T1_GND")
			(clearance 0.10795)
			(padstack
				(mode front_inner_back)
				(layer "Inner"
					(shape circle)
					(size 0.8001 0.8001)
					(clearance 0.1524)
				)
				(layer "B.Cu"
					(shape circle)
					(size 1.9939 1.9939)
					(thermal_gap 0.10795)
					(clearance 0.10795)
				)
			)
		)
		(pad "3" thru_hole circle
			(at -2.54 2.54 90)
			(size 1.9939 1.9939)
			(drill 0.249936)
			(layers "*.Cu" "*.Mask")
			(remove_unused_layers no)
			(net "T1_GND")
			(clearance 0.10795)
			(padstack
				(mode front_inner_back)
				(layer "Inner"
					(shape circle)
					(size 0.8001 0.8001)
					(clearance 0.1524)
				)
				(layer "B.Cu"
					(shape circle)
					(size 1.9939 1.9939)
					(thermal_gap 0.10795)
					(clearance 0.10795)
				)
			)
		)
		(pad "4" thru_hole circle
			(at 0 2.54 90)
			(size 1.0033 1.0033)
			(drill 0.249936)
			(layers "*.Cu" "*.Mask")
			(remove_unused_layers no)
			(net "TDR_DIFF_85_IN4_DP")
			(clearance 0.10795)
			(padstack
				(mode front_inner_back)
				(layer "Inner"
					(shape circle)
					(size 0.8001 0.8001)
					(clearance 0.1524)
				)
				(layer "B.Cu"
					(shape circle)
					(size 1.0033 1.0033)
					(thermal_gap 0.10795)
					(clearance 0.10795)
				)
			)
		)
	)
	(footprint ""
		(layer "B.Cu")
		(at 363.135418 -296.054526 180)
		(property "Reference" "C394"
			(at 0 0 0)
			(layer "B.SilkS")
			(hide yes)
			(effects
				(font
					(size 1.27 1.27)
				)
				(justify mirror)
			)
		)
		(property "Value" ""
			(at 0 0 0)
			(layer "B.Fab")
			(effects
				(font
					(size 1.27 1.27)
				)
				(justify mirror)
			)
		)
		(duplicate_pad_numbers_are_jumpers no)
		(fp_line
			(start 1.524 0.762)
			(end 1.524 -0.762)
			(stroke
				(width 0.1524)
				(type default)
			)
			(layer "B.SilkS")
		)
		(fp_line
			(start 1.524 -0.762)
			(end -1.524 -0.762)
			(stroke
				(width 0.1524)
				(type default)
			)
			(layer "B.SilkS")
		)
		(fp_line
			(start -1.524 0.762)
			(end 1.524 0.762)
			(stroke
				(width 0.1524)
				(type default)
			)
			(layer "B.SilkS")
		)
		(fp_line
			(start -1.524 -0.762)
			(end -1.524 0.762)
			(stroke
				(width 0.1524)
				(type default)
			)
			(layer "B.SilkS")
		)
		(fp_line
			(start 1.1049 0.724916)
			(end -1.1049 0.724916)
			(stroke
				(width 0.1)
				(type default)
			)
			(layer "B.Fab")
		)
		(fp_line
			(start 1.1049 -0.724916)
			(end 1.1049 0.724916)
			(stroke
				(width 0.1)
				(type default)
			)
			(layer "B.Fab")
		)
		(fp_line
			(start -1.1049 0.724916)
			(end -1.1049 -0.724916)
			(stroke
				(width 0.1)
				(type default)
			)
			(layer "B.Fab")
		)
		(fp_line
			(start -1.1049 -0.724916)
			(end 1.1049 -0.724916)
			(stroke
				(width 0.1)
				(type default)
			)
			(layer "B.Fab")
		)
		(pad "1" smd rect
			(at 0.889 0 180)
			(size 1.016 1.27)
			(layers "B.Cu" "B.Mask" "B.Paste")
			(net "PVCCIN_CPU0")
		)
		(pad "2" smd rect
			(at -0.889 0 180)
			(size 1.016 1.27)
			(layers "B.Cu" "B.Mask" "B.Paste")
			(net "GND")
		)
	)
	(footprint ""
		(layer "B.Cu")
		(at 420.453312 -366.454944 180)
		(property "Reference" "PC1675"
			(at 0 0 0)
			(layer "B.SilkS")
			(hide yes)
			(effects
				(font
					(size 1.27 1.27)
				)
				(justify mirror)
			)
		)
		(property "Value" ""
			(at 0 0 0)
			(layer "B.Fab")
			(effects
				(font
					(size 1.27 1.27)
				)
				(justify mirror)
			)
		)
		(duplicate_pad_numbers_are_jumpers no)
		(fp_line
			(start 1.524 0.762)
			(end 1.524 -0.762)
			(stroke
				(width 0.1524)
				(type default)
			)
			(layer "B.SilkS")
		)
		(fp_line
			(start 1.524 -0.762)
			(end -1.524 -0.762)
			(stroke
				(width 0.1524)
				(type default)
			)
			(layer "B.SilkS")
		)
		(fp_line
			(start -1.524 0.762)
			(end 1.524 0.762)
			(stroke
				(width 0.1524)
				(type default)
			)
			(layer "B.SilkS")
		)
		(fp_line
			(start -1.524 -0.762)
			(end -1.524 0.762)
			(stroke
				(width 0.1524)
				(type default)
			)
			(layer "B.SilkS")
		)
		(fp_line
			(start 1.1049 0.724916)
			(end -1.1049 0.724916)
			(stroke
				(width 0.1)
				(type default)
			)
			(layer "B.Fab")
		)
		(fp_line
			(start 1.1049 -0.724916)
			(end 1.1049 0.724916)
			(stroke
				(width 0.1)
				(type default)
			)
			(layer "B.Fab")
		)
		(fp_line
			(start -1.1049 0.724916)
			(end -1.1049 -0.724916)
			(stroke
				(width 0.1)
				(type default)
			)
			(layer "B.Fab")
		)
		(fp_line
			(start -1.1049 -0.724916)
			(end 1.1049 -0.724916)
			(stroke
				(width 0.1)
				(type default)
			)
			(layer "B.Fab")
		)
		(pad "1" smd rect
			(at 0.889 0 180)
			(size 1.016 1.27)
			(layers "B.Cu" "B.Mask" "B.Paste")
			(net "SW_P12V_PVCCFA_EHV_FIVRA_CPU0_R")
		)
		(pad "2" smd rect
			(at -0.889 0 180)
			(size 1.016 1.27)
			(layers "B.Cu" "B.Mask" "B.Paste")
			(net "GND")
		)
	)
	(footprint ""
		(layer "B.Cu")
		(at 299.679868 -198.197978 -90)
		(property "Reference" "R4296"
			(at 0 0 90)
			(layer "B.SilkS")
			(hide yes)
			(effects
				(font
					(size 1.27 1.27)
				)
				(justify mirror)
			)
		)
		(property "Value" ""
			(at 0 0 90)
			(layer "B.Fab")
			(effects
				(font
					(size 1.27 1.27)
				)
				(justify mirror)
			)
		)
		(duplicate_pad_numbers_are_jumpers no)
		(fp_line
			(start -0.7874 0.4064)
			(end 0.7874 0.4064)
			(stroke
				(width 0.1524)
				(type default)
			)
			(layer "B.SilkS")
		)
		(fp_line
			(start 0.7874 0.4064)
			(end 0.7874 -0.4064)
			(stroke
				(width 0.1524)
				(type default)
			)
			(layer "B.SilkS")
		)
		(fp_line
			(start -0.7874 -0.4064)
			(end -0.7874 0.4064)
			(stroke
				(width 0.1524)
				(type default)
			)
			(layer "B.SilkS")
		)
		(fp_line
			(start 0.7874 -0.4064)
			(end -0.7874 -0.4064)
			(stroke
				(width 0.1524)
				(type default)
			)
			(layer "B.SilkS")
		)
		(fp_line
			(start -0.67945 0.3048)
			(end -0.120396 0.3048)
			(stroke
				(width 0.1)
				(type default)
			)
			(layer "B.Fab")
		)
		(fp_line
			(start -0.120396 0.3048)
			(end -0.120396 0.2794)
			(stroke
				(width 0.1)
				(type default)
			)
			(layer "B.Fab")
		)
		(fp_line
			(start 0.12065 0.3048)
			(end 0.67945 0.3048)
			(stroke
				(width 0.1)
				(type default)
			)
			(layer "B.Fab")
		)
		(fp_line
			(start 0.67945 0.3048)
			(end 0.67945 -0.305054)
			(stroke
				(width 0.1)
				(type default)
			)
			(layer "B.Fab")
		)
		(fp_line
			(start -0.120396 0.2794)
			(end 0.12065 0.2794)
			(stroke
				(width 0.1)
				(type default)
			)
			(layer "B.Fab")
		)
		(fp_line
			(start 0.12065 0.2794)
			(end 0.12065 0.3048)
			(stroke
				(width 0.1)
				(type default)
			)
			(layer "B.Fab")
		)
		(fp_line
			(start -0.12065 -0.2794)
			(end -0.12065 -0.3048)
			(stroke
				(width 0.1)
				(type default)
			)
			(layer "B.Fab")
		)
		(fp_line
			(start 0.12065 -0.2794)
			(end -0.12065 -0.2794)
			(stroke
				(width 0.1)
				(type default)
			)
			(layer "B.Fab")
		)
		(fp_line
			(start -0.67945 -0.3048)
			(end -0.67945 0.3048)
			(stroke
				(width 0.1)
				(type default)
			)
			(layer "B.Fab")
		)
		(fp_line
			(start -0.12065 -0.3048)
			(end -0.67945 -0.3048)
			(stroke
				(width 0.1)
				(type default)
			)
			(layer "B.Fab")
		)
		(fp_line
			(start 0.12065 -0.305054)
			(end 0.12065 -0.2794)
			(stroke
				(width 0.1)
				(type default)
			)
			(layer "B.Fab")
		)
		(fp_line
			(start 0.67945 -0.305054)
			(end 0.12065 -0.305054)
			(stroke
				(width 0.1)
				(type default)
			)
			(layer "B.Fab")
		)
		(pad "1" smd circle
			(at 0.40005 0 90)
			(size 0 0)
			(layers "B.Cu" "B.Mask" "B.Paste")
			(net "PWRGD_DRAMPWRGD_CPU0_CD_LVC1_R2")
		)
		(pad "2" smd circle
			(at -0.40005 0 90)
			(size 0 0)
			(layers "B.Cu" "B.Mask" "B.Paste")
			(net "PWRGD_DRAMPWRGD_CPU0_CD_LVC1_R")
		)
	)
	(footprint ""
		(layer "B.Cu")
		(at 67.320922 -183.303926 -90)
		(property "Reference" "R155"
			(at 0 0 90)
			(layer "B.SilkS")
			(hide yes)
			(effects
				(font
					(size 1.27 1.27)
				)
				(justify mirror)
			)
		)
		(property "Value" ""
			(at 0 0 90)
			(layer "B.Fab")
			(effects
				(font
					(size 1.27 1.27)
				)
				(justify mirror)
			)
		)
		(duplicate_pad_numbers_are_jumpers no)
		(fp_line
			(start -0.7874 0.4064)
			(end 0.7874 0.4064)
			(stroke
				(width 0.1524)
				(type default)
			)
			(layer "B.SilkS")
		)
		(fp_line
			(start 0.7874 0.4064)
			(end 0.7874 -0.4064)
			(stroke
				(width 0.1524)
				(type default)
			)
			(layer "B.SilkS")
		)
		(fp_line
			(start -0.7874 -0.4064)
			(end -0.7874 0.4064)
			(stroke
				(width 0.1524)
				(type default)
			)
			(layer "B.SilkS")
		)
		(fp_line
			(start 0.7874 -0.4064)
			(end -0.7874 -0.4064)
			(stroke
				(width 0.1524)
				(type default)
			)
			(layer "B.SilkS")
		)
		(fp_line
			(start -0.67945 0.3048)
			(end -0.120396 0.3048)
			(stroke
				(width 0.1)
				(type default)
			)
			(layer "B.Fab")
		)
		(fp_line
			(start -0.120396 0.3048)
			(end -0.120396 0.2794)
			(stroke
				(width 0.1)
				(type default)
			)
			(layer "B.Fab")
		)
		(fp_line
			(start 0.12065 0.3048)
			(end 0.67945 0.3048)
			(stroke
				(width 0.1)
				(type default)
			)
			(layer "B.Fab")
		)
		(fp_line
			(start 0.67945 0.3048)
			(end 0.67945 -0.305054)
			(stroke
				(width 0.1)
				(type default)
			)
			(layer "B.Fab")
		)
		(fp_line
			(start -0.120396 0.2794)
			(end 0.12065 0.2794)
			(stroke
				(width 0.1)
				(type default)
			)
			(layer "B.Fab")
		)
		(fp_line
			(start 0.12065 0.2794)
			(end 0.12065 0.3048)
			(stroke
				(width 0.1)
				(type default)
			)
			(layer "B.Fab")
		)
		(fp_line
			(start -0.12065 -0.2794)
			(end -0.12065 -0.3048)
			(stroke
				(width 0.1)
				(type default)
			)
			(layer "B.Fab")
		)
		(fp_line
			(start 0.12065 -0.2794)
			(end -0.12065 -0.2794)
			(stroke
				(width 0.1)
				(type default)
			)
			(layer "B.Fab")
		)
		(fp_line
			(start -0.67945 -0.3048)
			(end -0.67945 0.3048)
			(stroke
				(width 0.1)
				(type default)
			)
			(layer "B.Fab")
		)
		(fp_line
			(start -0.12065 -0.3048)
			(end -0.67945 -0.3048)
			(stroke
				(width 0.1)
				(type default)
			)
			(layer "B.Fab")
		)
		(fp_line
			(start 0.12065 -0.305054)
			(end 0.12065 -0.2794)
			(stroke
				(width 0.1)
				(type default)
			)
			(layer "B.Fab")
		)
		(fp_line
			(start 0.67945 -0.305054)
			(end 0.12065 -0.305054)
			(stroke
				(width 0.1)
				(type default)
			)
			(layer "B.Fab")
		)
		(pad "1" smd circle
			(at 0.40005 0 90)
			(size 0 0)
			(layers "B.Cu" "B.Mask" "B.Paste")
			(net "PWRGD_CPU1_BUF_R")
		)
		(pad "2" smd circle
			(at -0.40005 0 90)
			(size 0 0)
			(layers "B.Cu" "B.Mask" "B.Paste")
			(net "PVNN_TERM_CPU1")
		)
	)
	(footprint ""
		(layer "B.Cu")
		(at 45.872146 -321.554856 -90)
		(property "Reference" "C61"
			(at 0 0 90)
			(layer "B.SilkS")
			(hide yes)
			(effects
				(font
					(size 1.27 1.27)
				)
				(justify mirror)
			)
		)
		(property "Value" ""
			(at 0 0 90)
			(layer "B.Fab")
			(effects
				(font
					(size 1.27 1.27)
				)
				(justify mirror)
			)
		)
		(duplicate_pad_numbers_are_jumpers no)
		(fp_line
			(start -1.524 0.762)
			(end 1.524 0.762)
			(stroke
				(width 0.1524)
				(type default)
			)
			(layer "B.SilkS")
		)
		(fp_line
			(start 1.524 0.762)
			(end 1.524 -0.762)
			(stroke
				(width 0.1524)
				(type default)
			)
			(layer "B.SilkS")
		)
		(fp_line
			(start -1.524 -0.762)
			(end -1.524 0.762)
			(stroke
				(width 0.1524)
				(type default)
			)
			(layer "B.SilkS")
		)
		(fp_line
			(start 1.524 -0.762)
			(end -1.524 -0.762)
			(stroke
				(width 0.1524)
				(type default)
			)
			(layer "B.SilkS")
		)
		(fp_line
			(start -1.1049 0.724916)
			(end -1.1049 -0.724916)
			(stroke
				(width 0.1)
				(type default)
			)
			(layer "B.Fab")
		)
		(fp_line
			(start 1.1049 0.724916)
			(end -1.1049 0.724916)
			(stroke
				(width 0.1)
				(type default)
			)
			(layer "B.Fab")
		)
		(fp_line
			(start -1.1049 -0.724916)
			(end 1.1049 -0.724916)
			(stroke
				(width 0.1)
				(type default)
			)
			(layer "B.Fab")
		)
		(fp_line
			(start 1.1049 -0.724916)
			(end 1.1049 0.724916)
			(stroke
				(width 0.1)
				(type default)
			)
			(layer "B.Fab")
		)
		(pad "1" smd rect
			(at 0.889 0 270)
			(size 1.016 1.27)
			(layers "B.Cu" "B.Mask" "B.Paste")
			(net "P12V_S3_AUX_CPU1_NVDIMM")
		)
		(pad "2" smd rect
			(at -0.889 0 270)
			(size 1.016 1.27)
			(layers "B.Cu" "B.Mask" "B.Paste")
			(net "GND")
		)
	)
	(footprint ""
		(layer "B.Cu")
		(at 233.5022 -251.879608 -90)
		(property "Reference" "C1884"
			(at 0 0 90)
			(layer "B.SilkS")
			(hide yes)
			(effects
				(font
					(size 1.27 1.27)
				)
				(justify mirror)
			)
		)
		(property "Value" ""
			(at 0 0 90)
			(layer "B.Fab")
			(effects
				(font
					(size 1.27 1.27)
				)
				(justify mirror)
			)
		)
		(duplicate_pad_numbers_are_jumpers no)
		(fp_line
			(start -0.7874 0.4064)
			(end 0.7874 0.4064)
			(stroke
				(width 0.1524)
				(type default)
			)
			(layer "B.SilkS")
		)
		(fp_line
			(start 0.7874 0.4064)
			(end 0.7874 -0.4064)
			(stroke
				(width 0.1524)
				(type default)
			)
			(layer "B.SilkS")
		)
		(fp_line
			(start -0.7874 -0.4064)
			(end -0.7874 0.4064)
			(stroke
				(width 0.1524)
				(type default)
			)
			(layer "B.SilkS")
		)
		(fp_line
			(start 0.7874 -0.4064)
			(end -0.7874 -0.4064)
			(stroke
				(width 0.1524)
				(type default)
			)
			(layer "B.SilkS")
		)
		(fp_line
			(start -0.67945 0.3048)
			(end -0.120396 0.3048)
			(stroke
				(width 0.1)
				(type default)
			)
			(layer "B.Fab")
		)
		(fp_line
			(start -0.120396 0.3048)
			(end -0.120396 0.2794)
			(stroke
				(width 0.1)
				(type default)
			)
			(layer "B.Fab")
		)
		(fp_line
			(start 0.12065 0.3048)
			(end 0.67945 0.3048)
			(stroke
				(width 0.1)
				(type default)
			)
			(layer "B.Fab")
		)
		(fp_line
			(start 0.67945 0.3048)
			(end 0.67945 -0.305054)
			(stroke
				(width 0.1)
				(type default)
			)
			(layer "B.Fab")
		)
		(fp_line
			(start -0.120396 0.2794)
			(end 0.12065 0.2794)
			(stroke
				(width 0.1)
				(type default)
			)
			(layer "B.Fab")
		)
		(fp_line
			(start 0.12065 0.2794)
			(end 0.12065 0.3048)
			(stroke
				(width 0.1)
				(type default)
			)
			(layer "B.Fab")
		)
		(fp_line
			(start -0.12065 -0.2794)
			(end -0.12065 -0.3048)
			(stroke
				(width 0.1)
				(type default)
			)
			(layer "B.Fab")
		)
		(fp_line
			(start 0.12065 -0.2794)
			(end -0.12065 -0.2794)
			(stroke
				(width 0.1)
				(type default)
			)
			(layer "B.Fab")
		)
		(fp_line
			(start -0.67945 -0.3048)
			(end -0.67945 0.3048)
			(stroke
				(width 0.1)
				(type default)
			)
			(layer "B.Fab")
		)
		(fp_line
			(start -0.12065 -0.3048)
			(end -0.67945 -0.3048)
			(stroke
				(width 0.1)
				(type default)
			)
			(layer "B.Fab")
		)
		(fp_line
			(start 0.12065 -0.305054)
			(end 0.12065 -0.2794)
			(stroke
				(width 0.1)
				(type default)
			)
			(layer "B.Fab")
		)
		(fp_line
			(start 0.67945 -0.305054)
			(end 0.12065 -0.305054)
			(stroke
				(width 0.1)
				(type default)
			)
			(layer "B.Fab")
		)
		(pad "1" smd circle
			(at 0.40005 0 90)
			(size 0 0)
			(layers "B.Cu" "B.Mask" "B.Paste")
			(net "VFG_3P3A_CLK_GEN")
		)
		(pad "2" smd circle
			(at -0.40005 0 90)
			(size 0 0)
			(layers "B.Cu" "B.Mask" "B.Paste")
			(net "GND")
		)
	)
	(footprint ""
		(layer "B.Cu")
		(at 329.738228 -342.936576 90)
		(property "Reference" "PC241_P0_7"
			(at 0 0 90)
			(layer "B.SilkS")
			(hide yes)
			(effects
				(font
					(size 1.27 1.27)
				)
				(justify mirror)
			)
		)
		(property "Value" ""
			(at 0 0 90)
			(layer "B.Fab")
			(effects
				(font
					(size 1.27 1.27)
				)
				(justify mirror)
			)
		)
		(duplicate_pad_numbers_are_jumpers no)
		(fp_line
			(start 1.524 -0.762)
			(end -1.524 -0.762)
			(stroke
				(width 0.1524)
				(type default)
			)
			(layer "B.SilkS")
		)
		(fp_line
			(start -1.524 -0.762)
			(end -1.524 0.762)
			(stroke
				(width 0.1524)
				(type default)
			)
			(layer "B.SilkS")
		)
		(fp_line
			(start 1.524 0.762)
			(end 1.524 -0.762)
			(stroke
				(width 0.1524)
				(type default)
			)
			(layer "B.SilkS")
		)
		(fp_line
			(start -1.524 0.762)
			(end 1.524 0.762)
			(stroke
				(width 0.1524)
				(type default)
			)
			(layer "B.SilkS")
		)
		(fp_line
			(start 1.1049 -0.724916)
			(end 1.1049 0.724916)
			(stroke
				(width 0.1)
				(type default)
			)
			(layer "B.Fab")
		)
		(fp_line
			(start -1.1049 -0.724916)
			(end 1.1049 -0.724916)
			(stroke
				(width 0.1)
				(type default)
			)
			(layer "B.Fab")
		)
		(fp_line
			(start 1.1049 0.724916)
			(end -1.1049 0.724916)
			(stroke
				(width 0.1)
				(type default)
			)
			(layer "B.Fab")
		)
		(fp_line
			(start -1.1049 0.724916)
			(end -1.1049 -0.724916)
			(stroke
				(width 0.1)
				(type default)
			)
			(layer "B.Fab")
		)
		(pad "1" smd rect
			(at 0.889 0 90)
			(size 1.016 1.27)
			(layers "B.Cu" "B.Mask" "B.Paste")
			(net "SW_P12V_PVCCIN_CPU0_FLT")
		)
		(pad "2" smd rect
			(at -0.889 0 90)
			(size 1.016 1.27)
			(layers "B.Cu" "B.Mask" "B.Paste")
			(net "GND")
		)
	)
	(footprint ""
		(layer "B.Cu")
		(at 430.82718 -50.37582 180)
		(property "Reference" "R4678"
			(at 0 0 0)
			(layer "B.SilkS")
			(hide yes)
			(effects
				(font
					(size 1.27 1.27)
				)
				(justify mirror)
			)
		)
		(property "Value" ""
			(at 0 0 0)
			(layer "B.Fab")
			(effects
				(font
					(size 1.27 1.27)
				)
				(justify mirror)
			)
		)
		(duplicate_pad_numbers_are_jumpers no)
		(fp_line
			(start 0.7874 0.4064)
			(end 0.7874 -0.4064)
			(stroke
				(width 0.1524)
				(type default)
			)
			(layer "B.SilkS")
		)
		(fp_line
			(start 0.7874 -0.4064)
			(end -0.7874 -0.4064)
			(stroke
				(width 0.1524)
				(type default)
			)
			(layer "B.SilkS")
		)
		(fp_line
			(start -0.7874 0.4064)
			(end 0.7874 0.4064)
			(stroke
				(width 0.1524)
				(type default)
			)
			(layer "B.SilkS")
		)
		(fp_line
			(start -0.7874 -0.4064)
			(end -0.7874 0.4064)
			(stroke
				(width 0.1524)
				(type default)
			)
			(layer "B.SilkS")
		)
		(fp_line
			(start 0.67945 0.3048)
			(end 0.67945 -0.305054)
			(stroke
				(width 0.1)
				(type default)
			)
			(layer "B.Fab")
		)
		(fp_line
			(start 0.67945 -0.305054)
			(end 0.12065 -0.305054)
			(stroke
				(width 0.1)
				(type default)
			)
			(layer "B.Fab")
		)
		(fp_line
			(start 0.12065 0.3048)
			(end 0.67945 0.3048)
			(stroke
				(width 0.1)
				(type default)
			)
			(layer "B.Fab")
		)
		(fp_line
			(start 0.12065 0.2794)
			(end 0.12065 0.3048)
			(stroke
				(width 0.1)
				(type default)
			)
			(layer "B.Fab")
		)
		(fp_line
			(start 0.12065 -0.2794)
			(end -0.12065 -0.2794)
			(stroke
				(width 0.1)
				(type default)
			)
			(layer "B.Fab")
		)
		(fp_line
			(start 0.12065 -0.305054)
			(end 0.12065 -0.2794)
			(stroke
				(width 0.1)
				(type default)
			)
			(layer "B.Fab")
		)
		(fp_line
			(start -0.120396 0.3048)
			(end -0.120396 0.2794)
			(stroke
				(width 0.1)
				(type default)
			)
			(layer "B.Fab")
		)
		(fp_line
			(start -0.120396 0.2794)
			(end 0.12065 0.2794)
			(stroke
				(width 0.1)
				(type default)
			)
			(layer "B.Fab")
		)
		(fp_line
			(start -0.12065 -0.2794)
			(end -0.12065 -0.3048)
			(stroke
				(width 0.1)
				(type default)
			)
			(layer "B.Fab")
		)
		(fp_line
			(start -0.12065 -0.3048)
			(end -0.67945 -0.3048)
			(stroke
				(width 0.1)
				(type default)
			)
			(layer "B.Fab")
		)
		(fp_line
			(start -0.67945 0.3048)
			(end -0.120396 0.3048)
			(stroke
				(width 0.1)
				(type default)
			)
			(layer "B.Fab")
		)
		(fp_line
			(start -0.67945 -0.3048)
			(end -0.67945 0.3048)
			(stroke
				(width 0.1)
				(type default)
			)
			(layer "B.Fab")
		)
		(pad "1" smd circle
			(at 0.40005 0)
			(size 0 0)
			(layers "B.Cu" "B.Mask" "B.Paste")
			(net "PWRGD_P5V_ISO_R")
		)
		(pad "2" smd circle
			(at -0.40005 0)
			(size 0 0)
			(layers "B.Cu" "B.Mask" "B.Paste")
			(net "PWRGD_P5V_ISO")
		)
	)
	(footprint ""
		(layer "B.Cu")
		(at 72.655684 -183.303926 -90)
		(property "Reference" "R50"
			(at 0 0 90)
			(layer "B.SilkS")
			(hide yes)
			(effects
				(font
					(size 1.27 1.27)
				)
				(justify mirror)
			)
		)
		(property "Value" ""
			(at 0 0 90)
			(layer "B.Fab")
			(effects
				(font
					(size 1.27 1.27)
				)
				(justify mirror)
			)
		)
		(duplicate_pad_numbers_are_jumpers no)
		(fp_line
			(start -0.7874 0.4064)
			(end 0.7874 0.4064)
			(stroke
				(width 0.1524)
				(type default)
			)
			(layer "B.SilkS")
		)
		(fp_line
			(start 0.7874 0.4064)
			(end 0.7874 -0.4064)
			(stroke
				(width 0.1524)
				(type default)
			)
			(layer "B.SilkS")
		)
		(fp_line
			(start -0.7874 -0.4064)
			(end -0.7874 0.4064)
			(stroke
				(width 0.1524)
				(type default)
			)
			(layer "B.SilkS")
		)
		(fp_line
			(start 0.7874 -0.4064)
			(end -0.7874 -0.4064)
			(stroke
				(width 0.1524)
				(type default)
			)
			(layer "B.SilkS")
		)
		(fp_line
			(start -0.67945 0.3048)
			(end -0.120396 0.3048)
			(stroke
				(width 0.1)
				(type default)
			)
			(layer "B.Fab")
		)
		(fp_line
			(start -0.120396 0.3048)
			(end -0.120396 0.2794)
			(stroke
				(width 0.1)
				(type default)
			)
			(layer "B.Fab")
		)
		(fp_line
			(start 0.12065 0.3048)
			(end 0.67945 0.3048)
			(stroke
				(width 0.1)
				(type default)
			)
			(layer "B.Fab")
		)
		(fp_line
			(start 0.67945 0.3048)
			(end 0.67945 -0.305054)
			(stroke
				(width 0.1)
				(type default)
			)
			(layer "B.Fab")
		)
		(fp_line
			(start -0.120396 0.2794)
			(end 0.12065 0.2794)
			(stroke
				(width 0.1)
				(type default)
			)
			(layer "B.Fab")
		)
		(fp_line
			(start 0.12065 0.2794)
			(end 0.12065 0.3048)
			(stroke
				(width 0.1)
				(type default)
			)
			(layer "B.Fab")
		)
		(fp_line
			(start -0.12065 -0.2794)
			(end -0.12065 -0.3048)
			(stroke
				(width 0.1)
				(type default)
			)
			(layer "B.Fab")
		)
		(fp_line
			(start 0.12065 -0.2794)
			(end -0.12065 -0.2794)
			(stroke
				(width 0.1)
				(type default)
			)
			(layer "B.Fab")
		)
		(fp_line
			(start -0.67945 -0.3048)
			(end -0.67945 0.3048)
			(stroke
				(width 0.1)
				(type default)
			)
			(layer "B.Fab")
		)
		(fp_line
			(start -0.12065 -0.3048)
			(end -0.67945 -0.3048)
			(stroke
				(width 0.1)
				(type default)
			)
			(layer "B.Fab")
		)
		(fp_line
			(start 0.12065 -0.305054)
			(end 0.12065 -0.2794)
			(stroke
				(width 0.1)
				(type default)
			)
			(layer "B.Fab")
		)
		(fp_line
			(start 0.67945 -0.305054)
			(end 0.12065 -0.305054)
			(stroke
				(width 0.1)
				(type default)
			)
			(layer "B.Fab")
		)
		(pad "1" smd circle
			(at 0.40005 0 90)
			(size 0 0)
			(layers "B.Cu" "B.Mask" "B.Paste")
			(net "PVNN_TERM_CPU1")
		)
		(pad "2" smd circle
			(at -0.40005 0 90)
			(size 0 0)
			(layers "B.Cu" "B.Mask" "B.Paste")
			(net "DBP_CPU_MBP1_GTL_N")
		)
	)
	(footprint ""
		(layer "B.Cu")
		(at 307.069998 -192.60947 90)
		(property "Reference" "R15"
			(at 0 0 90)
			(layer "B.SilkS")
			(hide yes)
			(effects
				(font
					(size 1.27 1.27)
				)
				(justify mirror)
			)
		)
		(property "Value" ""
			(at 0 0 90)
			(layer "B.Fab")
			(effects
				(font
					(size 1.27 1.27)
				)
				(justify mirror)
			)
		)
		(duplicate_pad_numbers_are_jumpers no)
		(fp_line
			(start 0.7874 -0.4064)
			(end -0.7874 -0.4064)
			(stroke
				(width 0.1524)
				(type default)
			)
			(layer "B.SilkS")
		)
		(fp_line
			(start -0.7874 -0.4064)
			(end -0.7874 0.4064)
			(stroke
				(width 0.1524)
				(type default)
			)
			(layer "B.SilkS")
		)
		(fp_line
			(start 0.7874 0.4064)
			(end 0.7874 -0.4064)
			(stroke
				(width 0.1524)
				(type default)
			)
			(layer "B.SilkS")
		)
		(fp_line
			(start -0.7874 0.4064)
			(end 0.7874 0.4064)
			(stroke
				(width 0.1524)
				(type default)
			)
			(layer "B.SilkS")
		)
		(fp_line
			(start 0.67945 -0.305054)
			(end 0.12065 -0.305054)
			(stroke
				(width 0.1)
				(type default)
			)
			(layer "B.Fab")
		)
		(fp_line
			(start 0.12065 -0.305054)
			(end 0.12065 -0.2794)
			(stroke
				(width 0.1)
				(type default)
			)
			(layer "B.Fab")
		)
		(fp_line
			(start -0.12065 -0.3048)
			(end -0.67945 -0.3048)
			(stroke
				(width 0.1)
				(type default)
			)
			(layer "B.Fab")
		)
		(fp_line
			(start -0.67945 -0.3048)
			(end -0.67945 0.3048)
			(stroke
				(width 0.1)
				(type default)
			)
			(layer "B.Fab")
		)
		(fp_line
			(start 0.12065 -0.2794)
			(end -0.12065 -0.2794)
			(stroke
				(width 0.1)
				(type default)
			)
			(layer "B.Fab")
		)
		(fp_line
			(start -0.12065 -0.2794)
			(end -0.12065 -0.3048)
			(stroke
				(width 0.1)
				(type default)
			)
			(layer "B.Fab")
		)
		(fp_line
			(start 0.12065 0.2794)
			(end 0.12065 0.3048)
			(stroke
				(width 0.1)
				(type default)
			)
			(layer "B.Fab")
		)
		(fp_line
			(start -0.120396 0.2794)
			(end 0.12065 0.2794)
			(stroke
				(width 0.1)
				(type default)
			)
			(layer "B.Fab")
		)
		(fp_line
			(start 0.67945 0.3048)
			(end 0.67945 -0.305054)
			(stroke
				(width 0.1)
				(type default)
			)
			(layer "B.Fab")
		)
		(fp_line
			(start 0.12065 0.3048)
			(end 0.67945 0.3048)
			(stroke
				(width 0.1)
				(type default)
			)
			(layer "B.Fab")
		)
		(fp_line
			(start -0.120396 0.3048)
			(end -0.120396 0.2794)
			(stroke
				(width 0.1)
				(type default)
			)
			(layer "B.Fab")
		)
		(fp_line
			(start -0.67945 0.3048)
			(end -0.120396 0.3048)
			(stroke
				(width 0.1)
				(type default)
			)
			(layer "B.Fab")
		)
		(pad "1" smd circle
			(at 0.40005 0 270)
			(size 0 0)
			(layers "B.Cu" "B.Mask" "B.Paste")
			(net "SVID_DIO1_CPU0")
		)
		(pad "2" smd circle
			(at -0.40005 0 270)
			(size 0 0)
			(layers "B.Cu" "B.Mask" "B.Paste")
			(net "SVID_DIO1_CPU0_R")
		)
	)
	(footprint ""
		(layer "B.Cu")
		(at 349.344742 -212.049614 180)
		(property "Reference" "C519"
			(at 0 0 0)
			(layer "B.SilkS")
			(hide yes)
			(effects
				(font
					(size 1.27 1.27)
				)
				(justify mirror)
			)
		)
		(property "Value" ""
			(at 0 0 0)
			(layer "B.Fab")
			(effects
				(font
					(size 1.27 1.27)
				)
				(justify mirror)
			)
		)
		(duplicate_pad_numbers_are_jumpers no)
		(fp_line
			(start 1.2954 0.5842)
			(end 1.2954 -0.5842)
			(stroke
				(width 0.1524)
				(type default)
			)
			(layer "B.SilkS")
		)
		(fp_line
			(start 1.2954 -0.5842)
			(end -1.2954 -0.5842)
			(stroke
				(width 0.1524)
				(type default)
			)
			(layer "B.SilkS")
		)
		(fp_line
			(start 0 -0.5842)
			(end 0 0.5842)
			(stroke
				(width 0.1524)
				(type default)
			)
			(layer "B.SilkS")
		)
		(fp_line
			(start -1.2954 0.5842)
			(end 1.2954 0.5842)
			(stroke
				(width 0.1524)
				(type default)
			)
			(layer "B.SilkS")
		)
		(fp_line
			(start -1.2954 -0.5842)
			(end -1.2954 0.5842)
			(stroke
				(width 0.1524)
				(type default)
			)
			(layer "B.SilkS")
		)
		(fp_line
			(start 1.1938 0.4064)
			(end 1.1938 -0.4064)
			(stroke
				(width 0.1)
				(type default)
			)
			(layer "B.Fab")
		)
		(fp_line
			(start 1.1938 -0.4064)
			(end 0.8636 -0.4064)
			(stroke
				(width 0.1)
				(type default)
			)
			(layer "B.Fab")
		)
		(fp_line
			(start 0.8636 0.4572)
			(end 0.8636 0.4064)
			(stroke
				(width 0.1)
				(type default)
			)
			(layer "B.Fab")
		)
		(fp_line
			(start 0.8636 0.4064)
			(end 1.1938 0.4064)
			(stroke
				(width 0.1)
				(type default)
			)
			(layer "B.Fab")
		)
		(fp_line
			(start 0.8636 -0.4064)
			(end 0.8636 -0.4572)
			(stroke
				(width 0.1)
				(type default)
			)
			(layer "B.Fab")
		)
		(fp_line
			(start 0.8636 -0.4572)
			(end -0.8636 -0.4572)
			(stroke
				(width 0.1)
				(type default)
			)
			(layer "B.Fab")
		)
		(fp_line
			(start -0.8636 0.4572)
			(end 0.8636 0.4572)
			(stroke
				(width 0.1)
				(type default)
			)
			(layer "B.Fab")
		)
		(fp_line
			(start -0.8636 0.4064)
			(end -0.8636 0.4572)
			(stroke
				(width 0.1)
				(type default)
			)
			(layer "B.Fab")
		)
		(fp_line
			(start -0.8636 -0.4064)
			(end -1.1938 -0.4064)
			(stroke
				(width 0.1)
				(type default)
			)
			(layer "B.Fab")
		)
		(fp_line
			(start -0.8636 -0.4572)
			(end -0.8636 -0.4064)
			(stroke
				(width 0.1)
				(type default)
			)
			(layer "B.Fab")
		)
		(fp_line
			(start -1.1938 0.4064)
			(end -0.8636 0.4064)
			(stroke
				(width 0.1)
				(type default)
			)
			(layer "B.Fab")
		)
		(fp_line
			(start -1.1938 -0.4064)
			(end -1.1938 0.4064)
			(stroke
				(width 0.1)
				(type default)
			)
			(layer "B.Fab")
		)
		(pad "1" smd rect
			(at 0.7366 0 90)
			(size 0.7112 0.8128)
			(layers "B.Cu" "B.Mask" "B.Paste")
			(net "PVCCFA_EHV_CPU0")
		)
		(pad "2" smd rect
			(at -0.7366 0 90)
			(size 0.7112 0.8128)
			(layers "B.Cu" "B.Mask" "B.Paste")
			(net "GND")
		)
	)
	(footprint ""
		(layer "B.Cu")
		(at 352.430334 -326.867012 -90)
		(property "Reference" "PC326"
			(at 0 0 90)
			(layer "B.SilkS")
			(hide yes)
			(effects
				(font
					(size 1.27 1.27)
				)
				(justify mirror)
			)
		)
		(property "Value" ""
			(at 0 0 90)
			(layer "B.Fab")
			(effects
				(font
					(size 1.27 1.27)
				)
				(justify mirror)
			)
		)
		(duplicate_pad_numbers_are_jumpers no)
		(fp_line
			(start -4.533392 2.249932)
			(end 4.533392 2.249932)
			(stroke
				(width 0.1524)
				(type default)
			)
			(layer "B.SilkS")
		)
		(fp_line
			(start 4.533392 2.249932)
			(end 4.533392 -2.249932)
			(stroke
				(width 0.1524)
				(type default)
			)
			(layer "B.SilkS")
		)
		(fp_line
			(start -4.533392 -2.249932)
			(end -4.533392 2.249932)
			(stroke
				(width 0.1524)
				(type default)
			)
			(layer "B.SilkS")
		)
		(fp_line
			(start 4.533392 -2.249932)
			(end -4.533392 -2.249932)
			(stroke
				(width 0.1524)
				(type default)
			)
			(layer "B.SilkS")
		)
		(fp_rect
			(start 5.39242 2.326132)
			(end 4.533392 -2.326132)
			(stroke
				(width 0)
				(type default)
			)
			(fill yes)
			(layer "B.SilkS")
		)
		(fp_line
			(start -3.750056 2.249932)
			(end 3.750056 2.249932)
			(stroke
				(width 0.1)
				(type default)
			)
			(layer "B.Fab")
		)
		(fp_line
			(start 3.750056 2.249932)
			(end 3.750056 -2.249932)
			(stroke
				(width 0.1)
				(type default)
			)
			(layer "B.Fab")
		)
		(fp_line
			(start -3.750056 -2.249932)
			(end -3.750056 2.249932)
			(stroke
				(width 0.1)
				(type default)
			)
			(layer "B.Fab")
		)
		(fp_line
			(start 3.750056 -2.249932)
			(end -3.750056 -2.249932)
			(stroke
				(width 0.1)
				(type default)
			)
			(layer "B.Fab")
		)
		(fp_text user "-"
			(at -4.702556 1.251204 270)
			(unlocked yes)
			(layer "B.SilkS")
			(effects
				(font
					(size 1.905 1.4224)
					(thickness 0.1524)
				)
				(justify left mirror)
			)
		)
		(fp_text user "+"
			(at 6.322314 0.786384 180)
			(unlocked yes)
			(layer "B.SilkS")
			(effects
				(font
					(size 1.905 1.4224)
					(thickness 0.1524)
				)
				(justify left mirror)
			)
		)
		(fp_text user "+"
			(at 6.322314 0.786384 180)
			(unlocked yes)
			(layer "B.Fab")
			(effects
				(font
					(size 1.905 1.4224)
					(thickness 0.1524)
				)
				(justify left mirror)
			)
		)
		(fp_text user "-"
			(at -4.8514 -0.14605 270)
			(unlocked yes)
			(layer "B.Fab")
			(effects
				(font
					(size 1.905 1.4224)
					(thickness 0.1524)
				)
				(justify left mirror)
			)
		)
		(pad "1" smd rect
			(at 3.199892 0 90)
			(size 2.413 2.8194)
			(layers "B.Cu" "B.Mask" "B.Paste")
			(net "PVCCIN_CPU0")
		)
		(pad "2" smd rect
			(at -3.199892 0 90)
			(size 2.413 2.8194)
			(layers "B.Cu" "B.Mask" "B.Paste")
			(net "GND")
		)
	)
	(footprint ""
		(layer "B.Cu")
		(at 237.40618 -132.422392)
		(property "Reference" "R577"
			(at 0 0 0)
			(layer "B.SilkS")
			(hide yes)
			(effects
				(font
					(size 1.27 1.27)
				)
				(justify mirror)
			)
		)
		(property "Value" ""
			(at 0 0 0)
			(layer "B.Fab")
			(effects
				(font
					(size 1.27 1.27)
				)
				(justify mirror)
			)
		)
		(duplicate_pad_numbers_are_jumpers no)
		(fp_line
			(start -0.7874 -0.4064)
			(end -0.7874 0.4064)
			(stroke
				(width 0.1524)
				(type default)
			)
			(layer "B.SilkS")
		)
		(fp_line
			(start -0.7874 0.4064)
			(end 0.7874 0.4064)
			(stroke
				(width 0.1524)
				(type default)
			)
			(layer "B.SilkS")
		)
		(fp_line
			(start 0.7874 -0.4064)
			(end -0.7874 -0.4064)
			(stroke
				(width 0.1524)
				(type default)
			)
			(layer "B.SilkS")
		)
		(fp_line
			(start 0.7874 0.4064)
			(end 0.7874 -0.4064)
			(stroke
				(width 0.1524)
				(type default)
			)
			(layer "B.SilkS")
		)
		(fp_line
			(start -0.67945 -0.3048)
			(end -0.67945 0.3048)
			(stroke
				(width 0.1)
				(type default)
			)
			(layer "B.Fab")
		)
		(fp_line
			(start -0.67945 0.3048)
			(end -0.120396 0.3048)
			(stroke
				(width 0.1)
				(type default)
			)
			(layer "B.Fab")
		)
		(fp_line
			(start -0.12065 -0.3048)
			(end -0.67945 -0.3048)
			(stroke
				(width 0.1)
				(type default)
			)
			(layer "B.Fab")
		)
		(fp_line
			(start -0.12065 -0.2794)
			(end -0.12065 -0.3048)
			(stroke
				(width 0.1)
				(type default)
			)
			(layer "B.Fab")
		)
		(fp_line
			(start -0.120396 0.2794)
			(end 0.12065 0.2794)
			(stroke
				(width 0.1)
				(type default)
			)
			(layer "B.Fab")
		)
		(fp_line
			(start -0.120396 0.3048)
			(end -0.120396 0.2794)
			(stroke
				(width 0.1)
				(type default)
			)
			(layer "B.Fab")
		)
		(fp_line
			(start 0.12065 -0.305054)
			(end 0.12065 -0.2794)
			(stroke
				(width 0.1)
				(type default)
			)
			(layer "B.Fab")
		)
		(fp_line
			(start 0.12065 -0.2794)
			(end -0.12065 -0.2794)
			(stroke
				(width 0.1)
				(type default)
			)
			(layer "B.Fab")
		)
		(fp_line
			(start 0.12065 0.2794)
			(end 0.12065 0.3048)
			(stroke
				(width 0.1)
				(type default)
			)
			(layer "B.Fab")
		)
		(fp_line
			(start 0.12065 0.3048)
			(end 0.67945 0.3048)
			(stroke
				(width 0.1)
				(type default)
			)
			(layer "B.Fab")
		)
		(fp_line
			(start 0.67945 -0.305054)
			(end 0.12065 -0.305054)
			(stroke
				(width 0.1)
				(type default)
			)
			(layer "B.Fab")
		)
		(fp_line
			(start 0.67945 0.3048)
			(end 0.67945 -0.305054)
			(stroke
				(width 0.1)
				(type default)
			)
			(layer "B.Fab")
		)
		(pad "1" smd circle
			(at 0.40005 0 180)
			(size 0 0)
			(layers "B.Cu" "B.Mask" "B.Paste")
			(net "SMB_HOST_3V3AUX_SCL_R4")
		)
		(pad "2" smd circle
			(at -0.40005 0 180)
			(size 0 0)
			(layers "B.Cu" "B.Mask" "B.Paste")
			(net "SMB_HOST_3V3AUX_SCL_R")
		)
	)
	(footprint ""
		(layer "B.Cu")
		(at 351.841308 -248.498106 -90)
		(property "Reference" "C495"
			(at 0 0 90)
			(layer "B.SilkS")
			(hide yes)
			(effects
				(font
					(size 1.27 1.27)
				)
				(justify mirror)
			)
		)
		(property "Value" ""
			(at 0 0 90)
			(layer "B.Fab")
			(effects
				(font
					(size 1.27 1.27)
				)
				(justify mirror)
			)
		)
		(duplicate_pad_numbers_are_jumpers no)
		(fp_line
			(start -1.524 0.762)
			(end 1.524 0.762)
			(stroke
				(width 0.1524)
				(type default)
			)
			(layer "B.SilkS")
		)
		(fp_line
			(start 1.524 0.762)
			(end 1.524 -0.762)
			(stroke
				(width 0.1524)
				(type default)
			)
			(layer "B.SilkS")
		)
		(fp_line
			(start -1.524 -0.762)
			(end -1.524 0.762)
			(stroke
				(width 0.1524)
				(type default)
			)
			(layer "B.SilkS")
		)
		(fp_line
			(start 1.524 -0.762)
			(end -1.524 -0.762)
			(stroke
				(width 0.1524)
				(type default)
			)
			(layer "B.SilkS")
		)
		(fp_line
			(start -1.1049 0.724916)
			(end -1.1049 -0.724916)
			(stroke
				(width 0.1)
				(type default)
			)
			(layer "B.Fab")
		)
		(fp_line
			(start 1.1049 0.724916)
			(end -1.1049 0.724916)
			(stroke
				(width 0.1)
				(type default)
			)
			(layer "B.Fab")
		)
		(fp_line
			(start -1.1049 -0.724916)
			(end 1.1049 -0.724916)
			(stroke
				(width 0.1)
				(type default)
			)
			(layer "B.Fab")
		)
		(fp_line
			(start 1.1049 -0.724916)
			(end 1.1049 0.724916)
			(stroke
				(width 0.1)
				(type default)
			)
			(layer "B.Fab")
		)
		(pad "1" smd rect
			(at 0.889 0 270)
			(size 1.016 1.27)
			(layers "B.Cu" "B.Mask" "B.Paste")
			(net "PVCCD_HV_CPU0")
		)
		(pad "2" smd rect
			(at -0.889 0 270)
			(size 1.016 1.27)
			(layers "B.Cu" "B.Mask" "B.Paste")
			(net "GND")
		)
	)
	(footprint ""
		(layer "B.Cu")
		(at 378.80036 -341.218012 -90)
		(property "Reference" "PC263_P0_5"
			(at 0 0 90)
			(layer "B.SilkS")
			(hide yes)
			(effects
				(font
					(size 1.27 1.27)
				)
				(justify mirror)
			)
		)
		(property "Value" ""
			(at 0 0 90)
			(layer "B.Fab")
			(effects
				(font
					(size 1.27 1.27)
				)
				(justify mirror)
			)
		)
		(duplicate_pad_numbers_are_jumpers no)
		(fp_line
			(start -1.524 0.762)
			(end 1.524 0.762)
			(stroke
				(width 0.1524)
				(type default)
			)
			(layer "B.SilkS")
		)
		(fp_line
			(start 1.524 0.762)
			(end 1.524 -0.762)
			(stroke
				(width 0.1524)
				(type default)
			)
			(layer "B.SilkS")
		)
		(fp_line
			(start -1.524 -0.762)
			(end -1.524 0.762)
			(stroke
				(width 0.1524)
				(type default)
			)
			(layer "B.SilkS")
		)
		(fp_line
			(start 1.524 -0.762)
			(end -1.524 -0.762)
			(stroke
				(width 0.1524)
				(type default)
			)
			(layer "B.SilkS")
		)
		(fp_line
			(start -1.1049 0.724916)
			(end -1.1049 -0.724916)
			(stroke
				(width 0.1)
				(type default)
			)
			(layer "B.Fab")
		)
		(fp_line
			(start 1.1049 0.724916)
			(end -1.1049 0.724916)
			(stroke
				(width 0.1)
				(type default)
			)
			(layer "B.Fab")
		)
		(fp_line
			(start -1.1049 -0.724916)
			(end 1.1049 -0.724916)
			(stroke
				(width 0.1)
				(type default)
			)
			(layer "B.Fab")
		)
		(fp_line
			(start 1.1049 -0.724916)
			(end 1.1049 0.724916)
			(stroke
				(width 0.1)
				(type default)
			)
			(layer "B.Fab")
		)
		(pad "1" smd rect
			(at 0.889 0 270)
			(size 1.016 1.27)
			(layers "B.Cu" "B.Mask" "B.Paste")
			(net "SW_P12V_PVCCIN_CPU0_FLT")
		)
		(pad "2" smd rect
			(at -0.889 0 270)
			(size 1.016 1.27)
			(layers "B.Cu" "B.Mask" "B.Paste")
			(net "GND")
		)
	)
	(footprint ""
		(layer "B.Cu")
		(at 321.747642 -26.71064 -90)
		(property "Reference" "R621"
			(at 0 0 90)
			(layer "B.SilkS")
			(hide yes)
			(effects
				(font
					(size 1.27 1.27)
				)
				(justify mirror)
			)
		)
		(property "Value" ""
			(at 0 0 90)
			(layer "B.Fab")
			(effects
				(font
					(size 1.27 1.27)
				)
				(justify mirror)
			)
		)
		(duplicate_pad_numbers_are_jumpers no)
		(fp_line
			(start -0.7874 0.4064)
			(end 0.7874 0.4064)
			(stroke
				(width 0.1524)
				(type default)
			)
			(layer "B.SilkS")
		)
		(fp_line
			(start 0.7874 0.4064)
			(end 0.7874 -0.4064)
			(stroke
				(width 0.1524)
				(type default)
			)
			(layer "B.SilkS")
		)
		(fp_line
			(start -0.7874 -0.4064)
			(end -0.7874 0.4064)
			(stroke
				(width 0.1524)
				(type default)
			)
			(layer "B.SilkS")
		)
		(fp_line
			(start 0.7874 -0.4064)
			(end -0.7874 -0.4064)
			(stroke
				(width 0.1524)
				(type default)
			)
			(layer "B.SilkS")
		)
		(fp_line
			(start -0.67945 0.3048)
			(end -0.120396 0.3048)
			(stroke
				(width 0.1)
				(type default)
			)
			(layer "B.Fab")
		)
		(fp_line
			(start -0.120396 0.3048)
			(end -0.120396 0.2794)
			(stroke
				(width 0.1)
				(type default)
			)
			(layer "B.Fab")
		)
		(fp_line
			(start 0.12065 0.3048)
			(end 0.67945 0.3048)
			(stroke
				(width 0.1)
				(type default)
			)
			(layer "B.Fab")
		)
		(fp_line
			(start 0.67945 0.3048)
			(end 0.67945 -0.305054)
			(stroke
				(width 0.1)
				(type default)
			)
			(layer "B.Fab")
		)
		(fp_line
			(start -0.120396 0.2794)
			(end 0.12065 0.2794)
			(stroke
				(width 0.1)
				(type default)
			)
			(layer "B.Fab")
		)
		(fp_line
			(start 0.12065 0.2794)
			(end 0.12065 0.3048)
			(stroke
				(width 0.1)
				(type default)
			)
			(layer "B.Fab")
		)
		(fp_line
			(start -0.12065 -0.2794)
			(end -0.12065 -0.3048)
			(stroke
				(width 0.1)
				(type default)
			)
			(layer "B.Fab")
		)
		(fp_line
			(start 0.12065 -0.2794)
			(end -0.12065 -0.2794)
			(stroke
				(width 0.1)
				(type default)
			)
			(layer "B.Fab")
		)
		(fp_line
			(start -0.67945 -0.3048)
			(end -0.67945 0.3048)
			(stroke
				(width 0.1)
				(type default)
			)
			(layer "B.Fab")
		)
		(fp_line
			(start -0.12065 -0.3048)
			(end -0.67945 -0.3048)
			(stroke
				(width 0.1)
				(type default)
			)
			(layer "B.Fab")
		)
		(fp_line
			(start 0.12065 -0.305054)
			(end 0.12065 -0.2794)
			(stroke
				(width 0.1)
				(type default)
			)
			(layer "B.Fab")
		)
		(fp_line
			(start 0.67945 -0.305054)
			(end 0.12065 -0.305054)
			(stroke
				(width 0.1)
				(type default)
			)
			(layer "B.Fab")
		)
		(pad "1" smd circle
			(at 0.40005 0 90)
			(size 0 0)
			(layers "B.Cu" "B.Mask" "B.Paste")
			(net "P3V3_AUX")
		)
		(pad "2" smd circle
			(at -0.40005 0 90)
			(size 0 0)
			(layers "B.Cu" "B.Mask" "B.Paste")
			(net "FM_PCH_SKIP_RTC_CLOCK")
		)
	)
	(footprint ""
		(layer "B.Cu")
		(at 409.197556 -318.755776)
		(property "Reference" "R35"
			(at 0 0 0)
			(layer "B.SilkS")
			(hide yes)
			(effects
				(font
					(size 1.27 1.27)
				)
				(justify mirror)
			)
		)
		(property "Value" ""
			(at 0 0 0)
			(layer "B.Fab")
			(effects
				(font
					(size 1.27 1.27)
				)
				(justify mirror)
			)
		)
		(duplicate_pad_numbers_are_jumpers no)
		(fp_line
			(start -0.7874 -0.4064)
			(end -0.7874 0.4064)
			(stroke
				(width 0.1524)
				(type default)
			)
			(layer "B.SilkS")
		)
		(fp_line
			(start -0.7874 0.4064)
			(end 0.7874 0.4064)
			(stroke
				(width 0.1524)
				(type default)
			)
			(layer "B.SilkS")
		)
		(fp_line
			(start 0.7874 -0.4064)
			(end -0.7874 -0.4064)
			(stroke
				(width 0.1524)
				(type default)
			)
			(layer "B.SilkS")
		)
		(fp_line
			(start 0.7874 0.4064)
			(end 0.7874 -0.4064)
			(stroke
				(width 0.1524)
				(type default)
			)
			(layer "B.SilkS")
		)
		(fp_line
			(start -0.67945 -0.3048)
			(end -0.67945 0.3048)
			(stroke
				(width 0.1)
				(type default)
			)
			(layer "B.Fab")
		)
		(fp_line
			(start -0.67945 0.3048)
			(end -0.120396 0.3048)
			(stroke
				(width 0.1)
				(type default)
			)
			(layer "B.Fab")
		)
		(fp_line
			(start -0.12065 -0.3048)
			(end -0.67945 -0.3048)
			(stroke
				(width 0.1)
				(type default)
			)
			(layer "B.Fab")
		)
		(fp_line
			(start -0.12065 -0.2794)
			(end -0.12065 -0.3048)
			(stroke
				(width 0.1)
				(type default)
			)
			(layer "B.Fab")
		)
		(fp_line
			(start -0.120396 0.2794)
			(end 0.12065 0.2794)
			(stroke
				(width 0.1)
				(type default)
			)
			(layer "B.Fab")
		)
		(fp_line
			(start -0.120396 0.3048)
			(end -0.120396 0.2794)
			(stroke
				(width 0.1)
				(type default)
			)
			(layer "B.Fab")
		)
		(fp_line
			(start 0.12065 -0.305054)
			(end 0.12065 -0.2794)
			(stroke
				(width 0.1)
				(type default)
			)
			(layer "B.Fab")
		)
		(fp_line
			(start 0.12065 -0.2794)
			(end -0.12065 -0.2794)
			(stroke
				(width 0.1)
				(type default)
			)
			(layer "B.Fab")
		)
		(fp_line
			(start 0.12065 0.2794)
			(end 0.12065 0.3048)
			(stroke
				(width 0.1)
				(type default)
			)
			(layer "B.Fab")
		)
		(fp_line
			(start 0.12065 0.3048)
			(end 0.67945 0.3048)
			(stroke
				(width 0.1)
				(type default)
			)
			(layer "B.Fab")
		)
		(fp_line
			(start 0.67945 -0.305054)
			(end 0.12065 -0.305054)
			(stroke
				(width 0.1)
				(type default)
			)
			(layer "B.Fab")
		)
		(fp_line
			(start 0.67945 0.3048)
			(end 0.67945 -0.305054)
			(stroke
				(width 0.1)
				(type default)
			)
			(layer "B.Fab")
		)
		(pad "1" smd circle
			(at 0.40005 0 180)
			(size 0 0)
			(layers "B.Cu" "B.Mask" "B.Paste")
			(net "PD_CHE_CPU0_DIMM2_SAA")
		)
		(pad "2" smd circle
			(at -0.40005 0 180)
			(size 0 0)
			(layers "B.Cu" "B.Mask" "B.Paste")
			(net "GND")
		)
	)
	(footprint ""
		(layer "B.Cu")
		(at 105.679494 -244.82044 -90)
		(property "Reference" "C316"
			(at 0 0 90)
			(layer "B.SilkS")
			(hide yes)
			(effects
				(font
					(size 1.27 1.27)
				)
				(justify mirror)
			)
		)
		(property "Value" ""
			(at 0 0 90)
			(layer "B.Fab")
			(effects
				(font
					(size 1.27 1.27)
				)
				(justify mirror)
			)
		)
		(duplicate_pad_numbers_are_jumpers no)
		(fp_line
			(start -1.524 0.762)
			(end 1.524 0.762)
			(stroke
				(width 0.1524)
				(type default)
			)
			(layer "B.SilkS")
		)
		(fp_line
			(start 1.524 0.762)
			(end 1.524 -0.762)
			(stroke
				(width 0.1524)
				(type default)
			)
			(layer "B.SilkS")
		)
		(fp_line
			(start -1.524 -0.762)
			(end -1.524 0.762)
			(stroke
				(width 0.1524)
				(type default)
			)
			(layer "B.SilkS")
		)
		(fp_line
			(start 1.524 -0.762)
			(end -1.524 -0.762)
			(stroke
				(width 0.1524)
				(type default)
			)
			(layer "B.SilkS")
		)
		(fp_line
			(start -1.1049 0.724916)
			(end -1.1049 -0.724916)
			(stroke
				(width 0.1)
				(type default)
			)
			(layer "B.Fab")
		)
		(fp_line
			(start 1.1049 0.724916)
			(end -1.1049 0.724916)
			(stroke
				(width 0.1)
				(type default)
			)
			(layer "B.Fab")
		)
		(fp_line
			(start -1.1049 -0.724916)
			(end 1.1049 -0.724916)
			(stroke
				(width 0.1)
				(type default)
			)
			(layer "B.Fab")
		)
		(fp_line
			(start 1.1049 -0.724916)
			(end 1.1049 0.724916)
			(stroke
				(width 0.1)
				(type default)
			)
			(layer "B.Fab")
		)
		(pad "1" smd rect
			(at 0.889 0 270)
			(size 1.016 1.27)
			(layers "B.Cu" "B.Mask" "B.Paste")
			(net "PVCCIN_CPU1")
		)
		(pad "2" smd rect
			(at -0.889 0 270)
			(size 1.016 1.27)
			(layers "B.Cu" "B.Mask" "B.Paste")
			(net "GND")
		)
	)
	(footprint ""
		(layer "B.Cu")
		(at 179.85994 -21.364448 -90)
		(property "Reference" "R4511"
			(at 0 0 90)
			(layer "B.SilkS")
			(hide yes)
			(effects
				(font
					(size 1.27 1.27)
				)
				(justify mirror)
			)
		)
		(property "Value" ""
			(at 0 0 90)
			(layer "B.Fab")
			(effects
				(font
					(size 1.27 1.27)
				)
				(justify mirror)
			)
		)
		(duplicate_pad_numbers_are_jumpers no)
		(fp_line
			(start -0.7874 0.4064)
			(end 0.7874 0.4064)
			(stroke
				(width 0.1524)
				(type default)
			)
			(layer "B.SilkS")
		)
		(fp_line
			(start 0.7874 0.4064)
			(end 0.7874 -0.4064)
			(stroke
				(width 0.1524)
				(type default)
			)
			(layer "B.SilkS")
		)
		(fp_line
			(start -0.7874 -0.4064)
			(end -0.7874 0.4064)
			(stroke
				(width 0.1524)
				(type default)
			)
			(layer "B.SilkS")
		)
		(fp_line
			(start 0.7874 -0.4064)
			(end -0.7874 -0.4064)
			(stroke
				(width 0.1524)
				(type default)
			)
			(layer "B.SilkS")
		)
		(fp_line
			(start -0.67945 0.3048)
			(end -0.120396 0.3048)
			(stroke
				(width 0.1)
				(type default)
			)
			(layer "B.Fab")
		)
		(fp_line
			(start -0.120396 0.3048)
			(end -0.120396 0.2794)
			(stroke
				(width 0.1)
				(type default)
			)
			(layer "B.Fab")
		)
		(fp_line
			(start 0.12065 0.3048)
			(end 0.67945 0.3048)
			(stroke
				(width 0.1)
				(type default)
			)
			(layer "B.Fab")
		)
		(fp_line
			(start 0.67945 0.3048)
			(end 0.67945 -0.305054)
			(stroke
				(width 0.1)
				(type default)
			)
			(layer "B.Fab")
		)
		(fp_line
			(start -0.120396 0.2794)
			(end 0.12065 0.2794)
			(stroke
				(width 0.1)
				(type default)
			)
			(layer "B.Fab")
		)
		(fp_line
			(start 0.12065 0.2794)
			(end 0.12065 0.3048)
			(stroke
				(width 0.1)
				(type default)
			)
			(layer "B.Fab")
		)
		(fp_line
			(start -0.12065 -0.2794)
			(end -0.12065 -0.3048)
			(stroke
				(width 0.1)
				(type default)
			)
			(layer "B.Fab")
		)
		(fp_line
			(start 0.12065 -0.2794)
			(end -0.12065 -0.2794)
			(stroke
				(width 0.1)
				(type default)
			)
			(layer "B.Fab")
		)
		(fp_line
			(start -0.67945 -0.3048)
			(end -0.67945 0.3048)
			(stroke
				(width 0.1)
				(type default)
			)
			(layer "B.Fab")
		)
		(fp_line
			(start -0.12065 -0.3048)
			(end -0.67945 -0.3048)
			(stroke
				(width 0.1)
				(type default)
			)
			(layer "B.Fab")
		)
		(fp_line
			(start 0.12065 -0.305054)
			(end 0.12065 -0.2794)
			(stroke
				(width 0.1)
				(type default)
			)
			(layer "B.Fab")
		)
		(fp_line
			(start 0.67945 -0.305054)
			(end 0.12065 -0.305054)
			(stroke
				(width 0.1)
				(type default)
			)
			(layer "B.Fab")
		)
		(pad "1" smd circle
			(at 0.40005 0 90)
			(size 0 0)
			(layers "B.Cu" "B.Mask" "B.Paste")
			(net "SMB_HOST_3V3AUX_SDA")
		)
		(pad "2" smd circle
			(at -0.40005 0 90)
			(size 0 0)
			(layers "B.Cu" "B.Mask" "B.Paste")
			(net "SMB_HOST_3V3AUX_SDA_R4")
		)
	)
	(footprint ""
		(layer "B.Cu")
		(at 410.492956 -318.908176 90)
		(property "Reference" "R886"
			(at 0 0 90)
			(layer "B.SilkS")
			(hide yes)
			(effects
				(font
					(size 1.27 1.27)
				)
				(justify mirror)
			)
		)
		(property "Value" ""
			(at 0 0 90)
			(layer "B.Fab")
			(effects
				(font
					(size 1.27 1.27)
				)
				(justify mirror)
			)
		)
		(duplicate_pad_numbers_are_jumpers no)
		(fp_line
			(start 0.7874 -0.4064)
			(end -0.7874 -0.4064)
			(stroke
				(width 0.1524)
				(type default)
			)
			(layer "B.SilkS")
		)
		(fp_line
			(start -0.7874 -0.4064)
			(end -0.7874 0.4064)
			(stroke
				(width 0.1524)
				(type default)
			)
			(layer "B.SilkS")
		)
		(fp_line
			(start 0.7874 0.4064)
			(end 0.7874 -0.4064)
			(stroke
				(width 0.1524)
				(type default)
			)
			(layer "B.SilkS")
		)
		(fp_line
			(start -0.7874 0.4064)
			(end 0.7874 0.4064)
			(stroke
				(width 0.1524)
				(type default)
			)
			(layer "B.SilkS")
		)
		(fp_line
			(start 0.67945 -0.305054)
			(end 0.12065 -0.305054)
			(stroke
				(width 0.1)
				(type default)
			)
			(layer "B.Fab")
		)
		(fp_line
			(start 0.12065 -0.305054)
			(end 0.12065 -0.2794)
			(stroke
				(width 0.1)
				(type default)
			)
			(layer "B.Fab")
		)
		(fp_line
			(start -0.12065 -0.3048)
			(end -0.67945 -0.3048)
			(stroke
				(width 0.1)
				(type default)
			)
			(layer "B.Fab")
		)
		(fp_line
			(start -0.67945 -0.3048)
			(end -0.67945 0.3048)
			(stroke
				(width 0.1)
				(type default)
			)
			(layer "B.Fab")
		)
		(fp_line
			(start 0.12065 -0.2794)
			(end -0.12065 -0.2794)
			(stroke
				(width 0.1)
				(type default)
			)
			(layer "B.Fab")
		)
		(fp_line
			(start -0.12065 -0.2794)
			(end -0.12065 -0.3048)
			(stroke
				(width 0.1)
				(type default)
			)
			(layer "B.Fab")
		)
		(fp_line
			(start 0.12065 0.2794)
			(end 0.12065 0.3048)
			(stroke
				(width 0.1)
				(type default)
			)
			(layer "B.Fab")
		)
		(fp_line
			(start -0.120396 0.2794)
			(end 0.12065 0.2794)
			(stroke
				(width 0.1)
				(type default)
			)
			(layer "B.Fab")
		)
		(fp_line
			(start 0.67945 0.3048)
			(end 0.67945 -0.305054)
			(stroke
				(width 0.1)
				(type default)
			)
			(layer "B.Fab")
		)
		(fp_line
			(start 0.12065 0.3048)
			(end 0.67945 0.3048)
			(stroke
				(width 0.1)
				(type default)
			)
			(layer "B.Fab")
		)
		(fp_line
			(start -0.120396 0.3048)
			(end -0.120396 0.2794)
			(stroke
				(width 0.1)
				(type default)
			)
			(layer "B.Fab")
		)
		(fp_line
			(start -0.67945 0.3048)
			(end -0.120396 0.3048)
			(stroke
				(width 0.1)
				(type default)
			)
			(layer "B.Fab")
		)
		(pad "1" smd circle
			(at 0.40005 0 270)
			(size 0 0)
			(layers "B.Cu" "B.Mask" "B.Paste")
			(net "PWRGD_CHE_CPU0_DIMM2")
		)
		(pad "2" smd circle
			(at -0.40005 0 270)
			(size 0 0)
			(layers "B.Cu" "B.Mask" "B.Paste")
			(net "PWRGD_FAIL_CPU0_EF")
		)
	)
	(footprint ""
		(layer "B.Cu")
		(at 38.015926 -344.935556 -90)
		(property "Reference" "PC1209_P1_4"
			(at 0 0 90)
			(layer "B.SilkS")
			(hide yes)
			(effects
				(font
					(size 1.27 1.27)
				)
				(justify mirror)
			)
		)
		(property "Value" ""
			(at 0 0 90)
			(layer "B.Fab")
			(effects
				(font
					(size 1.27 1.27)
				)
				(justify mirror)
			)
		)
		(duplicate_pad_numbers_are_jumpers no)
		(fp_line
			(start -1.524 0.762)
			(end 1.524 0.762)
			(stroke
				(width 0.1524)
				(type default)
			)
			(layer "B.SilkS")
		)
		(fp_line
			(start 1.524 0.762)
			(end 1.524 -0.762)
			(stroke
				(width 0.1524)
				(type default)
			)
			(layer "B.SilkS")
		)
		(fp_line
			(start -1.524 -0.762)
			(end -1.524 0.762)
			(stroke
				(width 0.1524)
				(type default)
			)
			(layer "B.SilkS")
		)
		(fp_line
			(start 1.524 -0.762)
			(end -1.524 -0.762)
			(stroke
				(width 0.1524)
				(type default)
			)
			(layer "B.SilkS")
		)
		(fp_line
			(start -1.1049 0.724916)
			(end -1.1049 -0.724916)
			(stroke
				(width 0.1)
				(type default)
			)
			(layer "B.Fab")
		)
		(fp_line
			(start 1.1049 0.724916)
			(end -1.1049 0.724916)
			(stroke
				(width 0.1)
				(type default)
			)
			(layer "B.Fab")
		)
		(fp_line
			(start -1.1049 -0.724916)
			(end 1.1049 -0.724916)
			(stroke
				(width 0.1)
				(type default)
			)
			(layer "B.Fab")
		)
		(fp_line
			(start 1.1049 -0.724916)
			(end 1.1049 0.724916)
			(stroke
				(width 0.1)
				(type default)
			)
			(layer "B.Fab")
		)
		(pad "1" smd rect
			(at 0.889 0 270)
			(size 1.016 1.27)
			(layers "B.Cu" "B.Mask" "B.Paste")
			(net "PVCCFA_EHV_FIVRA_CPU1")
		)
		(pad "2" smd rect
			(at -0.889 0 270)
			(size 1.016 1.27)
			(layers "B.Cu" "B.Mask" "B.Paste")
			(net "GND")
		)
	)
	(footprint ""
		(layer "B.Cu")
		(at 230.249222 -121.743216 -90)
		(property "Reference" "L3"
			(at 0 0 90)
			(layer "B.SilkS")
			(hide yes)
			(effects
				(font
					(size 1.27 1.27)
				)
				(justify mirror)
			)
		)
		(property "Value" ""
			(at 0 0 90)
			(layer "B.Fab")
			(effects
				(font
					(size 1.27 1.27)
				)
				(justify mirror)
			)
		)
		(duplicate_pad_numbers_are_jumpers no)
		(fp_line
			(start -1.27 0.5842)
			(end 1.27 0.5842)
			(stroke
				(width 0.1524)
				(type default)
			)
			(layer "B.SilkS")
		)
		(fp_line
			(start -1.27 0.5842)
			(end -1.27 -0.5842)
			(stroke
				(width 0.1524)
				(type default)
			)
			(layer "B.SilkS")
		)
		(fp_line
			(start -0.127 0.5842)
			(end -0.127 -0.5842)
			(stroke
				(width 0.1524)
				(type default)
			)
			(layer "B.SilkS")
		)
		(fp_line
			(start 0.127 0.5842)
			(end 0.127 -0.5842)
			(stroke
				(width 0.1524)
				(type default)
			)
			(layer "B.SilkS")
		)
		(fp_line
			(start 1.27 0.5842)
			(end 1.27 -0.5842)
			(stroke
				(width 0.1524)
				(type default)
			)
			(layer "B.SilkS")
		)
		(fp_line
			(start 1.27 -0.5588)
			(end 1.27 -0.5842)
			(stroke
				(width 0.1524)
				(type default)
			)
			(layer "B.SilkS")
		)
		(fp_line
			(start 1.27 -0.5842)
			(end -1.27 -0.5842)
			(stroke
				(width 0.1524)
				(type default)
			)
			(layer "B.SilkS")
		)
		(fp_line
			(start -0.9144 0.508)
			(end 0.9144 0.508)
			(stroke
				(width 0.1)
				(type default)
			)
			(layer "B.Fab")
		)
		(fp_line
			(start 0.9144 0.508)
			(end 0.9144 0.406654)
			(stroke
				(width 0.1)
				(type default)
			)
			(layer "B.Fab")
		)
		(fp_line
			(start 0.9144 0.406654)
			(end 1.194308 0.406654)
			(stroke
				(width 0.1)
				(type default)
			)
			(layer "B.Fab")
		)
		(fp_line
			(start 1.194308 0.406654)
			(end 1.194308 -0.406654)
			(stroke
				(width 0.1)
				(type default)
			)
			(layer "B.Fab")
		)
		(fp_line
			(start -1.1938 0.4064)
			(end -0.9144 0.4064)
			(stroke
				(width 0.1)
				(type default)
			)
			(layer "B.Fab")
		)
		(fp_line
			(start -0.9144 0.4064)
			(end -0.9144 0.508)
			(stroke
				(width 0.1)
				(type default)
			)
			(layer "B.Fab")
		)
		(fp_line
			(start -1.1938 -0.406654)
			(end -1.1938 0.4064)
			(stroke
				(width 0.1)
				(type default)
			)
			(layer "B.Fab")
		)
		(fp_line
			(start -0.9144 -0.406654)
			(end -1.1938 -0.406654)
			(stroke
				(width 0.1)
				(type default)
			)
			(layer "B.Fab")
		)
		(fp_line
			(start 0.9144 -0.406654)
			(end 0.9144 -0.508)
			(stroke
				(width 0.1)
				(type default)
			)
			(layer "B.Fab")
		)
		(fp_line
			(start 1.194308 -0.406654)
			(end 0.9144 -0.406654)
			(stroke
				(width 0.1)
				(type default)
			)
			(layer "B.Fab")
		)
		(fp_line
			(start -0.9144 -0.508)
			(end -0.9144 -0.406654)
			(stroke
				(width 0.1)
				(type default)
			)
			(layer "B.Fab")
		)
		(fp_line
			(start 0.9144 -0.508)
			(end -0.9144 -0.508)
			(stroke
				(width 0.1)
				(type default)
			)
			(layer "B.Fab")
		)
		(pad "1" smd rect
			(at 0.7366 0 180)
			(size 0.7112 0.8128)
			(layers "B.Cu" "B.Mask" "B.Paste")
			(net "P3V3")
		)
		(pad "2" smd rect
			(at -0.7366 0 180)
			(size 0.7112 0.8128)
			(layers "B.Cu" "B.Mask" "B.Paste")
			(net "P3V3_DB2000_VDD")
		)
	)
	(footprint ""
		(layer "B.Cu")
		(at 236.62513 -48.104044)
		(property "Reference" "C1283"
			(at 0 0 0)
			(layer "B.SilkS")
			(hide yes)
			(effects
				(font
					(size 1.27 1.27)
				)
				(justify mirror)
			)
		)
		(property "Value" ""
			(at 0 0 0)
			(layer "B.Fab")
			(effects
				(font
					(size 1.27 1.27)
				)
				(justify mirror)
			)
		)
		(duplicate_pad_numbers_are_jumpers no)
		(fp_line
			(start -0.7874 -0.4064)
			(end -0.7874 0.4064)
			(stroke
				(width 0.1524)
				(type default)
			)
			(layer "B.SilkS")
		)
		(fp_line
			(start -0.7874 0.4064)
			(end 0.7874 0.4064)
			(stroke
				(width 0.1524)
				(type default)
			)
			(layer "B.SilkS")
		)
		(fp_line
			(start 0.7874 -0.4064)
			(end -0.7874 -0.4064)
			(stroke
				(width 0.1524)
				(type default)
			)
			(layer "B.SilkS")
		)
		(fp_line
			(start 0.7874 0.4064)
			(end 0.7874 -0.4064)
			(stroke
				(width 0.1524)
				(type default)
			)
			(layer "B.SilkS")
		)
		(fp_line
			(start -0.67945 -0.3048)
			(end -0.67945 0.3048)
			(stroke
				(width 0.1)
				(type default)
			)
			(layer "B.Fab")
		)
		(fp_line
			(start -0.67945 0.3048)
			(end -0.120396 0.3048)
			(stroke
				(width 0.1)
				(type default)
			)
			(layer "B.Fab")
		)
		(fp_line
			(start -0.12065 -0.3048)
			(end -0.67945 -0.3048)
			(stroke
				(width 0.1)
				(type default)
			)
			(layer "B.Fab")
		)
		(fp_line
			(start -0.12065 -0.2794)
			(end -0.12065 -0.3048)
			(stroke
				(width 0.1)
				(type default)
			)
			(layer "B.Fab")
		)
		(fp_line
			(start -0.120396 0.2794)
			(end 0.12065 0.2794)
			(stroke
				(width 0.1)
				(type default)
			)
			(layer "B.Fab")
		)
		(fp_line
			(start -0.120396 0.3048)
			(end -0.120396 0.2794)
			(stroke
				(width 0.1)
				(type default)
			)
			(layer "B.Fab")
		)
		(fp_line
			(start 0.12065 -0.305054)
			(end 0.12065 -0.2794)
			(stroke
				(width 0.1)
				(type default)
			)
			(layer "B.Fab")
		)
		(fp_line
			(start 0.12065 -0.2794)
			(end -0.12065 -0.2794)
			(stroke
				(width 0.1)
				(type default)
			)
			(layer "B.Fab")
		)
		(fp_line
			(start 0.12065 0.2794)
			(end 0.12065 0.3048)
			(stroke
				(width 0.1)
				(type default)
			)
			(layer "B.Fab")
		)
		(fp_line
			(start 0.12065 0.3048)
			(end 0.67945 0.3048)
			(stroke
				(width 0.1)
				(type default)
			)
			(layer "B.Fab")
		)
		(fp_line
			(start 0.67945 -0.305054)
			(end 0.12065 -0.305054)
			(stroke
				(width 0.1)
				(type default)
			)
			(layer "B.Fab")
		)
		(fp_line
			(start 0.67945 0.3048)
			(end 0.67945 -0.305054)
			(stroke
				(width 0.1)
				(type default)
			)
			(layer "B.Fab")
		)
		(pad "1" smd circle
			(at 0.40005 0 180)
			(size 0 0)
			(layers "B.Cu" "B.Mask" "B.Paste")
			(net "P3V3_E1S_0")
		)
		(pad "2" smd circle
			(at -0.40005 0 180)
			(size 0 0)
			(layers "B.Cu" "B.Mask" "B.Paste")
			(net "GND")
		)
	)
	(footprint ""
		(layer "B.Cu")
		(at 334.744314 -33.173162 90)
		(property "Reference" "R918"
			(at 0 0 90)
			(layer "B.SilkS")
			(hide yes)
			(effects
				(font
					(size 1.27 1.27)
				)
				(justify mirror)
			)
		)
		(property "Value" ""
			(at 0 0 90)
			(layer "B.Fab")
			(effects
				(font
					(size 1.27 1.27)
				)
				(justify mirror)
			)
		)
		(duplicate_pad_numbers_are_jumpers no)
		(fp_line
			(start 0.7874 -0.4064)
			(end -0.7874 -0.4064)
			(stroke
				(width 0.1524)
				(type default)
			)
			(layer "B.SilkS")
		)
		(fp_line
			(start -0.7874 -0.4064)
			(end -0.7874 0.4064)
			(stroke
				(width 0.1524)
				(type default)
			)
			(layer "B.SilkS")
		)
		(fp_line
			(start 0.7874 0.4064)
			(end 0.7874 -0.4064)
			(stroke
				(width 0.1524)
				(type default)
			)
			(layer "B.SilkS")
		)
		(fp_line
			(start -0.7874 0.4064)
			(end 0.7874 0.4064)
			(stroke
				(width 0.1524)
				(type default)
			)
			(layer "B.SilkS")
		)
		(fp_line
			(start 0.67945 -0.305054)
			(end 0.12065 -0.305054)
			(stroke
				(width 0.1)
				(type default)
			)
			(layer "B.Fab")
		)
		(fp_line
			(start 0.12065 -0.305054)
			(end 0.12065 -0.2794)
			(stroke
				(width 0.1)
				(type default)
			)
			(layer "B.Fab")
		)
		(fp_line
			(start -0.12065 -0.3048)
			(end -0.67945 -0.3048)
			(stroke
				(width 0.1)
				(type default)
			)
			(layer "B.Fab")
		)
		(fp_line
			(start -0.67945 -0.3048)
			(end -0.67945 0.3048)
			(stroke
				(width 0.1)
				(type default)
			)
			(layer "B.Fab")
		)
		(fp_line
			(start 0.12065 -0.2794)
			(end -0.12065 -0.2794)
			(stroke
				(width 0.1)
				(type default)
			)
			(layer "B.Fab")
		)
		(fp_line
			(start -0.12065 -0.2794)
			(end -0.12065 -0.3048)
			(stroke
				(width 0.1)
				(type default)
			)
			(layer "B.Fab")
		)
		(fp_line
			(start 0.12065 0.2794)
			(end 0.12065 0.3048)
			(stroke
				(width 0.1)
				(type default)
			)
			(layer "B.Fab")
		)
		(fp_line
			(start -0.120396 0.2794)
			(end 0.12065 0.2794)
			(stroke
				(width 0.1)
				(type default)
			)
			(layer "B.Fab")
		)
		(fp_line
			(start 0.67945 0.3048)
			(end 0.67945 -0.305054)
			(stroke
				(width 0.1)
				(type default)
			)
			(layer "B.Fab")
		)
		(fp_line
			(start 0.12065 0.3048)
			(end 0.67945 0.3048)
			(stroke
				(width 0.1)
				(type default)
			)
			(layer "B.Fab")
		)
		(fp_line
			(start -0.120396 0.3048)
			(end -0.120396 0.2794)
			(stroke
				(width 0.1)
				(type default)
			)
			(layer "B.Fab")
		)
		(fp_line
			(start -0.67945 0.3048)
			(end -0.120396 0.3048)
			(stroke
				(width 0.1)
				(type default)
			)
			(layer "B.Fab")
		)
		(pad "1" smd circle
			(at 0.40005 0 270)
			(size 0 0)
			(layers "B.Cu" "B.Mask" "B.Paste")
			(net "SPI_PCH_IO2")
		)
		(pad "2" smd circle
			(at -0.40005 0 270)
			(size 0 0)
			(layers "B.Cu" "B.Mask" "B.Paste")
			(net "SPI_SYS_WP_IO2")
		)
	)
	(footprint ""
		(layer "B.Cu")
		(at 444.485014 -321.549776 -90)
		(property "Reference" "C40"
			(at 0 0 90)
			(layer "B.SilkS")
			(hide yes)
			(effects
				(font
					(size 1.27 1.27)
				)
				(justify mirror)
			)
		)
		(property "Value" ""
			(at 0 0 90)
			(layer "B.Fab")
			(effects
				(font
					(size 1.27 1.27)
				)
				(justify mirror)
			)
		)
		(duplicate_pad_numbers_are_jumpers no)
		(fp_line
			(start -1.524 0.762)
			(end 1.524 0.762)
			(stroke
				(width 0.1524)
				(type default)
			)
			(layer "B.SilkS")
		)
		(fp_line
			(start 1.524 0.762)
			(end 1.524 -0.762)
			(stroke
				(width 0.1524)
				(type default)
			)
			(layer "B.SilkS")
		)
		(fp_line
			(start -1.524 -0.762)
			(end -1.524 0.762)
			(stroke
				(width 0.1524)
				(type default)
			)
			(layer "B.SilkS")
		)
		(fp_line
			(start 1.524 -0.762)
			(end -1.524 -0.762)
			(stroke
				(width 0.1524)
				(type default)
			)
			(layer "B.SilkS")
		)
		(fp_line
			(start -1.1049 0.724916)
			(end -1.1049 -0.724916)
			(stroke
				(width 0.1)
				(type default)
			)
			(layer "B.Fab")
		)
		(fp_line
			(start 1.1049 0.724916)
			(end -1.1049 0.724916)
			(stroke
				(width 0.1)
				(type default)
			)
			(layer "B.Fab")
		)
		(fp_line
			(start -1.1049 -0.724916)
			(end 1.1049 -0.724916)
			(stroke
				(width 0.1)
				(type default)
			)
			(layer "B.Fab")
		)
		(fp_line
			(start 1.1049 -0.724916)
			(end 1.1049 0.724916)
			(stroke
				(width 0.1)
				(type default)
			)
			(layer "B.Fab")
		)
		(pad "1" smd rect
			(at 0.889 0 270)
			(size 1.016 1.27)
			(layers "B.Cu" "B.Mask" "B.Paste")
			(net "P12V_S3_AUX_CPU0_NVDIMM")
		)
		(pad "2" smd rect
			(at -0.889 0 270)
			(size 1.016 1.27)
			(layers "B.Cu" "B.Mask" "B.Paste")
			(net "GND")
		)
	)
	(footprint ""
		(layer "B.Cu")
		(at 343.840308 -62.056264 90)
		(property "Reference" "C162"
			(at 0 0 90)
			(layer "B.SilkS")
			(hide yes)
			(effects
				(font
					(size 1.27 1.27)
				)
				(justify mirror)
			)
		)
		(property "Value" ""
			(at 0 0 90)
			(layer "B.Fab")
			(effects
				(font
					(size 1.27 1.27)
				)
				(justify mirror)
			)
		)
		(duplicate_pad_numbers_are_jumpers no)
		(fp_line
			(start 0.299974 -0.150114)
			(end -0.299974 -0.150114)
			(stroke
				(width 0.1)
				(type default)
			)
			(layer "B.Fab")
		)
		(fp_line
			(start -0.299974 -0.150114)
			(end -0.299974 0.150114)
			(stroke
				(width 0.1)
				(type default)
			)
			(layer "B.Fab")
		)
		(fp_line
			(start 0.299974 0.150114)
			(end 0.299974 -0.150114)
			(stroke
				(width 0.1)
				(type default)
			)
			(layer "B.Fab")
		)
		(fp_line
			(start -0.299974 0.150114)
			(end 0.299974 0.150114)
			(stroke
				(width 0.1)
				(type default)
			)
			(layer "B.Fab")
		)
		(pad "1" smd rect
			(at 0.2667 0 270)
			(size 0.3048 0.381)
			(layers "B.Cu" "B.Mask" "B.Paste")
			(net "DMI_CPU0_PCH_RX_C_DP<4>")
		)
		(pad "2" smd rect
			(at -0.2667 0 270)
			(size 0.3048 0.381)
			(layers "B.Cu" "B.Mask" "B.Paste")
			(net "DMI_CPU0_PCH_RX_DP<4>")
		)
	)
	(footprint ""
		(layer "B.Cu")
		(at 325.66483 -66.840354 -90)
		(property "Reference" "C1191"
			(at 0 0 90)
			(layer "B.SilkS")
			(hide yes)
			(effects
				(font
					(size 1.27 1.27)
				)
				(justify mirror)
			)
		)
		(property "Value" ""
			(at 0 0 90)
			(layer "B.Fab")
			(effects
				(font
					(size 1.27 1.27)
				)
				(justify mirror)
			)
		)
		(duplicate_pad_numbers_are_jumpers no)
		(fp_line
			(start -1.2954 0.5842)
			(end 1.2954 0.5842)
			(stroke
				(width 0.1524)
				(type default)
			)
			(layer "B.SilkS")
		)
		(fp_line
			(start 1.2954 0.5842)
			(end 1.2954 -0.5842)
			(stroke
				(width 0.1524)
				(type default)
			)
			(layer "B.SilkS")
		)
		(fp_line
			(start -1.2954 -0.5842)
			(end -1.2954 0.5842)
			(stroke
				(width 0.1524)
				(type default)
			)
			(layer "B.SilkS")
		)
		(fp_line
			(start 0 -0.5842)
			(end 0 0.5842)
			(stroke
				(width 0.1524)
				(type default)
			)
			(layer "B.SilkS")
		)
		(fp_line
			(start 1.2954 -0.5842)
			(end -1.2954 -0.5842)
			(stroke
				(width 0.1524)
				(type default)
			)
			(layer "B.SilkS")
		)
		(fp_line
			(start -0.8636 0.4572)
			(end 0.8636 0.4572)
			(stroke
				(width 0.1)
				(type default)
			)
			(layer "B.Fab")
		)
		(fp_line
			(start 0.8636 0.4572)
			(end 0.8636 0.4064)
			(stroke
				(width 0.1)
				(type default)
			)
			(layer "B.Fab")
		)
		(fp_line
			(start -1.1938 0.4064)
			(end -0.8636 0.4064)
			(stroke
				(width 0.1)
				(type default)
			)
			(layer "B.Fab")
		)
		(fp_line
			(start -0.8636 0.4064)
			(end -0.8636 0.4572)
			(stroke
				(width 0.1)
				(type default)
			)
			(layer "B.Fab")
		)
		(fp_line
			(start 0.8636 0.4064)
			(end 1.1938 0.4064)
			(stroke
				(width 0.1)
				(type default)
			)
			(layer "B.Fab")
		)
		(fp_line
			(start 1.1938 0.4064)
			(end 1.1938 -0.4064)
			(stroke
				(width 0.1)
				(type default)
			)
			(layer "B.Fab")
		)
		(fp_line
			(start -1.1938 -0.4064)
			(end -1.1938 0.4064)
			(stroke
				(width 0.1)
				(type default)
			)
			(layer "B.Fab")
		)
		(fp_line
			(start -0.8636 -0.4064)
			(end -1.1938 -0.4064)
			(stroke
				(width 0.1)
				(type default)
			)
			(layer "B.Fab")
		)
		(fp_line
			(start 0.8636 -0.4064)
			(end 0.8636 -0.4572)
			(stroke
				(width 0.1)
				(type default)
			)
			(layer "B.Fab")
		)
		(fp_line
			(start 1.1938 -0.4064)
			(end 0.8636 -0.4064)
			(stroke
				(width 0.1)
				(type default)
			)
			(layer "B.Fab")
		)
		(fp_line
			(start -0.8636 -0.4572)
			(end -0.8636 -0.4064)
			(stroke
				(width 0.1)
				(type default)
			)
			(layer "B.Fab")
		)
		(fp_line
			(start 0.8636 -0.4572)
			(end -0.8636 -0.4572)
			(stroke
				(width 0.1)
				(type default)
			)
			(layer "B.Fab")
		)
		(pad "1" smd rect
			(at 0.7366 0 180)
			(size 0.7112 0.8128)
			(layers "B.Cu" "B.Mask" "B.Paste")
			(net "P3V3_AUX")
		)
		(pad "2" smd rect
			(at -0.7366 0 180)
			(size 0.7112 0.8128)
			(layers "B.Cu" "B.Mask" "B.Paste")
			(net "GND")
		)
	)
	(footprint ""
		(layer "B.Cu")
		(at 185.503312 -319.023492 90)
		(property "Reference" "R903"
			(at 0 0 90)
			(layer "B.SilkS")
			(hide yes)
			(effects
				(font
					(size 1.27 1.27)
				)
				(justify mirror)
			)
		)
		(property "Value" ""
			(at 0 0 90)
			(layer "B.Fab")
			(effects
				(font
					(size 1.27 1.27)
				)
				(justify mirror)
			)
		)
		(duplicate_pad_numbers_are_jumpers no)
		(fp_line
			(start 0.7874 -0.4064)
			(end -0.7874 -0.4064)
			(stroke
				(width 0.1524)
				(type default)
			)
			(layer "B.SilkS")
		)
		(fp_line
			(start -0.7874 -0.4064)
			(end -0.7874 0.4064)
			(stroke
				(width 0.1524)
				(type default)
			)
			(layer "B.SilkS")
		)
		(fp_line
			(start 0.7874 0.4064)
			(end 0.7874 -0.4064)
			(stroke
				(width 0.1524)
				(type default)
			)
			(layer "B.SilkS")
		)
		(fp_line
			(start -0.7874 0.4064)
			(end 0.7874 0.4064)
			(stroke
				(width 0.1524)
				(type default)
			)
			(layer "B.SilkS")
		)
		(fp_line
			(start 0.67945 -0.305054)
			(end 0.12065 -0.305054)
			(stroke
				(width 0.1)
				(type default)
			)
			(layer "B.Fab")
		)
		(fp_line
			(start 0.12065 -0.305054)
			(end 0.12065 -0.2794)
			(stroke
				(width 0.1)
				(type default)
			)
			(layer "B.Fab")
		)
		(fp_line
			(start -0.12065 -0.3048)
			(end -0.67945 -0.3048)
			(stroke
				(width 0.1)
				(type default)
			)
			(layer "B.Fab")
		)
		(fp_line
			(start -0.67945 -0.3048)
			(end -0.67945 0.3048)
			(stroke
				(width 0.1)
				(type default)
			)
			(layer "B.Fab")
		)
		(fp_line
			(start 0.12065 -0.2794)
			(end -0.12065 -0.2794)
			(stroke
				(width 0.1)
				(type default)
			)
			(layer "B.Fab")
		)
		(fp_line
			(start -0.12065 -0.2794)
			(end -0.12065 -0.3048)
			(stroke
				(width 0.1)
				(type default)
			)
			(layer "B.Fab")
		)
		(fp_line
			(start 0.12065 0.2794)
			(end 0.12065 0.3048)
			(stroke
				(width 0.1)
				(type default)
			)
			(layer "B.Fab")
		)
		(fp_line
			(start -0.120396 0.2794)
			(end 0.12065 0.2794)
			(stroke
				(width 0.1)
				(type default)
			)
			(layer "B.Fab")
		)
		(fp_line
			(start 0.67945 0.3048)
			(end 0.67945 -0.305054)
			(stroke
				(width 0.1)
				(type default)
			)
			(layer "B.Fab")
		)
		(fp_line
			(start 0.12065 0.3048)
			(end 0.67945 0.3048)
			(stroke
				(width 0.1)
				(type default)
			)
			(layer "B.Fab")
		)
		(fp_line
			(start -0.120396 0.3048)
			(end -0.120396 0.2794)
			(stroke
				(width 0.1)
				(type default)
			)
			(layer "B.Fab")
		)
		(fp_line
			(start -0.67945 0.3048)
			(end -0.120396 0.3048)
			(stroke
				(width 0.1)
				(type default)
			)
			(layer "B.Fab")
		)
		(pad "1" smd circle
			(at 0.40005 0 270)
			(size 0 0)
			(layers "B.Cu" "B.Mask" "B.Paste")
			(net "PWRGD_CHF_CPU1_DIMM1")
		)
		(pad "2" smd circle
			(at -0.40005 0 270)
			(size 0 0)
			(layers "B.Cu" "B.Mask" "B.Paste")
			(net "PWRGD_FAIL_CPU1_EF")
		)
	)
	(footprint ""
		(layer "B.Cu")
		(at 430.362106 -125.165612 90)
		(property "Reference" "PR4236"
			(at 0 0 90)
			(layer "B.SilkS")
			(hide yes)
			(effects
				(font
					(size 1.27 1.27)
				)
				(justify mirror)
			)
		)
		(property "Value" ""
			(at 0 0 90)
			(layer "B.Fab")
			(effects
				(font
					(size 1.27 1.27)
				)
				(justify mirror)
			)
		)
		(duplicate_pad_numbers_are_jumpers no)
		(fp_line
			(start 0.7874 -0.4064)
			(end -0.7874 -0.4064)
			(stroke
				(width 0.1524)
				(type default)
			)
			(layer "B.SilkS")
		)
		(fp_line
			(start -0.7874 -0.4064)
			(end -0.7874 0.4064)
			(stroke
				(width 0.1524)
				(type default)
			)
			(layer "B.SilkS")
		)
		(fp_line
			(start 0.7874 0.4064)
			(end 0.7874 -0.4064)
			(stroke
				(width 0.1524)
				(type default)
			)
			(layer "B.SilkS")
		)
		(fp_line
			(start -0.7874 0.4064)
			(end 0.7874 0.4064)
			(stroke
				(width 0.1524)
				(type default)
			)
			(layer "B.SilkS")
		)
		(fp_line
			(start 0.67945 -0.305054)
			(end 0.12065 -0.305054)
			(stroke
				(width 0.1)
				(type default)
			)
			(layer "B.Fab")
		)
		(fp_line
			(start 0.12065 -0.305054)
			(end 0.12065 -0.2794)
			(stroke
				(width 0.1)
				(type default)
			)
			(layer "B.Fab")
		)
		(fp_line
			(start -0.12065 -0.3048)
			(end -0.67945 -0.3048)
			(stroke
				(width 0.1)
				(type default)
			)
			(layer "B.Fab")
		)
		(fp_line
			(start -0.67945 -0.3048)
			(end -0.67945 0.3048)
			(stroke
				(width 0.1)
				(type default)
			)
			(layer "B.Fab")
		)
		(fp_line
			(start 0.12065 -0.2794)
			(end -0.12065 -0.2794)
			(stroke
				(width 0.1)
				(type default)
			)
			(layer "B.Fab")
		)
		(fp_line
			(start -0.12065 -0.2794)
			(end -0.12065 -0.3048)
			(stroke
				(width 0.1)
				(type default)
			)
			(layer "B.Fab")
		)
		(fp_line
			(start 0.12065 0.2794)
			(end 0.12065 0.3048)
			(stroke
				(width 0.1)
				(type default)
			)
			(layer "B.Fab")
		)
		(fp_line
			(start -0.120396 0.2794)
			(end 0.12065 0.2794)
			(stroke
				(width 0.1)
				(type default)
			)
			(layer "B.Fab")
		)
		(fp_line
			(start 0.67945 0.3048)
			(end 0.67945 -0.305054)
			(stroke
				(width 0.1)
				(type default)
			)
			(layer "B.Fab")
		)
		(fp_line
			(start 0.12065 0.3048)
			(end 0.67945 0.3048)
			(stroke
				(width 0.1)
				(type default)
			)
			(layer "B.Fab")
		)
		(fp_line
			(start -0.120396 0.3048)
			(end -0.120396 0.2794)
			(stroke
				(width 0.1)
				(type default)
			)
			(layer "B.Fab")
		)
		(fp_line
			(start -0.67945 0.3048)
			(end -0.120396 0.3048)
			(stroke
				(width 0.1)
				(type default)
			)
			(layer "B.Fab")
		)
		(pad "1" smd circle
			(at 0.40005 0 270)
			(size 0 0)
			(layers "B.Cu" "B.Mask" "B.Paste")
			(net "NC_PVCCD_HV_CPU0_ACSP8")
		)
		(pad "2" smd circle
			(at -0.40005 0 270)
			(size 0 0)
			(layers "B.Cu" "B.Mask" "B.Paste")
			(net "GND")
		)
	)
	(footprint ""
		(layer "B.Cu")
		(at 418.395404 -319.402968 180)
		(property "Reference" "R885"
			(at 0 0 0)
			(layer "B.SilkS")
			(hide yes)
			(effects
				(font
					(size 1.27 1.27)
				)
				(justify mirror)
			)
		)
		(property "Value" ""
			(at 0 0 0)
			(layer "B.Fab")
			(effects
				(font
					(size 1.27 1.27)
				)
				(justify mirror)
			)
		)
		(duplicate_pad_numbers_are_jumpers no)
		(fp_line
			(start 0.7874 0.4064)
			(end 0.7874 -0.4064)
			(stroke
				(width 0.1524)
				(type default)
			)
			(layer "B.SilkS")
		)
		(fp_line
			(start 0.7874 -0.4064)
			(end -0.7874 -0.4064)
			(stroke
				(width 0.1524)
				(type default)
			)
			(layer "B.SilkS")
		)
		(fp_line
			(start -0.7874 0.4064)
			(end 0.7874 0.4064)
			(stroke
				(width 0.1524)
				(type default)
			)
			(layer "B.SilkS")
		)
		(fp_line
			(start -0.7874 -0.4064)
			(end -0.7874 0.4064)
			(stroke
				(width 0.1524)
				(type default)
			)
			(layer "B.SilkS")
		)
		(fp_line
			(start 0.67945 0.3048)
			(end 0.67945 -0.305054)
			(stroke
				(width 0.1)
				(type default)
			)
			(layer "B.Fab")
		)
		(fp_line
			(start 0.67945 -0.305054)
			(end 0.12065 -0.305054)
			(stroke
				(width 0.1)
				(type default)
			)
			(layer "B.Fab")
		)
		(fp_line
			(start 0.12065 0.3048)
			(end 0.67945 0.3048)
			(stroke
				(width 0.1)
				(type default)
			)
			(layer "B.Fab")
		)
		(fp_line
			(start 0.12065 0.2794)
			(end 0.12065 0.3048)
			(stroke
				(width 0.1)
				(type default)
			)
			(layer "B.Fab")
		)
		(fp_line
			(start 0.12065 -0.2794)
			(end -0.12065 -0.2794)
			(stroke
				(width 0.1)
				(type default)
			)
			(layer "B.Fab")
		)
		(fp_line
			(start 0.12065 -0.305054)
			(end 0.12065 -0.2794)
			(stroke
				(width 0.1)
				(type default)
			)
			(layer "B.Fab")
		)
		(fp_line
			(start -0.120396 0.3048)
			(end -0.120396 0.2794)
			(stroke
				(width 0.1)
				(type default)
			)
			(layer "B.Fab")
		)
		(fp_line
			(start -0.120396 0.2794)
			(end 0.12065 0.2794)
			(stroke
				(width 0.1)
				(type default)
			)
			(layer "B.Fab")
		)
		(fp_line
			(start -0.12065 -0.2794)
			(end -0.12065 -0.3048)
			(stroke
				(width 0.1)
				(type default)
			)
			(layer "B.Fab")
		)
		(fp_line
			(start -0.12065 -0.3048)
			(end -0.67945 -0.3048)
			(stroke
				(width 0.1)
				(type default)
			)
			(layer "B.Fab")
		)
		(fp_line
			(start -0.67945 0.3048)
			(end -0.120396 0.3048)
			(stroke
				(width 0.1)
				(type default)
			)
			(layer "B.Fab")
		)
		(fp_line
			(start -0.67945 -0.3048)
			(end -0.67945 0.3048)
			(stroke
				(width 0.1)
				(type default)
			)
			(layer "B.Fab")
		)
		(pad "1" smd circle
			(at 0.40005 0)
			(size 0 0)
			(layers "B.Cu" "B.Mask" "B.Paste")
			(net "PWRGD_CHE_CPU0_DIMM1")
		)
		(pad "2" smd circle
			(at -0.40005 0)
			(size 0 0)
			(layers "B.Cu" "B.Mask" "B.Paste")
			(net "PWRGD_FAIL_CPU0_EF")
		)
	)
	(footprint ""
		(layer "B.Cu")
		(at 166.386002 -250.271534 180)
		(property "Reference" "R1236"
			(at 0 0 0)
			(layer "B.SilkS")
			(hide yes)
			(effects
				(font
					(size 1.27 1.27)
				)
				(justify mirror)
			)
		)
		(property "Value" ""
			(at 0 0 0)
			(layer "B.Fab")
			(effects
				(font
					(size 1.27 1.27)
				)
				(justify mirror)
			)
		)
		(duplicate_pad_numbers_are_jumpers no)
		(fp_line
			(start 0.7874 0.4064)
			(end 0.7874 -0.4064)
			(stroke
				(width 0.1524)
				(type default)
			)
			(layer "B.SilkS")
		)
		(fp_line
			(start 0.7874 -0.4064)
			(end -0.7874 -0.4064)
			(stroke
				(width 0.1524)
				(type default)
			)
			(layer "B.SilkS")
		)
		(fp_line
			(start -0.7874 0.4064)
			(end 0.7874 0.4064)
			(stroke
				(width 0.1524)
				(type default)
			)
			(layer "B.SilkS")
		)
		(fp_line
			(start -0.7874 -0.4064)
			(end -0.7874 0.4064)
			(stroke
				(width 0.1524)
				(type default)
			)
			(layer "B.SilkS")
		)
		(fp_line
			(start 0.67945 0.3048)
			(end 0.67945 -0.305054)
			(stroke
				(width 0.1)
				(type default)
			)
			(layer "B.Fab")
		)
		(fp_line
			(start 0.67945 -0.305054)
			(end 0.12065 -0.305054)
			(stroke
				(width 0.1)
				(type default)
			)
			(layer "B.Fab")
		)
		(fp_line
			(start 0.12065 0.3048)
			(end 0.67945 0.3048)
			(stroke
				(width 0.1)
				(type default)
			)
			(layer "B.Fab")
		)
		(fp_line
			(start 0.12065 0.2794)
			(end 0.12065 0.3048)
			(stroke
				(width 0.1)
				(type default)
			)
			(layer "B.Fab")
		)
		(fp_line
			(start 0.12065 -0.2794)
			(end -0.12065 -0.2794)
			(stroke
				(width 0.1)
				(type default)
			)
			(layer "B.Fab")
		)
		(fp_line
			(start 0.12065 -0.305054)
			(end 0.12065 -0.2794)
			(stroke
				(width 0.1)
				(type default)
			)
			(layer "B.Fab")
		)
		(fp_line
			(start -0.120396 0.3048)
			(end -0.120396 0.2794)
			(stroke
				(width 0.1)
				(type default)
			)
			(layer "B.Fab")
		)
		(fp_line
			(start -0.120396 0.2794)
			(end 0.12065 0.2794)
			(stroke
				(width 0.1)
				(type default)
			)
			(layer "B.Fab")
		)
		(fp_line
			(start -0.12065 -0.2794)
			(end -0.12065 -0.3048)
			(stroke
				(width 0.1)
				(type default)
			)
			(layer "B.Fab")
		)
		(fp_line
			(start -0.12065 -0.3048)
			(end -0.67945 -0.3048)
			(stroke
				(width 0.1)
				(type default)
			)
			(layer "B.Fab")
		)
		(fp_line
			(start -0.67945 0.3048)
			(end -0.120396 0.3048)
			(stroke
				(width 0.1)
				(type default)
			)
			(layer "B.Fab")
		)
		(fp_line
			(start -0.67945 -0.3048)
			(end -0.67945 0.3048)
			(stroke
				(width 0.1)
				(type default)
			)
			(layer "B.Fab")
		)
		(pad "1" smd circle
			(at 0.40005 0)
			(size 0 0)
			(layers "B.Cu" "B.Mask" "B.Paste")
			(net "GND")
		)
		(pad "2" smd circle
			(at -0.40005 0)
			(size 0 0)
			(layers "B.Cu" "B.Mask" "B.Paste")
			(net "PUD_XTAL_CPU1_MODE1")
		)
	)
	(footprint ""
		(layer "B.Cu")
		(at 30.226 -163.261548)
		(property "Reference" "PR4257"
			(at 0 0 0)
			(layer "B.SilkS")
			(hide yes)
			(effects
				(font
					(size 1.27 1.27)
				)
				(justify mirror)
			)
		)
		(property "Value" ""
			(at 0 0 0)
			(layer "B.Fab")
			(effects
				(font
					(size 1.27 1.27)
				)
				(justify mirror)
			)
		)
		(duplicate_pad_numbers_are_jumpers no)
		(fp_line
			(start -0.7874 -0.4064)
			(end -0.7874 0.4064)
			(stroke
				(width 0.1524)
				(type default)
			)
			(layer "B.SilkS")
		)
		(fp_line
			(start -0.7874 0.4064)
			(end 0.7874 0.4064)
			(stroke
				(width 0.1524)
				(type default)
			)
			(layer "B.SilkS")
		)
		(fp_line
			(start 0.7874 -0.4064)
			(end -0.7874 -0.4064)
			(stroke
				(width 0.1524)
				(type default)
			)
			(layer "B.SilkS")
		)
		(fp_line
			(start 0.7874 0.4064)
			(end 0.7874 -0.4064)
			(stroke
				(width 0.1524)
				(type default)
			)
			(layer "B.SilkS")
		)
		(fp_line
			(start -0.67945 -0.3048)
			(end -0.67945 0.3048)
			(stroke
				(width 0.1)
				(type default)
			)
			(layer "B.Fab")
		)
		(fp_line
			(start -0.67945 0.3048)
			(end -0.120396 0.3048)
			(stroke
				(width 0.1)
				(type default)
			)
			(layer "B.Fab")
		)
		(fp_line
			(start -0.12065 -0.3048)
			(end -0.67945 -0.3048)
			(stroke
				(width 0.1)
				(type default)
			)
			(layer "B.Fab")
		)
		(fp_line
			(start -0.12065 -0.2794)
			(end -0.12065 -0.3048)
			(stroke
				(width 0.1)
				(type default)
			)
			(layer "B.Fab")
		)
		(fp_line
			(start -0.120396 0.2794)
			(end 0.12065 0.2794)
			(stroke
				(width 0.1)
				(type default)
			)
			(layer "B.Fab")
		)
		(fp_line
			(start -0.120396 0.3048)
			(end -0.120396 0.2794)
			(stroke
				(width 0.1)
				(type default)
			)
			(layer "B.Fab")
		)
		(fp_line
			(start 0.12065 -0.305054)
			(end 0.12065 -0.2794)
			(stroke
				(width 0.1)
				(type default)
			)
			(layer "B.Fab")
		)
		(fp_line
			(start 0.12065 -0.2794)
			(end -0.12065 -0.2794)
			(stroke
				(width 0.1)
				(type default)
			)
			(layer "B.Fab")
		)
		(fp_line
			(start 0.12065 0.2794)
			(end 0.12065 0.3048)
			(stroke
				(width 0.1)
				(type default)
			)
			(layer "B.Fab")
		)
		(fp_line
			(start 0.12065 0.3048)
			(end 0.67945 0.3048)
			(stroke
				(width 0.1)
				(type default)
			)
			(layer "B.Fab")
		)
		(fp_line
			(start 0.67945 -0.305054)
			(end 0.12065 -0.305054)
			(stroke
				(width 0.1)
				(type default)
			)
			(layer "B.Fab")
		)
		(fp_line
			(start 0.67945 0.3048)
			(end 0.67945 -0.305054)
			(stroke
				(width 0.1)
				(type default)
			)
			(layer "B.Fab")
		)
		(pad "1" smd circle
			(at 0.40005 0 180)
			(size 0 0)
			(layers "B.Cu" "B.Mask" "B.Paste")
			(net "NC_PVCCD_HV_CPU1_ACSP8")
		)
		(pad "2" smd circle
			(at -0.40005 0 180)
			(size 0 0)
			(layers "B.Cu" "B.Mask" "B.Paste")
			(net "GND")
		)
	)
	(footprint ""
		(layer "B.Cu")
		(at 208.56448 -35.804348 90)
		(property "Reference" "C2019"
			(at 0 0 90)
			(layer "B.SilkS")
			(hide yes)
			(effects
				(font
					(size 1.27 1.27)
				)
				(justify mirror)
			)
		)
		(property "Value" ""
			(at 0 0 90)
			(layer "B.Fab")
			(effects
				(font
					(size 1.27 1.27)
				)
				(justify mirror)
			)
		)
		(duplicate_pad_numbers_are_jumpers no)
		(fp_line
			(start 0.7874 -0.4064)
			(end -0.7874 -0.4064)
			(stroke
				(width 0.1524)
				(type default)
			)
			(layer "B.SilkS")
		)
		(fp_line
			(start -0.7874 -0.4064)
			(end -0.7874 0.4064)
			(stroke
				(width 0.1524)
				(type default)
			)
			(layer "B.SilkS")
		)
		(fp_line
			(start 0.7874 0.4064)
			(end 0.7874 -0.4064)
			(stroke
				(width 0.1524)
				(type default)
			)
			(layer "B.SilkS")
		)
		(fp_line
			(start -0.7874 0.4064)
			(end 0.7874 0.4064)
			(stroke
				(width 0.1524)
				(type default)
			)
			(layer "B.SilkS")
		)
		(fp_line
			(start 0.67945 -0.305054)
			(end 0.12065 -0.305054)
			(stroke
				(width 0.1)
				(type default)
			)
			(layer "B.Fab")
		)
		(fp_line
			(start 0.12065 -0.305054)
			(end 0.12065 -0.2794)
			(stroke
				(width 0.1)
				(type default)
			)
			(layer "B.Fab")
		)
		(fp_line
			(start -0.12065 -0.3048)
			(end -0.67945 -0.3048)
			(stroke
				(width 0.1)
				(type default)
			)
			(layer "B.Fab")
		)
		(fp_line
			(start -0.67945 -0.3048)
			(end -0.67945 0.3048)
			(stroke
				(width 0.1)
				(type default)
			)
			(layer "B.Fab")
		)
		(fp_line
			(start 0.12065 -0.2794)
			(end -0.12065 -0.2794)
			(stroke
				(width 0.1)
				(type default)
			)
			(layer "B.Fab")
		)
		(fp_line
			(start -0.12065 -0.2794)
			(end -0.12065 -0.3048)
			(stroke
				(width 0.1)
				(type default)
			)
			(layer "B.Fab")
		)
		(fp_line
			(start 0.12065 0.2794)
			(end 0.12065 0.3048)
			(stroke
				(width 0.1)
				(type default)
			)
			(layer "B.Fab")
		)
		(fp_line
			(start -0.120396 0.2794)
			(end 0.12065 0.2794)
			(stroke
				(width 0.1)
				(type default)
			)
			(layer "B.Fab")
		)
		(fp_line
			(start 0.67945 0.3048)
			(end 0.67945 -0.305054)
			(stroke
				(width 0.1)
				(type default)
			)
			(layer "B.Fab")
		)
		(fp_line
			(start 0.12065 0.3048)
			(end 0.67945 0.3048)
			(stroke
				(width 0.1)
				(type default)
			)
			(layer "B.Fab")
		)
		(fp_line
			(start -0.120396 0.3048)
			(end -0.120396 0.2794)
			(stroke
				(width 0.1)
				(type default)
			)
			(layer "B.Fab")
		)
		(fp_line
			(start -0.67945 0.3048)
			(end -0.120396 0.3048)
			(stroke
				(width 0.1)
				(type default)
			)
			(layer "B.Fab")
		)
		(pad "1" smd circle
			(at 0.40005 0 270)
			(size 0 0)
			(layers "B.Cu" "B.Mask" "B.Paste")
			(net "P12V_SCM_R")
		)
		(pad "2" smd circle
			(at -0.40005 0 270)
			(size 0 0)
			(layers "B.Cu" "B.Mask" "B.Paste")
			(net "GND")
		)
	)
	(footprint ""
		(layer "B.Cu")
		(at 308.085998 -192.60947 90)
		(property "Reference" "R17"
			(at 0 0 90)
			(layer "B.SilkS")
			(hide yes)
			(effects
				(font
					(size 1.27 1.27)
				)
				(justify mirror)
			)
		)
		(property "Value" ""
			(at 0 0 90)
			(layer "B.Fab")
			(effects
				(font
					(size 1.27 1.27)
				)
				(justify mirror)
			)
		)
		(duplicate_pad_numbers_are_jumpers no)
		(fp_line
			(start 0.7874 -0.4064)
			(end -0.7874 -0.4064)
			(stroke
				(width 0.1524)
				(type default)
			)
			(layer "B.SilkS")
		)
		(fp_line
			(start -0.7874 -0.4064)
			(end -0.7874 0.4064)
			(stroke
				(width 0.1524)
				(type default)
			)
			(layer "B.SilkS")
		)
		(fp_line
			(start 0.7874 0.4064)
			(end 0.7874 -0.4064)
			(stroke
				(width 0.1524)
				(type default)
			)
			(layer "B.SilkS")
		)
		(fp_line
			(start -0.7874 0.4064)
			(end 0.7874 0.4064)
			(stroke
				(width 0.1524)
				(type default)
			)
			(layer "B.SilkS")
		)
		(fp_line
			(start 0.67945 -0.305054)
			(end 0.12065 -0.305054)
			(stroke
				(width 0.1)
				(type default)
			)
			(layer "B.Fab")
		)
		(fp_line
			(start 0.12065 -0.305054)
			(end 0.12065 -0.2794)
			(stroke
				(width 0.1)
				(type default)
			)
			(layer "B.Fab")
		)
		(fp_line
			(start -0.12065 -0.3048)
			(end -0.67945 -0.3048)
			(stroke
				(width 0.1)
				(type default)
			)
			(layer "B.Fab")
		)
		(fp_line
			(start -0.67945 -0.3048)
			(end -0.67945 0.3048)
			(stroke
				(width 0.1)
				(type default)
			)
			(layer "B.Fab")
		)
		(fp_line
			(start 0.12065 -0.2794)
			(end -0.12065 -0.2794)
			(stroke
				(width 0.1)
				(type default)
			)
			(layer "B.Fab")
		)
		(fp_line
			(start -0.12065 -0.2794)
			(end -0.12065 -0.3048)
			(stroke
				(width 0.1)
				(type default)
			)
			(layer "B.Fab")
		)
		(fp_line
			(start 0.12065 0.2794)
			(end 0.12065 0.3048)
			(stroke
				(width 0.1)
				(type default)
			)
			(layer "B.Fab")
		)
		(fp_line
			(start -0.120396 0.2794)
			(end 0.12065 0.2794)
			(stroke
				(width 0.1)
				(type default)
			)
			(layer "B.Fab")
		)
		(fp_line
			(start 0.67945 0.3048)
			(end 0.67945 -0.305054)
			(stroke
				(width 0.1)
				(type default)
			)
			(layer "B.Fab")
		)
		(fp_line
			(start 0.12065 0.3048)
			(end 0.67945 0.3048)
			(stroke
				(width 0.1)
				(type default)
			)
			(layer "B.Fab")
		)
		(fp_line
			(start -0.120396 0.3048)
			(end -0.120396 0.2794)
			(stroke
				(width 0.1)
				(type default)
			)
			(layer "B.Fab")
		)
		(fp_line
			(start -0.67945 0.3048)
			(end -0.120396 0.3048)
			(stroke
				(width 0.1)
				(type default)
			)
			(layer "B.Fab")
		)
		(pad "1" smd circle
			(at 0.40005 0 270)
			(size 0 0)
			(layers "B.Cu" "B.Mask" "B.Paste")
			(net "SVID_ALERT1_CPU0_N")
		)
		(pad "2" smd circle
			(at -0.40005 0 270)
			(size 0 0)
			(layers "B.Cu" "B.Mask" "B.Paste")
			(net "SVID_ALERT1_CPU0_R_N")
		)
	)
	(footprint ""
		(layer "B.Cu")
		(at 235.23448 -423.001948 90)
		(property "Reference" "C2295"
			(at 0 0 90)
			(layer "B.SilkS")
			(hide yes)
			(effects
				(font
					(size 1.27 1.27)
				)
				(justify mirror)
			)
		)
		(property "Value" ""
			(at 0 0 90)
			(layer "B.Fab")
			(effects
				(font
					(size 1.27 1.27)
				)
				(justify mirror)
			)
		)
		(duplicate_pad_numbers_are_jumpers no)
		(fp_line
			(start 0.7874 -0.4064)
			(end -0.7874 -0.4064)
			(stroke
				(width 0.1524)
				(type default)
			)
			(layer "B.SilkS")
		)
		(fp_line
			(start -0.7874 -0.4064)
			(end -0.7874 0.4064)
			(stroke
				(width 0.1524)
				(type default)
			)
			(layer "B.SilkS")
		)
		(fp_line
			(start 0.7874 0.4064)
			(end 0.7874 -0.4064)
			(stroke
				(width 0.1524)
				(type default)
			)
			(layer "B.SilkS")
		)
		(fp_line
			(start -0.7874 0.4064)
			(end 0.7874 0.4064)
			(stroke
				(width 0.1524)
				(type default)
			)
			(layer "B.SilkS")
		)
		(fp_line
			(start 0.67945 -0.305054)
			(end 0.12065 -0.305054)
			(stroke
				(width 0.1)
				(type default)
			)
			(layer "B.Fab")
		)
		(fp_line
			(start 0.12065 -0.305054)
			(end 0.12065 -0.2794)
			(stroke
				(width 0.1)
				(type default)
			)
			(layer "B.Fab")
		)
		(fp_line
			(start -0.12065 -0.3048)
			(end -0.67945 -0.3048)
			(stroke
				(width 0.1)
				(type default)
			)
			(layer "B.Fab")
		)
		(fp_line
			(start -0.67945 -0.3048)
			(end -0.67945 0.3048)
			(stroke
				(width 0.1)
				(type default)
			)
			(layer "B.Fab")
		)
		(fp_line
			(start 0.12065 -0.2794)
			(end -0.12065 -0.2794)
			(stroke
				(width 0.1)
				(type default)
			)
			(layer "B.Fab")
		)
		(fp_line
			(start -0.12065 -0.2794)
			(end -0.12065 -0.3048)
			(stroke
				(width 0.1)
				(type default)
			)
			(layer "B.Fab")
		)
		(fp_line
			(start 0.12065 0.2794)
			(end 0.12065 0.3048)
			(stroke
				(width 0.1)
				(type default)
			)
			(layer "B.Fab")
		)
		(fp_line
			(start -0.120396 0.2794)
			(end 0.12065 0.2794)
			(stroke
				(width 0.1)
				(type default)
			)
			(layer "B.Fab")
		)
		(fp_line
			(start 0.67945 0.3048)
			(end 0.67945 -0.305054)
			(stroke
				(width 0.1)
				(type default)
			)
			(layer "B.Fab")
		)
		(fp_line
			(start 0.12065 0.3048)
			(end 0.67945 0.3048)
			(stroke
				(width 0.1)
				(type default)
			)
			(layer "B.Fab")
		)
		(fp_line
			(start -0.120396 0.3048)
			(end -0.120396 0.2794)
			(stroke
				(width 0.1)
				(type default)
			)
			(layer "B.Fab")
		)
		(fp_line
			(start -0.67945 0.3048)
			(end -0.120396 0.3048)
			(stroke
				(width 0.1)
				(type default)
			)
			(layer "B.Fab")
		)
		(pad "1" smd circle
			(at 0.40005 0 270)
			(size 0 0)
			(layers "B.Cu" "B.Mask" "B.Paste")
			(net "HPDB_HSC_PWRGD_R")
		)
		(pad "2" smd circle
			(at -0.40005 0 270)
			(size 0 0)
			(layers "B.Cu" "B.Mask" "B.Paste")
			(net "GND")
		)
	)
	(footprint ""
		(layer "B.Cu")
		(at 163.66109 -318.717422 90)
		(property "Reference" "R902"
			(at 0 0 90)
			(layer "B.SilkS")
			(hide yes)
			(effects
				(font
					(size 1.27 1.27)
				)
				(justify mirror)
			)
		)
		(property "Value" ""
			(at 0 0 90)
			(layer "B.Fab")
			(effects
				(font
					(size 1.27 1.27)
				)
				(justify mirror)
			)
		)
		(duplicate_pad_numbers_are_jumpers no)
		(fp_line
			(start 0.7874 -0.4064)
			(end -0.7874 -0.4064)
			(stroke
				(width 0.1524)
				(type default)
			)
			(layer "B.SilkS")
		)
		(fp_line
			(start -0.7874 -0.4064)
			(end -0.7874 0.4064)
			(stroke
				(width 0.1524)
				(type default)
			)
			(layer "B.SilkS")
		)
		(fp_line
			(start 0.7874 0.4064)
			(end 0.7874 -0.4064)
			(stroke
				(width 0.1524)
				(type default)
			)
			(layer "B.SilkS")
		)
		(fp_line
			(start -0.7874 0.4064)
			(end 0.7874 0.4064)
			(stroke
				(width 0.1524)
				(type default)
			)
			(layer "B.SilkS")
		)
		(fp_line
			(start 0.67945 -0.305054)
			(end 0.12065 -0.305054)
			(stroke
				(width 0.1)
				(type default)
			)
			(layer "B.Fab")
		)
		(fp_line
			(start 0.12065 -0.305054)
			(end 0.12065 -0.2794)
			(stroke
				(width 0.1)
				(type default)
			)
			(layer "B.Fab")
		)
		(fp_line
			(start -0.12065 -0.3048)
			(end -0.67945 -0.3048)
			(stroke
				(width 0.1)
				(type default)
			)
			(layer "B.Fab")
		)
		(fp_line
			(start -0.67945 -0.3048)
			(end -0.67945 0.3048)
			(stroke
				(width 0.1)
				(type default)
			)
			(layer "B.Fab")
		)
		(fp_line
			(start 0.12065 -0.2794)
			(end -0.12065 -0.2794)
			(stroke
				(width 0.1)
				(type default)
			)
			(layer "B.Fab")
		)
		(fp_line
			(start -0.12065 -0.2794)
			(end -0.12065 -0.3048)
			(stroke
				(width 0.1)
				(type default)
			)
			(layer "B.Fab")
		)
		(fp_line
			(start 0.12065 0.2794)
			(end 0.12065 0.3048)
			(stroke
				(width 0.1)
				(type default)
			)
			(layer "B.Fab")
		)
		(fp_line
			(start -0.120396 0.2794)
			(end 0.12065 0.2794)
			(stroke
				(width 0.1)
				(type default)
			)
			(layer "B.Fab")
		)
		(fp_line
			(start 0.67945 0.3048)
			(end 0.67945 -0.305054)
			(stroke
				(width 0.1)
				(type default)
			)
			(layer "B.Fab")
		)
		(fp_line
			(start 0.12065 0.3048)
			(end 0.67945 0.3048)
			(stroke
				(width 0.1)
				(type default)
			)
			(layer "B.Fab")
		)
		(fp_line
			(start -0.120396 0.3048)
			(end -0.120396 0.2794)
			(stroke
				(width 0.1)
				(type default)
			)
			(layer "B.Fab")
		)
		(fp_line
			(start -0.67945 0.3048)
			(end -0.120396 0.3048)
			(stroke
				(width 0.1)
				(type default)
			)
			(layer "B.Fab")
		)
		(pad "1" smd circle
			(at 0.40005 0 270)
			(size 0 0)
			(layers "B.Cu" "B.Mask" "B.Paste")
			(net "PWRGD_CHE_CPU1_DIMM2")
		)
		(pad "2" smd circle
			(at -0.40005 0 270)
			(size 0 0)
			(layers "B.Cu" "B.Mask" "B.Paste")
			(net "PWRGD_FAIL_CPU1_EF")
		)
	)
	(footprint ""
		(layer "B.Cu")
		(at 429.14951 -353.05111 -90)
		(property "Reference" "PC1183_P0_3"
			(at 0 0 90)
			(layer "B.SilkS")
			(hide yes)
			(effects
				(font
					(size 1.27 1.27)
				)
				(justify mirror)
			)
		)
		(property "Value" ""
			(at 0 0 90)
			(layer "B.Fab")
			(effects
				(font
					(size 1.27 1.27)
				)
				(justify mirror)
			)
		)
		(duplicate_pad_numbers_are_jumpers no)
		(fp_line
			(start -0.7874 0.4064)
			(end 0.7874 0.4064)
			(stroke
				(width 0.1524)
				(type default)
			)
			(layer "B.SilkS")
		)
		(fp_line
			(start 0.7874 0.4064)
			(end 0.7874 -0.4064)
			(stroke
				(width 0.1524)
				(type default)
			)
			(layer "B.SilkS")
		)
		(fp_line
			(start -0.7874 -0.4064)
			(end -0.7874 0.4064)
			(stroke
				(width 0.1524)
				(type default)
			)
			(layer "B.SilkS")
		)
		(fp_line
			(start 0.7874 -0.4064)
			(end -0.7874 -0.4064)
			(stroke
				(width 0.1524)
				(type default)
			)
			(layer "B.SilkS")
		)
		(fp_line
			(start -0.67945 0.3048)
			(end -0.120396 0.3048)
			(stroke
				(width 0.1)
				(type default)
			)
			(layer "B.Fab")
		)
		(fp_line
			(start -0.120396 0.3048)
			(end -0.120396 0.2794)
			(stroke
				(width 0.1)
				(type default)
			)
			(layer "B.Fab")
		)
		(fp_line
			(start 0.12065 0.3048)
			(end 0.67945 0.3048)
			(stroke
				(width 0.1)
				(type default)
			)
			(layer "B.Fab")
		)
		(fp_line
			(start 0.67945 0.3048)
			(end 0.67945 -0.305054)
			(stroke
				(width 0.1)
				(type default)
			)
			(layer "B.Fab")
		)
		(fp_line
			(start -0.120396 0.2794)
			(end 0.12065 0.2794)
			(stroke
				(width 0.1)
				(type default)
			)
			(layer "B.Fab")
		)
		(fp_line
			(start 0.12065 0.2794)
			(end 0.12065 0.3048)
			(stroke
				(width 0.1)
				(type default)
			)
			(layer "B.Fab")
		)
		(fp_line
			(start -0.12065 -0.2794)
			(end -0.12065 -0.3048)
			(stroke
				(width 0.1)
				(type default)
			)
			(layer "B.Fab")
		)
		(fp_line
			(start 0.12065 -0.2794)
			(end -0.12065 -0.2794)
			(stroke
				(width 0.1)
				(type default)
			)
			(layer "B.Fab")
		)
		(fp_line
			(start -0.67945 -0.3048)
			(end -0.67945 0.3048)
			(stroke
				(width 0.1)
				(type default)
			)
			(layer "B.Fab")
		)
		(fp_line
			(start -0.12065 -0.3048)
			(end -0.67945 -0.3048)
			(stroke
				(width 0.1)
				(type default)
			)
			(layer "B.Fab")
		)
		(fp_line
			(start 0.12065 -0.305054)
			(end 0.12065 -0.2794)
			(stroke
				(width 0.1)
				(type default)
			)
			(layer "B.Fab")
		)
		(fp_line
			(start 0.67945 -0.305054)
			(end 0.12065 -0.305054)
			(stroke
				(width 0.1)
				(type default)
			)
			(layer "B.Fab")
		)
		(pad "1" smd circle
			(at 0.40005 0 90)
			(size 0 0)
			(layers "B.Cu" "B.Mask" "B.Paste")
			(net "PVCCFA_EHV_FIVRA_CPU0")
		)
		(pad "2" smd circle
			(at -0.40005 0 90)
			(size 0 0)
			(layers "B.Cu" "B.Mask" "B.Paste")
			(net "GND")
		)
	)
	(footprint ""
		(layer "B.Cu")
		(at 353.610418 -294.009826)
		(property "Reference" "C369"
			(at 0 0 0)
			(layer "B.SilkS")
			(hide yes)
			(effects
				(font
					(size 1.27 1.27)
				)
				(justify mirror)
			)
		)
		(property "Value" ""
			(at 0 0 0)
			(layer "B.Fab")
			(effects
				(font
					(size 1.27 1.27)
				)
				(justify mirror)
			)
		)
		(duplicate_pad_numbers_are_jumpers no)
		(fp_line
			(start -1.524 -0.762)
			(end -1.524 0.762)
			(stroke
				(width 0.1524)
				(type default)
			)
			(layer "B.SilkS")
		)
		(fp_line
			(start -1.524 0.762)
			(end 1.524 0.762)
			(stroke
				(width 0.1524)
				(type default)
			)
			(layer "B.SilkS")
		)
		(fp_line
			(start 1.524 -0.762)
			(end -1.524 -0.762)
			(stroke
				(width 0.1524)
				(type default)
			)
			(layer "B.SilkS")
		)
		(fp_line
			(start 1.524 0.762)
			(end 1.524 -0.762)
			(stroke
				(width 0.1524)
				(type default)
			)
			(layer "B.SilkS")
		)
		(fp_line
			(start -1.1049 -0.724916)
			(end 1.1049 -0.724916)
			(stroke
				(width 0.1)
				(type default)
			)
			(layer "B.Fab")
		)
		(fp_line
			(start -1.1049 0.724916)
			(end -1.1049 -0.724916)
			(stroke
				(width 0.1)
				(type default)
			)
			(layer "B.Fab")
		)
		(fp_line
			(start 1.1049 -0.724916)
			(end 1.1049 0.724916)
			(stroke
				(width 0.1)
				(type default)
			)
			(layer "B.Fab")
		)
		(fp_line
			(start 1.1049 0.724916)
			(end -1.1049 0.724916)
			(stroke
				(width 0.1)
				(type default)
			)
			(layer "B.Fab")
		)
		(pad "1" smd rect
			(at 0.889 0)
			(size 1.016 1.27)
			(layers "B.Cu" "B.Mask" "B.Paste")
			(net "PVCCIN_CPU0")
		)
		(pad "2" smd rect
			(at -0.889 0)
			(size 1.016 1.27)
			(layers "B.Cu" "B.Mask" "B.Paste")
			(net "GND")
		)
	)
	(footprint ""
		(layer "B.Cu")
		(at 236.925612 -250.480322)
		(property "Reference" "C1889"
			(at 0 0 0)
			(layer "B.SilkS")
			(hide yes)
			(effects
				(font
					(size 1.27 1.27)
				)
				(justify mirror)
			)
		)
		(property "Value" ""
			(at 0 0 0)
			(layer "B.Fab")
			(effects
				(font
					(size 1.27 1.27)
				)
				(justify mirror)
			)
		)
		(duplicate_pad_numbers_are_jumpers no)
		(fp_line
			(start -0.7874 -0.4064)
			(end -0.7874 0.4064)
			(stroke
				(width 0.1524)
				(type default)
			)
			(layer "B.SilkS")
		)
		(fp_line
			(start -0.7874 0.4064)
			(end 0.7874 0.4064)
			(stroke
				(width 0.1524)
				(type default)
			)
			(layer "B.SilkS")
		)
		(fp_line
			(start 0.7874 -0.4064)
			(end -0.7874 -0.4064)
			(stroke
				(width 0.1524)
				(type default)
			)
			(layer "B.SilkS")
		)
		(fp_line
			(start 0.7874 0.4064)
			(end 0.7874 -0.4064)
			(stroke
				(width 0.1524)
				(type default)
			)
			(layer "B.SilkS")
		)
		(fp_line
			(start -0.67945 -0.3048)
			(end -0.67945 0.3048)
			(stroke
				(width 0.1)
				(type default)
			)
			(layer "B.Fab")
		)
		(fp_line
			(start -0.67945 0.3048)
			(end -0.120396 0.3048)
			(stroke
				(width 0.1)
				(type default)
			)
			(layer "B.Fab")
		)
		(fp_line
			(start -0.12065 -0.3048)
			(end -0.67945 -0.3048)
			(stroke
				(width 0.1)
				(type default)
			)
			(layer "B.Fab")
		)
		(fp_line
			(start -0.12065 -0.2794)
			(end -0.12065 -0.3048)
			(stroke
				(width 0.1)
				(type default)
			)
			(layer "B.Fab")
		)
		(fp_line
			(start -0.120396 0.2794)
			(end 0.12065 0.2794)
			(stroke
				(width 0.1)
				(type default)
			)
			(layer "B.Fab")
		)
		(fp_line
			(start -0.120396 0.3048)
			(end -0.120396 0.2794)
			(stroke
				(width 0.1)
				(type default)
			)
			(layer "B.Fab")
		)
		(fp_line
			(start 0.12065 -0.305054)
			(end 0.12065 -0.2794)
			(stroke
				(width 0.1)
				(type default)
			)
			(layer "B.Fab")
		)
		(fp_line
			(start 0.12065 -0.2794)
			(end -0.12065 -0.2794)
			(stroke
				(width 0.1)
				(type default)
			)
			(layer "B.Fab")
		)
		(fp_line
			(start 0.12065 0.2794)
			(end 0.12065 0.3048)
			(stroke
				(width 0.1)
				(type default)
			)
			(layer "B.Fab")
		)
		(fp_line
			(start 0.12065 0.3048)
			(end 0.67945 0.3048)
			(stroke
				(width 0.1)
				(type default)
			)
			(layer "B.Fab")
		)
		(fp_line
			(start 0.67945 -0.305054)
			(end 0.12065 -0.305054)
			(stroke
				(width 0.1)
				(type default)
			)
			(layer "B.Fab")
		)
		(fp_line
			(start 0.67945 0.3048)
			(end 0.67945 -0.305054)
			(stroke
				(width 0.1)
				(type default)
			)
			(layer "B.Fab")
		)
		(pad "1" smd circle
			(at 0.40005 0 180)
			(size 0 0)
			(layers "B.Cu" "B.Mask" "B.Paste")
			(net "VFG3P3_CLK_GEN")
		)
		(pad "2" smd circle
			(at -0.40005 0 180)
			(size 0 0)
			(layers "B.Cu" "B.Mask" "B.Paste")
			(net "GND")
		)
	)
	(footprint ""
		(layer "B.Cu")
		(at 358.80675 -359.47985)
		(property "Reference" "PR158"
			(at 0 0 0)
			(layer "B.SilkS")
			(hide yes)
			(effects
				(font
					(size 1.27 1.27)
				)
				(justify mirror)
			)
		)
		(property "Value" ""
			(at 0 0 0)
			(layer "B.Fab")
			(effects
				(font
					(size 1.27 1.27)
				)
				(justify mirror)
			)
		)
		(duplicate_pad_numbers_are_jumpers no)
		(fp_line
			(start -0.7874 -0.4064)
			(end -0.7874 0.4064)
			(stroke
				(width 0.1524)
				(type default)
			)
			(layer "B.SilkS")
		)
		(fp_line
			(start -0.7874 0.4064)
			(end 0.7874 0.4064)
			(stroke
				(width 0.1524)
				(type default)
			)
			(layer "B.SilkS")
		)
		(fp_line
			(start 0.7874 -0.4064)
			(end -0.7874 -0.4064)
			(stroke
				(width 0.1524)
				(type default)
			)
			(layer "B.SilkS")
		)
		(fp_line
			(start 0.7874 0.4064)
			(end 0.7874 -0.4064)
			(stroke
				(width 0.1524)
				(type default)
			)
			(layer "B.SilkS")
		)
		(fp_line
			(start -0.67945 -0.3048)
			(end -0.67945 0.3048)
			(stroke
				(width 0.1)
				(type default)
			)
			(layer "B.Fab")
		)
		(fp_line
			(start -0.67945 0.3048)
			(end -0.120396 0.3048)
			(stroke
				(width 0.1)
				(type default)
			)
			(layer "B.Fab")
		)
		(fp_line
			(start -0.12065 -0.3048)
			(end -0.67945 -0.3048)
			(stroke
				(width 0.1)
				(type default)
			)
			(layer "B.Fab")
		)
		(fp_line
			(start -0.12065 -0.2794)
			(end -0.12065 -0.3048)
			(stroke
				(width 0.1)
				(type default)
			)
			(layer "B.Fab")
		)
		(fp_line
			(start -0.120396 0.2794)
			(end 0.12065 0.2794)
			(stroke
				(width 0.1)
				(type default)
			)
			(layer "B.Fab")
		)
		(fp_line
			(start -0.120396 0.3048)
			(end -0.120396 0.2794)
			(stroke
				(width 0.1)
				(type default)
			)
			(layer "B.Fab")
		)
		(fp_line
			(start 0.12065 -0.305054)
			(end 0.12065 -0.2794)
			(stroke
				(width 0.1)
				(type default)
			)
			(layer "B.Fab")
		)
		(fp_line
			(start 0.12065 -0.2794)
			(end -0.12065 -0.2794)
			(stroke
				(width 0.1)
				(type default)
			)
			(layer "B.Fab")
		)
		(fp_line
			(start 0.12065 0.2794)
			(end 0.12065 0.3048)
			(stroke
				(width 0.1)
				(type default)
			)
			(layer "B.Fab")
		)
		(fp_line
			(start 0.12065 0.3048)
			(end 0.67945 0.3048)
			(stroke
				(width 0.1)
				(type default)
			)
			(layer "B.Fab")
		)
		(fp_line
			(start 0.67945 -0.305054)
			(end 0.12065 -0.305054)
			(stroke
				(width 0.1)
				(type default)
			)
			(layer "B.Fab")
		)
		(fp_line
			(start 0.67945 0.3048)
			(end 0.67945 -0.305054)
			(stroke
				(width 0.1)
				(type default)
			)
			(layer "B.Fab")
		)
		(pad "1" smd circle
			(at 0.40005 0 180)
			(size 0 0)
			(layers "B.Cu" "B.Mask" "B.Paste")
			(net "PVCCIN_CPU0_CSPIN")
		)
		(pad "2" smd circle
			(at -0.40005 0 180)
			(size 0 0)
			(layers "B.Cu" "B.Mask" "B.Paste")
			(net "GND")
		)
	)
	(footprint ""
		(layer "B.Cu")
		(at 433.461414 -321.549776 -90)
		(property "Reference" "C34"
			(at 0 0 90)
			(layer "B.SilkS")
			(hide yes)
			(effects
				(font
					(size 1.27 1.27)
				)
				(justify mirror)
			)
		)
		(property "Value" ""
			(at 0 0 90)
			(layer "B.Fab")
			(effects
				(font
					(size 1.27 1.27)
				)
				(justify mirror)
			)
		)
		(duplicate_pad_numbers_are_jumpers no)
		(fp_line
			(start -1.524 0.762)
			(end 1.524 0.762)
			(stroke
				(width 0.1524)
				(type default)
			)
			(layer "B.SilkS")
		)
		(fp_line
			(start 1.524 0.762)
			(end 1.524 -0.762)
			(stroke
				(width 0.1524)
				(type default)
			)
			(layer "B.SilkS")
		)
		(fp_line
			(start -1.524 -0.762)
			(end -1.524 0.762)
			(stroke
				(width 0.1524)
				(type default)
			)
			(layer "B.SilkS")
		)
		(fp_line
			(start 1.524 -0.762)
			(end -1.524 -0.762)
			(stroke
				(width 0.1524)
				(type default)
			)
			(layer "B.SilkS")
		)
		(fp_line
			(start -1.1049 0.724916)
			(end -1.1049 -0.724916)
			(stroke
				(width 0.1)
				(type default)
			)
			(layer "B.Fab")
		)
		(fp_line
			(start 1.1049 0.724916)
			(end -1.1049 0.724916)
			(stroke
				(width 0.1)
				(type default)
			)
			(layer "B.Fab")
		)
		(fp_line
			(start -1.1049 -0.724916)
			(end 1.1049 -0.724916)
			(stroke
				(width 0.1)
				(type default)
			)
			(layer "B.Fab")
		)
		(fp_line
			(start 1.1049 -0.724916)
			(end 1.1049 0.724916)
			(stroke
				(width 0.1)
				(type default)
			)
			(layer "B.Fab")
		)
		(pad "1" smd rect
			(at 0.889 0 270)
			(size 1.016 1.27)
			(layers "B.Cu" "B.Mask" "B.Paste")
			(net "P12V_S3_AUX_CPU0_NVDIMM")
		)
		(pad "2" smd rect
			(at -0.889 0 270)
			(size 1.016 1.27)
			(layers "B.Cu" "B.Mask" "B.Paste")
			(net "GND")
		)
	)
	(footprint ""
		(layer "B.Cu")
		(at 369.055142 -357.667306 180)
		(property "Reference" "PC1421"
			(at 0 0 0)
			(layer "B.SilkS")
			(hide yes)
			(effects
				(font
					(size 1.27 1.27)
				)
				(justify mirror)
			)
		)
		(property "Value" ""
			(at 0 0 0)
			(layer "B.Fab")
			(effects
				(font
					(size 1.27 1.27)
				)
				(justify mirror)
			)
		)
		(duplicate_pad_numbers_are_jumpers no)
		(fp_line
			(start 0.7874 0.4064)
			(end 0.7874 -0.4064)
			(stroke
				(width 0.1524)
				(type default)
			)
			(layer "B.SilkS")
		)
		(fp_line
			(start 0.7874 -0.4064)
			(end -0.7874 -0.4064)
			(stroke
				(width 0.1524)
				(type default)
			)
			(layer "B.SilkS")
		)
		(fp_line
			(start -0.7874 0.4064)
			(end 0.7874 0.4064)
			(stroke
				(width 0.1524)
				(type default)
			)
			(layer "B.SilkS")
		)
		(fp_line
			(start -0.7874 -0.4064)
			(end -0.7874 0.4064)
			(stroke
				(width 0.1524)
				(type default)
			)
			(layer "B.SilkS")
		)
		(fp_line
			(start 0.67945 0.3048)
			(end 0.67945 -0.305054)
			(stroke
				(width 0.1)
				(type default)
			)
			(layer "B.Fab")
		)
		(fp_line
			(start 0.67945 -0.305054)
			(end 0.12065 -0.305054)
			(stroke
				(width 0.1)
				(type default)
			)
			(layer "B.Fab")
		)
		(fp_line
			(start 0.12065 0.3048)
			(end 0.67945 0.3048)
			(stroke
				(width 0.1)
				(type default)
			)
			(layer "B.Fab")
		)
		(fp_line
			(start 0.12065 0.2794)
			(end 0.12065 0.3048)
			(stroke
				(width 0.1)
				(type default)
			)
			(layer "B.Fab")
		)
		(fp_line
			(start 0.12065 -0.2794)
			(end -0.12065 -0.2794)
			(stroke
				(width 0.1)
				(type default)
			)
			(layer "B.Fab")
		)
		(fp_line
			(start 0.12065 -0.305054)
			(end 0.12065 -0.2794)
			(stroke
				(width 0.1)
				(type default)
			)
			(layer "B.Fab")
		)
		(fp_line
			(start -0.120396 0.3048)
			(end -0.120396 0.2794)
			(stroke
				(width 0.1)
				(type default)
			)
			(layer "B.Fab")
		)
		(fp_line
			(start -0.120396 0.2794)
			(end 0.12065 0.2794)
			(stroke
				(width 0.1)
				(type default)
			)
			(layer "B.Fab")
		)
		(fp_line
			(start -0.12065 -0.2794)
			(end -0.12065 -0.3048)
			(stroke
				(width 0.1)
				(type default)
			)
			(layer "B.Fab")
		)
		(fp_line
			(start -0.12065 -0.3048)
			(end -0.67945 -0.3048)
			(stroke
				(width 0.1)
				(type default)
			)
			(layer "B.Fab")
		)
		(fp_line
			(start -0.67945 0.3048)
			(end -0.120396 0.3048)
			(stroke
				(width 0.1)
				(type default)
			)
			(layer "B.Fab")
		)
		(fp_line
			(start -0.67945 -0.3048)
			(end -0.67945 0.3048)
			(stroke
				(width 0.1)
				(type default)
			)
			(layer "B.Fab")
		)
		(pad "1" smd circle
			(at 0.40005 0)
			(size 0 0)
			(layers "B.Cu" "B.Mask" "B.Paste")
			(net "SH_PVPP_HBM_CPU0_P")
		)
		(pad "2" smd circle
			(at -0.40005 0)
			(size 0 0)
			(layers "B.Cu" "B.Mask" "B.Paste")
			(net "SH_PVPP_HBM_CPU0_N")
		)
	)
	(footprint ""
		(layer "B.Cu")
		(at 53.912516 -145.445226)
		(property "Reference" "PR255"
			(at 0 0 0)
			(layer "B.SilkS")
			(hide yes)
			(effects
				(font
					(size 1.27 1.27)
				)
				(justify mirror)
			)
		)
		(property "Value" ""
			(at 0 0 0)
			(layer "B.Fab")
			(effects
				(font
					(size 1.27 1.27)
				)
				(justify mirror)
			)
		)
		(duplicate_pad_numbers_are_jumpers no)
		(fp_line
			(start -0.7874 -0.4064)
			(end -0.7874 0.4064)
			(stroke
				(width 0.1524)
				(type default)
			)
			(layer "B.SilkS")
		)
		(fp_line
			(start -0.7874 0.4064)
			(end 0.7874 0.4064)
			(stroke
				(width 0.1524)
				(type default)
			)
			(layer "B.SilkS")
		)
		(fp_line
			(start 0.7874 -0.4064)
			(end -0.7874 -0.4064)
			(stroke
				(width 0.1524)
				(type default)
			)
			(layer "B.SilkS")
		)
		(fp_line
			(start 0.7874 0.4064)
			(end 0.7874 -0.4064)
			(stroke
				(width 0.1524)
				(type default)
			)
			(layer "B.SilkS")
		)
		(fp_line
			(start -0.67945 -0.3048)
			(end -0.67945 0.3048)
			(stroke
				(width 0.1)
				(type default)
			)
			(layer "B.Fab")
		)
		(fp_line
			(start -0.67945 0.3048)
			(end -0.120396 0.3048)
			(stroke
				(width 0.1)
				(type default)
			)
			(layer "B.Fab")
		)
		(fp_line
			(start -0.12065 -0.3048)
			(end -0.67945 -0.3048)
			(stroke
				(width 0.1)
				(type default)
			)
			(layer "B.Fab")
		)
		(fp_line
			(start -0.12065 -0.2794)
			(end -0.12065 -0.3048)
			(stroke
				(width 0.1)
				(type default)
			)
			(layer "B.Fab")
		)
		(fp_line
			(start -0.120396 0.2794)
			(end 0.12065 0.2794)
			(stroke
				(width 0.1)
				(type default)
			)
			(layer "B.Fab")
		)
		(fp_line
			(start -0.120396 0.3048)
			(end -0.120396 0.2794)
			(stroke
				(width 0.1)
				(type default)
			)
			(layer "B.Fab")
		)
		(fp_line
			(start 0.12065 -0.305054)
			(end 0.12065 -0.2794)
			(stroke
				(width 0.1)
				(type default)
			)
			(layer "B.Fab")
		)
		(fp_line
			(start 0.12065 -0.2794)
			(end -0.12065 -0.2794)
			(stroke
				(width 0.1)
				(type default)
			)
			(layer "B.Fab")
		)
		(fp_line
			(start 0.12065 0.2794)
			(end 0.12065 0.3048)
			(stroke
				(width 0.1)
				(type default)
			)
			(layer "B.Fab")
		)
		(fp_line
			(start 0.12065 0.3048)
			(end 0.67945 0.3048)
			(stroke
				(width 0.1)
				(type default)
			)
			(layer "B.Fab")
		)
		(fp_line
			(start 0.67945 -0.305054)
			(end 0.12065 -0.305054)
			(stroke
				(width 0.1)
				(type default)
			)
			(layer "B.Fab")
		)
		(fp_line
			(start 0.67945 0.3048)
			(end 0.67945 -0.305054)
			(stroke
				(width 0.1)
				(type default)
			)
			(layer "B.Fab")
		)
		(pad "1" smd circle
			(at 0.40005 0 180)
			(size 0 0)
			(layers "B.Cu" "B.Mask" "B.Paste")
			(net "PVCCFA_EHV_CPU1_PVCC")
		)
		(pad "2" smd circle
			(at -0.40005 0 180)
			(size 0 0)
			(layers "B.Cu" "B.Mask" "B.Paste")
			(net "PVCCINFAON_CPU1_VDD2")
		)
	)
	(footprint ""
		(layer "B.Cu")
		(at 310.957214 -258.379976 -90)
		(property "Reference" "C523"
			(at 0 0 90)
			(layer "B.SilkS")
			(hide yes)
			(effects
				(font
					(size 1.27 1.27)
				)
				(justify mirror)
			)
		)
		(property "Value" ""
			(at 0 0 90)
			(layer "B.Fab")
			(effects
				(font
					(size 1.27 1.27)
				)
				(justify mirror)
			)
		)
		(duplicate_pad_numbers_are_jumpers no)
		(fp_line
			(start -1.524 0.762)
			(end 1.524 0.762)
			(stroke
				(width 0.1524)
				(type default)
			)
			(layer "B.SilkS")
		)
		(fp_line
			(start 1.524 0.762)
			(end 1.524 -0.762)
			(stroke
				(width 0.1524)
				(type default)
			)
			(layer "B.SilkS")
		)
		(fp_line
			(start -1.524 -0.762)
			(end -1.524 0.762)
			(stroke
				(width 0.1524)
				(type default)
			)
			(layer "B.SilkS")
		)
		(fp_line
			(start 1.524 -0.762)
			(end -1.524 -0.762)
			(stroke
				(width 0.1524)
				(type default)
			)
			(layer "B.SilkS")
		)
		(fp_line
			(start -1.1049 0.724916)
			(end -1.1049 -0.724916)
			(stroke
				(width 0.1)
				(type default)
			)
			(layer "B.Fab")
		)
		(fp_line
			(start 1.1049 0.724916)
			(end -1.1049 0.724916)
			(stroke
				(width 0.1)
				(type default)
			)
			(layer "B.Fab")
		)
		(fp_line
			(start -1.1049 -0.724916)
			(end 1.1049 -0.724916)
			(stroke
				(width 0.1)
				(type default)
			)
			(layer "B.Fab")
		)
		(fp_line
			(start 1.1049 -0.724916)
			(end 1.1049 0.724916)
			(stroke
				(width 0.1)
				(type default)
			)
			(layer "B.Fab")
		)
		(pad "1" smd rect
			(at 0.889 0 270)
			(size 1.016 1.27)
			(layers "B.Cu" "B.Mask" "B.Paste")
			(net "PVCCFA_EHV_FIVRA_CPU0")
		)
		(pad "2" smd rect
			(at -0.889 0 270)
			(size 1.016 1.27)
			(layers "B.Cu" "B.Mask" "B.Paste")
			(net "GND")
		)
	)
	(footprint ""
		(layer "B.Cu")
		(at 431.168556 -318.577976)
		(property "Reference" "R36"
			(at 0 0 0)
			(layer "B.SilkS")
			(hide yes)
			(effects
				(font
					(size 1.27 1.27)
				)
				(justify mirror)
			)
		)
		(property "Value" ""
			(at 0 0 0)
			(layer "B.Fab")
			(effects
				(font
					(size 1.27 1.27)
				)
				(justify mirror)
			)
		)
		(duplicate_pad_numbers_are_jumpers no)
		(fp_line
			(start -0.7874 -0.4064)
			(end -0.7874 0.4064)
			(stroke
				(width 0.1524)
				(type default)
			)
			(layer "B.SilkS")
		)
		(fp_line
			(start -0.7874 0.4064)
			(end 0.7874 0.4064)
			(stroke
				(width 0.1524)
				(type default)
			)
			(layer "B.SilkS")
		)
		(fp_line
			(start 0.7874 -0.4064)
			(end -0.7874 -0.4064)
			(stroke
				(width 0.1524)
				(type default)
			)
			(layer "B.SilkS")
		)
		(fp_line
			(start 0.7874 0.4064)
			(end 0.7874 -0.4064)
			(stroke
				(width 0.1524)
				(type default)
			)
			(layer "B.SilkS")
		)
		(fp_line
			(start -0.67945 -0.3048)
			(end -0.67945 0.3048)
			(stroke
				(width 0.1)
				(type default)
			)
			(layer "B.Fab")
		)
		(fp_line
			(start -0.67945 0.3048)
			(end -0.120396 0.3048)
			(stroke
				(width 0.1)
				(type default)
			)
			(layer "B.Fab")
		)
		(fp_line
			(start -0.12065 -0.3048)
			(end -0.67945 -0.3048)
			(stroke
				(width 0.1)
				(type default)
			)
			(layer "B.Fab")
		)
		(fp_line
			(start -0.12065 -0.2794)
			(end -0.12065 -0.3048)
			(stroke
				(width 0.1)
				(type default)
			)
			(layer "B.Fab")
		)
		(fp_line
			(start -0.120396 0.2794)
			(end 0.12065 0.2794)
			(stroke
				(width 0.1)
				(type default)
			)
			(layer "B.Fab")
		)
		(fp_line
			(start -0.120396 0.3048)
			(end -0.120396 0.2794)
			(stroke
				(width 0.1)
				(type default)
			)
			(layer "B.Fab")
		)
		(fp_line
			(start 0.12065 -0.305054)
			(end 0.12065 -0.2794)
			(stroke
				(width 0.1)
				(type default)
			)
			(layer "B.Fab")
		)
		(fp_line
			(start 0.12065 -0.2794)
			(end -0.12065 -0.2794)
			(stroke
				(width 0.1)
				(type default)
			)
			(layer "B.Fab")
		)
		(fp_line
			(start 0.12065 0.2794)
			(end 0.12065 0.3048)
			(stroke
				(width 0.1)
				(type default)
			)
			(layer "B.Fab")
		)
		(fp_line
			(start 0.12065 0.3048)
			(end 0.67945 0.3048)
			(stroke
				(width 0.1)
				(type default)
			)
			(layer "B.Fab")
		)
		(fp_line
			(start 0.67945 -0.305054)
			(end 0.12065 -0.305054)
			(stroke
				(width 0.1)
				(type default)
			)
			(layer "B.Fab")
		)
		(fp_line
			(start 0.67945 0.3048)
			(end 0.67945 -0.305054)
			(stroke
				(width 0.1)
				(type default)
			)
			(layer "B.Fab")
		)
		(pad "1" smd circle
			(at 0.40005 0 180)
			(size 0 0)
			(layers "B.Cu" "B.Mask" "B.Paste")
			(net "PD_CHF_CPU0_DIMM1_SAA")
		)
		(pad "2" smd circle
			(at -0.40005 0 180)
			(size 0 0)
			(layers "B.Cu" "B.Mask" "B.Paste")
			(net "GND")
		)
	)
	(footprint ""
		(layer "B.Cu")
		(at 256.286 -96.992948 -90)
		(property "Reference" "C173"
			(at 0 0 90)
			(layer "B.SilkS")
			(hide yes)
			(effects
				(font
					(size 1.27 1.27)
				)
				(justify mirror)
			)
		)
		(property "Value" ""
			(at 0 0 90)
			(layer "B.Fab")
			(effects
				(font
					(size 1.27 1.27)
				)
				(justify mirror)
			)
		)
		(duplicate_pad_numbers_are_jumpers no)
		(fp_line
			(start -0.7874 0.4064)
			(end 0.7874 0.4064)
			(stroke
				(width 0.1524)
				(type default)
			)
			(layer "B.SilkS")
		)
		(fp_line
			(start 0.7874 0.4064)
			(end 0.7874 -0.4064)
			(stroke
				(width 0.1524)
				(type default)
			)
			(layer "B.SilkS")
		)
		(fp_line
			(start -0.7874 -0.4064)
			(end -0.7874 0.4064)
			(stroke
				(width 0.1524)
				(type default)
			)
			(layer "B.SilkS")
		)
		(fp_line
			(start 0.7874 -0.4064)
			(end -0.7874 -0.4064)
			(stroke
				(width 0.1524)
				(type default)
			)
			(layer "B.SilkS")
		)
		(fp_line
			(start -0.67945 0.3048)
			(end -0.120396 0.3048)
			(stroke
				(width 0.1)
				(type default)
			)
			(layer "B.Fab")
		)
		(fp_line
			(start -0.120396 0.3048)
			(end -0.120396 0.2794)
			(stroke
				(width 0.1)
				(type default)
			)
			(layer "B.Fab")
		)
		(fp_line
			(start 0.12065 0.3048)
			(end 0.67945 0.3048)
			(stroke
				(width 0.1)
				(type default)
			)
			(layer "B.Fab")
		)
		(fp_line
			(start 0.67945 0.3048)
			(end 0.67945 -0.305054)
			(stroke
				(width 0.1)
				(type default)
			)
			(layer "B.Fab")
		)
		(fp_line
			(start -0.120396 0.2794)
			(end 0.12065 0.2794)
			(stroke
				(width 0.1)
				(type default)
			)
			(layer "B.Fab")
		)
		(fp_line
			(start 0.12065 0.2794)
			(end 0.12065 0.3048)
			(stroke
				(width 0.1)
				(type default)
			)
			(layer "B.Fab")
		)
		(fp_line
			(start -0.12065 -0.2794)
			(end -0.12065 -0.3048)
			(stroke
				(width 0.1)
				(type default)
			)
			(layer "B.Fab")
		)
		(fp_line
			(start 0.12065 -0.2794)
			(end -0.12065 -0.2794)
			(stroke
				(width 0.1)
				(type default)
			)
			(layer "B.Fab")
		)
		(fp_line
			(start -0.67945 -0.3048)
			(end -0.67945 0.3048)
			(stroke
				(width 0.1)
				(type default)
			)
			(layer "B.Fab")
		)
		(fp_line
			(start -0.12065 -0.3048)
			(end -0.67945 -0.3048)
			(stroke
				(width 0.1)
				(type default)
			)
			(layer "B.Fab")
		)
		(fp_line
			(start 0.12065 -0.305054)
			(end 0.12065 -0.2794)
			(stroke
				(width 0.1)
				(type default)
			)
			(layer "B.Fab")
		)
		(fp_line
			(start 0.67945 -0.305054)
			(end 0.12065 -0.305054)
			(stroke
				(width 0.1)
				(type default)
			)
			(layer "B.Fab")
		)
		(pad "1" smd circle
			(at 0.40005 0 90)
			(size 0 0)
			(layers "B.Cu" "B.Mask" "B.Paste")
			(net "P3V3_AUX_CLK_GEN_VDDA100M_CK440")
		)
		(pad "2" smd circle
			(at -0.40005 0 90)
			(size 0 0)
			(layers "B.Cu" "B.Mask" "B.Paste")
			(net "GND")
		)
	)
	(footprint ""
		(layer "B.Cu")
		(at 153.232104 -190.36411 90)
		(property "Reference" "R673"
			(at 0 0 90)
			(layer "B.SilkS")
			(hide yes)
			(effects
				(font
					(size 1.27 1.27)
				)
				(justify mirror)
			)
		)
		(property "Value" ""
			(at 0 0 90)
			(layer "B.Fab")
			(effects
				(font
					(size 1.27 1.27)
				)
				(justify mirror)
			)
		)
		(duplicate_pad_numbers_are_jumpers no)
		(fp_line
			(start 0.7874 -0.4064)
			(end -0.7874 -0.4064)
			(stroke
				(width 0.1524)
				(type default)
			)
			(layer "B.SilkS")
		)
		(fp_line
			(start -0.7874 -0.4064)
			(end -0.7874 0.4064)
			(stroke
				(width 0.1524)
				(type default)
			)
			(layer "B.SilkS")
		)
		(fp_line
			(start 0.7874 0.4064)
			(end 0.7874 -0.4064)
			(stroke
				(width 0.1524)
				(type default)
			)
			(layer "B.SilkS")
		)
		(fp_line
			(start -0.7874 0.4064)
			(end 0.7874 0.4064)
			(stroke
				(width 0.1524)
				(type default)
			)
			(layer "B.SilkS")
		)
		(fp_line
			(start 0.67945 -0.305054)
			(end 0.12065 -0.305054)
			(stroke
				(width 0.1)
				(type default)
			)
			(layer "B.Fab")
		)
		(fp_line
			(start 0.12065 -0.305054)
			(end 0.12065 -0.2794)
			(stroke
				(width 0.1)
				(type default)
			)
			(layer "B.Fab")
		)
		(fp_line
			(start -0.12065 -0.3048)
			(end -0.67945 -0.3048)
			(stroke
				(width 0.1)
				(type default)
			)
			(layer "B.Fab")
		)
		(fp_line
			(start -0.67945 -0.3048)
			(end -0.67945 0.3048)
			(stroke
				(width 0.1)
				(type default)
			)
			(layer "B.Fab")
		)
		(fp_line
			(start 0.12065 -0.2794)
			(end -0.12065 -0.2794)
			(stroke
				(width 0.1)
				(type default)
			)
			(layer "B.Fab")
		)
		(fp_line
			(start -0.12065 -0.2794)
			(end -0.12065 -0.3048)
			(stroke
				(width 0.1)
				(type default)
			)
			(layer "B.Fab")
		)
		(fp_line
			(start 0.12065 0.2794)
			(end 0.12065 0.3048)
			(stroke
				(width 0.1)
				(type default)
			)
			(layer "B.Fab")
		)
		(fp_line
			(start -0.120396 0.2794)
			(end 0.12065 0.2794)
			(stroke
				(width 0.1)
				(type default)
			)
			(layer "B.Fab")
		)
		(fp_line
			(start 0.67945 0.3048)
			(end 0.67945 -0.305054)
			(stroke
				(width 0.1)
				(type default)
			)
			(layer "B.Fab")
		)
		(fp_line
			(start 0.12065 0.3048)
			(end 0.67945 0.3048)
			(stroke
				(width 0.1)
				(type default)
			)
			(layer "B.Fab")
		)
		(fp_line
			(start -0.120396 0.3048)
			(end -0.120396 0.2794)
			(stroke
				(width 0.1)
				(type default)
			)
			(layer "B.Fab")
		)
		(fp_line
			(start -0.67945 0.3048)
			(end -0.120396 0.3048)
			(stroke
				(width 0.1)
				(type default)
			)
			(layer "B.Fab")
		)
		(pad "1" smd circle
			(at 0.40005 0 270)
			(size 0 0)
			(layers "B.Cu" "B.Mask" "B.Paste")
			(net "I3C_SPD_DDREFGH_CPU1_SDA")
		)
		(pad "2" smd circle
			(at -0.40005 0 270)
			(size 0 0)
			(layers "B.Cu" "B.Mask" "B.Paste")
			(net "I3C_SPD_DDREFGH_CPU1_R_SDA")
		)
	)
	(footprint ""
		(layer "B.Cu")
		(at 11.756136 -192.774824)
		(property "Reference" "U29"
			(at 1.6891 -2.880868 0)
			(unlocked yes)
			(layer "B.SilkS")
			(effects
				(font
					(size 0.7874 0.5842)
					(thickness 0.1524)
				)
				(justify left mirror)
			)
		)
		(property "Value" ""
			(at 0 0 0)
			(layer "B.Fab")
			(effects
				(font
					(size 1.27 1.27)
				)
				(justify mirror)
			)
		)
		(duplicate_pad_numbers_are_jumpers no)
		(fp_line
			(start -1.463548 -1.549908)
			(end -1.463548 1.549908)
			(stroke
				(width 0.1524)
				(type default)
			)
			(layer "B.SilkS")
		)
		(fp_line
			(start -1.463548 1.549908)
			(end 1.463548 1.549908)
			(stroke
				(width 0.1524)
				(type default)
			)
			(layer "B.SilkS")
		)
		(fp_line
			(start -0.762 -1.549908)
			(end -1.463548 -1.549908)
			(stroke
				(width 0.1524)
				(type default)
			)
			(layer "B.SilkS")
		)
		(fp_line
			(start 0 -0.762)
			(end -0.762 -1.549908)
			(stroke
				(width 0.1524)
				(type default)
			)
			(layer "B.SilkS")
		)
		(fp_line
			(start 0.787908 -1.549908)
			(end 0 -0.762)
			(stroke
				(width 0.1524)
				(type default)
			)
			(layer "B.SilkS")
		)
		(fp_line
			(start 1.463548 -1.549908)
			(end 0.787908 -1.549908)
			(stroke
				(width 0.1524)
				(type default)
			)
			(layer "B.SilkS")
		)
		(fp_line
			(start 1.463548 1.549908)
			(end 1.463548 -1.549908)
			(stroke
				(width 0.1524)
				(type default)
			)
			(layer "B.SilkS")
		)
		(fp_poly
			(pts
				(xy 3.4798 -1.359916) (xy 3.4798 -0.740156) (xy 2.86004 -1.050036)
			)
			(stroke
				(width 0)
				(type default)
			)
			(fill yes)
			(layer "B.SilkS")
		)
		(fp_line
			(start -1.549908 -1.549908)
			(end -1.549908 1.549908)
			(stroke
				(width 0.1)
				(type default)
			)
			(layer "B.Fab")
		)
		(fp_line
			(start -1.549908 1.549908)
			(end 1.549908 1.549908)
			(stroke
				(width 0.1)
				(type default)
			)
			(layer "B.Fab")
		)
		(fp_line
			(start 1.549908 -1.549908)
			(end -1.549908 -1.549908)
			(stroke
				(width 0.1)
				(type default)
			)
			(layer "B.Fab")
		)
		(fp_line
			(start 1.549908 1.549908)
			(end 1.549908 -1.549908)
			(stroke
				(width 0.1)
				(type default)
			)
			(layer "B.Fab")
		)
		(fp_poly
			(pts
				(xy 3.4798 -1.359916) (xy 2.86004 -1.050036) (xy 3.4798 -0.740156)
			)
			(stroke
				(width 0)
				(type default)
			)
			(fill yes)
			(layer "B.Fab")
		)
		(pad "1" smd rect
			(at 2.175002 -1.050036 90)
			(size 0.6096 1.1684)
			(layers "B.Cu" "B.Mask" "B.Paste")
			(net "PVNN_TERM_CPU1")
		)
		(pad "2" smd rect
			(at 2.175002 -0.32512 90)
			(size 0.4318 1.1684)
			(layers "B.Cu" "B.Mask" "B.Paste")
			(net "SMB_PEHPCPU1_GTL_R_SCL")
		)
		(pad "3" smd rect
			(at 2.175002 0.32512 90)
			(size 0.4318 1.1684)
			(layers "B.Cu" "B.Mask" "B.Paste")
			(net "SMB_PEHPCPU1_GTL_R_SDA")
		)
		(pad "4" smd rect
			(at 2.175002 1.050036 90)
			(size 0.6096 1.1684)
			(layers "B.Cu" "B.Mask" "B.Paste")
			(net "GND")
		)
		(pad "5" smd rect
			(at -2.175002 1.050036 90)
			(size 0.6096 1.1684)
			(layers "B.Cu" "B.Mask" "B.Paste")
			(net "TP_SMB_PEHPCPU1_EN")
		)
		(pad "6" smd rect
			(at -2.175002 0.32512 90)
			(size 0.4318 1.1684)
			(layers "B.Cu" "B.Mask" "B.Paste")
			(net "SMB_PEHPCPU1_LVC3_SDA_R0")
		)
		(pad "7" smd rect
			(at -2.175002 -0.32512 90)
			(size 0.4318 1.1684)
			(layers "B.Cu" "B.Mask" "B.Paste")
			(net "SMB_PEHPCPU1_LVC3_SCL_R0")
		)
		(pad "8" smd rect
			(at -2.175002 -1.050036 90)
			(size 0.6096 1.1684)
			(layers "B.Cu" "B.Mask" "B.Paste")
			(net "P3V3_AUX")
		)
	)
	(footprint ""
		(layer "B.Cu")
		(at 227.071174 -128.74625 180)
		(property "Reference" "R4516"
			(at 0 0 0)
			(layer "B.SilkS")
			(hide yes)
			(effects
				(font
					(size 1.27 1.27)
				)
				(justify mirror)
			)
		)
		(property "Value" ""
			(at 0 0 0)
			(layer "B.Fab")
			(effects
				(font
					(size 1.27 1.27)
				)
				(justify mirror)
			)
		)
		(duplicate_pad_numbers_are_jumpers no)
		(fp_line
			(start 0.7874 0.4064)
			(end 0.7874 -0.4064)
			(stroke
				(width 0.1524)
				(type default)
			)
			(layer "B.SilkS")
		)
		(fp_line
			(start 0.7874 -0.4064)
			(end -0.7874 -0.4064)
			(stroke
				(width 0.1524)
				(type default)
			)
			(layer "B.SilkS")
		)
		(fp_line
			(start -0.7874 0.4064)
			(end 0.7874 0.4064)
			(stroke
				(width 0.1524)
				(type default)
			)
			(layer "B.SilkS")
		)
		(fp_line
			(start -0.7874 -0.4064)
			(end -0.7874 0.4064)
			(stroke
				(width 0.1524)
				(type default)
			)
			(layer "B.SilkS")
		)
		(fp_line
			(start 0.67945 0.3048)
			(end 0.67945 -0.305054)
			(stroke
				(width 0.1)
				(type default)
			)
			(layer "B.Fab")
		)
		(fp_line
			(start 0.67945 -0.305054)
			(end 0.12065 -0.305054)
			(stroke
				(width 0.1)
				(type default)
			)
			(layer "B.Fab")
		)
		(fp_line
			(start 0.12065 0.3048)
			(end 0.67945 0.3048)
			(stroke
				(width 0.1)
				(type default)
			)
			(layer "B.Fab")
		)
		(fp_line
			(start 0.12065 0.2794)
			(end 0.12065 0.3048)
			(stroke
				(width 0.1)
				(type default)
			)
			(layer "B.Fab")
		)
		(fp_line
			(start 0.12065 -0.2794)
			(end -0.12065 -0.2794)
			(stroke
				(width 0.1)
				(type default)
			)
			(layer "B.Fab")
		)
		(fp_line
			(start 0.12065 -0.305054)
			(end 0.12065 -0.2794)
			(stroke
				(width 0.1)
				(type default)
			)
			(layer "B.Fab")
		)
		(fp_line
			(start -0.120396 0.3048)
			(end -0.120396 0.2794)
			(stroke
				(width 0.1)
				(type default)
			)
			(layer "B.Fab")
		)
		(fp_line
			(start -0.120396 0.2794)
			(end 0.12065 0.2794)
			(stroke
				(width 0.1)
				(type default)
			)
			(layer "B.Fab")
		)
		(fp_line
			(start -0.12065 -0.2794)
			(end -0.12065 -0.3048)
			(stroke
				(width 0.1)
				(type default)
			)
			(layer "B.Fab")
		)
		(fp_line
			(start -0.12065 -0.3048)
			(end -0.67945 -0.3048)
			(stroke
				(width 0.1)
				(type default)
			)
			(layer "B.Fab")
		)
		(fp_line
			(start -0.67945 0.3048)
			(end -0.120396 0.3048)
			(stroke
				(width 0.1)
				(type default)
			)
			(layer "B.Fab")
		)
		(fp_line
			(start -0.67945 -0.3048)
			(end -0.67945 0.3048)
			(stroke
				(width 0.1)
				(type default)
			)
			(layer "B.Fab")
		)
		(pad "1" smd circle
			(at 0.40005 0)
			(size 0 0)
			(layers "B.Cu" "B.Mask" "B.Paste")
			(net "P3V3")
		)
		(pad "2" smd circle
			(at -0.40005 0)
			(size 0 0)
			(layers "B.Cu" "B.Mask" "B.Paste")
			(net "CLK_SWB_OE_N")
		)
	)
	(footprint ""
		(layer "B.Cu")
		(at 12.076684 -112.319308 -90)
		(property "Reference" "U5201"
			(at -3.494532 -1.880616 0)
			(unlocked yes)
			(layer "B.SilkS")
			(effects
				(font
					(size 0.7874 0.5842)
					(thickness 0.1524)
				)
				(justify left mirror)
			)
		)
		(property "Value" ""
			(at 0 0 90)
			(layer "B.Fab")
			(effects
				(font
					(size 1.27 1.27)
				)
				(justify mirror)
			)
		)
		(duplicate_pad_numbers_are_jumpers no)
		(fp_line
			(start -1.2446 1.2446)
			(end -1.2446 0.479044)
			(stroke
				(width 0.1524)
				(type default)
			)
			(layer "B.SilkS")
		)
		(fp_line
			(start 1.2446 1.2446)
			(end -1.2446 1.2446)
			(stroke
				(width 0.1524)
				(type default)
			)
			(layer "B.SilkS")
		)
		(fp_line
			(start 1.2446 0.593344)
			(end 1.2446 1.2446)
			(stroke
				(width 0.1524)
				(type default)
			)
			(layer "B.SilkS")
		)
		(fp_line
			(start -1.2446 -0.506476)
			(end -1.2446 -1.2446)
			(stroke
				(width 0.1524)
				(type default)
			)
			(layer "B.SilkS")
		)
		(fp_line
			(start -1.2446 -1.2446)
			(end 1.2446 -1.2446)
			(stroke
				(width 0.1524)
				(type default)
			)
			(layer "B.SilkS")
		)
		(fp_line
			(start 1.2446 -1.2446)
			(end 1.2446 -0.592836)
			(stroke
				(width 0.1524)
				(type default)
			)
			(layer "B.SilkS")
		)
		(fp_poly
			(pts
				(xy 1.416812 -0.430022) (xy 1.688592 -1.246124) (xy 2.23266 -0.702056)
			)
			(stroke
				(width 0)
				(type default)
			)
			(fill yes)
			(layer "B.SilkS")
		)
		(fp_line
			(start -0.824992 0.824992)
			(end -0.824992 -0.824992)
			(stroke
				(width 0.1)
				(type default)
			)
			(layer "B.Fab")
		)
		(fp_line
			(start 0.824992 0.824992)
			(end -0.824992 0.824992)
			(stroke
				(width 0.1)
				(type default)
			)
			(layer "B.Fab")
		)
		(fp_line
			(start -0.824992 -0.824992)
			(end 0.824992 -0.824992)
			(stroke
				(width 0.1)
				(type default)
			)
			(layer "B.Fab")
		)
		(fp_line
			(start 0.824992 -0.824992)
			(end 0.824992 0.824992)
			(stroke
				(width 0.1)
				(type default)
			)
			(layer "B.Fab")
		)
		(fp_poly
			(pts
				(xy 1.389634 -0.199898) (xy 2.159 0.184658) (xy 2.159 -0.584708)
			)
			(stroke
				(width 0)
				(type default)
			)
			(fill yes)
			(layer "B.Fab")
		)
		(pad "1" smd rect
			(at 0.700024 -0.199898 180)
			(size 0.1778 0.8128)
			(layers "B.Cu" "B.Mask" "B.Paste")
			(net "USB2_HUB_BUF_SWB_R_DN")
		)
		(pad "2" smd rect
			(at 0.700024 0.199898 180)
			(size 0.1778 0.8128)
			(layers "B.Cu" "B.Mask" "B.Paste")
			(net "USB2_HUB_BUF_SWB_R_DP")
		)
		(pad "3" smd rect
			(at 0.599948 0.8001 90)
			(size 0.1778 0.6096)
			(layers "B.Cu" "B.Mask" "B.Paste")
			(net "TP_USB2_TEST")
		)
		(pad "4" smd rect
			(at 0.199898 0.8001 90)
			(size 0.1778 0.6096)
			(layers "B.Cu" "B.Mask" "B.Paste")
			(net "TP_USB2_CD")
		)
		(pad "5" smd rect
			(at -0.199898 0.8001 90)
			(size 0.1778 0.6096)
			(layers "B.Cu" "B.Mask" "B.Paste")
			(net "PD_U5201_RSTN")
		)
		(pad "6" smd rect
			(at -0.599948 0.8001 90)
			(size 0.1778 0.6096)
			(layers "B.Cu" "B.Mask" "B.Paste")
			(net "PD_U5201_EQ")
		)
		(pad "7" smd rect
			(at -0.700024 0.199898 180)
			(size 0.1778 0.8128)
			(layers "B.Cu" "B.Mask" "B.Paste")
			(net "USB2_HUB_BUF_SWB_R_DP")
		)
		(pad "8" smd rect
			(at -0.700024 -0.199898 180)
			(size 0.1778 0.8128)
			(layers "B.Cu" "B.Mask" "B.Paste")
			(net "USB2_HUB_BUF_SWB_R_DN")
		)
		(pad "9" smd rect
			(at -0.599948 -0.8001 90)
			(size 0.1778 0.6096)
			(layers "B.Cu" "B.Mask" "B.Paste")
			(net "TP_USB2_ENA_HS")
		)
		(pad "10" smd rect
			(at -0.199898 -0.8001 90)
			(size 0.1778 0.6096)
			(layers "B.Cu" "B.Mask" "B.Paste")
			(net "GND")
		)
		(pad "11" smd rect
			(at 0.199898 -0.8001 90)
			(size 0.1778 0.6096)
			(layers "B.Cu" "B.Mask" "B.Paste")
			(net "PD_U5201_VREG")
		)
		(pad "12" smd rect
			(at 0.599948 -0.8001 90)
			(size 0.1778 0.6096)
			(layers "B.Cu" "B.Mask" "B.Paste")
			(net "P3V3_AUX")
		)
	)
	(footprint ""
		(layer "B.Cu")
		(at 343.166192 -64.088264 90)
		(property "Reference" "C163"
			(at 0 0 90)
			(layer "B.SilkS")
			(hide yes)
			(effects
				(font
					(size 1.27 1.27)
				)
				(justify mirror)
			)
		)
		(property "Value" ""
			(at 0 0 90)
			(layer "B.Fab")
			(effects
				(font
					(size 1.27 1.27)
				)
				(justify mirror)
			)
		)
		(duplicate_pad_numbers_are_jumpers no)
		(fp_line
			(start 0.299974 -0.150114)
			(end -0.299974 -0.150114)
			(stroke
				(width 0.1)
				(type default)
			)
			(layer "B.Fab")
		)
		(fp_line
			(start -0.299974 -0.150114)
			(end -0.299974 0.150114)
			(stroke
				(width 0.1)
				(type default)
			)
			(layer "B.Fab")
		)
		(fp_line
			(start 0.299974 0.150114)
			(end 0.299974 -0.150114)
			(stroke
				(width 0.1)
				(type default)
			)
			(layer "B.Fab")
		)
		(fp_line
			(start -0.299974 0.150114)
			(end 0.299974 0.150114)
			(stroke
				(width 0.1)
				(type default)
			)
			(layer "B.Fab")
		)
		(pad "1" smd rect
			(at 0.2667 0 270)
			(size 0.3048 0.381)
			(layers "B.Cu" "B.Mask" "B.Paste")
			(net "DMI_CPU0_PCH_RX_C_DN<3>")
		)
		(pad "2" smd rect
			(at -0.2667 0 270)
			(size 0.3048 0.381)
			(layers "B.Cu" "B.Mask" "B.Paste")
			(net "DMI_CPU0_PCH_RX_DN<3>")
		)
	)
	(footprint ""
		(layer "B.Cu")
		(at 47.80661 -344.935556 -90)
		(property "Reference" "PC413_P1_2"
			(at 0 0 90)
			(layer "B.SilkS")
			(hide yes)
			(effects
				(font
					(size 1.27 1.27)
				)
				(justify mirror)
			)
		)
		(property "Value" ""
			(at 0 0 90)
			(layer "B.Fab")
			(effects
				(font
					(size 1.27 1.27)
				)
				(justify mirror)
			)
		)
		(duplicate_pad_numbers_are_jumpers no)
		(fp_line
			(start -1.524 0.762)
			(end 1.524 0.762)
			(stroke
				(width 0.1524)
				(type default)
			)
			(layer "B.SilkS")
		)
		(fp_line
			(start 1.524 0.762)
			(end 1.524 -0.762)
			(stroke
				(width 0.1524)
				(type default)
			)
			(layer "B.SilkS")
		)
		(fp_line
			(start -1.524 -0.762)
			(end -1.524 0.762)
			(stroke
				(width 0.1524)
				(type default)
			)
			(layer "B.SilkS")
		)
		(fp_line
			(start 1.524 -0.762)
			(end -1.524 -0.762)
			(stroke
				(width 0.1524)
				(type default)
			)
			(layer "B.SilkS")
		)
		(fp_line
			(start -1.1049 0.724916)
			(end -1.1049 -0.724916)
			(stroke
				(width 0.1)
				(type default)
			)
			(layer "B.Fab")
		)
		(fp_line
			(start 1.1049 0.724916)
			(end -1.1049 0.724916)
			(stroke
				(width 0.1)
				(type default)
			)
			(layer "B.Fab")
		)
		(fp_line
			(start -1.1049 -0.724916)
			(end 1.1049 -0.724916)
			(stroke
				(width 0.1)
				(type default)
			)
			(layer "B.Fab")
		)
		(fp_line
			(start 1.1049 -0.724916)
			(end 1.1049 0.724916)
			(stroke
				(width 0.1)
				(type default)
			)
			(layer "B.Fab")
		)
		(pad "1" smd rect
			(at 0.889 0 270)
			(size 1.016 1.27)
			(layers "B.Cu" "B.Mask" "B.Paste")
			(net "PVCCFA_EHV_FIVRA_CPU1")
		)
		(pad "2" smd rect
			(at -0.889 0 270)
			(size 1.016 1.27)
			(layers "B.Cu" "B.Mask" "B.Paste")
			(net "GND")
		)
	)
	(footprint ""
		(layer "B.Cu")
		(at 329.240388 2.923794)
		(property "Reference" "J119"
			(at 4.361942 1.521206 270)
			(unlocked yes)
			(layer "B.SilkS")
			(effects
				(font
					(size 0.7874 0.5842)
					(thickness 0.1524)
				)
				(justify left mirror)
			)
		)
		(property "Value" ""
			(at 0 0 0)
			(layer "B.Fab")
			(effects
				(font
					(size 1.27 1.27)
				)
				(justify mirror)
			)
		)
		(duplicate_pad_numbers_are_jumpers no)
		(fp_line
			(start -1.2192 -2.1082)
			(end -1.2192 2.1082)
			(stroke
				(width 0.1524)
				(type default)
			)
			(layer "B.SilkS")
		)
		(fp_line
			(start -1.2192 2.1082)
			(end 1.2192 2.1082)
			(stroke
				(width 0.1524)
				(type default)
			)
			(layer "B.SilkS")
		)
		(fp_line
			(start 1.2192 -2.1082)
			(end -1.2192 -2.1082)
			(stroke
				(width 0.1524)
				(type default)
			)
			(layer "B.SilkS")
		)
		(fp_line
			(start 1.2192 2.1082)
			(end 1.2192 -2.1082)
			(stroke
				(width 0.1524)
				(type default)
			)
			(layer "B.SilkS")
		)
		(pad "" np_thru_hole circle
			(at -3.4671 -1.27 270)
			(size 1.0414 1.0414)
			(drill 1.0414)
			(layers "*.Cu" "*.Mask")
			(clearance 0.381)
			(thermal_gap 0.381)
		)
		(pad "" np_thru_hole circle
			(at -3.4671 1.27 270)
			(size 1.0414 1.0414)
			(drill 1.0414)
			(layers "*.Cu" "*.Mask")
			(clearance 0.381)
			(thermal_gap 0.381)
		)
		(pad "" np_thru_hole circle
			(at 2.8829 -1.27 270)
			(size 1.0414 1.0414)
			(drill 1.0414)
			(layers "*.Cu" "*.Mask")
			(clearance 0.381)
			(thermal_gap 0.381)
		)
		(pad "" np_thru_hole circle
			(at 2.8829 1.27 270)
			(size 1.0414 1.0414)
			(drill 1.0414)
			(layers "*.Cu" "*.Mask")
			(clearance 0.381)
			(thermal_gap 0.381)
		)
		(pad "1" smd rect
			(at -0.8255 -0.249936 270)
			(size 0.3048 0.508)
			(layers "B.Cu" "B.Mask" "B.Paste")
			(net "DELTA_L_85_10INCH_IN6_DP")
		)
		(pad "2" smd rect
			(at -0.8255 0.249936 270)
			(size 0.3048 0.508)
			(layers "B.Cu" "B.Mask" "B.Paste")
			(net "DELTA_L_85_10INCH_IN6_DN")
		)
		(pad "3" smd circle
			(at 0 0 180)
			(size 0 0)
			(layers "B.Cu" "B.Mask" "B.Paste")
			(net "DELTA_L_GND_1")
		)
		(zone
			(layers "F.Cu" "B.Cu" "In1.Cu" "In2.Cu" "In3.Cu" "In4.Cu" "In5.Cu" "In6.Cu"
				"In7.Cu" "In8.Cu" "In9.Cu" "In10.Cu" "In11.Cu" "In12.Cu" "In13.Cu" "In14.Cu"
				"In15.Cu" "In16.Cu"
			)
			(hatch none 0.5)
			(connect_pads
				(clearance 0)
			)
			(min_thickness 0.25)
			(keepout
				(tracks not_allowed)
				(vias allowed)
				(pads allowed)
				(copperpour not_allowed)
				(footprints allowed)
			)
			(placement
				(enabled no)
				(sheetname "")
			)
			(fill
				(thermal_gap 0.5)
				(thermal_bridge_width 0.5)
				(island_removal_mode 0)
			)
			(polygon
				(pts
					(arc
						(start 326.700388 1.653794)
						(mid 324.846188 1.653794)
						(end 326.700388 1.653794)
					)
				)
			)
		)
		(zone
			(layers "F.Cu" "B.Cu" "In1.Cu" "In2.Cu" "In3.Cu" "In4.Cu" "In5.Cu" "In6.Cu"
				"In7.Cu" "In8.Cu" "In9.Cu" "In10.Cu" "In11.Cu" "In12.Cu" "In13.Cu" "In14.Cu"
				"In15.Cu" "In16.Cu"
			)
			(hatch none 0.5)
			(connect_pads
				(clearance 0)
			)
			(min_thickness 0.25)
			(keepout
				(tracks not_allowed)
				(vias allowed)
				(pads allowed)
				(copperpour not_allowed)
				(footprints allowed)
			)
			(placement
				(enabled no)
				(sheetname "")
			)
			(fill
				(thermal_gap 0.5)
				(thermal_bridge_width 0.5)
				(island_removal_mode 0)
			)
			(polygon
				(pts
					(arc
						(start 326.700388 4.193794)
						(mid 324.846188 4.193794)
						(end 326.700388 4.193794)
					)
				)
			)
		)
		(zone
			(layers "F.Cu" "B.Cu" "In1.Cu" "In2.Cu" "In3.Cu" "In4.Cu" "In5.Cu" "In6.Cu"
				"In7.Cu" "In8.Cu" "In9.Cu" "In10.Cu" "In11.Cu" "In12.Cu" "In13.Cu" "In14.Cu"
				"In15.Cu" "In16.Cu"
			)
			(hatch none 0.5)
			(connect_pads
				(clearance 0)
			)
			(min_thickness 0.25)
			(keepout
				(tracks not_allowed)
				(vias allowed)
				(pads allowed)
				(copperpour not_allowed)
				(footprints allowed)
			)
			(placement
				(enabled no)
				(sheetname "")
			)
			(fill
				(thermal_gap 0.5)
				(thermal_bridge_width 0.5)
				(island_removal_mode 0)
			)
			(polygon
				(pts
					(arc
						(start 333.050388 1.653794)
						(mid 331.196188 1.653794)
						(end 333.050388 1.653794)
					)
				)
			)
		)
		(zone
			(layers "F.Cu" "B.Cu" "In1.Cu" "In2.Cu" "In3.Cu" "In4.Cu" "In5.Cu" "In6.Cu"
				"In7.Cu" "In8.Cu" "In9.Cu" "In10.Cu" "In11.Cu" "In12.Cu" "In13.Cu" "In14.Cu"
				"In15.Cu" "In16.Cu"
			)
			(hatch none 0.5)
			(connect_pads
				(clearance 0)
			)
			(min_thickness 0.25)
			(keepout
				(tracks not_allowed)
				(vias allowed)
				(pads allowed)
				(copperpour not_allowed)
				(footprints allowed)
			)
			(placement
				(enabled no)
				(sheetname "")
			)
			(fill
				(thermal_gap 0.5)
				(thermal_bridge_width 0.5)
				(island_removal_mode 0)
			)
			(polygon
				(pts
					(arc
						(start 333.050388 4.193794)
						(mid 331.196188 4.193794)
						(end 333.050388 4.193794)
					)
				)
			)
		)
		(zone
			(layer "B.Cu")
			(hatch none 0.5)
			(connect_pads
				(clearance 0)
			)
			(min_thickness 0.25)
			(keepout
				(tracks not_allowed)
				(vias allowed)
				(pads allowed)
				(copperpour not_allowed)
				(footprints allowed)
			)
			(placement
				(enabled no)
				(sheetname "")
			)
			(fill
				(thermal_gap 0.5)
				(thermal_bridge_width 0.5)
				(island_removal_mode 0)
			)
			(polygon
				(pts
					(xy 328.122788 2.375154) (xy 328.122788 2.470658) (xy 328.719688 2.470658) (xy 328.719688 2.877058)
					(xy 328.122788 2.877058) (xy 328.122788 2.97053) (xy 328.719688 2.97053) (xy 328.719688 3.37693)
					(xy 328.122788 3.37693) (xy 328.122788 3.472434) (xy 328.821288 3.472434) (xy 328.821288 2.375154)
				)
			)
		)
	)
	(footprint ""
		(layer "B.Cu")
		(at 504.058428 2.33172 90)
		(property "Reference" "X31"
			(at 1.48082 3.196082 270)
			(unlocked yes)
			(layer "B.SilkS")
			(effects
				(font
					(size 0.7874 0.5842)
					(thickness 0.1524)
				)
				(justify left mirror)
			)
		)
		(property "Value" ""
			(at 0 0 90)
			(layer "B.Fab")
			(effects
				(font
					(size 1.27 1.27)
				)
				(justify mirror)
			)
		)
		(property "Device Type" "TP_TDR_4P_FTS_TH-TP_TDR_4P_DIPA"
			(at -1.30175 1.27 0)
			(unlocked yes)
			(layer "B.Fab")
			(hide yes)
			(effects
				(font
					(size 0.635 0.4064)
					(thickness 0.1524)
				)
				(justify mirror)
			)
		)
		(property "User Part Number" "N_A"
			(at -1.30175 1.27 0)
			(unlocked yes)
			(layer "Cmts.User")
			(hide yes)
			(effects
				(font
					(size 0.635 0.4064)
					(thickness 0.1524)
				)
				(justify mirror)
			)
		)
		(duplicate_pad_numbers_are_jumpers no)
		(fp_line
			(start 0 -1.27)
			(end 0 -0.635)
			(stroke
				(width 0.1524)
				(type default)
			)
			(layer "B.SilkS")
		)
		(fp_line
			(start -2.54 -1.27)
			(end 0 -1.27)
			(stroke
				(width 0.1524)
				(type default)
			)
			(layer "B.SilkS")
		)
		(fp_line
			(start -2.54 -1.1303)
			(end -2.54 -1.27)
			(stroke
				(width 0.1524)
				(type default)
			)
			(layer "B.SilkS")
		)
		(fp_line
			(start 0 0.635)
			(end 0 1.905)
			(stroke
				(width 0.1524)
				(type default)
			)
			(layer "B.SilkS")
		)
		(fp_line
			(start -2.54 1.4097)
			(end -2.54 1.1303)
			(stroke
				(width 0.1524)
				(type default)
			)
			(layer "B.SilkS")
		)
		(fp_line
			(start 0 3.175)
			(end 0 3.81)
			(stroke
				(width 0.1524)
				(type default)
			)
			(layer "B.SilkS")
		)
		(fp_line
			(start 0 3.81)
			(end -2.54 3.81)
			(stroke
				(width 0.1524)
				(type default)
			)
			(layer "B.SilkS")
		)
		(fp_line
			(start -2.54 3.81)
			(end -2.54 3.6703)
			(stroke
				(width 0.1524)
				(type default)
			)
			(layer "B.SilkS")
		)
		(fp_poly
			(pts
				(xy 2.285746 -0.762) (xy 2.285746 0.762) (xy 0.761746 0)
			)
			(stroke
				(width 0)
				(type default)
			)
			(fill yes)
			(layer "B.SilkS")
		)
		(fp_line
			(start 0 -1.27)
			(end 0 3.81)
			(stroke
				(width 0.1)
				(type default)
			)
			(layer "B.Fab")
		)
		(fp_line
			(start -2.54 -1.27)
			(end 0 -1.27)
			(stroke
				(width 0.1)
				(type default)
			)
			(layer "B.Fab")
		)
		(fp_line
			(start 0 3.81)
			(end -2.54 3.81)
			(stroke
				(width 0.1)
				(type default)
			)
			(layer "B.Fab")
		)
		(fp_line
			(start -2.54 3.81)
			(end -2.54 -1.27)
			(stroke
				(width 0.1)
				(type default)
			)
			(layer "B.Fab")
		)
		(fp_poly
			(pts
				(xy 0.761746 0) (xy 2.285746 -0.762) (xy 2.285746 0.762)
			)
			(stroke
				(width 0)
				(type default)
			)
			(fill yes)
			(layer "B.Fab")
		)
		(pad "1" thru_hole circle
			(at 0 0 270)
			(size 1.0033 1.0033)
			(drill 0.249936)
			(layers "*.Cu" "*.Mask")
			(remove_unused_layers no)
			(net "TDR_DIFF_100_IN5_DN")
			(clearance 0.10795)
			(padstack
				(mode front_inner_back)
				(layer "Inner"
					(shape circle)
					(size 0.8001 0.8001)
					(clearance 0.1524)
				)
				(layer "B.Cu"
					(shape circle)
					(size 1.0033 1.0033)
					(thermal_gap 0.10795)
					(clearance 0.10795)
				)
			)
		)
		(pad "2" thru_hole circle
			(at -2.54 0 270)
			(size 1.9939 1.9939)
			(drill 0.249936)
			(layers "*.Cu" "*.Mask")
			(remove_unused_layers no)
			(net "T1_GND")
			(clearance 0.10795)
			(padstack
				(mode front_inner_back)
				(layer "Inner"
					(shape circle)
					(size 0.8001 0.8001)
					(clearance 0.1524)
				)
				(layer "B.Cu"
					(shape circle)
					(size 1.9939 1.9939)
					(thermal_gap 0.10795)
					(clearance 0.10795)
				)
			)
		)
		(pad "3" thru_hole circle
			(at -2.54 2.54 270)
			(size 1.9939 1.9939)
			(drill 0.249936)
			(layers "*.Cu" "*.Mask")
			(remove_unused_layers no)
			(net "T1_GND")
			(clearance 0.10795)
			(padstack
				(mode front_inner_back)
				(layer "Inner"
					(shape circle)
					(size 0.8001 0.8001)
					(clearance 0.1524)
				)
				(layer "B.Cu"
					(shape circle)
					(size 1.9939 1.9939)
					(thermal_gap 0.10795)
					(clearance 0.10795)
				)
			)
		)
		(pad "4" thru_hole circle
			(at 0 2.54 270)
			(size 1.0033 1.0033)
			(drill 0.249936)
			(layers "*.Cu" "*.Mask")
			(remove_unused_layers no)
			(net "TDR_DIFF_100_IN5_DP")
			(clearance 0.10795)
			(padstack
				(mode front_inner_back)
				(layer "Inner"
					(shape circle)
					(size 0.8001 0.8001)
					(clearance 0.1524)
				)
				(layer "B.Cu"
					(shape circle)
					(size 1.0033 1.0033)
					(thermal_gap 0.10795)
					(clearance 0.10795)
				)
			)
		)
	)
	(footprint ""
		(layer "B.Cu")
		(at 233.5149 -249.182128 -90)
		(property "Reference" "R4077"
			(at 0 0 90)
			(layer "B.SilkS")
			(hide yes)
			(effects
				(font
					(size 1.27 1.27)
				)
				(justify mirror)
			)
		)
		(property "Value" ""
			(at 0 0 90)
			(layer "B.Fab")
			(effects
				(font
					(size 1.27 1.27)
				)
				(justify mirror)
			)
		)
		(duplicate_pad_numbers_are_jumpers no)
		(fp_line
			(start -0.7874 0.4064)
			(end 0.7874 0.4064)
			(stroke
				(width 0.1524)
				(type default)
			)
			(layer "B.SilkS")
		)
		(fp_line
			(start 0.7874 0.4064)
			(end 0.7874 -0.4064)
			(stroke
				(width 0.1524)
				(type default)
			)
			(layer "B.SilkS")
		)
		(fp_line
			(start -0.7874 -0.4064)
			(end -0.7874 0.4064)
			(stroke
				(width 0.1524)
				(type default)
			)
			(layer "B.SilkS")
		)
		(fp_line
			(start 0.7874 -0.4064)
			(end -0.7874 -0.4064)
			(stroke
				(width 0.1524)
				(type default)
			)
			(layer "B.SilkS")
		)
		(fp_line
			(start -0.67945 0.3048)
			(end -0.120396 0.3048)
			(stroke
				(width 0.1)
				(type default)
			)
			(layer "B.Fab")
		)
		(fp_line
			(start -0.120396 0.3048)
			(end -0.120396 0.2794)
			(stroke
				(width 0.1)
				(type default)
			)
			(layer "B.Fab")
		)
		(fp_line
			(start 0.12065 0.3048)
			(end 0.67945 0.3048)
			(stroke
				(width 0.1)
				(type default)
			)
			(layer "B.Fab")
		)
		(fp_line
			(start 0.67945 0.3048)
			(end 0.67945 -0.305054)
			(stroke
				(width 0.1)
				(type default)
			)
			(layer "B.Fab")
		)
		(fp_line
			(start -0.120396 0.2794)
			(end 0.12065 0.2794)
			(stroke
				(width 0.1)
				(type default)
			)
			(layer "B.Fab")
		)
		(fp_line
			(start 0.12065 0.2794)
			(end 0.12065 0.3048)
			(stroke
				(width 0.1)
				(type default)
			)
			(layer "B.Fab")
		)
		(fp_line
			(start -0.12065 -0.2794)
			(end -0.12065 -0.3048)
			(stroke
				(width 0.1)
				(type default)
			)
			(layer "B.Fab")
		)
		(fp_line
			(start 0.12065 -0.2794)
			(end -0.12065 -0.2794)
			(stroke
				(width 0.1)
				(type default)
			)
			(layer "B.Fab")
		)
		(fp_line
			(start -0.67945 -0.3048)
			(end -0.67945 0.3048)
			(stroke
				(width 0.1)
				(type default)
			)
			(layer "B.Fab")
		)
		(fp_line
			(start -0.12065 -0.3048)
			(end -0.67945 -0.3048)
			(stroke
				(width 0.1)
				(type default)
			)
			(layer "B.Fab")
		)
		(fp_line
			(start 0.12065 -0.305054)
			(end 0.12065 -0.2794)
			(stroke
				(width 0.1)
				(type default)
			)
			(layer "B.Fab")
		)
		(fp_line
			(start 0.67945 -0.305054)
			(end 0.12065 -0.305054)
			(stroke
				(width 0.1)
				(type default)
			)
			(layer "B.Fab")
		)
		(pad "1" smd circle
			(at 0.40005 0 90)
			(size 0 0)
			(layers "B.Cu" "B.Mask" "B.Paste")
			(net "VFG3P3_CLK_GEN")
		)
		(pad "2" smd circle
			(at -0.40005 0 90)
			(size 0 0)
			(layers "B.Cu" "B.Mask" "B.Paste")
			(net "VFG_3P3A_CLK_GEN")
		)
	)
	(footprint ""
		(layer "B.Cu")
		(at 138.77798 -30.157928 -90)
		(property "Reference" "C2323"
			(at 0 0 90)
			(layer "B.SilkS")
			(hide yes)
			(effects
				(font
					(size 1.27 1.27)
				)
				(justify mirror)
			)
		)
		(property "Value" ""
			(at 0 0 90)
			(layer "B.Fab")
			(effects
				(font
					(size 1.27 1.27)
				)
				(justify mirror)
			)
		)
		(duplicate_pad_numbers_are_jumpers no)
		(fp_line
			(start -0.7874 0.4064)
			(end 0.7874 0.4064)
			(stroke
				(width 0.1524)
				(type default)
			)
			(layer "B.SilkS")
		)
		(fp_line
			(start 0.7874 0.4064)
			(end 0.7874 -0.4064)
			(stroke
				(width 0.1524)
				(type default)
			)
			(layer "B.SilkS")
		)
		(fp_line
			(start -0.7874 -0.4064)
			(end -0.7874 0.4064)
			(stroke
				(width 0.1524)
				(type default)
			)
			(layer "B.SilkS")
		)
		(fp_line
			(start 0.7874 -0.4064)
			(end -0.7874 -0.4064)
			(stroke
				(width 0.1524)
				(type default)
			)
			(layer "B.SilkS")
		)
		(fp_line
			(start -0.67945 0.3048)
			(end -0.120396 0.3048)
			(stroke
				(width 0.1)
				(type default)
			)
			(layer "B.Fab")
		)
		(fp_line
			(start -0.120396 0.3048)
			(end -0.120396 0.2794)
			(stroke
				(width 0.1)
				(type default)
			)
			(layer "B.Fab")
		)
		(fp_line
			(start 0.12065 0.3048)
			(end 0.67945 0.3048)
			(stroke
				(width 0.1)
				(type default)
			)
			(layer "B.Fab")
		)
		(fp_line
			(start 0.67945 0.3048)
			(end 0.67945 -0.305054)
			(stroke
				(width 0.1)
				(type default)
			)
			(layer "B.Fab")
		)
		(fp_line
			(start -0.120396 0.2794)
			(end 0.12065 0.2794)
			(stroke
				(width 0.1)
				(type default)
			)
			(layer "B.Fab")
		)
		(fp_line
			(start 0.12065 0.2794)
			(end 0.12065 0.3048)
			(stroke
				(width 0.1)
				(type default)
			)
			(layer "B.Fab")
		)
		(fp_line
			(start -0.12065 -0.2794)
			(end -0.12065 -0.3048)
			(stroke
				(width 0.1)
				(type default)
			)
			(layer "B.Fab")
		)
		(fp_line
			(start 0.12065 -0.2794)
			(end -0.12065 -0.2794)
			(stroke
				(width 0.1)
				(type default)
			)
			(layer "B.Fab")
		)
		(fp_line
			(start -0.67945 -0.3048)
			(end -0.67945 0.3048)
			(stroke
				(width 0.1)
				(type default)
			)
			(layer "B.Fab")
		)
		(fp_line
			(start -0.12065 -0.3048)
			(end -0.67945 -0.3048)
			(stroke
				(width 0.1)
				(type default)
			)
			(layer "B.Fab")
		)
		(fp_line
			(start 0.12065 -0.305054)
			(end 0.12065 -0.2794)
			(stroke
				(width 0.1)
				(type default)
			)
			(layer "B.Fab")
		)
		(fp_line
			(start 0.67945 -0.305054)
			(end 0.12065 -0.305054)
			(stroke
				(width 0.1)
				(type default)
			)
			(layer "B.Fab")
		)
		(pad "1" smd circle
			(at 0.40005 0 90)
			(size 0 0)
			(layers "B.Cu" "B.Mask" "B.Paste")
			(net "P3V3_AUX")
		)
		(pad "2" smd circle
			(at -0.40005 0 90)
			(size 0 0)
			(layers "B.Cu" "B.Mask" "B.Paste")
			(net "GND")
		)
	)
	(footprint ""
		(layer "B.Cu")
		(at 89.394284 -184.015888 90)
		(property "Reference" "R999"
			(at 0 0 90)
			(layer "B.SilkS")
			(hide yes)
			(effects
				(font
					(size 1.27 1.27)
				)
				(justify mirror)
			)
		)
		(property "Value" ""
			(at 0 0 90)
			(layer "B.Fab")
			(effects
				(font
					(size 1.27 1.27)
				)
				(justify mirror)
			)
		)
		(duplicate_pad_numbers_are_jumpers no)
		(fp_line
			(start 0.7874 -0.4064)
			(end -0.7874 -0.4064)
			(stroke
				(width 0.1524)
				(type default)
			)
			(layer "B.SilkS")
		)
		(fp_line
			(start -0.7874 -0.4064)
			(end -0.7874 0.4064)
			(stroke
				(width 0.1524)
				(type default)
			)
			(layer "B.SilkS")
		)
		(fp_line
			(start 0.7874 0.4064)
			(end 0.7874 -0.4064)
			(stroke
				(width 0.1524)
				(type default)
			)
			(layer "B.SilkS")
		)
		(fp_line
			(start -0.7874 0.4064)
			(end 0.7874 0.4064)
			(stroke
				(width 0.1524)
				(type default)
			)
			(layer "B.SilkS")
		)
		(fp_line
			(start 0.67945 -0.305054)
			(end 0.12065 -0.305054)
			(stroke
				(width 0.1)
				(type default)
			)
			(layer "B.Fab")
		)
		(fp_line
			(start 0.12065 -0.305054)
			(end 0.12065 -0.2794)
			(stroke
				(width 0.1)
				(type default)
			)
			(layer "B.Fab")
		)
		(fp_line
			(start -0.12065 -0.3048)
			(end -0.67945 -0.3048)
			(stroke
				(width 0.1)
				(type default)
			)
			(layer "B.Fab")
		)
		(fp_line
			(start -0.67945 -0.3048)
			(end -0.67945 0.3048)
			(stroke
				(width 0.1)
				(type default)
			)
			(layer "B.Fab")
		)
		(fp_line
			(start 0.12065 -0.2794)
			(end -0.12065 -0.2794)
			(stroke
				(width 0.1)
				(type default)
			)
			(layer "B.Fab")
		)
		(fp_line
			(start -0.12065 -0.2794)
			(end -0.12065 -0.3048)
			(stroke
				(width 0.1)
				(type default)
			)
			(layer "B.Fab")
		)
		(fp_line
			(start 0.12065 0.2794)
			(end 0.12065 0.3048)
			(stroke
				(width 0.1)
				(type default)
			)
			(layer "B.Fab")
		)
		(fp_line
			(start -0.120396 0.2794)
			(end 0.12065 0.2794)
			(stroke
				(width 0.1)
				(type default)
			)
			(layer "B.Fab")
		)
		(fp_line
			(start 0.67945 0.3048)
			(end 0.67945 -0.305054)
			(stroke
				(width 0.1)
				(type default)
			)
			(layer "B.Fab")
		)
		(fp_line
			(start 0.12065 0.3048)
			(end 0.67945 0.3048)
			(stroke
				(width 0.1)
				(type default)
			)
			(layer "B.Fab")
		)
		(fp_line
			(start -0.120396 0.3048)
			(end -0.120396 0.2794)
			(stroke
				(width 0.1)
				(type default)
			)
			(layer "B.Fab")
		)
		(fp_line
			(start -0.67945 0.3048)
			(end -0.120396 0.3048)
			(stroke
				(width 0.1)
				(type default)
			)
			(layer "B.Fab")
		)
		(pad "1" smd circle
			(at 0.40005 0 270)
			(size 0 0)
			(layers "B.Cu" "B.Mask" "B.Paste")
			(net "FM_SMB_PEHPCPU1_PCIE_ALERT_N")
		)
		(pad "2" smd circle
			(at -0.40005 0 270)
			(size 0 0)
			(layers "B.Cu" "B.Mask" "B.Paste")
			(net "FM_SMB_PEHPCPU1_PCIE_ALERT_R_N")
		)
	)
	(footprint ""
		(layer "B.Cu")
		(at 27.0383 -130.396996)
		(property "Reference" "PR259"
			(at 0 0 0)
			(layer "B.SilkS")
			(hide yes)
			(effects
				(font
					(size 1.27 1.27)
				)
				(justify mirror)
			)
		)
		(property "Value" ""
			(at 0 0 0)
			(layer "B.Fab")
			(effects
				(font
					(size 1.27 1.27)
				)
				(justify mirror)
			)
		)
		(duplicate_pad_numbers_are_jumpers no)
		(fp_line
			(start -0.7874 -0.4064)
			(end -0.7874 0.4064)
			(stroke
				(width 0.1524)
				(type default)
			)
			(layer "B.SilkS")
		)
		(fp_line
			(start -0.7874 0.4064)
			(end 0.7874 0.4064)
			(stroke
				(width 0.1524)
				(type default)
			)
			(layer "B.SilkS")
		)
		(fp_line
			(start 0.7874 -0.4064)
			(end -0.7874 -0.4064)
			(stroke
				(width 0.1524)
				(type default)
			)
			(layer "B.SilkS")
		)
		(fp_line
			(start 0.7874 0.4064)
			(end 0.7874 -0.4064)
			(stroke
				(width 0.1524)
				(type default)
			)
			(layer "B.SilkS")
		)
		(fp_line
			(start -0.67945 -0.3048)
			(end -0.67945 0.3048)
			(stroke
				(width 0.1)
				(type default)
			)
			(layer "B.Fab")
		)
		(fp_line
			(start -0.67945 0.3048)
			(end -0.120396 0.3048)
			(stroke
				(width 0.1)
				(type default)
			)
			(layer "B.Fab")
		)
		(fp_line
			(start -0.12065 -0.3048)
			(end -0.67945 -0.3048)
			(stroke
				(width 0.1)
				(type default)
			)
			(layer "B.Fab")
		)
		(fp_line
			(start -0.12065 -0.2794)
			(end -0.12065 -0.3048)
			(stroke
				(width 0.1)
				(type default)
			)
			(layer "B.Fab")
		)
		(fp_line
			(start -0.120396 0.2794)
			(end 0.12065 0.2794)
			(stroke
				(width 0.1)
				(type default)
			)
			(layer "B.Fab")
		)
		(fp_line
			(start -0.120396 0.3048)
			(end -0.120396 0.2794)
			(stroke
				(width 0.1)
				(type default)
			)
			(layer "B.Fab")
		)
		(fp_line
			(start 0.12065 -0.305054)
			(end 0.12065 -0.2794)
			(stroke
				(width 0.1)
				(type default)
			)
			(layer "B.Fab")
		)
		(fp_line
			(start 0.12065 -0.2794)
			(end -0.12065 -0.2794)
			(stroke
				(width 0.1)
				(type default)
			)
			(layer "B.Fab")
		)
		(fp_line
			(start 0.12065 0.2794)
			(end 0.12065 0.3048)
			(stroke
				(width 0.1)
				(type default)
			)
			(layer "B.Fab")
		)
		(fp_line
			(start 0.12065 0.3048)
			(end 0.67945 0.3048)
			(stroke
				(width 0.1)
				(type default)
			)
			(layer "B.Fab")
		)
		(fp_line
			(start 0.67945 -0.305054)
			(end 0.12065 -0.305054)
			(stroke
				(width 0.1)
				(type default)
			)
			(layer "B.Fab")
		)
		(fp_line
			(start 0.67945 0.3048)
			(end 0.67945 -0.305054)
			(stroke
				(width 0.1)
				(type default)
			)
			(layer "B.Fab")
		)
		(pad "1" smd circle
			(at 0.40005 0 180)
			(size 0 0)
			(layers "B.Cu" "B.Mask" "B.Paste")
			(net "PVCCINFAON_CPU1_ADDR")
		)
		(pad "2" smd circle
			(at -0.40005 0 180)
			(size 0 0)
			(layers "B.Cu" "B.Mask" "B.Paste")
			(net "GND")
		)
	)
	(footprint ""
		(layer "B.Cu")
		(at 284.075378 -319.392046)
		(property "Reference" "R941"
			(at 0 0 0)
			(layer "B.SilkS")
			(hide yes)
			(effects
				(font
					(size 1.27 1.27)
				)
				(justify mirror)
			)
		)
		(property "Value" ""
			(at 0 0 0)
			(layer "B.Fab")
			(effects
				(font
					(size 1.27 1.27)
				)
				(justify mirror)
			)
		)
		(duplicate_pad_numbers_are_jumpers no)
		(fp_line
			(start -0.7874 -0.4064)
			(end -0.7874 0.4064)
			(stroke
				(width 0.1524)
				(type default)
			)
			(layer "B.SilkS")
		)
		(fp_line
			(start -0.7874 0.4064)
			(end 0.7874 0.4064)
			(stroke
				(width 0.1524)
				(type default)
			)
			(layer "B.SilkS")
		)
		(fp_line
			(start 0.7874 -0.4064)
			(end -0.7874 -0.4064)
			(stroke
				(width 0.1524)
				(type default)
			)
			(layer "B.SilkS")
		)
		(fp_line
			(start 0.7874 0.4064)
			(end 0.7874 -0.4064)
			(stroke
				(width 0.1524)
				(type default)
			)
			(layer "B.SilkS")
		)
		(fp_line
			(start -0.67945 -0.3048)
			(end -0.67945 0.3048)
			(stroke
				(width 0.1)
				(type default)
			)
			(layer "B.Fab")
		)
		(fp_line
			(start -0.67945 0.3048)
			(end -0.120396 0.3048)
			(stroke
				(width 0.1)
				(type default)
			)
			(layer "B.Fab")
		)
		(fp_line
			(start -0.12065 -0.3048)
			(end -0.67945 -0.3048)
			(stroke
				(width 0.1)
				(type default)
			)
			(layer "B.Fab")
		)
		(fp_line
			(start -0.12065 -0.2794)
			(end -0.12065 -0.3048)
			(stroke
				(width 0.1)
				(type default)
			)
			(layer "B.Fab")
		)
		(fp_line
			(start -0.120396 0.2794)
			(end 0.12065 0.2794)
			(stroke
				(width 0.1)
				(type default)
			)
			(layer "B.Fab")
		)
		(fp_line
			(start -0.120396 0.3048)
			(end -0.120396 0.2794)
			(stroke
				(width 0.1)
				(type default)
			)
			(layer "B.Fab")
		)
		(fp_line
			(start 0.12065 -0.305054)
			(end 0.12065 -0.2794)
			(stroke
				(width 0.1)
				(type default)
			)
			(layer "B.Fab")
		)
		(fp_line
			(start 0.12065 -0.2794)
			(end -0.12065 -0.2794)
			(stroke
				(width 0.1)
				(type default)
			)
			(layer "B.Fab")
		)
		(fp_line
			(start 0.12065 0.2794)
			(end 0.12065 0.3048)
			(stroke
				(width 0.1)
				(type default)
			)
			(layer "B.Fab")
		)
		(fp_line
			(start 0.12065 0.3048)
			(end 0.67945 0.3048)
			(stroke
				(width 0.1)
				(type default)
			)
			(layer "B.Fab")
		)
		(fp_line
			(start 0.67945 -0.305054)
			(end 0.12065 -0.305054)
			(stroke
				(width 0.1)
				(type default)
			)
			(layer "B.Fab")
		)
		(fp_line
			(start 0.67945 0.3048)
			(end 0.67945 -0.305054)
			(stroke
				(width 0.1)
				(type default)
			)
			(layer "B.Fab")
		)
		(pad "1" smd circle
			(at 0.40005 0 180)
			(size 0 0)
			(layers "B.Cu" "B.Mask" "B.Paste")
			(net "P3V3_AUX")
		)
		(pad "2" smd circle
			(at -0.40005 0 180)
			(size 0 0)
			(layers "B.Cu" "B.Mask" "B.Paste")
			(net "PWRGD_FAIL_CPU0_CD_R1")
		)
	)
	(footprint ""
		(layer "B.Cu")
		(at 237.488476 -121.236994 180)
		(property "Reference" "C208"
			(at 0 0 0)
			(layer "B.SilkS")
			(hide yes)
			(effects
				(font
					(size 1.27 1.27)
				)
				(justify mirror)
			)
		)
		(property "Value" ""
			(at 0 0 0)
			(layer "B.Fab")
			(effects
				(font
					(size 1.27 1.27)
				)
				(justify mirror)
			)
		)
		(duplicate_pad_numbers_are_jumpers no)
		(fp_line
			(start 1.2954 0.5842)
			(end 1.2954 -0.5842)
			(stroke
				(width 0.1524)
				(type default)
			)
			(layer "B.SilkS")
		)
		(fp_line
			(start 1.2954 -0.5842)
			(end -1.2954 -0.5842)
			(stroke
				(width 0.1524)
				(type default)
			)
			(layer "B.SilkS")
		)
		(fp_line
			(start 0 -0.5842)
			(end 0 0.5842)
			(stroke
				(width 0.1524)
				(type default)
			)
			(layer "B.SilkS")
		)
		(fp_line
			(start -1.2954 0.5842)
			(end 1.2954 0.5842)
			(stroke
				(width 0.1524)
				(type default)
			)
			(layer "B.SilkS")
		)
		(fp_line
			(start -1.2954 -0.5842)
			(end -1.2954 0.5842)
			(stroke
				(width 0.1524)
				(type default)
			)
			(layer "B.SilkS")
		)
		(fp_line
			(start 1.1938 0.4064)
			(end 1.1938 -0.4064)
			(stroke
				(width 0.1)
				(type default)
			)
			(layer "B.Fab")
		)
		(fp_line
			(start 1.1938 -0.4064)
			(end 0.8636 -0.4064)
			(stroke
				(width 0.1)
				(type default)
			)
			(layer "B.Fab")
		)
		(fp_line
			(start 0.8636 0.4572)
			(end 0.8636 0.4064)
			(stroke
				(width 0.1)
				(type default)
			)
			(layer "B.Fab")
		)
		(fp_line
			(start 0.8636 0.4064)
			(end 1.1938 0.4064)
			(stroke
				(width 0.1)
				(type default)
			)
			(layer "B.Fab")
		)
		(fp_line
			(start 0.8636 -0.4064)
			(end 0.8636 -0.4572)
			(stroke
				(width 0.1)
				(type default)
			)
			(layer "B.Fab")
		)
		(fp_line
			(start 0.8636 -0.4572)
			(end -0.8636 -0.4572)
			(stroke
				(width 0.1)
				(type default)
			)
			(layer "B.Fab")
		)
		(fp_line
			(start -0.8636 0.4572)
			(end 0.8636 0.4572)
			(stroke
				(width 0.1)
				(type default)
			)
			(layer "B.Fab")
		)
		(fp_line
			(start -0.8636 0.4064)
			(end -0.8636 0.4572)
			(stroke
				(width 0.1)
				(type default)
			)
			(layer "B.Fab")
		)
		(fp_line
			(start -0.8636 -0.4064)
			(end -1.1938 -0.4064)
			(stroke
				(width 0.1)
				(type default)
			)
			(layer "B.Fab")
		)
		(fp_line
			(start -0.8636 -0.4572)
			(end -0.8636 -0.4064)
			(stroke
				(width 0.1)
				(type default)
			)
			(layer "B.Fab")
		)
		(fp_line
			(start -1.1938 0.4064)
			(end -0.8636 0.4064)
			(stroke
				(width 0.1)
				(type default)
			)
			(layer "B.Fab")
		)
		(fp_line
			(start -1.1938 -0.4064)
			(end -1.1938 0.4064)
			(stroke
				(width 0.1)
				(type default)
			)
			(layer "B.Fab")
		)
		(pad "1" smd rect
			(at 0.7366 0 90)
			(size 0.7112 0.8128)
			(layers "B.Cu" "B.Mask" "B.Paste")
			(net "P3V3_DB2000_VDDR")
		)
		(pad "2" smd rect
			(at -0.7366 0 90)
			(size 0.7112 0.8128)
			(layers "B.Cu" "B.Mask" "B.Paste")
			(net "GND")
		)
	)
	(footprint ""
		(layer "B.Cu")
		(at 201.08799 -318.997076 90)
		(property "Reference" "R905"
			(at 0 0 90)
			(layer "B.SilkS")
			(hide yes)
			(effects
				(font
					(size 1.27 1.27)
				)
				(justify mirror)
			)
		)
		(property "Value" ""
			(at 0 0 90)
			(layer "B.Fab")
			(effects
				(font
					(size 1.27 1.27)
				)
				(justify mirror)
			)
		)
		(duplicate_pad_numbers_are_jumpers no)
		(fp_line
			(start 0.7874 -0.4064)
			(end -0.7874 -0.4064)
			(stroke
				(width 0.1524)
				(type default)
			)
			(layer "B.SilkS")
		)
		(fp_line
			(start -0.7874 -0.4064)
			(end -0.7874 0.4064)
			(stroke
				(width 0.1524)
				(type default)
			)
			(layer "B.SilkS")
		)
		(fp_line
			(start 0.7874 0.4064)
			(end 0.7874 -0.4064)
			(stroke
				(width 0.1524)
				(type default)
			)
			(layer "B.SilkS")
		)
		(fp_line
			(start -0.7874 0.4064)
			(end 0.7874 0.4064)
			(stroke
				(width 0.1524)
				(type default)
			)
			(layer "B.SilkS")
		)
		(fp_line
			(start 0.67945 -0.305054)
			(end 0.12065 -0.305054)
			(stroke
				(width 0.1)
				(type default)
			)
			(layer "B.Fab")
		)
		(fp_line
			(start 0.12065 -0.305054)
			(end 0.12065 -0.2794)
			(stroke
				(width 0.1)
				(type default)
			)
			(layer "B.Fab")
		)
		(fp_line
			(start -0.12065 -0.3048)
			(end -0.67945 -0.3048)
			(stroke
				(width 0.1)
				(type default)
			)
			(layer "B.Fab")
		)
		(fp_line
			(start -0.67945 -0.3048)
			(end -0.67945 0.3048)
			(stroke
				(width 0.1)
				(type default)
			)
			(layer "B.Fab")
		)
		(fp_line
			(start 0.12065 -0.2794)
			(end -0.12065 -0.2794)
			(stroke
				(width 0.1)
				(type default)
			)
			(layer "B.Fab")
		)
		(fp_line
			(start -0.12065 -0.2794)
			(end -0.12065 -0.3048)
			(stroke
				(width 0.1)
				(type default)
			)
			(layer "B.Fab")
		)
		(fp_line
			(start 0.12065 0.2794)
			(end 0.12065 0.3048)
			(stroke
				(width 0.1)
				(type default)
			)
			(layer "B.Fab")
		)
		(fp_line
			(start -0.120396 0.2794)
			(end 0.12065 0.2794)
			(stroke
				(width 0.1)
				(type default)
			)
			(layer "B.Fab")
		)
		(fp_line
			(start 0.67945 0.3048)
			(end 0.67945 -0.305054)
			(stroke
				(width 0.1)
				(type default)
			)
			(layer "B.Fab")
		)
		(fp_line
			(start 0.12065 0.3048)
			(end 0.67945 0.3048)
			(stroke
				(width 0.1)
				(type default)
			)
			(layer "B.Fab")
		)
		(fp_line
			(start -0.120396 0.3048)
			(end -0.120396 0.2794)
			(stroke
				(width 0.1)
				(type default)
			)
			(layer "B.Fab")
		)
		(fp_line
			(start -0.67945 0.3048)
			(end -0.120396 0.3048)
			(stroke
				(width 0.1)
				(type default)
			)
			(layer "B.Fab")
		)
		(pad "1" smd circle
			(at 0.40005 0 270)
			(size 0 0)
			(layers "B.Cu" "B.Mask" "B.Paste")
			(net "PWRGD_CHG_CPU1_DIMM1")
		)
		(pad "2" smd circle
			(at -0.40005 0 270)
			(size 0 0)
			(layers "B.Cu" "B.Mask" "B.Paste")
			(net "PWRGD_FAIL_CPU1_GH")
		)
	)
	(footprint ""
		(layer "B.Cu")
		(at 173.145958 -353.599242 90)
		(property "Reference" "PC403_P1_1"
			(at 0 0 90)
			(layer "B.SilkS")
			(hide yes)
			(effects
				(font
					(size 1.27 1.27)
				)
				(justify mirror)
			)
		)
		(property "Value" ""
			(at 0 0 90)
			(layer "B.Fab")
			(effects
				(font
					(size 1.27 1.27)
				)
				(justify mirror)
			)
		)
		(duplicate_pad_numbers_are_jumpers no)
		(fp_line
			(start 1.524 -0.762)
			(end -1.524 -0.762)
			(stroke
				(width 0.1524)
				(type default)
			)
			(layer "B.SilkS")
		)
		(fp_line
			(start -1.524 -0.762)
			(end -1.524 0.762)
			(stroke
				(width 0.1524)
				(type default)
			)
			(layer "B.SilkS")
		)
		(fp_line
			(start 1.524 0.762)
			(end 1.524 -0.762)
			(stroke
				(width 0.1524)
				(type default)
			)
			(layer "B.SilkS")
		)
		(fp_line
			(start -1.524 0.762)
			(end 1.524 0.762)
			(stroke
				(width 0.1524)
				(type default)
			)
			(layer "B.SilkS")
		)
		(fp_line
			(start 1.1049 -0.724916)
			(end 1.1049 0.724916)
			(stroke
				(width 0.1)
				(type default)
			)
			(layer "B.Fab")
		)
		(fp_line
			(start -1.1049 -0.724916)
			(end 1.1049 -0.724916)
			(stroke
				(width 0.1)
				(type default)
			)
			(layer "B.Fab")
		)
		(fp_line
			(start 1.1049 0.724916)
			(end -1.1049 0.724916)
			(stroke
				(width 0.1)
				(type default)
			)
			(layer "B.Fab")
		)
		(fp_line
			(start -1.1049 0.724916)
			(end -1.1049 -0.724916)
			(stroke
				(width 0.1)
				(type default)
			)
			(layer "B.Fab")
		)
		(pad "1" smd rect
			(at 0.889 0 90)
			(size 1.016 1.27)
			(layers "B.Cu" "B.Mask" "B.Paste")
			(net "SW_P12V_PVCCFA_EHV_FIVRA_CPU1_R")
		)
		(pad "2" smd rect
			(at -0.889 0 90)
			(size 1.016 1.27)
			(layers "B.Cu" "B.Mask" "B.Paste")
			(net "GND")
		)
	)
	(footprint ""
		(layer "B.Cu")
		(at 126.87554 -20.985988 -90)
		(property "Reference" "R4291"
			(at 0 0 90)
			(layer "B.SilkS")
			(hide yes)
			(effects
				(font
					(size 1.27 1.27)
				)
				(justify mirror)
			)
		)
		(property "Value" ""
			(at 0 0 90)
			(layer "B.Fab")
			(effects
				(font
					(size 1.27 1.27)
				)
				(justify mirror)
			)
		)
		(duplicate_pad_numbers_are_jumpers no)
		(fp_line
			(start -0.7874 0.4064)
			(end 0.7874 0.4064)
			(stroke
				(width 0.1524)
				(type default)
			)
			(layer "B.SilkS")
		)
		(fp_line
			(start 0.7874 0.4064)
			(end 0.7874 -0.4064)
			(stroke
				(width 0.1524)
				(type default)
			)
			(layer "B.SilkS")
		)
		(fp_line
			(start -0.7874 -0.4064)
			(end -0.7874 0.4064)
			(stroke
				(width 0.1524)
				(type default)
			)
			(layer "B.SilkS")
		)
		(fp_line
			(start 0.7874 -0.4064)
			(end -0.7874 -0.4064)
			(stroke
				(width 0.1524)
				(type default)
			)
			(layer "B.SilkS")
		)
		(fp_line
			(start -0.67945 0.3048)
			(end -0.120396 0.3048)
			(stroke
				(width 0.1)
				(type default)
			)
			(layer "B.Fab")
		)
		(fp_line
			(start -0.120396 0.3048)
			(end -0.120396 0.2794)
			(stroke
				(width 0.1)
				(type default)
			)
			(layer "B.Fab")
		)
		(fp_line
			(start 0.12065 0.3048)
			(end 0.67945 0.3048)
			(stroke
				(width 0.1)
				(type default)
			)
			(layer "B.Fab")
		)
		(fp_line
			(start 0.67945 0.3048)
			(end 0.67945 -0.305054)
			(stroke
				(width 0.1)
				(type default)
			)
			(layer "B.Fab")
		)
		(fp_line
			(start -0.120396 0.2794)
			(end 0.12065 0.2794)
			(stroke
				(width 0.1)
				(type default)
			)
			(layer "B.Fab")
		)
		(fp_line
			(start 0.12065 0.2794)
			(end 0.12065 0.3048)
			(stroke
				(width 0.1)
				(type default)
			)
			(layer "B.Fab")
		)
		(fp_line
			(start -0.12065 -0.2794)
			(end -0.12065 -0.3048)
			(stroke
				(width 0.1)
				(type default)
			)
			(layer "B.Fab")
		)
		(fp_line
			(start 0.12065 -0.2794)
			(end -0.12065 -0.2794)
			(stroke
				(width 0.1)
				(type default)
			)
			(layer "B.Fab")
		)
		(fp_line
			(start -0.67945 -0.3048)
			(end -0.67945 0.3048)
			(stroke
				(width 0.1)
				(type default)
			)
			(layer "B.Fab")
		)
		(fp_line
			(start -0.12065 -0.3048)
			(end -0.67945 -0.3048)
			(stroke
				(width 0.1)
				(type default)
			)
			(layer "B.Fab")
		)
		(fp_line
			(start 0.12065 -0.305054)
			(end 0.12065 -0.2794)
			(stroke
				(width 0.1)
				(type default)
			)
			(layer "B.Fab")
		)
		(fp_line
			(start 0.67945 -0.305054)
			(end 0.12065 -0.305054)
			(stroke
				(width 0.1)
				(type default)
			)
			(layer "B.Fab")
		)
		(pad "1" smd circle
			(at 0.40005 0 90)
			(size 0 0)
			(layers "B.Cu" "B.Mask" "B.Paste")
			(net "P3V3_AUX")
		)
		(pad "2" smd circle
			(at -0.40005 0 90)
			(size 0 0)
			(layers "B.Cu" "B.Mask" "B.Paste")
			(net "FM_USB3_1_EN_N")
		)
	)
	(footprint ""
		(layer "B.Cu")
		(at 127.907542 -366.723168 90)
		(property "Reference" "PC1269"
			(at 0 0 90)
			(layer "B.SilkS")
			(hide yes)
			(effects
				(font
					(size 1.27 1.27)
				)
				(justify mirror)
			)
		)
		(property "Value" ""
			(at 0 0 90)
			(layer "B.Fab")
			(effects
				(font
					(size 1.27 1.27)
				)
				(justify mirror)
			)
		)
		(duplicate_pad_numbers_are_jumpers no)
		(fp_line
			(start 1.524 -0.762)
			(end -1.524 -0.762)
			(stroke
				(width 0.1524)
				(type default)
			)
			(layer "B.SilkS")
		)
		(fp_line
			(start -1.524 -0.762)
			(end -1.524 0.762)
			(stroke
				(width 0.1524)
				(type default)
			)
			(layer "B.SilkS")
		)
		(fp_line
			(start 1.524 0.762)
			(end 1.524 -0.762)
			(stroke
				(width 0.1524)
				(type default)
			)
			(layer "B.SilkS")
		)
		(fp_line
			(start -1.524 0.762)
			(end 1.524 0.762)
			(stroke
				(width 0.1524)
				(type default)
			)
			(layer "B.SilkS")
		)
		(fp_line
			(start 1.1049 -0.724916)
			(end 1.1049 0.724916)
			(stroke
				(width 0.1)
				(type default)
			)
			(layer "B.Fab")
		)
		(fp_line
			(start -1.1049 -0.724916)
			(end 1.1049 -0.724916)
			(stroke
				(width 0.1)
				(type default)
			)
			(layer "B.Fab")
		)
		(fp_line
			(start 1.1049 0.724916)
			(end -1.1049 0.724916)
			(stroke
				(width 0.1)
				(type default)
			)
			(layer "B.Fab")
		)
		(fp_line
			(start -1.1049 0.724916)
			(end -1.1049 -0.724916)
			(stroke
				(width 0.1)
				(type default)
			)
			(layer "B.Fab")
		)
		(pad "1" smd rect
			(at 0.889 0 90)
			(size 1.016 1.27)
			(layers "B.Cu" "B.Mask" "B.Paste")
			(net "PVPP_HBM_CPU1")
		)
		(pad "2" smd rect
			(at -0.889 0 90)
			(size 1.016 1.27)
			(layers "B.Cu" "B.Mask" "B.Paste")
			(net "GND")
		)
	)
	(footprint ""
		(layer "B.Cu")
		(at 143.0274 -13.762228 90)
		(property "Reference" "R1815"
			(at 0 0 90)
			(layer "B.SilkS")
			(hide yes)
			(effects
				(font
					(size 1.27 1.27)
				)
				(justify mirror)
			)
		)
		(property "Value" ""
			(at 0 0 90)
			(layer "B.Fab")
			(effects
				(font
					(size 1.27 1.27)
				)
				(justify mirror)
			)
		)
		(duplicate_pad_numbers_are_jumpers no)
		(fp_line
			(start 0.7874 -0.4064)
			(end -0.7874 -0.4064)
			(stroke
				(width 0.1524)
				(type default)
			)
			(layer "B.SilkS")
		)
		(fp_line
			(start -0.7874 -0.4064)
			(end -0.7874 0.4064)
			(stroke
				(width 0.1524)
				(type default)
			)
			(layer "B.SilkS")
		)
		(fp_line
			(start 0.7874 0.4064)
			(end 0.7874 -0.4064)
			(stroke
				(width 0.1524)
				(type default)
			)
			(layer "B.SilkS")
		)
		(fp_line
			(start -0.7874 0.4064)
			(end 0.7874 0.4064)
			(stroke
				(width 0.1524)
				(type default)
			)
			(layer "B.SilkS")
		)
		(fp_line
			(start 0.67945 -0.305054)
			(end 0.12065 -0.305054)
			(stroke
				(width 0.1)
				(type default)
			)
			(layer "B.Fab")
		)
		(fp_line
			(start 0.12065 -0.305054)
			(end 0.12065 -0.2794)
			(stroke
				(width 0.1)
				(type default)
			)
			(layer "B.Fab")
		)
		(fp_line
			(start -0.12065 -0.3048)
			(end -0.67945 -0.3048)
			(stroke
				(width 0.1)
				(type default)
			)
			(layer "B.Fab")
		)
		(fp_line
			(start -0.67945 -0.3048)
			(end -0.67945 0.3048)
			(stroke
				(width 0.1)
				(type default)
			)
			(layer "B.Fab")
		)
		(fp_line
			(start 0.12065 -0.2794)
			(end -0.12065 -0.2794)
			(stroke
				(width 0.1)
				(type default)
			)
			(layer "B.Fab")
		)
		(fp_line
			(start -0.12065 -0.2794)
			(end -0.12065 -0.3048)
			(stroke
				(width 0.1)
				(type default)
			)
			(layer "B.Fab")
		)
		(fp_line
			(start 0.12065 0.2794)
			(end 0.12065 0.3048)
			(stroke
				(width 0.1)
				(type default)
			)
			(layer "B.Fab")
		)
		(fp_line
			(start -0.120396 0.2794)
			(end 0.12065 0.2794)
			(stroke
				(width 0.1)
				(type default)
			)
			(layer "B.Fab")
		)
		(fp_line
			(start 0.67945 0.3048)
			(end 0.67945 -0.305054)
			(stroke
				(width 0.1)
				(type default)
			)
			(layer "B.Fab")
		)
		(fp_line
			(start 0.12065 0.3048)
			(end 0.67945 0.3048)
			(stroke
				(width 0.1)
				(type default)
			)
			(layer "B.Fab")
		)
		(fp_line
			(start -0.120396 0.3048)
			(end -0.120396 0.2794)
			(stroke
				(width 0.1)
				(type default)
			)
			(layer "B.Fab")
		)
		(fp_line
			(start -0.67945 0.3048)
			(end -0.120396 0.3048)
			(stroke
				(width 0.1)
				(type default)
			)
			(layer "B.Fab")
		)
		(pad "1" smd circle
			(at 0.40005 0 270)
			(size 0 0)
			(layers "B.Cu" "B.Mask" "B.Paste")
			(net "FM_BMC_PWRBTN_OUT_N")
		)
		(pad "2" smd circle
			(at -0.40005 0 270)
			(size 0 0)
			(layers "B.Cu" "B.Mask" "B.Paste")
			(net "FM_BMC_PWRBTN_OUT_R_N")
		)
	)
	(footprint ""
		(layer "B.Cu")
		(at 430.600104 -132.462778)
		(property "Reference" "R2383"
			(at 0 0 0)
			(layer "B.SilkS")
			(hide yes)
			(effects
				(font
					(size 1.27 1.27)
				)
				(justify mirror)
			)
		)
		(property "Value" ""
			(at 0 0 0)
			(layer "B.Fab")
			(effects
				(font
					(size 1.27 1.27)
				)
				(justify mirror)
			)
		)
		(duplicate_pad_numbers_are_jumpers no)
		(fp_line
			(start -0.7874 -0.4064)
			(end -0.7874 0.4064)
			(stroke
				(width 0.1524)
				(type default)
			)
			(layer "B.SilkS")
		)
		(fp_line
			(start -0.7874 0.4064)
			(end 0.7874 0.4064)
			(stroke
				(width 0.1524)
				(type default)
			)
			(layer "B.SilkS")
		)
		(fp_line
			(start 0.7874 -0.4064)
			(end -0.7874 -0.4064)
			(stroke
				(width 0.1524)
				(type default)
			)
			(layer "B.SilkS")
		)
		(fp_line
			(start 0.7874 0.4064)
			(end 0.7874 -0.4064)
			(stroke
				(width 0.1524)
				(type default)
			)
			(layer "B.SilkS")
		)
		(fp_line
			(start -0.67945 -0.3048)
			(end -0.67945 0.3048)
			(stroke
				(width 0.1)
				(type default)
			)
			(layer "B.Fab")
		)
		(fp_line
			(start -0.67945 0.3048)
			(end -0.120396 0.3048)
			(stroke
				(width 0.1)
				(type default)
			)
			(layer "B.Fab")
		)
		(fp_line
			(start -0.12065 -0.3048)
			(end -0.67945 -0.3048)
			(stroke
				(width 0.1)
				(type default)
			)
			(layer "B.Fab")
		)
		(fp_line
			(start -0.12065 -0.2794)
			(end -0.12065 -0.3048)
			(stroke
				(width 0.1)
				(type default)
			)
			(layer "B.Fab")
		)
		(fp_line
			(start -0.120396 0.2794)
			(end 0.12065 0.2794)
			(stroke
				(width 0.1)
				(type default)
			)
			(layer "B.Fab")
		)
		(fp_line
			(start -0.120396 0.3048)
			(end -0.120396 0.2794)
			(stroke
				(width 0.1)
				(type default)
			)
			(layer "B.Fab")
		)
		(fp_line
			(start 0.12065 -0.305054)
			(end 0.12065 -0.2794)
			(stroke
				(width 0.1)
				(type default)
			)
			(layer "B.Fab")
		)
		(fp_line
			(start 0.12065 -0.2794)
			(end -0.12065 -0.2794)
			(stroke
				(width 0.1)
				(type default)
			)
			(layer "B.Fab")
		)
		(fp_line
			(start 0.12065 0.2794)
			(end 0.12065 0.3048)
			(stroke
				(width 0.1)
				(type default)
			)
			(layer "B.Fab")
		)
		(fp_line
			(start 0.12065 0.3048)
			(end 0.67945 0.3048)
			(stroke
				(width 0.1)
				(type default)
			)
			(layer "B.Fab")
		)
		(fp_line
			(start 0.67945 -0.305054)
			(end 0.12065 -0.305054)
			(stroke
				(width 0.1)
				(type default)
			)
			(layer "B.Fab")
		)
		(fp_line
			(start 0.67945 0.3048)
			(end 0.67945 -0.305054)
			(stroke
				(width 0.1)
				(type default)
			)
			(layer "B.Fab")
		)
		(pad "1" smd circle
			(at 0.40005 0 180)
			(size 0 0)
			(layers "B.Cu" "B.Mask" "B.Paste")
			(net "P3V3_AUX")
		)
		(pad "2" smd circle
			(at -0.40005 0 180)
			(size 0 0)
			(layers "B.Cu" "B.Mask" "B.Paste")
			(net "PWRGD_PVCCINFAON_CPU0_R")
		)
	)
	(footprint ""
		(layer "B.Cu")
		(at 256.271268 -75.32878 90)
		(property "Reference" "R4780"
			(at 0 0 90)
			(layer "B.SilkS")
			(hide yes)
			(effects
				(font
					(size 1.27 1.27)
				)
				(justify mirror)
			)
		)
		(property "Value" ""
			(at 0 0 90)
			(layer "B.Fab")
			(effects
				(font
					(size 1.27 1.27)
				)
				(justify mirror)
			)
		)
		(duplicate_pad_numbers_are_jumpers no)
		(fp_line
			(start 0.7874 -0.4064)
			(end -0.7874 -0.4064)
			(stroke
				(width 0.1524)
				(type default)
			)
			(layer "B.SilkS")
		)
		(fp_line
			(start -0.7874 -0.4064)
			(end -0.7874 0.4064)
			(stroke
				(width 0.1524)
				(type default)
			)
			(layer "B.SilkS")
		)
		(fp_line
			(start 0.7874 0.4064)
			(end 0.7874 -0.4064)
			(stroke
				(width 0.1524)
				(type default)
			)
			(layer "B.SilkS")
		)
		(fp_line
			(start -0.7874 0.4064)
			(end 0.7874 0.4064)
			(stroke
				(width 0.1524)
				(type default)
			)
			(layer "B.SilkS")
		)
		(fp_line
			(start 0.67945 -0.305054)
			(end 0.12065 -0.305054)
			(stroke
				(width 0.1)
				(type default)
			)
			(layer "B.Fab")
		)
		(fp_line
			(start 0.12065 -0.305054)
			(end 0.12065 -0.2794)
			(stroke
				(width 0.1)
				(type default)
			)
			(layer "B.Fab")
		)
		(fp_line
			(start -0.12065 -0.3048)
			(end -0.67945 -0.3048)
			(stroke
				(width 0.1)
				(type default)
			)
			(layer "B.Fab")
		)
		(fp_line
			(start -0.67945 -0.3048)
			(end -0.67945 0.3048)
			(stroke
				(width 0.1)
				(type default)
			)
			(layer "B.Fab")
		)
		(fp_line
			(start 0.12065 -0.2794)
			(end -0.12065 -0.2794)
			(stroke
				(width 0.1)
				(type default)
			)
			(layer "B.Fab")
		)
		(fp_line
			(start -0.12065 -0.2794)
			(end -0.12065 -0.3048)
			(stroke
				(width 0.1)
				(type default)
			)
			(layer "B.Fab")
		)
		(fp_line
			(start 0.12065 0.2794)
			(end 0.12065 0.3048)
			(stroke
				(width 0.1)
				(type default)
			)
			(layer "B.Fab")
		)
		(fp_line
			(start -0.120396 0.2794)
			(end 0.12065 0.2794)
			(stroke
				(width 0.1)
				(type default)
			)
			(layer "B.Fab")
		)
		(fp_line
			(start 0.67945 0.3048)
			(end 0.67945 -0.305054)
			(stroke
				(width 0.1)
				(type default)
			)
			(layer "B.Fab")
		)
		(fp_line
			(start 0.12065 0.3048)
			(end 0.67945 0.3048)
			(stroke
				(width 0.1)
				(type default)
			)
			(layer "B.Fab")
		)
		(fp_line
			(start -0.120396 0.3048)
			(end -0.120396 0.2794)
			(stroke
				(width 0.1)
				(type default)
			)
			(layer "B.Fab")
		)
		(fp_line
			(start -0.67945 0.3048)
			(end -0.120396 0.3048)
			(stroke
				(width 0.1)
				(type default)
			)
			(layer "B.Fab")
		)
		(pad "1" smd circle
			(at 0.40005 0 270)
			(size 0 0)
			(layers "B.Cu" "B.Mask" "B.Paste")
			(net "PWRGD_P1V05_PCH_AUX_R")
		)
		(pad "2" smd circle
			(at -0.40005 0 270)
			(size 0 0)
			(layers "B.Cu" "B.Mask" "B.Paste")
			(net "PWRGD_PVNN_PCH_AUX")
		)
	)
	(footprint ""
		(layer "B.Cu")
		(at 433.21478 -50.72888 180)
		(property "Reference" "R4680"
			(at 0 0 0)
			(layer "B.SilkS")
			(hide yes)
			(effects
				(font
					(size 1.27 1.27)
				)
				(justify mirror)
			)
		)
		(property "Value" ""
			(at 0 0 0)
			(layer "B.Fab")
			(effects
				(font
					(size 1.27 1.27)
				)
				(justify mirror)
			)
		)
		(duplicate_pad_numbers_are_jumpers no)
		(fp_line
			(start 0.7874 0.4064)
			(end 0.7874 -0.4064)
			(stroke
				(width 0.1524)
				(type default)
			)
			(layer "B.SilkS")
		)
		(fp_line
			(start 0.7874 -0.4064)
			(end -0.7874 -0.4064)
			(stroke
				(width 0.1524)
				(type default)
			)
			(layer "B.SilkS")
		)
		(fp_line
			(start -0.7874 0.4064)
			(end 0.7874 0.4064)
			(stroke
				(width 0.1524)
				(type default)
			)
			(layer "B.SilkS")
		)
		(fp_line
			(start -0.7874 -0.4064)
			(end -0.7874 0.4064)
			(stroke
				(width 0.1524)
				(type default)
			)
			(layer "B.SilkS")
		)
		(fp_line
			(start 0.67945 0.3048)
			(end 0.67945 -0.305054)
			(stroke
				(width 0.1)
				(type default)
			)
			(layer "B.Fab")
		)
		(fp_line
			(start 0.67945 -0.305054)
			(end 0.12065 -0.305054)
			(stroke
				(width 0.1)
				(type default)
			)
			(layer "B.Fab")
		)
		(fp_line
			(start 0.12065 0.3048)
			(end 0.67945 0.3048)
			(stroke
				(width 0.1)
				(type default)
			)
			(layer "B.Fab")
		)
		(fp_line
			(start 0.12065 0.2794)
			(end 0.12065 0.3048)
			(stroke
				(width 0.1)
				(type default)
			)
			(layer "B.Fab")
		)
		(fp_line
			(start 0.12065 -0.2794)
			(end -0.12065 -0.2794)
			(stroke
				(width 0.1)
				(type default)
			)
			(layer "B.Fab")
		)
		(fp_line
			(start 0.12065 -0.305054)
			(end 0.12065 -0.2794)
			(stroke
				(width 0.1)
				(type default)
			)
			(layer "B.Fab")
		)
		(fp_line
			(start -0.120396 0.3048)
			(end -0.120396 0.2794)
			(stroke
				(width 0.1)
				(type default)
			)
			(layer "B.Fab")
		)
		(fp_line
			(start -0.120396 0.2794)
			(end 0.12065 0.2794)
			(stroke
				(width 0.1)
				(type default)
			)
			(layer "B.Fab")
		)
		(fp_line
			(start -0.12065 -0.2794)
			(end -0.12065 -0.3048)
			(stroke
				(width 0.1)
				(type default)
			)
			(layer "B.Fab")
		)
		(fp_line
			(start -0.12065 -0.3048)
			(end -0.67945 -0.3048)
			(stroke
				(width 0.1)
				(type default)
			)
			(layer "B.Fab")
		)
		(fp_line
			(start -0.67945 0.3048)
			(end -0.120396 0.3048)
			(stroke
				(width 0.1)
				(type default)
			)
			(layer "B.Fab")
		)
		(fp_line
			(start -0.67945 -0.3048)
			(end -0.67945 0.3048)
			(stroke
				(width 0.1)
				(type default)
			)
			(layer "B.Fab")
		)
		(pad "1" smd circle
			(at 0.40005 0)
			(size 0 0)
			(layers "B.Cu" "B.Mask" "B.Paste")
			(net "P12V_AUX")
		)
		(pad "2" smd circle
			(at -0.40005 0)
			(size 0 0)
			(layers "B.Cu" "B.Mask" "B.Paste")
			(net "PWRGD_P5V_N")
		)
	)
	(footprint ""
		(layer "B.Cu")
		(at 116.575586 -333.73568 90)
		(property "Reference" "PC534_P1_3"
			(at 0 0 90)
			(layer "B.SilkS")
			(hide yes)
			(effects
				(font
					(size 1.27 1.27)
				)
				(justify mirror)
			)
		)
		(property "Value" ""
			(at 0 0 90)
			(layer "B.Fab")
			(effects
				(font
					(size 1.27 1.27)
				)
				(justify mirror)
			)
		)
		(duplicate_pad_numbers_are_jumpers no)
		(fp_line
			(start 1.524 -0.762)
			(end -1.524 -0.762)
			(stroke
				(width 0.1524)
				(type default)
			)
			(layer "B.SilkS")
		)
		(fp_line
			(start -1.524 -0.762)
			(end -1.524 0.762)
			(stroke
				(width 0.1524)
				(type default)
			)
			(layer "B.SilkS")
		)
		(fp_line
			(start 1.524 0.762)
			(end 1.524 -0.762)
			(stroke
				(width 0.1524)
				(type default)
			)
			(layer "B.SilkS")
		)
		(fp_line
			(start -1.524 0.762)
			(end 1.524 0.762)
			(stroke
				(width 0.1524)
				(type default)
			)
			(layer "B.SilkS")
		)
		(fp_line
			(start 1.1049 -0.724916)
			(end 1.1049 0.724916)
			(stroke
				(width 0.1)
				(type default)
			)
			(layer "B.Fab")
		)
		(fp_line
			(start -1.1049 -0.724916)
			(end 1.1049 -0.724916)
			(stroke
				(width 0.1)
				(type default)
			)
			(layer "B.Fab")
		)
		(fp_line
			(start 1.1049 0.724916)
			(end -1.1049 0.724916)
			(stroke
				(width 0.1)
				(type default)
			)
			(layer "B.Fab")
		)
		(fp_line
			(start -1.1049 0.724916)
			(end -1.1049 -0.724916)
			(stroke
				(width 0.1)
				(type default)
			)
			(layer "B.Fab")
		)
		(pad "1" smd rect
			(at 0.889 0 90)
			(size 1.016 1.27)
			(layers "B.Cu" "B.Mask" "B.Paste")
			(net "SW_P12V_PVCCIN_CPU1_FLT")
		)
		(pad "2" smd rect
			(at -0.889 0 90)
			(size 1.016 1.27)
			(layers "B.Cu" "B.Mask" "B.Paste")
			(net "GND")
		)
	)
	(footprint ""
		(layer "B.Cu")
		(at 74.850498 -179.34178 -90)
		(property "Reference" "R298"
			(at 0 0 90)
			(layer "B.SilkS")
			(hide yes)
			(effects
				(font
					(size 1.27 1.27)
				)
				(justify mirror)
			)
		)
		(property "Value" ""
			(at 0 0 90)
			(layer "B.Fab")
			(effects
				(font
					(size 1.27 1.27)
				)
				(justify mirror)
			)
		)
		(duplicate_pad_numbers_are_jumpers no)
		(fp_line
			(start -0.7874 0.4064)
			(end 0.7874 0.4064)
			(stroke
				(width 0.1524)
				(type default)
			)
			(layer "B.SilkS")
		)
		(fp_line
			(start 0.7874 0.4064)
			(end 0.7874 -0.4064)
			(stroke
				(width 0.1524)
				(type default)
			)
			(layer "B.SilkS")
		)
		(fp_line
			(start -0.7874 -0.4064)
			(end -0.7874 0.4064)
			(stroke
				(width 0.1524)
				(type default)
			)
			(layer "B.SilkS")
		)
		(fp_line
			(start 0.7874 -0.4064)
			(end -0.7874 -0.4064)
			(stroke
				(width 0.1524)
				(type default)
			)
			(layer "B.SilkS")
		)
		(fp_line
			(start -0.67945 0.3048)
			(end -0.120396 0.3048)
			(stroke
				(width 0.1)
				(type default)
			)
			(layer "B.Fab")
		)
		(fp_line
			(start -0.120396 0.3048)
			(end -0.120396 0.2794)
			(stroke
				(width 0.1)
				(type default)
			)
			(layer "B.Fab")
		)
		(fp_line
			(start 0.12065 0.3048)
			(end 0.67945 0.3048)
			(stroke
				(width 0.1)
				(type default)
			)
			(layer "B.Fab")
		)
		(fp_line
			(start 0.67945 0.3048)
			(end 0.67945 -0.305054)
			(stroke
				(width 0.1)
				(type default)
			)
			(layer "B.Fab")
		)
		(fp_line
			(start -0.120396 0.2794)
			(end 0.12065 0.2794)
			(stroke
				(width 0.1)
				(type default)
			)
			(layer "B.Fab")
		)
		(fp_line
			(start 0.12065 0.2794)
			(end 0.12065 0.3048)
			(stroke
				(width 0.1)
				(type default)
			)
			(layer "B.Fab")
		)
		(fp_line
			(start -0.12065 -0.2794)
			(end -0.12065 -0.3048)
			(stroke
				(width 0.1)
				(type default)
			)
			(layer "B.Fab")
		)
		(fp_line
			(start 0.12065 -0.2794)
			(end -0.12065 -0.2794)
			(stroke
				(width 0.1)
				(type default)
			)
			(layer "B.Fab")
		)
		(fp_line
			(start -0.67945 -0.3048)
			(end -0.67945 0.3048)
			(stroke
				(width 0.1)
				(type default)
			)
			(layer "B.Fab")
		)
		(fp_line
			(start -0.12065 -0.3048)
			(end -0.67945 -0.3048)
			(stroke
				(width 0.1)
				(type default)
			)
			(layer "B.Fab")
		)
		(fp_line
			(start 0.12065 -0.305054)
			(end 0.12065 -0.2794)
			(stroke
				(width 0.1)
				(type default)
			)
			(layer "B.Fab")
		)
		(fp_line
			(start 0.67945 -0.305054)
			(end 0.12065 -0.305054)
			(stroke
				(width 0.1)
				(type default)
			)
			(layer "B.Fab")
		)
		(pad "1" smd circle
			(at 0.40005 0 90)
			(size 0 0)
			(layers "B.Cu" "B.Mask" "B.Paste")
			(net "PVNN_TERM_CPU1")
		)
		(pad "2" smd circle
			(at -0.40005 0 90)
			(size 0 0)
			(layers "B.Cu" "B.Mask" "B.Paste")
			(net "H_CPU_CATERR_LVC1_R_N")
		)
	)
	(footprint ""
		(layer "B.Cu")
		(at 170.20032 -13.762228 90)
		(property "Reference" "R4536"
			(at 0 0 90)
			(layer "B.SilkS")
			(hide yes)
			(effects
				(font
					(size 1.27 1.27)
				)
				(justify mirror)
			)
		)
		(property "Value" ""
			(at 0 0 90)
			(layer "B.Fab")
			(effects
				(font
					(size 1.27 1.27)
				)
				(justify mirror)
			)
		)
		(duplicate_pad_numbers_are_jumpers no)
		(fp_line
			(start 0.7874 -0.4064)
			(end -0.7874 -0.4064)
			(stroke
				(width 0.1524)
				(type default)
			)
			(layer "B.SilkS")
		)
		(fp_line
			(start -0.7874 -0.4064)
			(end -0.7874 0.14732)
			(stroke
				(width 0.1524)
				(type default)
			)
			(layer "B.SilkS")
		)
		(fp_line
			(start 0.7874 0.20574)
			(end 0.7874 -0.4064)
			(stroke
				(width 0.1524)
				(type default)
			)
			(layer "B.SilkS")
		)
		(fp_line
			(start -0.10668 0.4064)
			(end 0.40386 0.4064)
			(stroke
				(width 0.1524)
				(type default)
			)
			(layer "B.SilkS")
		)
		(fp_line
			(start 0.67945 -0.305054)
			(end 0.12065 -0.305054)
			(stroke
				(width 0.1)
				(type default)
			)
			(layer "B.Fab")
		)
		(fp_line
			(start 0.12065 -0.305054)
			(end 0.12065 -0.2794)
			(stroke
				(width 0.1)
				(type default)
			)
			(layer "B.Fab")
		)
		(fp_line
			(start -0.12065 -0.3048)
			(end -0.67945 -0.3048)
			(stroke
				(width 0.1)
				(type default)
			)
			(layer "B.Fab")
		)
		(fp_line
			(start -0.67945 -0.3048)
			(end -0.67945 0.3048)
			(stroke
				(width 0.1)
				(type default)
			)
			(layer "B.Fab")
		)
		(fp_line
			(start 0.12065 -0.2794)
			(end -0.12065 -0.2794)
			(stroke
				(width 0.1)
				(type default)
			)
			(layer "B.Fab")
		)
		(fp_line
			(start -0.12065 -0.2794)
			(end -0.12065 -0.3048)
			(stroke
				(width 0.1)
				(type default)
			)
			(layer "B.Fab")
		)
		(fp_line
			(start 0.12065 0.2794)
			(end 0.12065 0.3048)
			(stroke
				(width 0.1)
				(type default)
			)
			(layer "B.Fab")
		)
		(fp_line
			(start -0.120396 0.2794)
			(end 0.12065 0.2794)
			(stroke
				(width 0.1)
				(type default)
			)
			(layer "B.Fab")
		)
		(fp_line
			(start 0.67945 0.3048)
			(end 0.67945 -0.305054)
			(stroke
				(width 0.1)
				(type default)
			)
			(layer "B.Fab")
		)
		(fp_line
			(start 0.12065 0.3048)
			(end 0.67945 0.3048)
			(stroke
				(width 0.1)
				(type default)
			)
			(layer "B.Fab")
		)
		(fp_line
			(start -0.120396 0.3048)
			(end -0.120396 0.2794)
			(stroke
				(width 0.1)
				(type default)
			)
			(layer "B.Fab")
		)
		(fp_line
			(start -0.67945 0.3048)
			(end -0.120396 0.3048)
			(stroke
				(width 0.1)
				(type default)
			)
			(layer "B.Fab")
		)
		(pad "1" smd circle
			(at 0.40005 0 270)
			(size 0 0)
			(layers "B.Cu" "B.Mask" "B.Paste")
			(net "CLK_100M_BMC_P3E_DN")
		)
		(pad "2" smd circle
			(at -0.40005 0 270)
			(size 0 0)
			(layers "B.Cu" "B.Mask" "B.Paste")
			(net "CLK_100M_BMC_P3E_DN_R")
		)
	)
	(footprint ""
		(layer "B.Cu")
		(at 367.009934 -237.709202 -90)
		(property "Reference" "C532"
			(at 0 0 90)
			(layer "B.SilkS")
			(hide yes)
			(effects
				(font
					(size 1.27 1.27)
				)
				(justify mirror)
			)
		)
		(property "Value" ""
			(at 0 0 90)
			(layer "B.Fab")
			(effects
				(font
					(size 1.27 1.27)
				)
				(justify mirror)
			)
		)
		(duplicate_pad_numbers_are_jumpers no)
		(fp_line
			(start -1.2954 0.5842)
			(end 1.2954 0.5842)
			(stroke
				(width 0.1524)
				(type default)
			)
			(layer "B.SilkS")
		)
		(fp_line
			(start 1.2954 0.5842)
			(end 1.2954 -0.5842)
			(stroke
				(width 0.1524)
				(type default)
			)
			(layer "B.SilkS")
		)
		(fp_line
			(start -1.2954 -0.5842)
			(end -1.2954 0.5842)
			(stroke
				(width 0.1524)
				(type default)
			)
			(layer "B.SilkS")
		)
		(fp_line
			(start 0 -0.5842)
			(end 0 0.5842)
			(stroke
				(width 0.1524)
				(type default)
			)
			(layer "B.SilkS")
		)
		(fp_line
			(start 1.2954 -0.5842)
			(end -1.2954 -0.5842)
			(stroke
				(width 0.1524)
				(type default)
			)
			(layer "B.SilkS")
		)
		(fp_line
			(start -0.8636 0.4572)
			(end 0.8636 0.4572)
			(stroke
				(width 0.1)
				(type default)
			)
			(layer "B.Fab")
		)
		(fp_line
			(start 0.8636 0.4572)
			(end 0.8636 0.4064)
			(stroke
				(width 0.1)
				(type default)
			)
			(layer "B.Fab")
		)
		(fp_line
			(start -1.1938 0.4064)
			(end -0.8636 0.4064)
			(stroke
				(width 0.1)
				(type default)
			)
			(layer "B.Fab")
		)
		(fp_line
			(start -0.8636 0.4064)
			(end -0.8636 0.4572)
			(stroke
				(width 0.1)
				(type default)
			)
			(layer "B.Fab")
		)
		(fp_line
			(start 0.8636 0.4064)
			(end 1.1938 0.4064)
			(stroke
				(width 0.1)
				(type default)
			)
			(layer "B.Fab")
		)
		(fp_line
			(start 1.1938 0.4064)
			(end 1.1938 -0.4064)
			(stroke
				(width 0.1)
				(type default)
			)
			(layer "B.Fab")
		)
		(fp_line
			(start -1.1938 -0.4064)
			(end -1.1938 0.4064)
			(stroke
				(width 0.1)
				(type default)
			)
			(layer "B.Fab")
		)
		(fp_line
			(start -0.8636 -0.4064)
			(end -1.1938 -0.4064)
			(stroke
				(width 0.1)
				(type default)
			)
			(layer "B.Fab")
		)
		(fp_line
			(start 0.8636 -0.4064)
			(end 0.8636 -0.4572)
			(stroke
				(width 0.1)
				(type default)
			)
			(layer "B.Fab")
		)
		(fp_line
			(start 1.1938 -0.4064)
			(end 0.8636 -0.4064)
			(stroke
				(width 0.1)
				(type default)
			)
			(layer "B.Fab")
		)
		(fp_line
			(start -0.8636 -0.4572)
			(end -0.8636 -0.4064)
			(stroke
				(width 0.1)
				(type default)
			)
			(layer "B.Fab")
		)
		(fp_line
			(start 0.8636 -0.4572)
			(end -0.8636 -0.4572)
			(stroke
				(width 0.1)
				(type default)
			)
			(layer "B.Fab")
		)
		(pad "1" smd rect
			(at 0.7366 0 180)
			(size 0.7112 0.8128)
			(layers "B.Cu" "B.Mask" "B.Paste")
			(net "PVCCINFAON_CPU0")
		)
		(pad "2" smd rect
			(at -0.7366 0 180)
			(size 0.7112 0.8128)
			(layers "B.Cu" "B.Mask" "B.Paste")
			(net "GND")
		)
	)
	(footprint ""
		(layer "B.Cu")
		(at 92.09405 -337.145884 90)
		(property "Reference" "PC511_P1_6"
			(at 0 0 90)
			(layer "B.SilkS")
			(hide yes)
			(effects
				(font
					(size 1.27 1.27)
				)
				(justify mirror)
			)
		)
		(property "Value" ""
			(at 0 0 90)
			(layer "B.Fab")
			(effects
				(font
					(size 1.27 1.27)
				)
				(justify mirror)
			)
		)
		(duplicate_pad_numbers_are_jumpers no)
		(fp_line
			(start 1.524 -0.762)
			(end -1.524 -0.762)
			(stroke
				(width 0.1524)
				(type default)
			)
			(layer "B.SilkS")
		)
		(fp_line
			(start -1.524 -0.762)
			(end -1.524 0.762)
			(stroke
				(width 0.1524)
				(type default)
			)
			(layer "B.SilkS")
		)
		(fp_line
			(start 1.524 0.762)
			(end 1.524 -0.762)
			(stroke
				(width 0.1524)
				(type default)
			)
			(layer "B.SilkS")
		)
		(fp_line
			(start -1.524 0.762)
			(end 1.524 0.762)
			(stroke
				(width 0.1524)
				(type default)
			)
			(layer "B.SilkS")
		)
		(fp_line
			(start 1.1049 -0.724916)
			(end 1.1049 0.724916)
			(stroke
				(width 0.1)
				(type default)
			)
			(layer "B.Fab")
		)
		(fp_line
			(start -1.1049 -0.724916)
			(end 1.1049 -0.724916)
			(stroke
				(width 0.1)
				(type default)
			)
			(layer "B.Fab")
		)
		(fp_line
			(start 1.1049 0.724916)
			(end -1.1049 0.724916)
			(stroke
				(width 0.1)
				(type default)
			)
			(layer "B.Fab")
		)
		(fp_line
			(start -1.1049 0.724916)
			(end -1.1049 -0.724916)
			(stroke
				(width 0.1)
				(type default)
			)
			(layer "B.Fab")
		)
		(pad "1" smd rect
			(at 0.889 0 90)
			(size 1.016 1.27)
			(layers "B.Cu" "B.Mask" "B.Paste")
			(net "SW_P12V_PVCCIN_CPU1_FLT")
		)
		(pad "2" smd rect
			(at -0.889 0 90)
			(size 1.016 1.27)
			(layers "B.Cu" "B.Mask" "B.Paste")
			(net "GND")
		)
	)
	(footprint ""
		(layer "B.Cu")
		(at 451.549516 -10.634726 90)
		(property "Reference" "R421"
			(at 0 0 90)
			(layer "B.SilkS")
			(hide yes)
			(effects
				(font
					(size 1.27 1.27)
				)
				(justify mirror)
			)
		)
		(property "Value" ""
			(at 0 0 90)
			(layer "B.Fab")
			(effects
				(font
					(size 1.27 1.27)
				)
				(justify mirror)
			)
		)
		(duplicate_pad_numbers_are_jumpers no)
		(fp_line
			(start 0.7874 -0.4064)
			(end -0.7874 -0.4064)
			(stroke
				(width 0.1524)
				(type default)
			)
			(layer "B.SilkS")
		)
		(fp_line
			(start -0.7874 -0.4064)
			(end -0.7874 0.4064)
			(stroke
				(width 0.1524)
				(type default)
			)
			(layer "B.SilkS")
		)
		(fp_line
			(start 0.7874 0.4064)
			(end 0.7874 -0.4064)
			(stroke
				(width 0.1524)
				(type default)
			)
			(layer "B.SilkS")
		)
		(fp_line
			(start -0.7874 0.4064)
			(end 0.7874 0.4064)
			(stroke
				(width 0.1524)
				(type default)
			)
			(layer "B.SilkS")
		)
		(fp_line
			(start 0.67945 -0.305054)
			(end 0.12065 -0.305054)
			(stroke
				(width 0.1)
				(type default)
			)
			(layer "B.Fab")
		)
		(fp_line
			(start 0.12065 -0.305054)
			(end 0.12065 -0.2794)
			(stroke
				(width 0.1)
				(type default)
			)
			(layer "B.Fab")
		)
		(fp_line
			(start -0.12065 -0.3048)
			(end -0.67945 -0.3048)
			(stroke
				(width 0.1)
				(type default)
			)
			(layer "B.Fab")
		)
		(fp_line
			(start -0.67945 -0.3048)
			(end -0.67945 0.3048)
			(stroke
				(width 0.1)
				(type default)
			)
			(layer "B.Fab")
		)
		(fp_line
			(start 0.12065 -0.2794)
			(end -0.12065 -0.2794)
			(stroke
				(width 0.1)
				(type default)
			)
			(layer "B.Fab")
		)
		(fp_line
			(start -0.12065 -0.2794)
			(end -0.12065 -0.3048)
			(stroke
				(width 0.1)
				(type default)
			)
			(layer "B.Fab")
		)
		(fp_line
			(start 0.12065 0.2794)
			(end 0.12065 0.3048)
			(stroke
				(width 0.1)
				(type default)
			)
			(layer "B.Fab")
		)
		(fp_line
			(start -0.120396 0.2794)
			(end 0.12065 0.2794)
			(stroke
				(width 0.1)
				(type default)
			)
			(layer "B.Fab")
		)
		(fp_line
			(start 0.67945 0.3048)
			(end 0.67945 -0.305054)
			(stroke
				(width 0.1)
				(type default)
			)
			(layer "B.Fab")
		)
		(fp_line
			(start 0.12065 0.3048)
			(end 0.67945 0.3048)
			(stroke
				(width 0.1)
				(type default)
			)
			(layer "B.Fab")
		)
		(fp_line
			(start -0.120396 0.3048)
			(end -0.120396 0.2794)
			(stroke
				(width 0.1)
				(type default)
			)
			(layer "B.Fab")
		)
		(fp_line
			(start -0.67945 0.3048)
			(end -0.120396 0.3048)
			(stroke
				(width 0.1)
				(type default)
			)
			(layer "B.Fab")
		)
		(pad "1" smd circle
			(at 0.40005 0 270)
			(size 0 0)
			(layers "B.Cu" "B.Mask" "B.Paste")
			(net "SGPIO_OCP_SFF_DATAIN")
		)
		(pad "2" smd circle
			(at -0.40005 0 270)
			(size 0 0)
			(layers "B.Cu" "B.Mask" "B.Paste")
			(net "P3V3_OCP_SFF")
		)
	)
	(footprint ""
		(layer "B.Cu")
		(at 254.824484 -106.467148)
		(property "Reference" "R1204"
			(at 0 0 0)
			(layer "B.SilkS")
			(hide yes)
			(effects
				(font
					(size 1.27 1.27)
				)
				(justify mirror)
			)
		)
		(property "Value" ""
			(at 0 0 0)
			(layer "B.Fab")
			(effects
				(font
					(size 1.27 1.27)
				)
				(justify mirror)
			)
		)
		(duplicate_pad_numbers_are_jumpers no)
		(fp_line
			(start -0.7874 -0.4064)
			(end -0.7874 0.4064)
			(stroke
				(width 0.1524)
				(type default)
			)
			(layer "B.SilkS")
		)
		(fp_line
			(start -0.7874 0.4064)
			(end 0.7874 0.4064)
			(stroke
				(width 0.1524)
				(type default)
			)
			(layer "B.SilkS")
		)
		(fp_line
			(start 0.7874 -0.4064)
			(end -0.7874 -0.4064)
			(stroke
				(width 0.1524)
				(type default)
			)
			(layer "B.SilkS")
		)
		(fp_line
			(start 0.7874 0.4064)
			(end 0.7874 -0.4064)
			(stroke
				(width 0.1524)
				(type default)
			)
			(layer "B.SilkS")
		)
		(fp_line
			(start -0.67945 -0.3048)
			(end -0.67945 0.3048)
			(stroke
				(width 0.1)
				(type default)
			)
			(layer "B.Fab")
		)
		(fp_line
			(start -0.67945 0.3048)
			(end -0.120396 0.3048)
			(stroke
				(width 0.1)
				(type default)
			)
			(layer "B.Fab")
		)
		(fp_line
			(start -0.12065 -0.3048)
			(end -0.67945 -0.3048)
			(stroke
				(width 0.1)
				(type default)
			)
			(layer "B.Fab")
		)
		(fp_line
			(start -0.12065 -0.2794)
			(end -0.12065 -0.3048)
			(stroke
				(width 0.1)
				(type default)
			)
			(layer "B.Fab")
		)
		(fp_line
			(start -0.120396 0.2794)
			(end 0.12065 0.2794)
			(stroke
				(width 0.1)
				(type default)
			)
			(layer "B.Fab")
		)
		(fp_line
			(start -0.120396 0.3048)
			(end -0.120396 0.2794)
			(stroke
				(width 0.1)
				(type default)
			)
			(layer "B.Fab")
		)
		(fp_line
			(start 0.12065 -0.305054)
			(end 0.12065 -0.2794)
			(stroke
				(width 0.1)
				(type default)
			)
			(layer "B.Fab")
		)
		(fp_line
			(start 0.12065 -0.2794)
			(end -0.12065 -0.2794)
			(stroke
				(width 0.1)
				(type default)
			)
			(layer "B.Fab")
		)
		(fp_line
			(start 0.12065 0.2794)
			(end 0.12065 0.3048)
			(stroke
				(width 0.1)
				(type default)
			)
			(layer "B.Fab")
		)
		(fp_line
			(start 0.12065 0.3048)
			(end 0.67945 0.3048)
			(stroke
				(width 0.1)
				(type default)
			)
			(layer "B.Fab")
		)
		(fp_line
			(start 0.67945 -0.305054)
			(end 0.12065 -0.305054)
			(stroke
				(width 0.1)
				(type default)
			)
			(layer "B.Fab")
		)
		(fp_line
			(start 0.67945 0.3048)
			(end 0.67945 -0.305054)
			(stroke
				(width 0.1)
				(type default)
			)
			(layer "B.Fab")
		)
		(pad "1" smd circle
			(at 0.40005 0 180)
			(size 0 0)
			(layers "B.Cu" "B.Mask" "B.Paste")
			(net "P3V3_AUX")
		)
		(pad "2" smd circle
			(at -0.40005 0 180)
			(size 0 0)
			(layers "B.Cu" "B.Mask" "B.Paste")
			(net "PU_CK440_SHFT_LD_N")
		)
	)
	(footprint ""
		(layer "B.Cu")
		(at 410.851604 -250.791218 90)
		(property "Reference" "C506"
			(at 0 0 90)
			(layer "B.SilkS")
			(hide yes)
			(effects
				(font
					(size 1.27 1.27)
				)
				(justify mirror)
			)
		)
		(property "Value" ""
			(at 0 0 90)
			(layer "B.Fab")
			(effects
				(font
					(size 1.27 1.27)
				)
				(justify mirror)
			)
		)
		(duplicate_pad_numbers_are_jumpers no)
		(fp_line
			(start 1.524 -0.762)
			(end -1.524 -0.762)
			(stroke
				(width 0.1524)
				(type default)
			)
			(layer "B.SilkS")
		)
		(fp_line
			(start -1.524 -0.762)
			(end -1.524 0.762)
			(stroke
				(width 0.1524)
				(type default)
			)
			(layer "B.SilkS")
		)
		(fp_line
			(start 1.524 0.762)
			(end 1.524 -0.762)
			(stroke
				(width 0.1524)
				(type default)
			)
			(layer "B.SilkS")
		)
		(fp_line
			(start -1.524 0.762)
			(end 1.524 0.762)
			(stroke
				(width 0.1524)
				(type default)
			)
			(layer "B.SilkS")
		)
		(fp_line
			(start 1.1049 -0.724916)
			(end 1.1049 0.724916)
			(stroke
				(width 0.1)
				(type default)
			)
			(layer "B.Fab")
		)
		(fp_line
			(start -1.1049 -0.724916)
			(end 1.1049 -0.724916)
			(stroke
				(width 0.1)
				(type default)
			)
			(layer "B.Fab")
		)
		(fp_line
			(start 1.1049 0.724916)
			(end -1.1049 0.724916)
			(stroke
				(width 0.1)
				(type default)
			)
			(layer "B.Fab")
		)
		(fp_line
			(start -1.1049 0.724916)
			(end -1.1049 -0.724916)
			(stroke
				(width 0.1)
				(type default)
			)
			(layer "B.Fab")
		)
		(pad "1" smd rect
			(at 0.889 0 90)
			(size 1.016 1.27)
			(layers "B.Cu" "B.Mask" "B.Paste")
			(net "PVCCFA_EHV_FIVRA_CPU0")
		)
		(pad "2" smd rect
			(at -0.889 0 90)
			(size 1.016 1.27)
			(layers "B.Cu" "B.Mask" "B.Paste")
			(net "GND")
		)
	)
	(footprint ""
		(layer "B.Cu")
		(at 21.914612 -168.437814 180)
		(property "Reference" "R2576"
			(at 0 0 0)
			(layer "B.SilkS")
			(hide yes)
			(effects
				(font
					(size 1.27 1.27)
				)
				(justify mirror)
			)
		)
		(property "Value" ""
			(at 0 0 0)
			(layer "B.Fab")
			(effects
				(font
					(size 1.27 1.27)
				)
				(justify mirror)
			)
		)
		(duplicate_pad_numbers_are_jumpers no)
		(fp_line
			(start 0.7874 0.4064)
			(end 0.7874 -0.4064)
			(stroke
				(width 0.1524)
				(type default)
			)
			(layer "B.SilkS")
		)
		(fp_line
			(start 0.7874 -0.4064)
			(end -0.7874 -0.4064)
			(stroke
				(width 0.1524)
				(type default)
			)
			(layer "B.SilkS")
		)
		(fp_line
			(start -0.7874 0.4064)
			(end 0.7874 0.4064)
			(stroke
				(width 0.1524)
				(type default)
			)
			(layer "B.SilkS")
		)
		(fp_line
			(start -0.7874 -0.4064)
			(end -0.7874 0.4064)
			(stroke
				(width 0.1524)
				(type default)
			)
			(layer "B.SilkS")
		)
		(fp_line
			(start 0.67945 0.3048)
			(end 0.67945 -0.305054)
			(stroke
				(width 0.1)
				(type default)
			)
			(layer "B.Fab")
		)
		(fp_line
			(start 0.67945 -0.305054)
			(end 0.12065 -0.305054)
			(stroke
				(width 0.1)
				(type default)
			)
			(layer "B.Fab")
		)
		(fp_line
			(start 0.12065 0.3048)
			(end 0.67945 0.3048)
			(stroke
				(width 0.1)
				(type default)
			)
			(layer "B.Fab")
		)
		(fp_line
			(start 0.12065 0.2794)
			(end 0.12065 0.3048)
			(stroke
				(width 0.1)
				(type default)
			)
			(layer "B.Fab")
		)
		(fp_line
			(start 0.12065 -0.2794)
			(end -0.12065 -0.2794)
			(stroke
				(width 0.1)
				(type default)
			)
			(layer "B.Fab")
		)
		(fp_line
			(start 0.12065 -0.305054)
			(end 0.12065 -0.2794)
			(stroke
				(width 0.1)
				(type default)
			)
			(layer "B.Fab")
		)
		(fp_line
			(start -0.120396 0.3048)
			(end -0.120396 0.2794)
			(stroke
				(width 0.1)
				(type default)
			)
			(layer "B.Fab")
		)
		(fp_line
			(start -0.120396 0.2794)
			(end 0.12065 0.2794)
			(stroke
				(width 0.1)
				(type default)
			)
			(layer "B.Fab")
		)
		(fp_line
			(start -0.12065 -0.2794)
			(end -0.12065 -0.3048)
			(stroke
				(width 0.1)
				(type default)
			)
			(layer "B.Fab")
		)
		(fp_line
			(start -0.12065 -0.3048)
			(end -0.67945 -0.3048)
			(stroke
				(width 0.1)
				(type default)
			)
			(layer "B.Fab")
		)
		(fp_line
			(start -0.67945 0.3048)
			(end -0.120396 0.3048)
			(stroke
				(width 0.1)
				(type default)
			)
			(layer "B.Fab")
		)
		(fp_line
			(start -0.67945 -0.3048)
			(end -0.67945 0.3048)
			(stroke
				(width 0.1)
				(type default)
			)
			(layer "B.Fab")
		)
		(pad "1" smd circle
			(at 0.40005 0)
			(size 0 0)
			(layers "B.Cu" "B.Mask" "B.Paste")
			(net "PWRGD_PVCCD_HV_CPU1")
		)
		(pad "2" smd circle
			(at -0.40005 0)
			(size 0 0)
			(layers "B.Cu" "B.Mask" "B.Paste")
			(net "PWRGD_PVCCD_HV_CPU1_R")
		)
	)
	(footprint ""
		(layer "B.Cu")
		(at 119.866918 -241.12347 90)
		(property "Reference" "C471"
			(at 0 0 90)
			(layer "B.SilkS")
			(hide yes)
			(effects
				(font
					(size 1.27 1.27)
				)
				(justify mirror)
			)
		)
		(property "Value" ""
			(at 0 0 90)
			(layer "B.Fab")
			(effects
				(font
					(size 1.27 1.27)
				)
				(justify mirror)
			)
		)
		(duplicate_pad_numbers_are_jumpers no)
		(fp_line
			(start 1.524 -0.762)
			(end -1.524 -0.762)
			(stroke
				(width 0.1524)
				(type default)
			)
			(layer "B.SilkS")
		)
		(fp_line
			(start -1.524 -0.762)
			(end -1.524 0.762)
			(stroke
				(width 0.1524)
				(type default)
			)
			(layer "B.SilkS")
		)
		(fp_line
			(start 1.524 0.762)
			(end 1.524 -0.762)
			(stroke
				(width 0.1524)
				(type default)
			)
			(layer "B.SilkS")
		)
		(fp_line
			(start -1.524 0.762)
			(end 1.524 0.762)
			(stroke
				(width 0.1524)
				(type default)
			)
			(layer "B.SilkS")
		)
		(fp_line
			(start 1.1049 -0.724916)
			(end 1.1049 0.724916)
			(stroke
				(width 0.1)
				(type default)
			)
			(layer "B.Fab")
		)
		(fp_line
			(start -1.1049 -0.724916)
			(end 1.1049 -0.724916)
			(stroke
				(width 0.1)
				(type default)
			)
			(layer "B.Fab")
		)
		(fp_line
			(start 1.1049 0.724916)
			(end -1.1049 0.724916)
			(stroke
				(width 0.1)
				(type default)
			)
			(layer "B.Fab")
		)
		(fp_line
			(start -1.1049 0.724916)
			(end -1.1049 -0.724916)
			(stroke
				(width 0.1)
				(type default)
			)
			(layer "B.Fab")
		)
		(pad "1" smd rect
			(at 0.889 0 90)
			(size 1.016 1.27)
			(layers "B.Cu" "B.Mask" "B.Paste")
			(net "PVCCD_HV_CPU1")
		)
		(pad "2" smd rect
			(at -0.889 0 90)
			(size 1.016 1.27)
			(layers "B.Cu" "B.Mask" "B.Paste")
			(net "GND")
		)
	)
	(footprint ""
		(layer "B.Cu")
		(at 44.16171 -315.423804 90)
		(property "Reference" "R3894"
			(at 0 0 90)
			(layer "B.SilkS")
			(hide yes)
			(effects
				(font
					(size 1.27 1.27)
				)
				(justify mirror)
			)
		)
		(property "Value" ""
			(at 0 0 90)
			(layer "B.Fab")
			(effects
				(font
					(size 1.27 1.27)
				)
				(justify mirror)
			)
		)
		(duplicate_pad_numbers_are_jumpers no)
		(fp_line
			(start 0.7874 -0.4064)
			(end -0.7874 -0.4064)
			(stroke
				(width 0.1524)
				(type default)
			)
			(layer "B.SilkS")
		)
		(fp_line
			(start -0.7874 -0.4064)
			(end -0.7874 0.4064)
			(stroke
				(width 0.1524)
				(type default)
			)
			(layer "B.SilkS")
		)
		(fp_line
			(start 0.7874 0.4064)
			(end 0.7874 -0.4064)
			(stroke
				(width 0.1524)
				(type default)
			)
			(layer "B.SilkS")
		)
		(fp_line
			(start -0.7874 0.4064)
			(end 0.7874 0.4064)
			(stroke
				(width 0.1524)
				(type default)
			)
			(layer "B.SilkS")
		)
		(fp_line
			(start 0.67945 -0.305054)
			(end 0.12065 -0.305054)
			(stroke
				(width 0.1)
				(type default)
			)
			(layer "B.Fab")
		)
		(fp_line
			(start 0.12065 -0.305054)
			(end 0.12065 -0.2794)
			(stroke
				(width 0.1)
				(type default)
			)
			(layer "B.Fab")
		)
		(fp_line
			(start -0.12065 -0.3048)
			(end -0.67945 -0.3048)
			(stroke
				(width 0.1)
				(type default)
			)
			(layer "B.Fab")
		)
		(fp_line
			(start -0.67945 -0.3048)
			(end -0.67945 0.3048)
			(stroke
				(width 0.1)
				(type default)
			)
			(layer "B.Fab")
		)
		(fp_line
			(start 0.12065 -0.2794)
			(end -0.12065 -0.2794)
			(stroke
				(width 0.1)
				(type default)
			)
			(layer "B.Fab")
		)
		(fp_line
			(start -0.12065 -0.2794)
			(end -0.12065 -0.3048)
			(stroke
				(width 0.1)
				(type default)
			)
			(layer "B.Fab")
		)
		(fp_line
			(start 0.12065 0.2794)
			(end 0.12065 0.3048)
			(stroke
				(width 0.1)
				(type default)
			)
			(layer "B.Fab")
		)
		(fp_line
			(start -0.120396 0.2794)
			(end 0.12065 0.2794)
			(stroke
				(width 0.1)
				(type default)
			)
			(layer "B.Fab")
		)
		(fp_line
			(start 0.67945 0.3048)
			(end 0.67945 -0.305054)
			(stroke
				(width 0.1)
				(type default)
			)
			(layer "B.Fab")
		)
		(fp_line
			(start 0.12065 0.3048)
			(end 0.67945 0.3048)
			(stroke
				(width 0.1)
				(type default)
			)
			(layer "B.Fab")
		)
		(fp_line
			(start -0.120396 0.3048)
			(end -0.120396 0.2794)
			(stroke
				(width 0.1)
				(type default)
			)
			(layer "B.Fab")
		)
		(fp_line
			(start -0.67945 0.3048)
			(end -0.120396 0.3048)
			(stroke
				(width 0.1)
				(type default)
			)
			(layer "B.Fab")
		)
		(pad "1" smd circle
			(at 0.40005 0 270)
			(size 0 0)
			(layers "B.Cu" "B.Mask" "B.Paste")
			(net "I3C_SPD_DDRABCD_CPU1_LVC1_SCL_3")
		)
		(pad "2" smd circle
			(at -0.40005 0 270)
			(size 0 0)
			(layers "B.Cu" "B.Mask" "B.Paste")
			(net "I3C_SPD_DDRABCD_CPU1_LVC1_SCL")
		)
	)
	(footprint ""
		(layer "B.Cu")
		(at 454.74128 -76.589128 -90)
		(property "Reference" "PC2344"
			(at 0 0 90)
			(layer "B.SilkS")
			(hide yes)
			(effects
				(font
					(size 1.27 1.27)
				)
				(justify mirror)
			)
		)
		(property "Value" ""
			(at 0 0 90)
			(layer "B.Fab")
			(effects
				(font
					(size 1.27 1.27)
				)
				(justify mirror)
			)
		)
		(duplicate_pad_numbers_are_jumpers no)
		(fp_line
			(start -1.524 0.762)
			(end 1.524 0.762)
			(stroke
				(width 0.1524)
				(type default)
			)
			(layer "B.SilkS")
		)
		(fp_line
			(start 1.524 0.762)
			(end 1.524 -0.762)
			(stroke
				(width 0.1524)
				(type default)
			)
			(layer "B.SilkS")
		)
		(fp_line
			(start -1.524 -0.762)
			(end -1.524 0.762)
			(stroke
				(width 0.1524)
				(type default)
			)
			(layer "B.SilkS")
		)
		(fp_line
			(start 1.524 -0.762)
			(end -1.524 -0.762)
			(stroke
				(width 0.1524)
				(type default)
			)
			(layer "B.SilkS")
		)
		(fp_line
			(start -1.1049 0.724916)
			(end -1.1049 -0.724916)
			(stroke
				(width 0.1)
				(type default)
			)
			(layer "B.Fab")
		)
		(fp_line
			(start 1.1049 0.724916)
			(end -1.1049 0.724916)
			(stroke
				(width 0.1)
				(type default)
			)
			(layer "B.Fab")
		)
		(fp_line
			(start -1.1049 -0.724916)
			(end 1.1049 -0.724916)
			(stroke
				(width 0.1)
				(type default)
			)
			(layer "B.Fab")
		)
		(fp_line
			(start 1.1049 -0.724916)
			(end 1.1049 0.724916)
			(stroke
				(width 0.1)
				(type default)
			)
			(layer "B.Fab")
		)
		(pad "1" smd rect
			(at 0.889 0 270)
			(size 1.016 1.27)
			(layers "B.Cu" "B.Mask" "B.Paste")
			(net "SW_P3V3_AUX_FLT")
		)
		(pad "2" smd rect
			(at -0.889 0 270)
			(size 1.016 1.27)
			(layers "B.Cu" "B.Mask" "B.Paste")
			(net "GND")
		)
	)
	(footprint ""
		(layer "B.Cu")
		(at 181.875938 -104.716326 180)
		(property "Reference" "R1328"
			(at 0 0 0)
			(layer "B.SilkS")
			(hide yes)
			(effects
				(font
					(size 1.27 1.27)
				)
				(justify mirror)
			)
		)
		(property "Value" ""
			(at 0 0 0)
			(layer "B.Fab")
			(effects
				(font
					(size 1.27 1.27)
				)
				(justify mirror)
			)
		)
		(duplicate_pad_numbers_are_jumpers no)
		(fp_line
			(start 0.7874 0.4064)
			(end 0.7874 -0.4064)
			(stroke
				(width 0.1524)
				(type default)
			)
			(layer "B.SilkS")
		)
		(fp_line
			(start 0.7874 -0.4064)
			(end -0.7874 -0.4064)
			(stroke
				(width 0.1524)
				(type default)
			)
			(layer "B.SilkS")
		)
		(fp_line
			(start -0.7874 0.4064)
			(end 0.7874 0.4064)
			(stroke
				(width 0.1524)
				(type default)
			)
			(layer "B.SilkS")
		)
		(fp_line
			(start -0.7874 -0.4064)
			(end -0.7874 0.4064)
			(stroke
				(width 0.1524)
				(type default)
			)
			(layer "B.SilkS")
		)
		(fp_line
			(start 0.67945 0.3048)
			(end 0.67945 -0.305054)
			(stroke
				(width 0.1)
				(type default)
			)
			(layer "B.Fab")
		)
		(fp_line
			(start 0.67945 -0.305054)
			(end 0.12065 -0.305054)
			(stroke
				(width 0.1)
				(type default)
			)
			(layer "B.Fab")
		)
		(fp_line
			(start 0.12065 0.3048)
			(end 0.67945 0.3048)
			(stroke
				(width 0.1)
				(type default)
			)
			(layer "B.Fab")
		)
		(fp_line
			(start 0.12065 0.2794)
			(end 0.12065 0.3048)
			(stroke
				(width 0.1)
				(type default)
			)
			(layer "B.Fab")
		)
		(fp_line
			(start 0.12065 -0.2794)
			(end -0.12065 -0.2794)
			(stroke
				(width 0.1)
				(type default)
			)
			(layer "B.Fab")
		)
		(fp_line
			(start 0.12065 -0.305054)
			(end 0.12065 -0.2794)
			(stroke
				(width 0.1)
				(type default)
			)
			(layer "B.Fab")
		)
		(fp_line
			(start -0.120396 0.3048)
			(end -0.120396 0.2794)
			(stroke
				(width 0.1)
				(type default)
			)
			(layer "B.Fab")
		)
		(fp_line
			(start -0.120396 0.2794)
			(end 0.12065 0.2794)
			(stroke
				(width 0.1)
				(type default)
			)
			(layer "B.Fab")
		)
		(fp_line
			(start -0.12065 -0.2794)
			(end -0.12065 -0.3048)
			(stroke
				(width 0.1)
				(type default)
			)
			(layer "B.Fab")
		)
		(fp_line
			(start -0.12065 -0.3048)
			(end -0.67945 -0.3048)
			(stroke
				(width 0.1)
				(type default)
			)
			(layer "B.Fab")
		)
		(fp_line
			(start -0.67945 0.3048)
			(end -0.120396 0.3048)
			(stroke
				(width 0.1)
				(type default)
			)
			(layer "B.Fab")
		)
		(fp_line
			(start -0.67945 -0.3048)
			(end -0.67945 0.3048)
			(stroke
				(width 0.1)
				(type default)
			)
			(layer "B.Fab")
		)
		(pad "1" smd circle
			(at 0.40005 0)
			(size 0 0)
			(layers "B.Cu" "B.Mask" "B.Paste")
			(net "PWRGD_DRAMPWRGD_CPU0_GH_R_LVC1")
		)
		(pad "2" smd circle
			(at -0.40005 0)
			(size 0 0)
			(layers "B.Cu" "B.Mask" "B.Paste")
			(net "GND")
		)
	)
	(footprint ""
		(layer "B.Cu")
		(at 139.346686 -9.362948 90)
		(property "Reference" "R4809"
			(at 0 0 90)
			(layer "B.SilkS")
			(hide yes)
			(effects
				(font
					(size 1.27 1.27)
				)
				(justify mirror)
			)
		)
		(property "Value" ""
			(at 0 0 90)
			(layer "B.Fab")
			(effects
				(font
					(size 1.27 1.27)
				)
				(justify mirror)
			)
		)
		(duplicate_pad_numbers_are_jumpers no)
		(fp_line
			(start 0.7874 -0.4064)
			(end -0.7874 -0.4064)
			(stroke
				(width 0.1524)
				(type default)
			)
			(layer "B.SilkS")
		)
		(fp_line
			(start -0.7874 -0.4064)
			(end -0.7874 0.4064)
			(stroke
				(width 0.1524)
				(type default)
			)
			(layer "B.SilkS")
		)
		(fp_line
			(start 0.7874 0.4064)
			(end 0.7874 -0.4064)
			(stroke
				(width 0.1524)
				(type default)
			)
			(layer "B.SilkS")
		)
		(fp_line
			(start -0.7874 0.4064)
			(end 0.7874 0.4064)
			(stroke
				(width 0.1524)
				(type default)
			)
			(layer "B.SilkS")
		)
		(fp_line
			(start 0.67945 -0.305054)
			(end 0.12065 -0.305054)
			(stroke
				(width 0.1)
				(type default)
			)
			(layer "B.Fab")
		)
		(fp_line
			(start 0.12065 -0.305054)
			(end 0.12065 -0.2794)
			(stroke
				(width 0.1)
				(type default)
			)
			(layer "B.Fab")
		)
		(fp_line
			(start -0.12065 -0.3048)
			(end -0.67945 -0.3048)
			(stroke
				(width 0.1)
				(type default)
			)
			(layer "B.Fab")
		)
		(fp_line
			(start -0.67945 -0.3048)
			(end -0.67945 0.3048)
			(stroke
				(width 0.1)
				(type default)
			)
			(layer "B.Fab")
		)
		(fp_line
			(start 0.12065 -0.2794)
			(end -0.12065 -0.2794)
			(stroke
				(width 0.1)
				(type default)
			)
			(layer "B.Fab")
		)
		(fp_line
			(start -0.12065 -0.2794)
			(end -0.12065 -0.3048)
			(stroke
				(width 0.1)
				(type default)
			)
			(layer "B.Fab")
		)
		(fp_line
			(start 0.12065 0.2794)
			(end 0.12065 0.3048)
			(stroke
				(width 0.1)
				(type default)
			)
			(layer "B.Fab")
		)
		(fp_line
			(start -0.120396 0.2794)
			(end 0.12065 0.2794)
			(stroke
				(width 0.1)
				(type default)
			)
			(layer "B.Fab")
		)
		(fp_line
			(start 0.67945 0.3048)
			(end 0.67945 -0.305054)
			(stroke
				(width 0.1)
				(type default)
			)
			(layer "B.Fab")
		)
		(fp_line
			(start 0.12065 0.3048)
			(end 0.67945 0.3048)
			(stroke
				(width 0.1)
				(type default)
			)
			(layer "B.Fab")
		)
		(fp_line
			(start -0.120396 0.3048)
			(end -0.120396 0.2794)
			(stroke
				(width 0.1)
				(type default)
			)
			(layer "B.Fab")
		)
		(fp_line
			(start -0.67945 0.3048)
			(end -0.120396 0.3048)
			(stroke
				(width 0.1)
				(type default)
			)
			(layer "B.Fab")
		)
		(pad "1" smd circle
			(at 0.40005 0 270)
			(size 0 0)
			(layers "B.Cu" "B.Mask" "B.Paste")
			(net "FM_BMC_INTRUDER_N")
		)
		(pad "2" smd circle
			(at -0.40005 0 270)
			(size 0 0)
			(layers "B.Cu" "B.Mask" "B.Paste")
			(net "GND")
		)
	)
	(footprint ""
		(layer "B.Cu")
		(at 169.66692 -52.415948 180)
		(property "Reference" "C1924"
			(at 0 0 0)
			(layer "B.SilkS")
			(hide yes)
			(effects
				(font
					(size 1.27 1.27)
				)
				(justify mirror)
			)
		)
		(property "Value" ""
			(at 0 0 0)
			(layer "B.Fab")
			(effects
				(font
					(size 1.27 1.27)
				)
				(justify mirror)
			)
		)
		(duplicate_pad_numbers_are_jumpers no)
		(fp_line
			(start 0.7874 0.4064)
			(end 0.7874 -0.4064)
			(stroke
				(width 0.1524)
				(type default)
			)
			(layer "B.SilkS")
		)
		(fp_line
			(start 0.7874 -0.4064)
			(end -0.7874 -0.4064)
			(stroke
				(width 0.1524)
				(type default)
			)
			(layer "B.SilkS")
		)
		(fp_line
			(start -0.7874 0.4064)
			(end 0.7874 0.4064)
			(stroke
				(width 0.1524)
				(type default)
			)
			(layer "B.SilkS")
		)
		(fp_line
			(start -0.7874 -0.4064)
			(end -0.7874 0.4064)
			(stroke
				(width 0.1524)
				(type default)
			)
			(layer "B.SilkS")
		)
		(fp_line
			(start 0.67945 0.3048)
			(end 0.67945 -0.305054)
			(stroke
				(width 0.1)
				(type default)
			)
			(layer "B.Fab")
		)
		(fp_line
			(start 0.67945 -0.305054)
			(end 0.12065 -0.305054)
			(stroke
				(width 0.1)
				(type default)
			)
			(layer "B.Fab")
		)
		(fp_line
			(start 0.12065 0.3048)
			(end 0.67945 0.3048)
			(stroke
				(width 0.1)
				(type default)
			)
			(layer "B.Fab")
		)
		(fp_line
			(start 0.12065 0.2794)
			(end 0.12065 0.3048)
			(stroke
				(width 0.1)
				(type default)
			)
			(layer "B.Fab")
		)
		(fp_line
			(start 0.12065 -0.2794)
			(end -0.12065 -0.2794)
			(stroke
				(width 0.1)
				(type default)
			)
			(layer "B.Fab")
		)
		(fp_line
			(start 0.12065 -0.305054)
			(end 0.12065 -0.2794)
			(stroke
				(width 0.1)
				(type default)
			)
			(layer "B.Fab")
		)
		(fp_line
			(start -0.120396 0.3048)
			(end -0.120396 0.2794)
			(stroke
				(width 0.1)
				(type default)
			)
			(layer "B.Fab")
		)
		(fp_line
			(start -0.120396 0.2794)
			(end 0.12065 0.2794)
			(stroke
				(width 0.1)
				(type default)
			)
			(layer "B.Fab")
		)
		(fp_line
			(start -0.12065 -0.2794)
			(end -0.12065 -0.3048)
			(stroke
				(width 0.1)
				(type default)
			)
			(layer "B.Fab")
		)
		(fp_line
			(start -0.12065 -0.3048)
			(end -0.67945 -0.3048)
			(stroke
				(width 0.1)
				(type default)
			)
			(layer "B.Fab")
		)
		(fp_line
			(start -0.67945 0.3048)
			(end -0.120396 0.3048)
			(stroke
				(width 0.1)
				(type default)
			)
			(layer "B.Fab")
		)
		(fp_line
			(start -0.67945 -0.3048)
			(end -0.67945 0.3048)
			(stroke
				(width 0.1)
				(type default)
			)
			(layer "B.Fab")
		)
		(pad "1" smd circle
			(at 0.40005 0)
			(size 0 0)
			(layers "B.Cu" "B.Mask" "B.Paste")
			(net "P3V3_M2_0")
		)
		(pad "2" smd circle
			(at -0.40005 0)
			(size 0 0)
			(layers "B.Cu" "B.Mask" "B.Paste")
			(net "GND")
		)
	)
	(footprint ""
		(layer "B.Cu")
		(at 120.26392 -237.709456 90)
		(property "Reference" "C465"
			(at 0 0 90)
			(layer "B.SilkS")
			(hide yes)
			(effects
				(font
					(size 1.27 1.27)
				)
				(justify mirror)
			)
		)
		(property "Value" ""
			(at 0 0 90)
			(layer "B.Fab")
			(effects
				(font
					(size 1.27 1.27)
				)
				(justify mirror)
			)
		)
		(duplicate_pad_numbers_are_jumpers no)
		(fp_line
			(start 1.2954 -0.5842)
			(end -1.2954 -0.5842)
			(stroke
				(width 0.1524)
				(type default)
			)
			(layer "B.SilkS")
		)
		(fp_line
			(start 0 -0.5842)
			(end 0 0.5842)
			(stroke
				(width 0.1524)
				(type default)
			)
			(layer "B.SilkS")
		)
		(fp_line
			(start -1.2954 -0.5842)
			(end -1.2954 0.5842)
			(stroke
				(width 0.1524)
				(type default)
			)
			(layer "B.SilkS")
		)
		(fp_line
			(start 1.2954 0.5842)
			(end 1.2954 -0.5842)
			(stroke
				(width 0.1524)
				(type default)
			)
			(layer "B.SilkS")
		)
		(fp_line
			(start -1.2954 0.5842)
			(end 1.2954 0.5842)
			(stroke
				(width 0.1524)
				(type default)
			)
			(layer "B.SilkS")
		)
		(fp_line
			(start 0.8636 -0.4572)
			(end -0.8636 -0.4572)
			(stroke
				(width 0.1)
				(type default)
			)
			(layer "B.Fab")
		)
		(fp_line
			(start -0.8636 -0.4572)
			(end -0.8636 -0.4064)
			(stroke
				(width 0.1)
				(type default)
			)
			(layer "B.Fab")
		)
		(fp_line
			(start 1.1938 -0.4064)
			(end 0.8636 -0.4064)
			(stroke
				(width 0.1)
				(type default)
			)
			(layer "B.Fab")
		)
		(fp_line
			(start 0.8636 -0.4064)
			(end 0.8636 -0.4572)
			(stroke
				(width 0.1)
				(type default)
			)
			(layer "B.Fab")
		)
		(fp_line
			(start -0.8636 -0.4064)
			(end -1.1938 -0.4064)
			(stroke
				(width 0.1)
				(type default)
			)
			(layer "B.Fab")
		)
		(fp_line
			(start -1.1938 -0.4064)
			(end -1.1938 0.4064)
			(stroke
				(width 0.1)
				(type default)
			)
			(layer "B.Fab")
		)
		(fp_line
			(start 1.1938 0.4064)
			(end 1.1938 -0.4064)
			(stroke
				(width 0.1)
				(type default)
			)
			(layer "B.Fab")
		)
		(fp_line
			(start 0.8636 0.4064)
			(end 1.1938 0.4064)
			(stroke
				(width 0.1)
				(type default)
			)
			(layer "B.Fab")
		)
		(fp_line
			(start -0.8636 0.4064)
			(end -0.8636 0.4572)
			(stroke
				(width 0.1)
				(type default)
			)
			(layer "B.Fab")
		)
		(fp_line
			(start -1.1938 0.4064)
			(end -0.8636 0.4064)
			(stroke
				(width 0.1)
				(type default)
			)
			(layer "B.Fab")
		)
		(fp_line
			(start 0.8636 0.4572)
			(end 0.8636 0.4064)
			(stroke
				(width 0.1)
				(type default)
			)
			(layer "B.Fab")
		)
		(fp_line
			(start -0.8636 0.4572)
			(end 0.8636 0.4572)
			(stroke
				(width 0.1)
				(type default)
			)
			(layer "B.Fab")
		)
		(pad "1" smd rect
			(at 0.7366 0)
			(size 0.7112 0.8128)
			(layers "B.Cu" "B.Mask" "B.Paste")
			(net "PVCCFA_EHV_FIVRA_CPU1")
		)
		(pad "2" smd rect
			(at -0.7366 0)
			(size 0.7112 0.8128)
			(layers "B.Cu" "B.Mask" "B.Paste")
			(net "GND")
		)
	)
	(footprint ""
		(layer "B.Cu")
		(at 353.0219 -58.458608)
		(property "Reference" "L10"
			(at 0 0 0)
			(layer "B.SilkS")
			(hide yes)
			(effects
				(font
					(size 1.27 1.27)
				)
				(justify mirror)
			)
		)
		(property "Value" ""
			(at 0 0 0)
			(layer "B.Fab")
			(effects
				(font
					(size 1.27 1.27)
				)
				(justify mirror)
			)
		)
		(duplicate_pad_numbers_are_jumpers no)
		(fp_line
			(start -1.27 0.5842)
			(end -1.27 -0.5842)
			(stroke
				(width 0.1524)
				(type default)
			)
			(layer "B.SilkS")
		)
		(fp_line
			(start -1.27 0.5842)
			(end 1.27 0.5842)
			(stroke
				(width 0.1524)
				(type default)
			)
			(layer "B.SilkS")
		)
		(fp_line
			(start -0.127 0.5842)
			(end -0.127 -0.5842)
			(stroke
				(width 0.1524)
				(type default)
			)
			(layer "B.SilkS")
		)
		(fp_line
			(start 0.127 0.5842)
			(end 0.127 -0.5842)
			(stroke
				(width 0.1524)
				(type default)
			)
			(layer "B.SilkS")
		)
		(fp_line
			(start 1.27 -0.5842)
			(end -1.27 -0.5842)
			(stroke
				(width 0.1524)
				(type default)
			)
			(layer "B.SilkS")
		)
		(fp_line
			(start 1.27 -0.5588)
			(end 1.27 -0.5842)
			(stroke
				(width 0.1524)
				(type default)
			)
			(layer "B.SilkS")
		)
		(fp_line
			(start 1.27 0.5842)
			(end 1.27 -0.5842)
			(stroke
				(width 0.1524)
				(type default)
			)
			(layer "B.SilkS")
		)
		(fp_line
			(start -1.1938 -0.406654)
			(end -1.1938 0.4064)
			(stroke
				(width 0.1)
				(type default)
			)
			(layer "B.Fab")
		)
		(fp_line
			(start -1.1938 0.4064)
			(end -0.9144 0.4064)
			(stroke
				(width 0.1)
				(type default)
			)
			(layer "B.Fab")
		)
		(fp_line
			(start -0.9144 -0.508)
			(end -0.9144 -0.406654)
			(stroke
				(width 0.1)
				(type default)
			)
			(layer "B.Fab")
		)
		(fp_line
			(start -0.9144 -0.406654)
			(end -1.1938 -0.406654)
			(stroke
				(width 0.1)
				(type default)
			)
			(layer "B.Fab")
		)
		(fp_line
			(start -0.9144 0.4064)
			(end -0.9144 0.508)
			(stroke
				(width 0.1)
				(type default)
			)
			(layer "B.Fab")
		)
		(fp_line
			(start -0.9144 0.508)
			(end 0.9144 0.508)
			(stroke
				(width 0.1)
				(type default)
			)
			(layer "B.Fab")
		)
		(fp_line
			(start 0.9144 -0.508)
			(end -0.9144 -0.508)
			(stroke
				(width 0.1)
				(type default)
			)
			(layer "B.Fab")
		)
		(fp_line
			(start 0.9144 -0.406654)
			(end 0.9144 -0.508)
			(stroke
				(width 0.1)
				(type default)
			)
			(layer "B.Fab")
		)
		(fp_line
			(start 0.9144 0.406654)
			(end 1.194308 0.406654)
			(stroke
				(width 0.1)
				(type default)
			)
			(layer "B.Fab")
		)
		(fp_line
			(start 0.9144 0.508)
			(end 0.9144 0.406654)
			(stroke
				(width 0.1)
				(type default)
			)
			(layer "B.Fab")
		)
		(fp_line
			(start 1.194308 -0.406654)
			(end 0.9144 -0.406654)
			(stroke
				(width 0.1)
				(type default)
			)
			(layer "B.Fab")
		)
		(fp_line
			(start 1.194308 0.406654)
			(end 1.194308 -0.406654)
			(stroke
				(width 0.1)
				(type default)
			)
			(layer "B.Fab")
		)
		(pad "1" smd rect
			(at 0.7366 0 270)
			(size 0.7112 0.8128)
			(layers "B.Cu" "B.Mask" "B.Paste")
			(net "P1V8_PCH_AUX")
		)
		(pad "2" smd rect
			(at -0.7366 0 270)
			(size 0.7112 0.8128)
			(layers "B.Cu" "B.Mask" "B.Paste")
			(net "P1V8_PCH_PLL_AUX")
		)
	)
	(footprint ""
		(layer "B.Cu")
		(at 170.433746 -321.554856 -90)
		(property "Reference" "C95"
			(at 0 0 90)
			(layer "B.SilkS")
			(hide yes)
			(effects
				(font
					(size 1.27 1.27)
				)
				(justify mirror)
			)
		)
		(property "Value" ""
			(at 0 0 90)
			(layer "B.Fab")
			(effects
				(font
					(size 1.27 1.27)
				)
				(justify mirror)
			)
		)
		(duplicate_pad_numbers_are_jumpers no)
		(fp_line
			(start -1.524 0.762)
			(end 1.524 0.762)
			(stroke
				(width 0.1524)
				(type default)
			)
			(layer "B.SilkS")
		)
		(fp_line
			(start 1.524 0.762)
			(end 1.524 -0.762)
			(stroke
				(width 0.1524)
				(type default)
			)
			(layer "B.SilkS")
		)
		(fp_line
			(start -1.524 -0.762)
			(end -1.524 0.762)
			(stroke
				(width 0.1524)
				(type default)
			)
			(layer "B.SilkS")
		)
		(fp_line
			(start 1.524 -0.762)
			(end -1.524 -0.762)
			(stroke
				(width 0.1524)
				(type default)
			)
			(layer "B.SilkS")
		)
		(fp_line
			(start -1.1049 0.724916)
			(end -1.1049 -0.724916)
			(stroke
				(width 0.1)
				(type default)
			)
			(layer "B.Fab")
		)
		(fp_line
			(start 1.1049 0.724916)
			(end -1.1049 0.724916)
			(stroke
				(width 0.1)
				(type default)
			)
			(layer "B.Fab")
		)
		(fp_line
			(start -1.1049 -0.724916)
			(end 1.1049 -0.724916)
			(stroke
				(width 0.1)
				(type default)
			)
			(layer "B.Fab")
		)
		(fp_line
			(start 1.1049 -0.724916)
			(end 1.1049 0.724916)
			(stroke
				(width 0.1)
				(type default)
			)
			(layer "B.Fab")
		)
		(pad "1" smd rect
			(at 0.889 0 270)
			(size 1.016 1.27)
			(layers "B.Cu" "B.Mask" "B.Paste")
			(net "P12V_S3_AUX_CPU1_NVDIMM")
		)
		(pad "2" smd rect
			(at -0.889 0 270)
			(size 1.016 1.27)
			(layers "B.Cu" "B.Mask" "B.Paste")
			(net "GND")
		)
	)
	(footprint ""
		(layer "B.Cu")
		(at 203.04506 -78.247748 180)
		(property "Reference" "R3244"
			(at 0 0 0)
			(layer "B.SilkS")
			(hide yes)
			(effects
				(font
					(size 1.27 1.27)
				)
				(justify mirror)
			)
		)
		(property "Value" ""
			(at 0 0 0)
			(layer "B.Fab")
			(effects
				(font
					(size 1.27 1.27)
				)
				(justify mirror)
			)
		)
		(duplicate_pad_numbers_are_jumpers no)
		(fp_line
			(start 0.7874 0.4064)
			(end 0.7874 -0.4064)
			(stroke
				(width 0.1524)
				(type default)
			)
			(layer "B.SilkS")
		)
		(fp_line
			(start 0.7874 -0.4064)
			(end -0.7874 -0.4064)
			(stroke
				(width 0.1524)
				(type default)
			)
			(layer "B.SilkS")
		)
		(fp_line
			(start -0.7874 0.4064)
			(end 0.7874 0.4064)
			(stroke
				(width 0.1524)
				(type default)
			)
			(layer "B.SilkS")
		)
		(fp_line
			(start -0.7874 -0.4064)
			(end -0.7874 0.4064)
			(stroke
				(width 0.1524)
				(type default)
			)
			(layer "B.SilkS")
		)
		(fp_line
			(start 0.67945 0.3048)
			(end 0.67945 -0.305054)
			(stroke
				(width 0.1)
				(type default)
			)
			(layer "B.Fab")
		)
		(fp_line
			(start 0.67945 -0.305054)
			(end 0.12065 -0.305054)
			(stroke
				(width 0.1)
				(type default)
			)
			(layer "B.Fab")
		)
		(fp_line
			(start 0.12065 0.3048)
			(end 0.67945 0.3048)
			(stroke
				(width 0.1)
				(type default)
			)
			(layer "B.Fab")
		)
		(fp_line
			(start 0.12065 0.2794)
			(end 0.12065 0.3048)
			(stroke
				(width 0.1)
				(type default)
			)
			(layer "B.Fab")
		)
		(fp_line
			(start 0.12065 -0.2794)
			(end -0.12065 -0.2794)
			(stroke
				(width 0.1)
				(type default)
			)
			(layer "B.Fab")
		)
		(fp_line
			(start 0.12065 -0.305054)
			(end 0.12065 -0.2794)
			(stroke
				(width 0.1)
				(type default)
			)
			(layer "B.Fab")
		)
		(fp_line
			(start -0.120396 0.3048)
			(end -0.120396 0.2794)
			(stroke
				(width 0.1)
				(type default)
			)
			(layer "B.Fab")
		)
		(fp_line
			(start -0.120396 0.2794)
			(end 0.12065 0.2794)
			(stroke
				(width 0.1)
				(type default)
			)
			(layer "B.Fab")
		)
		(fp_line
			(start -0.12065 -0.2794)
			(end -0.12065 -0.3048)
			(stroke
				(width 0.1)
				(type default)
			)
			(layer "B.Fab")
		)
		(fp_line
			(start -0.12065 -0.3048)
			(end -0.67945 -0.3048)
			(stroke
				(width 0.1)
				(type default)
			)
			(layer "B.Fab")
		)
		(fp_line
			(start -0.67945 0.3048)
			(end -0.120396 0.3048)
			(stroke
				(width 0.1)
				(type default)
			)
			(layer "B.Fab")
		)
		(fp_line
			(start -0.67945 -0.3048)
			(end -0.67945 0.3048)
			(stroke
				(width 0.1)
				(type default)
			)
			(layer "B.Fab")
		)
		(pad "1" smd circle
			(at 0.40005 0)
			(size 0 0)
			(layers "B.Cu" "B.Mask" "B.Paste")
			(net "OCP_V3_2_RBT_ARB_OUT")
		)
		(pad "2" smd circle
			(at -0.40005 0)
			(size 0 0)
			(layers "B.Cu" "B.Mask" "B.Paste")
			(net "OCP_V3_2_RBT_ARB_IN_R")
		)
	)
	(footprint ""
		(layer "B.Cu")
		(at 15.696946 -319.268856 180)
		(property "Reference" "C96"
			(at 0 0 0)
			(layer "B.SilkS")
			(hide yes)
			(effects
				(font
					(size 1.27 1.27)
				)
				(justify mirror)
			)
		)
		(property "Value" ""
			(at 0 0 0)
			(layer "B.Fab")
			(effects
				(font
					(size 1.27 1.27)
				)
				(justify mirror)
			)
		)
		(duplicate_pad_numbers_are_jumpers no)
		(fp_line
			(start 0.7874 0.4064)
			(end 0.7874 -0.4064)
			(stroke
				(width 0.1524)
				(type default)
			)
			(layer "B.SilkS")
		)
		(fp_line
			(start 0.7874 -0.4064)
			(end -0.7874 -0.4064)
			(stroke
				(width 0.1524)
				(type default)
			)
			(layer "B.SilkS")
		)
		(fp_line
			(start -0.7874 0.4064)
			(end 0.7874 0.4064)
			(stroke
				(width 0.1524)
				(type default)
			)
			(layer "B.SilkS")
		)
		(fp_line
			(start -0.7874 -0.4064)
			(end -0.7874 0.4064)
			(stroke
				(width 0.1524)
				(type default)
			)
			(layer "B.SilkS")
		)
		(fp_line
			(start 0.67945 0.3048)
			(end 0.67945 -0.305054)
			(stroke
				(width 0.1)
				(type default)
			)
			(layer "B.Fab")
		)
		(fp_line
			(start 0.67945 -0.305054)
			(end 0.12065 -0.305054)
			(stroke
				(width 0.1)
				(type default)
			)
			(layer "B.Fab")
		)
		(fp_line
			(start 0.12065 0.3048)
			(end 0.67945 0.3048)
			(stroke
				(width 0.1)
				(type default)
			)
			(layer "B.Fab")
		)
		(fp_line
			(start 0.12065 0.2794)
			(end 0.12065 0.3048)
			(stroke
				(width 0.1)
				(type default)
			)
			(layer "B.Fab")
		)
		(fp_line
			(start 0.12065 -0.2794)
			(end -0.12065 -0.2794)
			(stroke
				(width 0.1)
				(type default)
			)
			(layer "B.Fab")
		)
		(fp_line
			(start 0.12065 -0.305054)
			(end 0.12065 -0.2794)
			(stroke
				(width 0.1)
				(type default)
			)
			(layer "B.Fab")
		)
		(fp_line
			(start -0.120396 0.3048)
			(end -0.120396 0.2794)
			(stroke
				(width 0.1)
				(type default)
			)
			(layer "B.Fab")
		)
		(fp_line
			(start -0.120396 0.2794)
			(end 0.12065 0.2794)
			(stroke
				(width 0.1)
				(type default)
			)
			(layer "B.Fab")
		)
		(fp_line
			(start -0.12065 -0.2794)
			(end -0.12065 -0.3048)
			(stroke
				(width 0.1)
				(type default)
			)
			(layer "B.Fab")
		)
		(fp_line
			(start -0.12065 -0.3048)
			(end -0.67945 -0.3048)
			(stroke
				(width 0.1)
				(type default)
			)
			(layer "B.Fab")
		)
		(fp_line
			(start -0.67945 0.3048)
			(end -0.120396 0.3048)
			(stroke
				(width 0.1)
				(type default)
			)
			(layer "B.Fab")
		)
		(fp_line
			(start -0.67945 -0.3048)
			(end -0.67945 0.3048)
			(stroke
				(width 0.1)
				(type default)
			)
			(layer "B.Fab")
		)
		(pad "1" smd circle
			(at 0.40005 0)
			(size 0 0)
			(layers "B.Cu" "B.Mask" "B.Paste")
			(net "P3V3_AUX")
		)
		(pad "2" smd circle
			(at -0.40005 0)
			(size 0 0)
			(layers "B.Cu" "B.Mask" "B.Paste")
			(net "GND")
		)
	)
	(footprint ""
		(layer "B.Cu")
		(at 372.675912 -333.73568 90)
		(property "Reference" "PC280_P0_4"
			(at 0 0 90)
			(layer "B.SilkS")
			(hide yes)
			(effects
				(font
					(size 1.27 1.27)
				)
				(justify mirror)
			)
		)
		(property "Value" ""
			(at 0 0 90)
			(layer "B.Fab")
			(effects
				(font
					(size 1.27 1.27)
				)
				(justify mirror)
			)
		)
		(duplicate_pad_numbers_are_jumpers no)
		(fp_line
			(start 1.524 -0.762)
			(end -1.524 -0.762)
			(stroke
				(width 0.1524)
				(type default)
			)
			(layer "B.SilkS")
		)
		(fp_line
			(start -1.524 -0.762)
			(end -1.524 0.762)
			(stroke
				(width 0.1524)
				(type default)
			)
			(layer "B.SilkS")
		)
		(fp_line
			(start 1.524 0.762)
			(end 1.524 -0.762)
			(stroke
				(width 0.1524)
				(type default)
			)
			(layer "B.SilkS")
		)
		(fp_line
			(start -1.524 0.762)
			(end 1.524 0.762)
			(stroke
				(width 0.1524)
				(type default)
			)
			(layer "B.SilkS")
		)
		(fp_line
			(start 1.1049 -0.724916)
			(end 1.1049 0.724916)
			(stroke
				(width 0.1)
				(type default)
			)
			(layer "B.Fab")
		)
		(fp_line
			(start -1.1049 -0.724916)
			(end 1.1049 -0.724916)
			(stroke
				(width 0.1)
				(type default)
			)
			(layer "B.Fab")
		)
		(fp_line
			(start 1.1049 0.724916)
			(end -1.1049 0.724916)
			(stroke
				(width 0.1)
				(type default)
			)
			(layer "B.Fab")
		)
		(fp_line
			(start -1.1049 0.724916)
			(end -1.1049 -0.724916)
			(stroke
				(width 0.1)
				(type default)
			)
			(layer "B.Fab")
		)
		(pad "1" smd rect
			(at 0.889 0 90)
			(size 1.016 1.27)
			(layers "B.Cu" "B.Mask" "B.Paste")
			(net "SW_P12V_PVCCIN_CPU0_FLT")
		)
		(pad "2" smd rect
			(at -0.889 0 90)
			(size 1.016 1.27)
			(layers "B.Cu" "B.Mask" "B.Paste")
			(net "GND")
		)
	)
	(footprint ""
		(layer "B.Cu")
		(at 38.420548 -392.686286 180)
		(property "Reference" "C1866"
			(at 0 0 0)
			(layer "B.SilkS")
			(hide yes)
			(effects
				(font
					(size 1.27 1.27)
				)
				(justify mirror)
			)
		)
		(property "Value" ""
			(at 0 0 0)
			(layer "B.Fab")
			(effects
				(font
					(size 1.27 1.27)
				)
				(justify mirror)
			)
		)
		(duplicate_pad_numbers_are_jumpers no)
		(fp_line
			(start 0.7874 0.4064)
			(end 0.7874 -0.4064)
			(stroke
				(width 0.1524)
				(type default)
			)
			(layer "B.SilkS")
		)
		(fp_line
			(start 0.7874 -0.4064)
			(end -0.7874 -0.4064)
			(stroke
				(width 0.1524)
				(type default)
			)
			(layer "B.SilkS")
		)
		(fp_line
			(start -0.7874 0.4064)
			(end 0.7874 0.4064)
			(stroke
				(width 0.1524)
				(type default)
			)
			(layer "B.SilkS")
		)
		(fp_line
			(start -0.7874 -0.4064)
			(end -0.7874 0.4064)
			(stroke
				(width 0.1524)
				(type default)
			)
			(layer "B.SilkS")
		)
		(fp_line
			(start 0.67945 0.3048)
			(end 0.67945 -0.305054)
			(stroke
				(width 0.1)
				(type default)
			)
			(layer "B.Fab")
		)
		(fp_line
			(start 0.67945 -0.305054)
			(end 0.12065 -0.305054)
			(stroke
				(width 0.1)
				(type default)
			)
			(layer "B.Fab")
		)
		(fp_line
			(start 0.12065 0.3048)
			(end 0.67945 0.3048)
			(stroke
				(width 0.1)
				(type default)
			)
			(layer "B.Fab")
		)
		(fp_line
			(start 0.12065 0.2794)
			(end 0.12065 0.3048)
			(stroke
				(width 0.1)
				(type default)
			)
			(layer "B.Fab")
		)
		(fp_line
			(start 0.12065 -0.2794)
			(end -0.12065 -0.2794)
			(stroke
				(width 0.1)
				(type default)
			)
			(layer "B.Fab")
		)
		(fp_line
			(start 0.12065 -0.305054)
			(end 0.12065 -0.2794)
			(stroke
				(width 0.1)
				(type default)
			)
			(layer "B.Fab")
		)
		(fp_line
			(start -0.120396 0.3048)
			(end -0.120396 0.2794)
			(stroke
				(width 0.1)
				(type default)
			)
			(layer "B.Fab")
		)
		(fp_line
			(start -0.120396 0.2794)
			(end 0.12065 0.2794)
			(stroke
				(width 0.1)
				(type default)
			)
			(layer "B.Fab")
		)
		(fp_line
			(start -0.12065 -0.2794)
			(end -0.12065 -0.3048)
			(stroke
				(width 0.1)
				(type default)
			)
			(layer "B.Fab")
		)
		(fp_line
			(start -0.12065 -0.3048)
			(end -0.67945 -0.3048)
			(stroke
				(width 0.1)
				(type default)
			)
			(layer "B.Fab")
		)
		(fp_line
			(start -0.67945 0.3048)
			(end -0.120396 0.3048)
			(stroke
				(width 0.1)
				(type default)
			)
			(layer "B.Fab")
		)
		(fp_line
			(start -0.67945 -0.3048)
			(end -0.67945 0.3048)
			(stroke
				(width 0.1)
				(type default)
			)
			(layer "B.Fab")
		)
		(pad "1" smd circle
			(at 0.40005 0)
			(size 0 0)
			(layers "B.Cu" "B.Mask" "B.Paste")
			(net "P3V3_AUX")
		)
		(pad "2" smd circle
			(at -0.40005 0)
			(size 0 0)
			(layers "B.Cu" "B.Mask" "B.Paste")
			(net "GND")
		)
	)
	(footprint ""
		(layer "B.Cu")
		(at 369.769898 -359.586276 -90)
		(property "Reference" "PJ65"
			(at -4.651502 -2.444242 0)
			(unlocked yes)
			(layer "B.SilkS")
			(effects
				(font
					(size 0.7874 0.5842)
					(thickness 0.1524)
				)
				(justify left mirror)
			)
		)
		(property "Value" ""
			(at 0 0 90)
			(layer "B.Fab")
			(effects
				(font
					(size 1.27 1.27)
				)
				(justify mirror)
			)
		)
		(duplicate_pad_numbers_are_jumpers no)
		(pad "1" smd circle
			(at 0.7493 0)
			(size 0 0)
			(layers "B.Cu" "B.Mask" "B.Paste")
			(net "SH_PVPP_HBM_CPU0_N")
		)
		(pad "2" smd rect
			(at -0.7493 0 180)
			(size 0.7112 0.8128)
			(layers "B.Cu" "B.Mask" "B.Paste")
			(net "GND")
		)
		(zone
			(layer "B.Cu")
			(hatch none 0.5)
			(connect_pads
				(clearance 0)
			)
			(min_thickness 0.25)
			(keepout
				(tracks allowed)
				(vias not_allowed)
				(pads allowed)
				(copperpour not_allowed)
				(footprints allowed)
			)
			(placement
				(enabled no)
				(sheetname "")
			)
			(fill
				(thermal_gap 0.5)
				(thermal_bridge_width 0.5)
				(island_removal_mode 0)
			)
			(polygon
				(pts
					(xy 369.358672 -358.405176) (xy 370.176298 -358.405176) (xy 370.176298 -360.792776) (xy 369.358672 -360.792776)
				)
			)
		)
	)
	(footprint ""
		(layer "B.Cu")
		(at 52.15128 -171.541948 -90)
		(property "Reference" "PR678"
			(at 0 0 90)
			(layer "B.SilkS")
			(hide yes)
			(effects
				(font
					(size 1.27 1.27)
				)
				(justify mirror)
			)
		)
		(property "Value" ""
			(at 0 0 90)
			(layer "B.Fab")
			(effects
				(font
					(size 1.27 1.27)
				)
				(justify mirror)
			)
		)
		(duplicate_pad_numbers_are_jumpers no)
		(fp_line
			(start -0.7874 0.4064)
			(end 0.7874 0.4064)
			(stroke
				(width 0.1524)
				(type default)
			)
			(layer "B.SilkS")
		)
		(fp_line
			(start 0.7874 0.4064)
			(end 0.7874 -0.4064)
			(stroke
				(width 0.1524)
				(type default)
			)
			(layer "B.SilkS")
		)
		(fp_line
			(start -0.7874 -0.4064)
			(end -0.7874 0.4064)
			(stroke
				(width 0.1524)
				(type default)
			)
			(layer "B.SilkS")
		)
		(fp_line
			(start 0.7874 -0.4064)
			(end -0.7874 -0.4064)
			(stroke
				(width 0.1524)
				(type default)
			)
			(layer "B.SilkS")
		)
		(fp_line
			(start -0.67945 0.3048)
			(end -0.120396 0.3048)
			(stroke
				(width 0.1)
				(type default)
			)
			(layer "B.Fab")
		)
		(fp_line
			(start -0.120396 0.3048)
			(end -0.120396 0.2794)
			(stroke
				(width 0.1)
				(type default)
			)
			(layer "B.Fab")
		)
		(fp_line
			(start 0.12065 0.3048)
			(end 0.67945 0.3048)
			(stroke
				(width 0.1)
				(type default)
			)
			(layer "B.Fab")
		)
		(fp_line
			(start 0.67945 0.3048)
			(end 0.67945 -0.305054)
			(stroke
				(width 0.1)
				(type default)
			)
			(layer "B.Fab")
		)
		(fp_line
			(start -0.120396 0.2794)
			(end 0.12065 0.2794)
			(stroke
				(width 0.1)
				(type default)
			)
			(layer "B.Fab")
		)
		(fp_line
			(start 0.12065 0.2794)
			(end 0.12065 0.3048)
			(stroke
				(width 0.1)
				(type default)
			)
			(layer "B.Fab")
		)
		(fp_line
			(start -0.12065 -0.2794)
			(end -0.12065 -0.3048)
			(stroke
				(width 0.1)
				(type default)
			)
			(layer "B.Fab")
		)
		(fp_line
			(start 0.12065 -0.2794)
			(end -0.12065 -0.2794)
			(stroke
				(width 0.1)
				(type default)
			)
			(layer "B.Fab")
		)
		(fp_line
			(start -0.67945 -0.3048)
			(end -0.67945 0.3048)
			(stroke
				(width 0.1)
				(type default)
			)
			(layer "B.Fab")
		)
		(fp_line
			(start -0.12065 -0.3048)
			(end -0.67945 -0.3048)
			(stroke
				(width 0.1)
				(type default)
			)
			(layer "B.Fab")
		)
		(fp_line
			(start 0.12065 -0.305054)
			(end 0.12065 -0.2794)
			(stroke
				(width 0.1)
				(type default)
			)
			(layer "B.Fab")
		)
		(fp_line
			(start 0.67945 -0.305054)
			(end 0.12065 -0.305054)
			(stroke
				(width 0.1)
				(type default)
			)
			(layer "B.Fab")
		)
		(pad "1" smd circle
			(at 0.40005 0 90)
			(size 0 0)
			(layers "B.Cu" "B.Mask" "B.Paste")
			(net "P5V")
		)
		(pad "2" smd circle
			(at -0.40005 0 90)
			(size 0 0)
			(layers "B.Cu" "B.Mask" "B.Paste")
			(net "PVCCFA_EHV_CPU1_PVCC")
		)
	)
	(footprint ""
		(layer "B.Cu")
		(at 61.62421 -156.47797)
		(property "Reference" "PC1594"
			(at 0 0 0)
			(layer "B.SilkS")
			(hide yes)
			(effects
				(font
					(size 1.27 1.27)
				)
				(justify mirror)
			)
		)
		(property "Value" ""
			(at 0 0 0)
			(layer "B.Fab")
			(effects
				(font
					(size 1.27 1.27)
				)
				(justify mirror)
			)
		)
		(duplicate_pad_numbers_are_jumpers no)
		(fp_line
			(start -4.53898 -2.15011)
			(end -4.53898 2.15011)
			(stroke
				(width 0.1524)
				(type default)
			)
			(layer "B.SilkS")
		)
		(fp_line
			(start -4.53898 2.15011)
			(end 4.53898 2.15011)
			(stroke
				(width 0.1524)
				(type default)
			)
			(layer "B.SilkS")
		)
		(fp_line
			(start 4.53898 -2.150618)
			(end 4.539742 2.152142)
			(stroke
				(width 0.1524)
				(type default)
			)
			(layer "B.SilkS")
		)
		(fp_line
			(start 4.53898 -2.15011)
			(end -4.53898 -2.15011)
			(stroke
				(width 0.1524)
				(type default)
			)
			(layer "B.SilkS")
		)
		(fp_line
			(start 4.53898 2.15011)
			(end 4.53898 -2.15011)
			(stroke
				(width 0.1524)
				(type default)
			)
			(layer "B.SilkS")
		)
		(fp_line
			(start 4.69138 -2.150618)
			(end 4.692396 2.161032)
			(stroke
				(width 0.1524)
				(type default)
			)
			(layer "B.SilkS")
		)
		(fp_line
			(start 4.83108 2.150364)
			(end 4.447794 2.149348)
			(stroke
				(width 0.1524)
				(type default)
			)
			(layer "B.SilkS")
		)
		(fp_line
			(start 4.84378 -2.150618)
			(end 4.53898 -2.150618)
			(stroke
				(width 0.1524)
				(type default)
			)
			(layer "B.SilkS")
		)
		(fp_line
			(start 4.84378 -2.150618)
			(end 4.842256 2.163064)
			(stroke
				(width 0.1524)
				(type default)
			)
			(layer "B.SilkS")
		)
		(fp_line
			(start -3.64998 -2.15011)
			(end -3.64998 2.15011)
			(stroke
				(width 0.1)
				(type default)
			)
			(layer "B.Fab")
		)
		(fp_line
			(start -3.64998 2.15011)
			(end 3.64998 2.15011)
			(stroke
				(width 0.1)
				(type default)
			)
			(layer "B.Fab")
		)
		(fp_line
			(start 3.64998 -2.15011)
			(end -3.64998 -2.15011)
			(stroke
				(width 0.1)
				(type default)
			)
			(layer "B.Fab")
		)
		(fp_line
			(start 3.64998 2.15011)
			(end 3.64998 -2.15011)
			(stroke
				(width 0.1)
				(type default)
			)
			(layer "B.Fab")
		)
		(fp_text user "-"
			(at -4.79425 0.764032 0)
			(unlocked yes)
			(layer "B.SilkS")
			(effects
				(font
					(size 1.905 1.4224)
					(thickness 0.1524)
				)
				(justify left mirror)
			)
		)
		(fp_text user "+"
			(at 6.214872 -0.337058 0)
			(unlocked yes)
			(layer "B.SilkS")
			(effects
				(font
					(size 1.905 1.4224)
					(thickness 0.1524)
				)
				(justify left mirror)
			)
		)
		(fp_text user "-"
			(at -4.313174 -0.094488 0)
			(unlocked yes)
			(layer "B.Fab")
			(effects
				(font
					(size 1.905 1.4224)
					(thickness 0.1524)
				)
				(justify left mirror)
			)
		)
		(fp_text user "+"
			(at 6.214872 -0.337058 0)
			(unlocked yes)
			(layer "B.Fab")
			(effects
				(font
					(size 1.905 1.4224)
					(thickness 0.1524)
				)
				(justify left mirror)
			)
		)
		(pad "1" smd rect
			(at 3.199892 0 180)
			(size 2.413 2.8194)
			(layers "B.Cu" "B.Mask" "B.Paste")
			(net "PVCCINFAON_CPU1")
		)
		(pad "2" smd rect
			(at -3.199892 0 180)
			(size 2.413 2.8194)
			(layers "B.Cu" "B.Mask" "B.Paste")
			(net "GND")
		)
	)
	(footprint ""
		(layer "B.Cu")
		(at 378.099574 -2.156206)
		(property "Reference" "J64"
			(at 4.651756 1.013206 270)
			(unlocked yes)
			(layer "B.SilkS")
			(effects
				(font
					(size 0.7874 0.5842)
					(thickness 0.1524)
				)
				(justify left mirror)
			)
		)
		(property "Value" ""
			(at 0 0 0)
			(layer "B.Fab")
			(effects
				(font
					(size 1.27 1.27)
				)
				(justify mirror)
			)
		)
		(duplicate_pad_numbers_are_jumpers no)
		(fp_line
			(start -1.2192 -2.1082)
			(end -1.2192 2.1082)
			(stroke
				(width 0.1524)
				(type default)
			)
			(layer "B.SilkS")
		)
		(fp_line
			(start -1.2192 2.1082)
			(end 1.2192 2.1082)
			(stroke
				(width 0.1524)
				(type default)
			)
			(layer "B.SilkS")
		)
		(fp_line
			(start 1.2192 -2.1082)
			(end -1.2192 -2.1082)
			(stroke
				(width 0.1524)
				(type default)
			)
			(layer "B.SilkS")
		)
		(fp_line
			(start 1.2192 2.1082)
			(end 1.2192 -2.1082)
			(stroke
				(width 0.1524)
				(type default)
			)
			(layer "B.SilkS")
		)
		(pad "" np_thru_hole circle
			(at -3.4671 -1.27 270)
			(size 1.0414 1.0414)
			(drill 1.0414)
			(layers "*.Cu" "*.Mask")
			(clearance 0.381)
			(thermal_gap 0.381)
		)
		(pad "" np_thru_hole circle
			(at -3.4671 1.27 270)
			(size 1.0414 1.0414)
			(drill 1.0414)
			(layers "*.Cu" "*.Mask")
			(clearance 0.381)
			(thermal_gap 0.381)
		)
		(pad "" np_thru_hole circle
			(at 2.8829 -1.27 270)
			(size 1.0414 1.0414)
			(drill 1.0414)
			(layers "*.Cu" "*.Mask")
			(clearance 0.381)
			(thermal_gap 0.381)
		)
		(pad "" np_thru_hole circle
			(at 2.8829 1.27 270)
			(size 1.0414 1.0414)
			(drill 1.0414)
			(layers "*.Cu" "*.Mask")
			(clearance 0.381)
			(thermal_gap 0.381)
		)
		(pad "1" smd rect
			(at -0.8255 -0.249936 270)
			(size 0.3048 0.508)
			(layers "B.Cu" "B.Mask" "B.Paste")
			(net "DELTA_L_85_5INCH_BOT_DP")
		)
		(pad "2" smd rect
			(at -0.8255 0.249936 270)
			(size 0.3048 0.508)
			(layers "B.Cu" "B.Mask" "B.Paste")
			(net "DELTA_L_85_5INCH_BOT_DN")
		)
		(pad "3" smd circle
			(at 0 0 180)
			(size 0 0)
			(layers "B.Cu" "B.Mask" "B.Paste")
			(net "DELTA_L_GND_1")
		)
		(zone
			(layers "F.Cu" "B.Cu" "In1.Cu" "In2.Cu" "In3.Cu" "In4.Cu" "In5.Cu" "In6.Cu"
				"In7.Cu" "In8.Cu" "In9.Cu" "In10.Cu" "In11.Cu" "In12.Cu" "In13.Cu" "In14.Cu"
				"In15.Cu" "In16.Cu"
			)
			(hatch none 0.5)
			(connect_pads
				(clearance 0)
			)
			(min_thickness 0.25)
			(keepout
				(tracks not_allowed)
				(vias allowed)
				(pads allowed)
				(copperpour not_allowed)
				(footprints allowed)
			)
			(placement
				(enabled no)
				(sheetname "")
			)
			(fill
				(thermal_gap 0.5)
				(thermal_bridge_width 0.5)
				(island_removal_mode 0)
			)
			(polygon
				(pts
					(arc
						(start 375.559574 -3.426206)
						(mid 373.705374 -3.426206)
						(end 375.559574 -3.426206)
					)
				)
			)
		)
		(zone
			(layers "F.Cu" "B.Cu" "In1.Cu" "In2.Cu" "In3.Cu" "In4.Cu" "In5.Cu" "In6.Cu"
				"In7.Cu" "In8.Cu" "In9.Cu" "In10.Cu" "In11.Cu" "In12.Cu" "In13.Cu" "In14.Cu"
				"In15.Cu" "In16.Cu"
			)
			(hatch none 0.5)
			(connect_pads
				(clearance 0)
			)
			(min_thickness 0.25)
			(keepout
				(tracks not_allowed)
				(vias allowed)
				(pads allowed)
				(copperpour not_allowed)
				(footprints allowed)
			)
			(placement
				(enabled no)
				(sheetname "")
			)
			(fill
				(thermal_gap 0.5)
				(thermal_bridge_width 0.5)
				(island_removal_mode 0)
			)
			(polygon
				(pts
					(arc
						(start 375.559574 -0.886206)
						(mid 373.705374 -0.886206)
						(end 375.559574 -0.886206)
					)
				)
			)
		)
		(zone
			(layers "F.Cu" "B.Cu" "In1.Cu" "In2.Cu" "In3.Cu" "In4.Cu" "In5.Cu" "In6.Cu"
				"In7.Cu" "In8.Cu" "In9.Cu" "In10.Cu" "In11.Cu" "In12.Cu" "In13.Cu" "In14.Cu"
				"In15.Cu" "In16.Cu"
			)
			(hatch none 0.5)
			(connect_pads
				(clearance 0)
			)
			(min_thickness 0.25)
			(keepout
				(tracks not_allowed)
				(vias allowed)
				(pads allowed)
				(copperpour not_allowed)
				(footprints allowed)
			)
			(placement
				(enabled no)
				(sheetname "")
			)
			(fill
				(thermal_gap 0.5)
				(thermal_bridge_width 0.5)
				(island_removal_mode 0)
			)
			(polygon
				(pts
					(arc
						(start 381.909574 -3.426206)
						(mid 380.055374 -3.426206)
						(end 381.909574 -3.426206)
					)
				)
			)
		)
		(zone
			(layers "F.Cu" "B.Cu" "In1.Cu" "In2.Cu" "In3.Cu" "In4.Cu" "In5.Cu" "In6.Cu"
				"In7.Cu" "In8.Cu" "In9.Cu" "In10.Cu" "In11.Cu" "In12.Cu" "In13.Cu" "In14.Cu"
				"In15.Cu" "In16.Cu"
			)
			(hatch none 0.5)
			(connect_pads
				(clearance 0)
			)
			(min_thickness 0.25)
			(keepout
				(tracks not_allowed)
				(vias allowed)
				(pads allowed)
				(copperpour not_allowed)
				(footprints allowed)
			)
			(placement
				(enabled no)
				(sheetname "")
			)
			(fill
				(thermal_gap 0.5)
				(thermal_bridge_width 0.5)
				(island_removal_mode 0)
			)
			(polygon
				(pts
					(arc
						(start 381.909574 -0.886206)
						(mid 380.055374 -0.886206)
						(end 381.909574 -0.886206)
					)
				)
			)
		)
		(zone
			(layer "B.Cu")
			(hatch none 0.5)
			(connect_pads
				(clearance 0)
			)
			(min_thickness 0.25)
			(keepout
				(tracks not_allowed)
				(vias allowed)
				(pads allowed)
				(copperpour not_allowed)
				(footprints allowed)
			)
			(placement
				(enabled no)
				(sheetname "")
			)
			(fill
				(thermal_gap 0.5)
				(thermal_bridge_width 0.5)
				(island_removal_mode 0)
			)
			(polygon
				(pts
					(xy 376.981974 -2.704846) (xy 376.981974 -2.609342) (xy 377.578874 -2.609342) (xy 377.578874 -2.202942)
					(xy 376.981974 -2.202942) (xy 376.981974 -2.10947) (xy 377.578874 -2.10947) (xy 377.578874 -1.70307)
					(xy 376.981974 -1.70307) (xy 376.981974 -1.607566) (xy 377.680474 -1.607566) (xy 377.680474 -2.704846)
				)
			)
		)
	)
	(footprint ""
		(layer "B.Cu")
		(at 107.457494 -252.17628 -90)
		(property "Reference" "C333"
			(at 0 0 90)
			(layer "B.SilkS")
			(hide yes)
			(effects
				(font
					(size 1.27 1.27)
				)
				(justify mirror)
			)
		)
		(property "Value" ""
			(at 0 0 90)
			(layer "B.Fab")
			(effects
				(font
					(size 1.27 1.27)
				)
				(justify mirror)
			)
		)
		(duplicate_pad_numbers_are_jumpers no)
		(fp_line
			(start -1.524 0.762)
			(end 1.524 0.762)
			(stroke
				(width 0.1524)
				(type default)
			)
			(layer "B.SilkS")
		)
		(fp_line
			(start 1.524 0.762)
			(end 1.524 -0.762)
			(stroke
				(width 0.1524)
				(type default)
			)
			(layer "B.SilkS")
		)
		(fp_line
			(start -1.524 -0.762)
			(end -1.524 0.762)
			(stroke
				(width 0.1524)
				(type default)
			)
			(layer "B.SilkS")
		)
		(fp_line
			(start 1.524 -0.762)
			(end -1.524 -0.762)
			(stroke
				(width 0.1524)
				(type default)
			)
			(layer "B.SilkS")
		)
		(fp_line
			(start -1.1049 0.724916)
			(end -1.1049 -0.724916)
			(stroke
				(width 0.1)
				(type default)
			)
			(layer "B.Fab")
		)
		(fp_line
			(start 1.1049 0.724916)
			(end -1.1049 0.724916)
			(stroke
				(width 0.1)
				(type default)
			)
			(layer "B.Fab")
		)
		(fp_line
			(start -1.1049 -0.724916)
			(end 1.1049 -0.724916)
			(stroke
				(width 0.1)
				(type default)
			)
			(layer "B.Fab")
		)
		(fp_line
			(start 1.1049 -0.724916)
			(end 1.1049 0.724916)
			(stroke
				(width 0.1)
				(type default)
			)
			(layer "B.Fab")
		)
		(pad "1" smd rect
			(at 0.889 0 270)
			(size 1.016 1.27)
			(layers "B.Cu" "B.Mask" "B.Paste")
			(net "PVCCIN_CPU1")
		)
		(pad "2" smd rect
			(at -0.889 0 270)
			(size 1.016 1.27)
			(layers "B.Cu" "B.Mask" "B.Paste")
			(net "GND")
		)
	)
	(footprint ""
		(layer "B.Cu")
		(at 182.867046 -13.60043 -90)
		(property "Reference" "R600"
			(at 0 0 90)
			(layer "B.SilkS")
			(hide yes)
			(effects
				(font
					(size 1.27 1.27)
				)
				(justify mirror)
			)
		)
		(property "Value" ""
			(at 0 0 90)
			(layer "B.Fab")
			(effects
				(font
					(size 1.27 1.27)
				)
				(justify mirror)
			)
		)
		(duplicate_pad_numbers_are_jumpers no)
		(fp_line
			(start -0.7874 0.4064)
			(end 0.7874 0.4064)
			(stroke
				(width 0.1524)
				(type default)
			)
			(layer "B.SilkS")
		)
		(fp_line
			(start 0.7874 0.4064)
			(end 0.7874 -0.4064)
			(stroke
				(width 0.1524)
				(type default)
			)
			(layer "B.SilkS")
		)
		(fp_line
			(start -0.7874 -0.4064)
			(end -0.7874 0.4064)
			(stroke
				(width 0.1524)
				(type default)
			)
			(layer "B.SilkS")
		)
		(fp_line
			(start 0.7874 -0.4064)
			(end -0.7874 -0.4064)
			(stroke
				(width 0.1524)
				(type default)
			)
			(layer "B.SilkS")
		)
		(fp_line
			(start -0.67945 0.3048)
			(end -0.120396 0.3048)
			(stroke
				(width 0.1)
				(type default)
			)
			(layer "B.Fab")
		)
		(fp_line
			(start -0.120396 0.3048)
			(end -0.120396 0.2794)
			(stroke
				(width 0.1)
				(type default)
			)
			(layer "B.Fab")
		)
		(fp_line
			(start 0.12065 0.3048)
			(end 0.67945 0.3048)
			(stroke
				(width 0.1)
				(type default)
			)
			(layer "B.Fab")
		)
		(fp_line
			(start 0.67945 0.3048)
			(end 0.67945 -0.305054)
			(stroke
				(width 0.1)
				(type default)
			)
			(layer "B.Fab")
		)
		(fp_line
			(start -0.120396 0.2794)
			(end 0.12065 0.2794)
			(stroke
				(width 0.1)
				(type default)
			)
			(layer "B.Fab")
		)
		(fp_line
			(start 0.12065 0.2794)
			(end 0.12065 0.3048)
			(stroke
				(width 0.1)
				(type default)
			)
			(layer "B.Fab")
		)
		(fp_line
			(start -0.12065 -0.2794)
			(end -0.12065 -0.3048)
			(stroke
				(width 0.1)
				(type default)
			)
			(layer "B.Fab")
		)
		(fp_line
			(start 0.12065 -0.2794)
			(end -0.12065 -0.2794)
			(stroke
				(width 0.1)
				(type default)
			)
			(layer "B.Fab")
		)
		(fp_line
			(start -0.67945 -0.3048)
			(end -0.67945 0.3048)
			(stroke
				(width 0.1)
				(type default)
			)
			(layer "B.Fab")
		)
		(fp_line
			(start -0.12065 -0.3048)
			(end -0.67945 -0.3048)
			(stroke
				(width 0.1)
				(type default)
			)
			(layer "B.Fab")
		)
		(fp_line
			(start 0.12065 -0.305054)
			(end 0.12065 -0.2794)
			(stroke
				(width 0.1)
				(type default)
			)
			(layer "B.Fab")
		)
		(fp_line
			(start 0.67945 -0.305054)
			(end 0.12065 -0.305054)
			(stroke
				(width 0.1)
				(type default)
			)
			(layer "B.Fab")
		)
		(pad "1" smd circle
			(at 0.40005 0 90)
			(size 0 0)
			(layers "B.Cu" "B.Mask" "B.Paste")
			(net "I3C_SPD_DDREFGH_CPU1_BMC_R_SDA")
		)
		(pad "2" smd circle
			(at -0.40005 0 90)
			(size 0 0)
			(layers "B.Cu" "B.Mask" "B.Paste")
			(net "I3C_SPD_DDREFGH_CPU1_BMC_SDA")
		)
	)
	(footprint ""
		(layer "B.Cu")
		(at 384.484372 -331.58938 -90)
		(property "Reference" "PC246_P0_8"
			(at 0 0 90)
			(layer "B.SilkS")
			(hide yes)
			(effects
				(font
					(size 1.27 1.27)
				)
				(justify mirror)
			)
		)
		(property "Value" ""
			(at 0 0 90)
			(layer "B.Fab")
			(effects
				(font
					(size 1.27 1.27)
				)
				(justify mirror)
			)
		)
		(duplicate_pad_numbers_are_jumpers no)
		(fp_line
			(start -1.524 0.762)
			(end 1.524 0.762)
			(stroke
				(width 0.1524)
				(type default)
			)
			(layer "B.SilkS")
		)
		(fp_line
			(start 1.524 0.762)
			(end 1.524 -0.762)
			(stroke
				(width 0.1524)
				(type default)
			)
			(layer "B.SilkS")
		)
		(fp_line
			(start -1.524 -0.762)
			(end -1.524 0.762)
			(stroke
				(width 0.1524)
				(type default)
			)
			(layer "B.SilkS")
		)
		(fp_line
			(start 1.524 -0.762)
			(end -1.524 -0.762)
			(stroke
				(width 0.1524)
				(type default)
			)
			(layer "B.SilkS")
		)
		(fp_line
			(start -1.1049 0.724916)
			(end -1.1049 -0.724916)
			(stroke
				(width 0.1)
				(type default)
			)
			(layer "B.Fab")
		)
		(fp_line
			(start 1.1049 0.724916)
			(end -1.1049 0.724916)
			(stroke
				(width 0.1)
				(type default)
			)
			(layer "B.Fab")
		)
		(fp_line
			(start -1.1049 -0.724916)
			(end 1.1049 -0.724916)
			(stroke
				(width 0.1)
				(type default)
			)
			(layer "B.Fab")
		)
		(fp_line
			(start 1.1049 -0.724916)
			(end 1.1049 0.724916)
			(stroke
				(width 0.1)
				(type default)
			)
			(layer "B.Fab")
		)
		(pad "1" smd rect
			(at 0.889 0 270)
			(size 1.016 1.27)
			(layers "B.Cu" "B.Mask" "B.Paste")
			(net "PVCCIN_CPU0")
		)
		(pad "2" smd rect
			(at -0.889 0 270)
			(size 1.016 1.27)
			(layers "B.Cu" "B.Mask" "B.Paste")
			(net "GND")
		)
	)
	(footprint ""
		(layer "B.Cu")
		(at 196.544946 -319.268856 180)
		(property "Reference" "C81"
			(at 0 0 0)
			(layer "B.SilkS")
			(hide yes)
			(effects
				(font
					(size 1.27 1.27)
				)
				(justify mirror)
			)
		)
		(property "Value" ""
			(at 0 0 0)
			(layer "B.Fab")
			(effects
				(font
					(size 1.27 1.27)
				)
				(justify mirror)
			)
		)
		(duplicate_pad_numbers_are_jumpers no)
		(fp_line
			(start 0.7874 0.4064)
			(end 0.7874 -0.4064)
			(stroke
				(width 0.1524)
				(type default)
			)
			(layer "B.SilkS")
		)
		(fp_line
			(start 0.7874 -0.4064)
			(end -0.7874 -0.4064)
			(stroke
				(width 0.1524)
				(type default)
			)
			(layer "B.SilkS")
		)
		(fp_line
			(start -0.7874 0.4064)
			(end 0.7874 0.4064)
			(stroke
				(width 0.1524)
				(type default)
			)
			(layer "B.SilkS")
		)
		(fp_line
			(start -0.7874 -0.4064)
			(end -0.7874 0.4064)
			(stroke
				(width 0.1524)
				(type default)
			)
			(layer "B.SilkS")
		)
		(fp_line
			(start 0.67945 0.3048)
			(end 0.67945 -0.305054)
			(stroke
				(width 0.1)
				(type default)
			)
			(layer "B.Fab")
		)
		(fp_line
			(start 0.67945 -0.305054)
			(end 0.12065 -0.305054)
			(stroke
				(width 0.1)
				(type default)
			)
			(layer "B.Fab")
		)
		(fp_line
			(start 0.12065 0.3048)
			(end 0.67945 0.3048)
			(stroke
				(width 0.1)
				(type default)
			)
			(layer "B.Fab")
		)
		(fp_line
			(start 0.12065 0.2794)
			(end 0.12065 0.3048)
			(stroke
				(width 0.1)
				(type default)
			)
			(layer "B.Fab")
		)
		(fp_line
			(start 0.12065 -0.2794)
			(end -0.12065 -0.2794)
			(stroke
				(width 0.1)
				(type default)
			)
			(layer "B.Fab")
		)
		(fp_line
			(start 0.12065 -0.305054)
			(end 0.12065 -0.2794)
			(stroke
				(width 0.1)
				(type default)
			)
			(layer "B.Fab")
		)
		(fp_line
			(start -0.120396 0.3048)
			(end -0.120396 0.2794)
			(stroke
				(width 0.1)
				(type default)
			)
			(layer "B.Fab")
		)
		(fp_line
			(start -0.120396 0.2794)
			(end 0.12065 0.2794)
			(stroke
				(width 0.1)
				(type default)
			)
			(layer "B.Fab")
		)
		(fp_line
			(start -0.12065 -0.2794)
			(end -0.12065 -0.3048)
			(stroke
				(width 0.1)
				(type default)
			)
			(layer "B.Fab")
		)
		(fp_line
			(start -0.12065 -0.3048)
			(end -0.67945 -0.3048)
			(stroke
				(width 0.1)
				(type default)
			)
			(layer "B.Fab")
		)
		(fp_line
			(start -0.67945 0.3048)
			(end -0.120396 0.3048)
			(stroke
				(width 0.1)
				(type default)
			)
			(layer "B.Fab")
		)
		(fp_line
			(start -0.67945 -0.3048)
			(end -0.67945 0.3048)
			(stroke
				(width 0.1)
				(type default)
			)
			(layer "B.Fab")
		)
		(pad "1" smd circle
			(at 0.40005 0)
			(size 0 0)
			(layers "B.Cu" "B.Mask" "B.Paste")
			(net "P3V3_AUX")
		)
		(pad "2" smd circle
			(at -0.40005 0)
			(size 0 0)
			(layers "B.Cu" "B.Mask" "B.Paste")
			(net "GND")
		)
	)
	(footprint ""
		(layer "B.Cu")
		(at 179.168552 -192.699894 -90)
		(property "Reference" "R93"
			(at 0 0 90)
			(layer "B.SilkS")
			(hide yes)
			(effects
				(font
					(size 1.27 1.27)
				)
				(justify mirror)
			)
		)
		(property "Value" ""
			(at 0 0 90)
			(layer "B.Fab")
			(effects
				(font
					(size 1.27 1.27)
				)
				(justify mirror)
			)
		)
		(duplicate_pad_numbers_are_jumpers no)
		(fp_line
			(start -0.7874 0.4064)
			(end 0.7874 0.4064)
			(stroke
				(width 0.1524)
				(type default)
			)
			(layer "B.SilkS")
		)
		(fp_line
			(start 0.7874 0.4064)
			(end 0.7874 -0.4064)
			(stroke
				(width 0.1524)
				(type default)
			)
			(layer "B.SilkS")
		)
		(fp_line
			(start -0.7874 -0.4064)
			(end -0.7874 0.4064)
			(stroke
				(width 0.1524)
				(type default)
			)
			(layer "B.SilkS")
		)
		(fp_line
			(start 0.7874 -0.4064)
			(end -0.7874 -0.4064)
			(stroke
				(width 0.1524)
				(type default)
			)
			(layer "B.SilkS")
		)
		(fp_line
			(start -0.67945 0.3048)
			(end -0.120396 0.3048)
			(stroke
				(width 0.1)
				(type default)
			)
			(layer "B.Fab")
		)
		(fp_line
			(start -0.120396 0.3048)
			(end -0.120396 0.2794)
			(stroke
				(width 0.1)
				(type default)
			)
			(layer "B.Fab")
		)
		(fp_line
			(start 0.12065 0.3048)
			(end 0.67945 0.3048)
			(stroke
				(width 0.1)
				(type default)
			)
			(layer "B.Fab")
		)
		(fp_line
			(start 0.67945 0.3048)
			(end 0.67945 -0.305054)
			(stroke
				(width 0.1)
				(type default)
			)
			(layer "B.Fab")
		)
		(fp_line
			(start -0.120396 0.2794)
			(end 0.12065 0.2794)
			(stroke
				(width 0.1)
				(type default)
			)
			(layer "B.Fab")
		)
		(fp_line
			(start 0.12065 0.2794)
			(end 0.12065 0.3048)
			(stroke
				(width 0.1)
				(type default)
			)
			(layer "B.Fab")
		)
		(fp_line
			(start -0.12065 -0.2794)
			(end -0.12065 -0.3048)
			(stroke
				(width 0.1)
				(type default)
			)
			(layer "B.Fab")
		)
		(fp_line
			(start 0.12065 -0.2794)
			(end -0.12065 -0.2794)
			(stroke
				(width 0.1)
				(type default)
			)
			(layer "B.Fab")
		)
		(fp_line
			(start -0.67945 -0.3048)
			(end -0.67945 0.3048)
			(stroke
				(width 0.1)
				(type default)
			)
			(layer "B.Fab")
		)
		(fp_line
			(start -0.12065 -0.3048)
			(end -0.67945 -0.3048)
			(stroke
				(width 0.1)
				(type default)
			)
			(layer "B.Fab")
		)
		(fp_line
			(start 0.12065 -0.305054)
			(end 0.12065 -0.2794)
			(stroke
				(width 0.1)
				(type default)
			)
			(layer "B.Fab")
		)
		(fp_line
			(start 0.67945 -0.305054)
			(end 0.12065 -0.305054)
			(stroke
				(width 0.1)
				(type default)
			)
			(layer "B.Fab")
		)
		(pad "1" smd circle
			(at 0.40005 0 90)
			(size 0 0)
			(layers "B.Cu" "B.Mask" "B.Paste")
			(net "PVNN_TERM_CPU1")
		)
		(pad "2" smd circle
			(at -0.40005 0 90)
			(size 0 0)
			(layers "B.Cu" "B.Mask" "B.Paste")
			(net "PU_CPU1_UPI3_AC_COUPLING")
		)
	)
	(footprint ""
		(layer "B.Cu")
		(at 335.288128 -190.82893 90)
		(property "Reference" "R23"
			(at 0 0 90)
			(layer "B.SilkS")
			(hide yes)
			(effects
				(font
					(size 1.27 1.27)
				)
				(justify mirror)
			)
		)
		(property "Value" ""
			(at 0 0 90)
			(layer "B.Fab")
			(effects
				(font
					(size 1.27 1.27)
				)
				(justify mirror)
			)
		)
		(duplicate_pad_numbers_are_jumpers no)
		(fp_line
			(start 0.7874 -0.4064)
			(end -0.7874 -0.4064)
			(stroke
				(width 0.1524)
				(type default)
			)
			(layer "B.SilkS")
		)
		(fp_line
			(start -0.7874 -0.4064)
			(end -0.7874 0.4064)
			(stroke
				(width 0.1524)
				(type default)
			)
			(layer "B.SilkS")
		)
		(fp_line
			(start 0.7874 0.4064)
			(end 0.7874 -0.4064)
			(stroke
				(width 0.1524)
				(type default)
			)
			(layer "B.SilkS")
		)
		(fp_line
			(start -0.7874 0.4064)
			(end 0.7874 0.4064)
			(stroke
				(width 0.1524)
				(type default)
			)
			(layer "B.SilkS")
		)
		(fp_line
			(start 0.67945 -0.305054)
			(end 0.12065 -0.305054)
			(stroke
				(width 0.1)
				(type default)
			)
			(layer "B.Fab")
		)
		(fp_line
			(start 0.12065 -0.305054)
			(end 0.12065 -0.2794)
			(stroke
				(width 0.1)
				(type default)
			)
			(layer "B.Fab")
		)
		(fp_line
			(start -0.12065 -0.3048)
			(end -0.67945 -0.3048)
			(stroke
				(width 0.1)
				(type default)
			)
			(layer "B.Fab")
		)
		(fp_line
			(start -0.67945 -0.3048)
			(end -0.67945 0.3048)
			(stroke
				(width 0.1)
				(type default)
			)
			(layer "B.Fab")
		)
		(fp_line
			(start 0.12065 -0.2794)
			(end -0.12065 -0.2794)
			(stroke
				(width 0.1)
				(type default)
			)
			(layer "B.Fab")
		)
		(fp_line
			(start -0.12065 -0.2794)
			(end -0.12065 -0.3048)
			(stroke
				(width 0.1)
				(type default)
			)
			(layer "B.Fab")
		)
		(fp_line
			(start 0.12065 0.2794)
			(end 0.12065 0.3048)
			(stroke
				(width 0.1)
				(type default)
			)
			(layer "B.Fab")
		)
		(fp_line
			(start -0.120396 0.2794)
			(end 0.12065 0.2794)
			(stroke
				(width 0.1)
				(type default)
			)
			(layer "B.Fab")
		)
		(fp_line
			(start 0.67945 0.3048)
			(end 0.67945 -0.305054)
			(stroke
				(width 0.1)
				(type default)
			)
			(layer "B.Fab")
		)
		(fp_line
			(start 0.12065 0.3048)
			(end 0.67945 0.3048)
			(stroke
				(width 0.1)
				(type default)
			)
			(layer "B.Fab")
		)
		(fp_line
			(start -0.120396 0.3048)
			(end -0.120396 0.2794)
			(stroke
				(width 0.1)
				(type default)
			)
			(layer "B.Fab")
		)
		(fp_line
			(start -0.67945 0.3048)
			(end -0.120396 0.3048)
			(stroke
				(width 0.1)
				(type default)
			)
			(layer "B.Fab")
		)
		(pad "1" smd circle
			(at 0.40005 0 270)
			(size 0 0)
			(layers "B.Cu" "B.Mask" "B.Paste")
			(net "DBP_CPU0_MBP1_GTL_R_N")
		)
		(pad "2" smd circle
			(at -0.40005 0 270)
			(size 0 0)
			(layers "B.Cu" "B.Mask" "B.Paste")
			(net "DBP_CPU_MBP1_GTL_N")
		)
	)
	(footprint ""
		(layer "B.Cu")
		(at 258.023614 -321.524376 -90)
		(property "Reference" "C22"
			(at 0 0 90)
			(layer "B.SilkS")
			(hide yes)
			(effects
				(font
					(size 1.27 1.27)
				)
				(justify mirror)
			)
		)
		(property "Value" ""
			(at 0 0 90)
			(layer "B.Fab")
			(effects
				(font
					(size 1.27 1.27)
				)
				(justify mirror)
			)
		)
		(duplicate_pad_numbers_are_jumpers no)
		(fp_line
			(start -1.524 0.762)
			(end 1.524 0.762)
			(stroke
				(width 0.1524)
				(type default)
			)
			(layer "B.SilkS")
		)
		(fp_line
			(start 1.524 0.762)
			(end 1.524 -0.762)
			(stroke
				(width 0.1524)
				(type default)
			)
			(layer "B.SilkS")
		)
		(fp_line
			(start -1.524 -0.762)
			(end -1.524 0.762)
			(stroke
				(width 0.1524)
				(type default)
			)
			(layer "B.SilkS")
		)
		(fp_line
			(start 1.524 -0.762)
			(end -1.524 -0.762)
			(stroke
				(width 0.1524)
				(type default)
			)
			(layer "B.SilkS")
		)
		(fp_line
			(start -1.1049 0.724916)
			(end -1.1049 -0.724916)
			(stroke
				(width 0.1)
				(type default)
			)
			(layer "B.Fab")
		)
		(fp_line
			(start 1.1049 0.724916)
			(end -1.1049 0.724916)
			(stroke
				(width 0.1)
				(type default)
			)
			(layer "B.Fab")
		)
		(fp_line
			(start -1.1049 -0.724916)
			(end 1.1049 -0.724916)
			(stroke
				(width 0.1)
				(type default)
			)
			(layer "B.Fab")
		)
		(fp_line
			(start 1.1049 -0.724916)
			(end 1.1049 0.724916)
			(stroke
				(width 0.1)
				(type default)
			)
			(layer "B.Fab")
		)
		(pad "1" smd rect
			(at 0.889 0 270)
			(size 1.016 1.27)
			(layers "B.Cu" "B.Mask" "B.Paste")
			(net "P12V_S3_AUX_CPU0_NVDIMM")
		)
		(pad "2" smd rect
			(at -0.889 0 270)
			(size 1.016 1.27)
			(layers "B.Cu" "B.Mask" "B.Paste")
			(net "GND")
		)
	)
	(footprint ""
		(layer "B.Cu")
		(at 339.244686 -46.499272 180)
		(property "Reference" "C1205"
			(at 0 0 0)
			(layer "B.SilkS")
			(hide yes)
			(effects
				(font
					(size 1.27 1.27)
				)
				(justify mirror)
			)
		)
		(property "Value" ""
			(at 0 0 0)
			(layer "B.Fab")
			(effects
				(font
					(size 1.27 1.27)
				)
				(justify mirror)
			)
		)
		(duplicate_pad_numbers_are_jumpers no)
		(fp_line
			(start 0.7874 0.4064)
			(end 0.7874 -0.4064)
			(stroke
				(width 0.1524)
				(type default)
			)
			(layer "B.SilkS")
		)
		(fp_line
			(start 0.7874 -0.4064)
			(end -0.7874 -0.4064)
			(stroke
				(width 0.1524)
				(type default)
			)
			(layer "B.SilkS")
		)
		(fp_line
			(start -0.7874 0.4064)
			(end 0.7874 0.4064)
			(stroke
				(width 0.1524)
				(type default)
			)
			(layer "B.SilkS")
		)
		(fp_line
			(start -0.7874 -0.4064)
			(end -0.7874 0.4064)
			(stroke
				(width 0.1524)
				(type default)
			)
			(layer "B.SilkS")
		)
		(fp_line
			(start 0.67945 0.3048)
			(end 0.67945 -0.305054)
			(stroke
				(width 0.1)
				(type default)
			)
			(layer "B.Fab")
		)
		(fp_line
			(start 0.67945 -0.305054)
			(end 0.12065 -0.305054)
			(stroke
				(width 0.1)
				(type default)
			)
			(layer "B.Fab")
		)
		(fp_line
			(start 0.12065 0.3048)
			(end 0.67945 0.3048)
			(stroke
				(width 0.1)
				(type default)
			)
			(layer "B.Fab")
		)
		(fp_line
			(start 0.12065 0.2794)
			(end 0.12065 0.3048)
			(stroke
				(width 0.1)
				(type default)
			)
			(layer "B.Fab")
		)
		(fp_line
			(start 0.12065 -0.2794)
			(end -0.12065 -0.2794)
			(stroke
				(width 0.1)
				(type default)
			)
			(layer "B.Fab")
		)
		(fp_line
			(start 0.12065 -0.305054)
			(end 0.12065 -0.2794)
			(stroke
				(width 0.1)
				(type default)
			)
			(layer "B.Fab")
		)
		(fp_line
			(start -0.120396 0.3048)
			(end -0.120396 0.2794)
			(stroke
				(width 0.1)
				(type default)
			)
			(layer "B.Fab")
		)
		(fp_line
			(start -0.120396 0.2794)
			(end 0.12065 0.2794)
			(stroke
				(width 0.1)
				(type default)
			)
			(layer "B.Fab")
		)
		(fp_line
			(start -0.12065 -0.2794)
			(end -0.12065 -0.3048)
			(stroke
				(width 0.1)
				(type default)
			)
			(layer "B.Fab")
		)
		(fp_line
			(start -0.12065 -0.3048)
			(end -0.67945 -0.3048)
			(stroke
				(width 0.1)
				(type default)
			)
			(layer "B.Fab")
		)
		(fp_line
			(start -0.67945 0.3048)
			(end -0.120396 0.3048)
			(stroke
				(width 0.1)
				(type default)
			)
			(layer "B.Fab")
		)
		(fp_line
			(start -0.67945 -0.3048)
			(end -0.67945 0.3048)
			(stroke
				(width 0.1)
				(type default)
			)
			(layer "B.Fab")
		)
		(pad "1" smd circle
			(at 0.40005 0)
			(size 0 0)
			(layers "B.Cu" "B.Mask" "B.Paste")
			(net "P1V05_PCH_AUX")
		)
		(pad "2" smd circle
			(at -0.40005 0)
			(size 0 0)
			(layers "B.Cu" "B.Mask" "B.Paste")
			(net "GND")
		)
	)
	(footprint ""
		(layer "B.Cu")
		(at 62.996572 -144.44726)
		(property "Reference" "PC456_P1_2"
			(at 0 0 0)
			(layer "B.SilkS")
			(hide yes)
			(effects
				(font
					(size 1.27 1.27)
				)
				(justify mirror)
			)
		)
		(property "Value" ""
			(at 0 0 0)
			(layer "B.Fab")
			(effects
				(font
					(size 1.27 1.27)
				)
				(justify mirror)
			)
		)
		(duplicate_pad_numbers_are_jumpers no)
		(fp_line
			(start -1.524 -0.762)
			(end -1.524 0.762)
			(stroke
				(width 0.1524)
				(type default)
			)
			(layer "B.SilkS")
		)
		(fp_line
			(start -1.524 0.762)
			(end 1.524 0.762)
			(stroke
				(width 0.1524)
				(type default)
			)
			(layer "B.SilkS")
		)
		(fp_line
			(start 1.524 -0.762)
			(end -1.524 -0.762)
			(stroke
				(width 0.1524)
				(type default)
			)
			(layer "B.SilkS")
		)
		(fp_line
			(start 1.524 0.762)
			(end 1.524 -0.762)
			(stroke
				(width 0.1524)
				(type default)
			)
			(layer "B.SilkS")
		)
		(fp_line
			(start -1.1049 -0.724916)
			(end 1.1049 -0.724916)
			(stroke
				(width 0.1)
				(type default)
			)
			(layer "B.Fab")
		)
		(fp_line
			(start -1.1049 0.724916)
			(end -1.1049 -0.724916)
			(stroke
				(width 0.1)
				(type default)
			)
			(layer "B.Fab")
		)
		(fp_line
			(start 1.1049 -0.724916)
			(end 1.1049 0.724916)
			(stroke
				(width 0.1)
				(type default)
			)
			(layer "B.Fab")
		)
		(fp_line
			(start 1.1049 0.724916)
			(end -1.1049 0.724916)
			(stroke
				(width 0.1)
				(type default)
			)
			(layer "B.Fab")
		)
		(pad "1" smd rect
			(at 0.889 0)
			(size 1.016 1.27)
			(layers "B.Cu" "B.Mask" "B.Paste")
			(net "PVCCINFAON_CPU1")
		)
		(pad "2" smd rect
			(at -0.889 0)
			(size 1.016 1.27)
			(layers "B.Cu" "B.Mask" "B.Paste")
			(net "GND")
		)
	)
	(footprint ""
		(layer "B.Cu")
		(at 428.413926 -127.578866)
		(property "Reference" "PR372"
			(at 0 0 0)
			(layer "B.SilkS")
			(hide yes)
			(effects
				(font
					(size 1.27 1.27)
				)
				(justify mirror)
			)
		)
		(property "Value" ""
			(at 0 0 0)
			(layer "B.Fab")
			(effects
				(font
					(size 1.27 1.27)
				)
				(justify mirror)
			)
		)
		(duplicate_pad_numbers_are_jumpers no)
		(fp_line
			(start -0.7874 -0.4064)
			(end -0.7874 0.4064)
			(stroke
				(width 0.1524)
				(type default)
			)
			(layer "B.SilkS")
		)
		(fp_line
			(start -0.7874 0.4064)
			(end 0.7874 0.4064)
			(stroke
				(width 0.1524)
				(type default)
			)
			(layer "B.SilkS")
		)
		(fp_line
			(start 0.7874 -0.4064)
			(end -0.7874 -0.4064)
			(stroke
				(width 0.1524)
				(type default)
			)
			(layer "B.SilkS")
		)
		(fp_line
			(start 0.7874 0.4064)
			(end 0.7874 -0.4064)
			(stroke
				(width 0.1524)
				(type default)
			)
			(layer "B.SilkS")
		)
		(fp_line
			(start -0.67945 -0.3048)
			(end -0.67945 0.3048)
			(stroke
				(width 0.1)
				(type default)
			)
			(layer "B.Fab")
		)
		(fp_line
			(start -0.67945 0.3048)
			(end -0.120396 0.3048)
			(stroke
				(width 0.1)
				(type default)
			)
			(layer "B.Fab")
		)
		(fp_line
			(start -0.12065 -0.3048)
			(end -0.67945 -0.3048)
			(stroke
				(width 0.1)
				(type default)
			)
			(layer "B.Fab")
		)
		(fp_line
			(start -0.12065 -0.2794)
			(end -0.12065 -0.3048)
			(stroke
				(width 0.1)
				(type default)
			)
			(layer "B.Fab")
		)
		(fp_line
			(start -0.120396 0.2794)
			(end 0.12065 0.2794)
			(stroke
				(width 0.1)
				(type default)
			)
			(layer "B.Fab")
		)
		(fp_line
			(start -0.120396 0.3048)
			(end -0.120396 0.2794)
			(stroke
				(width 0.1)
				(type default)
			)
			(layer "B.Fab")
		)
		(fp_line
			(start 0.12065 -0.305054)
			(end 0.12065 -0.2794)
			(stroke
				(width 0.1)
				(type default)
			)
			(layer "B.Fab")
		)
		(fp_line
			(start 0.12065 -0.2794)
			(end -0.12065 -0.2794)
			(stroke
				(width 0.1)
				(type default)
			)
			(layer "B.Fab")
		)
		(fp_line
			(start 0.12065 0.2794)
			(end 0.12065 0.3048)
			(stroke
				(width 0.1)
				(type default)
			)
			(layer "B.Fab")
		)
		(fp_line
			(start 0.12065 0.3048)
			(end 0.67945 0.3048)
			(stroke
				(width 0.1)
				(type default)
			)
			(layer "B.Fab")
		)
		(fp_line
			(start 0.67945 -0.305054)
			(end 0.12065 -0.305054)
			(stroke
				(width 0.1)
				(type default)
			)
			(layer "B.Fab")
		)
		(fp_line
			(start 0.67945 0.3048)
			(end 0.67945 -0.305054)
			(stroke
				(width 0.1)
				(type default)
			)
			(layer "B.Fab")
		)
		(pad "1" smd circle
			(at 0.40005 0 180)
			(size 0 0)
			(layers "B.Cu" "B.Mask" "B.Paste")
			(net "P3V3_AUX")
		)
		(pad "2" smd circle
			(at -0.40005 0 180)
			(size 0 0)
			(layers "B.Cu" "B.Mask" "B.Paste")
			(net "PVCCD_HV_CPU0_FAULT")
		)
	)
	(footprint ""
		(layer "B.Cu")
		(at 255.064006 -102.285292 90)
		(property "Reference" "C1312"
			(at 0 0 90)
			(layer "B.SilkS")
			(hide yes)
			(effects
				(font
					(size 1.27 1.27)
				)
				(justify mirror)
			)
		)
		(property "Value" ""
			(at 0 0 90)
			(layer "B.Fab")
			(effects
				(font
					(size 1.27 1.27)
				)
				(justify mirror)
			)
		)
		(duplicate_pad_numbers_are_jumpers no)
		(fp_line
			(start 0.7874 -0.4064)
			(end -0.7874 -0.4064)
			(stroke
				(width 0.1524)
				(type default)
			)
			(layer "B.SilkS")
		)
		(fp_line
			(start -0.7874 -0.4064)
			(end -0.7874 0.4064)
			(stroke
				(width 0.1524)
				(type default)
			)
			(layer "B.SilkS")
		)
		(fp_line
			(start 0.7874 0.4064)
			(end 0.7874 -0.4064)
			(stroke
				(width 0.1524)
				(type default)
			)
			(layer "B.SilkS")
		)
		(fp_line
			(start -0.7874 0.4064)
			(end 0.7874 0.4064)
			(stroke
				(width 0.1524)
				(type default)
			)
			(layer "B.SilkS")
		)
		(fp_line
			(start 0.67945 -0.305054)
			(end 0.12065 -0.305054)
			(stroke
				(width 0.1)
				(type default)
			)
			(layer "B.Fab")
		)
		(fp_line
			(start 0.12065 -0.305054)
			(end 0.12065 -0.2794)
			(stroke
				(width 0.1)
				(type default)
			)
			(layer "B.Fab")
		)
		(fp_line
			(start -0.12065 -0.3048)
			(end -0.67945 -0.3048)
			(stroke
				(width 0.1)
				(type default)
			)
			(layer "B.Fab")
		)
		(fp_line
			(start -0.67945 -0.3048)
			(end -0.67945 0.3048)
			(stroke
				(width 0.1)
				(type default)
			)
			(layer "B.Fab")
		)
		(fp_line
			(start 0.12065 -0.2794)
			(end -0.12065 -0.2794)
			(stroke
				(width 0.1)
				(type default)
			)
			(layer "B.Fab")
		)
		(fp_line
			(start -0.12065 -0.2794)
			(end -0.12065 -0.3048)
			(stroke
				(width 0.1)
				(type default)
			)
			(layer "B.Fab")
		)
		(fp_line
			(start 0.12065 0.2794)
			(end 0.12065 0.3048)
			(stroke
				(width 0.1)
				(type default)
			)
			(layer "B.Fab")
		)
		(fp_line
			(start -0.120396 0.2794)
			(end 0.12065 0.2794)
			(stroke
				(width 0.1)
				(type default)
			)
			(layer "B.Fab")
		)
		(fp_line
			(start 0.67945 0.3048)
			(end 0.67945 -0.305054)
			(stroke
				(width 0.1)
				(type default)
			)
			(layer "B.Fab")
		)
		(fp_line
			(start 0.12065 0.3048)
			(end 0.67945 0.3048)
			(stroke
				(width 0.1)
				(type default)
			)
			(layer "B.Fab")
		)
		(fp_line
			(start -0.120396 0.3048)
			(end -0.120396 0.2794)
			(stroke
				(width 0.1)
				(type default)
			)
			(layer "B.Fab")
		)
		(fp_line
			(start -0.67945 0.3048)
			(end -0.120396 0.3048)
			(stroke
				(width 0.1)
				(type default)
			)
			(layer "B.Fab")
		)
		(pad "1" smd circle
			(at 0.40005 0 270)
			(size 0 0)
			(layers "B.Cu" "B.Mask" "B.Paste")
			(net "P3V3_AUX_CLK_GEN_VDDMXCK_CK440")
		)
		(pad "2" smd circle
			(at -0.40005 0 270)
			(size 0 0)
			(layers "B.Cu" "B.Mask" "B.Paste")
			(net "GND")
		)
	)
	(footprint ""
		(layer "B.Cu")
		(at 324.19163 -25.68702 90)
		(property "Reference" "R1996"
			(at 0 0 90)
			(layer "B.SilkS")
			(hide yes)
			(effects
				(font
					(size 1.27 1.27)
				)
				(justify mirror)
			)
		)
		(property "Value" ""
			(at 0 0 90)
			(layer "B.Fab")
			(effects
				(font
					(size 1.27 1.27)
				)
				(justify mirror)
			)
		)
		(duplicate_pad_numbers_are_jumpers no)
		(fp_line
			(start 0.7874 -0.4064)
			(end -0.7874 -0.4064)
			(stroke
				(width 0.1524)
				(type default)
			)
			(layer "B.SilkS")
		)
		(fp_line
			(start -0.7874 -0.4064)
			(end -0.7874 0.4064)
			(stroke
				(width 0.1524)
				(type default)
			)
			(layer "B.SilkS")
		)
		(fp_line
			(start 0.7874 0.4064)
			(end 0.7874 -0.4064)
			(stroke
				(width 0.1524)
				(type default)
			)
			(layer "B.SilkS")
		)
		(fp_line
			(start -0.7874 0.4064)
			(end 0.7874 0.4064)
			(stroke
				(width 0.1524)
				(type default)
			)
			(layer "B.SilkS")
		)
		(fp_line
			(start 0.67945 -0.305054)
			(end 0.12065 -0.305054)
			(stroke
				(width 0.1)
				(type default)
			)
			(layer "B.Fab")
		)
		(fp_line
			(start 0.12065 -0.305054)
			(end 0.12065 -0.2794)
			(stroke
				(width 0.1)
				(type default)
			)
			(layer "B.Fab")
		)
		(fp_line
			(start -0.12065 -0.3048)
			(end -0.67945 -0.3048)
			(stroke
				(width 0.1)
				(type default)
			)
			(layer "B.Fab")
		)
		(fp_line
			(start -0.67945 -0.3048)
			(end -0.67945 0.3048)
			(stroke
				(width 0.1)
				(type default)
			)
			(layer "B.Fab")
		)
		(fp_line
			(start 0.12065 -0.2794)
			(end -0.12065 -0.2794)
			(stroke
				(width 0.1)
				(type default)
			)
			(layer "B.Fab")
		)
		(fp_line
			(start -0.12065 -0.2794)
			(end -0.12065 -0.3048)
			(stroke
				(width 0.1)
				(type default)
			)
			(layer "B.Fab")
		)
		(fp_line
			(start 0.12065 0.2794)
			(end 0.12065 0.3048)
			(stroke
				(width 0.1)
				(type default)
			)
			(layer "B.Fab")
		)
		(fp_line
			(start -0.120396 0.2794)
			(end 0.12065 0.2794)
			(stroke
				(width 0.1)
				(type default)
			)
			(layer "B.Fab")
		)
		(fp_line
			(start 0.67945 0.3048)
			(end 0.67945 -0.305054)
			(stroke
				(width 0.1)
				(type default)
			)
			(layer "B.Fab")
		)
		(fp_line
			(start 0.12065 0.3048)
			(end 0.67945 0.3048)
			(stroke
				(width 0.1)
				(type default)
			)
			(layer "B.Fab")
		)
		(fp_line
			(start -0.120396 0.3048)
			(end -0.120396 0.2794)
			(stroke
				(width 0.1)
				(type default)
			)
			(layer "B.Fab")
		)
		(fp_line
			(start -0.67945 0.3048)
			(end -0.120396 0.3048)
			(stroke
				(width 0.1)
				(type default)
			)
			(layer "B.Fab")
		)
		(pad "1" smd circle
			(at 0.40005 0 270)
			(size 0 0)
			(layers "B.Cu" "B.Mask" "B.Paste")
			(net "FM_PCH_SLP_S4_N")
		)
		(pad "2" smd circle
			(at -0.40005 0 270)
			(size 0 0)
			(layers "B.Cu" "B.Mask" "B.Paste")
			(net "FM_SLPS4_PLD_N")
		)
	)
	(footprint ""
		(layer "B.Cu")
		(at 338.280502 -341.017606 -90)
		(property "Reference" "PC258_P0_6"
			(at 0 0 90)
			(layer "B.SilkS")
			(hide yes)
			(effects
				(font
					(size 1.27 1.27)
				)
				(justify mirror)
			)
		)
		(property "Value" ""
			(at 0 0 90)
			(layer "B.Fab")
			(effects
				(font
					(size 1.27 1.27)
				)
				(justify mirror)
			)
		)
		(duplicate_pad_numbers_are_jumpers no)
		(fp_line
			(start -1.524 0.762)
			(end 1.524 0.762)
			(stroke
				(width 0.1524)
				(type default)
			)
			(layer "B.SilkS")
		)
		(fp_line
			(start 1.524 0.762)
			(end 1.524 -0.762)
			(stroke
				(width 0.1524)
				(type default)
			)
			(layer "B.SilkS")
		)
		(fp_line
			(start -1.524 -0.762)
			(end -1.524 0.762)
			(stroke
				(width 0.1524)
				(type default)
			)
			(layer "B.SilkS")
		)
		(fp_line
			(start 1.524 -0.762)
			(end -1.524 -0.762)
			(stroke
				(width 0.1524)
				(type default)
			)
			(layer "B.SilkS")
		)
		(fp_line
			(start -1.1049 0.724916)
			(end -1.1049 -0.724916)
			(stroke
				(width 0.1)
				(type default)
			)
			(layer "B.Fab")
		)
		(fp_line
			(start 1.1049 0.724916)
			(end -1.1049 0.724916)
			(stroke
				(width 0.1)
				(type default)
			)
			(layer "B.Fab")
		)
		(fp_line
			(start -1.1049 -0.724916)
			(end 1.1049 -0.724916)
			(stroke
				(width 0.1)
				(type default)
			)
			(layer "B.Fab")
		)
		(fp_line
			(start 1.1049 -0.724916)
			(end 1.1049 0.724916)
			(stroke
				(width 0.1)
				(type default)
			)
			(layer "B.Fab")
		)
		(pad "1" smd rect
			(at 0.889 0 270)
			(size 1.016 1.27)
			(layers "B.Cu" "B.Mask" "B.Paste")
			(net "SW_P12V_PVCCIN_CPU0_FLT")
		)
		(pad "2" smd rect
			(at -0.889 0 270)
			(size 1.016 1.27)
			(layers "B.Cu" "B.Mask" "B.Paste")
			(net "GND")
		)
	)
	(footprint ""
		(layer "B.Cu")
		(at 367.824258 -241.11585 90)
		(property "Reference" "C515"
			(at 0 0 90)
			(layer "B.SilkS")
			(hide yes)
			(effects
				(font
					(size 1.27 1.27)
				)
				(justify mirror)
			)
		)
		(property "Value" ""
			(at 0 0 90)
			(layer "B.Fab")
			(effects
				(font
					(size 1.27 1.27)
				)
				(justify mirror)
			)
		)
		(duplicate_pad_numbers_are_jumpers no)
		(fp_line
			(start 1.524 -0.762)
			(end -1.524 -0.762)
			(stroke
				(width 0.1524)
				(type default)
			)
			(layer "B.SilkS")
		)
		(fp_line
			(start -1.524 -0.762)
			(end -1.524 0.762)
			(stroke
				(width 0.1524)
				(type default)
			)
			(layer "B.SilkS")
		)
		(fp_line
			(start 1.524 0.762)
			(end 1.524 -0.762)
			(stroke
				(width 0.1524)
				(type default)
			)
			(layer "B.SilkS")
		)
		(fp_line
			(start -1.524 0.762)
			(end 1.524 0.762)
			(stroke
				(width 0.1524)
				(type default)
			)
			(layer "B.SilkS")
		)
		(fp_line
			(start 1.1049 -0.724916)
			(end 1.1049 0.724916)
			(stroke
				(width 0.1)
				(type default)
			)
			(layer "B.Fab")
		)
		(fp_line
			(start -1.1049 -0.724916)
			(end 1.1049 -0.724916)
			(stroke
				(width 0.1)
				(type default)
			)
			(layer "B.Fab")
		)
		(fp_line
			(start 1.1049 0.724916)
			(end -1.1049 0.724916)
			(stroke
				(width 0.1)
				(type default)
			)
			(layer "B.Fab")
		)
		(fp_line
			(start -1.1049 0.724916)
			(end -1.1049 -0.724916)
			(stroke
				(width 0.1)
				(type default)
			)
			(layer "B.Fab")
		)
		(pad "1" smd rect
			(at 0.889 0 90)
			(size 1.016 1.27)
			(layers "B.Cu" "B.Mask" "B.Paste")
			(net "PVCCD_HV_CPU0")
		)
		(pad "2" smd rect
			(at -0.889 0 90)
			(size 1.016 1.27)
			(layers "B.Cu" "B.Mask" "B.Paste")
			(net "GND")
		)
	)
	(footprint ""
		(layer "B.Cu")
		(at 301.356014 -321.549776 -90)
		(property "Reference" "C4"
			(at 0 0 90)
			(layer "B.SilkS")
			(hide yes)
			(effects
				(font
					(size 1.27 1.27)
				)
				(justify mirror)
			)
		)
		(property "Value" ""
			(at 0 0 90)
			(layer "B.Fab")
			(effects
				(font
					(size 1.27 1.27)
				)
				(justify mirror)
			)
		)
		(duplicate_pad_numbers_are_jumpers no)
		(fp_line
			(start -1.524 0.762)
			(end 1.524 0.762)
			(stroke
				(width 0.1524)
				(type default)
			)
			(layer "B.SilkS")
		)
		(fp_line
			(start 1.524 0.762)
			(end 1.524 -0.762)
			(stroke
				(width 0.1524)
				(type default)
			)
			(layer "B.SilkS")
		)
		(fp_line
			(start -1.524 -0.762)
			(end -1.524 0.762)
			(stroke
				(width 0.1524)
				(type default)
			)
			(layer "B.SilkS")
		)
		(fp_line
			(start 1.524 -0.762)
			(end -1.524 -0.762)
			(stroke
				(width 0.1524)
				(type default)
			)
			(layer "B.SilkS")
		)
		(fp_line
			(start -1.1049 0.724916)
			(end -1.1049 -0.724916)
			(stroke
				(width 0.1)
				(type default)
			)
			(layer "B.Fab")
		)
		(fp_line
			(start 1.1049 0.724916)
			(end -1.1049 0.724916)
			(stroke
				(width 0.1)
				(type default)
			)
			(layer "B.Fab")
		)
		(fp_line
			(start -1.1049 -0.724916)
			(end 1.1049 -0.724916)
			(stroke
				(width 0.1)
				(type default)
			)
			(layer "B.Fab")
		)
		(fp_line
			(start 1.1049 -0.724916)
			(end 1.1049 0.724916)
			(stroke
				(width 0.1)
				(type default)
			)
			(layer "B.Fab")
		)
		(pad "1" smd rect
			(at 0.889 0 270)
			(size 1.016 1.27)
			(layers "B.Cu" "B.Mask" "B.Paste")
			(net "P12V_S3_AUX_CPU0_NVDIMM")
		)
		(pad "2" smd rect
			(at -0.889 0 270)
			(size 1.016 1.27)
			(layers "B.Cu" "B.Mask" "B.Paste")
			(net "GND")
		)
	)
	(footprint ""
		(layer "B.Cu")
		(at 320.039492 -186.440318 90)
		(property "Reference" "R4390"
			(at 0 0 90)
			(layer "B.SilkS")
			(hide yes)
			(effects
				(font
					(size 1.27 1.27)
				)
				(justify mirror)
			)
		)
		(property "Value" ""
			(at 0 0 90)
			(layer "B.Fab")
			(effects
				(font
					(size 1.27 1.27)
				)
				(justify mirror)
			)
		)
		(duplicate_pad_numbers_are_jumpers no)
		(fp_line
			(start 0.7874 -0.4064)
			(end -0.7874 -0.4064)
			(stroke
				(width 0.1524)
				(type default)
			)
			(layer "B.SilkS")
		)
		(fp_line
			(start -0.7874 -0.4064)
			(end -0.7874 0.4064)
			(stroke
				(width 0.1524)
				(type default)
			)
			(layer "B.SilkS")
		)
		(fp_line
			(start 0.7874 0.4064)
			(end 0.7874 -0.4064)
			(stroke
				(width 0.1524)
				(type default)
			)
			(layer "B.SilkS")
		)
		(fp_line
			(start -0.7874 0.4064)
			(end 0.7874 0.4064)
			(stroke
				(width 0.1524)
				(type default)
			)
			(layer "B.SilkS")
		)
		(fp_line
			(start 0.67945 -0.305054)
			(end 0.12065 -0.305054)
			(stroke
				(width 0.1)
				(type default)
			)
			(layer "B.Fab")
		)
		(fp_line
			(start 0.12065 -0.305054)
			(end 0.12065 -0.2794)
			(stroke
				(width 0.1)
				(type default)
			)
			(layer "B.Fab")
		)
		(fp_line
			(start -0.12065 -0.3048)
			(end -0.67945 -0.3048)
			(stroke
				(width 0.1)
				(type default)
			)
			(layer "B.Fab")
		)
		(fp_line
			(start -0.67945 -0.3048)
			(end -0.67945 0.3048)
			(stroke
				(width 0.1)
				(type default)
			)
			(layer "B.Fab")
		)
		(fp_line
			(start 0.12065 -0.2794)
			(end -0.12065 -0.2794)
			(stroke
				(width 0.1)
				(type default)
			)
			(layer "B.Fab")
		)
		(fp_line
			(start -0.12065 -0.2794)
			(end -0.12065 -0.3048)
			(stroke
				(width 0.1)
				(type default)
			)
			(layer "B.Fab")
		)
		(fp_line
			(start 0.12065 0.2794)
			(end 0.12065 0.3048)
			(stroke
				(width 0.1)
				(type default)
			)
			(layer "B.Fab")
		)
		(fp_line
			(start -0.120396 0.2794)
			(end 0.12065 0.2794)
			(stroke
				(width 0.1)
				(type default)
			)
			(layer "B.Fab")
		)
		(fp_line
			(start 0.67945 0.3048)
			(end 0.67945 -0.305054)
			(stroke
				(width 0.1)
				(type default)
			)
			(layer "B.Fab")
		)
		(fp_line
			(start 0.12065 0.3048)
			(end 0.67945 0.3048)
			(stroke
				(width 0.1)
				(type default)
			)
			(layer "B.Fab")
		)
		(fp_line
			(start -0.120396 0.3048)
			(end -0.120396 0.2794)
			(stroke
				(width 0.1)
				(type default)
			)
			(layer "B.Fab")
		)
		(fp_line
			(start -0.67945 0.3048)
			(end -0.120396 0.3048)
			(stroke
				(width 0.1)
				(type default)
			)
			(layer "B.Fab")
		)
		(pad "1" smd circle
			(at 0.40005 0 270)
			(size 0 0)
			(layers "B.Cu" "B.Mask" "B.Paste")
			(net "PVNN_TERM_CPU0")
		)
		(pad "2" smd circle
			(at -0.40005 0 270)
			(size 0 0)
			(layers "B.Cu" "B.Mask" "B.Paste")
			(net "H_CPU_ERR0_LVC1_R_N")
		)
	)
	(footprint ""
		(layer "B.Cu")
		(at 145.18132 -13.762228 90)
		(property "Reference" "R1816"
			(at 0 0 90)
			(layer "B.SilkS")
			(hide yes)
			(effects
				(font
					(size 1.27 1.27)
				)
				(justify mirror)
			)
		)
		(property "Value" ""
			(at 0 0 90)
			(layer "B.Fab")
			(effects
				(font
					(size 1.27 1.27)
				)
				(justify mirror)
			)
		)
		(duplicate_pad_numbers_are_jumpers no)
		(fp_line
			(start 0.7874 -0.4064)
			(end -0.7874 -0.4064)
			(stroke
				(width 0.1524)
				(type default)
			)
			(layer "B.SilkS")
		)
		(fp_line
			(start -0.7874 -0.4064)
			(end -0.7874 0.4064)
			(stroke
				(width 0.1524)
				(type default)
			)
			(layer "B.SilkS")
		)
		(fp_line
			(start 0.7874 0.4064)
			(end 0.7874 -0.4064)
			(stroke
				(width 0.1524)
				(type default)
			)
			(layer "B.SilkS")
		)
		(fp_line
			(start -0.7874 0.4064)
			(end 0.7874 0.4064)
			(stroke
				(width 0.1524)
				(type default)
			)
			(layer "B.SilkS")
		)
		(fp_line
			(start 0.67945 -0.305054)
			(end 0.12065 -0.305054)
			(stroke
				(width 0.1)
				(type default)
			)
			(layer "B.Fab")
		)
		(fp_line
			(start 0.12065 -0.305054)
			(end 0.12065 -0.2794)
			(stroke
				(width 0.1)
				(type default)
			)
			(layer "B.Fab")
		)
		(fp_line
			(start -0.12065 -0.3048)
			(end -0.67945 -0.3048)
			(stroke
				(width 0.1)
				(type default)
			)
			(layer "B.Fab")
		)
		(fp_line
			(start -0.67945 -0.3048)
			(end -0.67945 0.3048)
			(stroke
				(width 0.1)
				(type default)
			)
			(layer "B.Fab")
		)
		(fp_line
			(start 0.12065 -0.2794)
			(end -0.12065 -0.2794)
			(stroke
				(width 0.1)
				(type default)
			)
			(layer "B.Fab")
		)
		(fp_line
			(start -0.12065 -0.2794)
			(end -0.12065 -0.3048)
			(stroke
				(width 0.1)
				(type default)
			)
			(layer "B.Fab")
		)
		(fp_line
			(start 0.12065 0.2794)
			(end 0.12065 0.3048)
			(stroke
				(width 0.1)
				(type default)
			)
			(layer "B.Fab")
		)
		(fp_line
			(start -0.120396 0.2794)
			(end 0.12065 0.2794)
			(stroke
				(width 0.1)
				(type default)
			)
			(layer "B.Fab")
		)
		(fp_line
			(start 0.67945 0.3048)
			(end 0.67945 -0.305054)
			(stroke
				(width 0.1)
				(type default)
			)
			(layer "B.Fab")
		)
		(fp_line
			(start 0.12065 0.3048)
			(end 0.67945 0.3048)
			(stroke
				(width 0.1)
				(type default)
			)
			(layer "B.Fab")
		)
		(fp_line
			(start -0.120396 0.3048)
			(end -0.120396 0.2794)
			(stroke
				(width 0.1)
				(type default)
			)
			(layer "B.Fab")
		)
		(fp_line
			(start -0.67945 0.3048)
			(end -0.120396 0.3048)
			(stroke
				(width 0.1)
				(type default)
			)
			(layer "B.Fab")
		)
		(pad "1" smd circle
			(at 0.40005 0 270)
			(size 0 0)
			(layers "B.Cu" "B.Mask" "B.Paste")
			(net "PWRGD_PS_PWROK")
		)
		(pad "2" smd circle
			(at -0.40005 0 270)
			(size 0 0)
			(layers "B.Cu" "B.Mask" "B.Paste")
			(net "PWRGD_PS_PWROK_R")
		)
	)
	(footprint ""
		(layer "B.Cu")
		(at 446.941448 -181.977792 180)
		(property "Reference" "C1364"
			(at 0 0 0)
			(layer "B.SilkS")
			(hide yes)
			(effects
				(font
					(size 1.27 1.27)
				)
				(justify mirror)
			)
		)
		(property "Value" ""
			(at 0 0 0)
			(layer "B.Fab")
			(effects
				(font
					(size 1.27 1.27)
				)
				(justify mirror)
			)
		)
		(duplicate_pad_numbers_are_jumpers no)
		(fp_line
			(start 0.7874 0.4064)
			(end 0.7874 -0.4064)
			(stroke
				(width 0.1524)
				(type default)
			)
			(layer "B.SilkS")
		)
		(fp_line
			(start 0.7874 -0.4064)
			(end -0.7874 -0.4064)
			(stroke
				(width 0.1524)
				(type default)
			)
			(layer "B.SilkS")
		)
		(fp_line
			(start -0.7874 0.4064)
			(end 0.7874 0.4064)
			(stroke
				(width 0.1524)
				(type default)
			)
			(layer "B.SilkS")
		)
		(fp_line
			(start -0.7874 -0.4064)
			(end -0.7874 0.4064)
			(stroke
				(width 0.1524)
				(type default)
			)
			(layer "B.SilkS")
		)
		(fp_line
			(start 0.67945 0.3048)
			(end 0.67945 -0.305054)
			(stroke
				(width 0.1)
				(type default)
			)
			(layer "B.Fab")
		)
		(fp_line
			(start 0.67945 -0.305054)
			(end 0.12065 -0.305054)
			(stroke
				(width 0.1)
				(type default)
			)
			(layer "B.Fab")
		)
		(fp_line
			(start 0.12065 0.3048)
			(end 0.67945 0.3048)
			(stroke
				(width 0.1)
				(type default)
			)
			(layer "B.Fab")
		)
		(fp_line
			(start 0.12065 0.2794)
			(end 0.12065 0.3048)
			(stroke
				(width 0.1)
				(type default)
			)
			(layer "B.Fab")
		)
		(fp_line
			(start 0.12065 -0.2794)
			(end -0.12065 -0.2794)
			(stroke
				(width 0.1)
				(type default)
			)
			(layer "B.Fab")
		)
		(fp_line
			(start 0.12065 -0.305054)
			(end 0.12065 -0.2794)
			(stroke
				(width 0.1)
				(type default)
			)
			(layer "B.Fab")
		)
		(fp_line
			(start -0.120396 0.3048)
			(end -0.120396 0.2794)
			(stroke
				(width 0.1)
				(type default)
			)
			(layer "B.Fab")
		)
		(fp_line
			(start -0.120396 0.2794)
			(end 0.12065 0.2794)
			(stroke
				(width 0.1)
				(type default)
			)
			(layer "B.Fab")
		)
		(fp_line
			(start -0.12065 -0.2794)
			(end -0.12065 -0.3048)
			(stroke
				(width 0.1)
				(type default)
			)
			(layer "B.Fab")
		)
		(fp_line
			(start -0.12065 -0.3048)
			(end -0.67945 -0.3048)
			(stroke
				(width 0.1)
				(type default)
			)
			(layer "B.Fab")
		)
		(fp_line
			(start -0.67945 0.3048)
			(end -0.120396 0.3048)
			(stroke
				(width 0.1)
				(type default)
			)
			(layer "B.Fab")
		)
		(fp_line
			(start -0.67945 -0.3048)
			(end -0.67945 0.3048)
			(stroke
				(width 0.1)
				(type default)
			)
			(layer "B.Fab")
		)
		(pad "1" smd circle
			(at 0.40005 0)
			(size 0 0)
			(layers "B.Cu" "B.Mask" "B.Paste")
			(net "PVNN_MAIN_CPU0")
		)
		(pad "2" smd circle
			(at -0.40005 0)
			(size 0 0)
			(layers "B.Cu" "B.Mask" "B.Paste")
			(net "GND")
		)
	)
	(footprint ""
		(layer "B.Cu")
		(at 320.776092 -37.442902 45)
		(property "Reference" "R1402"
			(at 0 0 45)
			(layer "B.SilkS")
			(hide yes)
			(effects
				(font
					(size 1.27 1.27)
				)
				(justify mirror)
			)
		)
		(property "Value" ""
			(at 0 0 45)
			(layer "B.Fab")
			(effects
				(font
					(size 1.27 1.27)
				)
				(justify mirror)
			)
		)
		(duplicate_pad_numbers_are_jumpers no)
		(fp_line
			(start -0.787389 -0.406267)
			(end -0.787389 0.406267)
			(stroke
				(width 0.1524)
				(type default)
			)
			(layer "B.SilkS")
		)
		(fp_line
			(start -0.787389 0.406267)
			(end 0.787389 0.406267)
			(stroke
				(width 0.1524)
				(type default)
			)
			(layer "B.SilkS")
		)
		(fp_line
			(start 0.787389 -0.406267)
			(end -0.787389 -0.406267)
			(stroke
				(width 0.1524)
				(type default)
			)
			(layer "B.SilkS")
		)
		(fp_line
			(start 0.787389 0.406267)
			(end 0.787389 -0.406267)
			(stroke
				(width 0.1524)
				(type default)
			)
			(layer "B.SilkS")
		)
		(fp_line
			(start -0.679446 -0.30479)
			(end -0.679446 0.30479)
			(stroke
				(width 0.1)
				(type default)
			)
			(layer "B.Fab")
		)
		(fp_line
			(start -0.120515 -0.30479)
			(end -0.679446 -0.30479)
			(stroke
				(width 0.1)
				(type default)
			)
			(layer "B.Fab")
		)
		(fp_line
			(start -0.120695 -0.279466)
			(end -0.120515 -0.30479)
			(stroke
				(width 0.1)
				(type default)
			)
			(layer "B.Fab")
		)
		(fp_line
			(start -0.679446 0.30479)
			(end -0.120515 0.30479)
			(stroke
				(width 0.1)
				(type default)
			)
			(layer "B.Fab")
		)
		(fp_line
			(start 0.120695 -0.304969)
			(end 0.120695 -0.279466)
			(stroke
				(width 0.1)
				(type default)
			)
			(layer "B.Fab")
		)
		(fp_line
			(start 0.120695 -0.279466)
			(end -0.120695 -0.279466)
			(stroke
				(width 0.1)
				(type default)
			)
			(layer "B.Fab")
		)
		(fp_line
			(start -0.120335 0.279466)
			(end 0.120695 0.279466)
			(stroke
				(width 0.1)
				(type default)
			)
			(layer "B.Fab")
		)
		(fp_line
			(start -0.120515 0.30479)
			(end -0.120335 0.279466)
			(stroke
				(width 0.1)
				(type default)
			)
			(layer "B.Fab")
		)
		(fp_line
			(start 0.679446 -0.305149)
			(end 0.120695 -0.304969)
			(stroke
				(width 0.1)
				(type default)
			)
			(layer "B.Fab")
		)
		(fp_line
			(start 0.120695 0.279466)
			(end 0.120515 0.30479)
			(stroke
				(width 0.1)
				(type default)
			)
			(layer "B.Fab")
		)
		(fp_line
			(start 0.120515 0.30479)
			(end 0.679446 0.30479)
			(stroke
				(width 0.1)
				(type default)
			)
			(layer "B.Fab")
		)
		(fp_line
			(start 0.679446 0.30479)
			(end 0.679446 -0.305149)
			(stroke
				(width 0.1)
				(type default)
			)
			(layer "B.Fab")
		)
		(pad "1" smd circle
			(at 0.40005 0 225)
			(size 0 0)
			(layers "B.Cu" "B.Mask" "B.Paste")
			(net "PWRGD_SYS_PWROK")
		)
		(pad "2" smd circle
			(at -0.40005 0 225)
			(size 0 0)
			(layers "B.Cu" "B.Mask" "B.Paste")
			(net "GND")
		)
	)
	(footprint ""
		(layer "B.Cu")
		(at 157.02788 -115.026948 180)
		(property "Reference" "R3478"
			(at 0 0 0)
			(layer "B.SilkS")
			(hide yes)
			(effects
				(font
					(size 1.27 1.27)
				)
				(justify mirror)
			)
		)
		(property "Value" ""
			(at 0 0 0)
			(layer "B.Fab")
			(effects
				(font
					(size 1.27 1.27)
				)
				(justify mirror)
			)
		)
		(duplicate_pad_numbers_are_jumpers no)
		(fp_line
			(start 0.7874 0.4064)
			(end 0.7874 -0.4064)
			(stroke
				(width 0.1524)
				(type default)
			)
			(layer "B.SilkS")
		)
		(fp_line
			(start 0.7874 -0.4064)
			(end -0.7874 -0.4064)
			(stroke
				(width 0.1524)
				(type default)
			)
			(layer "B.SilkS")
		)
		(fp_line
			(start -0.7874 0.4064)
			(end 0.7874 0.4064)
			(stroke
				(width 0.1524)
				(type default)
			)
			(layer "B.SilkS")
		)
		(fp_line
			(start -0.7874 -0.4064)
			(end -0.7874 0.4064)
			(stroke
				(width 0.1524)
				(type default)
			)
			(layer "B.SilkS")
		)
		(fp_line
			(start 0.67945 0.3048)
			(end 0.67945 -0.305054)
			(stroke
				(width 0.1)
				(type default)
			)
			(layer "B.Fab")
		)
		(fp_line
			(start 0.67945 -0.305054)
			(end 0.12065 -0.305054)
			(stroke
				(width 0.1)
				(type default)
			)
			(layer "B.Fab")
		)
		(fp_line
			(start 0.12065 0.3048)
			(end 0.67945 0.3048)
			(stroke
				(width 0.1)
				(type default)
			)
			(layer "B.Fab")
		)
		(fp_line
			(start 0.12065 0.2794)
			(end 0.12065 0.3048)
			(stroke
				(width 0.1)
				(type default)
			)
			(layer "B.Fab")
		)
		(fp_line
			(start 0.12065 -0.2794)
			(end -0.12065 -0.2794)
			(stroke
				(width 0.1)
				(type default)
			)
			(layer "B.Fab")
		)
		(fp_line
			(start 0.12065 -0.305054)
			(end 0.12065 -0.2794)
			(stroke
				(width 0.1)
				(type default)
			)
			(layer "B.Fab")
		)
		(fp_line
			(start -0.120396 0.3048)
			(end -0.120396 0.2794)
			(stroke
				(width 0.1)
				(type default)
			)
			(layer "B.Fab")
		)
		(fp_line
			(start -0.120396 0.2794)
			(end 0.12065 0.2794)
			(stroke
				(width 0.1)
				(type default)
			)
			(layer "B.Fab")
		)
		(fp_line
			(start -0.12065 -0.2794)
			(end -0.12065 -0.3048)
			(stroke
				(width 0.1)
				(type default)
			)
			(layer "B.Fab")
		)
		(fp_line
			(start -0.12065 -0.3048)
			(end -0.67945 -0.3048)
			(stroke
				(width 0.1)
				(type default)
			)
			(layer "B.Fab")
		)
		(fp_line
			(start -0.67945 0.3048)
			(end -0.120396 0.3048)
			(stroke
				(width 0.1)
				(type default)
			)
			(layer "B.Fab")
		)
		(fp_line
			(start -0.67945 -0.3048)
			(end -0.67945 0.3048)
			(stroke
				(width 0.1)
				(type default)
			)
			(layer "B.Fab")
		)
		(pad "1" smd circle
			(at 0.40005 0)
			(size 0 0)
			(layers "B.Cu" "B.Mask" "B.Paste")
			(net "GPU_FPGA_EROT_RST_N")
		)
		(pad "2" smd circle
			(at -0.40005 0)
			(size 0 0)
			(layers "B.Cu" "B.Mask" "B.Paste")
			(net "GPU_FPGA_EROT_RST_R_N")
		)
	)
	(footprint ""
		(layer "B.Cu")
		(at 320.170556 -56.612028 90)
		(property "Reference" "R1260"
			(at 0 0 90)
			(layer "B.SilkS")
			(hide yes)
			(effects
				(font
					(size 1.27 1.27)
				)
				(justify mirror)
			)
		)
		(property "Value" ""
			(at 0 0 90)
			(layer "B.Fab")
			(effects
				(font
					(size 1.27 1.27)
				)
				(justify mirror)
			)
		)
		(duplicate_pad_numbers_are_jumpers no)
		(fp_line
			(start 0.7874 -0.4064)
			(end -0.7874 -0.4064)
			(stroke
				(width 0.1524)
				(type default)
			)
			(layer "B.SilkS")
		)
		(fp_line
			(start -0.7874 -0.4064)
			(end -0.7874 0.4064)
			(stroke
				(width 0.1524)
				(type default)
			)
			(layer "B.SilkS")
		)
		(fp_line
			(start 0.7874 0.4064)
			(end 0.7874 -0.4064)
			(stroke
				(width 0.1524)
				(type default)
			)
			(layer "B.SilkS")
		)
		(fp_line
			(start -0.7874 0.4064)
			(end 0.7874 0.4064)
			(stroke
				(width 0.1524)
				(type default)
			)
			(layer "B.SilkS")
		)
		(fp_line
			(start 0.67945 -0.305054)
			(end 0.12065 -0.305054)
			(stroke
				(width 0.1)
				(type default)
			)
			(layer "B.Fab")
		)
		(fp_line
			(start 0.12065 -0.305054)
			(end 0.12065 -0.2794)
			(stroke
				(width 0.1)
				(type default)
			)
			(layer "B.Fab")
		)
		(fp_line
			(start -0.12065 -0.3048)
			(end -0.67945 -0.3048)
			(stroke
				(width 0.1)
				(type default)
			)
			(layer "B.Fab")
		)
		(fp_line
			(start -0.67945 -0.3048)
			(end -0.67945 0.3048)
			(stroke
				(width 0.1)
				(type default)
			)
			(layer "B.Fab")
		)
		(fp_line
			(start 0.12065 -0.2794)
			(end -0.12065 -0.2794)
			(stroke
				(width 0.1)
				(type default)
			)
			(layer "B.Fab")
		)
		(fp_line
			(start -0.12065 -0.2794)
			(end -0.12065 -0.3048)
			(stroke
				(width 0.1)
				(type default)
			)
			(layer "B.Fab")
		)
		(fp_line
			(start 0.12065 0.2794)
			(end 0.12065 0.3048)
			(stroke
				(width 0.1)
				(type default)
			)
			(layer "B.Fab")
		)
		(fp_line
			(start -0.120396 0.2794)
			(end 0.12065 0.2794)
			(stroke
				(width 0.1)
				(type default)
			)
			(layer "B.Fab")
		)
		(fp_line
			(start 0.67945 0.3048)
			(end 0.67945 -0.305054)
			(stroke
				(width 0.1)
				(type default)
			)
			(layer "B.Fab")
		)
		(fp_line
			(start 0.12065 0.3048)
			(end 0.67945 0.3048)
			(stroke
				(width 0.1)
				(type default)
			)
			(layer "B.Fab")
		)
		(fp_line
			(start -0.120396 0.3048)
			(end -0.120396 0.2794)
			(stroke
				(width 0.1)
				(type default)
			)
			(layer "B.Fab")
		)
		(fp_line
			(start -0.67945 0.3048)
			(end -0.120396 0.3048)
			(stroke
				(width 0.1)
				(type default)
			)
			(layer "B.Fab")
		)
		(pad "1" smd circle
			(at 0.40005 0 270)
			(size 0 0)
			(layers "B.Cu" "B.Mask" "B.Paste")
			(net "P1V05_PCH_AUX")
		)
		(pad "2" smd circle
			(at -0.40005 0 270)
			(size 0 0)
			(layers "B.Cu" "B.Mask" "B.Paste")
			(net "H_CPU_ERR0_PCH_R_N")
		)
	)
	(footprint ""
		(layer "B.Cu")
		(at 179.454048 -405.288242 180)
		(property "Reference" "PR2106"
			(at 0 0 0)
			(layer "B.SilkS")
			(hide yes)
			(effects
				(font
					(size 1.27 1.27)
				)
				(justify mirror)
			)
		)
		(property "Value" ""
			(at 0 0 0)
			(layer "B.Fab")
			(effects
				(font
					(size 1.27 1.27)
				)
				(justify mirror)
			)
		)
		(duplicate_pad_numbers_are_jumpers no)
		(fp_line
			(start 0.7874 0.4064)
			(end 0.7874 -0.4064)
			(stroke
				(width 0.1524)
				(type default)
			)
			(layer "B.SilkS")
		)
		(fp_line
			(start 0.7874 -0.4064)
			(end -0.7874 -0.4064)
			(stroke
				(width 0.1524)
				(type default)
			)
			(layer "B.SilkS")
		)
		(fp_line
			(start -0.7874 0.4064)
			(end 0.7874 0.4064)
			(stroke
				(width 0.1524)
				(type default)
			)
			(layer "B.SilkS")
		)
		(fp_line
			(start -0.7874 -0.4064)
			(end -0.7874 0.4064)
			(stroke
				(width 0.1524)
				(type default)
			)
			(layer "B.SilkS")
		)
		(fp_line
			(start 0.67945 0.3048)
			(end 0.67945 -0.305054)
			(stroke
				(width 0.1)
				(type default)
			)
			(layer "B.Fab")
		)
		(fp_line
			(start 0.67945 -0.305054)
			(end 0.12065 -0.305054)
			(stroke
				(width 0.1)
				(type default)
			)
			(layer "B.Fab")
		)
		(fp_line
			(start 0.12065 0.3048)
			(end 0.67945 0.3048)
			(stroke
				(width 0.1)
				(type default)
			)
			(layer "B.Fab")
		)
		(fp_line
			(start 0.12065 0.2794)
			(end 0.12065 0.3048)
			(stroke
				(width 0.1)
				(type default)
			)
			(layer "B.Fab")
		)
		(fp_line
			(start 0.12065 -0.2794)
			(end -0.12065 -0.2794)
			(stroke
				(width 0.1)
				(type default)
			)
			(layer "B.Fab")
		)
		(fp_line
			(start 0.12065 -0.305054)
			(end 0.12065 -0.2794)
			(stroke
				(width 0.1)
				(type default)
			)
			(layer "B.Fab")
		)
		(fp_line
			(start -0.120396 0.3048)
			(end -0.120396 0.2794)
			(stroke
				(width 0.1)
				(type default)
			)
			(layer "B.Fab")
		)
		(fp_line
			(start -0.120396 0.2794)
			(end 0.12065 0.2794)
			(stroke
				(width 0.1)
				(type default)
			)
			(layer "B.Fab")
		)
		(fp_line
			(start -0.12065 -0.2794)
			(end -0.12065 -0.3048)
			(stroke
				(width 0.1)
				(type default)
			)
			(layer "B.Fab")
		)
		(fp_line
			(start -0.12065 -0.3048)
			(end -0.67945 -0.3048)
			(stroke
				(width 0.1)
				(type default)
			)
			(layer "B.Fab")
		)
		(fp_line
			(start -0.67945 0.3048)
			(end -0.120396 0.3048)
			(stroke
				(width 0.1)
				(type default)
			)
			(layer "B.Fab")
		)
		(fp_line
			(start -0.67945 -0.3048)
			(end -0.67945 0.3048)
			(stroke
				(width 0.1)
				(type default)
			)
			(layer "B.Fab")
		)
		(pad "1" smd circle
			(at 0.40005 0)
			(size 0 0)
			(layers "B.Cu" "B.Mask" "B.Paste")
			(net "HSC_VDD")
		)
		(pad "2" smd circle
			(at -0.40005 0)
			(size 0 0)
			(layers "B.Cu" "B.Mask" "B.Paste")
			(net "HSC_VIN_UVW_N")
		)
	)
	(footprint ""
		(layer "B.Cu")
		(at 47.689516 -319.009522)
		(property "Reference" "R45"
			(at 0 0 0)
			(layer "B.SilkS")
			(hide yes)
			(effects
				(font
					(size 1.27 1.27)
				)
				(justify mirror)
			)
		)
		(property "Value" ""
			(at 0 0 0)
			(layer "B.Fab")
			(effects
				(font
					(size 1.27 1.27)
				)
				(justify mirror)
			)
		)
		(duplicate_pad_numbers_are_jumpers no)
		(fp_line
			(start -0.7874 -0.4064)
			(end -0.7874 0.4064)
			(stroke
				(width 0.1524)
				(type default)
			)
			(layer "B.SilkS")
		)
		(fp_line
			(start -0.7874 0.4064)
			(end 0.7874 0.4064)
			(stroke
				(width 0.1524)
				(type default)
			)
			(layer "B.SilkS")
		)
		(fp_line
			(start 0.7874 -0.4064)
			(end -0.7874 -0.4064)
			(stroke
				(width 0.1524)
				(type default)
			)
			(layer "B.SilkS")
		)
		(fp_line
			(start 0.7874 0.4064)
			(end 0.7874 -0.4064)
			(stroke
				(width 0.1524)
				(type default)
			)
			(layer "B.SilkS")
		)
		(fp_line
			(start -0.67945 -0.3048)
			(end -0.67945 0.3048)
			(stroke
				(width 0.1)
				(type default)
			)
			(layer "B.Fab")
		)
		(fp_line
			(start -0.67945 0.3048)
			(end -0.120396 0.3048)
			(stroke
				(width 0.1)
				(type default)
			)
			(layer "B.Fab")
		)
		(fp_line
			(start -0.12065 -0.3048)
			(end -0.67945 -0.3048)
			(stroke
				(width 0.1)
				(type default)
			)
			(layer "B.Fab")
		)
		(fp_line
			(start -0.12065 -0.2794)
			(end -0.12065 -0.3048)
			(stroke
				(width 0.1)
				(type default)
			)
			(layer "B.Fab")
		)
		(fp_line
			(start -0.120396 0.2794)
			(end 0.12065 0.2794)
			(stroke
				(width 0.1)
				(type default)
			)
			(layer "B.Fab")
		)
		(fp_line
			(start -0.120396 0.3048)
			(end -0.120396 0.2794)
			(stroke
				(width 0.1)
				(type default)
			)
			(layer "B.Fab")
		)
		(fp_line
			(start 0.12065 -0.305054)
			(end 0.12065 -0.2794)
			(stroke
				(width 0.1)
				(type default)
			)
			(layer "B.Fab")
		)
		(fp_line
			(start 0.12065 -0.2794)
			(end -0.12065 -0.2794)
			(stroke
				(width 0.1)
				(type default)
			)
			(layer "B.Fab")
		)
		(fp_line
			(start 0.12065 0.2794)
			(end 0.12065 0.3048)
			(stroke
				(width 0.1)
				(type default)
			)
			(layer "B.Fab")
		)
		(fp_line
			(start 0.12065 0.3048)
			(end 0.67945 0.3048)
			(stroke
				(width 0.1)
				(type default)
			)
			(layer "B.Fab")
		)
		(fp_line
			(start 0.67945 -0.305054)
			(end 0.12065 -0.305054)
			(stroke
				(width 0.1)
				(type default)
			)
			(layer "B.Fab")
		)
		(fp_line
			(start 0.67945 0.3048)
			(end 0.67945 -0.305054)
			(stroke
				(width 0.1)
				(type default)
			)
			(layer "B.Fab")
		)
		(pad "1" smd circle
			(at 0.40005 0 180)
			(size 0 0)
			(layers "B.Cu" "B.Mask" "B.Paste")
			(net "PD_CHB_CPU1_DIMM2_SAA")
		)
		(pad "2" smd circle
			(at -0.40005 0 180)
			(size 0 0)
			(layers "B.Cu" "B.Mask" "B.Paste")
			(net "GND")
		)
	)
	(footprint ""
		(layer "B.Cu")
		(at 123.57862 -28.265628)
		(property "Reference" "C2291"
			(at 0 0 0)
			(layer "B.SilkS")
			(hide yes)
			(effects
				(font
					(size 1.27 1.27)
				)
				(justify mirror)
			)
		)
		(property "Value" ""
			(at 0 0 0)
			(layer "B.Fab")
			(effects
				(font
					(size 1.27 1.27)
				)
				(justify mirror)
			)
		)
		(duplicate_pad_numbers_are_jumpers no)
		(fp_line
			(start -0.299974 -0.150114)
			(end -0.299974 0.150114)
			(stroke
				(width 0.1)
				(type default)
			)
			(layer "B.Fab")
		)
		(fp_line
			(start -0.299974 0.150114)
			(end 0.299974 0.150114)
			(stroke
				(width 0.1)
				(type default)
			)
			(layer "B.Fab")
		)
		(fp_line
			(start 0.299974 -0.150114)
			(end -0.299974 -0.150114)
			(stroke
				(width 0.1)
				(type default)
			)
			(layer "B.Fab")
		)
		(fp_line
			(start 0.299974 0.150114)
			(end 0.299974 -0.150114)
			(stroke
				(width 0.1)
				(type default)
			)
			(layer "B.Fab")
		)
		(pad "1" smd rect
			(at 0.2667 0 180)
			(size 0.3048 0.381)
			(layers "B.Cu" "B.Mask" "B.Paste")
			(net "USB3_PCH_RX_BUF_C_DP<4>")
		)
		(pad "2" smd rect
			(at -0.2667 0 180)
			(size 0.3048 0.381)
			(layers "B.Cu" "B.Mask" "B.Paste")
			(net "USB3_PCH_RX_BUF_DP<4>")
		)
	)
	(footprint ""
		(layer "B.Cu")
		(at 385.1402 -79.428848)
		(property "Reference" "PR1850"
			(at 0 0 0)
			(layer "B.SilkS")
			(hide yes)
			(effects
				(font
					(size 1.27 1.27)
				)
				(justify mirror)
			)
		)
		(property "Value" ""
			(at 0 0 0)
			(layer "B.Fab")
			(effects
				(font
					(size 1.27 1.27)
				)
				(justify mirror)
			)
		)
		(duplicate_pad_numbers_are_jumpers no)
		(fp_line
			(start -0.7874 -0.4064)
			(end -0.7874 0.4064)
			(stroke
				(width 0.1524)
				(type default)
			)
			(layer "B.SilkS")
		)
		(fp_line
			(start -0.7874 0.4064)
			(end 0.7874 0.4064)
			(stroke
				(width 0.1524)
				(type default)
			)
			(layer "B.SilkS")
		)
		(fp_line
			(start 0.7874 -0.4064)
			(end -0.7874 -0.4064)
			(stroke
				(width 0.1524)
				(type default)
			)
			(layer "B.SilkS")
		)
		(fp_line
			(start 0.7874 0.4064)
			(end 0.7874 -0.4064)
			(stroke
				(width 0.1524)
				(type default)
			)
			(layer "B.SilkS")
		)
		(fp_line
			(start -0.67945 -0.3048)
			(end -0.67945 0.3048)
			(stroke
				(width 0.1)
				(type default)
			)
			(layer "B.Fab")
		)
		(fp_line
			(start -0.67945 0.3048)
			(end -0.120396 0.3048)
			(stroke
				(width 0.1)
				(type default)
			)
			(layer "B.Fab")
		)
		(fp_line
			(start -0.12065 -0.3048)
			(end -0.67945 -0.3048)
			(stroke
				(width 0.1)
				(type default)
			)
			(layer "B.Fab")
		)
		(fp_line
			(start -0.12065 -0.2794)
			(end -0.12065 -0.3048)
			(stroke
				(width 0.1)
				(type default)
			)
			(layer "B.Fab")
		)
		(fp_line
			(start -0.120396 0.2794)
			(end 0.12065 0.2794)
			(stroke
				(width 0.1)
				(type default)
			)
			(layer "B.Fab")
		)
		(fp_line
			(start -0.120396 0.3048)
			(end -0.120396 0.2794)
			(stroke
				(width 0.1)
				(type default)
			)
			(layer "B.Fab")
		)
		(fp_line
			(start 0.12065 -0.305054)
			(end 0.12065 -0.2794)
			(stroke
				(width 0.1)
				(type default)
			)
			(layer "B.Fab")
		)
		(fp_line
			(start 0.12065 -0.2794)
			(end -0.12065 -0.2794)
			(stroke
				(width 0.1)
				(type default)
			)
			(layer "B.Fab")
		)
		(fp_line
			(start 0.12065 0.2794)
			(end 0.12065 0.3048)
			(stroke
				(width 0.1)
				(type default)
			)
			(layer "B.Fab")
		)
		(fp_line
			(start 0.12065 0.3048)
			(end 0.67945 0.3048)
			(stroke
				(width 0.1)
				(type default)
			)
			(layer "B.Fab")
		)
		(fp_line
			(start 0.67945 -0.305054)
			(end 0.12065 -0.305054)
			(stroke
				(width 0.1)
				(type default)
			)
			(layer "B.Fab")
		)
		(fp_line
			(start 0.67945 0.3048)
			(end 0.67945 -0.305054)
			(stroke
				(width 0.1)
				(type default)
			)
			(layer "B.Fab")
		)
		(pad "1" smd circle
			(at 0.40005 0 180)
			(size 0 0)
			(layers "B.Cu" "B.Mask" "B.Paste")
			(net "GND")
		)
		(pad "2" smd circle
			(at -0.40005 0 180)
			(size 0 0)
			(layers "B.Cu" "B.Mask" "B.Paste")
			(net "FM_PCH_P1V8_AUX_EN_R")
		)
	)
	(footprint ""
		(layer "B.Cu")
		(at 216.212674 -76.591668 180)
		(property "Reference" "R3211"
			(at 0 0 0)
			(layer "B.SilkS")
			(hide yes)
			(effects
				(font
					(size 1.27 1.27)
				)
				(justify mirror)
			)
		)
		(property "Value" ""
			(at 0 0 0)
			(layer "B.Fab")
			(effects
				(font
					(size 1.27 1.27)
				)
				(justify mirror)
			)
		)
		(duplicate_pad_numbers_are_jumpers no)
		(fp_line
			(start 0.7874 0.4064)
			(end 0.7874 -0.4064)
			(stroke
				(width 0.1524)
				(type default)
			)
			(layer "B.SilkS")
		)
		(fp_line
			(start 0.7874 -0.4064)
			(end -0.7874 -0.4064)
			(stroke
				(width 0.1524)
				(type default)
			)
			(layer "B.SilkS")
		)
		(fp_line
			(start -0.7874 0.4064)
			(end 0.7874 0.4064)
			(stroke
				(width 0.1524)
				(type default)
			)
			(layer "B.SilkS")
		)
		(fp_line
			(start -0.7874 -0.4064)
			(end -0.7874 0.4064)
			(stroke
				(width 0.1524)
				(type default)
			)
			(layer "B.SilkS")
		)
		(fp_line
			(start 0.67945 0.3048)
			(end 0.67945 -0.305054)
			(stroke
				(width 0.1)
				(type default)
			)
			(layer "B.Fab")
		)
		(fp_line
			(start 0.67945 -0.305054)
			(end 0.12065 -0.305054)
			(stroke
				(width 0.1)
				(type default)
			)
			(layer "B.Fab")
		)
		(fp_line
			(start 0.12065 0.3048)
			(end 0.67945 0.3048)
			(stroke
				(width 0.1)
				(type default)
			)
			(layer "B.Fab")
		)
		(fp_line
			(start 0.12065 0.2794)
			(end 0.12065 0.3048)
			(stroke
				(width 0.1)
				(type default)
			)
			(layer "B.Fab")
		)
		(fp_line
			(start 0.12065 -0.2794)
			(end -0.12065 -0.2794)
			(stroke
				(width 0.1)
				(type default)
			)
			(layer "B.Fab")
		)
		(fp_line
			(start 0.12065 -0.305054)
			(end 0.12065 -0.2794)
			(stroke
				(width 0.1)
				(type default)
			)
			(layer "B.Fab")
		)
		(fp_line
			(start -0.120396 0.3048)
			(end -0.120396 0.2794)
			(stroke
				(width 0.1)
				(type default)
			)
			(layer "B.Fab")
		)
		(fp_line
			(start -0.120396 0.2794)
			(end 0.12065 0.2794)
			(stroke
				(width 0.1)
				(type default)
			)
			(layer "B.Fab")
		)
		(fp_line
			(start -0.12065 -0.2794)
			(end -0.12065 -0.3048)
			(stroke
				(width 0.1)
				(type default)
			)
			(layer "B.Fab")
		)
		(fp_line
			(start -0.12065 -0.3048)
			(end -0.67945 -0.3048)
			(stroke
				(width 0.1)
				(type default)
			)
			(layer "B.Fab")
		)
		(fp_line
			(start -0.67945 0.3048)
			(end -0.120396 0.3048)
			(stroke
				(width 0.1)
				(type default)
			)
			(layer "B.Fab")
		)
		(fp_line
			(start -0.67945 -0.3048)
			(end -0.67945 0.3048)
			(stroke
				(width 0.1)
				(type default)
			)
			(layer "B.Fab")
		)
		(pad "1" smd circle
			(at 0.40005 0)
			(size 0 0)
			(layers "B.Cu" "B.Mask" "B.Paste")
			(net "NCSI_BMC_RXD0_R1")
		)
		(pad "2" smd circle
			(at -0.40005 0)
			(size 0 0)
			(layers "B.Cu" "B.Mask" "B.Paste")
			(net "RMII_OCP_BMC_RXD_0")
		)
	)
	(footprint ""
		(layer "B.Cu")
		(at 320.645282 -26.71064 90)
		(property "Reference" "R622"
			(at 0 0 90)
			(layer "B.SilkS")
			(hide yes)
			(effects
				(font
					(size 1.27 1.27)
				)
				(justify mirror)
			)
		)
		(property "Value" ""
			(at 0 0 90)
			(layer "B.Fab")
			(effects
				(font
					(size 1.27 1.27)
				)
				(justify mirror)
			)
		)
		(duplicate_pad_numbers_are_jumpers no)
		(fp_line
			(start 0.7874 -0.4064)
			(end -0.7874 -0.4064)
			(stroke
				(width 0.1524)
				(type default)
			)
			(layer "B.SilkS")
		)
		(fp_line
			(start -0.7874 -0.4064)
			(end -0.7874 0.4064)
			(stroke
				(width 0.1524)
				(type default)
			)
			(layer "B.SilkS")
		)
		(fp_line
			(start 0.7874 0.4064)
			(end 0.7874 -0.4064)
			(stroke
				(width 0.1524)
				(type default)
			)
			(layer "B.SilkS")
		)
		(fp_line
			(start -0.7874 0.4064)
			(end 0.7874 0.4064)
			(stroke
				(width 0.1524)
				(type default)
			)
			(layer "B.SilkS")
		)
		(fp_line
			(start 0.67945 -0.305054)
			(end 0.12065 -0.305054)
			(stroke
				(width 0.1)
				(type default)
			)
			(layer "B.Fab")
		)
		(fp_line
			(start 0.12065 -0.305054)
			(end 0.12065 -0.2794)
			(stroke
				(width 0.1)
				(type default)
			)
			(layer "B.Fab")
		)
		(fp_line
			(start -0.12065 -0.3048)
			(end -0.67945 -0.3048)
			(stroke
				(width 0.1)
				(type default)
			)
			(layer "B.Fab")
		)
		(fp_line
			(start -0.67945 -0.3048)
			(end -0.67945 0.3048)
			(stroke
				(width 0.1)
				(type default)
			)
			(layer "B.Fab")
		)
		(fp_line
			(start 0.12065 -0.2794)
			(end -0.12065 -0.2794)
			(stroke
				(width 0.1)
				(type default)
			)
			(layer "B.Fab")
		)
		(fp_line
			(start -0.12065 -0.2794)
			(end -0.12065 -0.3048)
			(stroke
				(width 0.1)
				(type default)
			)
			(layer "B.Fab")
		)
		(fp_line
			(start 0.12065 0.2794)
			(end 0.12065 0.3048)
			(stroke
				(width 0.1)
				(type default)
			)
			(layer "B.Fab")
		)
		(fp_line
			(start -0.120396 0.2794)
			(end 0.12065 0.2794)
			(stroke
				(width 0.1)
				(type default)
			)
			(layer "B.Fab")
		)
		(fp_line
			(start 0.67945 0.3048)
			(end 0.67945 -0.305054)
			(stroke
				(width 0.1)
				(type default)
			)
			(layer "B.Fab")
		)
		(fp_line
			(start 0.12065 0.3048)
			(end 0.67945 0.3048)
			(stroke
				(width 0.1)
				(type default)
			)
			(layer "B.Fab")
		)
		(fp_line
			(start -0.120396 0.3048)
			(end -0.120396 0.2794)
			(stroke
				(width 0.1)
				(type default)
			)
			(layer "B.Fab")
		)
		(fp_line
			(start -0.67945 0.3048)
			(end -0.120396 0.3048)
			(stroke
				(width 0.1)
				(type default)
			)
			(layer "B.Fab")
		)
		(pad "1" smd circle
			(at 0.40005 0 270)
			(size 0 0)
			(layers "B.Cu" "B.Mask" "B.Paste")
			(net "FM_PCH_SKIP_RTC_CLOCK")
		)
		(pad "2" smd circle
			(at -0.40005 0 270)
			(size 0 0)
			(layers "B.Cu" "B.Mask" "B.Paste")
			(net "GND")
		)
	)
	(footprint ""
		(layer "B.Cu")
		(at 159.278574 -38.495986)
		(property "Reference" "C2315"
			(at 0 0 0)
			(layer "B.SilkS")
			(hide yes)
			(effects
				(font
					(size 1.27 1.27)
				)
				(justify mirror)
			)
		)
		(property "Value" ""
			(at 0 0 0)
			(layer "B.Fab")
			(effects
				(font
					(size 1.27 1.27)
				)
				(justify mirror)
			)
		)
		(duplicate_pad_numbers_are_jumpers no)
		(fp_line
			(start -0.7874 -0.4064)
			(end -0.7874 0.4064)
			(stroke
				(width 0.1524)
				(type default)
			)
			(layer "B.SilkS")
		)
		(fp_line
			(start -0.7874 0.4064)
			(end 0.7874 0.4064)
			(stroke
				(width 0.1524)
				(type default)
			)
			(layer "B.SilkS")
		)
		(fp_line
			(start 0.7874 -0.4064)
			(end -0.7874 -0.4064)
			(stroke
				(width 0.1524)
				(type default)
			)
			(layer "B.SilkS")
		)
		(fp_line
			(start 0.7874 0.4064)
			(end 0.7874 -0.4064)
			(stroke
				(width 0.1524)
				(type default)
			)
			(layer "B.SilkS")
		)
		(fp_line
			(start -0.67945 -0.3048)
			(end -0.67945 0.3048)
			(stroke
				(width 0.1)
				(type default)
			)
			(layer "B.Fab")
		)
		(fp_line
			(start -0.67945 0.3048)
			(end -0.120396 0.3048)
			(stroke
				(width 0.1)
				(type default)
			)
			(layer "B.Fab")
		)
		(fp_line
			(start -0.12065 -0.3048)
			(end -0.67945 -0.3048)
			(stroke
				(width 0.1)
				(type default)
			)
			(layer "B.Fab")
		)
		(fp_line
			(start -0.12065 -0.2794)
			(end -0.12065 -0.3048)
			(stroke
				(width 0.1)
				(type default)
			)
			(layer "B.Fab")
		)
		(fp_line
			(start -0.120396 0.2794)
			(end 0.12065 0.2794)
			(stroke
				(width 0.1)
				(type default)
			)
			(layer "B.Fab")
		)
		(fp_line
			(start -0.120396 0.3048)
			(end -0.120396 0.2794)
			(stroke
				(width 0.1)
				(type default)
			)
			(layer "B.Fab")
		)
		(fp_line
			(start 0.12065 -0.305054)
			(end 0.12065 -0.2794)
			(stroke
				(width 0.1)
				(type default)
			)
			(layer "B.Fab")
		)
		(fp_line
			(start 0.12065 -0.2794)
			(end -0.12065 -0.2794)
			(stroke
				(width 0.1)
				(type default)
			)
			(layer "B.Fab")
		)
		(fp_line
			(start 0.12065 0.2794)
			(end 0.12065 0.3048)
			(stroke
				(width 0.1)
				(type default)
			)
			(layer "B.Fab")
		)
		(fp_line
			(start 0.12065 0.3048)
			(end 0.67945 0.3048)
			(stroke
				(width 0.1)
				(type default)
			)
			(layer "B.Fab")
		)
		(fp_line
			(start 0.67945 -0.305054)
			(end 0.12065 -0.305054)
			(stroke
				(width 0.1)
				(type default)
			)
			(layer "B.Fab")
		)
		(fp_line
			(start 0.67945 0.3048)
			(end 0.67945 -0.305054)
			(stroke
				(width 0.1)
				(type default)
			)
			(layer "B.Fab")
		)
		(pad "1" smd circle
			(at 0.40005 0 180)
			(size 0 0)
			(layers "B.Cu" "B.Mask" "B.Paste")
			(net "P3V3_AUX_USB_HUB_2")
		)
		(pad "2" smd circle
			(at -0.40005 0 180)
			(size 0 0)
			(layers "B.Cu" "B.Mask" "B.Paste")
			(net "GND")
		)
	)
	(footprint ""
		(layer "B.Cu")
		(at 482.66985 2.372868 90)
		(property "Reference" "X24"
			(at 1.354328 3.30454 270)
			(unlocked yes)
			(layer "B.SilkS")
			(effects
				(font
					(size 0.7874 0.5842)
					(thickness 0.1524)
				)
				(justify left mirror)
			)
		)
		(property "Value" ""
			(at 0 0 90)
			(layer "B.Fab")
			(effects
				(font
					(size 1.27 1.27)
				)
				(justify mirror)
			)
		)
		(property "Device Type" "TP_TDR_4P_FTS_MPKT4_H025P0200_I"
			(at -1.30175 1.27 0)
			(unlocked yes)
			(layer "B.Fab")
			(hide yes)
			(effects
				(font
					(size 0.635 0.4064)
					(thickness 0.1524)
				)
				(justify mirror)
			)
		)
		(property "User Part Number" "TP15"
			(at -1.30175 1.27 0)
			(unlocked yes)
			(layer "Cmts.User")
			(hide yes)
			(effects
				(font
					(size 0.635 0.4064)
					(thickness 0.1524)
				)
				(justify mirror)
			)
		)
		(duplicate_pad_numbers_are_jumpers no)
		(fp_line
			(start 0 -1.27)
			(end 0 -0.635)
			(stroke
				(width 0.1524)
				(type default)
			)
			(layer "B.SilkS")
		)
		(fp_line
			(start -2.54 -1.27)
			(end 0 -1.27)
			(stroke
				(width 0.1524)
				(type default)
			)
			(layer "B.SilkS")
		)
		(fp_line
			(start -2.54 -1.1303)
			(end -2.54 -1.27)
			(stroke
				(width 0.1524)
				(type default)
			)
			(layer "B.SilkS")
		)
		(fp_line
			(start 0 0.635)
			(end 0 1.905)
			(stroke
				(width 0.1524)
				(type default)
			)
			(layer "B.SilkS")
		)
		(fp_line
			(start -2.54 1.4097)
			(end -2.54 1.1303)
			(stroke
				(width 0.1524)
				(type default)
			)
			(layer "B.SilkS")
		)
		(fp_line
			(start 0 3.175)
			(end 0 3.81)
			(stroke
				(width 0.1524)
				(type default)
			)
			(layer "B.SilkS")
		)
		(fp_line
			(start 0 3.81)
			(end -2.54 3.81)
			(stroke
				(width 0.1524)
				(type default)
			)
			(layer "B.SilkS")
		)
		(fp_line
			(start -2.54 3.81)
			(end -2.54 3.6703)
			(stroke
				(width 0.1524)
				(type default)
			)
			(layer "B.SilkS")
		)
		(fp_poly
			(pts
				(xy 2.285746 -0.762) (xy 2.285746 0.762) (xy 0.761746 0)
			)
			(stroke
				(width 0)
				(type default)
			)
			(fill yes)
			(layer "B.SilkS")
		)
		(fp_line
			(start 0 -1.27)
			(end 0 3.81)
			(stroke
				(width 0.1)
				(type default)
			)
			(layer "B.Fab")
		)
		(fp_line
			(start -2.54 -1.27)
			(end 0 -1.27)
			(stroke
				(width 0.1)
				(type default)
			)
			(layer "B.Fab")
		)
		(fp_line
			(start 0 3.81)
			(end -2.54 3.81)
			(stroke
				(width 0.1)
				(type default)
			)
			(layer "B.Fab")
		)
		(fp_line
			(start -2.54 3.81)
			(end -2.54 -1.27)
			(stroke
				(width 0.1)
				(type default)
			)
			(layer "B.Fab")
		)
		(fp_poly
			(pts
				(xy 0.761746 0) (xy 2.285746 -0.762) (xy 2.285746 0.762)
			)
			(stroke
				(width 0)
				(type default)
			)
			(fill yes)
			(layer "B.Fab")
		)
		(pad "1" thru_hole circle
			(at 0 0 270)
			(size 1.0033 1.0033)
			(drill 0.249936)
			(layers "*.Cu" "*.Mask")
			(remove_unused_layers no)
			(net "TDR_DIFF_100_BOT_DN")
			(clearance 0.10795)
			(padstack
				(mode front_inner_back)
				(layer "Inner"
					(shape circle)
					(size 0.8001 0.8001)
					(clearance 0.1524)
				)
				(layer "B.Cu"
					(shape circle)
					(size 1.0033 1.0033)
					(thermal_gap 0.10795)
					(clearance 0.10795)
				)
			)
		)
		(pad "2" thru_hole circle
			(at -2.54 0 270)
			(size 1.9939 1.9939)
			(drill 0.249936)
			(layers "*.Cu" "*.Mask")
			(remove_unused_layers no)
			(net "T1_GND")
			(clearance 0.10795)
			(padstack
				(mode front_inner_back)
				(layer "Inner"
					(shape circle)
					(size 0.8001 0.8001)
					(clearance 0.1524)
				)
				(layer "B.Cu"
					(shape circle)
					(size 1.9939 1.9939)
					(thermal_gap 0.10795)
					(clearance 0.10795)
				)
			)
		)
		(pad "3" thru_hole circle
			(at -2.54 2.54 270)
			(size 1.9939 1.9939)
			(drill 0.249936)
			(layers "*.Cu" "*.Mask")
			(remove_unused_layers no)
			(net "T1_GND")
			(clearance 0.10795)
			(padstack
				(mode front_inner_back)
				(layer "Inner"
					(shape circle)
					(size 0.8001 0.8001)
					(clearance 0.1524)
				)
				(layer "B.Cu"
					(shape circle)
					(size 1.9939 1.9939)
					(thermal_gap 0.10795)
					(clearance 0.10795)
				)
			)
		)
		(pad "4" thru_hole circle
			(at 0 2.54 270)
			(size 1.0033 1.0033)
			(drill 0.249936)
			(layers "*.Cu" "*.Mask")
			(remove_unused_layers no)
			(net "TDR_DIFF_100_BOT_DP")
			(clearance 0.10795)
			(padstack
				(mode front_inner_back)
				(layer "Inner"
					(shape circle)
					(size 0.8001 0.8001)
					(clearance 0.1524)
				)
				(layer "B.Cu"
					(shape circle)
					(size 1.0033 1.0033)
					(thermal_gap 0.10795)
					(clearance 0.10795)
				)
			)
		)
	)
	(footprint ""
		(layer "B.Cu")
		(at 169.66692 -51.399948 180)
		(property "Reference" "C1925"
			(at 0 0 0)
			(layer "B.SilkS")
			(hide yes)
			(effects
				(font
					(size 1.27 1.27)
				)
				(justify mirror)
			)
		)
		(property "Value" ""
			(at 0 0 0)
			(layer "B.Fab")
			(effects
				(font
					(size 1.27 1.27)
				)
				(justify mirror)
			)
		)
		(duplicate_pad_numbers_are_jumpers no)
		(fp_line
			(start 0.7874 0.4064)
			(end 0.7874 -0.4064)
			(stroke
				(width 0.1524)
				(type default)
			)
			(layer "B.SilkS")
		)
		(fp_line
			(start 0.7874 -0.4064)
			(end -0.7874 -0.4064)
			(stroke
				(width 0.1524)
				(type default)
			)
			(layer "B.SilkS")
		)
		(fp_line
			(start -0.7874 0.4064)
			(end 0.7874 0.4064)
			(stroke
				(width 0.1524)
				(type default)
			)
			(layer "B.SilkS")
		)
		(fp_line
			(start -0.7874 -0.4064)
			(end -0.7874 0.4064)
			(stroke
				(width 0.1524)
				(type default)
			)
			(layer "B.SilkS")
		)
		(fp_line
			(start 0.67945 0.3048)
			(end 0.67945 -0.305054)
			(stroke
				(width 0.1)
				(type default)
			)
			(layer "B.Fab")
		)
		(fp_line
			(start 0.67945 -0.305054)
			(end 0.12065 -0.305054)
			(stroke
				(width 0.1)
				(type default)
			)
			(layer "B.Fab")
		)
		(fp_line
			(start 0.12065 0.3048)
			(end 0.67945 0.3048)
			(stroke
				(width 0.1)
				(type default)
			)
			(layer "B.Fab")
		)
		(fp_line
			(start 0.12065 0.2794)
			(end 0.12065 0.3048)
			(stroke
				(width 0.1)
				(type default)
			)
			(layer "B.Fab")
		)
		(fp_line
			(start 0.12065 -0.2794)
			(end -0.12065 -0.2794)
			(stroke
				(width 0.1)
				(type default)
			)
			(layer "B.Fab")
		)
		(fp_line
			(start 0.12065 -0.305054)
			(end 0.12065 -0.2794)
			(stroke
				(width 0.1)
				(type default)
			)
			(layer "B.Fab")
		)
		(fp_line
			(start -0.120396 0.3048)
			(end -0.120396 0.2794)
			(stroke
				(width 0.1)
				(type default)
			)
			(layer "B.Fab")
		)
		(fp_line
			(start -0.120396 0.2794)
			(end 0.12065 0.2794)
			(stroke
				(width 0.1)
				(type default)
			)
			(layer "B.Fab")
		)
		(fp_line
			(start -0.12065 -0.2794)
			(end -0.12065 -0.3048)
			(stroke
				(width 0.1)
				(type default)
			)
			(layer "B.Fab")
		)
		(fp_line
			(start -0.12065 -0.3048)
			(end -0.67945 -0.3048)
			(stroke
				(width 0.1)
				(type default)
			)
			(layer "B.Fab")
		)
		(fp_line
			(start -0.67945 0.3048)
			(end -0.120396 0.3048)
			(stroke
				(width 0.1)
				(type default)
			)
			(layer "B.Fab")
		)
		(fp_line
			(start -0.67945 -0.3048)
			(end -0.67945 0.3048)
			(stroke
				(width 0.1)
				(type default)
			)
			(layer "B.Fab")
		)
		(pad "1" smd circle
			(at 0.40005 0)
			(size 0 0)
			(layers "B.Cu" "B.Mask" "B.Paste")
			(net "P3V3_M2_0")
		)
		(pad "2" smd circle
			(at -0.40005 0)
			(size 0 0)
			(layers "B.Cu" "B.Mask" "B.Paste")
			(net "GND")
		)
	)
	(footprint ""
		(layer "B.Cu")
		(at 405.129238 -193.04381 -90)
		(property "Reference" "R252"
			(at 0 0 90)
			(layer "B.SilkS")
			(hide yes)
			(effects
				(font
					(size 1.27 1.27)
				)
				(justify mirror)
			)
		)
		(property "Value" ""
			(at 0 0 90)
			(layer "B.Fab")
			(effects
				(font
					(size 1.27 1.27)
				)
				(justify mirror)
			)
		)
		(duplicate_pad_numbers_are_jumpers no)
		(fp_line
			(start -0.7874 0.4064)
			(end 0.7874 0.4064)
			(stroke
				(width 0.1524)
				(type default)
			)
			(layer "B.SilkS")
		)
		(fp_line
			(start 0.7874 0.4064)
			(end 0.7874 -0.4064)
			(stroke
				(width 0.1524)
				(type default)
			)
			(layer "B.SilkS")
		)
		(fp_line
			(start -0.7874 -0.4064)
			(end -0.7874 0.4064)
			(stroke
				(width 0.1524)
				(type default)
			)
			(layer "B.SilkS")
		)
		(fp_line
			(start 0.7874 -0.4064)
			(end -0.7874 -0.4064)
			(stroke
				(width 0.1524)
				(type default)
			)
			(layer "B.SilkS")
		)
		(fp_line
			(start -0.67945 0.3048)
			(end -0.120396 0.3048)
			(stroke
				(width 0.1)
				(type default)
			)
			(layer "B.Fab")
		)
		(fp_line
			(start -0.120396 0.3048)
			(end -0.120396 0.2794)
			(stroke
				(width 0.1)
				(type default)
			)
			(layer "B.Fab")
		)
		(fp_line
			(start 0.12065 0.3048)
			(end 0.67945 0.3048)
			(stroke
				(width 0.1)
				(type default)
			)
			(layer "B.Fab")
		)
		(fp_line
			(start 0.67945 0.3048)
			(end 0.67945 -0.305054)
			(stroke
				(width 0.1)
				(type default)
			)
			(layer "B.Fab")
		)
		(fp_line
			(start -0.120396 0.2794)
			(end 0.12065 0.2794)
			(stroke
				(width 0.1)
				(type default)
			)
			(layer "B.Fab")
		)
		(fp_line
			(start 0.12065 0.2794)
			(end 0.12065 0.3048)
			(stroke
				(width 0.1)
				(type default)
			)
			(layer "B.Fab")
		)
		(fp_line
			(start -0.12065 -0.2794)
			(end -0.12065 -0.3048)
			(stroke
				(width 0.1)
				(type default)
			)
			(layer "B.Fab")
		)
		(fp_line
			(start 0.12065 -0.2794)
			(end -0.12065 -0.2794)
			(stroke
				(width 0.1)
				(type default)
			)
			(layer "B.Fab")
		)
		(fp_line
			(start -0.67945 -0.3048)
			(end -0.67945 0.3048)
			(stroke
				(width 0.1)
				(type default)
			)
			(layer "B.Fab")
		)
		(fp_line
			(start -0.12065 -0.3048)
			(end -0.67945 -0.3048)
			(stroke
				(width 0.1)
				(type default)
			)
			(layer "B.Fab")
		)
		(fp_line
			(start 0.12065 -0.305054)
			(end 0.12065 -0.2794)
			(stroke
				(width 0.1)
				(type default)
			)
			(layer "B.Fab")
		)
		(fp_line
			(start 0.67945 -0.305054)
			(end 0.12065 -0.305054)
			(stroke
				(width 0.1)
				(type default)
			)
			(layer "B.Fab")
		)
		(pad "1" smd circle
			(at 0.40005 0 90)
			(size 0 0)
			(layers "B.Cu" "B.Mask" "B.Paste")
			(net "PVNN_TERM_CPU0")
		)
		(pad "2" smd circle
			(at -0.40005 0 90)
			(size 0 0)
			(layers "B.Cu" "B.Mask" "B.Paste")
			(net "PUD_PCH_BOOT_MODE_CPU0")
		)
	)
	(footprint ""
		(layer "B.Cu")
		(at 297.44416 -52.283868)
		(property "Reference" "C1182"
			(at 0 0 0)
			(layer "B.SilkS")
			(hide yes)
			(effects
				(font
					(size 1.27 1.27)
				)
				(justify mirror)
			)
		)
		(property "Value" ""
			(at 0 0 0)
			(layer "B.Fab")
			(effects
				(font
					(size 1.27 1.27)
				)
				(justify mirror)
			)
		)
		(duplicate_pad_numbers_are_jumpers no)
		(fp_line
			(start -1.2954 -0.5842)
			(end -1.2954 0.5842)
			(stroke
				(width 0.1524)
				(type default)
			)
			(layer "B.SilkS")
		)
		(fp_line
			(start -1.2954 0.5842)
			(end 1.2954 0.5842)
			(stroke
				(width 0.1524)
				(type default)
			)
			(layer "B.SilkS")
		)
		(fp_line
			(start 0 -0.5842)
			(end 0 0.5842)
			(stroke
				(width 0.1524)
				(type default)
			)
			(layer "B.SilkS")
		)
		(fp_line
			(start 1.2954 -0.5842)
			(end -1.2954 -0.5842)
			(stroke
				(width 0.1524)
				(type default)
			)
			(layer "B.SilkS")
		)
		(fp_line
			(start 1.2954 0.5842)
			(end 1.2954 -0.5842)
			(stroke
				(width 0.1524)
				(type default)
			)
			(layer "B.SilkS")
		)
		(fp_line
			(start -1.1938 -0.4064)
			(end -1.1938 0.4064)
			(stroke
				(width 0.1)
				(type default)
			)
			(layer "B.Fab")
		)
		(fp_line
			(start -1.1938 0.4064)
			(end -0.8636 0.4064)
			(stroke
				(width 0.1)
				(type default)
			)
			(layer "B.Fab")
		)
		(fp_line
			(start -0.8636 -0.4572)
			(end -0.8636 -0.4064)
			(stroke
				(width 0.1)
				(type default)
			)
			(layer "B.Fab")
		)
		(fp_line
			(start -0.8636 -0.4064)
			(end -1.1938 -0.4064)
			(stroke
				(width 0.1)
				(type default)
			)
			(layer "B.Fab")
		)
		(fp_line
			(start -0.8636 0.4064)
			(end -0.8636 0.4572)
			(stroke
				(width 0.1)
				(type default)
			)
			(layer "B.Fab")
		)
		(fp_line
			(start -0.8636 0.4572)
			(end 0.8636 0.4572)
			(stroke
				(width 0.1)
				(type default)
			)
			(layer "B.Fab")
		)
		(fp_line
			(start 0.8636 -0.4572)
			(end -0.8636 -0.4572)
			(stroke
				(width 0.1)
				(type default)
			)
			(layer "B.Fab")
		)
		(fp_line
			(start 0.8636 -0.4064)
			(end 0.8636 -0.4572)
			(stroke
				(width 0.1)
				(type default)
			)
			(layer "B.Fab")
		)
		(fp_line
			(start 0.8636 0.4064)
			(end 1.1938 0.4064)
			(stroke
				(width 0.1)
				(type default)
			)
			(layer "B.Fab")
		)
		(fp_line
			(start 0.8636 0.4572)
			(end 0.8636 0.4064)
			(stroke
				(width 0.1)
				(type default)
			)
			(layer "B.Fab")
		)
		(fp_line
			(start 1.1938 -0.4064)
			(end 0.8636 -0.4064)
			(stroke
				(width 0.1)
				(type default)
			)
			(layer "B.Fab")
		)
		(fp_line
			(start 1.1938 0.4064)
			(end 1.1938 -0.4064)
			(stroke
				(width 0.1)
				(type default)
			)
			(layer "B.Fab")
		)
		(pad "1" smd rect
			(at 0.7366 0 270)
			(size 0.7112 0.8128)
			(layers "B.Cu" "B.Mask" "B.Paste")
			(net "P1V05_PCH_AUX")
		)
		(pad "2" smd rect
			(at -0.7366 0 270)
			(size 0.7112 0.8128)
			(layers "B.Cu" "B.Mask" "B.Paste")
			(net "GND")
		)
	)
	(footprint ""
		(layer "B.Cu")
		(at 158.84017 -250.58243 90)
		(property "Reference" "C477"
			(at 0 0 90)
			(layer "B.SilkS")
			(hide yes)
			(effects
				(font
					(size 1.27 1.27)
				)
				(justify mirror)
			)
		)
		(property "Value" ""
			(at 0 0 90)
			(layer "B.Fab")
			(effects
				(font
					(size 1.27 1.27)
				)
				(justify mirror)
			)
		)
		(duplicate_pad_numbers_are_jumpers no)
		(fp_line
			(start 1.524 -0.762)
			(end -1.524 -0.762)
			(stroke
				(width 0.1524)
				(type default)
			)
			(layer "B.SilkS")
		)
		(fp_line
			(start -1.524 -0.762)
			(end -1.524 0.762)
			(stroke
				(width 0.1524)
				(type default)
			)
			(layer "B.SilkS")
		)
		(fp_line
			(start 1.524 0.762)
			(end 1.524 -0.762)
			(stroke
				(width 0.1524)
				(type default)
			)
			(layer "B.SilkS")
		)
		(fp_line
			(start -1.524 0.762)
			(end 1.524 0.762)
			(stroke
				(width 0.1524)
				(type default)
			)
			(layer "B.SilkS")
		)
		(fp_line
			(start 1.1049 -0.724916)
			(end 1.1049 0.724916)
			(stroke
				(width 0.1)
				(type default)
			)
			(layer "B.Fab")
		)
		(fp_line
			(start -1.1049 -0.724916)
			(end 1.1049 -0.724916)
			(stroke
				(width 0.1)
				(type default)
			)
			(layer "B.Fab")
		)
		(fp_line
			(start 1.1049 0.724916)
			(end -1.1049 0.724916)
			(stroke
				(width 0.1)
				(type default)
			)
			(layer "B.Fab")
		)
		(fp_line
			(start -1.1049 0.724916)
			(end -1.1049 -0.724916)
			(stroke
				(width 0.1)
				(type default)
			)
			(layer "B.Fab")
		)
		(pad "1" smd rect
			(at 0.889 0 90)
			(size 1.016 1.27)
			(layers "B.Cu" "B.Mask" "B.Paste")
			(net "PVCCFA_EHV_FIVRA_CPU1")
		)
		(pad "2" smd rect
			(at -0.889 0 90)
			(size 1.016 1.27)
			(layers "B.Cu" "B.Mask" "B.Paste")
			(net "GND")
		)
	)
	(footprint ""
		(layer "B.Cu")
		(at 370.695474 -354.93833 90)
		(property "Reference" "R2332"
			(at 0 0 90)
			(layer "B.SilkS")
			(hide yes)
			(effects
				(font
					(size 1.27 1.27)
				)
				(justify mirror)
			)
		)
		(property "Value" ""
			(at 0 0 90)
			(layer "B.Fab")
			(effects
				(font
					(size 1.27 1.27)
				)
				(justify mirror)
			)
		)
		(duplicate_pad_numbers_are_jumpers no)
		(fp_line
			(start 0.7874 -0.4064)
			(end -0.7874 -0.4064)
			(stroke
				(width 0.1524)
				(type default)
			)
			(layer "B.SilkS")
		)
		(fp_line
			(start -0.7874 -0.4064)
			(end -0.7874 0.4064)
			(stroke
				(width 0.1524)
				(type default)
			)
			(layer "B.SilkS")
		)
		(fp_line
			(start 0.7874 0.4064)
			(end 0.7874 -0.4064)
			(stroke
				(width 0.1524)
				(type default)
			)
			(layer "B.SilkS")
		)
		(fp_line
			(start -0.7874 0.4064)
			(end 0.7874 0.4064)
			(stroke
				(width 0.1524)
				(type default)
			)
			(layer "B.SilkS")
		)
		(fp_line
			(start 0.67945 -0.305054)
			(end 0.12065 -0.305054)
			(stroke
				(width 0.1)
				(type default)
			)
			(layer "B.Fab")
		)
		(fp_line
			(start 0.12065 -0.305054)
			(end 0.12065 -0.2794)
			(stroke
				(width 0.1)
				(type default)
			)
			(layer "B.Fab")
		)
		(fp_line
			(start -0.12065 -0.3048)
			(end -0.67945 -0.3048)
			(stroke
				(width 0.1)
				(type default)
			)
			(layer "B.Fab")
		)
		(fp_line
			(start -0.67945 -0.3048)
			(end -0.67945 0.3048)
			(stroke
				(width 0.1)
				(type default)
			)
			(layer "B.Fab")
		)
		(fp_line
			(start 0.12065 -0.2794)
			(end -0.12065 -0.2794)
			(stroke
				(width 0.1)
				(type default)
			)
			(layer "B.Fab")
		)
		(fp_line
			(start -0.12065 -0.2794)
			(end -0.12065 -0.3048)
			(stroke
				(width 0.1)
				(type default)
			)
			(layer "B.Fab")
		)
		(fp_line
			(start 0.12065 0.2794)
			(end 0.12065 0.3048)
			(stroke
				(width 0.1)
				(type default)
			)
			(layer "B.Fab")
		)
		(fp_line
			(start -0.120396 0.2794)
			(end 0.12065 0.2794)
			(stroke
				(width 0.1)
				(type default)
			)
			(layer "B.Fab")
		)
		(fp_line
			(start 0.67945 0.3048)
			(end 0.67945 -0.305054)
			(stroke
				(width 0.1)
				(type default)
			)
			(layer "B.Fab")
		)
		(fp_line
			(start 0.12065 0.3048)
			(end 0.67945 0.3048)
			(stroke
				(width 0.1)
				(type default)
			)
			(layer "B.Fab")
		)
		(fp_line
			(start -0.120396 0.3048)
			(end -0.120396 0.2794)
			(stroke
				(width 0.1)
				(type default)
			)
			(layer "B.Fab")
		)
		(fp_line
			(start -0.67945 0.3048)
			(end -0.120396 0.3048)
			(stroke
				(width 0.1)
				(type default)
			)
			(layer "B.Fab")
		)
		(pad "1" smd circle
			(at 0.40005 0 270)
			(size 0 0)
			(layers "B.Cu" "B.Mask" "B.Paste")
			(net "FM_PVPP_HBM_CPU0_EN")
		)
		(pad "2" smd circle
			(at -0.40005 0 270)
			(size 0 0)
			(layers "B.Cu" "B.Mask" "B.Paste")
			(net "GND")
		)
	)
	(footprint ""
		(layer "B.Cu")
		(at 289.907726 -362.795058 90)
		(property "Reference" "PC1180_P0_4"
			(at 0 0 90)
			(layer "B.SilkS")
			(hide yes)
			(effects
				(font
					(size 1.27 1.27)
				)
				(justify mirror)
			)
		)
		(property "Value" ""
			(at 0 0 90)
			(layer "B.Fab")
			(effects
				(font
					(size 1.27 1.27)
				)
				(justify mirror)
			)
		)
		(duplicate_pad_numbers_are_jumpers no)
		(fp_line
			(start 1.524 -0.762)
			(end -1.524 -0.762)
			(stroke
				(width 0.1524)
				(type default)
			)
			(layer "B.SilkS")
		)
		(fp_line
			(start -1.524 -0.762)
			(end -1.524 0.762)
			(stroke
				(width 0.1524)
				(type default)
			)
			(layer "B.SilkS")
		)
		(fp_line
			(start 1.524 0.762)
			(end 1.524 -0.762)
			(stroke
				(width 0.1524)
				(type default)
			)
			(layer "B.SilkS")
		)
		(fp_line
			(start -1.524 0.762)
			(end 1.524 0.762)
			(stroke
				(width 0.1524)
				(type default)
			)
			(layer "B.SilkS")
		)
		(fp_line
			(start 1.1049 -0.724916)
			(end 1.1049 0.724916)
			(stroke
				(width 0.1)
				(type default)
			)
			(layer "B.Fab")
		)
		(fp_line
			(start -1.1049 -0.724916)
			(end 1.1049 -0.724916)
			(stroke
				(width 0.1)
				(type default)
			)
			(layer "B.Fab")
		)
		(fp_line
			(start 1.1049 0.724916)
			(end -1.1049 0.724916)
			(stroke
				(width 0.1)
				(type default)
			)
			(layer "B.Fab")
		)
		(fp_line
			(start -1.1049 0.724916)
			(end -1.1049 -0.724916)
			(stroke
				(width 0.1)
				(type default)
			)
			(layer "B.Fab")
		)
		(pad "1" smd rect
			(at 0.889 0 90)
			(size 1.016 1.27)
			(layers "B.Cu" "B.Mask" "B.Paste")
			(net "SW_P12V_PVCCFA_EHV_FIVRA_CPU0_L")
		)
		(pad "2" smd rect
			(at -0.889 0 90)
			(size 1.016 1.27)
			(layers "B.Cu" "B.Mask" "B.Paste")
			(net "GND")
		)
	)
	(footprint ""
		(layer "B.Cu")
		(at 16.207994 -99.842066)
		(property "Reference" "C2038"
			(at 0 0 0)
			(layer "B.SilkS")
			(hide yes)
			(effects
				(font
					(size 1.27 1.27)
				)
				(justify mirror)
			)
		)
		(property "Value" ""
			(at 0 0 0)
			(layer "B.Fab")
			(effects
				(font
					(size 1.27 1.27)
				)
				(justify mirror)
			)
		)
		(duplicate_pad_numbers_are_jumpers no)
		(fp_line
			(start -0.7874 -0.4064)
			(end -0.7874 0.4064)
			(stroke
				(width 0.1524)
				(type default)
			)
			(layer "B.SilkS")
		)
		(fp_line
			(start -0.7874 0.4064)
			(end 0.7874 0.4064)
			(stroke
				(width 0.1524)
				(type default)
			)
			(layer "B.SilkS")
		)
		(fp_line
			(start 0.7874 -0.4064)
			(end -0.7874 -0.4064)
			(stroke
				(width 0.1524)
				(type default)
			)
			(layer "B.SilkS")
		)
		(fp_line
			(start 0.7874 0.4064)
			(end 0.7874 -0.4064)
			(stroke
				(width 0.1524)
				(type default)
			)
			(layer "B.SilkS")
		)
		(fp_line
			(start -0.67945 -0.3048)
			(end -0.67945 0.3048)
			(stroke
				(width 0.1)
				(type default)
			)
			(layer "B.Fab")
		)
		(fp_line
			(start -0.67945 0.3048)
			(end -0.120396 0.3048)
			(stroke
				(width 0.1)
				(type default)
			)
			(layer "B.Fab")
		)
		(fp_line
			(start -0.12065 -0.3048)
			(end -0.67945 -0.3048)
			(stroke
				(width 0.1)
				(type default)
			)
			(layer "B.Fab")
		)
		(fp_line
			(start -0.12065 -0.2794)
			(end -0.12065 -0.3048)
			(stroke
				(width 0.1)
				(type default)
			)
			(layer "B.Fab")
		)
		(fp_line
			(start -0.120396 0.2794)
			(end 0.12065 0.2794)
			(stroke
				(width 0.1)
				(type default)
			)
			(layer "B.Fab")
		)
		(fp_line
			(start -0.120396 0.3048)
			(end -0.120396 0.2794)
			(stroke
				(width 0.1)
				(type default)
			)
			(layer "B.Fab")
		)
		(fp_line
			(start 0.12065 -0.305054)
			(end 0.12065 -0.2794)
			(stroke
				(width 0.1)
				(type default)
			)
			(layer "B.Fab")
		)
		(fp_line
			(start 0.12065 -0.2794)
			(end -0.12065 -0.2794)
			(stroke
				(width 0.1)
				(type default)
			)
			(layer "B.Fab")
		)
		(fp_line
			(start 0.12065 0.2794)
			(end 0.12065 0.3048)
			(stroke
				(width 0.1)
				(type default)
			)
			(layer "B.Fab")
		)
		(fp_line
			(start 0.12065 0.3048)
			(end 0.67945 0.3048)
			(stroke
				(width 0.1)
				(type default)
			)
			(layer "B.Fab")
		)
		(fp_line
			(start 0.67945 -0.305054)
			(end 0.12065 -0.305054)
			(stroke
				(width 0.1)
				(type default)
			)
			(layer "B.Fab")
		)
		(fp_line
			(start 0.67945 0.3048)
			(end 0.67945 -0.305054)
			(stroke
				(width 0.1)
				(type default)
			)
			(layer "B.Fab")
		)
		(pad "1" smd circle
			(at 0.40005 0 180)
			(size 0 0)
			(layers "B.Cu" "B.Mask" "B.Paste")
			(net "P3V3_AUX_USB_HUB")
		)
		(pad "2" smd circle
			(at -0.40005 0 180)
			(size 0 0)
			(layers "B.Cu" "B.Mask" "B.Paste")
			(net "GND")
		)
	)
	(footprint ""
		(layer "B.Cu")
		(at 52.375054 -353.567492 90)
		(property "Reference" "PC404_P1_2"
			(at 0 0 90)
			(layer "B.SilkS")
			(hide yes)
			(effects
				(font
					(size 1.27 1.27)
				)
				(justify mirror)
			)
		)
		(property "Value" ""
			(at 0 0 90)
			(layer "B.Fab")
			(effects
				(font
					(size 1.27 1.27)
				)
				(justify mirror)
			)
		)
		(duplicate_pad_numbers_are_jumpers no)
		(fp_line
			(start 1.524 -0.762)
			(end -1.524 -0.762)
			(stroke
				(width 0.1524)
				(type default)
			)
			(layer "B.SilkS")
		)
		(fp_line
			(start -1.524 -0.762)
			(end -1.524 0.762)
			(stroke
				(width 0.1524)
				(type default)
			)
			(layer "B.SilkS")
		)
		(fp_line
			(start 1.524 0.762)
			(end 1.524 -0.762)
			(stroke
				(width 0.1524)
				(type default)
			)
			(layer "B.SilkS")
		)
		(fp_line
			(start -1.524 0.762)
			(end 1.524 0.762)
			(stroke
				(width 0.1524)
				(type default)
			)
			(layer "B.SilkS")
		)
		(fp_line
			(start 1.1049 -0.724916)
			(end 1.1049 0.724916)
			(stroke
				(width 0.1)
				(type default)
			)
			(layer "B.Fab")
		)
		(fp_line
			(start -1.1049 -0.724916)
			(end 1.1049 -0.724916)
			(stroke
				(width 0.1)
				(type default)
			)
			(layer "B.Fab")
		)
		(fp_line
			(start 1.1049 0.724916)
			(end -1.1049 0.724916)
			(stroke
				(width 0.1)
				(type default)
			)
			(layer "B.Fab")
		)
		(fp_line
			(start -1.1049 0.724916)
			(end -1.1049 -0.724916)
			(stroke
				(width 0.1)
				(type default)
			)
			(layer "B.Fab")
		)
		(pad "1" smd rect
			(at 0.889 0 90)
			(size 1.016 1.27)
			(layers "B.Cu" "B.Mask" "B.Paste")
			(net "SW_P12V_PVCCFA_EHV_FIVRA_CPU1_L")
		)
		(pad "2" smd rect
			(at -0.889 0 90)
			(size 1.016 1.27)
			(layers "B.Cu" "B.Mask" "B.Paste")
			(net "GND")
		)
	)
	(footprint ""
		(layer "B.Cu")
		(at 301.731172 -362.795058 90)
		(property "Reference" "PC611_P0_2"
			(at 0 0 90)
			(layer "B.SilkS")
			(hide yes)
			(effects
				(font
					(size 1.27 1.27)
				)
				(justify mirror)
			)
		)
		(property "Value" ""
			(at 0 0 90)
			(layer "B.Fab")
			(effects
				(font
					(size 1.27 1.27)
				)
				(justify mirror)
			)
		)
		(duplicate_pad_numbers_are_jumpers no)
		(fp_line
			(start 1.524 -0.762)
			(end -1.524 -0.762)
			(stroke
				(width 0.1524)
				(type default)
			)
			(layer "B.SilkS")
		)
		(fp_line
			(start -1.524 -0.762)
			(end -1.524 0.762)
			(stroke
				(width 0.1524)
				(type default)
			)
			(layer "B.SilkS")
		)
		(fp_line
			(start 1.524 0.762)
			(end 1.524 -0.762)
			(stroke
				(width 0.1524)
				(type default)
			)
			(layer "B.SilkS")
		)
		(fp_line
			(start -1.524 0.762)
			(end 1.524 0.762)
			(stroke
				(width 0.1524)
				(type default)
			)
			(layer "B.SilkS")
		)
		(fp_line
			(start 1.1049 -0.724916)
			(end 1.1049 0.724916)
			(stroke
				(width 0.1)
				(type default)
			)
			(layer "B.Fab")
		)
		(fp_line
			(start -1.1049 -0.724916)
			(end 1.1049 -0.724916)
			(stroke
				(width 0.1)
				(type default)
			)
			(layer "B.Fab")
		)
		(fp_line
			(start 1.1049 0.724916)
			(end -1.1049 0.724916)
			(stroke
				(width 0.1)
				(type default)
			)
			(layer "B.Fab")
		)
		(fp_line
			(start -1.1049 0.724916)
			(end -1.1049 -0.724916)
			(stroke
				(width 0.1)
				(type default)
			)
			(layer "B.Fab")
		)
		(pad "1" smd rect
			(at 0.889 0 90)
			(size 1.016 1.27)
			(layers "B.Cu" "B.Mask" "B.Paste")
			(net "SW_P12V_PVCCFA_EHV_FIVRA_CPU0_L")
		)
		(pad "2" smd rect
			(at -0.889 0 90)
			(size 1.016 1.27)
			(layers "B.Cu" "B.Mask" "B.Paste")
			(net "GND")
		)
	)
	(footprint ""
		(layer "B.Cu")
		(at 511.924808 -303.58588 -90)
		(property "Reference" "X27"
			(at 3.47472 2.673858 270)
			(unlocked yes)
			(layer "B.SilkS")
			(effects
				(font
					(size 0.7874 0.5842)
					(thickness 0.1524)
				)
				(justify left mirror)
			)
		)
		(property "Value" ""
			(at 0 0 90)
			(layer "B.Fab")
			(effects
				(font
					(size 1.27 1.27)
				)
				(justify mirror)
			)
		)
		(property "Device Type" "TP_TDR_4P_FTS_TH-TP_TDR_4P_DIPA"
			(at -1.30175 1.27 180)
			(unlocked yes)
			(layer "B.Fab")
			(hide yes)
			(effects
				(font
					(size 0.635 0.4064)
					(thickness 0.1524)
				)
				(justify mirror)
			)
		)
		(property "User Part Number" "N_A"
			(at -1.30175 1.27 180)
			(unlocked yes)
			(layer "Cmts.User")
			(hide yes)
			(effects
				(font
					(size 0.635 0.4064)
					(thickness 0.1524)
				)
				(justify mirror)
			)
		)
		(duplicate_pad_numbers_are_jumpers no)
		(fp_line
			(start -2.54 3.81)
			(end -2.54 3.6703)
			(stroke
				(width 0.1524)
				(type default)
			)
			(layer "B.SilkS")
		)
		(fp_line
			(start 0 3.81)
			(end -2.54 3.81)
			(stroke
				(width 0.1524)
				(type default)
			)
			(layer "B.SilkS")
		)
		(fp_line
			(start 0 3.175)
			(end 0 3.81)
			(stroke
				(width 0.1524)
				(type default)
			)
			(layer "B.SilkS")
		)
		(fp_line
			(start -2.54 1.4097)
			(end -2.54 1.1303)
			(stroke
				(width 0.1524)
				(type default)
			)
			(layer "B.SilkS")
		)
		(fp_line
			(start 0 0.635)
			(end 0 1.905)
			(stroke
				(width 0.1524)
				(type default)
			)
			(layer "B.SilkS")
		)
		(fp_line
			(start -2.54 -1.1303)
			(end -2.54 -1.27)
			(stroke
				(width 0.1524)
				(type default)
			)
			(layer "B.SilkS")
		)
		(fp_line
			(start -2.54 -1.27)
			(end 0 -1.27)
			(stroke
				(width 0.1524)
				(type default)
			)
			(layer "B.SilkS")
		)
		(fp_line
			(start 0 -1.27)
			(end 0 -0.635)
			(stroke
				(width 0.1524)
				(type default)
			)
			(layer "B.SilkS")
		)
		(fp_poly
			(pts
				(xy 3.001518 -0.804164) (xy 3.001518 0.719836) (xy 1.477518 -0.042164)
			)
			(stroke
				(width 0)
				(type default)
			)
			(fill yes)
			(layer "B.SilkS")
		)
		(fp_line
			(start -2.54 3.81)
			(end -2.54 -1.27)
			(stroke
				(width 0.1)
				(type default)
			)
			(layer "B.Fab")
		)
		(fp_line
			(start 0 3.81)
			(end -2.54 3.81)
			(stroke
				(width 0.1)
				(type default)
			)
			(layer "B.Fab")
		)
		(fp_line
			(start -2.54 -1.27)
			(end 0 -1.27)
			(stroke
				(width 0.1)
				(type default)
			)
			(layer "B.Fab")
		)
		(fp_line
			(start 0 -1.27)
			(end 0 3.81)
			(stroke
				(width 0.1)
				(type default)
			)
			(layer "B.Fab")
		)
		(fp_poly
			(pts
				(xy 0.761746 0) (xy 2.285746 -0.762) (xy 2.285746 0.762)
			)
			(stroke
				(width 0)
				(type default)
			)
			(fill yes)
			(layer "B.Fab")
		)
		(pad "1" thru_hole circle
			(at 0 0 90)
			(size 1.0033 1.0033)
			(drill 0.249936)
			(layers "*.Cu" "*.Mask")
			(remove_unused_layers no)
			(net "TDR_DIFF_85_IN5_DN")
			(clearance 0.10795)
			(padstack
				(mode front_inner_back)
				(layer "Inner"
					(shape circle)
					(size 0.8001 0.8001)
					(clearance 0.1524)
				)
				(layer "B.Cu"
					(shape circle)
					(size 1.0033 1.0033)
					(thermal_gap 0.10795)
					(clearance 0.10795)
				)
			)
		)
		(pad "2" thru_hole circle
			(at -2.54 0 90)
			(size 1.9939 1.9939)
			(drill 0.249936)
			(layers "*.Cu" "*.Mask")
			(remove_unused_layers no)
			(net "T1_GND")
			(clearance 0.10795)
			(padstack
				(mode front_inner_back)
				(layer "Inner"
					(shape circle)
					(size 0.8001 0.8001)
					(clearance 0.1524)
				)
				(layer "B.Cu"
					(shape circle)
					(size 1.9939 1.9939)
					(thermal_gap 0.10795)
					(clearance 0.10795)
				)
			)
		)
		(pad "3" thru_hole circle
			(at -2.54 2.54 90)
			(size 1.9939 1.9939)
			(drill 0.249936)
			(layers "*.Cu" "*.Mask")
			(remove_unused_layers no)
			(net "T1_GND")
			(clearance 0.10795)
			(padstack
				(mode front_inner_back)
				(layer "Inner"
					(shape circle)
					(size 0.8001 0.8001)
					(clearance 0.1524)
				)
				(layer "B.Cu"
					(shape circle)
					(size 1.9939 1.9939)
					(thermal_gap 0.10795)
					(clearance 0.10795)
				)
			)
		)
		(pad "4" thru_hole circle
			(at 0 2.54 90)
			(size 1.0033 1.0033)
			(drill 0.249936)
			(layers "*.Cu" "*.Mask")
			(remove_unused_layers no)
			(net "TDR_DIFF_85_IN5_DP")
			(clearance 0.10795)
			(padstack
				(mode front_inner_back)
				(layer "Inner"
					(shape circle)
					(size 0.8001 0.8001)
					(clearance 0.1524)
				)
				(layer "B.Cu"
					(shape circle)
					(size 1.0033 1.0033)
					(thermal_gap 0.10795)
					(clearance 0.10795)
				)
			)
		)
	)
	(footprint ""
		(layer "B.Cu")
		(at 36.60648 -344.757248 -90)
		(property "Reference" "PR4241"
			(at 0 0 90)
			(layer "B.SilkS")
			(hide yes)
			(effects
				(font
					(size 1.27 1.27)
				)
				(justify mirror)
			)
		)
		(property "Value" ""
			(at 0 0 90)
			(layer "B.Fab")
			(effects
				(font
					(size 1.27 1.27)
				)
				(justify mirror)
			)
		)
		(duplicate_pad_numbers_are_jumpers no)
		(fp_line
			(start -0.7874 0.4064)
			(end 0.7874 0.4064)
			(stroke
				(width 0.1524)
				(type default)
			)
			(layer "B.SilkS")
		)
		(fp_line
			(start 0.7874 0.4064)
			(end 0.7874 -0.4064)
			(stroke
				(width 0.1524)
				(type default)
			)
			(layer "B.SilkS")
		)
		(fp_line
			(start -0.7874 -0.4064)
			(end -0.7874 0.4064)
			(stroke
				(width 0.1524)
				(type default)
			)
			(layer "B.SilkS")
		)
		(fp_line
			(start 0.7874 -0.4064)
			(end -0.7874 -0.4064)
			(stroke
				(width 0.1524)
				(type default)
			)
			(layer "B.SilkS")
		)
		(fp_line
			(start -0.67945 0.3048)
			(end -0.120396 0.3048)
			(stroke
				(width 0.1)
				(type default)
			)
			(layer "B.Fab")
		)
		(fp_line
			(start -0.120396 0.3048)
			(end -0.120396 0.2794)
			(stroke
				(width 0.1)
				(type default)
			)
			(layer "B.Fab")
		)
		(fp_line
			(start 0.12065 0.3048)
			(end 0.67945 0.3048)
			(stroke
				(width 0.1)
				(type default)
			)
			(layer "B.Fab")
		)
		(fp_line
			(start 0.67945 0.3048)
			(end 0.67945 -0.305054)
			(stroke
				(width 0.1)
				(type default)
			)
			(layer "B.Fab")
		)
		(fp_line
			(start -0.120396 0.2794)
			(end 0.12065 0.2794)
			(stroke
				(width 0.1)
				(type default)
			)
			(layer "B.Fab")
		)
		(fp_line
			(start 0.12065 0.2794)
			(end 0.12065 0.3048)
			(stroke
				(width 0.1)
				(type default)
			)
			(layer "B.Fab")
		)
		(fp_line
			(start -0.12065 -0.2794)
			(end -0.12065 -0.3048)
			(stroke
				(width 0.1)
				(type default)
			)
			(layer "B.Fab")
		)
		(fp_line
			(start 0.12065 -0.2794)
			(end -0.12065 -0.2794)
			(stroke
				(width 0.1)
				(type default)
			)
			(layer "B.Fab")
		)
		(fp_line
			(start -0.67945 -0.3048)
			(end -0.67945 0.3048)
			(stroke
				(width 0.1)
				(type default)
			)
			(layer "B.Fab")
		)
		(fp_line
			(start -0.12065 -0.3048)
			(end -0.67945 -0.3048)
			(stroke
				(width 0.1)
				(type default)
			)
			(layer "B.Fab")
		)
		(fp_line
			(start 0.12065 -0.305054)
			(end 0.12065 -0.2794)
			(stroke
				(width 0.1)
				(type default)
			)
			(layer "B.Fab")
		)
		(fp_line
			(start 0.67945 -0.305054)
			(end 0.12065 -0.305054)
			(stroke
				(width 0.1)
				(type default)
			)
			(layer "B.Fab")
		)
		(pad "1" smd circle
			(at 0.40005 0 90)
			(size 0 0)
			(layers "B.Cu" "B.Mask" "B.Paste")
			(net "PVCCFA_EHV_FIVRA_CPU1")
		)
		(pad "2" smd circle
			(at -0.40005 0 90)
			(size 0 0)
			(layers "B.Cu" "B.Mask" "B.Paste")
			(net "GND")
		)
	)
	(footprint ""
		(layer "B.Cu")
		(at 8.153146 -318.25311 180)
		(property "Reference" "R3897"
			(at 0 0 0)
			(layer "B.SilkS")
			(hide yes)
			(effects
				(font
					(size 1.27 1.27)
				)
				(justify mirror)
			)
		)
		(property "Value" ""
			(at 0 0 0)
			(layer "B.Fab")
			(effects
				(font
					(size 1.27 1.27)
				)
				(justify mirror)
			)
		)
		(duplicate_pad_numbers_are_jumpers no)
		(fp_line
			(start 0.7874 0.4064)
			(end 0.7874 -0.4064)
			(stroke
				(width 0.1524)
				(type default)
			)
			(layer "B.SilkS")
		)
		(fp_line
			(start 0.7874 -0.4064)
			(end -0.7874 -0.4064)
			(stroke
				(width 0.1524)
				(type default)
			)
			(layer "B.SilkS")
		)
		(fp_line
			(start -0.7874 0.4064)
			(end 0.7874 0.4064)
			(stroke
				(width 0.1524)
				(type default)
			)
			(layer "B.SilkS")
		)
		(fp_line
			(start -0.7874 -0.4064)
			(end -0.7874 0.4064)
			(stroke
				(width 0.1524)
				(type default)
			)
			(layer "B.SilkS")
		)
		(fp_line
			(start 0.67945 0.3048)
			(end 0.67945 -0.305054)
			(stroke
				(width 0.1)
				(type default)
			)
			(layer "B.Fab")
		)
		(fp_line
			(start 0.67945 -0.305054)
			(end 0.12065 -0.305054)
			(stroke
				(width 0.1)
				(type default)
			)
			(layer "B.Fab")
		)
		(fp_line
			(start 0.12065 0.3048)
			(end 0.67945 0.3048)
			(stroke
				(width 0.1)
				(type default)
			)
			(layer "B.Fab")
		)
		(fp_line
			(start 0.12065 0.2794)
			(end 0.12065 0.3048)
			(stroke
				(width 0.1)
				(type default)
			)
			(layer "B.Fab")
		)
		(fp_line
			(start 0.12065 -0.2794)
			(end -0.12065 -0.2794)
			(stroke
				(width 0.1)
				(type default)
			)
			(layer "B.Fab")
		)
		(fp_line
			(start 0.12065 -0.305054)
			(end 0.12065 -0.2794)
			(stroke
				(width 0.1)
				(type default)
			)
			(layer "B.Fab")
		)
		(fp_line
			(start -0.120396 0.3048)
			(end -0.120396 0.2794)
			(stroke
				(width 0.1)
				(type default)
			)
			(layer "B.Fab")
		)
		(fp_line
			(start -0.120396 0.2794)
			(end 0.12065 0.2794)
			(stroke
				(width 0.1)
				(type default)
			)
			(layer "B.Fab")
		)
		(fp_line
			(start -0.12065 -0.2794)
			(end -0.12065 -0.3048)
			(stroke
				(width 0.1)
				(type default)
			)
			(layer "B.Fab")
		)
		(fp_line
			(start -0.12065 -0.3048)
			(end -0.67945 -0.3048)
			(stroke
				(width 0.1)
				(type default)
			)
			(layer "B.Fab")
		)
		(fp_line
			(start -0.67945 0.3048)
			(end -0.120396 0.3048)
			(stroke
				(width 0.1)
				(type default)
			)
			(layer "B.Fab")
		)
		(fp_line
			(start -0.67945 -0.3048)
			(end -0.67945 0.3048)
			(stroke
				(width 0.1)
				(type default)
			)
			(layer "B.Fab")
		)
		(pad "1" smd circle
			(at 0.40005 0)
			(size 0 0)
			(layers "B.Cu" "B.Mask" "B.Paste")
			(net "I3C_SPD_DDRABCD_CPU1_LVC1_SCL_6")
		)
		(pad "2" smd circle
			(at -0.40005 0)
			(size 0 0)
			(layers "B.Cu" "B.Mask" "B.Paste")
			(net "I3C_SPD_DDRABCD_CPU1_LVC1_SCL")
		)
	)
	(footprint ""
		(layer "B.Cu")
		(at 429.397414 -319.263776 180)
		(property "Reference" "C32"
			(at 0 0 0)
			(layer "B.SilkS")
			(hide yes)
			(effects
				(font
					(size 1.27 1.27)
				)
				(justify mirror)
			)
		)
		(property "Value" ""
			(at 0 0 0)
			(layer "B.Fab")
			(effects
				(font
					(size 1.27 1.27)
				)
				(justify mirror)
			)
		)
		(duplicate_pad_numbers_are_jumpers no)
		(fp_line
			(start 0.7874 0.4064)
			(end 0.7874 -0.4064)
			(stroke
				(width 0.1524)
				(type default)
			)
			(layer "B.SilkS")
		)
		(fp_line
			(start 0.7874 -0.4064)
			(end -0.7874 -0.4064)
			(stroke
				(width 0.1524)
				(type default)
			)
			(layer "B.SilkS")
		)
		(fp_line
			(start -0.7874 0.4064)
			(end 0.7874 0.4064)
			(stroke
				(width 0.1524)
				(type default)
			)
			(layer "B.SilkS")
		)
		(fp_line
			(start -0.7874 -0.4064)
			(end -0.7874 0.4064)
			(stroke
				(width 0.1524)
				(type default)
			)
			(layer "B.SilkS")
		)
		(fp_line
			(start 0.67945 0.3048)
			(end 0.67945 -0.305054)
			(stroke
				(width 0.1)
				(type default)
			)
			(layer "B.Fab")
		)
		(fp_line
			(start 0.67945 -0.305054)
			(end 0.12065 -0.305054)
			(stroke
				(width 0.1)
				(type default)
			)
			(layer "B.Fab")
		)
		(fp_line
			(start 0.12065 0.3048)
			(end 0.67945 0.3048)
			(stroke
				(width 0.1)
				(type default)
			)
			(layer "B.Fab")
		)
		(fp_line
			(start 0.12065 0.2794)
			(end 0.12065 0.3048)
			(stroke
				(width 0.1)
				(type default)
			)
			(layer "B.Fab")
		)
		(fp_line
			(start 0.12065 -0.2794)
			(end -0.12065 -0.2794)
			(stroke
				(width 0.1)
				(type default)
			)
			(layer "B.Fab")
		)
		(fp_line
			(start 0.12065 -0.305054)
			(end 0.12065 -0.2794)
			(stroke
				(width 0.1)
				(type default)
			)
			(layer "B.Fab")
		)
		(fp_line
			(start -0.120396 0.3048)
			(end -0.120396 0.2794)
			(stroke
				(width 0.1)
				(type default)
			)
			(layer "B.Fab")
		)
		(fp_line
			(start -0.120396 0.2794)
			(end 0.12065 0.2794)
			(stroke
				(width 0.1)
				(type default)
			)
			(layer "B.Fab")
		)
		(fp_line
			(start -0.12065 -0.2794)
			(end -0.12065 -0.3048)
			(stroke
				(width 0.1)
				(type default)
			)
			(layer "B.Fab")
		)
		(fp_line
			(start -0.12065 -0.3048)
			(end -0.67945 -0.3048)
			(stroke
				(width 0.1)
				(type default)
			)
			(layer "B.Fab")
		)
		(fp_line
			(start -0.67945 0.3048)
			(end -0.120396 0.3048)
			(stroke
				(width 0.1)
				(type default)
			)
			(layer "B.Fab")
		)
		(fp_line
			(start -0.67945 -0.3048)
			(end -0.67945 0.3048)
			(stroke
				(width 0.1)
				(type default)
			)
			(layer "B.Fab")
		)
		(pad "1" smd circle
			(at 0.40005 0)
			(size 0 0)
			(layers "B.Cu" "B.Mask" "B.Paste")
			(net "P3V3_AUX")
		)
		(pad "2" smd circle
			(at -0.40005 0)
			(size 0 0)
			(layers "B.Cu" "B.Mask" "B.Paste")
			(net "GND")
		)
	)
	(footprint ""
		(layer "B.Cu")
		(at 420.285418 -193.353436 -90)
		(property "Reference" "R708"
			(at 0 0 90)
			(layer "B.SilkS")
			(hide yes)
			(effects
				(font
					(size 1.27 1.27)
				)
				(justify mirror)
			)
		)
		(property "Value" ""
			(at 0 0 90)
			(layer "B.Fab")
			(effects
				(font
					(size 1.27 1.27)
				)
				(justify mirror)
			)
		)
		(duplicate_pad_numbers_are_jumpers no)
		(fp_line
			(start -0.7874 0.4064)
			(end 0.7874 0.4064)
			(stroke
				(width 0.1524)
				(type default)
			)
			(layer "B.SilkS")
		)
		(fp_line
			(start 0.7874 0.4064)
			(end 0.7874 -0.4064)
			(stroke
				(width 0.1524)
				(type default)
			)
			(layer "B.SilkS")
		)
		(fp_line
			(start -0.7874 -0.4064)
			(end -0.7874 0.4064)
			(stroke
				(width 0.1524)
				(type default)
			)
			(layer "B.SilkS")
		)
		(fp_line
			(start 0.7874 -0.4064)
			(end -0.7874 -0.4064)
			(stroke
				(width 0.1524)
				(type default)
			)
			(layer "B.SilkS")
		)
		(fp_line
			(start -0.67945 0.3048)
			(end -0.120396 0.3048)
			(stroke
				(width 0.1)
				(type default)
			)
			(layer "B.Fab")
		)
		(fp_line
			(start -0.120396 0.3048)
			(end -0.120396 0.2794)
			(stroke
				(width 0.1)
				(type default)
			)
			(layer "B.Fab")
		)
		(fp_line
			(start 0.12065 0.3048)
			(end 0.67945 0.3048)
			(stroke
				(width 0.1)
				(type default)
			)
			(layer "B.Fab")
		)
		(fp_line
			(start 0.67945 0.3048)
			(end 0.67945 -0.305054)
			(stroke
				(width 0.1)
				(type default)
			)
			(layer "B.Fab")
		)
		(fp_line
			(start -0.120396 0.2794)
			(end 0.12065 0.2794)
			(stroke
				(width 0.1)
				(type default)
			)
			(layer "B.Fab")
		)
		(fp_line
			(start 0.12065 0.2794)
			(end 0.12065 0.3048)
			(stroke
				(width 0.1)
				(type default)
			)
			(layer "B.Fab")
		)
		(fp_line
			(start -0.12065 -0.2794)
			(end -0.12065 -0.3048)
			(stroke
				(width 0.1)
				(type default)
			)
			(layer "B.Fab")
		)
		(fp_line
			(start 0.12065 -0.2794)
			(end -0.12065 -0.2794)
			(stroke
				(width 0.1)
				(type default)
			)
			(layer "B.Fab")
		)
		(fp_line
			(start -0.67945 -0.3048)
			(end -0.67945 0.3048)
			(stroke
				(width 0.1)
				(type default)
			)
			(layer "B.Fab")
		)
		(fp_line
			(start -0.12065 -0.3048)
			(end -0.67945 -0.3048)
			(stroke
				(width 0.1)
				(type default)
			)
			(layer "B.Fab")
		)
		(fp_line
			(start 0.12065 -0.305054)
			(end 0.12065 -0.2794)
			(stroke
				(width 0.1)
				(type default)
			)
			(layer "B.Fab")
		)
		(fp_line
			(start 0.67945 -0.305054)
			(end 0.12065 -0.305054)
			(stroke
				(width 0.1)
				(type default)
			)
			(layer "B.Fab")
		)
		(pad "1" smd circle
			(at 0.40005 0 90)
			(size 0 0)
			(layers "B.Cu" "B.Mask" "B.Paste")
			(net "RST_PLD_CPU0_DRAM_EF_N")
		)
		(pad "2" smd circle
			(at -0.40005 0 90)
			(size 0 0)
			(layers "B.Cu" "B.Mask" "B.Paste")
			(net "GND")
		)
	)
	(footprint ""
		(layer "B.Cu")
		(at 198.086472 -318.332358)
		(property "Reference" "R75"
			(at 0 0 0)
			(layer "B.SilkS")
			(hide yes)
			(effects
				(font
					(size 1.27 1.27)
				)
				(justify mirror)
			)
		)
		(property "Value" ""
			(at 0 0 0)
			(layer "B.Fab")
			(effects
				(font
					(size 1.27 1.27)
				)
				(justify mirror)
			)
		)
		(duplicate_pad_numbers_are_jumpers no)
		(fp_line
			(start -0.7874 -0.4064)
			(end -0.7874 0.4064)
			(stroke
				(width 0.1524)
				(type default)
			)
			(layer "B.SilkS")
		)
		(fp_line
			(start -0.7874 0.4064)
			(end 0.7874 0.4064)
			(stroke
				(width 0.1524)
				(type default)
			)
			(layer "B.SilkS")
		)
		(fp_line
			(start 0.7874 -0.4064)
			(end -0.7874 -0.4064)
			(stroke
				(width 0.1524)
				(type default)
			)
			(layer "B.SilkS")
		)
		(fp_line
			(start 0.7874 0.4064)
			(end 0.7874 -0.4064)
			(stroke
				(width 0.1524)
				(type default)
			)
			(layer "B.SilkS")
		)
		(fp_line
			(start -0.67945 -0.3048)
			(end -0.67945 0.3048)
			(stroke
				(width 0.1)
				(type default)
			)
			(layer "B.Fab")
		)
		(fp_line
			(start -0.67945 0.3048)
			(end -0.120396 0.3048)
			(stroke
				(width 0.1)
				(type default)
			)
			(layer "B.Fab")
		)
		(fp_line
			(start -0.12065 -0.3048)
			(end -0.67945 -0.3048)
			(stroke
				(width 0.1)
				(type default)
			)
			(layer "B.Fab")
		)
		(fp_line
			(start -0.12065 -0.2794)
			(end -0.12065 -0.3048)
			(stroke
				(width 0.1)
				(type default)
			)
			(layer "B.Fab")
		)
		(fp_line
			(start -0.120396 0.2794)
			(end 0.12065 0.2794)
			(stroke
				(width 0.1)
				(type default)
			)
			(layer "B.Fab")
		)
		(fp_line
			(start -0.120396 0.3048)
			(end -0.120396 0.2794)
			(stroke
				(width 0.1)
				(type default)
			)
			(layer "B.Fab")
		)
		(fp_line
			(start 0.12065 -0.305054)
			(end 0.12065 -0.2794)
			(stroke
				(width 0.1)
				(type default)
			)
			(layer "B.Fab")
		)
		(fp_line
			(start 0.12065 -0.2794)
			(end -0.12065 -0.2794)
			(stroke
				(width 0.1)
				(type default)
			)
			(layer "B.Fab")
		)
		(fp_line
			(start 0.12065 0.2794)
			(end 0.12065 0.3048)
			(stroke
				(width 0.1)
				(type default)
			)
			(layer "B.Fab")
		)
		(fp_line
			(start 0.12065 0.3048)
			(end 0.67945 0.3048)
			(stroke
				(width 0.1)
				(type default)
			)
			(layer "B.Fab")
		)
		(fp_line
			(start 0.67945 -0.305054)
			(end 0.12065 -0.305054)
			(stroke
				(width 0.1)
				(type default)
			)
			(layer "B.Fab")
		)
		(fp_line
			(start 0.67945 0.3048)
			(end 0.67945 -0.305054)
			(stroke
				(width 0.1)
				(type default)
			)
			(layer "B.Fab")
		)
		(pad "1" smd circle
			(at 0.40005 0 180)
			(size 0 0)
			(layers "B.Cu" "B.Mask" "B.Paste")
			(net "PD_CHG_CPU1_DIMM1_SAA")
		)
		(pad "2" smd circle
			(at -0.40005 0 180)
			(size 0 0)
			(layers "B.Cu" "B.Mask" "B.Paste")
			(net "GND")
		)
	)
	(footprint ""
		(layer "B.Cu")
		(at 65.023746 -321.554856 -90)
		(property "Reference" "C54"
			(at 0 0 90)
			(layer "B.SilkS")
			(hide yes)
			(effects
				(font
					(size 1.27 1.27)
				)
				(justify mirror)
			)
		)
		(property "Value" ""
			(at 0 0 90)
			(layer "B.Fab")
			(effects
				(font
					(size 1.27 1.27)
				)
				(justify mirror)
			)
		)
		(duplicate_pad_numbers_are_jumpers no)
		(fp_line
			(start -1.524 0.762)
			(end 1.524 0.762)
			(stroke
				(width 0.1524)
				(type default)
			)
			(layer "B.SilkS")
		)
		(fp_line
			(start 1.524 0.762)
			(end 1.524 -0.762)
			(stroke
				(width 0.1524)
				(type default)
			)
			(layer "B.SilkS")
		)
		(fp_line
			(start -1.524 -0.762)
			(end -1.524 0.762)
			(stroke
				(width 0.1524)
				(type default)
			)
			(layer "B.SilkS")
		)
		(fp_line
			(start 1.524 -0.762)
			(end -1.524 -0.762)
			(stroke
				(width 0.1524)
				(type default)
			)
			(layer "B.SilkS")
		)
		(fp_line
			(start -1.1049 0.724916)
			(end -1.1049 -0.724916)
			(stroke
				(width 0.1)
				(type default)
			)
			(layer "B.Fab")
		)
		(fp_line
			(start 1.1049 0.724916)
			(end -1.1049 0.724916)
			(stroke
				(width 0.1)
				(type default)
			)
			(layer "B.Fab")
		)
		(fp_line
			(start -1.1049 -0.724916)
			(end 1.1049 -0.724916)
			(stroke
				(width 0.1)
				(type default)
			)
			(layer "B.Fab")
		)
		(fp_line
			(start 1.1049 -0.724916)
			(end 1.1049 0.724916)
			(stroke
				(width 0.1)
				(type default)
			)
			(layer "B.Fab")
		)
		(pad "1" smd rect
			(at 0.889 0 270)
			(size 1.016 1.27)
			(layers "B.Cu" "B.Mask" "B.Paste")
			(net "P12V_S3_AUX_CPU1_NVDIMM")
		)
		(pad "2" smd rect
			(at -0.889 0 270)
			(size 1.016 1.27)
			(layers "B.Cu" "B.Mask" "B.Paste")
			(net "GND")
		)
	)
	(footprint ""
		(layer "B.Cu")
		(at 191.992758 -69.443346)
		(property "Reference" "R3213"
			(at 0 0 0)
			(layer "B.SilkS")
			(hide yes)
			(effects
				(font
					(size 1.27 1.27)
				)
				(justify mirror)
			)
		)
		(property "Value" ""
			(at 0 0 0)
			(layer "B.Fab")
			(effects
				(font
					(size 1.27 1.27)
				)
				(justify mirror)
			)
		)
		(duplicate_pad_numbers_are_jumpers no)
		(fp_line
			(start -0.7874 -0.4064)
			(end -0.7874 0.4064)
			(stroke
				(width 0.1524)
				(type default)
			)
			(layer "B.SilkS")
		)
		(fp_line
			(start -0.7874 0.4064)
			(end 0.7874 0.4064)
			(stroke
				(width 0.1524)
				(type default)
			)
			(layer "B.SilkS")
		)
		(fp_line
			(start 0.7874 -0.4064)
			(end -0.7874 -0.4064)
			(stroke
				(width 0.1524)
				(type default)
			)
			(layer "B.SilkS")
		)
		(fp_line
			(start 0.7874 0.4064)
			(end 0.7874 -0.4064)
			(stroke
				(width 0.1524)
				(type default)
			)
			(layer "B.SilkS")
		)
		(fp_line
			(start -0.67945 -0.3048)
			(end -0.67945 0.3048)
			(stroke
				(width 0.1)
				(type default)
			)
			(layer "B.Fab")
		)
		(fp_line
			(start -0.67945 0.3048)
			(end -0.120396 0.3048)
			(stroke
				(width 0.1)
				(type default)
			)
			(layer "B.Fab")
		)
		(fp_line
			(start -0.12065 -0.3048)
			(end -0.67945 -0.3048)
			(stroke
				(width 0.1)
				(type default)
			)
			(layer "B.Fab")
		)
		(fp_line
			(start -0.12065 -0.2794)
			(end -0.12065 -0.3048)
			(stroke
				(width 0.1)
				(type default)
			)
			(layer "B.Fab")
		)
		(fp_line
			(start -0.120396 0.2794)
			(end 0.12065 0.2794)
			(stroke
				(width 0.1)
				(type default)
			)
			(layer "B.Fab")
		)
		(fp_line
			(start -0.120396 0.3048)
			(end -0.120396 0.2794)
			(stroke
				(width 0.1)
				(type default)
			)
			(layer "B.Fab")
		)
		(fp_line
			(start 0.12065 -0.305054)
			(end 0.12065 -0.2794)
			(stroke
				(width 0.1)
				(type default)
			)
			(layer "B.Fab")
		)
		(fp_line
			(start 0.12065 -0.2794)
			(end -0.12065 -0.2794)
			(stroke
				(width 0.1)
				(type default)
			)
			(layer "B.Fab")
		)
		(fp_line
			(start 0.12065 0.2794)
			(end 0.12065 0.3048)
			(stroke
				(width 0.1)
				(type default)
			)
			(layer "B.Fab")
		)
		(fp_line
			(start 0.12065 0.3048)
			(end 0.67945 0.3048)
			(stroke
				(width 0.1)
				(type default)
			)
			(layer "B.Fab")
		)
		(fp_line
			(start 0.67945 -0.305054)
			(end 0.12065 -0.305054)
			(stroke
				(width 0.1)
				(type default)
			)
			(layer "B.Fab")
		)
		(fp_line
			(start 0.67945 0.3048)
			(end 0.67945 -0.305054)
			(stroke
				(width 0.1)
				(type default)
			)
			(layer "B.Fab")
		)
		(pad "1" smd circle
			(at 0.40005 0 180)
			(size 0 0)
			(layers "B.Cu" "B.Mask" "B.Paste")
			(net "NCSI_BMC_TX_EN_R1")
		)
		(pad "2" smd circle
			(at -0.40005 0 180)
			(size 0 0)
			(layers "B.Cu" "B.Mask" "B.Paste")
			(net "RMII_BMC_OCP_TX_EN")
		)
	)
	(footprint ""
		(layer "B.Cu")
		(at 315.14288 -49.113948 180)
		(property "Reference" "R1262"
			(at 0 0 0)
			(layer "B.SilkS")
			(hide yes)
			(effects
				(font
					(size 1.27 1.27)
				)
				(justify mirror)
			)
		)
		(property "Value" ""
			(at 0 0 0)
			(layer "B.Fab")
			(effects
				(font
					(size 1.27 1.27)
				)
				(justify mirror)
			)
		)
		(duplicate_pad_numbers_are_jumpers no)
		(fp_line
			(start 0.7874 0.4064)
			(end 0.7874 -0.4064)
			(stroke
				(width 0.1524)
				(type default)
			)
			(layer "B.SilkS")
		)
		(fp_line
			(start 0.7874 -0.4064)
			(end -0.7874 -0.4064)
			(stroke
				(width 0.1524)
				(type default)
			)
			(layer "B.SilkS")
		)
		(fp_line
			(start -0.7874 0.4064)
			(end 0.7874 0.4064)
			(stroke
				(width 0.1524)
				(type default)
			)
			(layer "B.SilkS")
		)
		(fp_line
			(start -0.7874 -0.4064)
			(end -0.7874 0.4064)
			(stroke
				(width 0.1524)
				(type default)
			)
			(layer "B.SilkS")
		)
		(fp_line
			(start 0.67945 0.3048)
			(end 0.67945 -0.305054)
			(stroke
				(width 0.1)
				(type default)
			)
			(layer "B.Fab")
		)
		(fp_line
			(start 0.67945 -0.305054)
			(end 0.12065 -0.305054)
			(stroke
				(width 0.1)
				(type default)
			)
			(layer "B.Fab")
		)
		(fp_line
			(start 0.12065 0.3048)
			(end 0.67945 0.3048)
			(stroke
				(width 0.1)
				(type default)
			)
			(layer "B.Fab")
		)
		(fp_line
			(start 0.12065 0.2794)
			(end 0.12065 0.3048)
			(stroke
				(width 0.1)
				(type default)
			)
			(layer "B.Fab")
		)
		(fp_line
			(start 0.12065 -0.2794)
			(end -0.12065 -0.2794)
			(stroke
				(width 0.1)
				(type default)
			)
			(layer "B.Fab")
		)
		(fp_line
			(start 0.12065 -0.305054)
			(end 0.12065 -0.2794)
			(stroke
				(width 0.1)
				(type default)
			)
			(layer "B.Fab")
		)
		(fp_line
			(start -0.120396 0.3048)
			(end -0.120396 0.2794)
			(stroke
				(width 0.1)
				(type default)
			)
			(layer "B.Fab")
		)
		(fp_line
			(start -0.120396 0.2794)
			(end 0.12065 0.2794)
			(stroke
				(width 0.1)
				(type default)
			)
			(layer "B.Fab")
		)
		(fp_line
			(start -0.12065 -0.2794)
			(end -0.12065 -0.3048)
			(stroke
				(width 0.1)
				(type default)
			)
			(layer "B.Fab")
		)
		(fp_line
			(start -0.12065 -0.3048)
			(end -0.67945 -0.3048)
			(stroke
				(width 0.1)
				(type default)
			)
			(layer "B.Fab")
		)
		(fp_line
			(start -0.67945 0.3048)
			(end -0.120396 0.3048)
			(stroke
				(width 0.1)
				(type default)
			)
			(layer "B.Fab")
		)
		(fp_line
			(start -0.67945 -0.3048)
			(end -0.67945 0.3048)
			(stroke
				(width 0.1)
				(type default)
			)
			(layer "B.Fab")
		)
		(pad "1" smd circle
			(at 0.40005 0)
			(size 0 0)
			(layers "B.Cu" "B.Mask" "B.Paste")
			(net "P1V05_PCH_AUX")
		)
		(pad "2" smd circle
			(at -0.40005 0)
			(size 0 0)
			(layers "B.Cu" "B.Mask" "B.Paste")
			(net "H_CPU_ERR2_PCH_R_N")
		)
	)
	(footprint ""
		(layer "B.Cu")
		(at 404.006812 -53.727604)
		(property "Reference" "R766"
			(at 0 0 0)
			(layer "B.SilkS")
			(hide yes)
			(effects
				(font
					(size 1.27 1.27)
				)
				(justify mirror)
			)
		)
		(property "Value" ""
			(at 0 0 0)
			(layer "B.Fab")
			(effects
				(font
					(size 1.27 1.27)
				)
				(justify mirror)
			)
		)
		(duplicate_pad_numbers_are_jumpers no)
		(fp_line
			(start -0.7874 -0.4064)
			(end -0.7874 0.4064)
			(stroke
				(width 0.1524)
				(type default)
			)
			(layer "B.SilkS")
		)
		(fp_line
			(start -0.7874 0.4064)
			(end 0.7874 0.4064)
			(stroke
				(width 0.1524)
				(type default)
			)
			(layer "B.SilkS")
		)
		(fp_line
			(start 0.7874 -0.4064)
			(end -0.7874 -0.4064)
			(stroke
				(width 0.1524)
				(type default)
			)
			(layer "B.SilkS")
		)
		(fp_line
			(start 0.7874 0.4064)
			(end 0.7874 -0.4064)
			(stroke
				(width 0.1524)
				(type default)
			)
			(layer "B.SilkS")
		)
		(fp_line
			(start -0.67945 -0.3048)
			(end -0.67945 0.3048)
			(stroke
				(width 0.1)
				(type default)
			)
			(layer "B.Fab")
		)
		(fp_line
			(start -0.67945 0.3048)
			(end -0.120396 0.3048)
			(stroke
				(width 0.1)
				(type default)
			)
			(layer "B.Fab")
		)
		(fp_line
			(start -0.12065 -0.3048)
			(end -0.67945 -0.3048)
			(stroke
				(width 0.1)
				(type default)
			)
			(layer "B.Fab")
		)
		(fp_line
			(start -0.12065 -0.2794)
			(end -0.12065 -0.3048)
			(stroke
				(width 0.1)
				(type default)
			)
			(layer "B.Fab")
		)
		(fp_line
			(start -0.120396 0.2794)
			(end 0.12065 0.2794)
			(stroke
				(width 0.1)
				(type default)
			)
			(layer "B.Fab")
		)
		(fp_line
			(start -0.120396 0.3048)
			(end -0.120396 0.2794)
			(stroke
				(width 0.1)
				(type default)
			)
			(layer "B.Fab")
		)
		(fp_line
			(start 0.12065 -0.305054)
			(end 0.12065 -0.2794)
			(stroke
				(width 0.1)
				(type default)
			)
			(layer "B.Fab")
		)
		(fp_line
			(start 0.12065 -0.2794)
			(end -0.12065 -0.2794)
			(stroke
				(width 0.1)
				(type default)
			)
			(layer "B.Fab")
		)
		(fp_line
			(start 0.12065 0.2794)
			(end 0.12065 0.3048)
			(stroke
				(width 0.1)
				(type default)
			)
			(layer "B.Fab")
		)
		(fp_line
			(start 0.12065 0.3048)
			(end 0.67945 0.3048)
			(stroke
				(width 0.1)
				(type default)
			)
			(layer "B.Fab")
		)
		(fp_line
			(start 0.67945 -0.305054)
			(end 0.12065 -0.305054)
			(stroke
				(width 0.1)
				(type default)
			)
			(layer "B.Fab")
		)
		(fp_line
			(start 0.67945 0.3048)
			(end 0.67945 -0.305054)
			(stroke
				(width 0.1)
				(type default)
			)
			(layer "B.Fab")
		)
		(pad "1" smd circle
			(at 0.40005 0 180)
			(size 0 0)
			(layers "B.Cu" "B.Mask" "B.Paste")
			(net "P3V3_AUX")
		)
		(pad "2" smd circle
			(at -0.40005 0 180)
			(size 0 0)
			(layers "B.Cu" "B.Mask" "B.Paste")
			(net "JTAG_DBP_POWER_BTN_N")
		)
	)
	(footprint ""
		(layer "B.Cu")
		(at 226.652328 -403.769322 -90)
		(property "Reference" "PR3981"
			(at 0 0 90)
			(layer "B.SilkS")
			(hide yes)
			(effects
				(font
					(size 1.27 1.27)
				)
				(justify mirror)
			)
		)
		(property "Value" ""
			(at 0 0 90)
			(layer "B.Fab")
			(effects
				(font
					(size 1.27 1.27)
				)
				(justify mirror)
			)
		)
		(duplicate_pad_numbers_are_jumpers no)
		(fp_line
			(start -0.7874 0.4064)
			(end 0.7874 0.4064)
			(stroke
				(width 0.1524)
				(type default)
			)
			(layer "B.SilkS")
		)
		(fp_line
			(start 0.7874 0.4064)
			(end 0.7874 -0.4064)
			(stroke
				(width 0.1524)
				(type default)
			)
			(layer "B.SilkS")
		)
		(fp_line
			(start -0.7874 -0.4064)
			(end -0.7874 0.4064)
			(stroke
				(width 0.1524)
				(type default)
			)
			(layer "B.SilkS")
		)
		(fp_line
			(start 0.7874 -0.4064)
			(end -0.7874 -0.4064)
			(stroke
				(width 0.1524)
				(type default)
			)
			(layer "B.SilkS")
		)
		(fp_line
			(start -0.67945 0.3048)
			(end -0.120396 0.3048)
			(stroke
				(width 0.1)
				(type default)
			)
			(layer "B.Fab")
		)
		(fp_line
			(start -0.120396 0.3048)
			(end -0.120396 0.2794)
			(stroke
				(width 0.1)
				(type default)
			)
			(layer "B.Fab")
		)
		(fp_line
			(start 0.12065 0.3048)
			(end 0.67945 0.3048)
			(stroke
				(width 0.1)
				(type default)
			)
			(layer "B.Fab")
		)
		(fp_line
			(start 0.67945 0.3048)
			(end 0.67945 -0.305054)
			(stroke
				(width 0.1)
				(type default)
			)
			(layer "B.Fab")
		)
		(fp_line
			(start -0.120396 0.2794)
			(end 0.12065 0.2794)
			(stroke
				(width 0.1)
				(type default)
			)
			(layer "B.Fab")
		)
		(fp_line
			(start 0.12065 0.2794)
			(end 0.12065 0.3048)
			(stroke
				(width 0.1)
				(type default)
			)
			(layer "B.Fab")
		)
		(fp_line
			(start -0.12065 -0.2794)
			(end -0.12065 -0.3048)
			(stroke
				(width 0.1)
				(type default)
			)
			(layer "B.Fab")
		)
		(fp_line
			(start 0.12065 -0.2794)
			(end -0.12065 -0.2794)
			(stroke
				(width 0.1)
				(type default)
			)
			(layer "B.Fab")
		)
		(fp_line
			(start -0.67945 -0.3048)
			(end -0.67945 0.3048)
			(stroke
				(width 0.1)
				(type default)
			)
			(layer "B.Fab")
		)
		(fp_line
			(start -0.12065 -0.3048)
			(end -0.67945 -0.3048)
			(stroke
				(width 0.1)
				(type default)
			)
			(layer "B.Fab")
		)
		(fp_line
			(start 0.12065 -0.305054)
			(end 0.12065 -0.2794)
			(stroke
				(width 0.1)
				(type default)
			)
			(layer "B.Fab")
		)
		(fp_line
			(start 0.67945 -0.305054)
			(end 0.12065 -0.305054)
			(stroke
				(width 0.1)
				(type default)
			)
			(layer "B.Fab")
		)
		(pad "1" smd circle
			(at 0.40005 0 90)
			(size 0 0)
			(layers "B.Cu" "B.Mask" "B.Paste")
			(net "HSC_VDD_R_4")
		)
		(pad "2" smd circle
			(at -0.40005 0 90)
			(size 0 0)
			(layers "B.Cu" "B.Mask" "B.Paste")
			(net "HSC_VDD")
		)
	)
	(footprint ""
		(layer "B.Cu")
		(at 321.001898 -186.43981 90)
		(property "Reference" "R336"
			(at 0 0 90)
			(layer "B.SilkS")
			(hide yes)
			(effects
				(font
					(size 1.27 1.27)
				)
				(justify mirror)
			)
		)
		(property "Value" ""
			(at 0 0 90)
			(layer "B.Fab")
			(effects
				(font
					(size 1.27 1.27)
				)
				(justify mirror)
			)
		)
		(duplicate_pad_numbers_are_jumpers no)
		(fp_line
			(start 0.7874 -0.4064)
			(end -0.7874 -0.4064)
			(stroke
				(width 0.1524)
				(type default)
			)
			(layer "B.SilkS")
		)
		(fp_line
			(start -0.7874 -0.4064)
			(end -0.7874 0.4064)
			(stroke
				(width 0.1524)
				(type default)
			)
			(layer "B.SilkS")
		)
		(fp_line
			(start 0.7874 0.4064)
			(end 0.7874 -0.4064)
			(stroke
				(width 0.1524)
				(type default)
			)
			(layer "B.SilkS")
		)
		(fp_line
			(start -0.7874 0.4064)
			(end 0.7874 0.4064)
			(stroke
				(width 0.1524)
				(type default)
			)
			(layer "B.SilkS")
		)
		(fp_line
			(start 0.67945 -0.305054)
			(end 0.12065 -0.305054)
			(stroke
				(width 0.1)
				(type default)
			)
			(layer "B.Fab")
		)
		(fp_line
			(start 0.12065 -0.305054)
			(end 0.12065 -0.2794)
			(stroke
				(width 0.1)
				(type default)
			)
			(layer "B.Fab")
		)
		(fp_line
			(start -0.12065 -0.3048)
			(end -0.67945 -0.3048)
			(stroke
				(width 0.1)
				(type default)
			)
			(layer "B.Fab")
		)
		(fp_line
			(start -0.67945 -0.3048)
			(end -0.67945 0.3048)
			(stroke
				(width 0.1)
				(type default)
			)
			(layer "B.Fab")
		)
		(fp_line
			(start 0.12065 -0.2794)
			(end -0.12065 -0.2794)
			(stroke
				(width 0.1)
				(type default)
			)
			(layer "B.Fab")
		)
		(fp_line
			(start -0.12065 -0.2794)
			(end -0.12065 -0.3048)
			(stroke
				(width 0.1)
				(type default)
			)
			(layer "B.Fab")
		)
		(fp_line
			(start 0.12065 0.2794)
			(end 0.12065 0.3048)
			(stroke
				(width 0.1)
				(type default)
			)
			(layer "B.Fab")
		)
		(fp_line
			(start -0.120396 0.2794)
			(end 0.12065 0.2794)
			(stroke
				(width 0.1)
				(type default)
			)
			(layer "B.Fab")
		)
		(fp_line
			(start 0.67945 0.3048)
			(end 0.67945 -0.305054)
			(stroke
				(width 0.1)
				(type default)
			)
			(layer "B.Fab")
		)
		(fp_line
			(start 0.12065 0.3048)
			(end 0.67945 0.3048)
			(stroke
				(width 0.1)
				(type default)
			)
			(layer "B.Fab")
		)
		(fp_line
			(start -0.120396 0.3048)
			(end -0.120396 0.2794)
			(stroke
				(width 0.1)
				(type default)
			)
			(layer "B.Fab")
		)
		(fp_line
			(start -0.67945 0.3048)
			(end -0.120396 0.3048)
			(stroke
				(width 0.1)
				(type default)
			)
			(layer "B.Fab")
		)
		(pad "1" smd circle
			(at 0.40005 0 270)
			(size 0 0)
			(layers "B.Cu" "B.Mask" "B.Paste")
			(net "H_CPU0_ERR0_LVC1_R_N")
		)
		(pad "2" smd circle
			(at -0.40005 0 270)
			(size 0 0)
			(layers "B.Cu" "B.Mask" "B.Paste")
			(net "H_CPU_ERR0_LVC1_R_N")
		)
	)
	(footprint ""
		(layer "B.Cu")
		(at 17.725136 -191.700404)
		(property "Reference" "R964"
			(at 0 0 0)
			(layer "B.SilkS")
			(hide yes)
			(effects
				(font
					(size 1.27 1.27)
				)
				(justify mirror)
			)
		)
		(property "Value" ""
			(at 0 0 0)
			(layer "B.Fab")
			(effects
				(font
					(size 1.27 1.27)
				)
				(justify mirror)
			)
		)
		(duplicate_pad_numbers_are_jumpers no)
		(fp_line
			(start -0.7874 -0.4064)
			(end -0.7874 0.4064)
			(stroke
				(width 0.1524)
				(type default)
			)
			(layer "B.SilkS")
		)
		(fp_line
			(start -0.7874 0.4064)
			(end 0.7874 0.4064)
			(stroke
				(width 0.1524)
				(type default)
			)
			(layer "B.SilkS")
		)
		(fp_line
			(start 0.7874 -0.4064)
			(end -0.7874 -0.4064)
			(stroke
				(width 0.1524)
				(type default)
			)
			(layer "B.SilkS")
		)
		(fp_line
			(start 0.7874 0.4064)
			(end 0.7874 -0.4064)
			(stroke
				(width 0.1524)
				(type default)
			)
			(layer "B.SilkS")
		)
		(fp_line
			(start -0.67945 -0.3048)
			(end -0.67945 0.3048)
			(stroke
				(width 0.1)
				(type default)
			)
			(layer "B.Fab")
		)
		(fp_line
			(start -0.67945 0.3048)
			(end -0.120396 0.3048)
			(stroke
				(width 0.1)
				(type default)
			)
			(layer "B.Fab")
		)
		(fp_line
			(start -0.12065 -0.3048)
			(end -0.67945 -0.3048)
			(stroke
				(width 0.1)
				(type default)
			)
			(layer "B.Fab")
		)
		(fp_line
			(start -0.12065 -0.2794)
			(end -0.12065 -0.3048)
			(stroke
				(width 0.1)
				(type default)
			)
			(layer "B.Fab")
		)
		(fp_line
			(start -0.120396 0.2794)
			(end 0.12065 0.2794)
			(stroke
				(width 0.1)
				(type default)
			)
			(layer "B.Fab")
		)
		(fp_line
			(start -0.120396 0.3048)
			(end -0.120396 0.2794)
			(stroke
				(width 0.1)
				(type default)
			)
			(layer "B.Fab")
		)
		(fp_line
			(start 0.12065 -0.305054)
			(end 0.12065 -0.2794)
			(stroke
				(width 0.1)
				(type default)
			)
			(layer "B.Fab")
		)
		(fp_line
			(start 0.12065 -0.2794)
			(end -0.12065 -0.2794)
			(stroke
				(width 0.1)
				(type default)
			)
			(layer "B.Fab")
		)
		(fp_line
			(start 0.12065 0.2794)
			(end 0.12065 0.3048)
			(stroke
				(width 0.1)
				(type default)
			)
			(layer "B.Fab")
		)
		(fp_line
			(start 0.12065 0.3048)
			(end 0.67945 0.3048)
			(stroke
				(width 0.1)
				(type default)
			)
			(layer "B.Fab")
		)
		(fp_line
			(start 0.67945 -0.305054)
			(end 0.12065 -0.305054)
			(stroke
				(width 0.1)
				(type default)
			)
			(layer "B.Fab")
		)
		(fp_line
			(start 0.67945 0.3048)
			(end 0.67945 -0.305054)
			(stroke
				(width 0.1)
				(type default)
			)
			(layer "B.Fab")
		)
		(pad "1" smd circle
			(at 0.40005 0 180)
			(size 0 0)
			(layers "B.Cu" "B.Mask" "B.Paste")
			(net "PVNN_TERM_CPU1")
		)
		(pad "2" smd circle
			(at -0.40005 0 180)
			(size 0 0)
			(layers "B.Cu" "B.Mask" "B.Paste")
			(net "SMB_PEHPCPU1_GTL_R_SDA")
		)
	)
	(footprint ""
		(layer "B.Cu")
		(at 173.377352 -22.564598 90)
		(property "Reference" "R1763"
			(at 0 0 90)
			(layer "B.SilkS")
			(hide yes)
			(effects
				(font
					(size 1.27 1.27)
				)
				(justify mirror)
			)
		)
		(property "Value" ""
			(at 0 0 90)
			(layer "B.Fab")
			(effects
				(font
					(size 1.27 1.27)
				)
				(justify mirror)
			)
		)
		(duplicate_pad_numbers_are_jumpers no)
		(fp_line
			(start 0.7874 -0.4064)
			(end -0.7874 -0.4064)
			(stroke
				(width 0.1524)
				(type default)
			)
			(layer "B.SilkS")
		)
		(fp_line
			(start -0.7874 -0.4064)
			(end -0.7874 0.4064)
			(stroke
				(width 0.1524)
				(type default)
			)
			(layer "B.SilkS")
		)
		(fp_line
			(start 0.7874 0.4064)
			(end 0.7874 -0.4064)
			(stroke
				(width 0.1524)
				(type default)
			)
			(layer "B.SilkS")
		)
		(fp_line
			(start -0.7874 0.4064)
			(end 0.7874 0.4064)
			(stroke
				(width 0.1524)
				(type default)
			)
			(layer "B.SilkS")
		)
		(fp_line
			(start 0.67945 -0.305054)
			(end 0.12065 -0.305054)
			(stroke
				(width 0.1)
				(type default)
			)
			(layer "B.Fab")
		)
		(fp_line
			(start 0.12065 -0.305054)
			(end 0.12065 -0.2794)
			(stroke
				(width 0.1)
				(type default)
			)
			(layer "B.Fab")
		)
		(fp_line
			(start -0.12065 -0.3048)
			(end -0.67945 -0.3048)
			(stroke
				(width 0.1)
				(type default)
			)
			(layer "B.Fab")
		)
		(fp_line
			(start -0.67945 -0.3048)
			(end -0.67945 0.3048)
			(stroke
				(width 0.1)
				(type default)
			)
			(layer "B.Fab")
		)
		(fp_line
			(start 0.12065 -0.2794)
			(end -0.12065 -0.2794)
			(stroke
				(width 0.1)
				(type default)
			)
			(layer "B.Fab")
		)
		(fp_line
			(start -0.12065 -0.2794)
			(end -0.12065 -0.3048)
			(stroke
				(width 0.1)
				(type default)
			)
			(layer "B.Fab")
		)
		(fp_line
			(start 0.12065 0.2794)
			(end 0.12065 0.3048)
			(stroke
				(width 0.1)
				(type default)
			)
			(layer "B.Fab")
		)
		(fp_line
			(start -0.120396 0.2794)
			(end 0.12065 0.2794)
			(stroke
				(width 0.1)
				(type default)
			)
			(layer "B.Fab")
		)
		(fp_line
			(start 0.67945 0.3048)
			(end 0.67945 -0.305054)
			(stroke
				(width 0.1)
				(type default)
			)
			(layer "B.Fab")
		)
		(fp_line
			(start 0.12065 0.3048)
			(end 0.67945 0.3048)
			(stroke
				(width 0.1)
				(type default)
			)
			(layer "B.Fab")
		)
		(fp_line
			(start -0.120396 0.3048)
			(end -0.120396 0.2794)
			(stroke
				(width 0.1)
				(type default)
			)
			(layer "B.Fab")
		)
		(fp_line
			(start -0.67945 0.3048)
			(end -0.120396 0.3048)
			(stroke
				(width 0.1)
				(type default)
			)
			(layer "B.Fab")
		)
		(pad "1" smd circle
			(at 0.40005 0 270)
			(size 0 0)
			(layers "B.Cu" "B.Mask" "B.Paste")
			(net "PGPPA_AUX")
		)
		(pad "2" smd circle
			(at -0.40005 0 270)
			(size 0 0)
			(layers "B.Cu" "B.Mask" "B.Paste")
			(net "FM_LPC_ESPI_SEL")
		)
	)
	(footprint ""
		(layer "B.Cu")
		(at 66.162174 -16.37157)
		(property "Reference" "C1832"
			(at 0 0 0)
			(layer "B.SilkS")
			(hide yes)
			(effects
				(font
					(size 1.27 1.27)
				)
				(justify mirror)
			)
		)
		(property "Value" ""
			(at 0 0 0)
			(layer "B.Fab")
			(effects
				(font
					(size 1.27 1.27)
				)
				(justify mirror)
			)
		)
		(duplicate_pad_numbers_are_jumpers no)
		(fp_line
			(start -0.7874 -0.4064)
			(end -0.7874 0.4064)
			(stroke
				(width 0.1524)
				(type default)
			)
			(layer "B.SilkS")
		)
		(fp_line
			(start -0.7874 0.4064)
			(end 0.7874 0.4064)
			(stroke
				(width 0.1524)
				(type default)
			)
			(layer "B.SilkS")
		)
		(fp_line
			(start 0.7874 -0.4064)
			(end -0.7874 -0.4064)
			(stroke
				(width 0.1524)
				(type default)
			)
			(layer "B.SilkS")
		)
		(fp_line
			(start 0.7874 0.4064)
			(end 0.7874 -0.4064)
			(stroke
				(width 0.1524)
				(type default)
			)
			(layer "B.SilkS")
		)
		(fp_line
			(start -0.67945 -0.3048)
			(end -0.67945 0.3048)
			(stroke
				(width 0.1)
				(type default)
			)
			(layer "B.Fab")
		)
		(fp_line
			(start -0.67945 0.3048)
			(end -0.120396 0.3048)
			(stroke
				(width 0.1)
				(type default)
			)
			(layer "B.Fab")
		)
		(fp_line
			(start -0.12065 -0.3048)
			(end -0.67945 -0.3048)
			(stroke
				(width 0.1)
				(type default)
			)
			(layer "B.Fab")
		)
		(fp_line
			(start -0.12065 -0.2794)
			(end -0.12065 -0.3048)
			(stroke
				(width 0.1)
				(type default)
			)
			(layer "B.Fab")
		)
		(fp_line
			(start -0.120396 0.2794)
			(end 0.12065 0.2794)
			(stroke
				(width 0.1)
				(type default)
			)
			(layer "B.Fab")
		)
		(fp_line
			(start -0.120396 0.3048)
			(end -0.120396 0.2794)
			(stroke
				(width 0.1)
				(type default)
			)
			(layer "B.Fab")
		)
		(fp_line
			(start 0.12065 -0.305054)
			(end 0.12065 -0.2794)
			(stroke
				(width 0.1)
				(type default)
			)
			(layer "B.Fab")
		)
		(fp_line
			(start 0.12065 -0.2794)
			(end -0.12065 -0.2794)
			(stroke
				(width 0.1)
				(type default)
			)
			(layer "B.Fab")
		)
		(fp_line
			(start 0.12065 0.2794)
			(end 0.12065 0.3048)
			(stroke
				(width 0.1)
				(type default)
			)
			(layer "B.Fab")
		)
		(fp_line
			(start 0.12065 0.3048)
			(end 0.67945 0.3048)
			(stroke
				(width 0.1)
				(type default)
			)
			(layer "B.Fab")
		)
		(fp_line
			(start 0.67945 -0.305054)
			(end 0.12065 -0.305054)
			(stroke
				(width 0.1)
				(type default)
			)
			(layer "B.Fab")
		)
		(fp_line
			(start 0.67945 0.3048)
			(end 0.67945 -0.305054)
			(stroke
				(width 0.1)
				(type default)
			)
			(layer "B.Fab")
		)
		(pad "1" smd circle
			(at 0.40005 0 180)
			(size 0 0)
			(layers "B.Cu" "B.Mask" "B.Paste")
			(net "P12V_OCP_V3_2")
		)
		(pad "2" smd circle
			(at -0.40005 0 180)
			(size 0 0)
			(layers "B.Cu" "B.Mask" "B.Paste")
			(net "GND")
		)
	)
	(footprint ""
		(layer "B.Cu")
		(at 180.90388 -330.495148 180)
		(property "Reference" "R1933"
			(at 0 0 0)
			(layer "B.SilkS")
			(hide yes)
			(effects
				(font
					(size 1.27 1.27)
				)
				(justify mirror)
			)
		)
		(property "Value" ""
			(at 0 0 0)
			(layer "B.Fab")
			(effects
				(font
					(size 1.27 1.27)
				)
				(justify mirror)
			)
		)
		(duplicate_pad_numbers_are_jumpers no)
		(fp_line
			(start 0.7874 0.4064)
			(end 0.7874 -0.4064)
			(stroke
				(width 0.1524)
				(type default)
			)
			(layer "B.SilkS")
		)
		(fp_line
			(start 0.7874 -0.4064)
			(end -0.7874 -0.4064)
			(stroke
				(width 0.1524)
				(type default)
			)
			(layer "B.SilkS")
		)
		(fp_line
			(start -0.7874 0.4064)
			(end 0.7874 0.4064)
			(stroke
				(width 0.1524)
				(type default)
			)
			(layer "B.SilkS")
		)
		(fp_line
			(start -0.7874 -0.4064)
			(end -0.7874 0.4064)
			(stroke
				(width 0.1524)
				(type default)
			)
			(layer "B.SilkS")
		)
		(fp_line
			(start 0.67945 0.3048)
			(end 0.67945 -0.305054)
			(stroke
				(width 0.1)
				(type default)
			)
			(layer "B.Fab")
		)
		(fp_line
			(start 0.67945 -0.305054)
			(end 0.12065 -0.305054)
			(stroke
				(width 0.1)
				(type default)
			)
			(layer "B.Fab")
		)
		(fp_line
			(start 0.12065 0.3048)
			(end 0.67945 0.3048)
			(stroke
				(width 0.1)
				(type default)
			)
			(layer "B.Fab")
		)
		(fp_line
			(start 0.12065 0.2794)
			(end 0.12065 0.3048)
			(stroke
				(width 0.1)
				(type default)
			)
			(layer "B.Fab")
		)
		(fp_line
			(start 0.12065 -0.2794)
			(end -0.12065 -0.2794)
			(stroke
				(width 0.1)
				(type default)
			)
			(layer "B.Fab")
		)
		(fp_line
			(start 0.12065 -0.305054)
			(end 0.12065 -0.2794)
			(stroke
				(width 0.1)
				(type default)
			)
			(layer "B.Fab")
		)
		(fp_line
			(start -0.120396 0.3048)
			(end -0.120396 0.2794)
			(stroke
				(width 0.1)
				(type default)
			)
			(layer "B.Fab")
		)
		(fp_line
			(start -0.120396 0.2794)
			(end 0.12065 0.2794)
			(stroke
				(width 0.1)
				(type default)
			)
			(layer "B.Fab")
		)
		(fp_line
			(start -0.12065 -0.2794)
			(end -0.12065 -0.3048)
			(stroke
				(width 0.1)
				(type default)
			)
			(layer "B.Fab")
		)
		(fp_line
			(start -0.12065 -0.3048)
			(end -0.67945 -0.3048)
			(stroke
				(width 0.1)
				(type default)
			)
			(layer "B.Fab")
		)
		(fp_line
			(start -0.67945 0.3048)
			(end -0.120396 0.3048)
			(stroke
				(width 0.1)
				(type default)
			)
			(layer "B.Fab")
		)
		(fp_line
			(start -0.67945 -0.3048)
			(end -0.67945 0.3048)
			(stroke
				(width 0.1)
				(type default)
			)
			(layer "B.Fab")
		)
		(pad "1" smd circle
			(at 0.40005 0)
			(size 0 0)
			(layers "B.Cu" "B.Mask" "B.Paste")
			(net "SMB_S3M_CPU0_PIROM_3V3AUX_SDA")
		)
		(pad "2" smd circle
			(at -0.40005 0)
			(size 0 0)
			(layers "B.Cu" "B.Mask" "B.Paste")
			(net "SMB_S3M_CPU0_PIROM_3V3AUX_SDA_1")
		)
	)
	(footprint ""
		(layer "B.Cu")
		(at 377.485402 -329.921616 -90)
		(property "Reference" "PC323"
			(at 0 0 90)
			(layer "B.SilkS")
			(hide yes)
			(effects
				(font
					(size 1.27 1.27)
				)
				(justify mirror)
			)
		)
		(property "Value" ""
			(at 0 0 90)
			(layer "B.Fab")
			(effects
				(font
					(size 1.27 1.27)
				)
				(justify mirror)
			)
		)
		(duplicate_pad_numbers_are_jumpers no)
		(fp_line
			(start -4.533392 2.249932)
			(end 4.533392 2.249932)
			(stroke
				(width 0.1524)
				(type default)
			)
			(layer "B.SilkS")
		)
		(fp_line
			(start 4.533392 2.249932)
			(end 4.533392 -2.249932)
			(stroke
				(width 0.1524)
				(type default)
			)
			(layer "B.SilkS")
		)
		(fp_line
			(start -4.533392 -2.249932)
			(end -4.533392 2.249932)
			(stroke
				(width 0.1524)
				(type default)
			)
			(layer "B.SilkS")
		)
		(fp_line
			(start 4.533392 -2.249932)
			(end -4.533392 -2.249932)
			(stroke
				(width 0.1524)
				(type default)
			)
			(layer "B.SilkS")
		)
		(fp_rect
			(start 5.39242 2.326132)
			(end 4.533392 -2.326132)
			(stroke
				(width 0)
				(type default)
			)
			(fill yes)
			(layer "B.SilkS")
		)
		(fp_line
			(start -3.750056 2.249932)
			(end 3.750056 2.249932)
			(stroke
				(width 0.1)
				(type default)
			)
			(layer "B.Fab")
		)
		(fp_line
			(start 3.750056 2.249932)
			(end 3.750056 -2.249932)
			(stroke
				(width 0.1)
				(type default)
			)
			(layer "B.Fab")
		)
		(fp_line
			(start -3.750056 -2.249932)
			(end -3.750056 2.249932)
			(stroke
				(width 0.1)
				(type default)
			)
			(layer "B.Fab")
		)
		(fp_line
			(start 3.750056 -2.249932)
			(end -3.750056 -2.249932)
			(stroke
				(width 0.1)
				(type default)
			)
			(layer "B.Fab")
		)
		(fp_text user "-"
			(at -4.673092 1.617472 270)
			(unlocked yes)
			(layer "B.SilkS")
			(effects
				(font
					(size 1.905 1.4224)
					(thickness 0.1524)
				)
				(justify left mirror)
			)
		)
		(fp_text user "+"
			(at 6.322314 0.786384 180)
			(unlocked yes)
			(layer "B.SilkS")
			(effects
				(font
					(size 1.905 1.4224)
					(thickness 0.1524)
				)
				(justify left mirror)
			)
		)
		(fp_text user "+"
			(at 6.322314 0.786384 180)
			(unlocked yes)
			(layer "B.Fab")
			(effects
				(font
					(size 1.905 1.4224)
					(thickness 0.1524)
				)
				(justify left mirror)
			)
		)
		(fp_text user "-"
			(at -4.8514 -0.14605 270)
			(unlocked yes)
			(layer "B.Fab")
			(effects
				(font
					(size 1.905 1.4224)
					(thickness 0.1524)
				)
				(justify left mirror)
			)
		)
		(pad "1" smd rect
			(at 3.199892 0 90)
			(size 2.413 2.8194)
			(layers "B.Cu" "B.Mask" "B.Paste")
			(net "PVCCIN_CPU0")
		)
		(pad "2" smd rect
			(at -3.199892 0 90)
			(size 2.413 2.8194)
			(layers "B.Cu" "B.Mask" "B.Paste")
			(net "GND")
		)
	)
	(footprint ""
		(layer "B.Cu")
		(at 156.1465 -192.77711 -90)
		(property "Reference" "R68"
			(at 0 0 90)
			(layer "B.SilkS")
			(hide yes)
			(effects
				(font
					(size 1.27 1.27)
				)
				(justify mirror)
			)
		)
		(property "Value" ""
			(at 0 0 90)
			(layer "B.Fab")
			(effects
				(font
					(size 1.27 1.27)
				)
				(justify mirror)
			)
		)
		(duplicate_pad_numbers_are_jumpers no)
		(fp_line
			(start -0.7874 0.4064)
			(end 0.7874 0.4064)
			(stroke
				(width 0.1524)
				(type default)
			)
			(layer "B.SilkS")
		)
		(fp_line
			(start 0.7874 0.4064)
			(end 0.7874 -0.4064)
			(stroke
				(width 0.1524)
				(type default)
			)
			(layer "B.SilkS")
		)
		(fp_line
			(start -0.7874 -0.4064)
			(end -0.7874 0.4064)
			(stroke
				(width 0.1524)
				(type default)
			)
			(layer "B.SilkS")
		)
		(fp_line
			(start 0.7874 -0.4064)
			(end -0.7874 -0.4064)
			(stroke
				(width 0.1524)
				(type default)
			)
			(layer "B.SilkS")
		)
		(fp_line
			(start -0.67945 0.3048)
			(end -0.120396 0.3048)
			(stroke
				(width 0.1)
				(type default)
			)
			(layer "B.Fab")
		)
		(fp_line
			(start -0.120396 0.3048)
			(end -0.120396 0.2794)
			(stroke
				(width 0.1)
				(type default)
			)
			(layer "B.Fab")
		)
		(fp_line
			(start 0.12065 0.3048)
			(end 0.67945 0.3048)
			(stroke
				(width 0.1)
				(type default)
			)
			(layer "B.Fab")
		)
		(fp_line
			(start 0.67945 0.3048)
			(end 0.67945 -0.305054)
			(stroke
				(width 0.1)
				(type default)
			)
			(layer "B.Fab")
		)
		(fp_line
			(start -0.120396 0.2794)
			(end 0.12065 0.2794)
			(stroke
				(width 0.1)
				(type default)
			)
			(layer "B.Fab")
		)
		(fp_line
			(start 0.12065 0.2794)
			(end 0.12065 0.3048)
			(stroke
				(width 0.1)
				(type default)
			)
			(layer "B.Fab")
		)
		(fp_line
			(start -0.12065 -0.2794)
			(end -0.12065 -0.3048)
			(stroke
				(width 0.1)
				(type default)
			)
			(layer "B.Fab")
		)
		(fp_line
			(start 0.12065 -0.2794)
			(end -0.12065 -0.2794)
			(stroke
				(width 0.1)
				(type default)
			)
			(layer "B.Fab")
		)
		(fp_line
			(start -0.67945 -0.3048)
			(end -0.67945 0.3048)
			(stroke
				(width 0.1)
				(type default)
			)
			(layer "B.Fab")
		)
		(fp_line
			(start -0.12065 -0.3048)
			(end -0.67945 -0.3048)
			(stroke
				(width 0.1)
				(type default)
			)
			(layer "B.Fab")
		)
		(fp_line
			(start 0.12065 -0.305054)
			(end 0.12065 -0.2794)
			(stroke
				(width 0.1)
				(type default)
			)
			(layer "B.Fab")
		)
		(fp_line
			(start 0.67945 -0.305054)
			(end 0.12065 -0.305054)
			(stroke
				(width 0.1)
				(type default)
			)
			(layer "B.Fab")
		)
		(pad "1" smd circle
			(at 0.40005 0 90)
			(size 0 0)
			(layers "B.Cu" "B.Mask" "B.Paste")
			(net "PWRGD_PLT_AUX_CPU1_LVT3_R")
		)
		(pad "2" smd circle
			(at -0.40005 0 90)
			(size 0 0)
			(layers "B.Cu" "B.Mask" "B.Paste")
			(net "PWRGD_PLT_AUX_CPU1_LVT3")
		)
	)
	(footprint ""
		(layer "B.Cu")
		(at 189.350396 -13.60043 -90)
		(property "Reference" "R594"
			(at 0 0 90)
			(layer "B.SilkS")
			(hide yes)
			(effects
				(font
					(size 1.27 1.27)
				)
				(justify mirror)
			)
		)
		(property "Value" ""
			(at 0 0 90)
			(layer "B.Fab")
			(effects
				(font
					(size 1.27 1.27)
				)
				(justify mirror)
			)
		)
		(duplicate_pad_numbers_are_jumpers no)
		(fp_line
			(start -0.7874 0.4064)
			(end 0.7874 0.4064)
			(stroke
				(width 0.1524)
				(type default)
			)
			(layer "B.SilkS")
		)
		(fp_line
			(start 0.7874 0.4064)
			(end 0.7874 -0.4064)
			(stroke
				(width 0.1524)
				(type default)
			)
			(layer "B.SilkS")
		)
		(fp_line
			(start -0.7874 -0.4064)
			(end -0.7874 0.4064)
			(stroke
				(width 0.1524)
				(type default)
			)
			(layer "B.SilkS")
		)
		(fp_line
			(start 0.7874 -0.4064)
			(end -0.7874 -0.4064)
			(stroke
				(width 0.1524)
				(type default)
			)
			(layer "B.SilkS")
		)
		(fp_line
			(start -0.67945 0.3048)
			(end -0.120396 0.3048)
			(stroke
				(width 0.1)
				(type default)
			)
			(layer "B.Fab")
		)
		(fp_line
			(start -0.120396 0.3048)
			(end -0.120396 0.2794)
			(stroke
				(width 0.1)
				(type default)
			)
			(layer "B.Fab")
		)
		(fp_line
			(start 0.12065 0.3048)
			(end 0.67945 0.3048)
			(stroke
				(width 0.1)
				(type default)
			)
			(layer "B.Fab")
		)
		(fp_line
			(start 0.67945 0.3048)
			(end 0.67945 -0.305054)
			(stroke
				(width 0.1)
				(type default)
			)
			(layer "B.Fab")
		)
		(fp_line
			(start -0.120396 0.2794)
			(end 0.12065 0.2794)
			(stroke
				(width 0.1)
				(type default)
			)
			(layer "B.Fab")
		)
		(fp_line
			(start 0.12065 0.2794)
			(end 0.12065 0.3048)
			(stroke
				(width 0.1)
				(type default)
			)
			(layer "B.Fab")
		)
		(fp_line
			(start -0.12065 -0.2794)
			(end -0.12065 -0.3048)
			(stroke
				(width 0.1)
				(type default)
			)
			(layer "B.Fab")
		)
		(fp_line
			(start 0.12065 -0.2794)
			(end -0.12065 -0.2794)
			(stroke
				(width 0.1)
				(type default)
			)
			(layer "B.Fab")
		)
		(fp_line
			(start -0.67945 -0.3048)
			(end -0.67945 0.3048)
			(stroke
				(width 0.1)
				(type default)
			)
			(layer "B.Fab")
		)
		(fp_line
			(start -0.12065 -0.3048)
			(end -0.67945 -0.3048)
			(stroke
				(width 0.1)
				(type default)
			)
			(layer "B.Fab")
		)
		(fp_line
			(start 0.12065 -0.305054)
			(end 0.12065 -0.2794)
			(stroke
				(width 0.1)
				(type default)
			)
			(layer "B.Fab")
		)
		(fp_line
			(start 0.67945 -0.305054)
			(end 0.12065 -0.305054)
			(stroke
				(width 0.1)
				(type default)
			)
			(layer "B.Fab")
		)
		(pad "1" smd circle
			(at 0.40005 0 90)
			(size 0 0)
			(layers "B.Cu" "B.Mask" "B.Paste")
			(net "I3C_SPD_DDRABCD_CPU0_BMC_R_SDA")
		)
		(pad "2" smd circle
			(at -0.40005 0 90)
			(size 0 0)
			(layers "B.Cu" "B.Mask" "B.Paste")
			(net "I3C_SPD_DDRABCD_CPU0_BMC_SDA")
		)
	)
	(footprint ""
		(layer "B.Cu")
		(at 211.634578 -316.14999 -90)
		(property "Reference" "D49"
			(at 4.116832 1.530858 0)
			(unlocked yes)
			(layer "B.SilkS")
			(effects
				(font
					(size 0.7874 0.5842)
					(thickness 0.1524)
				)
				(justify left mirror)
			)
		)
		(property "Value" ""
			(at 0 0 90)
			(layer "B.Fab")
			(effects
				(font
					(size 1.27 1.27)
				)
				(justify mirror)
			)
		)
		(duplicate_pad_numbers_are_jumpers no)
		(fp_line
			(start -2.050796 0.700024)
			(end 2.050796 0.700024)
			(stroke
				(width 0.1524)
				(type default)
			)
			(layer "B.SilkS")
		)
		(fp_line
			(start 2.050796 0.700024)
			(end 2.050796 -0.700024)
			(stroke
				(width 0.1524)
				(type default)
			)
			(layer "B.SilkS")
		)
		(fp_line
			(start -2.343404 0.6985)
			(end -2.216404 0.6985)
			(stroke
				(width 0.1524)
				(type default)
			)
			(layer "B.SilkS")
		)
		(fp_line
			(start -2.229104 0.6985)
			(end -2.051304 0.6985)
			(stroke
				(width 0.1524)
				(type default)
			)
			(layer "B.SilkS")
		)
		(fp_line
			(start -2.051304 0.6985)
			(end -2.051304 0.635)
			(stroke
				(width 0.1524)
				(type default)
			)
			(layer "B.SilkS")
		)
		(fp_line
			(start -2.152904 0.635)
			(end -2.152904 -0.6985)
			(stroke
				(width 0.1524)
				(type default)
			)
			(layer "B.SilkS")
		)
		(fp_line
			(start -2.051304 0.635)
			(end -2.152904 0.635)
			(stroke
				(width 0.1524)
				(type default)
			)
			(layer "B.SilkS")
		)
		(fp_line
			(start 0.30607 0.500126)
			(end -0.193802 0)
			(stroke
				(width 0.1524)
				(type default)
			)
			(layer "B.SilkS")
		)
		(fp_line
			(start -0.193802 0)
			(end 0.30607 -0.500126)
			(stroke
				(width 0.1524)
				(type default)
			)
			(layer "B.SilkS")
		)
		(fp_line
			(start -0.293878 -0.500126)
			(end -0.293878 0.500126)
			(stroke
				(width 0.1524)
				(type default)
			)
			(layer "B.SilkS")
		)
		(fp_line
			(start 0.30607 -0.500126)
			(end 0.30607 0.500126)
			(stroke
				(width 0.1524)
				(type default)
			)
			(layer "B.SilkS")
		)
		(fp_line
			(start -2.064004 -0.6731)
			(end -2.064004 -0.6985)
			(stroke
				(width 0.1524)
				(type default)
			)
			(layer "B.SilkS")
		)
		(fp_line
			(start -2.343404 -0.6985)
			(end -2.343404 0.6985)
			(stroke
				(width 0.1524)
				(type default)
			)
			(layer "B.SilkS")
		)
		(fp_line
			(start -2.229104 -0.6985)
			(end -2.229104 0.6985)
			(stroke
				(width 0.1524)
				(type default)
			)
			(layer "B.SilkS")
		)
		(fp_line
			(start -2.152904 -0.6985)
			(end -2.343404 -0.6985)
			(stroke
				(width 0.1524)
				(type default)
			)
			(layer "B.SilkS")
		)
		(fp_line
			(start -2.064004 -0.6985)
			(end -2.229104 -0.6985)
			(stroke
				(width 0.1524)
				(type default)
			)
			(layer "B.SilkS")
		)
		(fp_line
			(start -2.050796 -0.700024)
			(end -2.050796 0.700024)
			(stroke
				(width 0.1524)
				(type default)
			)
			(layer "B.SilkS")
		)
		(fp_line
			(start 2.050796 -0.700024)
			(end -2.050796 -0.700024)
			(stroke
				(width 0.1524)
				(type default)
			)
			(layer "B.SilkS")
		)
		(fp_line
			(start -0.899922 0.700024)
			(end 0.899922 0.700024)
			(stroke
				(width 0.1)
				(type default)
			)
			(layer "B.Fab")
		)
		(fp_line
			(start 0.899922 0.700024)
			(end 0.899922 -0.700024)
			(stroke
				(width 0.1)
				(type default)
			)
			(layer "B.Fab")
		)
		(fp_line
			(start -0.899922 -0.700024)
			(end -0.899922 0.700024)
			(stroke
				(width 0.1)
				(type default)
			)
			(layer "B.Fab")
		)
		(fp_line
			(start 0.899922 -0.700024)
			(end -0.899922 -0.700024)
			(stroke
				(width 0.1)
				(type default)
			)
			(layer "B.Fab")
		)
		(fp_text user "-"
			(at -0.268478 1.839468 90)
			(unlocked yes)
			(layer "B.SilkS")
			(effects
				(font
					(size 1.905 1.4224)
					(thickness 0.1524)
				)
				(justify left mirror)
			)
		)
		(fp_text user "+"
			(at 3.123946 0.762 180)
			(unlocked yes)
			(layer "B.SilkS")
			(effects
				(font
					(size 1.905 1.4224)
					(thickness 0.1524)
				)
				(justify left mirror)
			)
		)
		(fp_text user "+"
			(at 3.123946 0.762 180)
			(unlocked yes)
			(layer "B.Fab")
			(effects
				(font
					(size 1.905 1.4224)
					(thickness 0.1524)
				)
				(justify left mirror)
			)
		)
		(fp_text user "-"
			(at -3.880104 0.23495 90)
			(unlocked yes)
			(layer "B.Fab")
			(effects
				(font
					(size 1.905 1.4224)
					(thickness 0.1524)
				)
				(justify left mirror)
			)
		)
		(pad "1" smd rect
			(at 1.199896 0 180)
			(size 0.6604 1.3716)
			(layers "B.Cu" "B.Mask" "B.Paste")
			(net "PWRGD_FAIL_CPU1_GH_R1")
		)
		(pad "2" smd rect
			(at -1.199896 0)
			(size 0.6604 1.3716)
			(layers "B.Cu" "B.Mask" "B.Paste")
			(net "P3V3_AUX")
		)
	)
	(footprint ""
		(layer "B.Cu")
		(at 335.920588 -48.63338 90)
		(property "Reference" "C1183"
			(at 0 0 90)
			(layer "B.SilkS")
			(hide yes)
			(effects
				(font
					(size 1.27 1.27)
				)
				(justify mirror)
			)
		)
		(property "Value" ""
			(at 0 0 90)
			(layer "B.Fab")
			(effects
				(font
					(size 1.27 1.27)
				)
				(justify mirror)
			)
		)
		(duplicate_pad_numbers_are_jumpers no)
		(fp_line
			(start 0.7874 -0.4064)
			(end -0.7874 -0.4064)
			(stroke
				(width 0.1524)
				(type default)
			)
			(layer "B.SilkS")
		)
		(fp_line
			(start -0.7874 -0.4064)
			(end -0.7874 0.4064)
			(stroke
				(width 0.1524)
				(type default)
			)
			(layer "B.SilkS")
		)
		(fp_line
			(start 0.7874 0.4064)
			(end 0.7874 -0.4064)
			(stroke
				(width 0.1524)
				(type default)
			)
			(layer "B.SilkS")
		)
		(fp_line
			(start -0.7874 0.4064)
			(end 0.7874 0.4064)
			(stroke
				(width 0.1524)
				(type default)
			)
			(layer "B.SilkS")
		)
		(fp_line
			(start 0.67945 -0.305054)
			(end 0.12065 -0.305054)
			(stroke
				(width 0.1)
				(type default)
			)
			(layer "B.Fab")
		)
		(fp_line
			(start 0.12065 -0.305054)
			(end 0.12065 -0.2794)
			(stroke
				(width 0.1)
				(type default)
			)
			(layer "B.Fab")
		)
		(fp_line
			(start -0.12065 -0.3048)
			(end -0.67945 -0.3048)
			(stroke
				(width 0.1)
				(type default)
			)
			(layer "B.Fab")
		)
		(fp_line
			(start -0.67945 -0.3048)
			(end -0.67945 0.3048)
			(stroke
				(width 0.1)
				(type default)
			)
			(layer "B.Fab")
		)
		(fp_line
			(start 0.12065 -0.2794)
			(end -0.12065 -0.2794)
			(stroke
				(width 0.1)
				(type default)
			)
			(layer "B.Fab")
		)
		(fp_line
			(start -0.12065 -0.2794)
			(end -0.12065 -0.3048)
			(stroke
				(width 0.1)
				(type default)
			)
			(layer "B.Fab")
		)
		(fp_line
			(start 0.12065 0.2794)
			(end 0.12065 0.3048)
			(stroke
				(width 0.1)
				(type default)
			)
			(layer "B.Fab")
		)
		(fp_line
			(start -0.120396 0.2794)
			(end 0.12065 0.2794)
			(stroke
				(width 0.1)
				(type default)
			)
			(layer "B.Fab")
		)
		(fp_line
			(start 0.67945 0.3048)
			(end 0.67945 -0.305054)
			(stroke
				(width 0.1)
				(type default)
			)
			(layer "B.Fab")
		)
		(fp_line
			(start 0.12065 0.3048)
			(end 0.67945 0.3048)
			(stroke
				(width 0.1)
				(type default)
			)
			(layer "B.Fab")
		)
		(fp_line
			(start -0.120396 0.3048)
			(end -0.120396 0.2794)
			(stroke
				(width 0.1)
				(type default)
			)
			(layer "B.Fab")
		)
		(fp_line
			(start -0.67945 0.3048)
			(end -0.120396 0.3048)
			(stroke
				(width 0.1)
				(type default)
			)
			(layer "B.Fab")
		)
		(pad "1" smd circle
			(at 0.40005 0 270)
			(size 0 0)
			(layers "B.Cu" "B.Mask" "B.Paste")
			(net "P1V05_PCH_AUX")
		)
		(pad "2" smd circle
			(at -0.40005 0 270)
			(size 0 0)
			(layers "B.Cu" "B.Mask" "B.Paste")
			(net "GND")
		)
	)
	(footprint ""
		(layer "B.Cu")
		(at 79.414624 -184.096152 90)
		(property "Reference" "R345"
			(at 0 0 90)
			(layer "B.SilkS")
			(hide yes)
			(effects
				(font
					(size 1.27 1.27)
				)
				(justify mirror)
			)
		)
		(property "Value" ""
			(at 0 0 90)
			(layer "B.Fab")
			(effects
				(font
					(size 1.27 1.27)
				)
				(justify mirror)
			)
		)
		(duplicate_pad_numbers_are_jumpers no)
		(fp_line
			(start 0.7874 -0.4064)
			(end -0.7874 -0.4064)
			(stroke
				(width 0.1524)
				(type default)
			)
			(layer "B.SilkS")
		)
		(fp_line
			(start -0.7874 -0.4064)
			(end -0.7874 0.4064)
			(stroke
				(width 0.1524)
				(type default)
			)
			(layer "B.SilkS")
		)
		(fp_line
			(start 0.7874 0.4064)
			(end 0.7874 -0.4064)
			(stroke
				(width 0.1524)
				(type default)
			)
			(layer "B.SilkS")
		)
		(fp_line
			(start -0.7874 0.4064)
			(end 0.7874 0.4064)
			(stroke
				(width 0.1524)
				(type default)
			)
			(layer "B.SilkS")
		)
		(fp_line
			(start 0.67945 -0.305054)
			(end 0.12065 -0.305054)
			(stroke
				(width 0.1)
				(type default)
			)
			(layer "B.Fab")
		)
		(fp_line
			(start 0.12065 -0.305054)
			(end 0.12065 -0.2794)
			(stroke
				(width 0.1)
				(type default)
			)
			(layer "B.Fab")
		)
		(fp_line
			(start -0.12065 -0.3048)
			(end -0.67945 -0.3048)
			(stroke
				(width 0.1)
				(type default)
			)
			(layer "B.Fab")
		)
		(fp_line
			(start -0.67945 -0.3048)
			(end -0.67945 0.3048)
			(stroke
				(width 0.1)
				(type default)
			)
			(layer "B.Fab")
		)
		(fp_line
			(start 0.12065 -0.2794)
			(end -0.12065 -0.2794)
			(stroke
				(width 0.1)
				(type default)
			)
			(layer "B.Fab")
		)
		(fp_line
			(start -0.12065 -0.2794)
			(end -0.12065 -0.3048)
			(stroke
				(width 0.1)
				(type default)
			)
			(layer "B.Fab")
		)
		(fp_line
			(start 0.12065 0.2794)
			(end 0.12065 0.3048)
			(stroke
				(width 0.1)
				(type default)
			)
			(layer "B.Fab")
		)
		(fp_line
			(start -0.120396 0.2794)
			(end 0.12065 0.2794)
			(stroke
				(width 0.1)
				(type default)
			)
			(layer "B.Fab")
		)
		(fp_line
			(start 0.67945 0.3048)
			(end 0.67945 -0.305054)
			(stroke
				(width 0.1)
				(type default)
			)
			(layer "B.Fab")
		)
		(fp_line
			(start 0.12065 0.3048)
			(end 0.67945 0.3048)
			(stroke
				(width 0.1)
				(type default)
			)
			(layer "B.Fab")
		)
		(fp_line
			(start -0.120396 0.3048)
			(end -0.120396 0.2794)
			(stroke
				(width 0.1)
				(type default)
			)
			(layer "B.Fab")
		)
		(fp_line
			(start -0.67945 0.3048)
			(end -0.120396 0.3048)
			(stroke
				(width 0.1)
				(type default)
			)
			(layer "B.Fab")
		)
		(pad "1" smd circle
			(at 0.40005 0 270)
			(size 0 0)
			(layers "B.Cu" "B.Mask" "B.Paste")
			(net "H_CPU1_ERR2_LVC1_R_N")
		)
		(pad "2" smd circle
			(at -0.40005 0 270)
			(size 0 0)
			(layers "B.Cu" "B.Mask" "B.Paste")
			(net "H_CPU_ERR2_LVC1_R_N")
		)
	)
	(footprint ""
		(layer "B.Cu")
		(at 36.956238 -131.77774)
		(property "Reference" "R2572"
			(at 0 0 0)
			(layer "B.SilkS")
			(hide yes)
			(effects
				(font
					(size 1.27 1.27)
				)
				(justify mirror)
			)
		)
		(property "Value" ""
			(at 0 0 0)
			(layer "B.Fab")
			(effects
				(font
					(size 1.27 1.27)
				)
				(justify mirror)
			)
		)
		(duplicate_pad_numbers_are_jumpers no)
		(fp_line
			(start -0.7874 -0.4064)
			(end -0.7874 0.4064)
			(stroke
				(width 0.1524)
				(type default)
			)
			(layer "B.SilkS")
		)
		(fp_line
			(start -0.7874 0.4064)
			(end 0.7874 0.4064)
			(stroke
				(width 0.1524)
				(type default)
			)
			(layer "B.SilkS")
		)
		(fp_line
			(start 0.7874 -0.4064)
			(end -0.7874 -0.4064)
			(stroke
				(width 0.1524)
				(type default)
			)
			(layer "B.SilkS")
		)
		(fp_line
			(start 0.7874 0.4064)
			(end 0.7874 -0.4064)
			(stroke
				(width 0.1524)
				(type default)
			)
			(layer "B.SilkS")
		)
		(fp_line
			(start -0.67945 -0.3048)
			(end -0.67945 0.3048)
			(stroke
				(width 0.1)
				(type default)
			)
			(layer "B.Fab")
		)
		(fp_line
			(start -0.67945 0.3048)
			(end -0.120396 0.3048)
			(stroke
				(width 0.1)
				(type default)
			)
			(layer "B.Fab")
		)
		(fp_line
			(start -0.12065 -0.3048)
			(end -0.67945 -0.3048)
			(stroke
				(width 0.1)
				(type default)
			)
			(layer "B.Fab")
		)
		(fp_line
			(start -0.12065 -0.2794)
			(end -0.12065 -0.3048)
			(stroke
				(width 0.1)
				(type default)
			)
			(layer "B.Fab")
		)
		(fp_line
			(start -0.120396 0.2794)
			(end 0.12065 0.2794)
			(stroke
				(width 0.1)
				(type default)
			)
			(layer "B.Fab")
		)
		(fp_line
			(start -0.120396 0.3048)
			(end -0.120396 0.2794)
			(stroke
				(width 0.1)
				(type default)
			)
			(layer "B.Fab")
		)
		(fp_line
			(start 0.12065 -0.305054)
			(end 0.12065 -0.2794)
			(stroke
				(width 0.1)
				(type default)
			)
			(layer "B.Fab")
		)
		(fp_line
			(start 0.12065 -0.2794)
			(end -0.12065 -0.2794)
			(stroke
				(width 0.1)
				(type default)
			)
			(layer "B.Fab")
		)
		(fp_line
			(start 0.12065 0.2794)
			(end 0.12065 0.3048)
			(stroke
				(width 0.1)
				(type default)
			)
			(layer "B.Fab")
		)
		(fp_line
			(start 0.12065 0.3048)
			(end 0.67945 0.3048)
			(stroke
				(width 0.1)
				(type default)
			)
			(layer "B.Fab")
		)
		(fp_line
			(start 0.67945 -0.305054)
			(end 0.12065 -0.305054)
			(stroke
				(width 0.1)
				(type default)
			)
			(layer "B.Fab")
		)
		(fp_line
			(start 0.67945 0.3048)
			(end 0.67945 -0.305054)
			(stroke
				(width 0.1)
				(type default)
			)
			(layer "B.Fab")
		)
		(pad "1" smd circle
			(at 0.40005 0 180)
			(size 0 0)
			(layers "B.Cu" "B.Mask" "B.Paste")
			(net "PWRGD_PVCCFA_EHV_CPU1")
		)
		(pad "2" smd circle
			(at -0.40005 0 180)
			(size 0 0)
			(layers "B.Cu" "B.Mask" "B.Paste")
			(net "PWRGD_PVCCFA_EHV_CPU1_R")
		)
	)
	(footprint ""
		(layer "B.Cu")
		(at 84.974684 -188.035692 90)
		(property "Reference" "R304"
			(at 0 0 90)
			(layer "B.SilkS")
			(hide yes)
			(effects
				(font
					(size 1.27 1.27)
				)
				(justify mirror)
			)
		)
		(property "Value" ""
			(at 0 0 90)
			(layer "B.Fab")
			(effects
				(font
					(size 1.27 1.27)
				)
				(justify mirror)
			)
		)
		(duplicate_pad_numbers_are_jumpers no)
		(fp_line
			(start 0.7874 -0.4064)
			(end -0.7874 -0.4064)
			(stroke
				(width 0.1524)
				(type default)
			)
			(layer "B.SilkS")
		)
		(fp_line
			(start -0.7874 -0.4064)
			(end -0.7874 0.4064)
			(stroke
				(width 0.1524)
				(type default)
			)
			(layer "B.SilkS")
		)
		(fp_line
			(start 0.7874 0.4064)
			(end 0.7874 -0.4064)
			(stroke
				(width 0.1524)
				(type default)
			)
			(layer "B.SilkS")
		)
		(fp_line
			(start -0.7874 0.4064)
			(end 0.7874 0.4064)
			(stroke
				(width 0.1524)
				(type default)
			)
			(layer "B.SilkS")
		)
		(fp_line
			(start 0.67945 -0.305054)
			(end 0.12065 -0.305054)
			(stroke
				(width 0.1)
				(type default)
			)
			(layer "B.Fab")
		)
		(fp_line
			(start 0.12065 -0.305054)
			(end 0.12065 -0.2794)
			(stroke
				(width 0.1)
				(type default)
			)
			(layer "B.Fab")
		)
		(fp_line
			(start -0.12065 -0.3048)
			(end -0.67945 -0.3048)
			(stroke
				(width 0.1)
				(type default)
			)
			(layer "B.Fab")
		)
		(fp_line
			(start -0.67945 -0.3048)
			(end -0.67945 0.3048)
			(stroke
				(width 0.1)
				(type default)
			)
			(layer "B.Fab")
		)
		(fp_line
			(start 0.12065 -0.2794)
			(end -0.12065 -0.2794)
			(stroke
				(width 0.1)
				(type default)
			)
			(layer "B.Fab")
		)
		(fp_line
			(start -0.12065 -0.2794)
			(end -0.12065 -0.3048)
			(stroke
				(width 0.1)
				(type default)
			)
			(layer "B.Fab")
		)
		(fp_line
			(start 0.12065 0.2794)
			(end 0.12065 0.3048)
			(stroke
				(width 0.1)
				(type default)
			)
			(layer "B.Fab")
		)
		(fp_line
			(start -0.120396 0.2794)
			(end 0.12065 0.2794)
			(stroke
				(width 0.1)
				(type default)
			)
			(layer "B.Fab")
		)
		(fp_line
			(start 0.67945 0.3048)
			(end 0.67945 -0.305054)
			(stroke
				(width 0.1)
				(type default)
			)
			(layer "B.Fab")
		)
		(fp_line
			(start 0.12065 0.3048)
			(end 0.67945 0.3048)
			(stroke
				(width 0.1)
				(type default)
			)
			(layer "B.Fab")
		)
		(fp_line
			(start -0.120396 0.3048)
			(end -0.120396 0.2794)
			(stroke
				(width 0.1)
				(type default)
			)
			(layer "B.Fab")
		)
		(fp_line
			(start -0.67945 0.3048)
			(end -0.120396 0.3048)
			(stroke
				(width 0.1)
				(type default)
			)
			(layer "B.Fab")
		)
		(pad "1" smd circle
			(at 0.40005 0 270)
			(size 0 0)
			(layers "B.Cu" "B.Mask" "B.Paste")
			(net "H_CPU1_RMCA_LVC1_R_N")
		)
		(pad "2" smd circle
			(at -0.40005 0 270)
			(size 0 0)
			(layers "B.Cu" "B.Mask" "B.Paste")
			(net "H_CPU_RMCA_LVC1_R_N")
		)
	)
	(footprint ""
		(layer "B.Cu")
		(at 204.088746 -319.268856 180)
		(property "Reference" "C72"
			(at 0 0 0)
			(layer "B.SilkS")
			(hide yes)
			(effects
				(font
					(size 1.27 1.27)
				)
				(justify mirror)
			)
		)
		(property "Value" ""
			(at 0 0 0)
			(layer "B.Fab")
			(effects
				(font
					(size 1.27 1.27)
				)
				(justify mirror)
			)
		)
		(duplicate_pad_numbers_are_jumpers no)
		(fp_line
			(start 0.7874 0.4064)
			(end 0.7874 -0.4064)
			(stroke
				(width 0.1524)
				(type default)
			)
			(layer "B.SilkS")
		)
		(fp_line
			(start 0.7874 -0.4064)
			(end -0.7874 -0.4064)
			(stroke
				(width 0.1524)
				(type default)
			)
			(layer "B.SilkS")
		)
		(fp_line
			(start -0.7874 0.4064)
			(end 0.7874 0.4064)
			(stroke
				(width 0.1524)
				(type default)
			)
			(layer "B.SilkS")
		)
		(fp_line
			(start -0.7874 -0.4064)
			(end -0.7874 0.4064)
			(stroke
				(width 0.1524)
				(type default)
			)
			(layer "B.SilkS")
		)
		(fp_line
			(start 0.67945 0.3048)
			(end 0.67945 -0.305054)
			(stroke
				(width 0.1)
				(type default)
			)
			(layer "B.Fab")
		)
		(fp_line
			(start 0.67945 -0.305054)
			(end 0.12065 -0.305054)
			(stroke
				(width 0.1)
				(type default)
			)
			(layer "B.Fab")
		)
		(fp_line
			(start 0.12065 0.3048)
			(end 0.67945 0.3048)
			(stroke
				(width 0.1)
				(type default)
			)
			(layer "B.Fab")
		)
		(fp_line
			(start 0.12065 0.2794)
			(end 0.12065 0.3048)
			(stroke
				(width 0.1)
				(type default)
			)
			(layer "B.Fab")
		)
		(fp_line
			(start 0.12065 -0.2794)
			(end -0.12065 -0.2794)
			(stroke
				(width 0.1)
				(type default)
			)
			(layer "B.Fab")
		)
		(fp_line
			(start 0.12065 -0.305054)
			(end 0.12065 -0.2794)
			(stroke
				(width 0.1)
				(type default)
			)
			(layer "B.Fab")
		)
		(fp_line
			(start -0.120396 0.3048)
			(end -0.120396 0.2794)
			(stroke
				(width 0.1)
				(type default)
			)
			(layer "B.Fab")
		)
		(fp_line
			(start -0.120396 0.2794)
			(end 0.12065 0.2794)
			(stroke
				(width 0.1)
				(type default)
			)
			(layer "B.Fab")
		)
		(fp_line
			(start -0.12065 -0.2794)
			(end -0.12065 -0.3048)
			(stroke
				(width 0.1)
				(type default)
			)
			(layer "B.Fab")
		)
		(fp_line
			(start -0.12065 -0.3048)
			(end -0.67945 -0.3048)
			(stroke
				(width 0.1)
				(type default)
			)
			(layer "B.Fab")
		)
		(fp_line
			(start -0.67945 0.3048)
			(end -0.120396 0.3048)
			(stroke
				(width 0.1)
				(type default)
			)
			(layer "B.Fab")
		)
		(fp_line
			(start -0.67945 -0.3048)
			(end -0.67945 0.3048)
			(stroke
				(width 0.1)
				(type default)
			)
			(layer "B.Fab")
		)
		(pad "1" smd circle
			(at 0.40005 0)
			(size 0 0)
			(layers "B.Cu" "B.Mask" "B.Paste")
			(net "P3V3_AUX")
		)
		(pad "2" smd circle
			(at -0.40005 0)
			(size 0 0)
			(layers "B.Cu" "B.Mask" "B.Paste")
			(net "GND")
		)
	)
	(footprint ""
		(layer "B.Cu")
		(at 162.889946 -321.554856 -90)
		(property "Reference" "C92"
			(at 0 0 90)
			(layer "B.SilkS")
			(hide yes)
			(effects
				(font
					(size 1.27 1.27)
				)
				(justify mirror)
			)
		)
		(property "Value" ""
			(at 0 0 90)
			(layer "B.Fab")
			(effects
				(font
					(size 1.27 1.27)
				)
				(justify mirror)
			)
		)
		(duplicate_pad_numbers_are_jumpers no)
		(fp_line
			(start -1.524 0.762)
			(end 1.524 0.762)
			(stroke
				(width 0.1524)
				(type default)
			)
			(layer "B.SilkS")
		)
		(fp_line
			(start 1.524 0.762)
			(end 1.524 -0.762)
			(stroke
				(width 0.1524)
				(type default)
			)
			(layer "B.SilkS")
		)
		(fp_line
			(start -1.524 -0.762)
			(end -1.524 0.762)
			(stroke
				(width 0.1524)
				(type default)
			)
			(layer "B.SilkS")
		)
		(fp_line
			(start 1.524 -0.762)
			(end -1.524 -0.762)
			(stroke
				(width 0.1524)
				(type default)
			)
			(layer "B.SilkS")
		)
		(fp_line
			(start -1.1049 0.724916)
			(end -1.1049 -0.724916)
			(stroke
				(width 0.1)
				(type default)
			)
			(layer "B.Fab")
		)
		(fp_line
			(start 1.1049 0.724916)
			(end -1.1049 0.724916)
			(stroke
				(width 0.1)
				(type default)
			)
			(layer "B.Fab")
		)
		(fp_line
			(start -1.1049 -0.724916)
			(end 1.1049 -0.724916)
			(stroke
				(width 0.1)
				(type default)
			)
			(layer "B.Fab")
		)
		(fp_line
			(start 1.1049 -0.724916)
			(end 1.1049 0.724916)
			(stroke
				(width 0.1)
				(type default)
			)
			(layer "B.Fab")
		)
		(pad "1" smd rect
			(at 0.889 0 270)
			(size 1.016 1.27)
			(layers "B.Cu" "B.Mask" "B.Paste")
			(net "P12V_S3_AUX_CPU1_NVDIMM")
		)
		(pad "2" smd rect
			(at -0.889 0 270)
			(size 1.016 1.27)
			(layers "B.Cu" "B.Mask" "B.Paste")
			(net "GND")
		)
	)
	(footprint ""
		(layer "B.Cu")
		(at 176.955704 -112.175544)
		(property "Reference" "C1903"
			(at 0 0 0)
			(layer "B.SilkS")
			(hide yes)
			(effects
				(font
					(size 1.27 1.27)
				)
				(justify mirror)
			)
		)
		(property "Value" ""
			(at 0 0 0)
			(layer "B.Fab")
			(effects
				(font
					(size 1.27 1.27)
				)
				(justify mirror)
			)
		)
		(duplicate_pad_numbers_are_jumpers no)
		(fp_line
			(start -0.69215 -0.2921)
			(end -0.69215 0.2921)
			(stroke
				(width 0.1524)
				(type default)
			)
			(layer "B.SilkS")
		)
		(fp_line
			(start -0.69215 0.2921)
			(end 0.69215 0.2921)
			(stroke
				(width 0.1524)
				(type default)
			)
			(layer "B.SilkS")
		)
		(fp_line
			(start 0.69215 -0.2921)
			(end -0.69215 -0.2921)
			(stroke
				(width 0.1524)
				(type default)
			)
			(layer "B.SilkS")
		)
		(fp_line
			(start 0.69215 0.2921)
			(end 0.69215 -0.2921)
			(stroke
				(width 0.1524)
				(type default)
			)
			(layer "B.SilkS")
		)
		(fp_line
			(start -0.51435 -0.2794)
			(end -0.51435 0.2794)
			(stroke
				(width 0.1)
				(type default)
			)
			(layer "B.Fab")
		)
		(fp_line
			(start -0.51435 0.2794)
			(end 0.51435 0.2794)
			(stroke
				(width 0.1)
				(type default)
			)
			(layer "B.Fab")
		)
		(fp_line
			(start 0.51435 -0.2794)
			(end -0.51435 -0.2794)
			(stroke
				(width 0.1)
				(type default)
			)
			(layer "B.Fab")
		)
		(fp_line
			(start 0.51435 0.2794)
			(end 0.51435 -0.2794)
			(stroke
				(width 0.1)
				(type default)
			)
			(layer "B.Fab")
		)
		(pad "1" smd circle
			(at 0.40005 0 180)
			(size 0 0)
			(layers "B.Cu" "B.Mask" "B.Paste")
			(net "VCC_PLD_CORE")
		)
		(pad "2" smd circle
			(at -0.40005 0 180)
			(size 0 0)
			(layers "B.Cu" "B.Mask" "B.Paste")
			(net "GND")
		)
		(zone
			(layer "B.Cu")
			(hatch none 0.5)
			(connect_pads
				(clearance 0)
			)
			(min_thickness 0.25)
			(keepout
				(tracks not_allowed)
				(vias allowed)
				(pads allowed)
				(copperpour not_allowed)
				(footprints allowed)
			)
			(placement
				(enabled no)
				(sheetname "")
			)
			(fill
				(thermal_gap 0.5)
				(thermal_bridge_width 0.5)
				(island_removal_mode 0)
			)
			(polygon
				(pts
					(xy 177.146204 -112.087914) (xy 177.054764 -112.029748) (xy 176.855374 -112.029748) (xy 176.765204 -112.087914)
					(xy 176.765204 -112.263174) (xy 176.855374 -112.321594) (xy 177.054764 -112.321594) (xy 177.146204 -112.263428)
				)
			)
		)
	)
	(footprint ""
		(layer "B.Cu")
		(at 455.1299 -71.247508 90)
		(property "Reference" "PC571"
			(at 0 0 90)
			(layer "B.SilkS")
			(hide yes)
			(effects
				(font
					(size 1.27 1.27)
				)
				(justify mirror)
			)
		)
		(property "Value" ""
			(at 0 0 90)
			(layer "B.Fab")
			(effects
				(font
					(size 1.27 1.27)
				)
				(justify mirror)
			)
		)
		(duplicate_pad_numbers_are_jumpers no)
		(fp_line
			(start 1.524 -0.762)
			(end -1.524 -0.762)
			(stroke
				(width 0.1524)
				(type default)
			)
			(layer "B.SilkS")
		)
		(fp_line
			(start -1.524 -0.762)
			(end -1.524 0.762)
			(stroke
				(width 0.1524)
				(type default)
			)
			(layer "B.SilkS")
		)
		(fp_line
			(start 1.524 0.762)
			(end 1.524 -0.762)
			(stroke
				(width 0.1524)
				(type default)
			)
			(layer "B.SilkS")
		)
		(fp_line
			(start -1.524 0.762)
			(end 1.524 0.762)
			(stroke
				(width 0.1524)
				(type default)
			)
			(layer "B.SilkS")
		)
		(fp_line
			(start 1.1049 -0.724916)
			(end 1.1049 0.724916)
			(stroke
				(width 0.1)
				(type default)
			)
			(layer "B.Fab")
		)
		(fp_line
			(start -1.1049 -0.724916)
			(end 1.1049 -0.724916)
			(stroke
				(width 0.1)
				(type default)
			)
			(layer "B.Fab")
		)
		(fp_line
			(start 1.1049 0.724916)
			(end -1.1049 0.724916)
			(stroke
				(width 0.1)
				(type default)
			)
			(layer "B.Fab")
		)
		(fp_line
			(start -1.1049 0.724916)
			(end -1.1049 -0.724916)
			(stroke
				(width 0.1)
				(type default)
			)
			(layer "B.Fab")
		)
		(pad "1" smd rect
			(at 0.889 0 90)
			(size 1.016 1.27)
			(layers "B.Cu" "B.Mask" "B.Paste")
			(net "SW_P3V3_AUX_FLT")
		)
		(pad "2" smd rect
			(at -0.889 0 90)
			(size 1.016 1.27)
			(layers "B.Cu" "B.Mask" "B.Paste")
			(net "GND")
		)
	)
	(footprint ""
		(layer "B.Cu")
		(at 334.662018 -188.92647 -90)
		(property "Reference" "R19"
			(at 0 0 90)
			(layer "B.SilkS")
			(hide yes)
			(effects
				(font
					(size 1.27 1.27)
				)
				(justify mirror)
			)
		)
		(property "Value" ""
			(at 0 0 90)
			(layer "B.Fab")
			(effects
				(font
					(size 1.27 1.27)
				)
				(justify mirror)
			)
		)
		(duplicate_pad_numbers_are_jumpers no)
		(fp_line
			(start -0.7874 0.4064)
			(end 0.7874 0.4064)
			(stroke
				(width 0.1524)
				(type default)
			)
			(layer "B.SilkS")
		)
		(fp_line
			(start 0.7874 0.4064)
			(end 0.7874 -0.4064)
			(stroke
				(width 0.1524)
				(type default)
			)
			(layer "B.SilkS")
		)
		(fp_line
			(start -0.7874 -0.4064)
			(end -0.7874 0.4064)
			(stroke
				(width 0.1524)
				(type default)
			)
			(layer "B.SilkS")
		)
		(fp_line
			(start 0.7874 -0.4064)
			(end -0.7874 -0.4064)
			(stroke
				(width 0.1524)
				(type default)
			)
			(layer "B.SilkS")
		)
		(fp_line
			(start -0.67945 0.3048)
			(end -0.120396 0.3048)
			(stroke
				(width 0.1)
				(type default)
			)
			(layer "B.Fab")
		)
		(fp_line
			(start -0.120396 0.3048)
			(end -0.120396 0.2794)
			(stroke
				(width 0.1)
				(type default)
			)
			(layer "B.Fab")
		)
		(fp_line
			(start 0.12065 0.3048)
			(end 0.67945 0.3048)
			(stroke
				(width 0.1)
				(type default)
			)
			(layer "B.Fab")
		)
		(fp_line
			(start 0.67945 0.3048)
			(end 0.67945 -0.305054)
			(stroke
				(width 0.1)
				(type default)
			)
			(layer "B.Fab")
		)
		(fp_line
			(start -0.120396 0.2794)
			(end 0.12065 0.2794)
			(stroke
				(width 0.1)
				(type default)
			)
			(layer "B.Fab")
		)
		(fp_line
			(start 0.12065 0.2794)
			(end 0.12065 0.3048)
			(stroke
				(width 0.1)
				(type default)
			)
			(layer "B.Fab")
		)
		(fp_line
			(start -0.12065 -0.2794)
			(end -0.12065 -0.3048)
			(stroke
				(width 0.1)
				(type default)
			)
			(layer "B.Fab")
		)
		(fp_line
			(start 0.12065 -0.2794)
			(end -0.12065 -0.2794)
			(stroke
				(width 0.1)
				(type default)
			)
			(layer "B.Fab")
		)
		(fp_line
			(start -0.67945 -0.3048)
			(end -0.67945 0.3048)
			(stroke
				(width 0.1)
				(type default)
			)
			(layer "B.Fab")
		)
		(fp_line
			(start -0.12065 -0.3048)
			(end -0.67945 -0.3048)
			(stroke
				(width 0.1)
				(type default)
			)
			(layer "B.Fab")
		)
		(fp_line
			(start 0.12065 -0.305054)
			(end 0.12065 -0.2794)
			(stroke
				(width 0.1)
				(type default)
			)
			(layer "B.Fab")
		)
		(fp_line
			(start 0.67945 -0.305054)
			(end 0.12065 -0.305054)
			(stroke
				(width 0.1)
				(type default)
			)
			(layer "B.Fab")
		)
		(pad "1" smd circle
			(at 0.40005 0 90)
			(size 0 0)
			(layers "B.Cu" "B.Mask" "B.Paste")
			(net "PVNN_TERM_CPU0")
		)
		(pad "2" smd circle
			(at -0.40005 0 90)
			(size 0 0)
			(layers "B.Cu" "B.Mask" "B.Paste")
			(net "DBP_CPU_MBP1_GTL_N")
		)
	)
	(footprint ""
		(layer "B.Cu")
		(at 263.637014 -319.263776 180)
		(property "Reference" "C23"
			(at 0 0 0)
			(layer "B.SilkS")
			(hide yes)
			(effects
				(font
					(size 1.27 1.27)
				)
				(justify mirror)
			)
		)
		(property "Value" ""
			(at 0 0 0)
			(layer "B.Fab")
			(effects
				(font
					(size 1.27 1.27)
				)
				(justify mirror)
			)
		)
		(duplicate_pad_numbers_are_jumpers no)
		(fp_line
			(start 0.7874 0.4064)
			(end 0.7874 -0.4064)
			(stroke
				(width 0.1524)
				(type default)
			)
			(layer "B.SilkS")
		)
		(fp_line
			(start 0.7874 -0.4064)
			(end -0.7874 -0.4064)
			(stroke
				(width 0.1524)
				(type default)
			)
			(layer "B.SilkS")
		)
		(fp_line
			(start -0.7874 0.4064)
			(end 0.7874 0.4064)
			(stroke
				(width 0.1524)
				(type default)
			)
			(layer "B.SilkS")
		)
		(fp_line
			(start -0.7874 -0.4064)
			(end -0.7874 0.4064)
			(stroke
				(width 0.1524)
				(type default)
			)
			(layer "B.SilkS")
		)
		(fp_line
			(start 0.67945 0.3048)
			(end 0.67945 -0.305054)
			(stroke
				(width 0.1)
				(type default)
			)
			(layer "B.Fab")
		)
		(fp_line
			(start 0.67945 -0.305054)
			(end 0.12065 -0.305054)
			(stroke
				(width 0.1)
				(type default)
			)
			(layer "B.Fab")
		)
		(fp_line
			(start 0.12065 0.3048)
			(end 0.67945 0.3048)
			(stroke
				(width 0.1)
				(type default)
			)
			(layer "B.Fab")
		)
		(fp_line
			(start 0.12065 0.2794)
			(end 0.12065 0.3048)
			(stroke
				(width 0.1)
				(type default)
			)
			(layer "B.Fab")
		)
		(fp_line
			(start 0.12065 -0.2794)
			(end -0.12065 -0.2794)
			(stroke
				(width 0.1)
				(type default)
			)
			(layer "B.Fab")
		)
		(fp_line
			(start 0.12065 -0.305054)
			(end 0.12065 -0.2794)
			(stroke
				(width 0.1)
				(type default)
			)
			(layer "B.Fab")
		)
		(fp_line
			(start -0.120396 0.3048)
			(end -0.120396 0.2794)
			(stroke
				(width 0.1)
				(type default)
			)
			(layer "B.Fab")
		)
		(fp_line
			(start -0.120396 0.2794)
			(end 0.12065 0.2794)
			(stroke
				(width 0.1)
				(type default)
			)
			(layer "B.Fab")
		)
		(fp_line
			(start -0.12065 -0.2794)
			(end -0.12065 -0.3048)
			(stroke
				(width 0.1)
				(type default)
			)
			(layer "B.Fab")
		)
		(fp_line
			(start -0.12065 -0.3048)
			(end -0.67945 -0.3048)
			(stroke
				(width 0.1)
				(type default)
			)
			(layer "B.Fab")
		)
		(fp_line
			(start -0.67945 0.3048)
			(end -0.120396 0.3048)
			(stroke
				(width 0.1)
				(type default)
			)
			(layer "B.Fab")
		)
		(fp_line
			(start -0.67945 -0.3048)
			(end -0.67945 0.3048)
			(stroke
				(width 0.1)
				(type default)
			)
			(layer "B.Fab")
		)
		(pad "1" smd circle
			(at 0.40005 0)
			(size 0 0)
			(layers "B.Cu" "B.Mask" "B.Paste")
			(net "P3V3_AUX")
		)
		(pad "2" smd circle
			(at -0.40005 0)
			(size 0 0)
			(layers "B.Cu" "B.Mask" "B.Paste")
			(net "GND")
		)
	)
	(footprint ""
		(layer "B.Cu")
		(at 128.85928 -31.542228 90)
		(property "Reference" "R4273"
			(at 0 0 90)
			(layer "B.SilkS")
			(hide yes)
			(effects
				(font
					(size 1.27 1.27)
				)
				(justify mirror)
			)
		)
		(property "Value" ""
			(at 0 0 90)
			(layer "B.Fab")
			(effects
				(font
					(size 1.27 1.27)
				)
				(justify mirror)
			)
		)
		(duplicate_pad_numbers_are_jumpers no)
		(fp_line
			(start 0.7874 -0.4064)
			(end -0.7874 -0.4064)
			(stroke
				(width 0.1524)
				(type default)
			)
			(layer "B.SilkS")
		)
		(fp_line
			(start -0.7874 -0.4064)
			(end -0.7874 0.4064)
			(stroke
				(width 0.1524)
				(type default)
			)
			(layer "B.SilkS")
		)
		(fp_line
			(start 0.7874 0.4064)
			(end 0.7874 -0.4064)
			(stroke
				(width 0.1524)
				(type default)
			)
			(layer "B.SilkS")
		)
		(fp_line
			(start -0.7874 0.4064)
			(end 0.7874 0.4064)
			(stroke
				(width 0.1524)
				(type default)
			)
			(layer "B.SilkS")
		)
		(fp_line
			(start 0.67945 -0.305054)
			(end 0.12065 -0.305054)
			(stroke
				(width 0.1)
				(type default)
			)
			(layer "B.Fab")
		)
		(fp_line
			(start 0.12065 -0.305054)
			(end 0.12065 -0.2794)
			(stroke
				(width 0.1)
				(type default)
			)
			(layer "B.Fab")
		)
		(fp_line
			(start -0.12065 -0.3048)
			(end -0.67945 -0.3048)
			(stroke
				(width 0.1)
				(type default)
			)
			(layer "B.Fab")
		)
		(fp_line
			(start -0.67945 -0.3048)
			(end -0.67945 0.3048)
			(stroke
				(width 0.1)
				(type default)
			)
			(layer "B.Fab")
		)
		(fp_line
			(start 0.12065 -0.2794)
			(end -0.12065 -0.2794)
			(stroke
				(width 0.1)
				(type default)
			)
			(layer "B.Fab")
		)
		(fp_line
			(start -0.12065 -0.2794)
			(end -0.12065 -0.3048)
			(stroke
				(width 0.1)
				(type default)
			)
			(layer "B.Fab")
		)
		(fp_line
			(start 0.12065 0.2794)
			(end 0.12065 0.3048)
			(stroke
				(width 0.1)
				(type default)
			)
			(layer "B.Fab")
		)
		(fp_line
			(start -0.120396 0.2794)
			(end 0.12065 0.2794)
			(stroke
				(width 0.1)
				(type default)
			)
			(layer "B.Fab")
		)
		(fp_line
			(start 0.67945 0.3048)
			(end 0.67945 -0.305054)
			(stroke
				(width 0.1)
				(type default)
			)
			(layer "B.Fab")
		)
		(fp_line
			(start 0.12065 0.3048)
			(end 0.67945 0.3048)
			(stroke
				(width 0.1)
				(type default)
			)
			(layer "B.Fab")
		)
		(fp_line
			(start -0.120396 0.3048)
			(end -0.120396 0.2794)
			(stroke
				(width 0.1)
				(type default)
			)
			(layer "B.Fab")
		)
		(fp_line
			(start -0.67945 0.3048)
			(end -0.120396 0.3048)
			(stroke
				(width 0.1)
				(type default)
			)
			(layer "B.Fab")
		)
		(pad "1" smd circle
			(at 0.40005 0 270)
			(size 0 0)
			(layers "B.Cu" "B.Mask" "B.Paste")
			(net "P3V3_AUX")
		)
		(pad "2" smd circle
			(at -0.40005 0 270)
			(size 0 0)
			(layers "B.Cu" "B.Mask" "B.Paste")
			(net "FM_USB3_1_FGB")
		)
	)
	(footprint ""
		(layer "B.Cu")
		(at 315.110622 -54.219348)
		(property "Reference" "R4109"
			(at 0 0 0)
			(layer "B.SilkS")
			(hide yes)
			(effects
				(font
					(size 1.27 1.27)
				)
				(justify mirror)
			)
		)
		(property "Value" ""
			(at 0 0 0)
			(layer "B.Fab")
			(effects
				(font
					(size 1.27 1.27)
				)
				(justify mirror)
			)
		)
		(duplicate_pad_numbers_are_jumpers no)
		(fp_line
			(start -0.7874 -0.4064)
			(end -0.7874 0.4064)
			(stroke
				(width 0.1524)
				(type default)
			)
			(layer "B.SilkS")
		)
		(fp_line
			(start -0.7874 0.4064)
			(end 0.7874 0.4064)
			(stroke
				(width 0.1524)
				(type default)
			)
			(layer "B.SilkS")
		)
		(fp_line
			(start 0.7874 -0.4064)
			(end -0.7874 -0.4064)
			(stroke
				(width 0.1524)
				(type default)
			)
			(layer "B.SilkS")
		)
		(fp_line
			(start 0.7874 0.4064)
			(end 0.7874 -0.4064)
			(stroke
				(width 0.1524)
				(type default)
			)
			(layer "B.SilkS")
		)
		(fp_line
			(start -0.67945 -0.3048)
			(end -0.67945 0.3048)
			(stroke
				(width 0.1)
				(type default)
			)
			(layer "B.Fab")
		)
		(fp_line
			(start -0.67945 0.3048)
			(end -0.120396 0.3048)
			(stroke
				(width 0.1)
				(type default)
			)
			(layer "B.Fab")
		)
		(fp_line
			(start -0.12065 -0.3048)
			(end -0.67945 -0.3048)
			(stroke
				(width 0.1)
				(type default)
			)
			(layer "B.Fab")
		)
		(fp_line
			(start -0.12065 -0.2794)
			(end -0.12065 -0.3048)
			(stroke
				(width 0.1)
				(type default)
			)
			(layer "B.Fab")
		)
		(fp_line
			(start -0.120396 0.2794)
			(end 0.12065 0.2794)
			(stroke
				(width 0.1)
				(type default)
			)
			(layer "B.Fab")
		)
		(fp_line
			(start -0.120396 0.3048)
			(end -0.120396 0.2794)
			(stroke
				(width 0.1)
				(type default)
			)
			(layer "B.Fab")
		)
		(fp_line
			(start 0.12065 -0.305054)
			(end 0.12065 -0.2794)
			(stroke
				(width 0.1)
				(type default)
			)
			(layer "B.Fab")
		)
		(fp_line
			(start 0.12065 -0.2794)
			(end -0.12065 -0.2794)
			(stroke
				(width 0.1)
				(type default)
			)
			(layer "B.Fab")
		)
		(fp_line
			(start 0.12065 0.2794)
			(end 0.12065 0.3048)
			(stroke
				(width 0.1)
				(type default)
			)
			(layer "B.Fab")
		)
		(fp_line
			(start 0.12065 0.3048)
			(end 0.67945 0.3048)
			(stroke
				(width 0.1)
				(type default)
			)
			(layer "B.Fab")
		)
		(fp_line
			(start 0.67945 -0.305054)
			(end 0.12065 -0.305054)
			(stroke
				(width 0.1)
				(type default)
			)
			(layer "B.Fab")
		)
		(fp_line
			(start 0.67945 0.3048)
			(end 0.67945 -0.305054)
			(stroke
				(width 0.1)
				(type default)
			)
			(layer "B.Fab")
		)
		(pad "1" smd circle
			(at 0.40005 0 180)
			(size 0 0)
			(layers "B.Cu" "B.Mask" "B.Paste")
			(net "PD_GPP_I_15")
		)
		(pad "2" smd circle
			(at -0.40005 0 180)
			(size 0 0)
			(layers "B.Cu" "B.Mask" "B.Paste")
			(net "GND")
		)
	)
	(footprint ""
		(layer "B.Cu")
		(at 344.820748 -31.527242)
		(property "Reference" "R502"
			(at 0 0 0)
			(layer "B.SilkS")
			(hide yes)
			(effects
				(font
					(size 1.27 1.27)
				)
				(justify mirror)
			)
		)
		(property "Value" ""
			(at 0 0 0)
			(layer "B.Fab")
			(effects
				(font
					(size 1.27 1.27)
				)
				(justify mirror)
			)
		)
		(duplicate_pad_numbers_are_jumpers no)
		(fp_line
			(start -0.7874 -0.4064)
			(end -0.7874 0.4064)
			(stroke
				(width 0.1524)
				(type default)
			)
			(layer "B.SilkS")
		)
		(fp_line
			(start -0.7874 0.4064)
			(end 0.7874 0.4064)
			(stroke
				(width 0.1524)
				(type default)
			)
			(layer "B.SilkS")
		)
		(fp_line
			(start 0.7874 -0.4064)
			(end -0.7874 -0.4064)
			(stroke
				(width 0.1524)
				(type default)
			)
			(layer "B.SilkS")
		)
		(fp_line
			(start 0.7874 0.4064)
			(end 0.7874 -0.4064)
			(stroke
				(width 0.1524)
				(type default)
			)
			(layer "B.SilkS")
		)
		(fp_line
			(start -0.67945 -0.3048)
			(end -0.67945 0.3048)
			(stroke
				(width 0.1)
				(type default)
			)
			(layer "B.Fab")
		)
		(fp_line
			(start -0.67945 0.3048)
			(end -0.120396 0.3048)
			(stroke
				(width 0.1)
				(type default)
			)
			(layer "B.Fab")
		)
		(fp_line
			(start -0.12065 -0.3048)
			(end -0.67945 -0.3048)
			(stroke
				(width 0.1)
				(type default)
			)
			(layer "B.Fab")
		)
		(fp_line
			(start -0.12065 -0.2794)
			(end -0.12065 -0.3048)
			(stroke
				(width 0.1)
				(type default)
			)
			(layer "B.Fab")
		)
		(fp_line
			(start -0.120396 0.2794)
			(end 0.12065 0.2794)
			(stroke
				(width 0.1)
				(type default)
			)
			(layer "B.Fab")
		)
		(fp_line
			(start -0.120396 0.3048)
			(end -0.120396 0.2794)
			(stroke
				(width 0.1)
				(type default)
			)
			(layer "B.Fab")
		)
		(fp_line
			(start 0.12065 -0.305054)
			(end 0.12065 -0.2794)
			(stroke
				(width 0.1)
				(type default)
			)
			(layer "B.Fab")
		)
		(fp_line
			(start 0.12065 -0.2794)
			(end -0.12065 -0.2794)
			(stroke
				(width 0.1)
				(type default)
			)
			(layer "B.Fab")
		)
		(fp_line
			(start 0.12065 0.2794)
			(end 0.12065 0.3048)
			(stroke
				(width 0.1)
				(type default)
			)
			(layer "B.Fab")
		)
		(fp_line
			(start 0.12065 0.3048)
			(end 0.67945 0.3048)
			(stroke
				(width 0.1)
				(type default)
			)
			(layer "B.Fab")
		)
		(fp_line
			(start 0.67945 -0.305054)
			(end 0.12065 -0.305054)
			(stroke
				(width 0.1)
				(type default)
			)
			(layer "B.Fab")
		)
		(fp_line
			(start 0.67945 0.3048)
			(end 0.67945 -0.305054)
			(stroke
				(width 0.1)
				(type default)
			)
			(layer "B.Fab")
		)
		(pad "1" smd circle
			(at 0.40005 0 180)
			(size 0 0)
			(layers "B.Cu" "B.Mask" "B.Paste")
			(net "P3V3_AUX")
		)
		(pad "2" smd circle
			(at -0.40005 0 180)
			(size 0 0)
			(layers "B.Cu" "B.Mask" "B.Paste")
			(net "FM_PCH_CONSENT_STRAP_N")
		)
	)
	(footprint ""
		(layer "B.Cu")
		(at 355.397308 -259.531866 90)
		(property "Reference" "C505"
			(at 0 0 90)
			(layer "B.SilkS")
			(hide yes)
			(effects
				(font
					(size 1.27 1.27)
				)
				(justify mirror)
			)
		)
		(property "Value" ""
			(at 0 0 90)
			(layer "B.Fab")
			(effects
				(font
					(size 1.27 1.27)
				)
				(justify mirror)
			)
		)
		(duplicate_pad_numbers_are_jumpers no)
		(fp_line
			(start 1.524 -0.762)
			(end -1.524 -0.762)
			(stroke
				(width 0.1524)
				(type default)
			)
			(layer "B.SilkS")
		)
		(fp_line
			(start -1.524 -0.762)
			(end -1.524 0.762)
			(stroke
				(width 0.1524)
				(type default)
			)
			(layer "B.SilkS")
		)
		(fp_line
			(start 1.524 0.762)
			(end 1.524 -0.762)
			(stroke
				(width 0.1524)
				(type default)
			)
			(layer "B.SilkS")
		)
		(fp_line
			(start -1.524 0.762)
			(end 1.524 0.762)
			(stroke
				(width 0.1524)
				(type default)
			)
			(layer "B.SilkS")
		)
		(fp_line
			(start 1.1049 -0.724916)
			(end 1.1049 0.724916)
			(stroke
				(width 0.1)
				(type default)
			)
			(layer "B.Fab")
		)
		(fp_line
			(start -1.1049 -0.724916)
			(end 1.1049 -0.724916)
			(stroke
				(width 0.1)
				(type default)
			)
			(layer "B.Fab")
		)
		(fp_line
			(start 1.1049 0.724916)
			(end -1.1049 0.724916)
			(stroke
				(width 0.1)
				(type default)
			)
			(layer "B.Fab")
		)
		(fp_line
			(start -1.1049 0.724916)
			(end -1.1049 -0.724916)
			(stroke
				(width 0.1)
				(type default)
			)
			(layer "B.Fab")
		)
		(pad "1" smd rect
			(at 0.889 0 90)
			(size 1.016 1.27)
			(layers "B.Cu" "B.Mask" "B.Paste")
			(net "PVCCFA_EHV_FIVRA_CPU0")
		)
		(pad "2" smd rect
			(at -0.889 0 90)
			(size 1.016 1.27)
			(layers "B.Cu" "B.Mask" "B.Paste")
			(net "GND")
		)
	)
	(footprint ""
		(layer "B.Cu")
		(at 64.637158 -192.96253 90)
		(property "Reference" "R137"
			(at 0 0 90)
			(layer "B.SilkS")
			(hide yes)
			(effects
				(font
					(size 1.27 1.27)
				)
				(justify mirror)
			)
		)
		(property "Value" ""
			(at 0 0 90)
			(layer "B.Fab")
			(effects
				(font
					(size 1.27 1.27)
				)
				(justify mirror)
			)
		)
		(duplicate_pad_numbers_are_jumpers no)
		(fp_line
			(start 0.7874 -0.4064)
			(end -0.7874 -0.4064)
			(stroke
				(width 0.1524)
				(type default)
			)
			(layer "B.SilkS")
		)
		(fp_line
			(start -0.7874 -0.4064)
			(end -0.7874 0.4064)
			(stroke
				(width 0.1524)
				(type default)
			)
			(layer "B.SilkS")
		)
		(fp_line
			(start 0.7874 0.4064)
			(end 0.7874 -0.4064)
			(stroke
				(width 0.1524)
				(type default)
			)
			(layer "B.SilkS")
		)
		(fp_line
			(start -0.7874 0.4064)
			(end 0.7874 0.4064)
			(stroke
				(width 0.1524)
				(type default)
			)
			(layer "B.SilkS")
		)
		(fp_line
			(start 0.67945 -0.305054)
			(end 0.12065 -0.305054)
			(stroke
				(width 0.1)
				(type default)
			)
			(layer "B.Fab")
		)
		(fp_line
			(start 0.12065 -0.305054)
			(end 0.12065 -0.2794)
			(stroke
				(width 0.1)
				(type default)
			)
			(layer "B.Fab")
		)
		(fp_line
			(start -0.12065 -0.3048)
			(end -0.67945 -0.3048)
			(stroke
				(width 0.1)
				(type default)
			)
			(layer "B.Fab")
		)
		(fp_line
			(start -0.67945 -0.3048)
			(end -0.67945 0.3048)
			(stroke
				(width 0.1)
				(type default)
			)
			(layer "B.Fab")
		)
		(fp_line
			(start 0.12065 -0.2794)
			(end -0.12065 -0.2794)
			(stroke
				(width 0.1)
				(type default)
			)
			(layer "B.Fab")
		)
		(fp_line
			(start -0.12065 -0.2794)
			(end -0.12065 -0.3048)
			(stroke
				(width 0.1)
				(type default)
			)
			(layer "B.Fab")
		)
		(fp_line
			(start 0.12065 0.2794)
			(end 0.12065 0.3048)
			(stroke
				(width 0.1)
				(type default)
			)
			(layer "B.Fab")
		)
		(fp_line
			(start -0.120396 0.2794)
			(end 0.12065 0.2794)
			(stroke
				(width 0.1)
				(type default)
			)
			(layer "B.Fab")
		)
		(fp_line
			(start 0.67945 0.3048)
			(end 0.67945 -0.305054)
			(stroke
				(width 0.1)
				(type default)
			)
			(layer "B.Fab")
		)
		(fp_line
			(start 0.12065 0.3048)
			(end 0.67945 0.3048)
			(stroke
				(width 0.1)
				(type default)
			)
			(layer "B.Fab")
		)
		(fp_line
			(start -0.120396 0.3048)
			(end -0.120396 0.2794)
			(stroke
				(width 0.1)
				(type default)
			)
			(layer "B.Fab")
		)
		(fp_line
			(start -0.67945 0.3048)
			(end -0.120396 0.3048)
			(stroke
				(width 0.1)
				(type default)
			)
			(layer "B.Fab")
		)
		(pad "1" smd circle
			(at 0.40005 0 270)
			(size 0 0)
			(layers "B.Cu" "B.Mask" "B.Paste")
			(net "PWRGD_DRAMPWRGD_CPU1_CD_LVC1_R2")
		)
		(pad "2" smd circle
			(at -0.40005 0 270)
			(size 0 0)
			(layers "B.Cu" "B.Mask" "B.Paste")
			(net "PVCCD_HV_CPU1")
		)
	)
	(footprint ""
		(layer "B.Cu")
		(at 379.720602 -190.795148 90)
		(property "Reference" "R690"
			(at 0 0 90)
			(layer "B.SilkS")
			(hide yes)
			(effects
				(font
					(size 1.27 1.27)
				)
				(justify mirror)
			)
		)
		(property "Value" ""
			(at 0 0 90)
			(layer "B.Fab")
			(effects
				(font
					(size 1.27 1.27)
				)
				(justify mirror)
			)
		)
		(duplicate_pad_numbers_are_jumpers no)
		(fp_line
			(start 0.7874 -0.4064)
			(end -0.7874 -0.4064)
			(stroke
				(width 0.1524)
				(type default)
			)
			(layer "B.SilkS")
		)
		(fp_line
			(start -0.7874 -0.4064)
			(end -0.7874 0.4064)
			(stroke
				(width 0.1524)
				(type default)
			)
			(layer "B.SilkS")
		)
		(fp_line
			(start 0.7874 0.4064)
			(end 0.7874 -0.4064)
			(stroke
				(width 0.1524)
				(type default)
			)
			(layer "B.SilkS")
		)
		(fp_line
			(start -0.7874 0.4064)
			(end 0.7874 0.4064)
			(stroke
				(width 0.1524)
				(type default)
			)
			(layer "B.SilkS")
		)
		(fp_line
			(start 0.67945 -0.305054)
			(end 0.12065 -0.305054)
			(stroke
				(width 0.1)
				(type default)
			)
			(layer "B.Fab")
		)
		(fp_line
			(start 0.12065 -0.305054)
			(end 0.12065 -0.2794)
			(stroke
				(width 0.1)
				(type default)
			)
			(layer "B.Fab")
		)
		(fp_line
			(start -0.12065 -0.3048)
			(end -0.67945 -0.3048)
			(stroke
				(width 0.1)
				(type default)
			)
			(layer "B.Fab")
		)
		(fp_line
			(start -0.67945 -0.3048)
			(end -0.67945 0.3048)
			(stroke
				(width 0.1)
				(type default)
			)
			(layer "B.Fab")
		)
		(fp_line
			(start 0.12065 -0.2794)
			(end -0.12065 -0.2794)
			(stroke
				(width 0.1)
				(type default)
			)
			(layer "B.Fab")
		)
		(fp_line
			(start -0.12065 -0.2794)
			(end -0.12065 -0.3048)
			(stroke
				(width 0.1)
				(type default)
			)
			(layer "B.Fab")
		)
		(fp_line
			(start 0.12065 0.2794)
			(end 0.12065 0.3048)
			(stroke
				(width 0.1)
				(type default)
			)
			(layer "B.Fab")
		)
		(fp_line
			(start -0.120396 0.2794)
			(end 0.12065 0.2794)
			(stroke
				(width 0.1)
				(type default)
			)
			(layer "B.Fab")
		)
		(fp_line
			(start 0.67945 0.3048)
			(end 0.67945 -0.305054)
			(stroke
				(width 0.1)
				(type default)
			)
			(layer "B.Fab")
		)
		(fp_line
			(start 0.12065 0.3048)
			(end 0.67945 0.3048)
			(stroke
				(width 0.1)
				(type default)
			)
			(layer "B.Fab")
		)
		(fp_line
			(start -0.120396 0.3048)
			(end -0.120396 0.2794)
			(stroke
				(width 0.1)
				(type default)
			)
			(layer "B.Fab")
		)
		(fp_line
			(start -0.67945 0.3048)
			(end -0.120396 0.3048)
			(stroke
				(width 0.1)
				(type default)
			)
			(layer "B.Fab")
		)
		(pad "1" smd circle
			(at 0.40005 0 270)
			(size 0 0)
			(layers "B.Cu" "B.Mask" "B.Paste")
			(net "I3C_SPD_DDREFGH_CPU0_SDA")
		)
		(pad "2" smd circle
			(at -0.40005 0 270)
			(size 0 0)
			(layers "B.Cu" "B.Mask" "B.Paste")
			(net "I3C_SPD_DDREFGH_CPU0_R_SDA")
		)
	)
	(footprint ""
		(layer "B.Cu")
		(at 197.182232 -123.139708 180)
		(property "Reference" "R4521"
			(at 0 0 0)
			(layer "B.SilkS")
			(hide yes)
			(effects
				(font
					(size 1.27 1.27)
				)
				(justify mirror)
			)
		)
		(property "Value" ""
			(at 0 0 0)
			(layer "B.Fab")
			(effects
				(font
					(size 1.27 1.27)
				)
				(justify mirror)
			)
		)
		(duplicate_pad_numbers_are_jumpers no)
		(fp_line
			(start 0.7874 0.4064)
			(end 0.7874 -0.4064)
			(stroke
				(width 0.1524)
				(type default)
			)
			(layer "B.SilkS")
		)
		(fp_line
			(start 0.7874 -0.4064)
			(end -0.7874 -0.4064)
			(stroke
				(width 0.1524)
				(type default)
			)
			(layer "B.SilkS")
		)
		(fp_line
			(start -0.7874 0.4064)
			(end 0.7874 0.4064)
			(stroke
				(width 0.1524)
				(type default)
			)
			(layer "B.SilkS")
		)
		(fp_line
			(start -0.7874 -0.4064)
			(end -0.7874 0.4064)
			(stroke
				(width 0.1524)
				(type default)
			)
			(layer "B.SilkS")
		)
		(fp_line
			(start 0.67945 0.3048)
			(end 0.67945 -0.305054)
			(stroke
				(width 0.1)
				(type default)
			)
			(layer "B.Fab")
		)
		(fp_line
			(start 0.67945 -0.305054)
			(end 0.12065 -0.305054)
			(stroke
				(width 0.1)
				(type default)
			)
			(layer "B.Fab")
		)
		(fp_line
			(start 0.12065 0.3048)
			(end 0.67945 0.3048)
			(stroke
				(width 0.1)
				(type default)
			)
			(layer "B.Fab")
		)
		(fp_line
			(start 0.12065 0.2794)
			(end 0.12065 0.3048)
			(stroke
				(width 0.1)
				(type default)
			)
			(layer "B.Fab")
		)
		(fp_line
			(start 0.12065 -0.2794)
			(end -0.12065 -0.2794)
			(stroke
				(width 0.1)
				(type default)
			)
			(layer "B.Fab")
		)
		(fp_line
			(start 0.12065 -0.305054)
			(end 0.12065 -0.2794)
			(stroke
				(width 0.1)
				(type default)
			)
			(layer "B.Fab")
		)
		(fp_line
			(start -0.120396 0.3048)
			(end -0.120396 0.2794)
			(stroke
				(width 0.1)
				(type default)
			)
			(layer "B.Fab")
		)
		(fp_line
			(start -0.120396 0.2794)
			(end 0.12065 0.2794)
			(stroke
				(width 0.1)
				(type default)
			)
			(layer "B.Fab")
		)
		(fp_line
			(start -0.12065 -0.2794)
			(end -0.12065 -0.3048)
			(stroke
				(width 0.1)
				(type default)
			)
			(layer "B.Fab")
		)
		(fp_line
			(start -0.12065 -0.3048)
			(end -0.67945 -0.3048)
			(stroke
				(width 0.1)
				(type default)
			)
			(layer "B.Fab")
		)
		(fp_line
			(start -0.67945 0.3048)
			(end -0.120396 0.3048)
			(stroke
				(width 0.1)
				(type default)
			)
			(layer "B.Fab")
		)
		(fp_line
			(start -0.67945 -0.3048)
			(end -0.67945 0.3048)
			(stroke
				(width 0.1)
				(type default)
			)
			(layer "B.Fab")
		)
		(pad "1" smd circle
			(at 0.40005 0)
			(size 0 0)
			(layers "B.Cu" "B.Mask" "B.Paste")
			(net "P3V3_AUX")
		)
		(pad "2" smd circle
			(at -0.40005 0)
			(size 0 0)
			(layers "B.Cu" "B.Mask" "B.Paste")
			(net "CLK_GEN2_BMC_RC_OE_N")
		)
	)
	(footprint ""
		(layer "B.Cu")
		(at 366.310418 -296.054526)
		(property "Reference" "C396"
			(at 0 0 0)
			(layer "B.SilkS")
			(hide yes)
			(effects
				(font
					(size 1.27 1.27)
				)
				(justify mirror)
			)
		)
		(property "Value" ""
			(at 0 0 0)
			(layer "B.Fab")
			(effects
				(font
					(size 1.27 1.27)
				)
				(justify mirror)
			)
		)
		(duplicate_pad_numbers_are_jumpers no)
		(fp_line
			(start -1.524 -0.762)
			(end -1.524 0.762)
			(stroke
				(width 0.1524)
				(type default)
			)
			(layer "B.SilkS")
		)
		(fp_line
			(start -1.524 0.762)
			(end 1.524 0.762)
			(stroke
				(width 0.1524)
				(type default)
			)
			(layer "B.SilkS")
		)
		(fp_line
			(start 1.524 -0.762)
			(end -1.524 -0.762)
			(stroke
				(width 0.1524)
				(type default)
			)
			(layer "B.SilkS")
		)
		(fp_line
			(start 1.524 0.762)
			(end 1.524 -0.762)
			(stroke
				(width 0.1524)
				(type default)
			)
			(layer "B.SilkS")
		)
		(fp_line
			(start -1.1049 -0.724916)
			(end 1.1049 -0.724916)
			(stroke
				(width 0.1)
				(type default)
			)
			(layer "B.Fab")
		)
		(fp_line
			(start -1.1049 0.724916)
			(end -1.1049 -0.724916)
			(stroke
				(width 0.1)
				(type default)
			)
			(layer "B.Fab")
		)
		(fp_line
			(start 1.1049 -0.724916)
			(end 1.1049 0.724916)
			(stroke
				(width 0.1)
				(type default)
			)
			(layer "B.Fab")
		)
		(fp_line
			(start 1.1049 0.724916)
			(end -1.1049 0.724916)
			(stroke
				(width 0.1)
				(type default)
			)
			(layer "B.Fab")
		)
		(pad "1" smd rect
			(at 0.889 0)
			(size 1.016 1.27)
			(layers "B.Cu" "B.Mask" "B.Paste")
			(net "PVCCIN_CPU0")
		)
		(pad "2" smd rect
			(at -0.889 0)
			(size 1.016 1.27)
			(layers "B.Cu" "B.Mask" "B.Paste")
			(net "GND")
		)
	)
	(footprint ""
		(layer "B.Cu")
		(at 325.322438 -188.45911 -90)
		(property "Reference" "R5"
			(at 0 0 90)
			(layer "B.SilkS")
			(hide yes)
			(effects
				(font
					(size 1.27 1.27)
				)
				(justify mirror)
			)
		)
		(property "Value" ""
			(at 0 0 90)
			(layer "B.Fab")
			(effects
				(font
					(size 1.27 1.27)
				)
				(justify mirror)
			)
		)
		(duplicate_pad_numbers_are_jumpers no)
		(fp_line
			(start -0.7874 0.4064)
			(end 0.7874 0.4064)
			(stroke
				(width 0.1524)
				(type default)
			)
			(layer "B.SilkS")
		)
		(fp_line
			(start 0.7874 0.4064)
			(end 0.7874 -0.4064)
			(stroke
				(width 0.1524)
				(type default)
			)
			(layer "B.SilkS")
		)
		(fp_line
			(start -0.7874 -0.4064)
			(end -0.7874 0.4064)
			(stroke
				(width 0.1524)
				(type default)
			)
			(layer "B.SilkS")
		)
		(fp_line
			(start 0.7874 -0.4064)
			(end -0.7874 -0.4064)
			(stroke
				(width 0.1524)
				(type default)
			)
			(layer "B.SilkS")
		)
		(fp_line
			(start -0.67945 0.3048)
			(end -0.120396 0.3048)
			(stroke
				(width 0.1)
				(type default)
			)
			(layer "B.Fab")
		)
		(fp_line
			(start -0.120396 0.3048)
			(end -0.120396 0.2794)
			(stroke
				(width 0.1)
				(type default)
			)
			(layer "B.Fab")
		)
		(fp_line
			(start 0.12065 0.3048)
			(end 0.67945 0.3048)
			(stroke
				(width 0.1)
				(type default)
			)
			(layer "B.Fab")
		)
		(fp_line
			(start 0.67945 0.3048)
			(end 0.67945 -0.305054)
			(stroke
				(width 0.1)
				(type default)
			)
			(layer "B.Fab")
		)
		(fp_line
			(start -0.120396 0.2794)
			(end 0.12065 0.2794)
			(stroke
				(width 0.1)
				(type default)
			)
			(layer "B.Fab")
		)
		(fp_line
			(start 0.12065 0.2794)
			(end 0.12065 0.3048)
			(stroke
				(width 0.1)
				(type default)
			)
			(layer "B.Fab")
		)
		(fp_line
			(start -0.12065 -0.2794)
			(end -0.12065 -0.3048)
			(stroke
				(width 0.1)
				(type default)
			)
			(layer "B.Fab")
		)
		(fp_line
			(start 0.12065 -0.2794)
			(end -0.12065 -0.2794)
			(stroke
				(width 0.1)
				(type default)
			)
			(layer "B.Fab")
		)
		(fp_line
			(start -0.67945 -0.3048)
			(end -0.67945 0.3048)
			(stroke
				(width 0.1)
				(type default)
			)
			(layer "B.Fab")
		)
		(fp_line
			(start -0.12065 -0.3048)
			(end -0.67945 -0.3048)
			(stroke
				(width 0.1)
				(type default)
			)
			(layer "B.Fab")
		)
		(fp_line
			(start 0.12065 -0.305054)
			(end 0.12065 -0.2794)
			(stroke
				(width 0.1)
				(type default)
			)
			(layer "B.Fab")
		)
		(fp_line
			(start 0.67945 -0.305054)
			(end 0.12065 -0.305054)
			(stroke
				(width 0.1)
				(type default)
			)
			(layer "B.Fab")
		)
		(pad "1" smd circle
			(at 0.40005 0 90)
			(size 0 0)
			(layers "B.Cu" "B.Mask" "B.Paste")
			(net "JTAG_DBP_CPU_GTL_TCK")
		)
		(pad "2" smd circle
			(at -0.40005 0 90)
			(size 0 0)
			(layers "B.Cu" "B.Mask" "B.Paste")
			(net "JTAG_DBP_CPU0_GTL_R_TCK")
		)
	)
	(footprint ""
		(layer "B.Cu")
		(at 168.742868 -197.131178 -90)
		(property "Reference" "R4301"
			(at 0 0 90)
			(layer "B.SilkS")
			(hide yes)
			(effects
				(font
					(size 1.27 1.27)
				)
				(justify mirror)
			)
		)
		(property "Value" ""
			(at 0 0 90)
			(layer "B.Fab")
			(effects
				(font
					(size 1.27 1.27)
				)
				(justify mirror)
			)
		)
		(duplicate_pad_numbers_are_jumpers no)
		(fp_line
			(start -0.7874 0.4064)
			(end 0.7874 0.4064)
			(stroke
				(width 0.1524)
				(type default)
			)
			(layer "B.SilkS")
		)
		(fp_line
			(start 0.7874 0.4064)
			(end 0.7874 -0.4064)
			(stroke
				(width 0.1524)
				(type default)
			)
			(layer "B.SilkS")
		)
		(fp_line
			(start -0.7874 -0.4064)
			(end -0.7874 0.4064)
			(stroke
				(width 0.1524)
				(type default)
			)
			(layer "B.SilkS")
		)
		(fp_line
			(start 0.7874 -0.4064)
			(end -0.7874 -0.4064)
			(stroke
				(width 0.1524)
				(type default)
			)
			(layer "B.SilkS")
		)
		(fp_line
			(start -0.67945 0.3048)
			(end -0.120396 0.3048)
			(stroke
				(width 0.1)
				(type default)
			)
			(layer "B.Fab")
		)
		(fp_line
			(start -0.120396 0.3048)
			(end -0.120396 0.2794)
			(stroke
				(width 0.1)
				(type default)
			)
			(layer "B.Fab")
		)
		(fp_line
			(start 0.12065 0.3048)
			(end 0.67945 0.3048)
			(stroke
				(width 0.1)
				(type default)
			)
			(layer "B.Fab")
		)
		(fp_line
			(start 0.67945 0.3048)
			(end 0.67945 -0.305054)
			(stroke
				(width 0.1)
				(type default)
			)
			(layer "B.Fab")
		)
		(fp_line
			(start -0.120396 0.2794)
			(end 0.12065 0.2794)
			(stroke
				(width 0.1)
				(type default)
			)
			(layer "B.Fab")
		)
		(fp_line
			(start 0.12065 0.2794)
			(end 0.12065 0.3048)
			(stroke
				(width 0.1)
				(type default)
			)
			(layer "B.Fab")
		)
		(fp_line
			(start -0.12065 -0.2794)
			(end -0.12065 -0.3048)
			(stroke
				(width 0.1)
				(type default)
			)
			(layer "B.Fab")
		)
		(fp_line
			(start 0.12065 -0.2794)
			(end -0.12065 -0.2794)
			(stroke
				(width 0.1)
				(type default)
			)
			(layer "B.Fab")
		)
		(fp_line
			(start -0.67945 -0.3048)
			(end -0.67945 0.3048)
			(stroke
				(width 0.1)
				(type default)
			)
			(layer "B.Fab")
		)
		(fp_line
			(start -0.12065 -0.3048)
			(end -0.67945 -0.3048)
			(stroke
				(width 0.1)
				(type default)
			)
			(layer "B.Fab")
		)
		(fp_line
			(start 0.12065 -0.305054)
			(end 0.12065 -0.2794)
			(stroke
				(width 0.1)
				(type default)
			)
			(layer "B.Fab")
		)
		(fp_line
			(start 0.67945 -0.305054)
			(end 0.12065 -0.305054)
			(stroke
				(width 0.1)
				(type default)
			)
			(layer "B.Fab")
		)
		(pad "1" smd circle
			(at 0.40005 0 90)
			(size 0 0)
			(layers "B.Cu" "B.Mask" "B.Paste")
			(net "PWRGD_DRAMPWRGD_CPU1_EF_LVC1_R2")
		)
		(pad "2" smd circle
			(at -0.40005 0 90)
			(size 0 0)
			(layers "B.Cu" "B.Mask" "B.Paste")
			(net "PWRGD_DRAMPWRGD_CPU1_EF_LVC1_R")
		)
	)
	(footprint ""
		(layer "B.Cu")
		(at 440.617356 -318.933576 90)
		(property "Reference" "R890"
			(at 0 0 90)
			(layer "B.SilkS")
			(hide yes)
			(effects
				(font
					(size 1.27 1.27)
				)
				(justify mirror)
			)
		)
		(property "Value" ""
			(at 0 0 90)
			(layer "B.Fab")
			(effects
				(font
					(size 1.27 1.27)
				)
				(justify mirror)
			)
		)
		(duplicate_pad_numbers_are_jumpers no)
		(fp_line
			(start 0.7874 -0.4064)
			(end -0.7874 -0.4064)
			(stroke
				(width 0.1524)
				(type default)
			)
			(layer "B.SilkS")
		)
		(fp_line
			(start -0.7874 -0.4064)
			(end -0.7874 0.4064)
			(stroke
				(width 0.1524)
				(type default)
			)
			(layer "B.SilkS")
		)
		(fp_line
			(start 0.7874 0.4064)
			(end 0.7874 -0.4064)
			(stroke
				(width 0.1524)
				(type default)
			)
			(layer "B.SilkS")
		)
		(fp_line
			(start -0.7874 0.4064)
			(end 0.7874 0.4064)
			(stroke
				(width 0.1524)
				(type default)
			)
			(layer "B.SilkS")
		)
		(fp_line
			(start 0.67945 -0.305054)
			(end 0.12065 -0.305054)
			(stroke
				(width 0.1)
				(type default)
			)
			(layer "B.Fab")
		)
		(fp_line
			(start 0.12065 -0.305054)
			(end 0.12065 -0.2794)
			(stroke
				(width 0.1)
				(type default)
			)
			(layer "B.Fab")
		)
		(fp_line
			(start -0.12065 -0.3048)
			(end -0.67945 -0.3048)
			(stroke
				(width 0.1)
				(type default)
			)
			(layer "B.Fab")
		)
		(fp_line
			(start -0.67945 -0.3048)
			(end -0.67945 0.3048)
			(stroke
				(width 0.1)
				(type default)
			)
			(layer "B.Fab")
		)
		(fp_line
			(start 0.12065 -0.2794)
			(end -0.12065 -0.2794)
			(stroke
				(width 0.1)
				(type default)
			)
			(layer "B.Fab")
		)
		(fp_line
			(start -0.12065 -0.2794)
			(end -0.12065 -0.3048)
			(stroke
				(width 0.1)
				(type default)
			)
			(layer "B.Fab")
		)
		(fp_line
			(start 0.12065 0.2794)
			(end 0.12065 0.3048)
			(stroke
				(width 0.1)
				(type default)
			)
			(layer "B.Fab")
		)
		(fp_line
			(start -0.120396 0.2794)
			(end 0.12065 0.2794)
			(stroke
				(width 0.1)
				(type default)
			)
			(layer "B.Fab")
		)
		(fp_line
			(start 0.67945 0.3048)
			(end 0.67945 -0.305054)
			(stroke
				(width 0.1)
				(type default)
			)
			(layer "B.Fab")
		)
		(fp_line
			(start 0.12065 0.3048)
			(end 0.67945 0.3048)
			(stroke
				(width 0.1)
				(type default)
			)
			(layer "B.Fab")
		)
		(fp_line
			(start -0.120396 0.3048)
			(end -0.120396 0.2794)
			(stroke
				(width 0.1)
				(type default)
			)
			(layer "B.Fab")
		)
		(fp_line
			(start -0.67945 0.3048)
			(end -0.120396 0.3048)
			(stroke
				(width 0.1)
				(type default)
			)
			(layer "B.Fab")
		)
		(pad "1" smd circle
			(at 0.40005 0 270)
			(size 0 0)
			(layers "B.Cu" "B.Mask" "B.Paste")
			(net "PWRGD_CHG_CPU0_DIMM2")
		)
		(pad "2" smd circle
			(at -0.40005 0 270)
			(size 0 0)
			(layers "B.Cu" "B.Mask" "B.Paste")
			(net "PWRGD_FAIL_CPU0_GH")
		)
	)
	(footprint ""
		(layer "B.Cu")
		(at 309.558182 -32.243268 180)
		(property "Reference" "R1299"
			(at 0 0 0)
			(layer "B.SilkS")
			(hide yes)
			(effects
				(font
					(size 1.27 1.27)
				)
				(justify mirror)
			)
		)
		(property "Value" ""
			(at 0 0 0)
			(layer "B.Fab")
			(effects
				(font
					(size 1.27 1.27)
				)
				(justify mirror)
			)
		)
		(duplicate_pad_numbers_are_jumpers no)
		(fp_line
			(start 0.7874 0.4064)
			(end 0.7874 -0.4064)
			(stroke
				(width 0.1524)
				(type default)
			)
			(layer "B.SilkS")
		)
		(fp_line
			(start 0.7874 -0.4064)
			(end -0.7874 -0.4064)
			(stroke
				(width 0.1524)
				(type default)
			)
			(layer "B.SilkS")
		)
		(fp_line
			(start -0.7874 0.4064)
			(end 0.7874 0.4064)
			(stroke
				(width 0.1524)
				(type default)
			)
			(layer "B.SilkS")
		)
		(fp_line
			(start -0.7874 -0.4064)
			(end -0.7874 0.4064)
			(stroke
				(width 0.1524)
				(type default)
			)
			(layer "B.SilkS")
		)
		(fp_line
			(start 0.67945 0.3048)
			(end 0.67945 -0.305054)
			(stroke
				(width 0.1)
				(type default)
			)
			(layer "B.Fab")
		)
		(fp_line
			(start 0.67945 -0.305054)
			(end 0.12065 -0.305054)
			(stroke
				(width 0.1)
				(type default)
			)
			(layer "B.Fab")
		)
		(fp_line
			(start 0.12065 0.3048)
			(end 0.67945 0.3048)
			(stroke
				(width 0.1)
				(type default)
			)
			(layer "B.Fab")
		)
		(fp_line
			(start 0.12065 0.2794)
			(end 0.12065 0.3048)
			(stroke
				(width 0.1)
				(type default)
			)
			(layer "B.Fab")
		)
		(fp_line
			(start 0.12065 -0.2794)
			(end -0.12065 -0.2794)
			(stroke
				(width 0.1)
				(type default)
			)
			(layer "B.Fab")
		)
		(fp_line
			(start 0.12065 -0.305054)
			(end 0.12065 -0.2794)
			(stroke
				(width 0.1)
				(type default)
			)
			(layer "B.Fab")
		)
		(fp_line
			(start -0.120396 0.3048)
			(end -0.120396 0.2794)
			(stroke
				(width 0.1)
				(type default)
			)
			(layer "B.Fab")
		)
		(fp_line
			(start -0.120396 0.2794)
			(end 0.12065 0.2794)
			(stroke
				(width 0.1)
				(type default)
			)
			(layer "B.Fab")
		)
		(fp_line
			(start -0.12065 -0.2794)
			(end -0.12065 -0.3048)
			(stroke
				(width 0.1)
				(type default)
			)
			(layer "B.Fab")
		)
		(fp_line
			(start -0.12065 -0.3048)
			(end -0.67945 -0.3048)
			(stroke
				(width 0.1)
				(type default)
			)
			(layer "B.Fab")
		)
		(fp_line
			(start -0.67945 0.3048)
			(end -0.120396 0.3048)
			(stroke
				(width 0.1)
				(type default)
			)
			(layer "B.Fab")
		)
		(fp_line
			(start -0.67945 -0.3048)
			(end -0.67945 0.3048)
			(stroke
				(width 0.1)
				(type default)
			)
			(layer "B.Fab")
		)
		(pad "1" smd circle
			(at 0.40005 0)
			(size 0 0)
			(layers "B.Cu" "B.Mask" "B.Paste")
			(net "FM_MFG_MODE")
		)
		(pad "2" smd circle
			(at -0.40005 0)
			(size 0 0)
			(layers "B.Cu" "B.Mask" "B.Paste")
			(net "GND")
		)
	)
	(footprint ""
		(layer "B.Cu")
		(at 168.475152 -344.941906 -90)
		(property "Reference" "PC410_P1_1"
			(at 0 0 90)
			(layer "B.SilkS")
			(hide yes)
			(effects
				(font
					(size 1.27 1.27)
				)
				(justify mirror)
			)
		)
		(property "Value" ""
			(at 0 0 90)
			(layer "B.Fab")
			(effects
				(font
					(size 1.27 1.27)
				)
				(justify mirror)
			)
		)
		(duplicate_pad_numbers_are_jumpers no)
		(fp_line
			(start -1.524 0.762)
			(end 1.524 0.762)
			(stroke
				(width 0.1524)
				(type default)
			)
			(layer "B.SilkS")
		)
		(fp_line
			(start 1.524 0.762)
			(end 1.524 -0.762)
			(stroke
				(width 0.1524)
				(type default)
			)
			(layer "B.SilkS")
		)
		(fp_line
			(start -1.524 -0.762)
			(end -1.524 0.762)
			(stroke
				(width 0.1524)
				(type default)
			)
			(layer "B.SilkS")
		)
		(fp_line
			(start 1.524 -0.762)
			(end -1.524 -0.762)
			(stroke
				(width 0.1524)
				(type default)
			)
			(layer "B.SilkS")
		)
		(fp_line
			(start -1.1049 0.724916)
			(end -1.1049 -0.724916)
			(stroke
				(width 0.1)
				(type default)
			)
			(layer "B.Fab")
		)
		(fp_line
			(start 1.1049 0.724916)
			(end -1.1049 0.724916)
			(stroke
				(width 0.1)
				(type default)
			)
			(layer "B.Fab")
		)
		(fp_line
			(start -1.1049 -0.724916)
			(end 1.1049 -0.724916)
			(stroke
				(width 0.1)
				(type default)
			)
			(layer "B.Fab")
		)
		(fp_line
			(start 1.1049 -0.724916)
			(end 1.1049 0.724916)
			(stroke
				(width 0.1)
				(type default)
			)
			(layer "B.Fab")
		)
		(pad "1" smd rect
			(at 0.889 0 270)
			(size 1.016 1.27)
			(layers "B.Cu" "B.Mask" "B.Paste")
			(net "PVCCFA_EHV_FIVRA_CPU1")
		)
		(pad "2" smd rect
			(at -0.889 0 270)
			(size 1.016 1.27)
			(layers "B.Cu" "B.Mask" "B.Paste")
			(net "GND")
		)
	)
	(footprint ""
		(layer "B.Cu")
		(at 23.240746 -319.268856 180)
		(property "Reference" "C62"
			(at 0 0 0)
			(layer "B.SilkS")
			(hide yes)
			(effects
				(font
					(size 1.27 1.27)
				)
				(justify mirror)
			)
		)
		(property "Value" ""
			(at 0 0 0)
			(layer "B.Fab")
			(effects
				(font
					(size 1.27 1.27)
				)
				(justify mirror)
			)
		)
		(duplicate_pad_numbers_are_jumpers no)
		(fp_line
			(start 0.7874 0.4064)
			(end 0.7874 -0.4064)
			(stroke
				(width 0.1524)
				(type default)
			)
			(layer "B.SilkS")
		)
		(fp_line
			(start 0.7874 -0.4064)
			(end -0.7874 -0.4064)
			(stroke
				(width 0.1524)
				(type default)
			)
			(layer "B.SilkS")
		)
		(fp_line
			(start -0.7874 0.4064)
			(end 0.7874 0.4064)
			(stroke
				(width 0.1524)
				(type default)
			)
			(layer "B.SilkS")
		)
		(fp_line
			(start -0.7874 -0.4064)
			(end -0.7874 0.4064)
			(stroke
				(width 0.1524)
				(type default)
			)
			(layer "B.SilkS")
		)
		(fp_line
			(start 0.67945 0.3048)
			(end 0.67945 -0.305054)
			(stroke
				(width 0.1)
				(type default)
			)
			(layer "B.Fab")
		)
		(fp_line
			(start 0.67945 -0.305054)
			(end 0.12065 -0.305054)
			(stroke
				(width 0.1)
				(type default)
			)
			(layer "B.Fab")
		)
		(fp_line
			(start 0.12065 0.3048)
			(end 0.67945 0.3048)
			(stroke
				(width 0.1)
				(type default)
			)
			(layer "B.Fab")
		)
		(fp_line
			(start 0.12065 0.2794)
			(end 0.12065 0.3048)
			(stroke
				(width 0.1)
				(type default)
			)
			(layer "B.Fab")
		)
		(fp_line
			(start 0.12065 -0.2794)
			(end -0.12065 -0.2794)
			(stroke
				(width 0.1)
				(type default)
			)
			(layer "B.Fab")
		)
		(fp_line
			(start 0.12065 -0.305054)
			(end 0.12065 -0.2794)
			(stroke
				(width 0.1)
				(type default)
			)
			(layer "B.Fab")
		)
		(fp_line
			(start -0.120396 0.3048)
			(end -0.120396 0.2794)
			(stroke
				(width 0.1)
				(type default)
			)
			(layer "B.Fab")
		)
		(fp_line
			(start -0.120396 0.2794)
			(end 0.12065 0.2794)
			(stroke
				(width 0.1)
				(type default)
			)
			(layer "B.Fab")
		)
		(fp_line
			(start -0.12065 -0.2794)
			(end -0.12065 -0.3048)
			(stroke
				(width 0.1)
				(type default)
			)
			(layer "B.Fab")
		)
		(fp_line
			(start -0.12065 -0.3048)
			(end -0.67945 -0.3048)
			(stroke
				(width 0.1)
				(type default)
			)
			(layer "B.Fab")
		)
		(fp_line
			(start -0.67945 0.3048)
			(end -0.120396 0.3048)
			(stroke
				(width 0.1)
				(type default)
			)
			(layer "B.Fab")
		)
		(fp_line
			(start -0.67945 -0.3048)
			(end -0.67945 0.3048)
			(stroke
				(width 0.1)
				(type default)
			)
			(layer "B.Fab")
		)
		(pad "1" smd circle
			(at 0.40005 0)
			(size 0 0)
			(layers "B.Cu" "B.Mask" "B.Paste")
			(net "P3V3_AUX")
		)
		(pad "2" smd circle
			(at -0.40005 0)
			(size 0 0)
			(layers "B.Cu" "B.Mask" "B.Paste")
			(net "GND")
		)
	)
	(footprint ""
		(layer "B.Cu")
		(at 315.110622 -51.171348)
		(property "Reference" "R1339"
			(at 0 0 0)
			(layer "B.SilkS")
			(hide yes)
			(effects
				(font
					(size 1.27 1.27)
				)
				(justify mirror)
			)
		)
		(property "Value" ""
			(at 0 0 0)
			(layer "B.Fab")
			(effects
				(font
					(size 1.27 1.27)
				)
				(justify mirror)
			)
		)
		(duplicate_pad_numbers_are_jumpers no)
		(fp_line
			(start -0.7874 -0.4064)
			(end -0.7874 0.4064)
			(stroke
				(width 0.1524)
				(type default)
			)
			(layer "B.SilkS")
		)
		(fp_line
			(start -0.7874 0.4064)
			(end 0.7874 0.4064)
			(stroke
				(width 0.1524)
				(type default)
			)
			(layer "B.SilkS")
		)
		(fp_line
			(start 0.7874 -0.4064)
			(end -0.7874 -0.4064)
			(stroke
				(width 0.1524)
				(type default)
			)
			(layer "B.SilkS")
		)
		(fp_line
			(start 0.7874 0.4064)
			(end 0.7874 -0.4064)
			(stroke
				(width 0.1524)
				(type default)
			)
			(layer "B.SilkS")
		)
		(fp_line
			(start -0.67945 -0.3048)
			(end -0.67945 0.3048)
			(stroke
				(width 0.1)
				(type default)
			)
			(layer "B.Fab")
		)
		(fp_line
			(start -0.67945 0.3048)
			(end -0.120396 0.3048)
			(stroke
				(width 0.1)
				(type default)
			)
			(layer "B.Fab")
		)
		(fp_line
			(start -0.12065 -0.3048)
			(end -0.67945 -0.3048)
			(stroke
				(width 0.1)
				(type default)
			)
			(layer "B.Fab")
		)
		(fp_line
			(start -0.12065 -0.2794)
			(end -0.12065 -0.3048)
			(stroke
				(width 0.1)
				(type default)
			)
			(layer "B.Fab")
		)
		(fp_line
			(start -0.120396 0.2794)
			(end 0.12065 0.2794)
			(stroke
				(width 0.1)
				(type default)
			)
			(layer "B.Fab")
		)
		(fp_line
			(start -0.120396 0.3048)
			(end -0.120396 0.2794)
			(stroke
				(width 0.1)
				(type default)
			)
			(layer "B.Fab")
		)
		(fp_line
			(start 0.12065 -0.305054)
			(end 0.12065 -0.2794)
			(stroke
				(width 0.1)
				(type default)
			)
			(layer "B.Fab")
		)
		(fp_line
			(start 0.12065 -0.2794)
			(end -0.12065 -0.2794)
			(stroke
				(width 0.1)
				(type default)
			)
			(layer "B.Fab")
		)
		(fp_line
			(start 0.12065 0.2794)
			(end 0.12065 0.3048)
			(stroke
				(width 0.1)
				(type default)
			)
			(layer "B.Fab")
		)
		(fp_line
			(start 0.12065 0.3048)
			(end 0.67945 0.3048)
			(stroke
				(width 0.1)
				(type default)
			)
			(layer "B.Fab")
		)
		(fp_line
			(start 0.67945 -0.305054)
			(end 0.12065 -0.305054)
			(stroke
				(width 0.1)
				(type default)
			)
			(layer "B.Fab")
		)
		(fp_line
			(start 0.67945 0.3048)
			(end 0.67945 -0.305054)
			(stroke
				(width 0.1)
				(type default)
			)
			(layer "B.Fab")
		)
		(pad "1" smd circle
			(at 0.40005 0 180)
			(size 0 0)
			(layers "B.Cu" "B.Mask" "B.Paste")
			(net "P3V3_AUX")
		)
		(pad "2" smd circle
			(at -0.40005 0 180)
			(size 0 0)
			(layers "B.Cu" "B.Mask" "B.Paste")
			(net "FM_BIOS_IMAGE_SWAP_N")
		)
	)
	(footprint ""
		(layer "B.Cu")
		(at 246.984266 -128.343914 -90)
		(property "Reference" "R570"
			(at 0 0 90)
			(layer "B.SilkS")
			(hide yes)
			(effects
				(font
					(size 1.27 1.27)
				)
				(justify mirror)
			)
		)
		(property "Value" ""
			(at 0 0 90)
			(layer "B.Fab")
			(effects
				(font
					(size 1.27 1.27)
				)
				(justify mirror)
			)
		)
		(duplicate_pad_numbers_are_jumpers no)
		(fp_line
			(start -0.7874 0.4064)
			(end 0.7874 0.4064)
			(stroke
				(width 0.1524)
				(type default)
			)
			(layer "B.SilkS")
		)
		(fp_line
			(start 0.7874 0.4064)
			(end 0.7874 -0.4064)
			(stroke
				(width 0.1524)
				(type default)
			)
			(layer "B.SilkS")
		)
		(fp_line
			(start -0.7874 -0.4064)
			(end -0.7874 0.4064)
			(stroke
				(width 0.1524)
				(type default)
			)
			(layer "B.SilkS")
		)
		(fp_line
			(start 0.7874 -0.4064)
			(end -0.7874 -0.4064)
			(stroke
				(width 0.1524)
				(type default)
			)
			(layer "B.SilkS")
		)
		(fp_line
			(start -0.67945 0.3048)
			(end -0.120396 0.3048)
			(stroke
				(width 0.1)
				(type default)
			)
			(layer "B.Fab")
		)
		(fp_line
			(start -0.120396 0.3048)
			(end -0.120396 0.2794)
			(stroke
				(width 0.1)
				(type default)
			)
			(layer "B.Fab")
		)
		(fp_line
			(start 0.12065 0.3048)
			(end 0.67945 0.3048)
			(stroke
				(width 0.1)
				(type default)
			)
			(layer "B.Fab")
		)
		(fp_line
			(start 0.67945 0.3048)
			(end 0.67945 -0.305054)
			(stroke
				(width 0.1)
				(type default)
			)
			(layer "B.Fab")
		)
		(fp_line
			(start -0.120396 0.2794)
			(end 0.12065 0.2794)
			(stroke
				(width 0.1)
				(type default)
			)
			(layer "B.Fab")
		)
		(fp_line
			(start 0.12065 0.2794)
			(end 0.12065 0.3048)
			(stroke
				(width 0.1)
				(type default)
			)
			(layer "B.Fab")
		)
		(fp_line
			(start -0.12065 -0.2794)
			(end -0.12065 -0.3048)
			(stroke
				(width 0.1)
				(type default)
			)
			(layer "B.Fab")
		)
		(fp_line
			(start 0.12065 -0.2794)
			(end -0.12065 -0.2794)
			(stroke
				(width 0.1)
				(type default)
			)
			(layer "B.Fab")
		)
		(fp_line
			(start -0.67945 -0.3048)
			(end -0.67945 0.3048)
			(stroke
				(width 0.1)
				(type default)
			)
			(layer "B.Fab")
		)
		(fp_line
			(start -0.12065 -0.3048)
			(end -0.67945 -0.3048)
			(stroke
				(width 0.1)
				(type default)
			)
			(layer "B.Fab")
		)
		(fp_line
			(start 0.12065 -0.305054)
			(end 0.12065 -0.2794)
			(stroke
				(width 0.1)
				(type default)
			)
			(layer "B.Fab")
		)
		(fp_line
			(start 0.67945 -0.305054)
			(end 0.12065 -0.305054)
			(stroke
				(width 0.1)
				(type default)
			)
			(layer "B.Fab")
		)
		(pad "1" smd circle
			(at 0.40005 0 90)
			(size 0 0)
			(layers "B.Cu" "B.Mask" "B.Paste")
			(net "PD_DB2000_SMB_SA0")
		)
		(pad "2" smd circle
			(at -0.40005 0 90)
			(size 0 0)
			(layers "B.Cu" "B.Mask" "B.Paste")
			(net "GND")
		)
	)
	(footprint ""
		(layer "B.Cu")
		(at 237.24108 -252.113288 90)
		(property "Reference" "C1886"
			(at 0 0 90)
			(layer "B.SilkS")
			(hide yes)
			(effects
				(font
					(size 1.27 1.27)
				)
				(justify mirror)
			)
		)
		(property "Value" ""
			(at 0 0 90)
			(layer "B.Fab")
			(effects
				(font
					(size 1.27 1.27)
				)
				(justify mirror)
			)
		)
		(duplicate_pad_numbers_are_jumpers no)
		(fp_line
			(start 0.7874 -0.4064)
			(end -0.7874 -0.4064)
			(stroke
				(width 0.1524)
				(type default)
			)
			(layer "B.SilkS")
		)
		(fp_line
			(start -0.7874 -0.4064)
			(end -0.7874 0.4064)
			(stroke
				(width 0.1524)
				(type default)
			)
			(layer "B.SilkS")
		)
		(fp_line
			(start 0.7874 0.4064)
			(end 0.7874 -0.4064)
			(stroke
				(width 0.1524)
				(type default)
			)
			(layer "B.SilkS")
		)
		(fp_line
			(start -0.7874 0.4064)
			(end 0.7874 0.4064)
			(stroke
				(width 0.1524)
				(type default)
			)
			(layer "B.SilkS")
		)
		(fp_line
			(start 0.67945 -0.305054)
			(end 0.12065 -0.305054)
			(stroke
				(width 0.1)
				(type default)
			)
			(layer "B.Fab")
		)
		(fp_line
			(start 0.12065 -0.305054)
			(end 0.12065 -0.2794)
			(stroke
				(width 0.1)
				(type default)
			)
			(layer "B.Fab")
		)
		(fp_line
			(start -0.12065 -0.3048)
			(end -0.67945 -0.3048)
			(stroke
				(width 0.1)
				(type default)
			)
			(layer "B.Fab")
		)
		(fp_line
			(start -0.67945 -0.3048)
			(end -0.67945 0.3048)
			(stroke
				(width 0.1)
				(type default)
			)
			(layer "B.Fab")
		)
		(fp_line
			(start 0.12065 -0.2794)
			(end -0.12065 -0.2794)
			(stroke
				(width 0.1)
				(type default)
			)
			(layer "B.Fab")
		)
		(fp_line
			(start -0.12065 -0.2794)
			(end -0.12065 -0.3048)
			(stroke
				(width 0.1)
				(type default)
			)
			(layer "B.Fab")
		)
		(fp_line
			(start 0.12065 0.2794)
			(end 0.12065 0.3048)
			(stroke
				(width 0.1)
				(type default)
			)
			(layer "B.Fab")
		)
		(fp_line
			(start -0.120396 0.2794)
			(end 0.12065 0.2794)
			(stroke
				(width 0.1)
				(type default)
			)
			(layer "B.Fab")
		)
		(fp_line
			(start 0.67945 0.3048)
			(end 0.67945 -0.305054)
			(stroke
				(width 0.1)
				(type default)
			)
			(layer "B.Fab")
		)
		(fp_line
			(start 0.12065 0.3048)
			(end 0.67945 0.3048)
			(stroke
				(width 0.1)
				(type default)
			)
			(layer "B.Fab")
		)
		(fp_line
			(start -0.120396 0.3048)
			(end -0.120396 0.2794)
			(stroke
				(width 0.1)
				(type default)
			)
			(layer "B.Fab")
		)
		(fp_line
			(start -0.67945 0.3048)
			(end -0.120396 0.3048)
			(stroke
				(width 0.1)
				(type default)
			)
			(layer "B.Fab")
		)
		(pad "1" smd circle
			(at 0.40005 0 270)
			(size 0 0)
			(layers "B.Cu" "B.Mask" "B.Paste")
			(net "VFG3P3_CLK_GEN")
		)
		(pad "2" smd circle
			(at -0.40005 0 270)
			(size 0 0)
			(layers "B.Cu" "B.Mask" "B.Paste")
			(net "GND")
		)
	)
	(footprint ""
		(layer "B.Cu")
		(at 189.001146 -321.554856 -90)
		(property "Reference" "C80"
			(at 0 0 90)
			(layer "B.SilkS")
			(hide yes)
			(effects
				(font
					(size 1.27 1.27)
				)
				(justify mirror)
			)
		)
		(property "Value" ""
			(at 0 0 90)
			(layer "B.Fab")
			(effects
				(font
					(size 1.27 1.27)
				)
				(justify mirror)
			)
		)
		(duplicate_pad_numbers_are_jumpers no)
		(fp_line
			(start -1.524 0.762)
			(end 1.524 0.762)
			(stroke
				(width 0.1524)
				(type default)
			)
			(layer "B.SilkS")
		)
		(fp_line
			(start 1.524 0.762)
			(end 1.524 -0.762)
			(stroke
				(width 0.1524)
				(type default)
			)
			(layer "B.SilkS")
		)
		(fp_line
			(start -1.524 -0.762)
			(end -1.524 0.762)
			(stroke
				(width 0.1524)
				(type default)
			)
			(layer "B.SilkS")
		)
		(fp_line
			(start 1.524 -0.762)
			(end -1.524 -0.762)
			(stroke
				(width 0.1524)
				(type default)
			)
			(layer "B.SilkS")
		)
		(fp_line
			(start -1.1049 0.724916)
			(end -1.1049 -0.724916)
			(stroke
				(width 0.1)
				(type default)
			)
			(layer "B.Fab")
		)
		(fp_line
			(start 1.1049 0.724916)
			(end -1.1049 0.724916)
			(stroke
				(width 0.1)
				(type default)
			)
			(layer "B.Fab")
		)
		(fp_line
			(start -1.1049 -0.724916)
			(end 1.1049 -0.724916)
			(stroke
				(width 0.1)
				(type default)
			)
			(layer "B.Fab")
		)
		(fp_line
			(start 1.1049 -0.724916)
			(end 1.1049 0.724916)
			(stroke
				(width 0.1)
				(type default)
			)
			(layer "B.Fab")
		)
		(pad "1" smd rect
			(at 0.889 0 270)
			(size 1.016 1.27)
			(layers "B.Cu" "B.Mask" "B.Paste")
			(net "P12V_S3_AUX_CPU1_NVDIMM")
		)
		(pad "2" smd rect
			(at -0.889 0 270)
			(size 1.016 1.27)
			(layers "B.Cu" "B.Mask" "B.Paste")
			(net "GND")
		)
	)
	(footprint ""
		(layer "B.Cu")
		(at 178.323748 -319.022476 90)
		(property "Reference" "R2736"
			(at 0 0 90)
			(layer "B.SilkS")
			(hide yes)
			(effects
				(font
					(size 1.27 1.27)
				)
				(justify mirror)
			)
		)
		(property "Value" ""
			(at 0 0 90)
			(layer "B.Fab")
			(effects
				(font
					(size 1.27 1.27)
				)
				(justify mirror)
			)
		)
		(duplicate_pad_numbers_are_jumpers no)
		(fp_line
			(start 0.7874 -0.4064)
			(end -0.7874 -0.4064)
			(stroke
				(width 0.1524)
				(type default)
			)
			(layer "B.SilkS")
		)
		(fp_line
			(start -0.7874 -0.4064)
			(end -0.7874 0.4064)
			(stroke
				(width 0.1524)
				(type default)
			)
			(layer "B.SilkS")
		)
		(fp_line
			(start 0.7874 0.4064)
			(end 0.7874 -0.4064)
			(stroke
				(width 0.1524)
				(type default)
			)
			(layer "B.SilkS")
		)
		(fp_line
			(start -0.7874 0.4064)
			(end 0.7874 0.4064)
			(stroke
				(width 0.1524)
				(type default)
			)
			(layer "B.SilkS")
		)
		(fp_line
			(start 0.67945 -0.305054)
			(end 0.12065 -0.305054)
			(stroke
				(width 0.1)
				(type default)
			)
			(layer "B.Fab")
		)
		(fp_line
			(start 0.12065 -0.305054)
			(end 0.12065 -0.2794)
			(stroke
				(width 0.1)
				(type default)
			)
			(layer "B.Fab")
		)
		(fp_line
			(start -0.12065 -0.3048)
			(end -0.67945 -0.3048)
			(stroke
				(width 0.1)
				(type default)
			)
			(layer "B.Fab")
		)
		(fp_line
			(start -0.67945 -0.3048)
			(end -0.67945 0.3048)
			(stroke
				(width 0.1)
				(type default)
			)
			(layer "B.Fab")
		)
		(fp_line
			(start 0.12065 -0.2794)
			(end -0.12065 -0.2794)
			(stroke
				(width 0.1)
				(type default)
			)
			(layer "B.Fab")
		)
		(fp_line
			(start -0.12065 -0.2794)
			(end -0.12065 -0.3048)
			(stroke
				(width 0.1)
				(type default)
			)
			(layer "B.Fab")
		)
		(fp_line
			(start 0.12065 0.2794)
			(end 0.12065 0.3048)
			(stroke
				(width 0.1)
				(type default)
			)
			(layer "B.Fab")
		)
		(fp_line
			(start -0.120396 0.2794)
			(end 0.12065 0.2794)
			(stroke
				(width 0.1)
				(type default)
			)
			(layer "B.Fab")
		)
		(fp_line
			(start 0.67945 0.3048)
			(end 0.67945 -0.305054)
			(stroke
				(width 0.1)
				(type default)
			)
			(layer "B.Fab")
		)
		(fp_line
			(start 0.12065 0.3048)
			(end 0.67945 0.3048)
			(stroke
				(width 0.1)
				(type default)
			)
			(layer "B.Fab")
		)
		(fp_line
			(start -0.120396 0.3048)
			(end -0.120396 0.2794)
			(stroke
				(width 0.1)
				(type default)
			)
			(layer "B.Fab")
		)
		(fp_line
			(start -0.67945 0.3048)
			(end -0.120396 0.3048)
			(stroke
				(width 0.1)
				(type default)
			)
			(layer "B.Fab")
		)
		(pad "1" smd circle
			(at 0.40005 0 270)
			(size 0 0)
			(layers "B.Cu" "B.Mask" "B.Paste")
			(net "PWRGD_CHF_CPU1_DIMM2")
		)
		(pad "2" smd circle
			(at -0.40005 0 270)
			(size 0 0)
			(layers "B.Cu" "B.Mask" "B.Paste")
			(net "PWRGD_FAIL_CPU1_EF")
		)
	)
	(footprint ""
		(layer "B.Cu")
		(at 104.790494 -237.794292 -90)
		(property "Reference" "C1393"
			(at 0 0 90)
			(layer "B.SilkS")
			(hide yes)
			(effects
				(font
					(size 1.27 1.27)
				)
				(justify mirror)
			)
		)
		(property "Value" ""
			(at 0 0 90)
			(layer "B.Fab")
			(effects
				(font
					(size 1.27 1.27)
				)
				(justify mirror)
			)
		)
		(duplicate_pad_numbers_are_jumpers no)
		(fp_line
			(start -1.2954 0.5842)
			(end 1.2954 0.5842)
			(stroke
				(width 0.1524)
				(type default)
			)
			(layer "B.SilkS")
		)
		(fp_line
			(start 1.2954 0.5842)
			(end 1.2954 -0.5842)
			(stroke
				(width 0.1524)
				(type default)
			)
			(layer "B.SilkS")
		)
		(fp_line
			(start -1.2954 -0.5842)
			(end -1.2954 0.5842)
			(stroke
				(width 0.1524)
				(type default)
			)
			(layer "B.SilkS")
		)
		(fp_line
			(start 0 -0.5842)
			(end 0 0.5842)
			(stroke
				(width 0.1524)
				(type default)
			)
			(layer "B.SilkS")
		)
		(fp_line
			(start 1.2954 -0.5842)
			(end -1.2954 -0.5842)
			(stroke
				(width 0.1524)
				(type default)
			)
			(layer "B.SilkS")
		)
		(fp_line
			(start -0.8636 0.4572)
			(end 0.8636 0.4572)
			(stroke
				(width 0.1)
				(type default)
			)
			(layer "B.Fab")
		)
		(fp_line
			(start 0.8636 0.4572)
			(end 0.8636 0.4064)
			(stroke
				(width 0.1)
				(type default)
			)
			(layer "B.Fab")
		)
		(fp_line
			(start -1.1938 0.4064)
			(end -0.8636 0.4064)
			(stroke
				(width 0.1)
				(type default)
			)
			(layer "B.Fab")
		)
		(fp_line
			(start -0.8636 0.4064)
			(end -0.8636 0.4572)
			(stroke
				(width 0.1)
				(type default)
			)
			(layer "B.Fab")
		)
		(fp_line
			(start 0.8636 0.4064)
			(end 1.1938 0.4064)
			(stroke
				(width 0.1)
				(type default)
			)
			(layer "B.Fab")
		)
		(fp_line
			(start 1.1938 0.4064)
			(end 1.1938 -0.4064)
			(stroke
				(width 0.1)
				(type default)
			)
			(layer "B.Fab")
		)
		(fp_line
			(start -1.1938 -0.4064)
			(end -1.1938 0.4064)
			(stroke
				(width 0.1)
				(type default)
			)
			(layer "B.Fab")
		)
		(fp_line
			(start -0.8636 -0.4064)
			(end -1.1938 -0.4064)
			(stroke
				(width 0.1)
				(type default)
			)
			(layer "B.Fab")
		)
		(fp_line
			(start 0.8636 -0.4064)
			(end 0.8636 -0.4572)
			(stroke
				(width 0.1)
				(type default)
			)
			(layer "B.Fab")
		)
		(fp_line
			(start 1.1938 -0.4064)
			(end 0.8636 -0.4064)
			(stroke
				(width 0.1)
				(type default)
			)
			(layer "B.Fab")
		)
		(fp_line
			(start -0.8636 -0.4572)
			(end -0.8636 -0.4064)
			(stroke
				(width 0.1)
				(type default)
			)
			(layer "B.Fab")
		)
		(fp_line
			(start 0.8636 -0.4572)
			(end -0.8636 -0.4572)
			(stroke
				(width 0.1)
				(type default)
			)
			(layer "B.Fab")
		)
		(pad "1" smd rect
			(at 0.7366 0 180)
			(size 0.7112 0.8128)
			(layers "B.Cu" "B.Mask" "B.Paste")
			(net "PVNN_MAIN_CPU1")
		)
		(pad "2" smd rect
			(at -0.7366 0 180)
			(size 0.7112 0.8128)
			(layers "B.Cu" "B.Mask" "B.Paste")
			(net "GND")
		)
	)
	(footprint ""
		(layer "B.Cu")
		(at 433.832 -24.094948 -90)
		(property "Reference" "R1897"
			(at 0 0 90)
			(layer "B.SilkS")
			(hide yes)
			(effects
				(font
					(size 1.27 1.27)
				)
				(justify mirror)
			)
		)
		(property "Value" ""
			(at 0 0 90)
			(layer "B.Fab")
			(effects
				(font
					(size 1.27 1.27)
				)
				(justify mirror)
			)
		)
		(duplicate_pad_numbers_are_jumpers no)
		(fp_line
			(start -0.7874 0.4064)
			(end 0.7874 0.4064)
			(stroke
				(width 0.1524)
				(type default)
			)
			(layer "B.SilkS")
		)
		(fp_line
			(start 0.7874 0.4064)
			(end 0.7874 -0.4064)
			(stroke
				(width 0.1524)
				(type default)
			)
			(layer "B.SilkS")
		)
		(fp_line
			(start -0.7874 -0.4064)
			(end -0.7874 0.4064)
			(stroke
				(width 0.1524)
				(type default)
			)
			(layer "B.SilkS")
		)
		(fp_line
			(start 0.7874 -0.4064)
			(end -0.7874 -0.4064)
			(stroke
				(width 0.1524)
				(type default)
			)
			(layer "B.SilkS")
		)
		(fp_line
			(start -0.67945 0.3048)
			(end -0.120396 0.3048)
			(stroke
				(width 0.1)
				(type default)
			)
			(layer "B.Fab")
		)
		(fp_line
			(start -0.120396 0.3048)
			(end -0.120396 0.2794)
			(stroke
				(width 0.1)
				(type default)
			)
			(layer "B.Fab")
		)
		(fp_line
			(start 0.12065 0.3048)
			(end 0.67945 0.3048)
			(stroke
				(width 0.1)
				(type default)
			)
			(layer "B.Fab")
		)
		(fp_line
			(start 0.67945 0.3048)
			(end 0.67945 -0.305054)
			(stroke
				(width 0.1)
				(type default)
			)
			(layer "B.Fab")
		)
		(fp_line
			(start -0.120396 0.2794)
			(end 0.12065 0.2794)
			(stroke
				(width 0.1)
				(type default)
			)
			(layer "B.Fab")
		)
		(fp_line
			(start 0.12065 0.2794)
			(end 0.12065 0.3048)
			(stroke
				(width 0.1)
				(type default)
			)
			(layer "B.Fab")
		)
		(fp_line
			(start -0.12065 -0.2794)
			(end -0.12065 -0.3048)
			(stroke
				(width 0.1)
				(type default)
			)
			(layer "B.Fab")
		)
		(fp_line
			(start 0.12065 -0.2794)
			(end -0.12065 -0.2794)
			(stroke
				(width 0.1)
				(type default)
			)
			(layer "B.Fab")
		)
		(fp_line
			(start -0.67945 -0.3048)
			(end -0.67945 0.3048)
			(stroke
				(width 0.1)
				(type default)
			)
			(layer "B.Fab")
		)
		(fp_line
			(start -0.12065 -0.3048)
			(end -0.67945 -0.3048)
			(stroke
				(width 0.1)
				(type default)
			)
			(layer "B.Fab")
		)
		(fp_line
			(start 0.12065 -0.305054)
			(end 0.12065 -0.2794)
			(stroke
				(width 0.1)
				(type default)
			)
			(layer "B.Fab")
		)
		(fp_line
			(start 0.67945 -0.305054)
			(end 0.12065 -0.305054)
			(stroke
				(width 0.1)
				(type default)
			)
			(layer "B.Fab")
		)
		(pad "1" smd circle
			(at 0.40005 0 90)
			(size 0 0)
			(layers "B.Cu" "B.Mask" "B.Paste")
			(net "OCP_SFF_ISO_BIF1_EN")
		)
		(pad "2" smd circle
			(at -0.40005 0 90)
			(size 0 0)
			(layers "B.Cu" "B.Mask" "B.Paste")
			(net "GND")
		)
	)
	(footprint ""
		(layer "B.Cu")
		(at 62.666372 -168.58488)
		(property "Reference" "PC382"
			(at 0 0 0)
			(layer "B.SilkS")
			(hide yes)
			(effects
				(font
					(size 1.27 1.27)
				)
				(justify mirror)
			)
		)
		(property "Value" ""
			(at 0 0 0)
			(layer "B.Fab")
			(effects
				(font
					(size 1.27 1.27)
				)
				(justify mirror)
			)
		)
		(duplicate_pad_numbers_are_jumpers no)
		(fp_line
			(start -1.524 -0.762)
			(end -1.524 0.762)
			(stroke
				(width 0.1524)
				(type default)
			)
			(layer "B.SilkS")
		)
		(fp_line
			(start -1.524 0.762)
			(end 1.524 0.762)
			(stroke
				(width 0.1524)
				(type default)
			)
			(layer "B.SilkS")
		)
		(fp_line
			(start 1.524 -0.762)
			(end -1.524 -0.762)
			(stroke
				(width 0.1524)
				(type default)
			)
			(layer "B.SilkS")
		)
		(fp_line
			(start 1.524 0.762)
			(end 1.524 -0.762)
			(stroke
				(width 0.1524)
				(type default)
			)
			(layer "B.SilkS")
		)
		(fp_line
			(start -1.1049 -0.724916)
			(end 1.1049 -0.724916)
			(stroke
				(width 0.1)
				(type default)
			)
			(layer "B.Fab")
		)
		(fp_line
			(start -1.1049 0.724916)
			(end -1.1049 -0.724916)
			(stroke
				(width 0.1)
				(type default)
			)
			(layer "B.Fab")
		)
		(fp_line
			(start 1.1049 -0.724916)
			(end 1.1049 0.724916)
			(stroke
				(width 0.1)
				(type default)
			)
			(layer "B.Fab")
		)
		(fp_line
			(start 1.1049 0.724916)
			(end -1.1049 0.724916)
			(stroke
				(width 0.1)
				(type default)
			)
			(layer "B.Fab")
		)
		(pad "1" smd rect
			(at 0.889 0)
			(size 1.016 1.27)
			(layers "B.Cu" "B.Mask" "B.Paste")
			(net "PVCCD_HV_CPU1")
		)
		(pad "2" smd rect
			(at -0.889 0)
			(size 1.016 1.27)
			(layers "B.Cu" "B.Mask" "B.Paste")
			(net "GND")
		)
	)
	(footprint ""
		(layer "B.Cu")
		(at 187.174886 -193.599816 -90)
		(property "Reference" "C616"
			(at 0 0 90)
			(layer "B.SilkS")
			(hide yes)
			(effects
				(font
					(size 1.27 1.27)
				)
				(justify mirror)
			)
		)
		(property "Value" ""
			(at 0 0 90)
			(layer "B.Fab")
			(effects
				(font
					(size 1.27 1.27)
				)
				(justify mirror)
			)
		)
		(duplicate_pad_numbers_are_jumpers no)
		(fp_line
			(start -0.7874 0.4064)
			(end 0.7874 0.4064)
			(stroke
				(width 0.1524)
				(type default)
			)
			(layer "B.SilkS")
		)
		(fp_line
			(start 0.7874 0.4064)
			(end 0.7874 -0.4064)
			(stroke
				(width 0.1524)
				(type default)
			)
			(layer "B.SilkS")
		)
		(fp_line
			(start -0.7874 -0.4064)
			(end -0.7874 0.4064)
			(stroke
				(width 0.1524)
				(type default)
			)
			(layer "B.SilkS")
		)
		(fp_line
			(start 0.7874 -0.4064)
			(end -0.7874 -0.4064)
			(stroke
				(width 0.1524)
				(type default)
			)
			(layer "B.SilkS")
		)
		(fp_line
			(start -0.67945 0.3048)
			(end -0.120396 0.3048)
			(stroke
				(width 0.1)
				(type default)
			)
			(layer "B.Fab")
		)
		(fp_line
			(start -0.120396 0.3048)
			(end -0.120396 0.2794)
			(stroke
				(width 0.1)
				(type default)
			)
			(layer "B.Fab")
		)
		(fp_line
			(start 0.12065 0.3048)
			(end 0.67945 0.3048)
			(stroke
				(width 0.1)
				(type default)
			)
			(layer "B.Fab")
		)
		(fp_line
			(start 0.67945 0.3048)
			(end 0.67945 -0.305054)
			(stroke
				(width 0.1)
				(type default)
			)
			(layer "B.Fab")
		)
		(fp_line
			(start -0.120396 0.2794)
			(end 0.12065 0.2794)
			(stroke
				(width 0.1)
				(type default)
			)
			(layer "B.Fab")
		)
		(fp_line
			(start 0.12065 0.2794)
			(end 0.12065 0.3048)
			(stroke
				(width 0.1)
				(type default)
			)
			(layer "B.Fab")
		)
		(fp_line
			(start -0.12065 -0.2794)
			(end -0.12065 -0.3048)
			(stroke
				(width 0.1)
				(type default)
			)
			(layer "B.Fab")
		)
		(fp_line
			(start 0.12065 -0.2794)
			(end -0.12065 -0.2794)
			(stroke
				(width 0.1)
				(type default)
			)
			(layer "B.Fab")
		)
		(fp_line
			(start -0.67945 -0.3048)
			(end -0.67945 0.3048)
			(stroke
				(width 0.1)
				(type default)
			)
			(layer "B.Fab")
		)
		(fp_line
			(start -0.12065 -0.3048)
			(end -0.67945 -0.3048)
			(stroke
				(width 0.1)
				(type default)
			)
			(layer "B.Fab")
		)
		(fp_line
			(start 0.12065 -0.305054)
			(end 0.12065 -0.2794)
			(stroke
				(width 0.1)
				(type default)
			)
			(layer "B.Fab")
		)
		(fp_line
			(start 0.67945 -0.305054)
			(end 0.12065 -0.305054)
			(stroke
				(width 0.1)
				(type default)
			)
			(layer "B.Fab")
		)
		(pad "1" smd circle
			(at 0.40005 0 90)
			(size 0 0)
			(layers "B.Cu" "B.Mask" "B.Paste")
			(net "RST_PLD_CPU1_DRAM_EF_N")
		)
		(pad "2" smd circle
			(at -0.40005 0 90)
			(size 0 0)
			(layers "B.Cu" "B.Mask" "B.Paste")
			(net "GND")
		)
	)
	(footprint ""
		(layer "B.Cu")
		(at 355.397308 -241.142266 90)
		(property "Reference" "C360"
			(at 0 0 90)
			(layer "B.SilkS")
			(hide yes)
			(effects
				(font
					(size 1.27 1.27)
				)
				(justify mirror)
			)
		)
		(property "Value" ""
			(at 0 0 90)
			(layer "B.Fab")
			(effects
				(font
					(size 1.27 1.27)
				)
				(justify mirror)
			)
		)
		(duplicate_pad_numbers_are_jumpers no)
		(fp_line
			(start 1.524 -0.762)
			(end -1.524 -0.762)
			(stroke
				(width 0.1524)
				(type default)
			)
			(layer "B.SilkS")
		)
		(fp_line
			(start -1.524 -0.762)
			(end -1.524 0.762)
			(stroke
				(width 0.1524)
				(type default)
			)
			(layer "B.SilkS")
		)
		(fp_line
			(start 1.524 0.762)
			(end 1.524 -0.762)
			(stroke
				(width 0.1524)
				(type default)
			)
			(layer "B.SilkS")
		)
		(fp_line
			(start -1.524 0.762)
			(end 1.524 0.762)
			(stroke
				(width 0.1524)
				(type default)
			)
			(layer "B.SilkS")
		)
		(fp_line
			(start 1.1049 -0.724916)
			(end 1.1049 0.724916)
			(stroke
				(width 0.1)
				(type default)
			)
			(layer "B.Fab")
		)
		(fp_line
			(start -1.1049 -0.724916)
			(end 1.1049 -0.724916)
			(stroke
				(width 0.1)
				(type default)
			)
			(layer "B.Fab")
		)
		(fp_line
			(start 1.1049 0.724916)
			(end -1.1049 0.724916)
			(stroke
				(width 0.1)
				(type default)
			)
			(layer "B.Fab")
		)
		(fp_line
			(start -1.1049 0.724916)
			(end -1.1049 -0.724916)
			(stroke
				(width 0.1)
				(type default)
			)
			(layer "B.Fab")
		)
		(pad "1" smd rect
			(at 0.889 0 90)
			(size 1.016 1.27)
			(layers "B.Cu" "B.Mask" "B.Paste")
			(net "PVCCIN_CPU0")
		)
		(pad "2" smd rect
			(at -0.889 0 90)
			(size 1.016 1.27)
			(layers "B.Cu" "B.Mask" "B.Paste")
			(net "GND")
		)
	)
	(footprint ""
		(layer "B.Cu")
		(at 420.682166 -137.178034)
		(property "Reference" "PR106"
			(at 0 0 0)
			(layer "B.SilkS")
			(hide yes)
			(effects
				(font
					(size 1.27 1.27)
				)
				(justify mirror)
			)
		)
		(property "Value" ""
			(at 0 0 0)
			(layer "B.Fab")
			(effects
				(font
					(size 1.27 1.27)
				)
				(justify mirror)
			)
		)
		(duplicate_pad_numbers_are_jumpers no)
		(fp_line
			(start -0.7874 -0.4064)
			(end -0.7874 0.4064)
			(stroke
				(width 0.1524)
				(type default)
			)
			(layer "B.SilkS")
		)
		(fp_line
			(start -0.7874 0.4064)
			(end 0.7874 0.4064)
			(stroke
				(width 0.1524)
				(type default)
			)
			(layer "B.SilkS")
		)
		(fp_line
			(start 0.7874 -0.4064)
			(end -0.7874 -0.4064)
			(stroke
				(width 0.1524)
				(type default)
			)
			(layer "B.SilkS")
		)
		(fp_line
			(start 0.7874 0.4064)
			(end 0.7874 -0.4064)
			(stroke
				(width 0.1524)
				(type default)
			)
			(layer "B.SilkS")
		)
		(fp_line
			(start -0.67945 -0.3048)
			(end -0.67945 0.3048)
			(stroke
				(width 0.1)
				(type default)
			)
			(layer "B.Fab")
		)
		(fp_line
			(start -0.67945 0.3048)
			(end -0.120396 0.3048)
			(stroke
				(width 0.1)
				(type default)
			)
			(layer "B.Fab")
		)
		(fp_line
			(start -0.12065 -0.3048)
			(end -0.67945 -0.3048)
			(stroke
				(width 0.1)
				(type default)
			)
			(layer "B.Fab")
		)
		(fp_line
			(start -0.12065 -0.2794)
			(end -0.12065 -0.3048)
			(stroke
				(width 0.1)
				(type default)
			)
			(layer "B.Fab")
		)
		(fp_line
			(start -0.120396 0.2794)
			(end 0.12065 0.2794)
			(stroke
				(width 0.1)
				(type default)
			)
			(layer "B.Fab")
		)
		(fp_line
			(start -0.120396 0.3048)
			(end -0.120396 0.2794)
			(stroke
				(width 0.1)
				(type default)
			)
			(layer "B.Fab")
		)
		(fp_line
			(start 0.12065 -0.305054)
			(end 0.12065 -0.2794)
			(stroke
				(width 0.1)
				(type default)
			)
			(layer "B.Fab")
		)
		(fp_line
			(start 0.12065 -0.2794)
			(end -0.12065 -0.2794)
			(stroke
				(width 0.1)
				(type default)
			)
			(layer "B.Fab")
		)
		(fp_line
			(start 0.12065 0.2794)
			(end 0.12065 0.3048)
			(stroke
				(width 0.1)
				(type default)
			)
			(layer "B.Fab")
		)
		(fp_line
			(start 0.12065 0.3048)
			(end 0.67945 0.3048)
			(stroke
				(width 0.1)
				(type default)
			)
			(layer "B.Fab")
		)
		(fp_line
			(start 0.67945 -0.305054)
			(end 0.12065 -0.305054)
			(stroke
				(width 0.1)
				(type default)
			)
			(layer "B.Fab")
		)
		(fp_line
			(start 0.67945 0.3048)
			(end 0.67945 -0.305054)
			(stroke
				(width 0.1)
				(type default)
			)
			(layer "B.Fab")
		)
		(pad "1" smd circle
			(at 0.40005 0 180)
			(size 0 0)
			(layers "B.Cu" "B.Mask" "B.Paste")
			(net "PVCCINFAON_CPU0_ADDR")
		)
		(pad "2" smd circle
			(at -0.40005 0 180)
			(size 0 0)
			(layers "B.Cu" "B.Mask" "B.Paste")
			(net "GND")
		)
	)
	(footprint ""
		(layer "B.Cu")
		(at 105.670604 -294.01008)
		(property "Reference" "C325"
			(at 0 0 0)
			(layer "B.SilkS")
			(hide yes)
			(effects
				(font
					(size 1.27 1.27)
				)
				(justify mirror)
			)
		)
		(property "Value" ""
			(at 0 0 0)
			(layer "B.Fab")
			(effects
				(font
					(size 1.27 1.27)
				)
				(justify mirror)
			)
		)
		(duplicate_pad_numbers_are_jumpers no)
		(fp_line
			(start -1.524 -0.762)
			(end -1.524 0.762)
			(stroke
				(width 0.1524)
				(type default)
			)
			(layer "B.SilkS")
		)
		(fp_line
			(start -1.524 0.762)
			(end 1.524 0.762)
			(stroke
				(width 0.1524)
				(type default)
			)
			(layer "B.SilkS")
		)
		(fp_line
			(start 1.524 -0.762)
			(end -1.524 -0.762)
			(stroke
				(width 0.1524)
				(type default)
			)
			(layer "B.SilkS")
		)
		(fp_line
			(start 1.524 0.762)
			(end 1.524 -0.762)
			(stroke
				(width 0.1524)
				(type default)
			)
			(layer "B.SilkS")
		)
		(fp_line
			(start -1.1049 -0.724916)
			(end 1.1049 -0.724916)
			(stroke
				(width 0.1)
				(type default)
			)
			(layer "B.Fab")
		)
		(fp_line
			(start -1.1049 0.724916)
			(end -1.1049 -0.724916)
			(stroke
				(width 0.1)
				(type default)
			)
			(layer "B.Fab")
		)
		(fp_line
			(start 1.1049 -0.724916)
			(end 1.1049 0.724916)
			(stroke
				(width 0.1)
				(type default)
			)
			(layer "B.Fab")
		)
		(fp_line
			(start 1.1049 0.724916)
			(end -1.1049 0.724916)
			(stroke
				(width 0.1)
				(type default)
			)
			(layer "B.Fab")
		)
		(pad "1" smd rect
			(at 0.889 0)
			(size 1.016 1.27)
			(layers "B.Cu" "B.Mask" "B.Paste")
			(net "PVCCIN_CPU1")
		)
		(pad "2" smd rect
			(at -0.889 0)
			(size 1.016 1.27)
			(layers "B.Cu" "B.Mask" "B.Paste")
			(net "GND")
		)
	)
	(footprint ""
		(layer "B.Cu")
		(at 452.028814 -321.549776 -90)
		(property "Reference" "C49"
			(at 0 0 90)
			(layer "B.SilkS")
			(hide yes)
			(effects
				(font
					(size 1.27 1.27)
				)
				(justify mirror)
			)
		)
		(property "Value" ""
			(at 0 0 90)
			(layer "B.Fab")
			(effects
				(font
					(size 1.27 1.27)
				)
				(justify mirror)
			)
		)
		(duplicate_pad_numbers_are_jumpers no)
		(fp_line
			(start -1.524 0.762)
			(end 1.524 0.762)
			(stroke
				(width 0.1524)
				(type default)
			)
			(layer "B.SilkS")
		)
		(fp_line
			(start 1.524 0.762)
			(end 1.524 -0.762)
			(stroke
				(width 0.1524)
				(type default)
			)
			(layer "B.SilkS")
		)
		(fp_line
			(start -1.524 -0.762)
			(end -1.524 0.762)
			(stroke
				(width 0.1524)
				(type default)
			)
			(layer "B.SilkS")
		)
		(fp_line
			(start 1.524 -0.762)
			(end -1.524 -0.762)
			(stroke
				(width 0.1524)
				(type default)
			)
			(layer "B.SilkS")
		)
		(fp_line
			(start -1.1049 0.724916)
			(end -1.1049 -0.724916)
			(stroke
				(width 0.1)
				(type default)
			)
			(layer "B.Fab")
		)
		(fp_line
			(start 1.1049 0.724916)
			(end -1.1049 0.724916)
			(stroke
				(width 0.1)
				(type default)
			)
			(layer "B.Fab")
		)
		(fp_line
			(start -1.1049 -0.724916)
			(end 1.1049 -0.724916)
			(stroke
				(width 0.1)
				(type default)
			)
			(layer "B.Fab")
		)
		(fp_line
			(start 1.1049 -0.724916)
			(end 1.1049 0.724916)
			(stroke
				(width 0.1)
				(type default)
			)
			(layer "B.Fab")
		)
		(pad "1" smd rect
			(at 0.889 0 270)
			(size 1.016 1.27)
			(layers "B.Cu" "B.Mask" "B.Paste")
			(net "P12V_S3_AUX_CPU0_NVDIMM")
		)
		(pad "2" smd rect
			(at -0.889 0 270)
			(size 1.016 1.27)
			(layers "B.Cu" "B.Mask" "B.Paste")
			(net "GND")
		)
	)
	(footprint ""
		(layer "B.Cu")
		(at 340.35746 -66.425064 90)
		(property "Reference" "C167"
			(at 0 0 90)
			(layer "B.SilkS")
			(hide yes)
			(effects
				(font
					(size 1.27 1.27)
				)
				(justify mirror)
			)
		)
		(property "Value" ""
			(at 0 0 90)
			(layer "B.Fab")
			(effects
				(font
					(size 1.27 1.27)
				)
				(justify mirror)
			)
		)
		(duplicate_pad_numbers_are_jumpers no)
		(fp_line
			(start 0.299974 -0.150114)
			(end -0.299974 -0.150114)
			(stroke
				(width 0.1)
				(type default)
			)
			(layer "B.Fab")
		)
		(fp_line
			(start -0.299974 -0.150114)
			(end -0.299974 0.150114)
			(stroke
				(width 0.1)
				(type default)
			)
			(layer "B.Fab")
		)
		(fp_line
			(start 0.299974 0.150114)
			(end 0.299974 -0.150114)
			(stroke
				(width 0.1)
				(type default)
			)
			(layer "B.Fab")
		)
		(fp_line
			(start -0.299974 0.150114)
			(end 0.299974 0.150114)
			(stroke
				(width 0.1)
				(type default)
			)
			(layer "B.Fab")
		)
		(pad "1" smd rect
			(at 0.2667 0 270)
			(size 0.3048 0.381)
			(layers "B.Cu" "B.Mask" "B.Paste")
			(net "DMI_CPU0_PCH_RX_C_DN<1>")
		)
		(pad "2" smd rect
			(at -0.2667 0 270)
			(size 0.3048 0.381)
			(layers "B.Cu" "B.Mask" "B.Paste")
			(net "DMI_CPU0_PCH_RX_DN<1>")
		)
	)
	(footprint ""
		(layer "B.Cu")
		(at 171.985178 -346.586302 -90)
		(property "Reference" "PC418"
			(at 0 0 90)
			(layer "B.SilkS")
			(hide yes)
			(effects
				(font
					(size 1.27 1.27)
				)
				(justify mirror)
			)
		)
		(property "Value" ""
			(at 0 0 90)
			(layer "B.Fab")
			(effects
				(font
					(size 1.27 1.27)
				)
				(justify mirror)
			)
		)
		(duplicate_pad_numbers_are_jumpers no)
		(fp_line
			(start -4.533392 2.249932)
			(end 4.533392 2.249932)
			(stroke
				(width 0.1524)
				(type default)
			)
			(layer "B.SilkS")
		)
		(fp_line
			(start 4.533392 2.249932)
			(end 4.533392 -2.249932)
			(stroke
				(width 0.1524)
				(type default)
			)
			(layer "B.SilkS")
		)
		(fp_line
			(start -4.533392 -2.249932)
			(end -4.533392 2.249932)
			(stroke
				(width 0.1524)
				(type default)
			)
			(layer "B.SilkS")
		)
		(fp_line
			(start 4.533392 -2.249932)
			(end -4.533392 -2.249932)
			(stroke
				(width 0.1524)
				(type default)
			)
			(layer "B.SilkS")
		)
		(fp_poly
			(pts
				(xy 4.533392 -2.326132) (xy 5.39242 -2.326132) (xy 5.39242 2.326132) (xy 4.533392 2.326132)
			)
			(stroke
				(width 0)
				(type default)
			)
			(fill yes)
			(layer "B.SilkS")
		)
		(fp_line
			(start -3.750056 2.249932)
			(end 3.750056 2.249932)
			(stroke
				(width 0.1)
				(type default)
			)
			(layer "B.Fab")
		)
		(fp_line
			(start 3.750056 2.249932)
			(end 3.750056 -2.249932)
			(stroke
				(width 0.1)
				(type default)
			)
			(layer "B.Fab")
		)
		(fp_line
			(start -3.750056 -2.249932)
			(end -3.750056 2.249932)
			(stroke
				(width 0.1)
				(type default)
			)
			(layer "B.Fab")
		)
		(fp_line
			(start 3.750056 -2.249932)
			(end -3.750056 -2.249932)
			(stroke
				(width 0.1)
				(type default)
			)
			(layer "B.Fab")
		)
		(fp_text user "+"
			(at 6.322314 0.786384 180)
			(unlocked yes)
			(layer "B.SilkS")
			(effects
				(font
					(size 1.905 1.4224)
					(thickness 0.1524)
				)
				(justify left mirror)
			)
		)
		(fp_text user "-"
			(at -4.8514 -0.14605 270)
			(unlocked yes)
			(layer "B.SilkS")
			(effects
				(font
					(size 1.905 1.4224)
					(thickness 0.1524)
				)
				(justify left mirror)
			)
		)
		(fp_text user "+"
			(at 6.322314 0.786384 180)
			(unlocked yes)
			(layer "B.Fab")
			(effects
				(font
					(size 1.905 1.4224)
					(thickness 0.1524)
				)
				(justify left mirror)
			)
		)
		(fp_text user "-"
			(at -4.8514 -0.14605 270)
			(unlocked yes)
			(layer "B.Fab")
			(effects
				(font
					(size 1.905 1.4224)
					(thickness 0.1524)
				)
				(justify left mirror)
			)
		)
		(pad "1" smd rect
			(at 3.199892 0 90)
			(size 2.413 2.8194)
			(layers "B.Cu" "B.Mask" "B.Paste")
			(net "PVCCFA_EHV_FIVRA_CPU1")
		)
		(pad "2" smd rect
			(at -3.199892 0 90)
			(size 2.413 2.8194)
			(layers "B.Cu" "B.Mask" "B.Paste")
			(net "GND")
		)
	)
	(footprint ""
		(layer "B.Cu")
		(at 353.619308 -248.498106 -90)
		(property "Reference" "C357"
			(at 0 0 90)
			(layer "B.SilkS")
			(hide yes)
			(effects
				(font
					(size 1.27 1.27)
				)
				(justify mirror)
			)
		)
		(property "Value" ""
			(at 0 0 90)
			(layer "B.Fab")
			(effects
				(font
					(size 1.27 1.27)
				)
				(justify mirror)
			)
		)
		(duplicate_pad_numbers_are_jumpers no)
		(fp_line
			(start -1.524 0.762)
			(end 1.524 0.762)
			(stroke
				(width 0.1524)
				(type default)
			)
			(layer "B.SilkS")
		)
		(fp_line
			(start 1.524 0.762)
			(end 1.524 -0.762)
			(stroke
				(width 0.1524)
				(type default)
			)
			(layer "B.SilkS")
		)
		(fp_line
			(start -1.524 -0.762)
			(end -1.524 0.762)
			(stroke
				(width 0.1524)
				(type default)
			)
			(layer "B.SilkS")
		)
		(fp_line
			(start 1.524 -0.762)
			(end -1.524 -0.762)
			(stroke
				(width 0.1524)
				(type default)
			)
			(layer "B.SilkS")
		)
		(fp_line
			(start -1.1049 0.724916)
			(end -1.1049 -0.724916)
			(stroke
				(width 0.1)
				(type default)
			)
			(layer "B.Fab")
		)
		(fp_line
			(start 1.1049 0.724916)
			(end -1.1049 0.724916)
			(stroke
				(width 0.1)
				(type default)
			)
			(layer "B.Fab")
		)
		(fp_line
			(start -1.1049 -0.724916)
			(end 1.1049 -0.724916)
			(stroke
				(width 0.1)
				(type default)
			)
			(layer "B.Fab")
		)
		(fp_line
			(start 1.1049 -0.724916)
			(end 1.1049 0.724916)
			(stroke
				(width 0.1)
				(type default)
			)
			(layer "B.Fab")
		)
		(pad "1" smd rect
			(at 0.889 0 270)
			(size 1.016 1.27)
			(layers "B.Cu" "B.Mask" "B.Paste")
			(net "PVCCIN_CPU0")
		)
		(pad "2" smd rect
			(at -0.889 0 270)
			(size 1.016 1.27)
			(layers "B.Cu" "B.Mask" "B.Paste")
			(net "GND")
		)
	)
	(footprint ""
		(layer "B.Cu")
		(at 34.846514 -166.733474)
		(property "Reference" "PR1410"
			(at 0 0 0)
			(layer "B.SilkS")
			(hide yes)
			(effects
				(font
					(size 1.27 1.27)
				)
				(justify mirror)
			)
		)
		(property "Value" ""
			(at 0 0 0)
			(layer "B.Fab")
			(effects
				(font
					(size 1.27 1.27)
				)
				(justify mirror)
			)
		)
		(duplicate_pad_numbers_are_jumpers no)
		(fp_line
			(start -0.7874 -0.4064)
			(end -0.7874 0.4064)
			(stroke
				(width 0.1524)
				(type default)
			)
			(layer "B.SilkS")
		)
		(fp_line
			(start -0.7874 0.4064)
			(end 0.7874 0.4064)
			(stroke
				(width 0.1524)
				(type default)
			)
			(layer "B.SilkS")
		)
		(fp_line
			(start 0.7874 -0.4064)
			(end -0.7874 -0.4064)
			(stroke
				(width 0.1524)
				(type default)
			)
			(layer "B.SilkS")
		)
		(fp_line
			(start 0.7874 0.4064)
			(end 0.7874 -0.4064)
			(stroke
				(width 0.1524)
				(type default)
			)
			(layer "B.SilkS")
		)
		(fp_line
			(start -0.67945 -0.3048)
			(end -0.67945 0.3048)
			(stroke
				(width 0.1)
				(type default)
			)
			(layer "B.Fab")
		)
		(fp_line
			(start -0.67945 0.3048)
			(end -0.120396 0.3048)
			(stroke
				(width 0.1)
				(type default)
			)
			(layer "B.Fab")
		)
		(fp_line
			(start -0.12065 -0.3048)
			(end -0.67945 -0.3048)
			(stroke
				(width 0.1)
				(type default)
			)
			(layer "B.Fab")
		)
		(fp_line
			(start -0.12065 -0.2794)
			(end -0.12065 -0.3048)
			(stroke
				(width 0.1)
				(type default)
			)
			(layer "B.Fab")
		)
		(fp_line
			(start -0.120396 0.2794)
			(end 0.12065 0.2794)
			(stroke
				(width 0.1)
				(type default)
			)
			(layer "B.Fab")
		)
		(fp_line
			(start -0.120396 0.3048)
			(end -0.120396 0.2794)
			(stroke
				(width 0.1)
				(type default)
			)
			(layer "B.Fab")
		)
		(fp_line
			(start 0.12065 -0.305054)
			(end 0.12065 -0.2794)
			(stroke
				(width 0.1)
				(type default)
			)
			(layer "B.Fab")
		)
		(fp_line
			(start 0.12065 -0.2794)
			(end -0.12065 -0.2794)
			(stroke
				(width 0.1)
				(type default)
			)
			(layer "B.Fab")
		)
		(fp_line
			(start 0.12065 0.2794)
			(end 0.12065 0.3048)
			(stroke
				(width 0.1)
				(type default)
			)
			(layer "B.Fab")
		)
		(fp_line
			(start 0.12065 0.3048)
			(end 0.67945 0.3048)
			(stroke
				(width 0.1)
				(type default)
			)
			(layer "B.Fab")
		)
		(fp_line
			(start 0.67945 -0.305054)
			(end 0.12065 -0.305054)
			(stroke
				(width 0.1)
				(type default)
			)
			(layer "B.Fab")
		)
		(fp_line
			(start 0.67945 0.3048)
			(end 0.67945 -0.305054)
			(stroke
				(width 0.1)
				(type default)
			)
			(layer "B.Fab")
		)
		(pad "1" smd circle
			(at 0.40005 0 180)
			(size 0 0)
			(layers "B.Cu" "B.Mask" "B.Paste")
			(net "P12V_AUX_CPU1_DIMM_ISEN_N")
		)
		(pad "2" smd circle
			(at -0.40005 0 180)
			(size 0 0)
			(layers "B.Cu" "B.Mask" "B.Paste")
			(net "PVCCD_HV_CPU1_ISENSE_N")
		)
	)
	(footprint ""
		(layer "B.Cu")
		(at 436.971694 -119.952008)
		(property "Reference" "R361"
			(at 0 0 0)
			(layer "B.SilkS")
			(hide yes)
			(effects
				(font
					(size 1.27 1.27)
				)
				(justify mirror)
			)
		)
		(property "Value" ""
			(at 0 0 0)
			(layer "B.Fab")
			(effects
				(font
					(size 1.27 1.27)
				)
				(justify mirror)
			)
		)
		(duplicate_pad_numbers_are_jumpers no)
		(fp_line
			(start -0.7874 -0.4064)
			(end -0.7874 0.4064)
			(stroke
				(width 0.1524)
				(type default)
			)
			(layer "B.SilkS")
		)
		(fp_line
			(start -0.7874 0.4064)
			(end 0.7874 0.4064)
			(stroke
				(width 0.1524)
				(type default)
			)
			(layer "B.SilkS")
		)
		(fp_line
			(start 0.7874 -0.4064)
			(end -0.7874 -0.4064)
			(stroke
				(width 0.1524)
				(type default)
			)
			(layer "B.SilkS")
		)
		(fp_line
			(start 0.7874 0.4064)
			(end 0.7874 -0.4064)
			(stroke
				(width 0.1524)
				(type default)
			)
			(layer "B.SilkS")
		)
		(fp_line
			(start -0.67945 -0.3048)
			(end -0.67945 0.3048)
			(stroke
				(width 0.1)
				(type default)
			)
			(layer "B.Fab")
		)
		(fp_line
			(start -0.67945 0.3048)
			(end -0.120396 0.3048)
			(stroke
				(width 0.1)
				(type default)
			)
			(layer "B.Fab")
		)
		(fp_line
			(start -0.12065 -0.3048)
			(end -0.67945 -0.3048)
			(stroke
				(width 0.1)
				(type default)
			)
			(layer "B.Fab")
		)
		(fp_line
			(start -0.12065 -0.2794)
			(end -0.12065 -0.3048)
			(stroke
				(width 0.1)
				(type default)
			)
			(layer "B.Fab")
		)
		(fp_line
			(start -0.120396 0.2794)
			(end 0.12065 0.2794)
			(stroke
				(width 0.1)
				(type default)
			)
			(layer "B.Fab")
		)
		(fp_line
			(start -0.120396 0.3048)
			(end -0.120396 0.2794)
			(stroke
				(width 0.1)
				(type default)
			)
			(layer "B.Fab")
		)
		(fp_line
			(start 0.12065 -0.305054)
			(end 0.12065 -0.2794)
			(stroke
				(width 0.1)
				(type default)
			)
			(layer "B.Fab")
		)
		(fp_line
			(start 0.12065 -0.2794)
			(end -0.12065 -0.2794)
			(stroke
				(width 0.1)
				(type default)
			)
			(layer "B.Fab")
		)
		(fp_line
			(start 0.12065 0.2794)
			(end 0.12065 0.3048)
			(stroke
				(width 0.1)
				(type default)
			)
			(layer "B.Fab")
		)
		(fp_line
			(start 0.12065 0.3048)
			(end 0.67945 0.3048)
			(stroke
				(width 0.1)
				(type default)
			)
			(layer "B.Fab")
		)
		(fp_line
			(start 0.67945 -0.305054)
			(end 0.12065 -0.305054)
			(stroke
				(width 0.1)
				(type default)
			)
			(layer "B.Fab")
		)
		(fp_line
			(start 0.67945 0.3048)
			(end 0.67945 -0.305054)
			(stroke
				(width 0.1)
				(type default)
			)
			(layer "B.Fab")
		)
		(pad "1" smd circle
			(at 0.40005 0 180)
			(size 0 0)
			(layers "B.Cu" "B.Mask" "B.Paste")
			(net "P3V3_AUX")
		)
		(pad "2" smd circle
			(at -0.40005 0 180)
			(size 0 0)
			(layers "B.Cu" "B.Mask" "B.Paste")
			(net "PWRGD_PVCCD_HV_CPU0_R")
		)
	)
	(footprint ""
		(layer "B.Cu")
		(at 65.55994 -379.0696)
		(property "Reference" "ME9"
			(at 9.652 -9.540748 0)
			(unlocked yes)
			(layer "B.SilkS")
			(effects
				(font
					(size 0.7874 0.5842)
					(thickness 0.1524)
				)
				(justify left mirror)
			)
		)
		(property "Value" ""
			(at 0 0 0)
			(layer "B.Fab")
			(effects
				(font
					(size 1.27 1.27)
				)
				(justify mirror)
			)
		)
		(duplicate_pad_numbers_are_jumpers no)
		(zone
			(layer "B.Cu")
			(hatch none 0.5)
			(connect_pads
				(clearance 0)
			)
			(min_thickness 0.25)
			(keepout
				(tracks allowed)
				(vias allowed)
				(pads allowed)
				(copperpour allowed)
				(footprints not_allowed)
			)
			(placement
				(enabled no)
				(sheetname "")
			)
			(fill
				(thermal_gap 0.5)
				(thermal_bridge_width 0.5)
				(island_removal_mode 0)
			)
			(polygon
				(pts
					(arc
						(start 75.55992 -379.0696)
						(mid 55.55996 -379.0696)
						(end 75.55992 -379.0696)
					)
				)
			)
		)
	)
	(footprint ""
		(layer "B.Cu")
		(at 157.0355 -8.801608 180)
		(property "Reference" "R2204"
			(at 0 0 0)
			(layer "B.SilkS")
			(hide yes)
			(effects
				(font
					(size 1.27 1.27)
				)
				(justify mirror)
			)
		)
		(property "Value" ""
			(at 0 0 0)
			(layer "B.Fab")
			(effects
				(font
					(size 1.27 1.27)
				)
				(justify mirror)
			)
		)
		(duplicate_pad_numbers_are_jumpers no)
		(fp_line
			(start 0.7874 0.4064)
			(end 0.7874 -0.4064)
			(stroke
				(width 0.1524)
				(type default)
			)
			(layer "B.SilkS")
		)
		(fp_line
			(start 0.7874 -0.4064)
			(end -0.7874 -0.4064)
			(stroke
				(width 0.1524)
				(type default)
			)
			(layer "B.SilkS")
		)
		(fp_line
			(start -0.7874 0.4064)
			(end 0.7874 0.4064)
			(stroke
				(width 0.1524)
				(type default)
			)
			(layer "B.SilkS")
		)
		(fp_line
			(start -0.7874 -0.4064)
			(end -0.7874 0.4064)
			(stroke
				(width 0.1524)
				(type default)
			)
			(layer "B.SilkS")
		)
		(fp_line
			(start 0.67945 0.3048)
			(end 0.67945 -0.305054)
			(stroke
				(width 0.1)
				(type default)
			)
			(layer "B.Fab")
		)
		(fp_line
			(start 0.67945 -0.305054)
			(end 0.12065 -0.305054)
			(stroke
				(width 0.1)
				(type default)
			)
			(layer "B.Fab")
		)
		(fp_line
			(start 0.12065 0.3048)
			(end 0.67945 0.3048)
			(stroke
				(width 0.1)
				(type default)
			)
			(layer "B.Fab")
		)
		(fp_line
			(start 0.12065 0.2794)
			(end 0.12065 0.3048)
			(stroke
				(width 0.1)
				(type default)
			)
			(layer "B.Fab")
		)
		(fp_line
			(start 0.12065 -0.2794)
			(end -0.12065 -0.2794)
			(stroke
				(width 0.1)
				(type default)
			)
			(layer "B.Fab")
		)
		(fp_line
			(start 0.12065 -0.305054)
			(end 0.12065 -0.2794)
			(stroke
				(width 0.1)
				(type default)
			)
			(layer "B.Fab")
		)
		(fp_line
			(start -0.120396 0.3048)
			(end -0.120396 0.2794)
			(stroke
				(width 0.1)
				(type default)
			)
			(layer "B.Fab")
		)
		(fp_line
			(start -0.120396 0.2794)
			(end 0.12065 0.2794)
			(stroke
				(width 0.1)
				(type default)
			)
			(layer "B.Fab")
		)
		(fp_line
			(start -0.12065 -0.2794)
			(end -0.12065 -0.3048)
			(stroke
				(width 0.1)
				(type default)
			)
			(layer "B.Fab")
		)
		(fp_line
			(start -0.12065 -0.3048)
			(end -0.67945 -0.3048)
			(stroke
				(width 0.1)
				(type default)
			)
			(layer "B.Fab")
		)
		(fp_line
			(start -0.67945 0.3048)
			(end -0.120396 0.3048)
			(stroke
				(width 0.1)
				(type default)
			)
			(layer "B.Fab")
		)
		(fp_line
			(start -0.67945 -0.3048)
			(end -0.67945 0.3048)
			(stroke
				(width 0.1)
				(type default)
			)
			(layer "B.Fab")
		)
		(pad "1" smd circle
			(at 0.40005 0)
			(size 0 0)
			(layers "B.Cu" "B.Mask" "B.Paste")
			(net "P3V3_AUX")
		)
		(pad "2" smd circle
			(at -0.40005 0)
			(size 0 0)
			(layers "B.Cu" "B.Mask" "B.Paste")
			(net "SMB_PCIE0_3V3AUX_SCL")
		)
	)
	(footprint ""
		(layer "B.Cu")
		(at 333.569056 -58.473086 -90)
		(property "Reference" "C1186"
			(at 0 0 90)
			(layer "B.SilkS")
			(hide yes)
			(effects
				(font
					(size 1.27 1.27)
				)
				(justify mirror)
			)
		)
		(property "Value" ""
			(at 0 0 90)
			(layer "B.Fab")
			(effects
				(font
					(size 1.27 1.27)
				)
				(justify mirror)
			)
		)
		(duplicate_pad_numbers_are_jumpers no)
		(fp_line
			(start -1.2954 0.5842)
			(end 1.2954 0.5842)
			(stroke
				(width 0.1524)
				(type default)
			)
			(layer "B.SilkS")
		)
		(fp_line
			(start 1.2954 0.5842)
			(end 1.2954 -0.5842)
			(stroke
				(width 0.1524)
				(type default)
			)
			(layer "B.SilkS")
		)
		(fp_line
			(start -1.2954 -0.5842)
			(end -1.2954 0.5842)
			(stroke
				(width 0.1524)
				(type default)
			)
			(layer "B.SilkS")
		)
		(fp_line
			(start 0 -0.5842)
			(end 0 0.5842)
			(stroke
				(width 0.1524)
				(type default)
			)
			(layer "B.SilkS")
		)
		(fp_line
			(start 1.2954 -0.5842)
			(end -1.2954 -0.5842)
			(stroke
				(width 0.1524)
				(type default)
			)
			(layer "B.SilkS")
		)
		(fp_line
			(start -0.8636 0.4572)
			(end 0.8636 0.4572)
			(stroke
				(width 0.1)
				(type default)
			)
			(layer "B.Fab")
		)
		(fp_line
			(start 0.8636 0.4572)
			(end 0.8636 0.4064)
			(stroke
				(width 0.1)
				(type default)
			)
			(layer "B.Fab")
		)
		(fp_line
			(start -1.1938 0.4064)
			(end -0.8636 0.4064)
			(stroke
				(width 0.1)
				(type default)
			)
			(layer "B.Fab")
		)
		(fp_line
			(start -0.8636 0.4064)
			(end -0.8636 0.4572)
			(stroke
				(width 0.1)
				(type default)
			)
			(layer "B.Fab")
		)
		(fp_line
			(start 0.8636 0.4064)
			(end 1.1938 0.4064)
			(stroke
				(width 0.1)
				(type default)
			)
			(layer "B.Fab")
		)
		(fp_line
			(start 1.1938 0.4064)
			(end 1.1938 -0.4064)
			(stroke
				(width 0.1)
				(type default)
			)
			(layer "B.Fab")
		)
		(fp_line
			(start -1.1938 -0.4064)
			(end -1.1938 0.4064)
			(stroke
				(width 0.1)
				(type default)
			)
			(layer "B.Fab")
		)
		(fp_line
			(start -0.8636 -0.4064)
			(end -1.1938 -0.4064)
			(stroke
				(width 0.1)
				(type default)
			)
			(layer "B.Fab")
		)
		(fp_line
			(start 0.8636 -0.4064)
			(end 0.8636 -0.4572)
			(stroke
				(width 0.1)
				(type default)
			)
			(layer "B.Fab")
		)
		(fp_line
			(start 1.1938 -0.4064)
			(end 0.8636 -0.4064)
			(stroke
				(width 0.1)
				(type default)
			)
			(layer "B.Fab")
		)
		(fp_line
			(start -0.8636 -0.4572)
			(end -0.8636 -0.4064)
			(stroke
				(width 0.1)
				(type default)
			)
			(layer "B.Fab")
		)
		(fp_line
			(start 0.8636 -0.4572)
			(end -0.8636 -0.4572)
			(stroke
				(width 0.1)
				(type default)
			)
			(layer "B.Fab")
		)
		(pad "1" smd rect
			(at 0.7366 0 180)
			(size 0.7112 0.8128)
			(layers "B.Cu" "B.Mask" "B.Paste")
			(net "P1V8_PCH_AUX")
		)
		(pad "2" smd rect
			(at -0.7366 0 180)
			(size 0.7112 0.8128)
			(layers "B.Cu" "B.Mask" "B.Paste")
			(net "GND")
		)
	)
	(footprint ""
		(layer "B.Cu")
		(at 65.364868 -195.632578 -90)
		(property "Reference" "R4300"
			(at 0 0 90)
			(layer "B.SilkS")
			(hide yes)
			(effects
				(font
					(size 1.27 1.27)
				)
				(justify mirror)
			)
		)
		(property "Value" ""
			(at 0 0 90)
			(layer "B.Fab")
			(effects
				(font
					(size 1.27 1.27)
				)
				(justify mirror)
			)
		)
		(duplicate_pad_numbers_are_jumpers no)
		(fp_line
			(start -0.7874 0.4064)
			(end 0.7874 0.4064)
			(stroke
				(width 0.1524)
				(type default)
			)
			(layer "B.SilkS")
		)
		(fp_line
			(start 0.7874 0.4064)
			(end 0.7874 -0.4064)
			(stroke
				(width 0.1524)
				(type default)
			)
			(layer "B.SilkS")
		)
		(fp_line
			(start -0.7874 -0.4064)
			(end -0.7874 0.4064)
			(stroke
				(width 0.1524)
				(type default)
			)
			(layer "B.SilkS")
		)
		(fp_line
			(start 0.7874 -0.4064)
			(end -0.7874 -0.4064)
			(stroke
				(width 0.1524)
				(type default)
			)
			(layer "B.SilkS")
		)
		(fp_line
			(start -0.67945 0.3048)
			(end -0.120396 0.3048)
			(stroke
				(width 0.1)
				(type default)
			)
			(layer "B.Fab")
		)
		(fp_line
			(start -0.120396 0.3048)
			(end -0.120396 0.2794)
			(stroke
				(width 0.1)
				(type default)
			)
			(layer "B.Fab")
		)
		(fp_line
			(start 0.12065 0.3048)
			(end 0.67945 0.3048)
			(stroke
				(width 0.1)
				(type default)
			)
			(layer "B.Fab")
		)
		(fp_line
			(start 0.67945 0.3048)
			(end 0.67945 -0.305054)
			(stroke
				(width 0.1)
				(type default)
			)
			(layer "B.Fab")
		)
		(fp_line
			(start -0.120396 0.2794)
			(end 0.12065 0.2794)
			(stroke
				(width 0.1)
				(type default)
			)
			(layer "B.Fab")
		)
		(fp_line
			(start 0.12065 0.2794)
			(end 0.12065 0.3048)
			(stroke
				(width 0.1)
				(type default)
			)
			(layer "B.Fab")
		)
		(fp_line
			(start -0.12065 -0.2794)
			(end -0.12065 -0.3048)
			(stroke
				(width 0.1)
				(type default)
			)
			(layer "B.Fab")
		)
		(fp_line
			(start 0.12065 -0.2794)
			(end -0.12065 -0.2794)
			(stroke
				(width 0.1)
				(type default)
			)
			(layer "B.Fab")
		)
		(fp_line
			(start -0.67945 -0.3048)
			(end -0.67945 0.3048)
			(stroke
				(width 0.1)
				(type default)
			)
			(layer "B.Fab")
		)
		(fp_line
			(start -0.12065 -0.3048)
			(end -0.67945 -0.3048)
			(stroke
				(width 0.1)
				(type default)
			)
			(layer "B.Fab")
		)
		(fp_line
			(start 0.12065 -0.305054)
			(end 0.12065 -0.2794)
			(stroke
				(width 0.1)
				(type default)
			)
			(layer "B.Fab")
		)
		(fp_line
			(start 0.67945 -0.305054)
			(end 0.12065 -0.305054)
			(stroke
				(width 0.1)
				(type default)
			)
			(layer "B.Fab")
		)
		(pad "1" smd circle
			(at 0.40005 0 90)
			(size 0 0)
			(layers "B.Cu" "B.Mask" "B.Paste")
			(net "PWRGD_DRAMPWRGD_CPU1_CD_LVC1_R2")
		)
		(pad "2" smd circle
			(at -0.40005 0 90)
			(size 0 0)
			(layers "B.Cu" "B.Mask" "B.Paste")
			(net "PWRGD_DRAMPWRGD_CPU1_CD_LVC1_R")
		)
	)
	(footprint ""
		(layer "B.Cu")
		(at 383.429256 -343.927938 -90)
		(property "Reference" "PR134"
			(at 0 0 90)
			(layer "B.SilkS")
			(hide yes)
			(effects
				(font
					(size 1.27 1.27)
				)
				(justify mirror)
			)
		)
		(property "Value" ""
			(at 0 0 90)
			(layer "B.Fab")
			(effects
				(font
					(size 1.27 1.27)
				)
				(justify mirror)
			)
		)
		(duplicate_pad_numbers_are_jumpers no)
		(fp_line
			(start -0.7874 0.4064)
			(end 0.7874 0.4064)
			(stroke
				(width 0.1524)
				(type default)
			)
			(layer "B.SilkS")
		)
		(fp_line
			(start 0.7874 0.4064)
			(end 0.7874 -0.4064)
			(stroke
				(width 0.1524)
				(type default)
			)
			(layer "B.SilkS")
		)
		(fp_line
			(start -0.7874 -0.4064)
			(end -0.7874 0.4064)
			(stroke
				(width 0.1524)
				(type default)
			)
			(layer "B.SilkS")
		)
		(fp_line
			(start 0.7874 -0.4064)
			(end -0.7874 -0.4064)
			(stroke
				(width 0.1524)
				(type default)
			)
			(layer "B.SilkS")
		)
		(fp_line
			(start -0.67945 0.3048)
			(end -0.120396 0.3048)
			(stroke
				(width 0.1)
				(type default)
			)
			(layer "B.Fab")
		)
		(fp_line
			(start -0.120396 0.3048)
			(end -0.120396 0.2794)
			(stroke
				(width 0.1)
				(type default)
			)
			(layer "B.Fab")
		)
		(fp_line
			(start 0.12065 0.3048)
			(end 0.67945 0.3048)
			(stroke
				(width 0.1)
				(type default)
			)
			(layer "B.Fab")
		)
		(fp_line
			(start 0.67945 0.3048)
			(end 0.67945 -0.305054)
			(stroke
				(width 0.1)
				(type default)
			)
			(layer "B.Fab")
		)
		(fp_line
			(start -0.120396 0.2794)
			(end 0.12065 0.2794)
			(stroke
				(width 0.1)
				(type default)
			)
			(layer "B.Fab")
		)
		(fp_line
			(start 0.12065 0.2794)
			(end 0.12065 0.3048)
			(stroke
				(width 0.1)
				(type default)
			)
			(layer "B.Fab")
		)
		(fp_line
			(start -0.12065 -0.2794)
			(end -0.12065 -0.3048)
			(stroke
				(width 0.1)
				(type default)
			)
			(layer "B.Fab")
		)
		(fp_line
			(start 0.12065 -0.2794)
			(end -0.12065 -0.2794)
			(stroke
				(width 0.1)
				(type default)
			)
			(layer "B.Fab")
		)
		(fp_line
			(start -0.67945 -0.3048)
			(end -0.67945 0.3048)
			(stroke
				(width 0.1)
				(type default)
			)
			(layer "B.Fab")
		)
		(fp_line
			(start -0.12065 -0.3048)
			(end -0.67945 -0.3048)
			(stroke
				(width 0.1)
				(type default)
			)
			(layer "B.Fab")
		)
		(fp_line
			(start 0.12065 -0.305054)
			(end 0.12065 -0.2794)
			(stroke
				(width 0.1)
				(type default)
			)
			(layer "B.Fab")
		)
		(fp_line
			(start 0.67945 -0.305054)
			(end 0.12065 -0.305054)
			(stroke
				(width 0.1)
				(type default)
			)
			(layer "B.Fab")
		)
		(pad "1" smd circle
			(at 0.40005 0 90)
			(size 0 0)
			(layers "B.Cu" "B.Mask" "B.Paste")
			(net "PVCCIN_CPU0_PVCC")
		)
		(pad "2" smd circle
			(at -0.40005 0 90)
			(size 0 0)
			(layers "B.Cu" "B.Mask" "B.Paste")
			(net "PVCCIN_CPU0_VDD8")
		)
	)
	(footprint ""
		(layer "B.Cu")
		(at 322.682616 -66.937128 -90)
		(property "Reference" "C1245"
			(at 0 0 90)
			(layer "B.SilkS")
			(hide yes)
			(effects
				(font
					(size 1.27 1.27)
				)
				(justify mirror)
			)
		)
		(property "Value" ""
			(at 0 0 90)
			(layer "B.Fab")
			(effects
				(font
					(size 1.27 1.27)
				)
				(justify mirror)
			)
		)
		(duplicate_pad_numbers_are_jumpers no)
		(fp_line
			(start -1.524 0.762)
			(end 1.524 0.762)
			(stroke
				(width 0.1524)
				(type default)
			)
			(layer "B.SilkS")
		)
		(fp_line
			(start 1.524 0.762)
			(end 1.524 -0.762)
			(stroke
				(width 0.1524)
				(type default)
			)
			(layer "B.SilkS")
		)
		(fp_line
			(start -1.524 -0.762)
			(end -1.524 0.762)
			(stroke
				(width 0.1524)
				(type default)
			)
			(layer "B.SilkS")
		)
		(fp_line
			(start 1.524 -0.762)
			(end -1.524 -0.762)
			(stroke
				(width 0.1524)
				(type default)
			)
			(layer "B.SilkS")
		)
		(fp_line
			(start -1.1049 0.724916)
			(end -1.1049 -0.724916)
			(stroke
				(width 0.1)
				(type default)
			)
			(layer "B.Fab")
		)
		(fp_line
			(start 1.1049 0.724916)
			(end -1.1049 0.724916)
			(stroke
				(width 0.1)
				(type default)
			)
			(layer "B.Fab")
		)
		(fp_line
			(start -1.1049 -0.724916)
			(end 1.1049 -0.724916)
			(stroke
				(width 0.1)
				(type default)
			)
			(layer "B.Fab")
		)
		(fp_line
			(start 1.1049 -0.724916)
			(end 1.1049 0.724916)
			(stroke
				(width 0.1)
				(type default)
			)
			(layer "B.Fab")
		)
		(pad "1" smd rect
			(at 0.889 0 270)
			(size 1.016 1.27)
			(layers "B.Cu" "B.Mask" "B.Paste")
			(net "P3V3_AUX")
		)
		(pad "2" smd rect
			(at -0.889 0 270)
			(size 1.016 1.27)
			(layers "B.Cu" "B.Mask" "B.Paste")
			(net "GND")
		)
	)
	(footprint ""
		(layer "B.Cu")
		(at 201.962258 -192.64757)
		(property "Reference" "R738"
			(at 0 0 0)
			(layer "B.SilkS")
			(hide yes)
			(effects
				(font
					(size 1.27 1.27)
				)
				(justify mirror)
			)
		)
		(property "Value" ""
			(at 0 0 0)
			(layer "B.Fab")
			(effects
				(font
					(size 1.27 1.27)
				)
				(justify mirror)
			)
		)
		(duplicate_pad_numbers_are_jumpers no)
		(fp_line
			(start -0.7874 -0.4064)
			(end -0.7874 0.4064)
			(stroke
				(width 0.1524)
				(type default)
			)
			(layer "B.SilkS")
		)
		(fp_line
			(start -0.7874 0.4064)
			(end 0.7874 0.4064)
			(stroke
				(width 0.1524)
				(type default)
			)
			(layer "B.SilkS")
		)
		(fp_line
			(start 0.7874 -0.4064)
			(end -0.7874 -0.4064)
			(stroke
				(width 0.1524)
				(type default)
			)
			(layer "B.SilkS")
		)
		(fp_line
			(start 0.7874 0.4064)
			(end 0.7874 -0.4064)
			(stroke
				(width 0.1524)
				(type default)
			)
			(layer "B.SilkS")
		)
		(fp_line
			(start -0.67945 -0.3048)
			(end -0.67945 0.3048)
			(stroke
				(width 0.1)
				(type default)
			)
			(layer "B.Fab")
		)
		(fp_line
			(start -0.67945 0.3048)
			(end -0.120396 0.3048)
			(stroke
				(width 0.1)
				(type default)
			)
			(layer "B.Fab")
		)
		(fp_line
			(start -0.12065 -0.3048)
			(end -0.67945 -0.3048)
			(stroke
				(width 0.1)
				(type default)
			)
			(layer "B.Fab")
		)
		(fp_line
			(start -0.12065 -0.2794)
			(end -0.12065 -0.3048)
			(stroke
				(width 0.1)
				(type default)
			)
			(layer "B.Fab")
		)
		(fp_line
			(start -0.120396 0.2794)
			(end 0.12065 0.2794)
			(stroke
				(width 0.1)
				(type default)
			)
			(layer "B.Fab")
		)
		(fp_line
			(start -0.120396 0.3048)
			(end -0.120396 0.2794)
			(stroke
				(width 0.1)
				(type default)
			)
			(layer "B.Fab")
		)
		(fp_line
			(start 0.12065 -0.305054)
			(end 0.12065 -0.2794)
			(stroke
				(width 0.1)
				(type default)
			)
			(layer "B.Fab")
		)
		(fp_line
			(start 0.12065 -0.2794)
			(end -0.12065 -0.2794)
			(stroke
				(width 0.1)
				(type default)
			)
			(layer "B.Fab")
		)
		(fp_line
			(start 0.12065 0.2794)
			(end 0.12065 0.3048)
			(stroke
				(width 0.1)
				(type default)
			)
			(layer "B.Fab")
		)
		(fp_line
			(start 0.12065 0.3048)
			(end 0.67945 0.3048)
			(stroke
				(width 0.1)
				(type default)
			)
			(layer "B.Fab")
		)
		(fp_line
			(start 0.67945 -0.305054)
			(end 0.12065 -0.305054)
			(stroke
				(width 0.1)
				(type default)
			)
			(layer "B.Fab")
		)
		(fp_line
			(start 0.67945 0.3048)
			(end 0.67945 -0.305054)
			(stroke
				(width 0.1)
				(type default)
			)
			(layer "B.Fab")
		)
		(pad "1" smd circle
			(at 0.40005 0 180)
			(size 0 0)
			(layers "B.Cu" "B.Mask" "B.Paste")
			(net "FM_CPU0_SKTOCC_LVT3_N")
		)
		(pad "2" smd circle
			(at -0.40005 0 180)
			(size 0 0)
			(layers "B.Cu" "B.Mask" "B.Paste")
			(net "FM_CPU0_SKTOCC_N")
		)
	)
	(footprint ""
		(layer "B.Cu")
		(at 490.2708 -342.785192)
		(property "Reference" "DB14"
			(at 2.639822 -5.63118 270)
			(unlocked yes)
			(layer "B.SilkS")
			(effects
				(font
					(size 0.7874 0.5842)
					(thickness 0.1524)
				)
				(justify left mirror)
			)
		)
		(property "Value" ""
			(at 0 0 0)
			(layer "B.Fab")
			(effects
				(font
					(size 1.27 1.27)
				)
				(justify mirror)
			)
		)
		(duplicate_pad_numbers_are_jumpers no)
		(fp_line
			(start -3.330702 -4.771136)
			(end 0 4.011168)
			(stroke
				(width 0.1524)
				(type default)
			)
			(layer "B.SilkS")
		)
		(fp_line
			(start 0 4.011168)
			(end 3.330702 -4.771136)
			(stroke
				(width 0.1524)
				(type default)
			)
			(layer "B.SilkS")
		)
		(fp_line
			(start 3.330702 -4.771136)
			(end -3.330702 -4.771136)
			(stroke
				(width 0.1524)
				(type default)
			)
			(layer "B.SilkS")
		)
		(fp_line
			(start -3.330702 -4.771136)
			(end 0 4.011168)
			(stroke
				(width 0.1)
				(type default)
			)
			(layer "B.Fab")
		)
		(fp_line
			(start 0 4.011168)
			(end 3.330702 -4.771136)
			(stroke
				(width 0.1)
				(type default)
			)
			(layer "B.Fab")
		)
		(fp_line
			(start 3.330702 -4.771136)
			(end -3.330702 -4.771136)
			(stroke
				(width 0.1)
				(type default)
			)
			(layer "B.Fab")
		)
		(pad "1" thru_hole circle
			(at 0 0 180)
			(size 2.159 2.159)
			(drill 1.7018)
			(layers "*.Cu" "*.Mask")
			(remove_unused_layers no)
			(net "T1_GND")
			(clearance 0.0254)
			(thermal_gap 0.0254)
		)
		(pad "2" thru_hole circle
			(at 1.27 -3.348736 180)
			(size 2.159 2.159)
			(drill 1.7018)
			(layers "*.Cu" "*.Mask")
			(remove_unused_layers no)
			(net "TDR_SE_40_OHM_IN6")
			(clearance 0.0254)
			(thermal_gap 0.0254)
		)
		(pad "3" thru_hole circle
			(at -1.27 -3.348736 180)
			(size 2.159 2.159)
			(drill 1.7018)
			(layers "*.Cu" "*.Mask")
			(remove_unused_layers no)
			(net "TDR_SE_40_OHM_IN6")
			(clearance 0.0254)
			(thermal_gap 0.0254)
		)
	)
	(footprint ""
		(layer "B.Cu")
		(at 134.54888 -9.362948 -90)
		(property "Reference" "R3777"
			(at 0 0 90)
			(layer "B.SilkS")
			(hide yes)
			(effects
				(font
					(size 1.27 1.27)
				)
				(justify mirror)
			)
		)
		(property "Value" ""
			(at 0 0 90)
			(layer "B.Fab")
			(effects
				(font
					(size 1.27 1.27)
				)
				(justify mirror)
			)
		)
		(duplicate_pad_numbers_are_jumpers no)
		(fp_line
			(start -0.7874 0.4064)
			(end 0.7874 0.4064)
			(stroke
				(width 0.1524)
				(type default)
			)
			(layer "B.SilkS")
		)
		(fp_line
			(start 0.7874 0.4064)
			(end 0.7874 -0.4064)
			(stroke
				(width 0.1524)
				(type default)
			)
			(layer "B.SilkS")
		)
		(fp_line
			(start -0.7874 -0.4064)
			(end -0.7874 0.4064)
			(stroke
				(width 0.1524)
				(type default)
			)
			(layer "B.SilkS")
		)
		(fp_line
			(start 0.7874 -0.4064)
			(end -0.7874 -0.4064)
			(stroke
				(width 0.1524)
				(type default)
			)
			(layer "B.SilkS")
		)
		(fp_line
			(start -0.67945 0.3048)
			(end -0.120396 0.3048)
			(stroke
				(width 0.1)
				(type default)
			)
			(layer "B.Fab")
		)
		(fp_line
			(start -0.120396 0.3048)
			(end -0.120396 0.2794)
			(stroke
				(width 0.1)
				(type default)
			)
			(layer "B.Fab")
		)
		(fp_line
			(start 0.12065 0.3048)
			(end 0.67945 0.3048)
			(stroke
				(width 0.1)
				(type default)
			)
			(layer "B.Fab")
		)
		(fp_line
			(start 0.67945 0.3048)
			(end 0.67945 -0.305054)
			(stroke
				(width 0.1)
				(type default)
			)
			(layer "B.Fab")
		)
		(fp_line
			(start -0.120396 0.2794)
			(end 0.12065 0.2794)
			(stroke
				(width 0.1)
				(type default)
			)
			(layer "B.Fab")
		)
		(fp_line
			(start 0.12065 0.2794)
			(end 0.12065 0.3048)
			(stroke
				(width 0.1)
				(type default)
			)
			(layer "B.Fab")
		)
		(fp_line
			(start -0.12065 -0.2794)
			(end -0.12065 -0.3048)
			(stroke
				(width 0.1)
				(type default)
			)
			(layer "B.Fab")
		)
		(fp_line
			(start 0.12065 -0.2794)
			(end -0.12065 -0.2794)
			(stroke
				(width 0.1)
				(type default)
			)
			(layer "B.Fab")
		)
		(fp_line
			(start -0.67945 -0.3048)
			(end -0.67945 0.3048)
			(stroke
				(width 0.1)
				(type default)
			)
			(layer "B.Fab")
		)
		(fp_line
			(start -0.12065 -0.3048)
			(end -0.67945 -0.3048)
			(stroke
				(width 0.1)
				(type default)
			)
			(layer "B.Fab")
		)
		(fp_line
			(start 0.12065 -0.305054)
			(end 0.12065 -0.2794)
			(stroke
				(width 0.1)
				(type default)
			)
			(layer "B.Fab")
		)
		(fp_line
			(start 0.67945 -0.305054)
			(end 0.12065 -0.305054)
			(stroke
				(width 0.1)
				(type default)
			)
			(layer "B.Fab")
		)
		(pad "1" smd circle
			(at 0.40005 0 90)
			(size 0 0)
			(layers "B.Cu" "B.Mask" "B.Paste")
			(net "FM_UARTSW_LSB_N")
		)
		(pad "2" smd circle
			(at -0.40005 0 90)
			(size 0 0)
			(layers "B.Cu" "B.Mask" "B.Paste")
			(net "FM_UARTSW_LSB_R")
		)
	)
	(footprint ""
		(layer "B.Cu")
		(at 170.12158 -50.107088 180)
		(property "Reference" "C1922"
			(at 0 0 0)
			(layer "B.SilkS")
			(hide yes)
			(effects
				(font
					(size 1.27 1.27)
				)
				(justify mirror)
			)
		)
		(property "Value" ""
			(at 0 0 0)
			(layer "B.Fab")
			(effects
				(font
					(size 1.27 1.27)
				)
				(justify mirror)
			)
		)
		(duplicate_pad_numbers_are_jumpers no)
		(fp_line
			(start 1.2954 0.5842)
			(end 1.2954 -0.5842)
			(stroke
				(width 0.1524)
				(type default)
			)
			(layer "B.SilkS")
		)
		(fp_line
			(start 1.2954 -0.5842)
			(end -1.2954 -0.5842)
			(stroke
				(width 0.1524)
				(type default)
			)
			(layer "B.SilkS")
		)
		(fp_line
			(start 0 -0.5842)
			(end 0 0.5842)
			(stroke
				(width 0.1524)
				(type default)
			)
			(layer "B.SilkS")
		)
		(fp_line
			(start -1.2954 0.5842)
			(end 1.2954 0.5842)
			(stroke
				(width 0.1524)
				(type default)
			)
			(layer "B.SilkS")
		)
		(fp_line
			(start -1.2954 -0.5842)
			(end -1.2954 0.5842)
			(stroke
				(width 0.1524)
				(type default)
			)
			(layer "B.SilkS")
		)
		(fp_line
			(start 1.1938 0.4064)
			(end 1.1938 -0.4064)
			(stroke
				(width 0.1)
				(type default)
			)
			(layer "B.Fab")
		)
		(fp_line
			(start 1.1938 -0.4064)
			(end 0.8636 -0.4064)
			(stroke
				(width 0.1)
				(type default)
			)
			(layer "B.Fab")
		)
		(fp_line
			(start 0.8636 0.4572)
			(end 0.8636 0.4064)
			(stroke
				(width 0.1)
				(type default)
			)
			(layer "B.Fab")
		)
		(fp_line
			(start 0.8636 0.4064)
			(end 1.1938 0.4064)
			(stroke
				(width 0.1)
				(type default)
			)
			(layer "B.Fab")
		)
		(fp_line
			(start 0.8636 -0.4064)
			(end 0.8636 -0.4572)
			(stroke
				(width 0.1)
				(type default)
			)
			(layer "B.Fab")
		)
		(fp_line
			(start 0.8636 -0.4572)
			(end -0.8636 -0.4572)
			(stroke
				(width 0.1)
				(type default)
			)
			(layer "B.Fab")
		)
		(fp_line
			(start -0.8636 0.4572)
			(end 0.8636 0.4572)
			(stroke
				(width 0.1)
				(type default)
			)
			(layer "B.Fab")
		)
		(fp_line
			(start -0.8636 0.4064)
			(end -0.8636 0.4572)
			(stroke
				(width 0.1)
				(type default)
			)
			(layer "B.Fab")
		)
		(fp_line
			(start -0.8636 -0.4064)
			(end -1.1938 -0.4064)
			(stroke
				(width 0.1)
				(type default)
			)
			(layer "B.Fab")
		)
		(fp_line
			(start -0.8636 -0.4572)
			(end -0.8636 -0.4064)
			(stroke
				(width 0.1)
				(type default)
			)
			(layer "B.Fab")
		)
		(fp_line
			(start -1.1938 0.4064)
			(end -0.8636 0.4064)
			(stroke
				(width 0.1)
				(type default)
			)
			(layer "B.Fab")
		)
		(fp_line
			(start -1.1938 -0.4064)
			(end -1.1938 0.4064)
			(stroke
				(width 0.1)
				(type default)
			)
			(layer "B.Fab")
		)
		(pad "1" smd rect
			(at 0.7366 0 90)
			(size 0.7112 0.8128)
			(layers "B.Cu" "B.Mask" "B.Paste")
			(net "P3V3_M2_0")
		)
		(pad "2" smd rect
			(at -0.7366 0 90)
			(size 0.7112 0.8128)
			(layers "B.Cu" "B.Mask" "B.Paste")
			(net "GND")
		)
	)
	(footprint ""
		(layer "B.Cu")
		(at 118.18112 -244.82044 -90)
		(property "Reference" "C317"
			(at 0 0 90)
			(layer "B.SilkS")
			(hide yes)
			(effects
				(font
					(size 1.27 1.27)
				)
				(justify mirror)
			)
		)
		(property "Value" ""
			(at 0 0 90)
			(layer "B.Fab")
			(effects
				(font
					(size 1.27 1.27)
				)
				(justify mirror)
			)
		)
		(duplicate_pad_numbers_are_jumpers no)
		(fp_line
			(start -1.524 0.762)
			(end 1.524 0.762)
			(stroke
				(width 0.1524)
				(type default)
			)
			(layer "B.SilkS")
		)
		(fp_line
			(start 1.524 0.762)
			(end 1.524 -0.762)
			(stroke
				(width 0.1524)
				(type default)
			)
			(layer "B.SilkS")
		)
		(fp_line
			(start -1.524 -0.762)
			(end -1.524 0.762)
			(stroke
				(width 0.1524)
				(type default)
			)
			(layer "B.SilkS")
		)
		(fp_line
			(start 1.524 -0.762)
			(end -1.524 -0.762)
			(stroke
				(width 0.1524)
				(type default)
			)
			(layer "B.SilkS")
		)
		(fp_line
			(start -1.1049 0.724916)
			(end -1.1049 -0.724916)
			(stroke
				(width 0.1)
				(type default)
			)
			(layer "B.Fab")
		)
		(fp_line
			(start 1.1049 0.724916)
			(end -1.1049 0.724916)
			(stroke
				(width 0.1)
				(type default)
			)
			(layer "B.Fab")
		)
		(fp_line
			(start -1.1049 -0.724916)
			(end 1.1049 -0.724916)
			(stroke
				(width 0.1)
				(type default)
			)
			(layer "B.Fab")
		)
		(fp_line
			(start 1.1049 -0.724916)
			(end 1.1049 0.724916)
			(stroke
				(width 0.1)
				(type default)
			)
			(layer "B.Fab")
		)
		(pad "1" smd rect
			(at 0.889 0 270)
			(size 1.016 1.27)
			(layers "B.Cu" "B.Mask" "B.Paste")
			(net "PVCCIN_CPU1")
		)
		(pad "2" smd rect
			(at -0.889 0 270)
			(size 1.016 1.27)
			(layers "B.Cu" "B.Mask" "B.Paste")
			(net "GND")
		)
	)
	(footprint ""
		(layer "B.Cu")
		(at 72.82688 -11.267948 90)
		(property "Reference" "R3163"
			(at 0 0 90)
			(layer "B.SilkS")
			(hide yes)
			(effects
				(font
					(size 1.27 1.27)
				)
				(justify mirror)
			)
		)
		(property "Value" ""
			(at 0 0 90)
			(layer "B.Fab")
			(effects
				(font
					(size 1.27 1.27)
				)
				(justify mirror)
			)
		)
		(duplicate_pad_numbers_are_jumpers no)
		(fp_line
			(start 0.7874 -0.4064)
			(end -0.7874 -0.4064)
			(stroke
				(width 0.1524)
				(type default)
			)
			(layer "B.SilkS")
		)
		(fp_line
			(start -0.7874 -0.4064)
			(end -0.7874 0.4064)
			(stroke
				(width 0.1524)
				(type default)
			)
			(layer "B.SilkS")
		)
		(fp_line
			(start 0.7874 0.4064)
			(end 0.7874 -0.4064)
			(stroke
				(width 0.1524)
				(type default)
			)
			(layer "B.SilkS")
		)
		(fp_line
			(start -0.7874 0.4064)
			(end 0.7874 0.4064)
			(stroke
				(width 0.1524)
				(type default)
			)
			(layer "B.SilkS")
		)
		(fp_line
			(start 0.67945 -0.305054)
			(end 0.12065 -0.305054)
			(stroke
				(width 0.1)
				(type default)
			)
			(layer "B.Fab")
		)
		(fp_line
			(start 0.12065 -0.305054)
			(end 0.12065 -0.2794)
			(stroke
				(width 0.1)
				(type default)
			)
			(layer "B.Fab")
		)
		(fp_line
			(start -0.12065 -0.3048)
			(end -0.67945 -0.3048)
			(stroke
				(width 0.1)
				(type default)
			)
			(layer "B.Fab")
		)
		(fp_line
			(start -0.67945 -0.3048)
			(end -0.67945 0.3048)
			(stroke
				(width 0.1)
				(type default)
			)
			(layer "B.Fab")
		)
		(fp_line
			(start 0.12065 -0.2794)
			(end -0.12065 -0.2794)
			(stroke
				(width 0.1)
				(type default)
			)
			(layer "B.Fab")
		)
		(fp_line
			(start -0.12065 -0.2794)
			(end -0.12065 -0.3048)
			(stroke
				(width 0.1)
				(type default)
			)
			(layer "B.Fab")
		)
		(fp_line
			(start 0.12065 0.2794)
			(end 0.12065 0.3048)
			(stroke
				(width 0.1)
				(type default)
			)
			(layer "B.Fab")
		)
		(fp_line
			(start -0.120396 0.2794)
			(end 0.12065 0.2794)
			(stroke
				(width 0.1)
				(type default)
			)
			(layer "B.Fab")
		)
		(fp_line
			(start 0.67945 0.3048)
			(end 0.67945 -0.305054)
			(stroke
				(width 0.1)
				(type default)
			)
			(layer "B.Fab")
		)
		(fp_line
			(start 0.12065 0.3048)
			(end 0.67945 0.3048)
			(stroke
				(width 0.1)
				(type default)
			)
			(layer "B.Fab")
		)
		(fp_line
			(start -0.120396 0.3048)
			(end -0.120396 0.2794)
			(stroke
				(width 0.1)
				(type default)
			)
			(layer "B.Fab")
		)
		(fp_line
			(start -0.67945 0.3048)
			(end -0.120396 0.3048)
			(stroke
				(width 0.1)
				(type default)
			)
			(layer "B.Fab")
		)
		(pad "1" smd circle
			(at 0.40005 0 270)
			(size 0 0)
			(layers "B.Cu" "B.Mask" "B.Paste")
			(net "OCP_V3_2_ID0")
		)
		(pad "2" smd circle
			(at -0.40005 0 270)
			(size 0 0)
			(layers "B.Cu" "B.Mask" "B.Paste")
			(net "GND")
		)
	)
	(footprint ""
		(layer "B.Cu")
		(at 36.968938 -125.38456)
		(property "Reference" "R2556"
			(at 0 0 0)
			(layer "B.SilkS")
			(hide yes)
			(effects
				(font
					(size 1.27 1.27)
				)
				(justify mirror)
			)
		)
		(property "Value" ""
			(at 0 0 0)
			(layer "B.Fab")
			(effects
				(font
					(size 1.27 1.27)
				)
				(justify mirror)
			)
		)
		(duplicate_pad_numbers_are_jumpers no)
		(fp_line
			(start -0.7874 -0.4064)
			(end -0.7874 0.4064)
			(stroke
				(width 0.1524)
				(type default)
			)
			(layer "B.SilkS")
		)
		(fp_line
			(start -0.7874 0.4064)
			(end 0.7874 0.4064)
			(stroke
				(width 0.1524)
				(type default)
			)
			(layer "B.SilkS")
		)
		(fp_line
			(start 0.7874 -0.4064)
			(end -0.7874 -0.4064)
			(stroke
				(width 0.1524)
				(type default)
			)
			(layer "B.SilkS")
		)
		(fp_line
			(start 0.7874 0.4064)
			(end 0.7874 -0.4064)
			(stroke
				(width 0.1524)
				(type default)
			)
			(layer "B.SilkS")
		)
		(fp_line
			(start -0.67945 -0.3048)
			(end -0.67945 0.3048)
			(stroke
				(width 0.1)
				(type default)
			)
			(layer "B.Fab")
		)
		(fp_line
			(start -0.67945 0.3048)
			(end -0.120396 0.3048)
			(stroke
				(width 0.1)
				(type default)
			)
			(layer "B.Fab")
		)
		(fp_line
			(start -0.12065 -0.3048)
			(end -0.67945 -0.3048)
			(stroke
				(width 0.1)
				(type default)
			)
			(layer "B.Fab")
		)
		(fp_line
			(start -0.12065 -0.2794)
			(end -0.12065 -0.3048)
			(stroke
				(width 0.1)
				(type default)
			)
			(layer "B.Fab")
		)
		(fp_line
			(start -0.120396 0.2794)
			(end 0.12065 0.2794)
			(stroke
				(width 0.1)
				(type default)
			)
			(layer "B.Fab")
		)
		(fp_line
			(start -0.120396 0.3048)
			(end -0.120396 0.2794)
			(stroke
				(width 0.1)
				(type default)
			)
			(layer "B.Fab")
		)
		(fp_line
			(start 0.12065 -0.305054)
			(end 0.12065 -0.2794)
			(stroke
				(width 0.1)
				(type default)
			)
			(layer "B.Fab")
		)
		(fp_line
			(start 0.12065 -0.2794)
			(end -0.12065 -0.2794)
			(stroke
				(width 0.1)
				(type default)
			)
			(layer "B.Fab")
		)
		(fp_line
			(start 0.12065 0.2794)
			(end 0.12065 0.3048)
			(stroke
				(width 0.1)
				(type default)
			)
			(layer "B.Fab")
		)
		(fp_line
			(start 0.12065 0.3048)
			(end 0.67945 0.3048)
			(stroke
				(width 0.1)
				(type default)
			)
			(layer "B.Fab")
		)
		(fp_line
			(start 0.67945 -0.305054)
			(end 0.12065 -0.305054)
			(stroke
				(width 0.1)
				(type default)
			)
			(layer "B.Fab")
		)
		(fp_line
			(start 0.67945 0.3048)
			(end 0.67945 -0.305054)
			(stroke
				(width 0.1)
				(type default)
			)
			(layer "B.Fab")
		)
		(pad "1" smd circle
			(at 0.40005 0 180)
			(size 0 0)
			(layers "B.Cu" "B.Mask" "B.Paste")
			(net "P3V3_AUX")
		)
		(pad "2" smd circle
			(at -0.40005 0 180)
			(size 0 0)
			(layers "B.Cu" "B.Mask" "B.Paste")
			(net "PWRGD_PVCCINFAON_CPU1_R")
		)
	)
	(footprint ""
		(layer "B.Cu")
		(at 176.555654 -110.975394 -90)
		(property "Reference" "C1898"
			(at 0 0 90)
			(layer "B.SilkS")
			(hide yes)
			(effects
				(font
					(size 1.27 1.27)
				)
				(justify mirror)
			)
		)
		(property "Value" ""
			(at 0 0 90)
			(layer "B.Fab")
			(effects
				(font
					(size 1.27 1.27)
				)
				(justify mirror)
			)
		)
		(duplicate_pad_numbers_are_jumpers no)
		(fp_line
			(start -0.69215 0.2921)
			(end 0.69215 0.2921)
			(stroke
				(width 0.1524)
				(type default)
			)
			(layer "B.SilkS")
		)
		(fp_line
			(start 0.69215 0.2921)
			(end 0.69215 -0.2921)
			(stroke
				(width 0.1524)
				(type default)
			)
			(layer "B.SilkS")
		)
		(fp_line
			(start -0.69215 -0.2921)
			(end -0.69215 0.2921)
			(stroke
				(width 0.1524)
				(type default)
			)
			(layer "B.SilkS")
		)
		(fp_line
			(start 0.69215 -0.2921)
			(end -0.69215 -0.2921)
			(stroke
				(width 0.1524)
				(type default)
			)
			(layer "B.SilkS")
		)
		(fp_line
			(start -0.51435 0.2794)
			(end 0.51435 0.2794)
			(stroke
				(width 0.1)
				(type default)
			)
			(layer "B.Fab")
		)
		(fp_line
			(start 0.51435 0.2794)
			(end 0.51435 -0.2794)
			(stroke
				(width 0.1)
				(type default)
			)
			(layer "B.Fab")
		)
		(fp_line
			(start -0.51435 -0.2794)
			(end -0.51435 0.2794)
			(stroke
				(width 0.1)
				(type default)
			)
			(layer "B.Fab")
		)
		(fp_line
			(start 0.51435 -0.2794)
			(end -0.51435 -0.2794)
			(stroke
				(width 0.1)
				(type default)
			)
			(layer "B.Fab")
		)
		(pad "1" smd circle
			(at 0.40005 0 90)
			(size 0 0)
			(layers "B.Cu" "B.Mask" "B.Paste")
			(net "P3V3_AUX_FPGA_VCCIO5")
		)
		(pad "2" smd circle
			(at -0.40005 0 90)
			(size 0 0)
			(layers "B.Cu" "B.Mask" "B.Paste")
			(net "GND")
		)
		(zone
			(layer "B.Cu")
			(hatch none 0.5)
			(connect_pads
				(clearance 0)
			)
			(min_thickness 0.25)
			(keepout
				(tracks not_allowed)
				(vias allowed)
				(pads allowed)
				(copperpour not_allowed)
				(footprints allowed)
			)
			(placement
				(enabled no)
				(sheetname "")
			)
			(fill
				(thermal_gap 0.5)
				(thermal_bridge_width 0.5)
				(island_removal_mode 0)
			)
			(polygon
				(pts
					(xy 176.468024 -110.784894) (xy 176.409858 -110.876334) (xy 176.409858 -111.075724) (xy 176.468024 -111.165894)
					(xy 176.643284 -111.165894) (xy 176.701704 -111.075724) (xy 176.701704 -110.876334) (xy 176.643538 -110.784894)
				)
			)
		)
	)
	(footprint ""
		(layer "B.Cu")
		(at 364.342934 -259.531866 90)
		(property "Reference" "C497"
			(at 0 0 90)
			(layer "B.SilkS")
			(hide yes)
			(effects
				(font
					(size 1.27 1.27)
				)
				(justify mirror)
			)
		)
		(property "Value" ""
			(at 0 0 90)
			(layer "B.Fab")
			(effects
				(font
					(size 1.27 1.27)
				)
				(justify mirror)
			)
		)
		(duplicate_pad_numbers_are_jumpers no)
		(fp_line
			(start 1.524 -0.762)
			(end -1.524 -0.762)
			(stroke
				(width 0.1524)
				(type default)
			)
			(layer "B.SilkS")
		)
		(fp_line
			(start -1.524 -0.762)
			(end -1.524 0.762)
			(stroke
				(width 0.1524)
				(type default)
			)
			(layer "B.SilkS")
		)
		(fp_line
			(start 1.524 0.762)
			(end 1.524 -0.762)
			(stroke
				(width 0.1524)
				(type default)
			)
			(layer "B.SilkS")
		)
		(fp_line
			(start -1.524 0.762)
			(end 1.524 0.762)
			(stroke
				(width 0.1524)
				(type default)
			)
			(layer "B.SilkS")
		)
		(fp_line
			(start 1.1049 -0.724916)
			(end 1.1049 0.724916)
			(stroke
				(width 0.1)
				(type default)
			)
			(layer "B.Fab")
		)
		(fp_line
			(start -1.1049 -0.724916)
			(end 1.1049 -0.724916)
			(stroke
				(width 0.1)
				(type default)
			)
			(layer "B.Fab")
		)
		(fp_line
			(start 1.1049 0.724916)
			(end -1.1049 0.724916)
			(stroke
				(width 0.1)
				(type default)
			)
			(layer "B.Fab")
		)
		(fp_line
			(start -1.1049 0.724916)
			(end -1.1049 -0.724916)
			(stroke
				(width 0.1)
				(type default)
			)
			(layer "B.Fab")
		)
		(pad "1" smd rect
			(at 0.889 0 90)
			(size 1.016 1.27)
			(layers "B.Cu" "B.Mask" "B.Paste")
			(net "PVCCFA_EHV_FIVRA_CPU0")
		)
		(pad "2" smd rect
			(at -0.889 0 90)
			(size 1.016 1.27)
			(layers "B.Cu" "B.Mask" "B.Paste")
			(net "GND")
		)
	)
	(footprint ""
		(layer "B.Cu")
		(at 141.057122 -342.936576 90)
		(property "Reference" "PC493_P1_8"
			(at 0 0 90)
			(layer "B.SilkS")
			(hide yes)
			(effects
				(font
					(size 1.27 1.27)
				)
				(justify mirror)
			)
		)
		(property "Value" ""
			(at 0 0 90)
			(layer "B.Fab")
			(effects
				(font
					(size 1.27 1.27)
				)
				(justify mirror)
			)
		)
		(duplicate_pad_numbers_are_jumpers no)
		(fp_line
			(start 1.524 -0.762)
			(end -1.524 -0.762)
			(stroke
				(width 0.1524)
				(type default)
			)
			(layer "B.SilkS")
		)
		(fp_line
			(start -1.524 -0.762)
			(end -1.524 0.762)
			(stroke
				(width 0.1524)
				(type default)
			)
			(layer "B.SilkS")
		)
		(fp_line
			(start 1.524 0.762)
			(end 1.524 -0.762)
			(stroke
				(width 0.1524)
				(type default)
			)
			(layer "B.SilkS")
		)
		(fp_line
			(start -1.524 0.762)
			(end 1.524 0.762)
			(stroke
				(width 0.1524)
				(type default)
			)
			(layer "B.SilkS")
		)
		(fp_line
			(start 1.1049 -0.724916)
			(end 1.1049 0.724916)
			(stroke
				(width 0.1)
				(type default)
			)
			(layer "B.Fab")
		)
		(fp_line
			(start -1.1049 -0.724916)
			(end 1.1049 -0.724916)
			(stroke
				(width 0.1)
				(type default)
			)
			(layer "B.Fab")
		)
		(fp_line
			(start 1.1049 0.724916)
			(end -1.1049 0.724916)
			(stroke
				(width 0.1)
				(type default)
			)
			(layer "B.Fab")
		)
		(fp_line
			(start -1.1049 0.724916)
			(end -1.1049 -0.724916)
			(stroke
				(width 0.1)
				(type default)
			)
			(layer "B.Fab")
		)
		(pad "1" smd rect
			(at 0.889 0 90)
			(size 1.016 1.27)
			(layers "B.Cu" "B.Mask" "B.Paste")
			(net "SW_P12V_PVCCIN_CPU1_FLT")
		)
		(pad "2" smd rect
			(at -0.889 0 90)
			(size 1.016 1.27)
			(layers "B.Cu" "B.Mask" "B.Paste")
			(net "GND")
		)
	)
	(footprint ""
		(layer "B.Cu")
		(at 164.64788 -111.470948)
		(property "Reference" "R1660"
			(at 0 0 0)
			(layer "B.SilkS")
			(hide yes)
			(effects
				(font
					(size 1.27 1.27)
				)
				(justify mirror)
			)
		)
		(property "Value" ""
			(at 0 0 0)
			(layer "B.Fab")
			(effects
				(font
					(size 1.27 1.27)
				)
				(justify mirror)
			)
		)
		(duplicate_pad_numbers_are_jumpers no)
		(fp_line
			(start -0.7874 -0.4064)
			(end -0.7874 0.4064)
			(stroke
				(width 0.1524)
				(type default)
			)
			(layer "B.SilkS")
		)
		(fp_line
			(start -0.7874 0.4064)
			(end 0.7874 0.4064)
			(stroke
				(width 0.1524)
				(type default)
			)
			(layer "B.SilkS")
		)
		(fp_line
			(start 0.7874 -0.4064)
			(end -0.7874 -0.4064)
			(stroke
				(width 0.1524)
				(type default)
			)
			(layer "B.SilkS")
		)
		(fp_line
			(start 0.7874 0.4064)
			(end 0.7874 -0.4064)
			(stroke
				(width 0.1524)
				(type default)
			)
			(layer "B.SilkS")
		)
		(fp_line
			(start -0.67945 -0.3048)
			(end -0.67945 0.3048)
			(stroke
				(width 0.1)
				(type default)
			)
			(layer "B.Fab")
		)
		(fp_line
			(start -0.67945 0.3048)
			(end -0.120396 0.3048)
			(stroke
				(width 0.1)
				(type default)
			)
			(layer "B.Fab")
		)
		(fp_line
			(start -0.12065 -0.3048)
			(end -0.67945 -0.3048)
			(stroke
				(width 0.1)
				(type default)
			)
			(layer "B.Fab")
		)
		(fp_line
			(start -0.12065 -0.2794)
			(end -0.12065 -0.3048)
			(stroke
				(width 0.1)
				(type default)
			)
			(layer "B.Fab")
		)
		(fp_line
			(start -0.120396 0.2794)
			(end 0.12065 0.2794)
			(stroke
				(width 0.1)
				(type default)
			)
			(layer "B.Fab")
		)
		(fp_line
			(start -0.120396 0.3048)
			(end -0.120396 0.2794)
			(stroke
				(width 0.1)
				(type default)
			)
			(layer "B.Fab")
		)
		(fp_line
			(start 0.12065 -0.305054)
			(end 0.12065 -0.2794)
			(stroke
				(width 0.1)
				(type default)
			)
			(layer "B.Fab")
		)
		(fp_line
			(start 0.12065 -0.2794)
			(end -0.12065 -0.2794)
			(stroke
				(width 0.1)
				(type default)
			)
			(layer "B.Fab")
		)
		(fp_line
			(start 0.12065 0.2794)
			(end 0.12065 0.3048)
			(stroke
				(width 0.1)
				(type default)
			)
			(layer "B.Fab")
		)
		(fp_line
			(start 0.12065 0.3048)
			(end 0.67945 0.3048)
			(stroke
				(width 0.1)
				(type default)
			)
			(layer "B.Fab")
		)
		(fp_line
			(start 0.67945 -0.305054)
			(end 0.12065 -0.305054)
			(stroke
				(width 0.1)
				(type default)
			)
			(layer "B.Fab")
		)
		(fp_line
			(start 0.67945 0.3048)
			(end 0.67945 -0.305054)
			(stroke
				(width 0.1)
				(type default)
			)
			(layer "B.Fab")
		)
		(pad "1" smd circle
			(at 0.40005 0 180)
			(size 0 0)
			(layers "B.Cu" "B.Mask" "B.Paste")
			(net "FM_SLP_SUS_RSM_RST_N")
		)
		(pad "2" smd circle
			(at -0.40005 0 180)
			(size 0 0)
			(layers "B.Cu" "B.Mask" "B.Paste")
			(net "P3V3_AUX")
		)
	)
	(footprint ""
		(layer "B.Cu")
		(at 436.971694 -121.730008)
		(property "Reference" "R363"
			(at 0 0 0)
			(layer "B.SilkS")
			(hide yes)
			(effects
				(font
					(size 1.27 1.27)
				)
				(justify mirror)
			)
		)
		(property "Value" ""
			(at 0 0 0)
			(layer "B.Fab")
			(effects
				(font
					(size 1.27 1.27)
				)
				(justify mirror)
			)
		)
		(duplicate_pad_numbers_are_jumpers no)
		(fp_line
			(start -0.7874 -0.4064)
			(end -0.7874 0.4064)
			(stroke
				(width 0.1524)
				(type default)
			)
			(layer "B.SilkS")
		)
		(fp_line
			(start -0.7874 0.4064)
			(end 0.7874 0.4064)
			(stroke
				(width 0.1524)
				(type default)
			)
			(layer "B.SilkS")
		)
		(fp_line
			(start 0.7874 -0.4064)
			(end -0.7874 -0.4064)
			(stroke
				(width 0.1524)
				(type default)
			)
			(layer "B.SilkS")
		)
		(fp_line
			(start 0.7874 0.4064)
			(end 0.7874 -0.4064)
			(stroke
				(width 0.1524)
				(type default)
			)
			(layer "B.SilkS")
		)
		(fp_line
			(start -0.67945 -0.3048)
			(end -0.67945 0.3048)
			(stroke
				(width 0.1)
				(type default)
			)
			(layer "B.Fab")
		)
		(fp_line
			(start -0.67945 0.3048)
			(end -0.120396 0.3048)
			(stroke
				(width 0.1)
				(type default)
			)
			(layer "B.Fab")
		)
		(fp_line
			(start -0.12065 -0.3048)
			(end -0.67945 -0.3048)
			(stroke
				(width 0.1)
				(type default)
			)
			(layer "B.Fab")
		)
		(fp_line
			(start -0.12065 -0.2794)
			(end -0.12065 -0.3048)
			(stroke
				(width 0.1)
				(type default)
			)
			(layer "B.Fab")
		)
		(fp_line
			(start -0.120396 0.2794)
			(end 0.12065 0.2794)
			(stroke
				(width 0.1)
				(type default)
			)
			(layer "B.Fab")
		)
		(fp_line
			(start -0.120396 0.3048)
			(end -0.120396 0.2794)
			(stroke
				(width 0.1)
				(type default)
			)
			(layer "B.Fab")
		)
		(fp_line
			(start 0.12065 -0.305054)
			(end 0.12065 -0.2794)
			(stroke
				(width 0.1)
				(type default)
			)
			(layer "B.Fab")
		)
		(fp_line
			(start 0.12065 -0.2794)
			(end -0.12065 -0.2794)
			(stroke
				(width 0.1)
				(type default)
			)
			(layer "B.Fab")
		)
		(fp_line
			(start 0.12065 0.2794)
			(end 0.12065 0.3048)
			(stroke
				(width 0.1)
				(type default)
			)
			(layer "B.Fab")
		)
		(fp_line
			(start 0.12065 0.3048)
			(end 0.67945 0.3048)
			(stroke
				(width 0.1)
				(type default)
			)
			(layer "B.Fab")
		)
		(fp_line
			(start 0.67945 -0.305054)
			(end 0.12065 -0.305054)
			(stroke
				(width 0.1)
				(type default)
			)
			(layer "B.Fab")
		)
		(fp_line
			(start 0.67945 0.3048)
			(end 0.67945 -0.305054)
			(stroke
				(width 0.1)
				(type default)
			)
			(layer "B.Fab")
		)
		(pad "1" smd circle
			(at 0.40005 0 180)
			(size 0 0)
			(layers "B.Cu" "B.Mask" "B.Paste")
			(net "FM_PVCCD_HV_CPU0_EN")
		)
		(pad "2" smd circle
			(at -0.40005 0 180)
			(size 0 0)
			(layers "B.Cu" "B.Mask" "B.Paste")
			(net "PVCCD_HV_CPU0_EN_R")
		)
	)
	(footprint ""
		(layer "B.Cu")
		(at 429.397414 -321.549776 -90)
		(property "Reference" "C33"
			(at 0 0 90)
			(layer "B.SilkS")
			(hide yes)
			(effects
				(font
					(size 1.27 1.27)
				)
				(justify mirror)
			)
		)
		(property "Value" ""
			(at 0 0 90)
			(layer "B.Fab")
			(effects
				(font
					(size 1.27 1.27)
				)
				(justify mirror)
			)
		)
		(duplicate_pad_numbers_are_jumpers no)
		(fp_line
			(start -1.524 0.762)
			(end 1.524 0.762)
			(stroke
				(width 0.1524)
				(type default)
			)
			(layer "B.SilkS")
		)
		(fp_line
			(start 1.524 0.762)
			(end 1.524 -0.762)
			(stroke
				(width 0.1524)
				(type default)
			)
			(layer "B.SilkS")
		)
		(fp_line
			(start -1.524 -0.762)
			(end -1.524 0.762)
			(stroke
				(width 0.1524)
				(type default)
			)
			(layer "B.SilkS")
		)
		(fp_line
			(start 1.524 -0.762)
			(end -1.524 -0.762)
			(stroke
				(width 0.1524)
				(type default)
			)
			(layer "B.SilkS")
		)
		(fp_line
			(start -1.1049 0.724916)
			(end -1.1049 -0.724916)
			(stroke
				(width 0.1)
				(type default)
			)
			(layer "B.Fab")
		)
		(fp_line
			(start 1.1049 0.724916)
			(end -1.1049 0.724916)
			(stroke
				(width 0.1)
				(type default)
			)
			(layer "B.Fab")
		)
		(fp_line
			(start -1.1049 -0.724916)
			(end 1.1049 -0.724916)
			(stroke
				(width 0.1)
				(type default)
			)
			(layer "B.Fab")
		)
		(fp_line
			(start 1.1049 -0.724916)
			(end 1.1049 0.724916)
			(stroke
				(width 0.1)
				(type default)
			)
			(layer "B.Fab")
		)
		(pad "1" smd rect
			(at 0.889 0 270)
			(size 1.016 1.27)
			(layers "B.Cu" "B.Mask" "B.Paste")
			(net "P12V_S3_AUX_CPU0_NVDIMM")
		)
		(pad "2" smd rect
			(at -0.889 0 270)
			(size 1.016 1.27)
			(layers "B.Cu" "B.Mask" "B.Paste")
			(net "GND")
		)
	)
	(footprint ""
		(layer "B.Cu")
		(at 121.582688 -210.194144 180)
		(property "Reference" "C487"
			(at 0 0 0)
			(layer "B.SilkS")
			(hide yes)
			(effects
				(font
					(size 1.27 1.27)
				)
				(justify mirror)
			)
		)
		(property "Value" ""
			(at 0 0 0)
			(layer "B.Fab")
			(effects
				(font
					(size 1.27 1.27)
				)
				(justify mirror)
			)
		)
		(duplicate_pad_numbers_are_jumpers no)
		(fp_line
			(start 1.524 0.762)
			(end 1.524 -0.762)
			(stroke
				(width 0.1524)
				(type default)
			)
			(layer "B.SilkS")
		)
		(fp_line
			(start 1.524 -0.762)
			(end -1.524 -0.762)
			(stroke
				(width 0.1524)
				(type default)
			)
			(layer "B.SilkS")
		)
		(fp_line
			(start -1.524 0.762)
			(end 1.524 0.762)
			(stroke
				(width 0.1524)
				(type default)
			)
			(layer "B.SilkS")
		)
		(fp_line
			(start -1.524 -0.762)
			(end -1.524 0.762)
			(stroke
				(width 0.1524)
				(type default)
			)
			(layer "B.SilkS")
		)
		(fp_line
			(start 1.1049 0.724916)
			(end -1.1049 0.724916)
			(stroke
				(width 0.1)
				(type default)
			)
			(layer "B.Fab")
		)
		(fp_line
			(start 1.1049 -0.724916)
			(end 1.1049 0.724916)
			(stroke
				(width 0.1)
				(type default)
			)
			(layer "B.Fab")
		)
		(fp_line
			(start -1.1049 0.724916)
			(end -1.1049 -0.724916)
			(stroke
				(width 0.1)
				(type default)
			)
			(layer "B.Fab")
		)
		(fp_line
			(start -1.1049 -0.724916)
			(end 1.1049 -0.724916)
			(stroke
				(width 0.1)
				(type default)
			)
			(layer "B.Fab")
		)
		(pad "1" smd rect
			(at 0.889 0 180)
			(size 1.016 1.27)
			(layers "B.Cu" "B.Mask" "B.Paste")
			(net "PVCCINFAON_CPU1")
		)
		(pad "2" smd rect
			(at -0.889 0 180)
			(size 1.016 1.27)
			(layers "B.Cu" "B.Mask" "B.Paste")
			(net "GND")
		)
	)
	(footprint ""
		(layer "B.Cu")
		(at 435.145942 -8.316976 -90)
		(property "Reference" "R1895"
			(at 0 0 90)
			(layer "B.SilkS")
			(hide yes)
			(effects
				(font
					(size 1.27 1.27)
				)
				(justify mirror)
			)
		)
		(property "Value" ""
			(at 0 0 90)
			(layer "B.Fab")
			(effects
				(font
					(size 1.27 1.27)
				)
				(justify mirror)
			)
		)
		(duplicate_pad_numbers_are_jumpers no)
		(fp_line
			(start -0.7874 0.4064)
			(end 0.7874 0.4064)
			(stroke
				(width 0.1524)
				(type default)
			)
			(layer "B.SilkS")
		)
		(fp_line
			(start 0.7874 0.4064)
			(end 0.7874 -0.4064)
			(stroke
				(width 0.1524)
				(type default)
			)
			(layer "B.SilkS")
		)
		(fp_line
			(start -0.7874 -0.4064)
			(end -0.7874 0.4064)
			(stroke
				(width 0.1524)
				(type default)
			)
			(layer "B.SilkS")
		)
		(fp_line
			(start 0.7874 -0.4064)
			(end -0.7874 -0.4064)
			(stroke
				(width 0.1524)
				(type default)
			)
			(layer "B.SilkS")
		)
		(fp_line
			(start -0.67945 0.3048)
			(end -0.120396 0.3048)
			(stroke
				(width 0.1)
				(type default)
			)
			(layer "B.Fab")
		)
		(fp_line
			(start -0.120396 0.3048)
			(end -0.120396 0.2794)
			(stroke
				(width 0.1)
				(type default)
			)
			(layer "B.Fab")
		)
		(fp_line
			(start 0.12065 0.3048)
			(end 0.67945 0.3048)
			(stroke
				(width 0.1)
				(type default)
			)
			(layer "B.Fab")
		)
		(fp_line
			(start 0.67945 0.3048)
			(end 0.67945 -0.305054)
			(stroke
				(width 0.1)
				(type default)
			)
			(layer "B.Fab")
		)
		(fp_line
			(start -0.120396 0.2794)
			(end 0.12065 0.2794)
			(stroke
				(width 0.1)
				(type default)
			)
			(layer "B.Fab")
		)
		(fp_line
			(start 0.12065 0.2794)
			(end 0.12065 0.3048)
			(stroke
				(width 0.1)
				(type default)
			)
			(layer "B.Fab")
		)
		(fp_line
			(start -0.12065 -0.2794)
			(end -0.12065 -0.3048)
			(stroke
				(width 0.1)
				(type default)
			)
			(layer "B.Fab")
		)
		(fp_line
			(start 0.12065 -0.2794)
			(end -0.12065 -0.2794)
			(stroke
				(width 0.1)
				(type default)
			)
			(layer "B.Fab")
		)
		(fp_line
			(start -0.67945 -0.3048)
			(end -0.67945 0.3048)
			(stroke
				(width 0.1)
				(type default)
			)
			(layer "B.Fab")
		)
		(fp_line
			(start -0.12065 -0.3048)
			(end -0.67945 -0.3048)
			(stroke
				(width 0.1)
				(type default)
			)
			(layer "B.Fab")
		)
		(fp_line
			(start 0.12065 -0.305054)
			(end 0.12065 -0.2794)
			(stroke
				(width 0.1)
				(type default)
			)
			(layer "B.Fab")
		)
		(fp_line
			(start 0.67945 -0.305054)
			(end 0.12065 -0.305054)
			(stroke
				(width 0.1)
				(type default)
			)
			(layer "B.Fab")
		)
		(pad "1" smd circle
			(at 0.40005 0 90)
			(size 0 0)
			(layers "B.Cu" "B.Mask" "B.Paste")
			(net "OCP_SFF_PRSNTA_R_N")
		)
		(pad "2" smd circle
			(at -0.40005 0 90)
			(size 0 0)
			(layers "B.Cu" "B.Mask" "B.Paste")
			(net "GND")
		)
	)
	(footprint ""
		(layer "B.Cu")
		(at 407.0731 -319.080642 90)
		(property "Reference" "C29"
			(at 0 0 90)
			(layer "B.SilkS")
			(hide yes)
			(effects
				(font
					(size 1.27 1.27)
				)
				(justify mirror)
			)
		)
		(property "Value" ""
			(at 0 0 90)
			(layer "B.Fab")
			(effects
				(font
					(size 1.27 1.27)
				)
				(justify mirror)
			)
		)
		(duplicate_pad_numbers_are_jumpers no)
		(fp_line
			(start 0.7874 -0.4064)
			(end -0.7874 -0.4064)
			(stroke
				(width 0.1524)
				(type default)
			)
			(layer "B.SilkS")
		)
		(fp_line
			(start -0.7874 -0.4064)
			(end -0.7874 0.4064)
			(stroke
				(width 0.1524)
				(type default)
			)
			(layer "B.SilkS")
		)
		(fp_line
			(start 0.7874 0.4064)
			(end 0.7874 -0.4064)
			(stroke
				(width 0.1524)
				(type default)
			)
			(layer "B.SilkS")
		)
		(fp_line
			(start -0.7874 0.4064)
			(end 0.7874 0.4064)
			(stroke
				(width 0.1524)
				(type default)
			)
			(layer "B.SilkS")
		)
		(fp_line
			(start 0.67945 -0.305054)
			(end 0.12065 -0.305054)
			(stroke
				(width 0.1)
				(type default)
			)
			(layer "B.Fab")
		)
		(fp_line
			(start 0.12065 -0.305054)
			(end 0.12065 -0.2794)
			(stroke
				(width 0.1)
				(type default)
			)
			(layer "B.Fab")
		)
		(fp_line
			(start -0.12065 -0.3048)
			(end -0.67945 -0.3048)
			(stroke
				(width 0.1)
				(type default)
			)
			(layer "B.Fab")
		)
		(fp_line
			(start -0.67945 -0.3048)
			(end -0.67945 0.3048)
			(stroke
				(width 0.1)
				(type default)
			)
			(layer "B.Fab")
		)
		(fp_line
			(start 0.12065 -0.2794)
			(end -0.12065 -0.2794)
			(stroke
				(width 0.1)
				(type default)
			)
			(layer "B.Fab")
		)
		(fp_line
			(start -0.12065 -0.2794)
			(end -0.12065 -0.3048)
			(stroke
				(width 0.1)
				(type default)
			)
			(layer "B.Fab")
		)
		(fp_line
			(start 0.12065 0.2794)
			(end 0.12065 0.3048)
			(stroke
				(width 0.1)
				(type default)
			)
			(layer "B.Fab")
		)
		(fp_line
			(start -0.120396 0.2794)
			(end 0.12065 0.2794)
			(stroke
				(width 0.1)
				(type default)
			)
			(layer "B.Fab")
		)
		(fp_line
			(start 0.67945 0.3048)
			(end 0.67945 -0.305054)
			(stroke
				(width 0.1)
				(type default)
			)
			(layer "B.Fab")
		)
		(fp_line
			(start 0.12065 0.3048)
			(end 0.67945 0.3048)
			(stroke
				(width 0.1)
				(type default)
			)
			(layer "B.Fab")
		)
		(fp_line
			(start -0.120396 0.3048)
			(end -0.120396 0.2794)
			(stroke
				(width 0.1)
				(type default)
			)
			(layer "B.Fab")
		)
		(fp_line
			(start -0.67945 0.3048)
			(end -0.120396 0.3048)
			(stroke
				(width 0.1)
				(type default)
			)
			(layer "B.Fab")
		)
		(pad "1" smd circle
			(at 0.40005 0 270)
			(size 0 0)
			(layers "B.Cu" "B.Mask" "B.Paste")
			(net "P3V3_AUX")
		)
		(pad "2" smd circle
			(at -0.40005 0 270)
			(size 0 0)
			(layers "B.Cu" "B.Mask" "B.Paste")
			(net "GND")
		)
	)
	(footprint ""
		(layer "B.Cu")
		(at 233.2482 -423.0116 90)
		(property "Reference" "C2371"
			(at 0 0 90)
			(layer "B.SilkS")
			(hide yes)
			(effects
				(font
					(size 1.27 1.27)
				)
				(justify mirror)
			)
		)
		(property "Value" ""
			(at 0 0 90)
			(layer "B.Fab")
			(effects
				(font
					(size 1.27 1.27)
				)
				(justify mirror)
			)
		)
		(duplicate_pad_numbers_are_jumpers no)
		(fp_line
			(start 0.7874 -0.4064)
			(end -0.7874 -0.4064)
			(stroke
				(width 0.1524)
				(type default)
			)
			(layer "B.SilkS")
		)
		(fp_line
			(start -0.7874 -0.4064)
			(end -0.7874 0.4064)
			(stroke
				(width 0.1524)
				(type default)
			)
			(layer "B.SilkS")
		)
		(fp_line
			(start 0.7874 0.4064)
			(end 0.7874 -0.4064)
			(stroke
				(width 0.1524)
				(type default)
			)
			(layer "B.SilkS")
		)
		(fp_line
			(start -0.7874 0.4064)
			(end 0.7874 0.4064)
			(stroke
				(width 0.1524)
				(type default)
			)
			(layer "B.SilkS")
		)
		(fp_line
			(start 0.67945 -0.305054)
			(end 0.12065 -0.305054)
			(stroke
				(width 0.1)
				(type default)
			)
			(layer "B.Fab")
		)
		(fp_line
			(start 0.12065 -0.305054)
			(end 0.12065 -0.2794)
			(stroke
				(width 0.1)
				(type default)
			)
			(layer "B.Fab")
		)
		(fp_line
			(start -0.12065 -0.3048)
			(end -0.67945 -0.3048)
			(stroke
				(width 0.1)
				(type default)
			)
			(layer "B.Fab")
		)
		(fp_line
			(start -0.67945 -0.3048)
			(end -0.67945 0.3048)
			(stroke
				(width 0.1)
				(type default)
			)
			(layer "B.Fab")
		)
		(fp_line
			(start 0.12065 -0.2794)
			(end -0.12065 -0.2794)
			(stroke
				(width 0.1)
				(type default)
			)
			(layer "B.Fab")
		)
		(fp_line
			(start -0.12065 -0.2794)
			(end -0.12065 -0.3048)
			(stroke
				(width 0.1)
				(type default)
			)
			(layer "B.Fab")
		)
		(fp_line
			(start 0.12065 0.2794)
			(end 0.12065 0.3048)
			(stroke
				(width 0.1)
				(type default)
			)
			(layer "B.Fab")
		)
		(fp_line
			(start -0.120396 0.2794)
			(end 0.12065 0.2794)
			(stroke
				(width 0.1)
				(type default)
			)
			(layer "B.Fab")
		)
		(fp_line
			(start 0.67945 0.3048)
			(end 0.67945 -0.305054)
			(stroke
				(width 0.1)
				(type default)
			)
			(layer "B.Fab")
		)
		(fp_line
			(start 0.12065 0.3048)
			(end 0.67945 0.3048)
			(stroke
				(width 0.1)
				(type default)
			)
			(layer "B.Fab")
		)
		(fp_line
			(start -0.120396 0.3048)
			(end -0.120396 0.2794)
			(stroke
				(width 0.1)
				(type default)
			)
			(layer "B.Fab")
		)
		(fp_line
			(start -0.67945 0.3048)
			(end -0.120396 0.3048)
			(stroke
				(width 0.1)
				(type default)
			)
			(layer "B.Fab")
		)
		(pad "1" smd circle
			(at 0.40005 0 270)
			(size 0 0)
			(layers "B.Cu" "B.Mask" "B.Paste")
			(net "FM_AC_PWR_BTN_PDB_N")
		)
		(pad "2" smd circle
			(at -0.40005 0 270)
			(size 0 0)
			(layers "B.Cu" "B.Mask" "B.Paste")
			(net "GND")
		)
	)
	(footprint ""
		(layer "B.Cu")
		(at 375.943876 -366.755426 90)
		(property "Reference" "PC1255"
			(at 0 0 90)
			(layer "B.SilkS")
			(hide yes)
			(effects
				(font
					(size 1.27 1.27)
				)
				(justify mirror)
			)
		)
		(property "Value" ""
			(at 0 0 90)
			(layer "B.Fab")
			(effects
				(font
					(size 1.27 1.27)
				)
				(justify mirror)
			)
		)
		(duplicate_pad_numbers_are_jumpers no)
		(fp_line
			(start 1.524 -0.762)
			(end -1.524 -0.762)
			(stroke
				(width 0.1524)
				(type default)
			)
			(layer "B.SilkS")
		)
		(fp_line
			(start -1.524 -0.762)
			(end -1.524 0.762)
			(stroke
				(width 0.1524)
				(type default)
			)
			(layer "B.SilkS")
		)
		(fp_line
			(start 1.524 0.762)
			(end 1.524 -0.762)
			(stroke
				(width 0.1524)
				(type default)
			)
			(layer "B.SilkS")
		)
		(fp_line
			(start -1.524 0.762)
			(end 1.524 0.762)
			(stroke
				(width 0.1524)
				(type default)
			)
			(layer "B.SilkS")
		)
		(fp_line
			(start 1.1049 -0.724916)
			(end 1.1049 0.724916)
			(stroke
				(width 0.1)
				(type default)
			)
			(layer "B.Fab")
		)
		(fp_line
			(start -1.1049 -0.724916)
			(end 1.1049 -0.724916)
			(stroke
				(width 0.1)
				(type default)
			)
			(layer "B.Fab")
		)
		(fp_line
			(start 1.1049 0.724916)
			(end -1.1049 0.724916)
			(stroke
				(width 0.1)
				(type default)
			)
			(layer "B.Fab")
		)
		(fp_line
			(start -1.1049 0.724916)
			(end -1.1049 -0.724916)
			(stroke
				(width 0.1)
				(type default)
			)
			(layer "B.Fab")
		)
		(pad "1" smd rect
			(at 0.889 0 90)
			(size 1.016 1.27)
			(layers "B.Cu" "B.Mask" "B.Paste")
			(net "PVPP_HBM_CPU0")
		)
		(pad "2" smd rect
			(at -0.889 0 90)
			(size 1.016 1.27)
			(layers "B.Cu" "B.Mask" "B.Paste")
			(net "GND")
		)
	)
	(footprint ""
		(layer "B.Cu")
		(at 286.275526 -315.46673 -90)
		(property "Reference" "D43"
			(at 1.767332 3.355086 0)
			(unlocked yes)
			(layer "B.SilkS")
			(effects
				(font
					(size 0.7874 0.5842)
					(thickness 0.1524)
				)
				(justify left mirror)
			)
		)
		(property "Value" ""
			(at 0 0 90)
			(layer "B.Fab")
			(effects
				(font
					(size 1.27 1.27)
				)
				(justify mirror)
			)
		)
		(duplicate_pad_numbers_are_jumpers no)
		(fp_line
			(start -2.050796 0.700024)
			(end 2.050796 0.700024)
			(stroke
				(width 0.1524)
				(type default)
			)
			(layer "B.SilkS")
		)
		(fp_line
			(start 2.050796 0.700024)
			(end 2.050796 -0.700024)
			(stroke
				(width 0.1524)
				(type default)
			)
			(layer "B.SilkS")
		)
		(fp_line
			(start -2.343404 0.6985)
			(end -2.216404 0.6985)
			(stroke
				(width 0.1524)
				(type default)
			)
			(layer "B.SilkS")
		)
		(fp_line
			(start -2.229104 0.6985)
			(end -2.051304 0.6985)
			(stroke
				(width 0.1524)
				(type default)
			)
			(layer "B.SilkS")
		)
		(fp_line
			(start -2.051304 0.6985)
			(end -2.051304 0.635)
			(stroke
				(width 0.1524)
				(type default)
			)
			(layer "B.SilkS")
		)
		(fp_line
			(start -2.152904 0.635)
			(end -2.152904 -0.6985)
			(stroke
				(width 0.1524)
				(type default)
			)
			(layer "B.SilkS")
		)
		(fp_line
			(start -2.051304 0.635)
			(end -2.152904 0.635)
			(stroke
				(width 0.1524)
				(type default)
			)
			(layer "B.SilkS")
		)
		(fp_line
			(start 0.30607 0.500126)
			(end -0.193802 0)
			(stroke
				(width 0.1524)
				(type default)
			)
			(layer "B.SilkS")
		)
		(fp_line
			(start -0.193802 0)
			(end 0.30607 -0.500126)
			(stroke
				(width 0.1524)
				(type default)
			)
			(layer "B.SilkS")
		)
		(fp_line
			(start -0.293878 -0.500126)
			(end -0.293878 0.500126)
			(stroke
				(width 0.1524)
				(type default)
			)
			(layer "B.SilkS")
		)
		(fp_line
			(start 0.30607 -0.500126)
			(end 0.30607 0.500126)
			(stroke
				(width 0.1524)
				(type default)
			)
			(layer "B.SilkS")
		)
		(fp_line
			(start -2.064004 -0.6731)
			(end -2.064004 -0.6985)
			(stroke
				(width 0.1524)
				(type default)
			)
			(layer "B.SilkS")
		)
		(fp_line
			(start -2.343404 -0.6985)
			(end -2.343404 0.6985)
			(stroke
				(width 0.1524)
				(type default)
			)
			(layer "B.SilkS")
		)
		(fp_line
			(start -2.229104 -0.6985)
			(end -2.229104 0.6985)
			(stroke
				(width 0.1524)
				(type default)
			)
			(layer "B.SilkS")
		)
		(fp_line
			(start -2.152904 -0.6985)
			(end -2.343404 -0.6985)
			(stroke
				(width 0.1524)
				(type default)
			)
			(layer "B.SilkS")
		)
		(fp_line
			(start -2.064004 -0.6985)
			(end -2.229104 -0.6985)
			(stroke
				(width 0.1524)
				(type default)
			)
			(layer "B.SilkS")
		)
		(fp_line
			(start -2.050796 -0.700024)
			(end -2.050796 0.700024)
			(stroke
				(width 0.1524)
				(type default)
			)
			(layer "B.SilkS")
		)
		(fp_line
			(start 2.050796 -0.700024)
			(end -2.050796 -0.700024)
			(stroke
				(width 0.1524)
				(type default)
			)
			(layer "B.SilkS")
		)
		(fp_line
			(start -0.899922 0.700024)
			(end 0.899922 0.700024)
			(stroke
				(width 0.1)
				(type default)
			)
			(layer "B.Fab")
		)
		(fp_line
			(start 0.899922 0.700024)
			(end 0.899922 -0.700024)
			(stroke
				(width 0.1)
				(type default)
			)
			(layer "B.Fab")
		)
		(fp_line
			(start -0.899922 -0.700024)
			(end -0.899922 0.700024)
			(stroke
				(width 0.1)
				(type default)
			)
			(layer "B.Fab")
		)
		(fp_line
			(start 0.899922 -0.700024)
			(end -0.899922 -0.700024)
			(stroke
				(width 0.1)
				(type default)
			)
			(layer "B.Fab")
		)
		(fp_text user "+"
			(at 3.123946 0.762 180)
			(unlocked yes)
			(layer "B.SilkS")
			(effects
				(font
					(size 1.905 1.4224)
					(thickness 0.1524)
				)
				(justify left mirror)
			)
		)
		(fp_text user "-"
			(at -1.345438 -1.784604 90)
			(unlocked yes)
			(layer "B.SilkS")
			(effects
				(font
					(size 1.905 1.4224)
					(thickness 0.1524)
				)
				(justify left mirror)
			)
		)
		(fp_text user "+"
			(at 3.123946 0.762 180)
			(unlocked yes)
			(layer "B.Fab")
			(effects
				(font
					(size 1.905 1.4224)
					(thickness 0.1524)
				)
				(justify left mirror)
			)
		)
		(fp_text user "-"
			(at -3.880104 0.23495 90)
			(unlocked yes)
			(layer "B.Fab")
			(effects
				(font
					(size 1.905 1.4224)
					(thickness 0.1524)
				)
				(justify left mirror)
			)
		)
		(pad "1" smd rect
			(at 1.199896 0 180)
			(size 0.6604 1.3716)
			(layers "B.Cu" "B.Mask" "B.Paste")
			(net "PWRGD_FAIL_CPU0_CD_R1")
		)
		(pad "2" smd rect
			(at -1.199896 0)
			(size 0.6604 1.3716)
			(layers "B.Cu" "B.Mask" "B.Paste")
			(net "P3V3_AUX")
		)
	)
	(footprint ""
		(layer "B.Cu")
		(at 315.53404 -193.53911 -90)
		(property "Reference" "R94"
			(at 0 0 90)
			(layer "B.SilkS")
			(hide yes)
			(effects
				(font
					(size 1.27 1.27)
				)
				(justify mirror)
			)
		)
		(property "Value" ""
			(at 0 0 90)
			(layer "B.Fab")
			(effects
				(font
					(size 1.27 1.27)
				)
				(justify mirror)
			)
		)
		(duplicate_pad_numbers_are_jumpers no)
		(fp_line
			(start -0.7874 0.4064)
			(end 0.7874 0.4064)
			(stroke
				(width 0.1524)
				(type default)
			)
			(layer "B.SilkS")
		)
		(fp_line
			(start 0.7874 0.4064)
			(end 0.7874 -0.4064)
			(stroke
				(width 0.1524)
				(type default)
			)
			(layer "B.SilkS")
		)
		(fp_line
			(start -0.7874 -0.4064)
			(end -0.7874 0.4064)
			(stroke
				(width 0.1524)
				(type default)
			)
			(layer "B.SilkS")
		)
		(fp_line
			(start 0.7874 -0.4064)
			(end -0.7874 -0.4064)
			(stroke
				(width 0.1524)
				(type default)
			)
			(layer "B.SilkS")
		)
		(fp_line
			(start -0.67945 0.3048)
			(end -0.120396 0.3048)
			(stroke
				(width 0.1)
				(type default)
			)
			(layer "B.Fab")
		)
		(fp_line
			(start -0.120396 0.3048)
			(end -0.120396 0.2794)
			(stroke
				(width 0.1)
				(type default)
			)
			(layer "B.Fab")
		)
		(fp_line
			(start 0.12065 0.3048)
			(end 0.67945 0.3048)
			(stroke
				(width 0.1)
				(type default)
			)
			(layer "B.Fab")
		)
		(fp_line
			(start 0.67945 0.3048)
			(end 0.67945 -0.305054)
			(stroke
				(width 0.1)
				(type default)
			)
			(layer "B.Fab")
		)
		(fp_line
			(start -0.120396 0.2794)
			(end 0.12065 0.2794)
			(stroke
				(width 0.1)
				(type default)
			)
			(layer "B.Fab")
		)
		(fp_line
			(start 0.12065 0.2794)
			(end 0.12065 0.3048)
			(stroke
				(width 0.1)
				(type default)
			)
			(layer "B.Fab")
		)
		(fp_line
			(start -0.12065 -0.2794)
			(end -0.12065 -0.3048)
			(stroke
				(width 0.1)
				(type default)
			)
			(layer "B.Fab")
		)
		(fp_line
			(start 0.12065 -0.2794)
			(end -0.12065 -0.2794)
			(stroke
				(width 0.1)
				(type default)
			)
			(layer "B.Fab")
		)
		(fp_line
			(start -0.67945 -0.3048)
			(end -0.67945 0.3048)
			(stroke
				(width 0.1)
				(type default)
			)
			(layer "B.Fab")
		)
		(fp_line
			(start -0.12065 -0.3048)
			(end -0.67945 -0.3048)
			(stroke
				(width 0.1)
				(type default)
			)
			(layer "B.Fab")
		)
		(fp_line
			(start 0.12065 -0.305054)
			(end 0.12065 -0.2794)
			(stroke
				(width 0.1)
				(type default)
			)
			(layer "B.Fab")
		)
		(fp_line
			(start 0.67945 -0.305054)
			(end 0.12065 -0.305054)
			(stroke
				(width 0.1)
				(type default)
			)
			(layer "B.Fab")
		)
		(pad "1" smd circle
			(at 0.40005 0 90)
			(size 0 0)
			(layers "B.Cu" "B.Mask" "B.Paste")
			(net "PVNN_TERM_CPU0")
		)
		(pad "2" smd circle
			(at -0.40005 0 90)
			(size 0 0)
			(layers "B.Cu" "B.Mask" "B.Paste")
			(net "PU_CPU0_UPI0_AC_COUPLING")
		)
	)
	(footprint ""
		(layer "B.Cu")
		(at 330.577698 -190.82893 -90)
		(property "Reference" "R184"
			(at 0 0 90)
			(layer "B.SilkS")
			(hide yes)
			(effects
				(font
					(size 1.27 1.27)
				)
				(justify mirror)
			)
		)
		(property "Value" ""
			(at 0 0 90)
			(layer "B.Fab")
			(effects
				(font
					(size 1.27 1.27)
				)
				(justify mirror)
			)
		)
		(duplicate_pad_numbers_are_jumpers no)
		(fp_line
			(start -0.7874 0.4064)
			(end 0.7874 0.4064)
			(stroke
				(width 0.1524)
				(type default)
			)
			(layer "B.SilkS")
		)
		(fp_line
			(start 0.7874 0.4064)
			(end 0.7874 -0.4064)
			(stroke
				(width 0.1524)
				(type default)
			)
			(layer "B.SilkS")
		)
		(fp_line
			(start -0.7874 -0.4064)
			(end -0.7874 0.4064)
			(stroke
				(width 0.1524)
				(type default)
			)
			(layer "B.SilkS")
		)
		(fp_line
			(start 0.7874 -0.4064)
			(end -0.7874 -0.4064)
			(stroke
				(width 0.1524)
				(type default)
			)
			(layer "B.SilkS")
		)
		(fp_line
			(start -0.67945 0.3048)
			(end -0.120396 0.3048)
			(stroke
				(width 0.1)
				(type default)
			)
			(layer "B.Fab")
		)
		(fp_line
			(start -0.120396 0.3048)
			(end -0.120396 0.2794)
			(stroke
				(width 0.1)
				(type default)
			)
			(layer "B.Fab")
		)
		(fp_line
			(start 0.12065 0.3048)
			(end 0.67945 0.3048)
			(stroke
				(width 0.1)
				(type default)
			)
			(layer "B.Fab")
		)
		(fp_line
			(start 0.67945 0.3048)
			(end 0.67945 -0.305054)
			(stroke
				(width 0.1)
				(type default)
			)
			(layer "B.Fab")
		)
		(fp_line
			(start -0.120396 0.2794)
			(end 0.12065 0.2794)
			(stroke
				(width 0.1)
				(type default)
			)
			(layer "B.Fab")
		)
		(fp_line
			(start 0.12065 0.2794)
			(end 0.12065 0.3048)
			(stroke
				(width 0.1)
				(type default)
			)
			(layer "B.Fab")
		)
		(fp_line
			(start -0.12065 -0.2794)
			(end -0.12065 -0.3048)
			(stroke
				(width 0.1)
				(type default)
			)
			(layer "B.Fab")
		)
		(fp_line
			(start 0.12065 -0.2794)
			(end -0.12065 -0.2794)
			(stroke
				(width 0.1)
				(type default)
			)
			(layer "B.Fab")
		)
		(fp_line
			(start -0.67945 -0.3048)
			(end -0.67945 0.3048)
			(stroke
				(width 0.1)
				(type default)
			)
			(layer "B.Fab")
		)
		(fp_line
			(start -0.12065 -0.3048)
			(end -0.67945 -0.3048)
			(stroke
				(width 0.1)
				(type default)
			)
			(layer "B.Fab")
		)
		(fp_line
			(start 0.12065 -0.305054)
			(end 0.12065 -0.2794)
			(stroke
				(width 0.1)
				(type default)
			)
			(layer "B.Fab")
		)
		(fp_line
			(start 0.67945 -0.305054)
			(end 0.12065 -0.305054)
			(stroke
				(width 0.1)
				(type default)
			)
			(layer "B.Fab")
		)
		(pad "1" smd circle
			(at 0.40005 0 90)
			(size 0 0)
			(layers "B.Cu" "B.Mask" "B.Paste")
			(net "PWRGD_CPU0_BUF_R")
		)
		(pad "2" smd circle
			(at -0.40005 0 90)
			(size 0 0)
			(layers "B.Cu" "B.Mask" "B.Paste")
			(net "PWRGD_CPU0_LVC1")
		)
	)
	(footprint ""
		(layer "B.Cu")
		(at 315.110622 -52.187348)
		(property "Reference" "R4107"
			(at 0 0 0)
			(layer "B.SilkS")
			(hide yes)
			(effects
				(font
					(size 1.27 1.27)
				)
				(justify mirror)
			)
		)
		(property "Value" ""
			(at 0 0 0)
			(layer "B.Fab")
			(effects
				(font
					(size 1.27 1.27)
				)
				(justify mirror)
			)
		)
		(duplicate_pad_numbers_are_jumpers no)
		(fp_line
			(start -0.7874 -0.4064)
			(end -0.7874 0.4064)
			(stroke
				(width 0.1524)
				(type default)
			)
			(layer "B.SilkS")
		)
		(fp_line
			(start -0.7874 0.4064)
			(end 0.7874 0.4064)
			(stroke
				(width 0.1524)
				(type default)
			)
			(layer "B.SilkS")
		)
		(fp_line
			(start 0.7874 -0.4064)
			(end -0.7874 -0.4064)
			(stroke
				(width 0.1524)
				(type default)
			)
			(layer "B.SilkS")
		)
		(fp_line
			(start 0.7874 0.4064)
			(end 0.7874 -0.4064)
			(stroke
				(width 0.1524)
				(type default)
			)
			(layer "B.SilkS")
		)
		(fp_line
			(start -0.67945 -0.3048)
			(end -0.67945 0.3048)
			(stroke
				(width 0.1)
				(type default)
			)
			(layer "B.Fab")
		)
		(fp_line
			(start -0.67945 0.3048)
			(end -0.120396 0.3048)
			(stroke
				(width 0.1)
				(type default)
			)
			(layer "B.Fab")
		)
		(fp_line
			(start -0.12065 -0.3048)
			(end -0.67945 -0.3048)
			(stroke
				(width 0.1)
				(type default)
			)
			(layer "B.Fab")
		)
		(fp_line
			(start -0.12065 -0.2794)
			(end -0.12065 -0.3048)
			(stroke
				(width 0.1)
				(type default)
			)
			(layer "B.Fab")
		)
		(fp_line
			(start -0.120396 0.2794)
			(end 0.12065 0.2794)
			(stroke
				(width 0.1)
				(type default)
			)
			(layer "B.Fab")
		)
		(fp_line
			(start -0.120396 0.3048)
			(end -0.120396 0.2794)
			(stroke
				(width 0.1)
				(type default)
			)
			(layer "B.Fab")
		)
		(fp_line
			(start 0.12065 -0.305054)
			(end 0.12065 -0.2794)
			(stroke
				(width 0.1)
				(type default)
			)
			(layer "B.Fab")
		)
		(fp_line
			(start 0.12065 -0.2794)
			(end -0.12065 -0.2794)
			(stroke
				(width 0.1)
				(type default)
			)
			(layer "B.Fab")
		)
		(fp_line
			(start 0.12065 0.2794)
			(end 0.12065 0.3048)
			(stroke
				(width 0.1)
				(type default)
			)
			(layer "B.Fab")
		)
		(fp_line
			(start 0.12065 0.3048)
			(end 0.67945 0.3048)
			(stroke
				(width 0.1)
				(type default)
			)
			(layer "B.Fab")
		)
		(fp_line
			(start 0.67945 -0.305054)
			(end 0.12065 -0.305054)
			(stroke
				(width 0.1)
				(type default)
			)
			(layer "B.Fab")
		)
		(fp_line
			(start 0.67945 0.3048)
			(end 0.67945 -0.305054)
			(stroke
				(width 0.1)
				(type default)
			)
			(layer "B.Fab")
		)
		(pad "1" smd circle
			(at 0.40005 0 180)
			(size 0 0)
			(layers "B.Cu" "B.Mask" "B.Paste")
			(net "PD_GPP_I_17")
		)
		(pad "2" smd circle
			(at -0.40005 0 180)
			(size 0 0)
			(layers "B.Cu" "B.Mask" "B.Paste")
			(net "GND")
		)
	)
	(footprint ""
		(layer "B.Cu")
		(at 347.398594 -54.484016 90)
		(property "Reference" "C1255"
			(at 0 0 90)
			(layer "B.SilkS")
			(hide yes)
			(effects
				(font
					(size 1.27 1.27)
				)
				(justify mirror)
			)
		)
		(property "Value" ""
			(at 0 0 90)
			(layer "B.Fab")
			(effects
				(font
					(size 1.27 1.27)
				)
				(justify mirror)
			)
		)
		(duplicate_pad_numbers_are_jumpers no)
		(fp_line
			(start 1.2954 -0.5842)
			(end -1.2954 -0.5842)
			(stroke
				(width 0.1524)
				(type default)
			)
			(layer "B.SilkS")
		)
		(fp_line
			(start 0 -0.5842)
			(end 0 0.5842)
			(stroke
				(width 0.1524)
				(type default)
			)
			(layer "B.SilkS")
		)
		(fp_line
			(start -1.2954 -0.5842)
			(end -1.2954 0.5842)
			(stroke
				(width 0.1524)
				(type default)
			)
			(layer "B.SilkS")
		)
		(fp_line
			(start 1.2954 0.5842)
			(end 1.2954 -0.5842)
			(stroke
				(width 0.1524)
				(type default)
			)
			(layer "B.SilkS")
		)
		(fp_line
			(start -1.2954 0.5842)
			(end 1.2954 0.5842)
			(stroke
				(width 0.1524)
				(type default)
			)
			(layer "B.SilkS")
		)
		(fp_line
			(start 0.8636 -0.4572)
			(end -0.8636 -0.4572)
			(stroke
				(width 0.1)
				(type default)
			)
			(layer "B.Fab")
		)
		(fp_line
			(start -0.8636 -0.4572)
			(end -0.8636 -0.4064)
			(stroke
				(width 0.1)
				(type default)
			)
			(layer "B.Fab")
		)
		(fp_line
			(start 1.1938 -0.4064)
			(end 0.8636 -0.4064)
			(stroke
				(width 0.1)
				(type default)
			)
			(layer "B.Fab")
		)
		(fp_line
			(start 0.8636 -0.4064)
			(end 0.8636 -0.4572)
			(stroke
				(width 0.1)
				(type default)
			)
			(layer "B.Fab")
		)
		(fp_line
			(start -0.8636 -0.4064)
			(end -1.1938 -0.4064)
			(stroke
				(width 0.1)
				(type default)
			)
			(layer "B.Fab")
		)
		(fp_line
			(start -1.1938 -0.4064)
			(end -1.1938 0.4064)
			(stroke
				(width 0.1)
				(type default)
			)
			(layer "B.Fab")
		)
		(fp_line
			(start 1.1938 0.4064)
			(end 1.1938 -0.4064)
			(stroke
				(width 0.1)
				(type default)
			)
			(layer "B.Fab")
		)
		(fp_line
			(start 0.8636 0.4064)
			(end 1.1938 0.4064)
			(stroke
				(width 0.1)
				(type default)
			)
			(layer "B.Fab")
		)
		(fp_line
			(start -0.8636 0.4064)
			(end -0.8636 0.4572)
			(stroke
				(width 0.1)
				(type default)
			)
			(layer "B.Fab")
		)
		(fp_line
			(start -1.1938 0.4064)
			(end -0.8636 0.4064)
			(stroke
				(width 0.1)
				(type default)
			)
			(layer "B.Fab")
		)
		(fp_line
			(start 0.8636 0.4572)
			(end 0.8636 0.4064)
			(stroke
				(width 0.1)
				(type default)
			)
			(layer "B.Fab")
		)
		(fp_line
			(start -0.8636 0.4572)
			(end 0.8636 0.4572)
			(stroke
				(width 0.1)
				(type default)
			)
			(layer "B.Fab")
		)
		(pad "1" smd rect
			(at 0.7366 0)
			(size 0.7112 0.8128)
			(layers "B.Cu" "B.Mask" "B.Paste")
			(net "P1V8_PCH_PLL_AUX")
		)
		(pad "2" smd rect
			(at -0.7366 0)
			(size 0.7112 0.8128)
			(layers "B.Cu" "B.Mask" "B.Paste")
			(net "GND")
		)
	)
	(footprint ""
		(layer "B.Cu")
		(at 241.786156 -97.551748 -90)
		(property "Reference" "R442"
			(at 0 0 90)
			(layer "B.SilkS")
			(hide yes)
			(effects
				(font
					(size 1.27 1.27)
				)
				(justify mirror)
			)
		)
		(property "Value" ""
			(at 0 0 90)
			(layer "B.Fab")
			(effects
				(font
					(size 1.27 1.27)
				)
				(justify mirror)
			)
		)
		(duplicate_pad_numbers_are_jumpers no)
		(fp_line
			(start -1.2954 0.5842)
			(end 1.2954 0.5842)
			(stroke
				(width 0.1524)
				(type default)
			)
			(layer "B.SilkS")
		)
		(fp_line
			(start 1.2954 0.5842)
			(end 1.2954 -0.5842)
			(stroke
				(width 0.1524)
				(type default)
			)
			(layer "B.SilkS")
		)
		(fp_line
			(start -1.2954 -0.5842)
			(end -1.2954 0.5842)
			(stroke
				(width 0.1524)
				(type default)
			)
			(layer "B.SilkS")
		)
		(fp_line
			(start 1.2954 -0.5842)
			(end -1.2954 -0.5842)
			(stroke
				(width 0.1524)
				(type default)
			)
			(layer "B.SilkS")
		)
		(fp_line
			(start -0.8636 0.4572)
			(end 0.8636 0.4572)
			(stroke
				(width 0.1)
				(type default)
			)
			(layer "B.Fab")
		)
		(fp_line
			(start 0.8636 0.4572)
			(end 0.8636 0.4318)
			(stroke
				(width 0.1)
				(type default)
			)
			(layer "B.Fab")
		)
		(fp_line
			(start 0.8636 0.4318)
			(end 0.8636 0.4064)
			(stroke
				(width 0.1)
				(type default)
			)
			(layer "B.Fab")
		)
		(fp_line
			(start -1.1938 0.4064)
			(end -0.8636 0.4064)
			(stroke
				(width 0.1)
				(type default)
			)
			(layer "B.Fab")
		)
		(fp_line
			(start -0.8636 0.4064)
			(end -0.8636 0.4572)
			(stroke
				(width 0.1)
				(type default)
			)
			(layer "B.Fab")
		)
		(fp_line
			(start 0.8636 0.4064)
			(end 1.1938 0.4064)
			(stroke
				(width 0.1)
				(type default)
			)
			(layer "B.Fab")
		)
		(fp_line
			(start 1.1938 0.4064)
			(end 1.1938 -0.406654)
			(stroke
				(width 0.1)
				(type default)
			)
			(layer "B.Fab")
		)
		(fp_line
			(start -1.1938 -0.406654)
			(end -1.1938 0.4064)
			(stroke
				(width 0.1)
				(type default)
			)
			(layer "B.Fab")
		)
		(fp_line
			(start -0.8636 -0.406654)
			(end -1.1938 -0.406654)
			(stroke
				(width 0.1)
				(type default)
			)
			(layer "B.Fab")
		)
		(fp_line
			(start 0.8636 -0.406654)
			(end 0.8636 -0.4572)
			(stroke
				(width 0.1)
				(type default)
			)
			(layer "B.Fab")
		)
		(fp_line
			(start 1.1938 -0.406654)
			(end 0.8636 -0.406654)
			(stroke
				(width 0.1)
				(type default)
			)
			(layer "B.Fab")
		)
		(fp_line
			(start -0.8636 -0.4572)
			(end -0.8636 -0.406654)
			(stroke
				(width 0.1)
				(type default)
			)
			(layer "B.Fab")
		)
		(fp_line
			(start 0.8636 -0.4572)
			(end -0.8636 -0.4572)
			(stroke
				(width 0.1)
				(type default)
			)
			(layer "B.Fab")
		)
		(pad "1" smd rect
			(at 0.7366 0 180)
			(size 0.7112 0.8128)
			(layers "B.Cu" "B.Mask" "B.Paste")
			(net "P3V3_AUX_CLK_GEN_VDDXTAL_CK440")
		)
		(pad "2" smd rect
			(at -0.7366 0 180)
			(size 0.7112 0.8128)
			(layers "B.Cu" "B.Mask" "B.Paste")
			(net "P3V3_AUX_CLK_GEN_VDDA25M_CK440")
		)
	)
	(footprint ""
		(layer "B.Cu")
		(at 77.368908 -185.926476 -90)
		(property "Reference" "R90"
			(at 0 0 90)
			(layer "B.SilkS")
			(hide yes)
			(effects
				(font
					(size 1.27 1.27)
				)
				(justify mirror)
			)
		)
		(property "Value" ""
			(at 0 0 90)
			(layer "B.Fab")
			(effects
				(font
					(size 1.27 1.27)
				)
				(justify mirror)
			)
		)
		(duplicate_pad_numbers_are_jumpers no)
		(fp_line
			(start -0.7874 0.4064)
			(end 0.7874 0.4064)
			(stroke
				(width 0.1524)
				(type default)
			)
			(layer "B.SilkS")
		)
		(fp_line
			(start 0.7874 0.4064)
			(end 0.7874 -0.4064)
			(stroke
				(width 0.1524)
				(type default)
			)
			(layer "B.SilkS")
		)
		(fp_line
			(start -0.7874 -0.4064)
			(end -0.7874 0.4064)
			(stroke
				(width 0.1524)
				(type default)
			)
			(layer "B.SilkS")
		)
		(fp_line
			(start 0.7874 -0.4064)
			(end -0.7874 -0.4064)
			(stroke
				(width 0.1524)
				(type default)
			)
			(layer "B.SilkS")
		)
		(fp_line
			(start -0.67945 0.3048)
			(end -0.120396 0.3048)
			(stroke
				(width 0.1)
				(type default)
			)
			(layer "B.Fab")
		)
		(fp_line
			(start -0.120396 0.3048)
			(end -0.120396 0.2794)
			(stroke
				(width 0.1)
				(type default)
			)
			(layer "B.Fab")
		)
		(fp_line
			(start 0.12065 0.3048)
			(end 0.67945 0.3048)
			(stroke
				(width 0.1)
				(type default)
			)
			(layer "B.Fab")
		)
		(fp_line
			(start 0.67945 0.3048)
			(end 0.67945 -0.305054)
			(stroke
				(width 0.1)
				(type default)
			)
			(layer "B.Fab")
		)
		(fp_line
			(start -0.120396 0.2794)
			(end 0.12065 0.2794)
			(stroke
				(width 0.1)
				(type default)
			)
			(layer "B.Fab")
		)
		(fp_line
			(start 0.12065 0.2794)
			(end 0.12065 0.3048)
			(stroke
				(width 0.1)
				(type default)
			)
			(layer "B.Fab")
		)
		(fp_line
			(start -0.12065 -0.2794)
			(end -0.12065 -0.3048)
			(stroke
				(width 0.1)
				(type default)
			)
			(layer "B.Fab")
		)
		(fp_line
			(start 0.12065 -0.2794)
			(end -0.12065 -0.2794)
			(stroke
				(width 0.1)
				(type default)
			)
			(layer "B.Fab")
		)
		(fp_line
			(start -0.67945 -0.3048)
			(end -0.67945 0.3048)
			(stroke
				(width 0.1)
				(type default)
			)
			(layer "B.Fab")
		)
		(fp_line
			(start -0.12065 -0.3048)
			(end -0.67945 -0.3048)
			(stroke
				(width 0.1)
				(type default)
			)
			(layer "B.Fab")
		)
		(fp_line
			(start 0.12065 -0.305054)
			(end 0.12065 -0.2794)
			(stroke
				(width 0.1)
				(type default)
			)
			(layer "B.Fab")
		)
		(fp_line
			(start 0.67945 -0.305054)
			(end 0.12065 -0.305054)
			(stroke
				(width 0.1)
				(type default)
			)
			(layer "B.Fab")
		)
		(pad "1" smd circle
			(at 0.40005 0 90)
			(size 0 0)
			(layers "B.Cu" "B.Mask" "B.Paste")
			(net "PVNN_TERM_CPU1")
		)
		(pad "2" smd circle
			(at -0.40005 0 90)
			(size 0 0)
			(layers "B.Cu" "B.Mask" "B.Paste")
			(net "PU_CPU1_UPI0_AC_COUPLING")
		)
	)
	(footprint ""
		(layer "B.Cu")
		(at 341.00135 -37.574728 -90)
		(property "Reference" "R1554"
			(at 0 0 90)
			(layer "B.SilkS")
			(hide yes)
			(effects
				(font
					(size 1.27 1.27)
				)
				(justify mirror)
			)
		)
		(property "Value" ""
			(at 0 0 90)
			(layer "B.Fab")
			(effects
				(font
					(size 1.27 1.27)
				)
				(justify mirror)
			)
		)
		(duplicate_pad_numbers_are_jumpers no)
		(fp_line
			(start -0.7874 0.4064)
			(end 0.7874 0.4064)
			(stroke
				(width 0.1524)
				(type default)
			)
			(layer "B.SilkS")
		)
		(fp_line
			(start 0.7874 0.4064)
			(end 0.7874 -0.4064)
			(stroke
				(width 0.1524)
				(type default)
			)
			(layer "B.SilkS")
		)
		(fp_line
			(start -0.7874 -0.4064)
			(end -0.7874 0.4064)
			(stroke
				(width 0.1524)
				(type default)
			)
			(layer "B.SilkS")
		)
		(fp_line
			(start 0.7874 -0.4064)
			(end -0.7874 -0.4064)
			(stroke
				(width 0.1524)
				(type default)
			)
			(layer "B.SilkS")
		)
		(fp_line
			(start -0.67945 0.3048)
			(end -0.120396 0.3048)
			(stroke
				(width 0.1)
				(type default)
			)
			(layer "B.Fab")
		)
		(fp_line
			(start -0.120396 0.3048)
			(end -0.120396 0.2794)
			(stroke
				(width 0.1)
				(type default)
			)
			(layer "B.Fab")
		)
		(fp_line
			(start 0.12065 0.3048)
			(end 0.67945 0.3048)
			(stroke
				(width 0.1)
				(type default)
			)
			(layer "B.Fab")
		)
		(fp_line
			(start 0.67945 0.3048)
			(end 0.67945 -0.305054)
			(stroke
				(width 0.1)
				(type default)
			)
			(layer "B.Fab")
		)
		(fp_line
			(start -0.120396 0.2794)
			(end 0.12065 0.2794)
			(stroke
				(width 0.1)
				(type default)
			)
			(layer "B.Fab")
		)
		(fp_line
			(start 0.12065 0.2794)
			(end 0.12065 0.3048)
			(stroke
				(width 0.1)
				(type default)
			)
			(layer "B.Fab")
		)
		(fp_line
			(start -0.12065 -0.2794)
			(end -0.12065 -0.3048)
			(stroke
				(width 0.1)
				(type default)
			)
			(layer "B.Fab")
		)
		(fp_line
			(start 0.12065 -0.2794)
			(end -0.12065 -0.2794)
			(stroke
				(width 0.1)
				(type default)
			)
			(layer "B.Fab")
		)
		(fp_line
			(start -0.67945 -0.3048)
			(end -0.67945 0.3048)
			(stroke
				(width 0.1)
				(type default)
			)
			(layer "B.Fab")
		)
		(fp_line
			(start -0.12065 -0.3048)
			(end -0.67945 -0.3048)
			(stroke
				(width 0.1)
				(type default)
			)
			(layer "B.Fab")
		)
		(fp_line
			(start 0.12065 -0.305054)
			(end 0.12065 -0.2794)
			(stroke
				(width 0.1)
				(type default)
			)
			(layer "B.Fab")
		)
		(fp_line
			(start 0.67945 -0.305054)
			(end 0.12065 -0.305054)
			(stroke
				(width 0.1)
				(type default)
			)
			(layer "B.Fab")
		)
		(pad "1" smd circle
			(at 0.40005 0 90)
			(size 0 0)
			(layers "B.Cu" "B.Mask" "B.Paste")
			(net "P3V3_AUX")
		)
		(pad "2" smd circle
			(at -0.40005 0 90)
			(size 0 0)
			(layers "B.Cu" "B.Mask" "B.Paste")
			(net "FM_ME_AUTHN_FAIL")
		)
	)
	(footprint ""
		(layer "B.Cu")
		(at 27.304746 -319.268856 180)
		(property "Reference" "R897"
			(at 0 0 0)
			(layer "B.SilkS")
			(hide yes)
			(effects
				(font
					(size 1.27 1.27)
				)
				(justify mirror)
			)
		)
		(property "Value" ""
			(at 0 0 0)
			(layer "B.Fab")
			(effects
				(font
					(size 1.27 1.27)
				)
				(justify mirror)
			)
		)
		(duplicate_pad_numbers_are_jumpers no)
		(fp_line
			(start 0.7874 0.4064)
			(end 0.7874 -0.4064)
			(stroke
				(width 0.1524)
				(type default)
			)
			(layer "B.SilkS")
		)
		(fp_line
			(start 0.7874 -0.4064)
			(end -0.7874 -0.4064)
			(stroke
				(width 0.1524)
				(type default)
			)
			(layer "B.SilkS")
		)
		(fp_line
			(start -0.7874 0.4064)
			(end 0.7874 0.4064)
			(stroke
				(width 0.1524)
				(type default)
			)
			(layer "B.SilkS")
		)
		(fp_line
			(start -0.7874 -0.4064)
			(end -0.7874 0.4064)
			(stroke
				(width 0.1524)
				(type default)
			)
			(layer "B.SilkS")
		)
		(fp_line
			(start 0.67945 0.3048)
			(end 0.67945 -0.305054)
			(stroke
				(width 0.1)
				(type default)
			)
			(layer "B.Fab")
		)
		(fp_line
			(start 0.67945 -0.305054)
			(end 0.12065 -0.305054)
			(stroke
				(width 0.1)
				(type default)
			)
			(layer "B.Fab")
		)
		(fp_line
			(start 0.12065 0.3048)
			(end 0.67945 0.3048)
			(stroke
				(width 0.1)
				(type default)
			)
			(layer "B.Fab")
		)
		(fp_line
			(start 0.12065 0.2794)
			(end 0.12065 0.3048)
			(stroke
				(width 0.1)
				(type default)
			)
			(layer "B.Fab")
		)
		(fp_line
			(start 0.12065 -0.2794)
			(end -0.12065 -0.2794)
			(stroke
				(width 0.1)
				(type default)
			)
			(layer "B.Fab")
		)
		(fp_line
			(start 0.12065 -0.305054)
			(end 0.12065 -0.2794)
			(stroke
				(width 0.1)
				(type default)
			)
			(layer "B.Fab")
		)
		(fp_line
			(start -0.120396 0.3048)
			(end -0.120396 0.2794)
			(stroke
				(width 0.1)
				(type default)
			)
			(layer "B.Fab")
		)
		(fp_line
			(start -0.120396 0.2794)
			(end 0.12065 0.2794)
			(stroke
				(width 0.1)
				(type default)
			)
			(layer "B.Fab")
		)
		(fp_line
			(start -0.12065 -0.2794)
			(end -0.12065 -0.3048)
			(stroke
				(width 0.1)
				(type default)
			)
			(layer "B.Fab")
		)
		(fp_line
			(start -0.12065 -0.3048)
			(end -0.67945 -0.3048)
			(stroke
				(width 0.1)
				(type default)
			)
			(layer "B.Fab")
		)
		(fp_line
			(start -0.67945 0.3048)
			(end -0.120396 0.3048)
			(stroke
				(width 0.1)
				(type default)
			)
			(layer "B.Fab")
		)
		(fp_line
			(start -0.67945 -0.3048)
			(end -0.67945 0.3048)
			(stroke
				(width 0.1)
				(type default)
			)
			(layer "B.Fab")
		)
		(pad "1" smd circle
			(at 0.40005 0)
			(size 0 0)
			(layers "B.Cu" "B.Mask" "B.Paste")
			(net "PWRGD_CHC_CPU1_DIMM1")
		)
		(pad "2" smd circle
			(at -0.40005 0)
			(size 0 0)
			(layers "B.Cu" "B.Mask" "B.Paste")
			(net "PWRGD_FAIL_CPU1_CD")
		)
	)
	(footprint ""
		(layer "B.Cu")
		(at 126.67742 -31.526988 90)
		(property "Reference" "R4289"
			(at 0 0 90)
			(layer "B.SilkS")
			(hide yes)
			(effects
				(font
					(size 1.27 1.27)
				)
				(justify mirror)
			)
		)
		(property "Value" ""
			(at 0 0 90)
			(layer "B.Fab")
			(effects
				(font
					(size 1.27 1.27)
				)
				(justify mirror)
			)
		)
		(duplicate_pad_numbers_are_jumpers no)
		(fp_line
			(start 0.7874 -0.4064)
			(end -0.7874 -0.4064)
			(stroke
				(width 0.1524)
				(type default)
			)
			(layer "B.SilkS")
		)
		(fp_line
			(start -0.7874 -0.4064)
			(end -0.7874 0.4064)
			(stroke
				(width 0.1524)
				(type default)
			)
			(layer "B.SilkS")
		)
		(fp_line
			(start 0.7874 0.4064)
			(end 0.7874 -0.4064)
			(stroke
				(width 0.1524)
				(type default)
			)
			(layer "B.SilkS")
		)
		(fp_line
			(start -0.7874 0.4064)
			(end 0.7874 0.4064)
			(stroke
				(width 0.1524)
				(type default)
			)
			(layer "B.SilkS")
		)
		(fp_line
			(start 0.67945 -0.305054)
			(end 0.12065 -0.305054)
			(stroke
				(width 0.1)
				(type default)
			)
			(layer "B.Fab")
		)
		(fp_line
			(start 0.12065 -0.305054)
			(end 0.12065 -0.2794)
			(stroke
				(width 0.1)
				(type default)
			)
			(layer "B.Fab")
		)
		(fp_line
			(start -0.12065 -0.3048)
			(end -0.67945 -0.3048)
			(stroke
				(width 0.1)
				(type default)
			)
			(layer "B.Fab")
		)
		(fp_line
			(start -0.67945 -0.3048)
			(end -0.67945 0.3048)
			(stroke
				(width 0.1)
				(type default)
			)
			(layer "B.Fab")
		)
		(fp_line
			(start 0.12065 -0.2794)
			(end -0.12065 -0.2794)
			(stroke
				(width 0.1)
				(type default)
			)
			(layer "B.Fab")
		)
		(fp_line
			(start -0.12065 -0.2794)
			(end -0.12065 -0.3048)
			(stroke
				(width 0.1)
				(type default)
			)
			(layer "B.Fab")
		)
		(fp_line
			(start 0.12065 0.2794)
			(end 0.12065 0.3048)
			(stroke
				(width 0.1)
				(type default)
			)
			(layer "B.Fab")
		)
		(fp_line
			(start -0.120396 0.2794)
			(end 0.12065 0.2794)
			(stroke
				(width 0.1)
				(type default)
			)
			(layer "B.Fab")
		)
		(fp_line
			(start 0.67945 0.3048)
			(end 0.67945 -0.305054)
			(stroke
				(width 0.1)
				(type default)
			)
			(layer "B.Fab")
		)
		(fp_line
			(start 0.12065 0.3048)
			(end 0.67945 0.3048)
			(stroke
				(width 0.1)
				(type default)
			)
			(layer "B.Fab")
		)
		(fp_line
			(start -0.120396 0.3048)
			(end -0.120396 0.2794)
			(stroke
				(width 0.1)
				(type default)
			)
			(layer "B.Fab")
		)
		(fp_line
			(start -0.67945 0.3048)
			(end -0.120396 0.3048)
			(stroke
				(width 0.1)
				(type default)
			)
			(layer "B.Fab")
		)
		(pad "1" smd circle
			(at 0.40005 0 270)
			(size 0 0)
			(layers "B.Cu" "B.Mask" "B.Paste")
			(net "P3V3_AUX")
		)
		(pad "2" smd circle
			(at -0.40005 0 270)
			(size 0 0)
			(layers "B.Cu" "B.Mask" "B.Paste")
			(net "FM_USB3_1_RXDET_EN")
		)
	)
	(footprint ""
		(layer "B.Cu")
		(at 176.955704 -113.77549)
		(property "Reference" "C1150"
			(at 0 0 0)
			(layer "B.SilkS")
			(hide yes)
			(effects
				(font
					(size 1.27 1.27)
				)
				(justify mirror)
			)
		)
		(property "Value" ""
			(at 0 0 0)
			(layer "B.Fab")
			(effects
				(font
					(size 1.27 1.27)
				)
				(justify mirror)
			)
		)
		(duplicate_pad_numbers_are_jumpers no)
		(fp_line
			(start -0.69215 -0.2921)
			(end -0.69215 0.2921)
			(stroke
				(width 0.1524)
				(type default)
			)
			(layer "B.SilkS")
		)
		(fp_line
			(start -0.69215 0.2921)
			(end 0.69215 0.2921)
			(stroke
				(width 0.1524)
				(type default)
			)
			(layer "B.SilkS")
		)
		(fp_line
			(start 0.69215 -0.2921)
			(end -0.69215 -0.2921)
			(stroke
				(width 0.1524)
				(type default)
			)
			(layer "B.SilkS")
		)
		(fp_line
			(start 0.69215 0.2921)
			(end 0.69215 -0.2921)
			(stroke
				(width 0.1524)
				(type default)
			)
			(layer "B.SilkS")
		)
		(fp_line
			(start -0.51435 -0.2794)
			(end -0.51435 0.2794)
			(stroke
				(width 0.1)
				(type default)
			)
			(layer "B.Fab")
		)
		(fp_line
			(start -0.51435 0.2794)
			(end 0.51435 0.2794)
			(stroke
				(width 0.1)
				(type default)
			)
			(layer "B.Fab")
		)
		(fp_line
			(start 0.51435 -0.2794)
			(end -0.51435 -0.2794)
			(stroke
				(width 0.1)
				(type default)
			)
			(layer "B.Fab")
		)
		(fp_line
			(start 0.51435 0.2794)
			(end 0.51435 -0.2794)
			(stroke
				(width 0.1)
				(type default)
			)
			(layer "B.Fab")
		)
		(pad "1" smd circle
			(at 0.40005 0 180)
			(size 0 0)
			(layers "B.Cu" "B.Mask" "B.Paste")
			(net "VCC_PLD_CORE")
		)
		(pad "2" smd circle
			(at -0.40005 0 180)
			(size 0 0)
			(layers "B.Cu" "B.Mask" "B.Paste")
			(net "GND")
		)
		(zone
			(layer "B.Cu")
			(hatch none 0.5)
			(connect_pads
				(clearance 0)
			)
			(min_thickness 0.25)
			(keepout
				(tracks not_allowed)
				(vias allowed)
				(pads allowed)
				(copperpour not_allowed)
				(footprints allowed)
			)
			(placement
				(enabled no)
				(sheetname "")
			)
			(fill
				(thermal_gap 0.5)
				(thermal_bridge_width 0.5)
				(island_removal_mode 0)
			)
			(polygon
				(pts
					(xy 177.146204 -113.68786) (xy 177.054764 -113.629694) (xy 176.855374 -113.629694) (xy 176.765204 -113.68786)
					(xy 176.765204 -113.86312) (xy 176.855374 -113.92154) (xy 177.054764 -113.92154) (xy 177.146204 -113.863374)
				)
			)
		)
	)
	(footprint ""
		(layer "B.Cu")
		(at 151.059388 -188.20257)
		(property "Reference" "R288"
			(at 0 0 0)
			(layer "B.SilkS")
			(hide yes)
			(effects
				(font
					(size 1.27 1.27)
				)
				(justify mirror)
			)
		)
		(property "Value" ""
			(at 0 0 0)
			(layer "B.Fab")
			(effects
				(font
					(size 1.27 1.27)
				)
				(justify mirror)
			)
		)
		(duplicate_pad_numbers_are_jumpers no)
		(fp_line
			(start -0.7874 -0.4064)
			(end -0.7874 0.4064)
			(stroke
				(width 0.1524)
				(type default)
			)
			(layer "B.SilkS")
		)
		(fp_line
			(start -0.7874 0.4064)
			(end 0.7874 0.4064)
			(stroke
				(width 0.1524)
				(type default)
			)
			(layer "B.SilkS")
		)
		(fp_line
			(start 0.7874 -0.4064)
			(end -0.7874 -0.4064)
			(stroke
				(width 0.1524)
				(type default)
			)
			(layer "B.SilkS")
		)
		(fp_line
			(start 0.7874 0.4064)
			(end 0.7874 -0.4064)
			(stroke
				(width 0.1524)
				(type default)
			)
			(layer "B.SilkS")
		)
		(fp_line
			(start -0.67945 -0.3048)
			(end -0.67945 0.3048)
			(stroke
				(width 0.1)
				(type default)
			)
			(layer "B.Fab")
		)
		(fp_line
			(start -0.67945 0.3048)
			(end -0.120396 0.3048)
			(stroke
				(width 0.1)
				(type default)
			)
			(layer "B.Fab")
		)
		(fp_line
			(start -0.12065 -0.3048)
			(end -0.67945 -0.3048)
			(stroke
				(width 0.1)
				(type default)
			)
			(layer "B.Fab")
		)
		(fp_line
			(start -0.12065 -0.2794)
			(end -0.12065 -0.3048)
			(stroke
				(width 0.1)
				(type default)
			)
			(layer "B.Fab")
		)
		(fp_line
			(start -0.120396 0.2794)
			(end 0.12065 0.2794)
			(stroke
				(width 0.1)
				(type default)
			)
			(layer "B.Fab")
		)
		(fp_line
			(start -0.120396 0.3048)
			(end -0.120396 0.2794)
			(stroke
				(width 0.1)
				(type default)
			)
			(layer "B.Fab")
		)
		(fp_line
			(start 0.12065 -0.305054)
			(end 0.12065 -0.2794)
			(stroke
				(width 0.1)
				(type default)
			)
			(layer "B.Fab")
		)
		(fp_line
			(start 0.12065 -0.2794)
			(end -0.12065 -0.2794)
			(stroke
				(width 0.1)
				(type default)
			)
			(layer "B.Fab")
		)
		(fp_line
			(start 0.12065 0.2794)
			(end 0.12065 0.3048)
			(stroke
				(width 0.1)
				(type default)
			)
			(layer "B.Fab")
		)
		(fp_line
			(start 0.12065 0.3048)
			(end 0.67945 0.3048)
			(stroke
				(width 0.1)
				(type default)
			)
			(layer "B.Fab")
		)
		(fp_line
			(start 0.67945 -0.305054)
			(end 0.12065 -0.305054)
			(stroke
				(width 0.1)
				(type default)
			)
			(layer "B.Fab")
		)
		(fp_line
			(start 0.67945 0.3048)
			(end 0.67945 -0.305054)
			(stroke
				(width 0.1)
				(type default)
			)
			(layer "B.Fab")
		)
		(pad "1" smd circle
			(at 0.40005 0 180)
			(size 0 0)
			(layers "B.Cu" "B.Mask" "B.Paste")
			(net "PVNN_TERM_CPU0")
		)
		(pad "2" smd circle
			(at -0.40005 0 180)
			(size 0 0)
			(layers "B.Cu" "B.Mask" "B.Paste")
			(net "PD_CPU1_TXT_PLTEN")
		)
	)
	(footprint ""
		(layer "B.Cu")
		(at 102.495604 -294.01008 180)
		(property "Reference" "C322"
			(at 0 0 0)
			(layer "B.SilkS")
			(hide yes)
			(effects
				(font
					(size 1.27 1.27)
				)
				(justify mirror)
			)
		)
		(property "Value" ""
			(at 0 0 0)
			(layer "B.Fab")
			(effects
				(font
					(size 1.27 1.27)
				)
				(justify mirror)
			)
		)
		(duplicate_pad_numbers_are_jumpers no)
		(fp_line
			(start 1.524 0.762)
			(end 1.524 -0.762)
			(stroke
				(width 0.1524)
				(type default)
			)
			(layer "B.SilkS")
		)
		(fp_line
			(start 1.524 -0.762)
			(end -1.524 -0.762)
			(stroke
				(width 0.1524)
				(type default)
			)
			(layer "B.SilkS")
		)
		(fp_line
			(start -1.524 0.762)
			(end 1.524 0.762)
			(stroke
				(width 0.1524)
				(type default)
			)
			(layer "B.SilkS")
		)
		(fp_line
			(start -1.524 -0.762)
			(end -1.524 0.762)
			(stroke
				(width 0.1524)
				(type default)
			)
			(layer "B.SilkS")
		)
		(fp_line
			(start 1.1049 0.724916)
			(end -1.1049 0.724916)
			(stroke
				(width 0.1)
				(type default)
			)
			(layer "B.Fab")
		)
		(fp_line
			(start 1.1049 -0.724916)
			(end 1.1049 0.724916)
			(stroke
				(width 0.1)
				(type default)
			)
			(layer "B.Fab")
		)
		(fp_line
			(start -1.1049 0.724916)
			(end -1.1049 -0.724916)
			(stroke
				(width 0.1)
				(type default)
			)
			(layer "B.Fab")
		)
		(fp_line
			(start -1.1049 -0.724916)
			(end 1.1049 -0.724916)
			(stroke
				(width 0.1)
				(type default)
			)
			(layer "B.Fab")
		)
		(pad "1" smd rect
			(at 0.889 0 180)
			(size 1.016 1.27)
			(layers "B.Cu" "B.Mask" "B.Paste")
			(net "PVCCIN_CPU1")
		)
		(pad "2" smd rect
			(at -0.889 0 180)
			(size 1.016 1.27)
			(layers "B.Cu" "B.Mask" "B.Paste")
			(net "GND")
		)
	)
	(footprint ""
		(layer "B.Cu")
		(at 420.152322 -318.05499 90)
		(property "Reference" "R3886"
			(at 0 0 90)
			(layer "B.SilkS")
			(hide yes)
			(effects
				(font
					(size 1.27 1.27)
				)
				(justify mirror)
			)
		)
		(property "Value" ""
			(at 0 0 90)
			(layer "B.Fab")
			(effects
				(font
					(size 1.27 1.27)
				)
				(justify mirror)
			)
		)
		(duplicate_pad_numbers_are_jumpers no)
		(fp_line
			(start 0.7874 -0.4064)
			(end -0.7874 -0.4064)
			(stroke
				(width 0.1524)
				(type default)
			)
			(layer "B.SilkS")
		)
		(fp_line
			(start -0.7874 -0.4064)
			(end -0.7874 0.4064)
			(stroke
				(width 0.1524)
				(type default)
			)
			(layer "B.SilkS")
		)
		(fp_line
			(start 0.7874 0.4064)
			(end 0.7874 -0.4064)
			(stroke
				(width 0.1524)
				(type default)
			)
			(layer "B.SilkS")
		)
		(fp_line
			(start -0.7874 0.4064)
			(end 0.7874 0.4064)
			(stroke
				(width 0.1524)
				(type default)
			)
			(layer "B.SilkS")
		)
		(fp_line
			(start 0.67945 -0.305054)
			(end 0.12065 -0.305054)
			(stroke
				(width 0.1)
				(type default)
			)
			(layer "B.Fab")
		)
		(fp_line
			(start 0.12065 -0.305054)
			(end 0.12065 -0.2794)
			(stroke
				(width 0.1)
				(type default)
			)
			(layer "B.Fab")
		)
		(fp_line
			(start -0.12065 -0.3048)
			(end -0.67945 -0.3048)
			(stroke
				(width 0.1)
				(type default)
			)
			(layer "B.Fab")
		)
		(fp_line
			(start -0.67945 -0.3048)
			(end -0.67945 0.3048)
			(stroke
				(width 0.1)
				(type default)
			)
			(layer "B.Fab")
		)
		(fp_line
			(start 0.12065 -0.2794)
			(end -0.12065 -0.2794)
			(stroke
				(width 0.1)
				(type default)
			)
			(layer "B.Fab")
		)
		(fp_line
			(start -0.12065 -0.2794)
			(end -0.12065 -0.3048)
			(stroke
				(width 0.1)
				(type default)
			)
			(layer "B.Fab")
		)
		(fp_line
			(start 0.12065 0.2794)
			(end 0.12065 0.3048)
			(stroke
				(width 0.1)
				(type default)
			)
			(layer "B.Fab")
		)
		(fp_line
			(start -0.120396 0.2794)
			(end 0.12065 0.2794)
			(stroke
				(width 0.1)
				(type default)
			)
			(layer "B.Fab")
		)
		(fp_line
			(start 0.67945 0.3048)
			(end 0.67945 -0.305054)
			(stroke
				(width 0.1)
				(type default)
			)
			(layer "B.Fab")
		)
		(fp_line
			(start 0.12065 0.3048)
			(end 0.67945 0.3048)
			(stroke
				(width 0.1)
				(type default)
			)
			(layer "B.Fab")
		)
		(fp_line
			(start -0.120396 0.3048)
			(end -0.120396 0.2794)
			(stroke
				(width 0.1)
				(type default)
			)
			(layer "B.Fab")
		)
		(fp_line
			(start -0.67945 0.3048)
			(end -0.120396 0.3048)
			(stroke
				(width 0.1)
				(type default)
			)
			(layer "B.Fab")
		)
		(pad "1" smd circle
			(at 0.40005 0 270)
			(size 0 0)
			(layers "B.Cu" "B.Mask" "B.Paste")
			(net "I3C_SPD_DDREFGH_CPU0_LVC1_SCL_3")
		)
		(pad "2" smd circle
			(at -0.40005 0 270)
			(size 0 0)
			(layers "B.Cu" "B.Mask" "B.Paste")
			(net "I3C_SPD_DDREFGH_CPU0_LVC1_SCL")
		)
	)
	(footprint ""
		(layer "B.Cu")
		(at 211.69503 -57.078372 -90)
		(property "Reference" "R3752"
			(at 0 0 90)
			(layer "B.SilkS")
			(hide yes)
			(effects
				(font
					(size 1.27 1.27)
				)
				(justify mirror)
			)
		)
		(property "Value" ""
			(at 0 0 90)
			(layer "B.Fab")
			(effects
				(font
					(size 1.27 1.27)
				)
				(justify mirror)
			)
		)
		(duplicate_pad_numbers_are_jumpers no)
		(fp_line
			(start -0.7874 0.4064)
			(end 0.7874 0.4064)
			(stroke
				(width 0.1524)
				(type default)
			)
			(layer "B.SilkS")
		)
		(fp_line
			(start 0.7874 0.4064)
			(end 0.7874 -0.4064)
			(stroke
				(width 0.1524)
				(type default)
			)
			(layer "B.SilkS")
		)
		(fp_line
			(start -0.7874 -0.4064)
			(end -0.7874 0.4064)
			(stroke
				(width 0.1524)
				(type default)
			)
			(layer "B.SilkS")
		)
		(fp_line
			(start 0.7874 -0.4064)
			(end -0.7874 -0.4064)
			(stroke
				(width 0.1524)
				(type default)
			)
			(layer "B.SilkS")
		)
		(fp_line
			(start -0.67945 0.3048)
			(end -0.120396 0.3048)
			(stroke
				(width 0.1)
				(type default)
			)
			(layer "B.Fab")
		)
		(fp_line
			(start -0.120396 0.3048)
			(end -0.120396 0.2794)
			(stroke
				(width 0.1)
				(type default)
			)
			(layer "B.Fab")
		)
		(fp_line
			(start 0.12065 0.3048)
			(end 0.67945 0.3048)
			(stroke
				(width 0.1)
				(type default)
			)
			(layer "B.Fab")
		)
		(fp_line
			(start 0.67945 0.3048)
			(end 0.67945 -0.305054)
			(stroke
				(width 0.1)
				(type default)
			)
			(layer "B.Fab")
		)
		(fp_line
			(start -0.120396 0.2794)
			(end 0.12065 0.2794)
			(stroke
				(width 0.1)
				(type default)
			)
			(layer "B.Fab")
		)
		(fp_line
			(start 0.12065 0.2794)
			(end 0.12065 0.3048)
			(stroke
				(width 0.1)
				(type default)
			)
			(layer "B.Fab")
		)
		(fp_line
			(start -0.12065 -0.2794)
			(end -0.12065 -0.3048)
			(stroke
				(width 0.1)
				(type default)
			)
			(layer "B.Fab")
		)
		(fp_line
			(start 0.12065 -0.2794)
			(end -0.12065 -0.2794)
			(stroke
				(width 0.1)
				(type default)
			)
			(layer "B.Fab")
		)
		(fp_line
			(start -0.67945 -0.3048)
			(end -0.67945 0.3048)
			(stroke
				(width 0.1)
				(type default)
			)
			(layer "B.Fab")
		)
		(fp_line
			(start -0.12065 -0.3048)
			(end -0.67945 -0.3048)
			(stroke
				(width 0.1)
				(type default)
			)
			(layer "B.Fab")
		)
		(fp_line
			(start 0.12065 -0.305054)
			(end 0.12065 -0.2794)
			(stroke
				(width 0.1)
				(type default)
			)
			(layer "B.Fab")
		)
		(fp_line
			(start 0.67945 -0.305054)
			(end 0.12065 -0.305054)
			(stroke
				(width 0.1)
				(type default)
			)
			(layer "B.Fab")
		)
		(pad "1" smd circle
			(at 0.40005 0 90)
			(size 0 0)
			(layers "B.Cu" "B.Mask" "B.Paste")
			(net "E1S_0_P3V3_ADC_ALERT_R")
		)
		(pad "2" smd circle
			(at -0.40005 0 90)
			(size 0 0)
			(layers "B.Cu" "B.Mask" "B.Paste")
			(net "E1S_0_P3V3_ADC_ALERT")
		)
	)
	(footprint ""
		(layer "B.Cu")
		(at 331.09408 -25.212548)
		(property "Reference" "R4097"
			(at 0 0 0)
			(layer "B.SilkS")
			(hide yes)
			(effects
				(font
					(size 1.27 1.27)
				)
				(justify mirror)
			)
		)
		(property "Value" ""
			(at 0 0 0)
			(layer "B.Fab")
			(effects
				(font
					(size 1.27 1.27)
				)
				(justify mirror)
			)
		)
		(duplicate_pad_numbers_are_jumpers no)
		(fp_line
			(start -0.7874 -0.4064)
			(end -0.7874 0.4064)
			(stroke
				(width 0.1524)
				(type default)
			)
			(layer "B.SilkS")
		)
		(fp_line
			(start -0.7874 0.4064)
			(end 0.7874 0.4064)
			(stroke
				(width 0.1524)
				(type default)
			)
			(layer "B.SilkS")
		)
		(fp_line
			(start 0.7874 -0.4064)
			(end -0.7874 -0.4064)
			(stroke
				(width 0.1524)
				(type default)
			)
			(layer "B.SilkS")
		)
		(fp_line
			(start 0.7874 0.4064)
			(end 0.7874 -0.4064)
			(stroke
				(width 0.1524)
				(type default)
			)
			(layer "B.SilkS")
		)
		(fp_line
			(start -0.67945 -0.3048)
			(end -0.67945 0.3048)
			(stroke
				(width 0.1)
				(type default)
			)
			(layer "B.Fab")
		)
		(fp_line
			(start -0.67945 0.3048)
			(end -0.120396 0.3048)
			(stroke
				(width 0.1)
				(type default)
			)
			(layer "B.Fab")
		)
		(fp_line
			(start -0.12065 -0.3048)
			(end -0.67945 -0.3048)
			(stroke
				(width 0.1)
				(type default)
			)
			(layer "B.Fab")
		)
		(fp_line
			(start -0.12065 -0.2794)
			(end -0.12065 -0.3048)
			(stroke
				(width 0.1)
				(type default)
			)
			(layer "B.Fab")
		)
		(fp_line
			(start -0.120396 0.2794)
			(end 0.12065 0.2794)
			(stroke
				(width 0.1)
				(type default)
			)
			(layer "B.Fab")
		)
		(fp_line
			(start -0.120396 0.3048)
			(end -0.120396 0.2794)
			(stroke
				(width 0.1)
				(type default)
			)
			(layer "B.Fab")
		)
		(fp_line
			(start 0.12065 -0.305054)
			(end 0.12065 -0.2794)
			(stroke
				(width 0.1)
				(type default)
			)
			(layer "B.Fab")
		)
		(fp_line
			(start 0.12065 -0.2794)
			(end -0.12065 -0.2794)
			(stroke
				(width 0.1)
				(type default)
			)
			(layer "B.Fab")
		)
		(fp_line
			(start 0.12065 0.2794)
			(end 0.12065 0.3048)
			(stroke
				(width 0.1)
				(type default)
			)
			(layer "B.Fab")
		)
		(fp_line
			(start 0.12065 0.3048)
			(end 0.67945 0.3048)
			(stroke
				(width 0.1)
				(type default)
			)
			(layer "B.Fab")
		)
		(fp_line
			(start 0.67945 -0.305054)
			(end 0.12065 -0.305054)
			(stroke
				(width 0.1)
				(type default)
			)
			(layer "B.Fab")
		)
		(fp_line
			(start 0.67945 0.3048)
			(end 0.67945 -0.305054)
			(stroke
				(width 0.1)
				(type default)
			)
			(layer "B.Fab")
		)
		(pad "1" smd circle
			(at 0.40005 0 180)
			(size 0 0)
			(layers "B.Cu" "B.Mask" "B.Paste")
			(net "PD_PCH_GPPC_A_15")
		)
		(pad "2" smd circle
			(at -0.40005 0 180)
			(size 0 0)
			(layers "B.Cu" "B.Mask" "B.Paste")
			(net "GND")
		)
	)
	(footprint ""
		(layer "B.Cu")
		(at 160.89249 -258.399534 -90)
		(property "Reference" "C476"
			(at 0 0 90)
			(layer "B.SilkS")
			(hide yes)
			(effects
				(font
					(size 1.27 1.27)
				)
				(justify mirror)
			)
		)
		(property "Value" ""
			(at 0 0 90)
			(layer "B.Fab")
			(effects
				(font
					(size 1.27 1.27)
				)
				(justify mirror)
			)
		)
		(duplicate_pad_numbers_are_jumpers no)
		(fp_line
			(start -1.524 0.762)
			(end 1.524 0.762)
			(stroke
				(width 0.1524)
				(type default)
			)
			(layer "B.SilkS")
		)
		(fp_line
			(start 1.524 0.762)
			(end 1.524 -0.762)
			(stroke
				(width 0.1524)
				(type default)
			)
			(layer "B.SilkS")
		)
		(fp_line
			(start -1.524 -0.762)
			(end -1.524 0.762)
			(stroke
				(width 0.1524)
				(type default)
			)
			(layer "B.SilkS")
		)
		(fp_line
			(start 1.524 -0.762)
			(end -1.524 -0.762)
			(stroke
				(width 0.1524)
				(type default)
			)
			(layer "B.SilkS")
		)
		(fp_line
			(start -1.1049 0.724916)
			(end -1.1049 -0.724916)
			(stroke
				(width 0.1)
				(type default)
			)
			(layer "B.Fab")
		)
		(fp_line
			(start 1.1049 0.724916)
			(end -1.1049 0.724916)
			(stroke
				(width 0.1)
				(type default)
			)
			(layer "B.Fab")
		)
		(fp_line
			(start -1.1049 -0.724916)
			(end 1.1049 -0.724916)
			(stroke
				(width 0.1)
				(type default)
			)
			(layer "B.Fab")
		)
		(fp_line
			(start 1.1049 -0.724916)
			(end 1.1049 0.724916)
			(stroke
				(width 0.1)
				(type default)
			)
			(layer "B.Fab")
		)
		(pad "1" smd rect
			(at 0.889 0 270)
			(size 1.016 1.27)
			(layers "B.Cu" "B.Mask" "B.Paste")
			(net "PVCCFA_EHV_FIVRA_CPU1")
		)
		(pad "2" smd rect
			(at -0.889 0 270)
			(size 1.016 1.27)
			(layers "B.Cu" "B.Mask" "B.Paste")
			(net "GND")
		)
	)
	(footprint ""
		(layer "B.Cu")
		(at 13.649452 -101.21138 90)
		(property "Reference" "C2035"
			(at 0 0 90)
			(layer "B.SilkS")
			(hide yes)
			(effects
				(font
					(size 1.27 1.27)
				)
				(justify mirror)
			)
		)
		(property "Value" ""
			(at 0 0 90)
			(layer "B.Fab")
			(effects
				(font
					(size 1.27 1.27)
				)
				(justify mirror)
			)
		)
		(duplicate_pad_numbers_are_jumpers no)
		(fp_line
			(start 0.7874 -0.4064)
			(end -0.7874 -0.4064)
			(stroke
				(width 0.1524)
				(type default)
			)
			(layer "B.SilkS")
		)
		(fp_line
			(start -0.7874 -0.4064)
			(end -0.7874 0.4064)
			(stroke
				(width 0.1524)
				(type default)
			)
			(layer "B.SilkS")
		)
		(fp_line
			(start 0.7874 0.4064)
			(end 0.7874 -0.4064)
			(stroke
				(width 0.1524)
				(type default)
			)
			(layer "B.SilkS")
		)
		(fp_line
			(start -0.7874 0.4064)
			(end 0.7874 0.4064)
			(stroke
				(width 0.1524)
				(type default)
			)
			(layer "B.SilkS")
		)
		(fp_line
			(start 0.67945 -0.305054)
			(end 0.12065 -0.305054)
			(stroke
				(width 0.1)
				(type default)
			)
			(layer "B.Fab")
		)
		(fp_line
			(start 0.12065 -0.305054)
			(end 0.12065 -0.2794)
			(stroke
				(width 0.1)
				(type default)
			)
			(layer "B.Fab")
		)
		(fp_line
			(start -0.12065 -0.3048)
			(end -0.67945 -0.3048)
			(stroke
				(width 0.1)
				(type default)
			)
			(layer "B.Fab")
		)
		(fp_line
			(start -0.67945 -0.3048)
			(end -0.67945 0.3048)
			(stroke
				(width 0.1)
				(type default)
			)
			(layer "B.Fab")
		)
		(fp_line
			(start 0.12065 -0.2794)
			(end -0.12065 -0.2794)
			(stroke
				(width 0.1)
				(type default)
			)
			(layer "B.Fab")
		)
		(fp_line
			(start -0.12065 -0.2794)
			(end -0.12065 -0.3048)
			(stroke
				(width 0.1)
				(type default)
			)
			(layer "B.Fab")
		)
		(fp_line
			(start 0.12065 0.2794)
			(end 0.12065 0.3048)
			(stroke
				(width 0.1)
				(type default)
			)
			(layer "B.Fab")
		)
		(fp_line
			(start -0.120396 0.2794)
			(end 0.12065 0.2794)
			(stroke
				(width 0.1)
				(type default)
			)
			(layer "B.Fab")
		)
		(fp_line
			(start 0.67945 0.3048)
			(end 0.67945 -0.305054)
			(stroke
				(width 0.1)
				(type default)
			)
			(layer "B.Fab")
		)
		(fp_line
			(start 0.12065 0.3048)
			(end 0.67945 0.3048)
			(stroke
				(width 0.1)
				(type default)
			)
			(layer "B.Fab")
		)
		(fp_line
			(start -0.120396 0.3048)
			(end -0.120396 0.2794)
			(stroke
				(width 0.1)
				(type default)
			)
			(layer "B.Fab")
		)
		(fp_line
			(start -0.67945 0.3048)
			(end -0.120396 0.3048)
			(stroke
				(width 0.1)
				(type default)
			)
			(layer "B.Fab")
		)
		(pad "1" smd circle
			(at 0.40005 0 270)
			(size 0 0)
			(layers "B.Cu" "B.Mask" "B.Paste")
			(net "P3V3_AUX_USB_HUB")
		)
		(pad "2" smd circle
			(at -0.40005 0 270)
			(size 0 0)
			(layers "B.Cu" "B.Mask" "B.Paste")
			(net "GND")
		)
	)
	(footprint ""
		(layer "B.Cu")
		(at 416.02914 -158.92907)
		(property "Reference" "PC637"
			(at 0 0 0)
			(layer "B.SilkS")
			(hide yes)
			(effects
				(font
					(size 1.27 1.27)
				)
				(justify mirror)
			)
		)
		(property "Value" ""
			(at 0 0 0)
			(layer "B.Fab")
			(effects
				(font
					(size 1.27 1.27)
				)
				(justify mirror)
			)
		)
		(duplicate_pad_numbers_are_jumpers no)
		(fp_line
			(start -1.524 -0.762)
			(end -1.524 0.762)
			(stroke
				(width 0.1524)
				(type default)
			)
			(layer "B.SilkS")
		)
		(fp_line
			(start -1.524 0.762)
			(end 1.524 0.762)
			(stroke
				(width 0.1524)
				(type default)
			)
			(layer "B.SilkS")
		)
		(fp_line
			(start 1.524 -0.762)
			(end -1.524 -0.762)
			(stroke
				(width 0.1524)
				(type default)
			)
			(layer "B.SilkS")
		)
		(fp_line
			(start 1.524 0.762)
			(end 1.524 -0.762)
			(stroke
				(width 0.1524)
				(type default)
			)
			(layer "B.SilkS")
		)
		(fp_line
			(start -1.1049 -0.724916)
			(end 1.1049 -0.724916)
			(stroke
				(width 0.1)
				(type default)
			)
			(layer "B.Fab")
		)
		(fp_line
			(start -1.1049 0.724916)
			(end -1.1049 -0.724916)
			(stroke
				(width 0.1)
				(type default)
			)
			(layer "B.Fab")
		)
		(fp_line
			(start 1.1049 -0.724916)
			(end 1.1049 0.724916)
			(stroke
				(width 0.1)
				(type default)
			)
			(layer "B.Fab")
		)
		(fp_line
			(start 1.1049 0.724916)
			(end -1.1049 0.724916)
			(stroke
				(width 0.1)
				(type default)
			)
			(layer "B.Fab")
		)
		(pad "1" smd rect
			(at 0.889 0)
			(size 1.016 1.27)
			(layers "B.Cu" "B.Mask" "B.Paste")
			(net "SW_P12V_PVCCINFAON_CPU0_FLT")
		)
		(pad "2" smd rect
			(at -0.889 0)
			(size 1.016 1.27)
			(layers "B.Cu" "B.Mask" "B.Paste")
			(net "GND")
		)
	)
	(footprint ""
		(layer "B.Cu")
		(at 180.364384 -422.615868)
		(property "Reference" "R2805"
			(at 0 0 0)
			(layer "B.SilkS")
			(hide yes)
			(effects
				(font
					(size 1.27 1.27)
				)
				(justify mirror)
			)
		)
		(property "Value" ""
			(at 0 0 0)
			(layer "B.Fab")
			(effects
				(font
					(size 1.27 1.27)
				)
				(justify mirror)
			)
		)
		(duplicate_pad_numbers_are_jumpers no)
		(fp_line
			(start -0.7874 -0.4064)
			(end -0.7874 0.4064)
			(stroke
				(width 0.1524)
				(type default)
			)
			(layer "B.SilkS")
		)
		(fp_line
			(start -0.7874 0.4064)
			(end 0.7874 0.4064)
			(stroke
				(width 0.1524)
				(type default)
			)
			(layer "B.SilkS")
		)
		(fp_line
			(start 0.7874 -0.4064)
			(end -0.7874 -0.4064)
			(stroke
				(width 0.1524)
				(type default)
			)
			(layer "B.SilkS")
		)
		(fp_line
			(start 0.7874 0.4064)
			(end 0.7874 -0.4064)
			(stroke
				(width 0.1524)
				(type default)
			)
			(layer "B.SilkS")
		)
		(fp_line
			(start -0.67945 -0.3048)
			(end -0.67945 0.3048)
			(stroke
				(width 0.1)
				(type default)
			)
			(layer "B.Fab")
		)
		(fp_line
			(start -0.67945 0.3048)
			(end -0.120396 0.3048)
			(stroke
				(width 0.1)
				(type default)
			)
			(layer "B.Fab")
		)
		(fp_line
			(start -0.12065 -0.3048)
			(end -0.67945 -0.3048)
			(stroke
				(width 0.1)
				(type default)
			)
			(layer "B.Fab")
		)
		(fp_line
			(start -0.12065 -0.2794)
			(end -0.12065 -0.3048)
			(stroke
				(width 0.1)
				(type default)
			)
			(layer "B.Fab")
		)
		(fp_line
			(start -0.120396 0.2794)
			(end 0.12065 0.2794)
			(stroke
				(width 0.1)
				(type default)
			)
			(layer "B.Fab")
		)
		(fp_line
			(start -0.120396 0.3048)
			(end -0.120396 0.2794)
			(stroke
				(width 0.1)
				(type default)
			)
			(layer "B.Fab")
		)
		(fp_line
			(start 0.12065 -0.305054)
			(end 0.12065 -0.2794)
			(stroke
				(width 0.1)
				(type default)
			)
			(layer "B.Fab")
		)
		(fp_line
			(start 0.12065 -0.2794)
			(end -0.12065 -0.2794)
			(stroke
				(width 0.1)
				(type default)
			)
			(layer "B.Fab")
		)
		(fp_line
			(start 0.12065 0.2794)
			(end 0.12065 0.3048)
			(stroke
				(width 0.1)
				(type default)
			)
			(layer "B.Fab")
		)
		(fp_line
			(start 0.12065 0.3048)
			(end 0.67945 0.3048)
			(stroke
				(width 0.1)
				(type default)
			)
			(layer "B.Fab")
		)
		(fp_line
			(start 0.67945 -0.305054)
			(end 0.12065 -0.305054)
			(stroke
				(width 0.1)
				(type default)
			)
			(layer "B.Fab")
		)
		(fp_line
			(start 0.67945 0.3048)
			(end 0.67945 -0.305054)
			(stroke
				(width 0.1)
				(type default)
			)
			(layer "B.Fab")
		)
		(pad "1" smd circle
			(at 0.40005 0 180)
			(size 0 0)
			(layers "B.Cu" "B.Mask" "B.Paste")
			(net "P3V3_AUX")
		)
		(pad "2" smd circle
			(at -0.40005 0 180)
			(size 0 0)
			(layers "B.Cu" "B.Mask" "B.Paste")
			(net "SMB_FAN_3V3AUX_BUF_SCL")
		)
	)
	(footprint ""
		(layer "B.Cu")
		(at 330.17206 -32.700468 -90)
		(property "Reference" "R374"
			(at 0 0 90)
			(layer "B.SilkS")
			(hide yes)
			(effects
				(font
					(size 1.27 1.27)
				)
				(justify mirror)
			)
		)
		(property "Value" ""
			(at 0 0 90)
			(layer "B.Fab")
			(effects
				(font
					(size 1.27 1.27)
				)
				(justify mirror)
			)
		)
		(duplicate_pad_numbers_are_jumpers no)
		(fp_line
			(start -0.7874 0.4064)
			(end 0.7874 0.4064)
			(stroke
				(width 0.1524)
				(type default)
			)
			(layer "B.SilkS")
		)
		(fp_line
			(start 0.7874 0.4064)
			(end 0.7874 -0.4064)
			(stroke
				(width 0.1524)
				(type default)
			)
			(layer "B.SilkS")
		)
		(fp_line
			(start -0.7874 -0.4064)
			(end -0.7874 0.4064)
			(stroke
				(width 0.1524)
				(type default)
			)
			(layer "B.SilkS")
		)
		(fp_line
			(start 0.7874 -0.4064)
			(end -0.7874 -0.4064)
			(stroke
				(width 0.1524)
				(type default)
			)
			(layer "B.SilkS")
		)
		(fp_line
			(start -0.67945 0.3048)
			(end -0.120396 0.3048)
			(stroke
				(width 0.1)
				(type default)
			)
			(layer "B.Fab")
		)
		(fp_line
			(start -0.120396 0.3048)
			(end -0.120396 0.2794)
			(stroke
				(width 0.1)
				(type default)
			)
			(layer "B.Fab")
		)
		(fp_line
			(start 0.12065 0.3048)
			(end 0.67945 0.3048)
			(stroke
				(width 0.1)
				(type default)
			)
			(layer "B.Fab")
		)
		(fp_line
			(start 0.67945 0.3048)
			(end 0.67945 -0.305054)
			(stroke
				(width 0.1)
				(type default)
			)
			(layer "B.Fab")
		)
		(fp_line
			(start -0.120396 0.2794)
			(end 0.12065 0.2794)
			(stroke
				(width 0.1)
				(type default)
			)
			(layer "B.Fab")
		)
		(fp_line
			(start 0.12065 0.2794)
			(end 0.12065 0.3048)
			(stroke
				(width 0.1)
				(type default)
			)
			(layer "B.Fab")
		)
		(fp_line
			(start -0.12065 -0.2794)
			(end -0.12065 -0.3048)
			(stroke
				(width 0.1)
				(type default)
			)
			(layer "B.Fab")
		)
		(fp_line
			(start 0.12065 -0.2794)
			(end -0.12065 -0.2794)
			(stroke
				(width 0.1)
				(type default)
			)
			(layer "B.Fab")
		)
		(fp_line
			(start -0.67945 -0.3048)
			(end -0.67945 0.3048)
			(stroke
				(width 0.1)
				(type default)
			)
			(layer "B.Fab")
		)
		(fp_line
			(start -0.12065 -0.3048)
			(end -0.67945 -0.3048)
			(stroke
				(width 0.1)
				(type default)
			)
			(layer "B.Fab")
		)
		(fp_line
			(start 0.12065 -0.305054)
			(end 0.12065 -0.2794)
			(stroke
				(width 0.1)
				(type default)
			)
			(layer "B.Fab")
		)
		(fp_line
			(start 0.67945 -0.305054)
			(end 0.12065 -0.305054)
			(stroke
				(width 0.1)
				(type default)
			)
			(layer "B.Fab")
		)
		(pad "1" smd circle
			(at 0.40005 0 90)
			(size 0 0)
			(layers "B.Cu" "B.Mask" "B.Paste")
			(net "P3V3_AUX")
		)
		(pad "2" smd circle
			(at -0.40005 0 90)
			(size 0 0)
			(layers "B.Cu" "B.Mask" "B.Paste")
			(net "FM_SPI_3V3_1V8_VOLTAGE")
		)
	)
	(footprint ""
		(layer "B.Cu")
		(at 21.97608 -389.829548 -90)
		(property "Reference" "C1867"
			(at 0 0 90)
			(layer "B.SilkS")
			(hide yes)
			(effects
				(font
					(size 1.27 1.27)
				)
				(justify mirror)
			)
		)
		(property "Value" ""
			(at 0 0 90)
			(layer "B.Fab")
			(effects
				(font
					(size 1.27 1.27)
				)
				(justify mirror)
			)
		)
		(duplicate_pad_numbers_are_jumpers no)
		(fp_line
			(start -1.524 0.762)
			(end 1.524 0.762)
			(stroke
				(width 0.1524)
				(type default)
			)
			(layer "B.SilkS")
		)
		(fp_line
			(start 1.524 0.762)
			(end 1.524 -0.762)
			(stroke
				(width 0.1524)
				(type default)
			)
			(layer "B.SilkS")
		)
		(fp_line
			(start -1.524 -0.762)
			(end -1.524 0.762)
			(stroke
				(width 0.1524)
				(type default)
			)
			(layer "B.SilkS")
		)
		(fp_line
			(start 1.524 -0.762)
			(end -1.524 -0.762)
			(stroke
				(width 0.1524)
				(type default)
			)
			(layer "B.SilkS")
		)
		(fp_line
			(start -1.1049 0.724916)
			(end -1.1049 -0.724916)
			(stroke
				(width 0.1)
				(type default)
			)
			(layer "B.Fab")
		)
		(fp_line
			(start 1.1049 0.724916)
			(end -1.1049 0.724916)
			(stroke
				(width 0.1)
				(type default)
			)
			(layer "B.Fab")
		)
		(fp_line
			(start -1.1049 -0.724916)
			(end 1.1049 -0.724916)
			(stroke
				(width 0.1)
				(type default)
			)
			(layer "B.Fab")
		)
		(fp_line
			(start 1.1049 -0.724916)
			(end 1.1049 0.724916)
			(stroke
				(width 0.1)
				(type default)
			)
			(layer "B.Fab")
		)
		(pad "1" smd rect
			(at 0.889 0 270)
			(size 1.016 1.27)
			(layers "B.Cu" "B.Mask" "B.Paste")
			(net "P3V3_AUX")
		)
		(pad "2" smd rect
			(at -0.889 0 270)
			(size 1.016 1.27)
			(layers "B.Cu" "B.Mask" "B.Paste")
			(net "GND")
		)
	)
	(footprint ""
		(layer "B.Cu")
		(at 312.963814 -321.549776 -90)
		(property "Reference" "C6"
			(at 0 0 90)
			(layer "B.SilkS")
			(hide yes)
			(effects
				(font
					(size 1.27 1.27)
				)
				(justify mirror)
			)
		)
		(property "Value" ""
			(at 0 0 90)
			(layer "B.Fab")
			(effects
				(font
					(size 1.27 1.27)
				)
				(justify mirror)
			)
		)
		(duplicate_pad_numbers_are_jumpers no)
		(fp_line
			(start -1.524 0.762)
			(end 1.524 0.762)
			(stroke
				(width 0.1524)
				(type default)
			)
			(layer "B.SilkS")
		)
		(fp_line
			(start 1.524 0.762)
			(end 1.524 -0.762)
			(stroke
				(width 0.1524)
				(type default)
			)
			(layer "B.SilkS")
		)
		(fp_line
			(start -1.524 -0.762)
			(end -1.524 0.762)
			(stroke
				(width 0.1524)
				(type default)
			)
			(layer "B.SilkS")
		)
		(fp_line
			(start 1.524 -0.762)
			(end -1.524 -0.762)
			(stroke
				(width 0.1524)
				(type default)
			)
			(layer "B.SilkS")
		)
		(fp_line
			(start -1.1049 0.724916)
			(end -1.1049 -0.724916)
			(stroke
				(width 0.1)
				(type default)
			)
			(layer "B.Fab")
		)
		(fp_line
			(start 1.1049 0.724916)
			(end -1.1049 0.724916)
			(stroke
				(width 0.1)
				(type default)
			)
			(layer "B.Fab")
		)
		(fp_line
			(start -1.1049 -0.724916)
			(end 1.1049 -0.724916)
			(stroke
				(width 0.1)
				(type default)
			)
			(layer "B.Fab")
		)
		(fp_line
			(start 1.1049 -0.724916)
			(end 1.1049 0.724916)
			(stroke
				(width 0.1)
				(type default)
			)
			(layer "B.Fab")
		)
		(pad "1" smd rect
			(at 0.889 0 270)
			(size 1.016 1.27)
			(layers "B.Cu" "B.Mask" "B.Paste")
			(net "P12V_S3_AUX_CPU0_NVDIMM")
		)
		(pad "2" smd rect
			(at -0.889 0 270)
			(size 1.016 1.27)
			(layers "B.Cu" "B.Mask" "B.Paste")
			(net "GND")
		)
	)
	(footprint ""
		(layer "B.Cu")
		(at 98.5012 -337.607402 -90)
		(property "Reference" "PC569_P1_1"
			(at 0 0 90)
			(layer "B.SilkS")
			(hide yes)
			(effects
				(font
					(size 1.27 1.27)
				)
				(justify mirror)
			)
		)
		(property "Value" ""
			(at 0 0 90)
			(layer "B.Fab")
			(effects
				(font
					(size 1.27 1.27)
				)
				(justify mirror)
			)
		)
		(duplicate_pad_numbers_are_jumpers no)
		(fp_line
			(start -1.524 0.762)
			(end 1.524 0.762)
			(stroke
				(width 0.1524)
				(type default)
			)
			(layer "B.SilkS")
		)
		(fp_line
			(start 1.524 0.762)
			(end 1.524 -0.762)
			(stroke
				(width 0.1524)
				(type default)
			)
			(layer "B.SilkS")
		)
		(fp_line
			(start -1.524 -0.762)
			(end -1.524 0.762)
			(stroke
				(width 0.1524)
				(type default)
			)
			(layer "B.SilkS")
		)
		(fp_line
			(start 1.524 -0.762)
			(end -1.524 -0.762)
			(stroke
				(width 0.1524)
				(type default)
			)
			(layer "B.SilkS")
		)
		(fp_line
			(start -1.1049 0.724916)
			(end -1.1049 -0.724916)
			(stroke
				(width 0.1)
				(type default)
			)
			(layer "B.Fab")
		)
		(fp_line
			(start 1.1049 0.724916)
			(end -1.1049 0.724916)
			(stroke
				(width 0.1)
				(type default)
			)
			(layer "B.Fab")
		)
		(fp_line
			(start -1.1049 -0.724916)
			(end 1.1049 -0.724916)
			(stroke
				(width 0.1)
				(type default)
			)
			(layer "B.Fab")
		)
		(fp_line
			(start 1.1049 -0.724916)
			(end 1.1049 0.724916)
			(stroke
				(width 0.1)
				(type default)
			)
			(layer "B.Fab")
		)
		(pad "1" smd rect
			(at 0.889 0 270)
			(size 1.016 1.27)
			(layers "B.Cu" "B.Mask" "B.Paste")
			(net "SW_P12V_PVCCIN_CPU1_FLT")
		)
		(pad "2" smd rect
			(at -0.889 0 270)
			(size 1.016 1.27)
			(layers "B.Cu" "B.Mask" "B.Paste")
			(net "GND")
		)
	)
	(footprint ""
		(layer "B.Cu")
		(at 133.5786 -26.8732 90)
		(property "Reference" "R4637"
			(at 0 0 90)
			(layer "B.SilkS")
			(hide yes)
			(effects
				(font
					(size 1.27 1.27)
				)
				(justify mirror)
			)
		)
		(property "Value" ""
			(at 0 0 90)
			(layer "B.Fab")
			(effects
				(font
					(size 1.27 1.27)
				)
				(justify mirror)
			)
		)
		(duplicate_pad_numbers_are_jumpers no)
		(fp_line
			(start 0.7874 -0.4064)
			(end -0.7874 -0.4064)
			(stroke
				(width 0.1524)
				(type default)
			)
			(layer "B.SilkS")
		)
		(fp_line
			(start -0.7874 -0.4064)
			(end -0.7874 0.4064)
			(stroke
				(width 0.1524)
				(type default)
			)
			(layer "B.SilkS")
		)
		(fp_line
			(start 0.7874 0.4064)
			(end 0.7874 -0.4064)
			(stroke
				(width 0.1524)
				(type default)
			)
			(layer "B.SilkS")
		)
		(fp_line
			(start -0.7874 0.4064)
			(end 0.7874 0.4064)
			(stroke
				(width 0.1524)
				(type default)
			)
			(layer "B.SilkS")
		)
		(fp_line
			(start 0.67945 -0.305054)
			(end 0.12065 -0.305054)
			(stroke
				(width 0.1)
				(type default)
			)
			(layer "B.Fab")
		)
		(fp_line
			(start 0.12065 -0.305054)
			(end 0.12065 -0.2794)
			(stroke
				(width 0.1)
				(type default)
			)
			(layer "B.Fab")
		)
		(fp_line
			(start -0.12065 -0.3048)
			(end -0.67945 -0.3048)
			(stroke
				(width 0.1)
				(type default)
			)
			(layer "B.Fab")
		)
		(fp_line
			(start -0.67945 -0.3048)
			(end -0.67945 0.3048)
			(stroke
				(width 0.1)
				(type default)
			)
			(layer "B.Fab")
		)
		(fp_line
			(start 0.12065 -0.2794)
			(end -0.12065 -0.2794)
			(stroke
				(width 0.1)
				(type default)
			)
			(layer "B.Fab")
		)
		(fp_line
			(start -0.12065 -0.2794)
			(end -0.12065 -0.3048)
			(stroke
				(width 0.1)
				(type default)
			)
			(layer "B.Fab")
		)
		(fp_line
			(start 0.12065 0.2794)
			(end 0.12065 0.3048)
			(stroke
				(width 0.1)
				(type default)
			)
			(layer "B.Fab")
		)
		(fp_line
			(start -0.120396 0.2794)
			(end 0.12065 0.2794)
			(stroke
				(width 0.1)
				(type default)
			)
			(layer "B.Fab")
		)
		(fp_line
			(start 0.67945 0.3048)
			(end 0.67945 -0.305054)
			(stroke
				(width 0.1)
				(type default)
			)
			(layer "B.Fab")
		)
		(fp_line
			(start 0.12065 0.3048)
			(end 0.67945 0.3048)
			(stroke
				(width 0.1)
				(type default)
			)
			(layer "B.Fab")
		)
		(fp_line
			(start -0.120396 0.3048)
			(end -0.120396 0.2794)
			(stroke
				(width 0.1)
				(type default)
			)
			(layer "B.Fab")
		)
		(fp_line
			(start -0.67945 0.3048)
			(end -0.120396 0.3048)
			(stroke
				(width 0.1)
				(type default)
			)
			(layer "B.Fab")
		)
		(pad "1" smd circle
			(at 0.40005 0 270)
			(size 0 0)
			(layers "B.Cu" "B.Mask" "B.Paste")
			(net "USB3_PCH_RX_DN<4>")
		)
		(pad "2" smd circle
			(at -0.40005 0 270)
			(size 0 0)
			(layers "B.Cu" "B.Mask" "B.Paste")
			(net "GND")
		)
	)
	(footprint ""
		(layer "B.Cu")
		(at 396.72006 -50.864008 90)
		(property "Reference" "C551"
			(at 0 0 90)
			(layer "B.SilkS")
			(hide yes)
			(effects
				(font
					(size 1.27 1.27)
				)
				(justify mirror)
			)
		)
		(property "Value" ""
			(at 0 0 90)
			(layer "B.Fab")
			(effects
				(font
					(size 1.27 1.27)
				)
				(justify mirror)
			)
		)
		(duplicate_pad_numbers_are_jumpers no)
		(fp_line
			(start 0.7874 -0.4064)
			(end -0.7874 -0.4064)
			(stroke
				(width 0.1524)
				(type default)
			)
			(layer "B.SilkS")
		)
		(fp_line
			(start -0.7874 -0.4064)
			(end -0.7874 0.4064)
			(stroke
				(width 0.1524)
				(type default)
			)
			(layer "B.SilkS")
		)
		(fp_line
			(start 0.7874 0.4064)
			(end 0.7874 -0.4064)
			(stroke
				(width 0.1524)
				(type default)
			)
			(layer "B.SilkS")
		)
		(fp_line
			(start -0.7874 0.4064)
			(end 0.7874 0.4064)
			(stroke
				(width 0.1524)
				(type default)
			)
			(layer "B.SilkS")
		)
		(fp_line
			(start 0.67945 -0.305054)
			(end 0.12065 -0.305054)
			(stroke
				(width 0.1)
				(type default)
			)
			(layer "B.Fab")
		)
		(fp_line
			(start 0.12065 -0.305054)
			(end 0.12065 -0.2794)
			(stroke
				(width 0.1)
				(type default)
			)
			(layer "B.Fab")
		)
		(fp_line
			(start -0.12065 -0.3048)
			(end -0.67945 -0.3048)
			(stroke
				(width 0.1)
				(type default)
			)
			(layer "B.Fab")
		)
		(fp_line
			(start -0.67945 -0.3048)
			(end -0.67945 0.3048)
			(stroke
				(width 0.1)
				(type default)
			)
			(layer "B.Fab")
		)
		(fp_line
			(start 0.12065 -0.2794)
			(end -0.12065 -0.2794)
			(stroke
				(width 0.1)
				(type default)
			)
			(layer "B.Fab")
		)
		(fp_line
			(start -0.12065 -0.2794)
			(end -0.12065 -0.3048)
			(stroke
				(width 0.1)
				(type default)
			)
			(layer "B.Fab")
		)
		(fp_line
			(start 0.12065 0.2794)
			(end 0.12065 0.3048)
			(stroke
				(width 0.1)
				(type default)
			)
			(layer "B.Fab")
		)
		(fp_line
			(start -0.120396 0.2794)
			(end 0.12065 0.2794)
			(stroke
				(width 0.1)
				(type default)
			)
			(layer "B.Fab")
		)
		(fp_line
			(start 0.67945 0.3048)
			(end 0.67945 -0.305054)
			(stroke
				(width 0.1)
				(type default)
			)
			(layer "B.Fab")
		)
		(fp_line
			(start 0.12065 0.3048)
			(end 0.67945 0.3048)
			(stroke
				(width 0.1)
				(type default)
			)
			(layer "B.Fab")
		)
		(fp_line
			(start -0.120396 0.3048)
			(end -0.120396 0.2794)
			(stroke
				(width 0.1)
				(type default)
			)
			(layer "B.Fab")
		)
		(fp_line
			(start -0.67945 0.3048)
			(end -0.120396 0.3048)
			(stroke
				(width 0.1)
				(type default)
			)
			(layer "B.Fab")
		)
		(pad "1" smd circle
			(at 0.40005 0 270)
			(size 0 0)
			(layers "B.Cu" "B.Mask" "B.Paste")
			(net "P3V3_AUX")
		)
		(pad "2" smd circle
			(at -0.40005 0 270)
			(size 0 0)
			(layers "B.Cu" "B.Mask" "B.Paste")
			(net "GND")
		)
	)
	(footprint ""
		(layer "B.Cu")
		(at 305.589432 -149.533356)
		(property "Reference" "R678"
			(at 0 0 0)
			(layer "B.SilkS")
			(hide yes)
			(effects
				(font
					(size 1.27 1.27)
				)
				(justify mirror)
			)
		)
		(property "Value" ""
			(at 0 0 0)
			(layer "B.Fab")
			(effects
				(font
					(size 1.27 1.27)
				)
				(justify mirror)
			)
		)
		(duplicate_pad_numbers_are_jumpers no)
		(fp_line
			(start -0.7874 -0.4064)
			(end -0.7874 0.4064)
			(stroke
				(width 0.1524)
				(type default)
			)
			(layer "B.SilkS")
		)
		(fp_line
			(start -0.7874 0.4064)
			(end 0.7874 0.4064)
			(stroke
				(width 0.1524)
				(type default)
			)
			(layer "B.SilkS")
		)
		(fp_line
			(start 0.7874 -0.4064)
			(end -0.7874 -0.4064)
			(stroke
				(width 0.1524)
				(type default)
			)
			(layer "B.SilkS")
		)
		(fp_line
			(start 0.7874 0.4064)
			(end 0.7874 -0.4064)
			(stroke
				(width 0.1524)
				(type default)
			)
			(layer "B.SilkS")
		)
		(fp_line
			(start -0.67945 -0.3048)
			(end -0.67945 0.3048)
			(stroke
				(width 0.1)
				(type default)
			)
			(layer "B.Fab")
		)
		(fp_line
			(start -0.67945 0.3048)
			(end -0.120396 0.3048)
			(stroke
				(width 0.1)
				(type default)
			)
			(layer "B.Fab")
		)
		(fp_line
			(start -0.12065 -0.3048)
			(end -0.67945 -0.3048)
			(stroke
				(width 0.1)
				(type default)
			)
			(layer "B.Fab")
		)
		(fp_line
			(start -0.12065 -0.2794)
			(end -0.12065 -0.3048)
			(stroke
				(width 0.1)
				(type default)
			)
			(layer "B.Fab")
		)
		(fp_line
			(start -0.120396 0.2794)
			(end 0.12065 0.2794)
			(stroke
				(width 0.1)
				(type default)
			)
			(layer "B.Fab")
		)
		(fp_line
			(start -0.120396 0.3048)
			(end -0.120396 0.2794)
			(stroke
				(width 0.1)
				(type default)
			)
			(layer "B.Fab")
		)
		(fp_line
			(start 0.12065 -0.305054)
			(end 0.12065 -0.2794)
			(stroke
				(width 0.1)
				(type default)
			)
			(layer "B.Fab")
		)
		(fp_line
			(start 0.12065 -0.2794)
			(end -0.12065 -0.2794)
			(stroke
				(width 0.1)
				(type default)
			)
			(layer "B.Fab")
		)
		(fp_line
			(start 0.12065 0.2794)
			(end 0.12065 0.3048)
			(stroke
				(width 0.1)
				(type default)
			)
			(layer "B.Fab")
		)
		(fp_line
			(start 0.12065 0.3048)
			(end 0.67945 0.3048)
			(stroke
				(width 0.1)
				(type default)
			)
			(layer "B.Fab")
		)
		(fp_line
			(start 0.67945 -0.305054)
			(end 0.12065 -0.305054)
			(stroke
				(width 0.1)
				(type default)
			)
			(layer "B.Fab")
		)
		(fp_line
			(start 0.67945 0.3048)
			(end 0.67945 -0.305054)
			(stroke
				(width 0.1)
				(type default)
			)
			(layer "B.Fab")
		)
		(pad "1" smd circle
			(at 0.40005 0 180)
			(size 0 0)
			(layers "B.Cu" "B.Mask" "B.Paste")
			(net "PD_I3C_SPD_DDR_CPU0_OE_N")
		)
		(pad "2" smd circle
			(at -0.40005 0 180)
			(size 0 0)
			(layers "B.Cu" "B.Mask" "B.Paste")
			(net "GND")
		)
	)
	(footprint ""
		(layer "B.Cu")
		(at 40.436038 -313.866784 90)
		(property "Reference" "R2503"
			(at 0 0 90)
			(layer "B.SilkS")
			(hide yes)
			(effects
				(font
					(size 1.27 1.27)
				)
				(justify mirror)
			)
		)
		(property "Value" ""
			(at 0 0 90)
			(layer "B.Fab")
			(effects
				(font
					(size 1.27 1.27)
				)
				(justify mirror)
			)
		)
		(duplicate_pad_numbers_are_jumpers no)
		(fp_line
			(start 0.7874 -0.4064)
			(end -0.7874 -0.4064)
			(stroke
				(width 0.1524)
				(type default)
			)
			(layer "B.SilkS")
		)
		(fp_line
			(start -0.7874 -0.4064)
			(end -0.7874 0.4064)
			(stroke
				(width 0.1524)
				(type default)
			)
			(layer "B.SilkS")
		)
		(fp_line
			(start 0.7874 0.4064)
			(end 0.7874 -0.4064)
			(stroke
				(width 0.1524)
				(type default)
			)
			(layer "B.SilkS")
		)
		(fp_line
			(start -0.7874 0.4064)
			(end 0.7874 0.4064)
			(stroke
				(width 0.1524)
				(type default)
			)
			(layer "B.SilkS")
		)
		(fp_line
			(start 0.67945 -0.305054)
			(end 0.12065 -0.305054)
			(stroke
				(width 0.1)
				(type default)
			)
			(layer "B.Fab")
		)
		(fp_line
			(start 0.12065 -0.305054)
			(end 0.12065 -0.2794)
			(stroke
				(width 0.1)
				(type default)
			)
			(layer "B.Fab")
		)
		(fp_line
			(start -0.12065 -0.3048)
			(end -0.67945 -0.3048)
			(stroke
				(width 0.1)
				(type default)
			)
			(layer "B.Fab")
		)
		(fp_line
			(start -0.67945 -0.3048)
			(end -0.67945 0.3048)
			(stroke
				(width 0.1)
				(type default)
			)
			(layer "B.Fab")
		)
		(fp_line
			(start 0.12065 -0.2794)
			(end -0.12065 -0.2794)
			(stroke
				(width 0.1)
				(type default)
			)
			(layer "B.Fab")
		)
		(fp_line
			(start -0.12065 -0.2794)
			(end -0.12065 -0.3048)
			(stroke
				(width 0.1)
				(type default)
			)
			(layer "B.Fab")
		)
		(fp_line
			(start 0.12065 0.2794)
			(end 0.12065 0.3048)
			(stroke
				(width 0.1)
				(type default)
			)
			(layer "B.Fab")
		)
		(fp_line
			(start -0.120396 0.2794)
			(end 0.12065 0.2794)
			(stroke
				(width 0.1)
				(type default)
			)
			(layer "B.Fab")
		)
		(fp_line
			(start 0.67945 0.3048)
			(end 0.67945 -0.305054)
			(stroke
				(width 0.1)
				(type default)
			)
			(layer "B.Fab")
		)
		(fp_line
			(start 0.12065 0.3048)
			(end 0.67945 0.3048)
			(stroke
				(width 0.1)
				(type default)
			)
			(layer "B.Fab")
		)
		(fp_line
			(start -0.120396 0.3048)
			(end -0.120396 0.2794)
			(stroke
				(width 0.1)
				(type default)
			)
			(layer "B.Fab")
		)
		(fp_line
			(start -0.67945 0.3048)
			(end -0.120396 0.3048)
			(stroke
				(width 0.1)
				(type default)
			)
			(layer "B.Fab")
		)
		(pad "1" smd circle
			(at 0.40005 0 270)
			(size 0 0)
			(layers "B.Cu" "B.Mask" "B.Paste")
			(net "PWRGD_FAIL_CPU1_CD_R1")
		)
		(pad "2" smd circle
			(at -0.40005 0 270)
			(size 0 0)
			(layers "B.Cu" "B.Mask" "B.Paste")
			(net "PWRGD_FAIL_CPU1_CD_R")
		)
	)
	(footprint ""
		(layer "B.Cu")
		(at 184.555638 -113.37544 -90)
		(property "Reference" "C1900"
			(at 0 0 90)
			(layer "B.SilkS")
			(hide yes)
			(effects
				(font
					(size 1.27 1.27)
				)
				(justify mirror)
			)
		)
		(property "Value" ""
			(at 0 0 90)
			(layer "B.Fab")
			(effects
				(font
					(size 1.27 1.27)
				)
				(justify mirror)
			)
		)
		(duplicate_pad_numbers_are_jumpers no)
		(fp_line
			(start -0.69215 0.2921)
			(end 0.69215 0.2921)
			(stroke
				(width 0.1524)
				(type default)
			)
			(layer "B.SilkS")
		)
		(fp_line
			(start 0.69215 0.2921)
			(end 0.69215 -0.2921)
			(stroke
				(width 0.1524)
				(type default)
			)
			(layer "B.SilkS")
		)
		(fp_line
			(start -0.69215 -0.2921)
			(end -0.69215 0.2921)
			(stroke
				(width 0.1524)
				(type default)
			)
			(layer "B.SilkS")
		)
		(fp_line
			(start 0.69215 -0.2921)
			(end -0.69215 -0.2921)
			(stroke
				(width 0.1524)
				(type default)
			)
			(layer "B.SilkS")
		)
		(fp_line
			(start -0.51435 0.2794)
			(end 0.51435 0.2794)
			(stroke
				(width 0.1)
				(type default)
			)
			(layer "B.Fab")
		)
		(fp_line
			(start 0.51435 0.2794)
			(end 0.51435 -0.2794)
			(stroke
				(width 0.1)
				(type default)
			)
			(layer "B.Fab")
		)
		(fp_line
			(start -0.51435 -0.2794)
			(end -0.51435 0.2794)
			(stroke
				(width 0.1)
				(type default)
			)
			(layer "B.Fab")
		)
		(fp_line
			(start 0.51435 -0.2794)
			(end -0.51435 -0.2794)
			(stroke
				(width 0.1)
				(type default)
			)
			(layer "B.Fab")
		)
		(pad "1" smd circle
			(at 0.40005 0 90)
			(size 0 0)
			(layers "B.Cu" "B.Mask" "B.Paste")
			(net "P3V3_AUX_FPGA_VCCIO2")
		)
		(pad "2" smd circle
			(at -0.40005 0 90)
			(size 0 0)
			(layers "B.Cu" "B.Mask" "B.Paste")
			(net "GND")
		)
		(zone
			(layer "B.Cu")
			(hatch none 0.5)
			(connect_pads
				(clearance 0)
			)
			(min_thickness 0.25)
			(keepout
				(tracks not_allowed)
				(vias allowed)
				(pads allowed)
				(copperpour not_allowed)
				(footprints allowed)
			)
			(placement
				(enabled no)
				(sheetname "")
			)
			(fill
				(thermal_gap 0.5)
				(thermal_bridge_width 0.5)
				(island_removal_mode 0)
			)
			(polygon
				(pts
					(xy 184.468008 -113.18494) (xy 184.409842 -113.27638) (xy 184.409842 -113.47577) (xy 184.468008 -113.56594)
					(xy 184.643268 -113.56594) (xy 184.701688 -113.47577) (xy 184.701688 -113.27638) (xy 184.643522 -113.18494)
				)
			)
		)
	)
	(footprint ""
		(layer "B.Cu")
		(at 177.00244 -344.79992 -90)
		(property "Reference" "PC621_P1_1"
			(at 0 0 90)
			(layer "B.SilkS")
			(hide yes)
			(effects
				(font
					(size 1.27 1.27)
				)
				(justify mirror)
			)
		)
		(property "Value" ""
			(at 0 0 90)
			(layer "B.Fab")
			(effects
				(font
					(size 1.27 1.27)
				)
				(justify mirror)
			)
		)
		(duplicate_pad_numbers_are_jumpers no)
		(fp_line
			(start -0.7874 0.4064)
			(end 0.7874 0.4064)
			(stroke
				(width 0.1524)
				(type default)
			)
			(layer "B.SilkS")
		)
		(fp_line
			(start 0.7874 0.4064)
			(end 0.7874 -0.4064)
			(stroke
				(width 0.1524)
				(type default)
			)
			(layer "B.SilkS")
		)
		(fp_line
			(start -0.7874 -0.4064)
			(end -0.7874 0.4064)
			(stroke
				(width 0.1524)
				(type default)
			)
			(layer "B.SilkS")
		)
		(fp_line
			(start 0.7874 -0.4064)
			(end -0.7874 -0.4064)
			(stroke
				(width 0.1524)
				(type default)
			)
			(layer "B.SilkS")
		)
		(fp_line
			(start -0.67945 0.3048)
			(end -0.120396 0.3048)
			(stroke
				(width 0.1)
				(type default)
			)
			(layer "B.Fab")
		)
		(fp_line
			(start -0.120396 0.3048)
			(end -0.120396 0.2794)
			(stroke
				(width 0.1)
				(type default)
			)
			(layer "B.Fab")
		)
		(fp_line
			(start 0.12065 0.3048)
			(end 0.67945 0.3048)
			(stroke
				(width 0.1)
				(type default)
			)
			(layer "B.Fab")
		)
		(fp_line
			(start 0.67945 0.3048)
			(end 0.67945 -0.305054)
			(stroke
				(width 0.1)
				(type default)
			)
			(layer "B.Fab")
		)
		(fp_line
			(start -0.120396 0.2794)
			(end 0.12065 0.2794)
			(stroke
				(width 0.1)
				(type default)
			)
			(layer "B.Fab")
		)
		(fp_line
			(start 0.12065 0.2794)
			(end 0.12065 0.3048)
			(stroke
				(width 0.1)
				(type default)
			)
			(layer "B.Fab")
		)
		(fp_line
			(start -0.12065 -0.2794)
			(end -0.12065 -0.3048)
			(stroke
				(width 0.1)
				(type default)
			)
			(layer "B.Fab")
		)
		(fp_line
			(start 0.12065 -0.2794)
			(end -0.12065 -0.2794)
			(stroke
				(width 0.1)
				(type default)
			)
			(layer "B.Fab")
		)
		(fp_line
			(start -0.67945 -0.3048)
			(end -0.67945 0.3048)
			(stroke
				(width 0.1)
				(type default)
			)
			(layer "B.Fab")
		)
		(fp_line
			(start -0.12065 -0.3048)
			(end -0.67945 -0.3048)
			(stroke
				(width 0.1)
				(type default)
			)
			(layer "B.Fab")
		)
		(fp_line
			(start 0.12065 -0.305054)
			(end 0.12065 -0.2794)
			(stroke
				(width 0.1)
				(type default)
			)
			(layer "B.Fab")
		)
		(fp_line
			(start 0.67945 -0.305054)
			(end 0.12065 -0.305054)
			(stroke
				(width 0.1)
				(type default)
			)
			(layer "B.Fab")
		)
		(pad "1" smd circle
			(at 0.40005 0 90)
			(size 0 0)
			(layers "B.Cu" "B.Mask" "B.Paste")
			(net "PVCCFA_EHV_FIVRA_CPU1")
		)
		(pad "2" smd circle
			(at -0.40005 0 90)
			(size 0 0)
			(layers "B.Cu" "B.Mask" "B.Paste")
			(net "GND")
		)
	)
	(footprint ""
		(layer "B.Cu")
		(at 323.001132 -59.742324)
		(property "Reference" "R1247"
			(at 0 0 0)
			(layer "B.SilkS")
			(hide yes)
			(effects
				(font
					(size 1.27 1.27)
				)
				(justify mirror)
			)
		)
		(property "Value" ""
			(at 0 0 0)
			(layer "B.Fab")
			(effects
				(font
					(size 1.27 1.27)
				)
				(justify mirror)
			)
		)
		(duplicate_pad_numbers_are_jumpers no)
		(fp_line
			(start -0.7874 -0.4064)
			(end -0.7874 0.4064)
			(stroke
				(width 0.1524)
				(type default)
			)
			(layer "B.SilkS")
		)
		(fp_line
			(start -0.7874 0.4064)
			(end 0.7874 0.4064)
			(stroke
				(width 0.1524)
				(type default)
			)
			(layer "B.SilkS")
		)
		(fp_line
			(start 0.7874 -0.4064)
			(end -0.7874 -0.4064)
			(stroke
				(width 0.1524)
				(type default)
			)
			(layer "B.SilkS")
		)
		(fp_line
			(start 0.7874 0.4064)
			(end 0.7874 -0.4064)
			(stroke
				(width 0.1524)
				(type default)
			)
			(layer "B.SilkS")
		)
		(fp_line
			(start -0.67945 -0.3048)
			(end -0.67945 0.3048)
			(stroke
				(width 0.1)
				(type default)
			)
			(layer "B.Fab")
		)
		(fp_line
			(start -0.67945 0.3048)
			(end -0.120396 0.3048)
			(stroke
				(width 0.1)
				(type default)
			)
			(layer "B.Fab")
		)
		(fp_line
			(start -0.12065 -0.3048)
			(end -0.67945 -0.3048)
			(stroke
				(width 0.1)
				(type default)
			)
			(layer "B.Fab")
		)
		(fp_line
			(start -0.12065 -0.2794)
			(end -0.12065 -0.3048)
			(stroke
				(width 0.1)
				(type default)
			)
			(layer "B.Fab")
		)
		(fp_line
			(start -0.120396 0.2794)
			(end 0.12065 0.2794)
			(stroke
				(width 0.1)
				(type default)
			)
			(layer "B.Fab")
		)
		(fp_line
			(start -0.120396 0.3048)
			(end -0.120396 0.2794)
			(stroke
				(width 0.1)
				(type default)
			)
			(layer "B.Fab")
		)
		(fp_line
			(start 0.12065 -0.305054)
			(end 0.12065 -0.2794)
			(stroke
				(width 0.1)
				(type default)
			)
			(layer "B.Fab")
		)
		(fp_line
			(start 0.12065 -0.2794)
			(end -0.12065 -0.2794)
			(stroke
				(width 0.1)
				(type default)
			)
			(layer "B.Fab")
		)
		(fp_line
			(start 0.12065 0.2794)
			(end 0.12065 0.3048)
			(stroke
				(width 0.1)
				(type default)
			)
			(layer "B.Fab")
		)
		(fp_line
			(start 0.12065 0.3048)
			(end 0.67945 0.3048)
			(stroke
				(width 0.1)
				(type default)
			)
			(layer "B.Fab")
		)
		(fp_line
			(start 0.67945 -0.305054)
			(end 0.12065 -0.305054)
			(stroke
				(width 0.1)
				(type default)
			)
			(layer "B.Fab")
		)
		(fp_line
			(start 0.67945 0.3048)
			(end 0.67945 -0.305054)
			(stroke
				(width 0.1)
				(type default)
			)
			(layer "B.Fab")
		)
		(pad "1" smd circle
			(at 0.40005 0 180)
			(size 0 0)
			(layers "B.Cu" "B.Mask" "B.Paste")
			(net "FM_PCH_CPU_PWR_DEBUG_N")
		)
		(pad "2" smd circle
			(at -0.40005 0 180)
			(size 0 0)
			(layers "B.Cu" "B.Mask" "B.Paste")
			(net "FM_CPU_FBRK_DEBUG_N")
		)
	)
	(footprint ""
		(layer "B.Cu")
		(at 176.317148 -358.09936 180)
		(property "Reference" "PC1683"
			(at 0 0 0)
			(layer "B.SilkS")
			(hide yes)
			(effects
				(font
					(size 1.27 1.27)
				)
				(justify mirror)
			)
		)
		(property "Value" ""
			(at 0 0 0)
			(layer "B.Fab")
			(effects
				(font
					(size 1.27 1.27)
				)
				(justify mirror)
			)
		)
		(duplicate_pad_numbers_are_jumpers no)
		(fp_line
			(start 1.524 0.762)
			(end 1.524 -0.762)
			(stroke
				(width 0.1524)
				(type default)
			)
			(layer "B.SilkS")
		)
		(fp_line
			(start 1.524 -0.762)
			(end -1.524 -0.762)
			(stroke
				(width 0.1524)
				(type default)
			)
			(layer "B.SilkS")
		)
		(fp_line
			(start -1.524 0.762)
			(end 1.524 0.762)
			(stroke
				(width 0.1524)
				(type default)
			)
			(layer "B.SilkS")
		)
		(fp_line
			(start -1.524 -0.762)
			(end -1.524 0.762)
			(stroke
				(width 0.1524)
				(type default)
			)
			(layer "B.SilkS")
		)
		(fp_line
			(start 1.1049 0.724916)
			(end -1.1049 0.724916)
			(stroke
				(width 0.1)
				(type default)
			)
			(layer "B.Fab")
		)
		(fp_line
			(start 1.1049 -0.724916)
			(end 1.1049 0.724916)
			(stroke
				(width 0.1)
				(type default)
			)
			(layer "B.Fab")
		)
		(fp_line
			(start -1.1049 0.724916)
			(end -1.1049 -0.724916)
			(stroke
				(width 0.1)
				(type default)
			)
			(layer "B.Fab")
		)
		(fp_line
			(start -1.1049 -0.724916)
			(end 1.1049 -0.724916)
			(stroke
				(width 0.1)
				(type default)
			)
			(layer "B.Fab")
		)
		(pad "1" smd rect
			(at 0.889 0 180)
			(size 1.016 1.27)
			(layers "B.Cu" "B.Mask" "B.Paste")
			(net "SW_P12V_PVCCFA_EHV_FIVRA_CPU1_R")
		)
		(pad "2" smd rect
			(at -0.889 0 180)
			(size 1.016 1.27)
			(layers "B.Cu" "B.Mask" "B.Paste")
			(net "GND")
		)
	)
	(footprint ""
		(layer "B.Cu")
		(at 297.525948 -48.409352)
		(property "Reference" "C1185"
			(at 0 0 0)
			(layer "B.SilkS")
			(hide yes)
			(effects
				(font
					(size 1.27 1.27)
				)
				(justify mirror)
			)
		)
		(property "Value" ""
			(at 0 0 0)
			(layer "B.Fab")
			(effects
				(font
					(size 1.27 1.27)
				)
				(justify mirror)
			)
		)
		(duplicate_pad_numbers_are_jumpers no)
		(fp_line
			(start -1.2954 -0.5842)
			(end -1.2954 0.5842)
			(stroke
				(width 0.1524)
				(type default)
			)
			(layer "B.SilkS")
		)
		(fp_line
			(start -1.2954 0.5842)
			(end 1.2954 0.5842)
			(stroke
				(width 0.1524)
				(type default)
			)
			(layer "B.SilkS")
		)
		(fp_line
			(start 0 -0.5842)
			(end 0 0.5842)
			(stroke
				(width 0.1524)
				(type default)
			)
			(layer "B.SilkS")
		)
		(fp_line
			(start 1.2954 -0.5842)
			(end -1.2954 -0.5842)
			(stroke
				(width 0.1524)
				(type default)
			)
			(layer "B.SilkS")
		)
		(fp_line
			(start 1.2954 0.5842)
			(end 1.2954 -0.5842)
			(stroke
				(width 0.1524)
				(type default)
			)
			(layer "B.SilkS")
		)
		(fp_line
			(start -1.1938 -0.4064)
			(end -1.1938 0.4064)
			(stroke
				(width 0.1)
				(type default)
			)
			(layer "B.Fab")
		)
		(fp_line
			(start -1.1938 0.4064)
			(end -0.8636 0.4064)
			(stroke
				(width 0.1)
				(type default)
			)
			(layer "B.Fab")
		)
		(fp_line
			(start -0.8636 -0.4572)
			(end -0.8636 -0.4064)
			(stroke
				(width 0.1)
				(type default)
			)
			(layer "B.Fab")
		)
		(fp_line
			(start -0.8636 -0.4064)
			(end -1.1938 -0.4064)
			(stroke
				(width 0.1)
				(type default)
			)
			(layer "B.Fab")
		)
		(fp_line
			(start -0.8636 0.4064)
			(end -0.8636 0.4572)
			(stroke
				(width 0.1)
				(type default)
			)
			(layer "B.Fab")
		)
		(fp_line
			(start -0.8636 0.4572)
			(end 0.8636 0.4572)
			(stroke
				(width 0.1)
				(type default)
			)
			(layer "B.Fab")
		)
		(fp_line
			(start 0.8636 -0.4572)
			(end -0.8636 -0.4572)
			(stroke
				(width 0.1)
				(type default)
			)
			(layer "B.Fab")
		)
		(fp_line
			(start 0.8636 -0.4064)
			(end 0.8636 -0.4572)
			(stroke
				(width 0.1)
				(type default)
			)
			(layer "B.Fab")
		)
		(fp_line
			(start 0.8636 0.4064)
			(end 1.1938 0.4064)
			(stroke
				(width 0.1)
				(type default)
			)
			(layer "B.Fab")
		)
		(fp_line
			(start 0.8636 0.4572)
			(end 0.8636 0.4064)
			(stroke
				(width 0.1)
				(type default)
			)
			(layer "B.Fab")
		)
		(fp_line
			(start 1.1938 -0.4064)
			(end 0.8636 -0.4064)
			(stroke
				(width 0.1)
				(type default)
			)
			(layer "B.Fab")
		)
		(fp_line
			(start 1.1938 0.4064)
			(end 1.1938 -0.4064)
			(stroke
				(width 0.1)
				(type default)
			)
			(layer "B.Fab")
		)
		(pad "1" smd rect
			(at 0.7366 0 270)
			(size 0.7112 0.8128)
			(layers "B.Cu" "B.Mask" "B.Paste")
			(net "P1V05_PCH_AUX")
		)
		(pad "2" smd rect
			(at -0.7366 0 270)
			(size 0.7112 0.8128)
			(layers "B.Cu" "B.Mask" "B.Paste")
			(net "GND")
		)
	)
	(footprint ""
		(layer "B.Cu")
		(at 169.506138 -193.01079 90)
		(property "Reference" "R151"
			(at 0 0 90)
			(layer "B.SilkS")
			(hide yes)
			(effects
				(font
					(size 1.27 1.27)
				)
				(justify mirror)
			)
		)
		(property "Value" ""
			(at 0 0 90)
			(layer "B.Fab")
			(effects
				(font
					(size 1.27 1.27)
				)
				(justify mirror)
			)
		)
		(duplicate_pad_numbers_are_jumpers no)
		(fp_line
			(start 0.7874 -0.4064)
			(end -0.7874 -0.4064)
			(stroke
				(width 0.1524)
				(type default)
			)
			(layer "B.SilkS")
		)
		(fp_line
			(start -0.7874 -0.4064)
			(end -0.7874 0.4064)
			(stroke
				(width 0.1524)
				(type default)
			)
			(layer "B.SilkS")
		)
		(fp_line
			(start 0.7874 0.4064)
			(end 0.7874 -0.4064)
			(stroke
				(width 0.1524)
				(type default)
			)
			(layer "B.SilkS")
		)
		(fp_line
			(start -0.7874 0.4064)
			(end 0.7874 0.4064)
			(stroke
				(width 0.1524)
				(type default)
			)
			(layer "B.SilkS")
		)
		(fp_line
			(start 0.67945 -0.305054)
			(end 0.12065 -0.305054)
			(stroke
				(width 0.1)
				(type default)
			)
			(layer "B.Fab")
		)
		(fp_line
			(start 0.12065 -0.305054)
			(end 0.12065 -0.2794)
			(stroke
				(width 0.1)
				(type default)
			)
			(layer "B.Fab")
		)
		(fp_line
			(start -0.12065 -0.3048)
			(end -0.67945 -0.3048)
			(stroke
				(width 0.1)
				(type default)
			)
			(layer "B.Fab")
		)
		(fp_line
			(start -0.67945 -0.3048)
			(end -0.67945 0.3048)
			(stroke
				(width 0.1)
				(type default)
			)
			(layer "B.Fab")
		)
		(fp_line
			(start 0.12065 -0.2794)
			(end -0.12065 -0.2794)
			(stroke
				(width 0.1)
				(type default)
			)
			(layer "B.Fab")
		)
		(fp_line
			(start -0.12065 -0.2794)
			(end -0.12065 -0.3048)
			(stroke
				(width 0.1)
				(type default)
			)
			(layer "B.Fab")
		)
		(fp_line
			(start 0.12065 0.2794)
			(end 0.12065 0.3048)
			(stroke
				(width 0.1)
				(type default)
			)
			(layer "B.Fab")
		)
		(fp_line
			(start -0.120396 0.2794)
			(end 0.12065 0.2794)
			(stroke
				(width 0.1)
				(type default)
			)
			(layer "B.Fab")
		)
		(fp_line
			(start 0.67945 0.3048)
			(end 0.67945 -0.305054)
			(stroke
				(width 0.1)
				(type default)
			)
			(layer "B.Fab")
		)
		(fp_line
			(start 0.12065 0.3048)
			(end 0.67945 0.3048)
			(stroke
				(width 0.1)
				(type default)
			)
			(layer "B.Fab")
		)
		(fp_line
			(start -0.120396 0.3048)
			(end -0.120396 0.2794)
			(stroke
				(width 0.1)
				(type default)
			)
			(layer "B.Fab")
		)
		(fp_line
			(start -0.67945 0.3048)
			(end -0.120396 0.3048)
			(stroke
				(width 0.1)
				(type default)
			)
			(layer "B.Fab")
		)
		(pad "1" smd circle
			(at 0.40005 0 270)
			(size 0 0)
			(layers "B.Cu" "B.Mask" "B.Paste")
			(net "PWRGD_DRAMPWRGD_CPU1_EF_LVC1_R2")
		)
		(pad "2" smd circle
			(at -0.40005 0 270)
			(size 0 0)
			(layers "B.Cu" "B.Mask" "B.Paste")
			(net "PVCCD_HV_CPU1")
		)
	)
	(footprint ""
		(layer "B.Cu")
		(at 107.887008 -212.049868 180)
		(property "Reference" "C460"
			(at 0 0 0)
			(layer "B.SilkS")
			(hide yes)
			(effects
				(font
					(size 1.27 1.27)
				)
				(justify mirror)
			)
		)
		(property "Value" ""
			(at 0 0 0)
			(layer "B.Fab")
			(effects
				(font
					(size 1.27 1.27)
				)
				(justify mirror)
			)
		)
		(duplicate_pad_numbers_are_jumpers no)
		(fp_line
			(start 1.524 0.762)
			(end 1.524 -0.762)
			(stroke
				(width 0.1524)
				(type default)
			)
			(layer "B.SilkS")
		)
		(fp_line
			(start 1.524 -0.762)
			(end -1.524 -0.762)
			(stroke
				(width 0.1524)
				(type default)
			)
			(layer "B.SilkS")
		)
		(fp_line
			(start -1.524 0.762)
			(end 1.524 0.762)
			(stroke
				(width 0.1524)
				(type default)
			)
			(layer "B.SilkS")
		)
		(fp_line
			(start -1.524 -0.762)
			(end -1.524 0.762)
			(stroke
				(width 0.1524)
				(type default)
			)
			(layer "B.SilkS")
		)
		(fp_line
			(start 1.1049 0.724916)
			(end -1.1049 0.724916)
			(stroke
				(width 0.1)
				(type default)
			)
			(layer "B.Fab")
		)
		(fp_line
			(start 1.1049 -0.724916)
			(end 1.1049 0.724916)
			(stroke
				(width 0.1)
				(type default)
			)
			(layer "B.Fab")
		)
		(fp_line
			(start -1.1049 0.724916)
			(end -1.1049 -0.724916)
			(stroke
				(width 0.1)
				(type default)
			)
			(layer "B.Fab")
		)
		(fp_line
			(start -1.1049 -0.724916)
			(end 1.1049 -0.724916)
			(stroke
				(width 0.1)
				(type default)
			)
			(layer "B.Fab")
		)
		(pad "1" smd rect
			(at 0.889 0 180)
			(size 1.016 1.27)
			(layers "B.Cu" "B.Mask" "B.Paste")
			(net "PVCCFA_EHV_CPU1")
		)
		(pad "2" smd rect
			(at -0.889 0 180)
			(size 1.016 1.27)
			(layers "B.Cu" "B.Mask" "B.Paste")
			(net "GND")
		)
	)
	(footprint ""
		(layer "B.Cu")
		(at 304.926238 -194.72021 90)
		(property "Reference" "R12"
			(at 0 0 90)
			(layer "B.SilkS")
			(hide yes)
			(effects
				(font
					(size 1.27 1.27)
				)
				(justify mirror)
			)
		)
		(property "Value" ""
			(at 0 0 90)
			(layer "B.Fab")
			(effects
				(font
					(size 1.27 1.27)
				)
				(justify mirror)
			)
		)
		(duplicate_pad_numbers_are_jumpers no)
		(fp_line
			(start 0.7874 -0.4064)
			(end -0.7874 -0.4064)
			(stroke
				(width 0.1524)
				(type default)
			)
			(layer "B.SilkS")
		)
		(fp_line
			(start -0.7874 -0.4064)
			(end -0.7874 0.4064)
			(stroke
				(width 0.1524)
				(type default)
			)
			(layer "B.SilkS")
		)
		(fp_line
			(start 0.7874 0.4064)
			(end 0.7874 -0.4064)
			(stroke
				(width 0.1524)
				(type default)
			)
			(layer "B.SilkS")
		)
		(fp_line
			(start -0.7874 0.4064)
			(end 0.7874 0.4064)
			(stroke
				(width 0.1524)
				(type default)
			)
			(layer "B.SilkS")
		)
		(fp_line
			(start 0.67945 -0.305054)
			(end 0.12065 -0.305054)
			(stroke
				(width 0.1)
				(type default)
			)
			(layer "B.Fab")
		)
		(fp_line
			(start 0.12065 -0.305054)
			(end 0.12065 -0.2794)
			(stroke
				(width 0.1)
				(type default)
			)
			(layer "B.Fab")
		)
		(fp_line
			(start -0.12065 -0.3048)
			(end -0.67945 -0.3048)
			(stroke
				(width 0.1)
				(type default)
			)
			(layer "B.Fab")
		)
		(fp_line
			(start -0.67945 -0.3048)
			(end -0.67945 0.3048)
			(stroke
				(width 0.1)
				(type default)
			)
			(layer "B.Fab")
		)
		(fp_line
			(start 0.12065 -0.2794)
			(end -0.12065 -0.2794)
			(stroke
				(width 0.1)
				(type default)
			)
			(layer "B.Fab")
		)
		(fp_line
			(start -0.12065 -0.2794)
			(end -0.12065 -0.3048)
			(stroke
				(width 0.1)
				(type default)
			)
			(layer "B.Fab")
		)
		(fp_line
			(start 0.12065 0.2794)
			(end 0.12065 0.3048)
			(stroke
				(width 0.1)
				(type default)
			)
			(layer "B.Fab")
		)
		(fp_line
			(start -0.120396 0.2794)
			(end 0.12065 0.2794)
			(stroke
				(width 0.1)
				(type default)
			)
			(layer "B.Fab")
		)
		(fp_line
			(start 0.67945 0.3048)
			(end 0.67945 -0.305054)
			(stroke
				(width 0.1)
				(type default)
			)
			(layer "B.Fab")
		)
		(fp_line
			(start 0.12065 0.3048)
			(end 0.67945 0.3048)
			(stroke
				(width 0.1)
				(type default)
			)
			(layer "B.Fab")
		)
		(fp_line
			(start -0.120396 0.3048)
			(end -0.120396 0.2794)
			(stroke
				(width 0.1)
				(type default)
			)
			(layer "B.Fab")
		)
		(fp_line
			(start -0.67945 0.3048)
			(end -0.120396 0.3048)
			(stroke
				(width 0.1)
				(type default)
			)
			(layer "B.Fab")
		)
		(pad "1" smd circle
			(at 0.40005 0 270)
			(size 0 0)
			(layers "B.Cu" "B.Mask" "B.Paste")
			(net "SVID_DIO0_CPU0")
		)
		(pad "2" smd circle
			(at -0.40005 0 270)
			(size 0 0)
			(layers "B.Cu" "B.Mask" "B.Paste")
			(net "SVID_DIO0_CPU0_R")
		)
	)
	(footprint ""
		(layer "B.Cu")
		(at 430.518316 -352.974148 -90)
		(property "Reference" "PC1185_P0_3"
			(at 0 0 90)
			(layer "B.SilkS")
			(hide yes)
			(effects
				(font
					(size 1.27 1.27)
				)
				(justify mirror)
			)
		)
		(property "Value" ""
			(at 0 0 90)
			(layer "B.Fab")
			(effects
				(font
					(size 1.27 1.27)
				)
				(justify mirror)
			)
		)
		(duplicate_pad_numbers_are_jumpers no)
		(fp_line
			(start -1.524 0.762)
			(end 1.524 0.762)
			(stroke
				(width 0.1524)
				(type default)
			)
			(layer "B.SilkS")
		)
		(fp_line
			(start 1.524 0.762)
			(end 1.524 -0.762)
			(stroke
				(width 0.1524)
				(type default)
			)
			(layer "B.SilkS")
		)
		(fp_line
			(start -1.524 -0.762)
			(end -1.524 0.762)
			(stroke
				(width 0.1524)
				(type default)
			)
			(layer "B.SilkS")
		)
		(fp_line
			(start 1.524 -0.762)
			(end -1.524 -0.762)
			(stroke
				(width 0.1524)
				(type default)
			)
			(layer "B.SilkS")
		)
		(fp_line
			(start -1.1049 0.724916)
			(end -1.1049 -0.724916)
			(stroke
				(width 0.1)
				(type default)
			)
			(layer "B.Fab")
		)
		(fp_line
			(start 1.1049 0.724916)
			(end -1.1049 0.724916)
			(stroke
				(width 0.1)
				(type default)
			)
			(layer "B.Fab")
		)
		(fp_line
			(start -1.1049 -0.724916)
			(end 1.1049 -0.724916)
			(stroke
				(width 0.1)
				(type default)
			)
			(layer "B.Fab")
		)
		(fp_line
			(start 1.1049 -0.724916)
			(end 1.1049 0.724916)
			(stroke
				(width 0.1)
				(type default)
			)
			(layer "B.Fab")
		)
		(pad "1" smd rect
			(at 0.889 0 270)
			(size 1.016 1.27)
			(layers "B.Cu" "B.Mask" "B.Paste")
			(net "PVCCFA_EHV_FIVRA_CPU0")
		)
		(pad "2" smd rect
			(at -0.889 0 270)
			(size 1.016 1.27)
			(layers "B.Cu" "B.Mask" "B.Paste")
			(net "GND")
		)
	)
	(footprint ""
		(layer "B.Cu")
		(at 109.125512 -415.047938 90)
		(property "Reference" "C2331"
			(at 0 0 90)
			(layer "B.SilkS")
			(hide yes)
			(effects
				(font
					(size 1.27 1.27)
				)
				(justify mirror)
			)
		)
		(property "Value" ""
			(at 0 0 90)
			(layer "B.Fab")
			(effects
				(font
					(size 1.27 1.27)
				)
				(justify mirror)
			)
		)
		(duplicate_pad_numbers_are_jumpers no)
		(fp_line
			(start 1.2954 -0.5842)
			(end -1.2954 -0.5842)
			(stroke
				(width 0.1524)
				(type default)
			)
			(layer "B.SilkS")
		)
		(fp_line
			(start 0 -0.5842)
			(end 0 0.5842)
			(stroke
				(width 0.1524)
				(type default)
			)
			(layer "B.SilkS")
		)
		(fp_line
			(start -1.2954 -0.5842)
			(end -1.2954 0.5842)
			(stroke
				(width 0.1524)
				(type default)
			)
			(layer "B.SilkS")
		)
		(fp_line
			(start 1.2954 0.5842)
			(end 1.2954 -0.5842)
			(stroke
				(width 0.1524)
				(type default)
			)
			(layer "B.SilkS")
		)
		(fp_line
			(start -1.2954 0.5842)
			(end 1.2954 0.5842)
			(stroke
				(width 0.1524)
				(type default)
			)
			(layer "B.SilkS")
		)
		(fp_line
			(start 0.8636 -0.4572)
			(end -0.8636 -0.4572)
			(stroke
				(width 0.1)
				(type default)
			)
			(layer "B.Fab")
		)
		(fp_line
			(start -0.8636 -0.4572)
			(end -0.8636 -0.4064)
			(stroke
				(width 0.1)
				(type default)
			)
			(layer "B.Fab")
		)
		(fp_line
			(start 1.1938 -0.4064)
			(end 0.8636 -0.4064)
			(stroke
				(width 0.1)
				(type default)
			)
			(layer "B.Fab")
		)
		(fp_line
			(start 0.8636 -0.4064)
			(end 0.8636 -0.4572)
			(stroke
				(width 0.1)
				(type default)
			)
			(layer "B.Fab")
		)
		(fp_line
			(start -0.8636 -0.4064)
			(end -1.1938 -0.4064)
			(stroke
				(width 0.1)
				(type default)
			)
			(layer "B.Fab")
		)
		(fp_line
			(start -1.1938 -0.4064)
			(end -1.1938 0.4064)
			(stroke
				(width 0.1)
				(type default)
			)
			(layer "B.Fab")
		)
		(fp_line
			(start 1.1938 0.4064)
			(end 1.1938 -0.4064)
			(stroke
				(width 0.1)
				(type default)
			)
			(layer "B.Fab")
		)
		(fp_line
			(start 0.8636 0.4064)
			(end 1.1938 0.4064)
			(stroke
				(width 0.1)
				(type default)
			)
			(layer "B.Fab")
		)
		(fp_line
			(start -0.8636 0.4064)
			(end -0.8636 0.4572)
			(stroke
				(width 0.1)
				(type default)
			)
			(layer "B.Fab")
		)
		(fp_line
			(start -1.1938 0.4064)
			(end -0.8636 0.4064)
			(stroke
				(width 0.1)
				(type default)
			)
			(layer "B.Fab")
		)
		(fp_line
			(start 0.8636 0.4572)
			(end 0.8636 0.4064)
			(stroke
				(width 0.1)
				(type default)
			)
			(layer "B.Fab")
		)
		(fp_line
			(start -0.8636 0.4572)
			(end 0.8636 0.4572)
			(stroke
				(width 0.1)
				(type default)
			)
			(layer "B.Fab")
		)
		(pad "1" smd rect
			(at 0.7366 0)
			(size 0.7112 0.8128)
			(layers "B.Cu" "B.Mask" "B.Paste")
			(net "P3V3_9ZXL045_VDDA")
		)
		(pad "2" smd rect
			(at -0.7366 0)
			(size 0.7112 0.8128)
			(layers "B.Cu" "B.Mask" "B.Paste")
			(net "GND")
		)
	)
	(footprint ""
		(layer "B.Cu")
		(at 205.28788 -35.956748 90)
		(property "Reference" "C2022"
			(at 0 0 90)
			(layer "B.SilkS")
			(hide yes)
			(effects
				(font
					(size 1.27 1.27)
				)
				(justify mirror)
			)
		)
		(property "Value" ""
			(at 0 0 90)
			(layer "B.Fab")
			(effects
				(font
					(size 1.27 1.27)
				)
				(justify mirror)
			)
		)
		(duplicate_pad_numbers_are_jumpers no)
		(fp_line
			(start 0.7874 -0.4064)
			(end -0.7874 -0.4064)
			(stroke
				(width 0.1524)
				(type default)
			)
			(layer "B.SilkS")
		)
		(fp_line
			(start -0.7874 -0.4064)
			(end -0.7874 0.4064)
			(stroke
				(width 0.1524)
				(type default)
			)
			(layer "B.SilkS")
		)
		(fp_line
			(start 0.7874 0.4064)
			(end 0.7874 -0.4064)
			(stroke
				(width 0.1524)
				(type default)
			)
			(layer "B.SilkS")
		)
		(fp_line
			(start -0.7874 0.4064)
			(end 0.7874 0.4064)
			(stroke
				(width 0.1524)
				(type default)
			)
			(layer "B.SilkS")
		)
		(fp_line
			(start 0.67945 -0.305054)
			(end 0.12065 -0.305054)
			(stroke
				(width 0.1)
				(type default)
			)
			(layer "B.Fab")
		)
		(fp_line
			(start 0.12065 -0.305054)
			(end 0.12065 -0.2794)
			(stroke
				(width 0.1)
				(type default)
			)
			(layer "B.Fab")
		)
		(fp_line
			(start -0.12065 -0.3048)
			(end -0.67945 -0.3048)
			(stroke
				(width 0.1)
				(type default)
			)
			(layer "B.Fab")
		)
		(fp_line
			(start -0.67945 -0.3048)
			(end -0.67945 0.3048)
			(stroke
				(width 0.1)
				(type default)
			)
			(layer "B.Fab")
		)
		(fp_line
			(start 0.12065 -0.2794)
			(end -0.12065 -0.2794)
			(stroke
				(width 0.1)
				(type default)
			)
			(layer "B.Fab")
		)
		(fp_line
			(start -0.12065 -0.2794)
			(end -0.12065 -0.3048)
			(stroke
				(width 0.1)
				(type default)
			)
			(layer "B.Fab")
		)
		(fp_line
			(start 0.12065 0.2794)
			(end 0.12065 0.3048)
			(stroke
				(width 0.1)
				(type default)
			)
			(layer "B.Fab")
		)
		(fp_line
			(start -0.120396 0.2794)
			(end 0.12065 0.2794)
			(stroke
				(width 0.1)
				(type default)
			)
			(layer "B.Fab")
		)
		(fp_line
			(start 0.67945 0.3048)
			(end 0.67945 -0.305054)
			(stroke
				(width 0.1)
				(type default)
			)
			(layer "B.Fab")
		)
		(fp_line
			(start 0.12065 0.3048)
			(end 0.67945 0.3048)
			(stroke
				(width 0.1)
				(type default)
			)
			(layer "B.Fab")
		)
		(fp_line
			(start -0.120396 0.3048)
			(end -0.120396 0.2794)
			(stroke
				(width 0.1)
				(type default)
			)
			(layer "B.Fab")
		)
		(fp_line
			(start -0.67945 0.3048)
			(end -0.120396 0.3048)
			(stroke
				(width 0.1)
				(type default)
			)
			(layer "B.Fab")
		)
		(pad "1" smd circle
			(at 0.40005 0 270)
			(size 0 0)
			(layers "B.Cu" "B.Mask" "B.Paste")
			(net "VSENSE_P12V_INA230_5_INP")
		)
		(pad "2" smd circle
			(at -0.40005 0 270)
			(size 0 0)
			(layers "B.Cu" "B.Mask" "B.Paste")
			(net "VSENSE_P12V_INA230_5_INN")
		)
	)
	(footprint ""
		(layer "B.Cu")
		(at 131.74726 -27.3177)
		(property "Reference" "C2350"
			(at 0 0 0)
			(layer "B.SilkS")
			(hide yes)
			(effects
				(font
					(size 1.27 1.27)
				)
				(justify mirror)
			)
		)
		(property "Value" ""
			(at 0 0 0)
			(layer "B.Fab")
			(effects
				(font
					(size 1.27 1.27)
				)
				(justify mirror)
			)
		)
		(duplicate_pad_numbers_are_jumpers no)
		(fp_line
			(start -0.40005 0.4064)
			(end 0.40005 0.4064)
			(stroke
				(width 0.1524)
				(type default)
			)
			(layer "B.SilkS")
		)
		(fp_line
			(start 0.40005 -0.4064)
			(end -0.40005 -0.4064)
			(stroke
				(width 0.1524)
				(type default)
			)
			(layer "B.SilkS")
		)
		(fp_line
			(start -0.6858 -0.3048)
			(end -0.6858 0.3048)
			(stroke
				(width 0.1)
				(type default)
			)
			(layer "B.Fab")
		)
		(fp_line
			(start -0.6858 0.3048)
			(end -0.1016 0.3048)
			(stroke
				(width 0.1)
				(type default)
			)
			(layer "B.Fab")
		)
		(fp_line
			(start -0.1016 -0.3048)
			(end -0.6858 -0.3048)
			(stroke
				(width 0.1)
				(type default)
			)
			(layer "B.Fab")
		)
		(fp_line
			(start -0.1016 -0.2794)
			(end -0.1016 -0.3048)
			(stroke
				(width 0.1)
				(type default)
			)
			(layer "B.Fab")
		)
		(fp_line
			(start -0.1016 0.2794)
			(end 0.1016 0.2794)
			(stroke
				(width 0.1)
				(type default)
			)
			(layer "B.Fab")
		)
		(fp_line
			(start -0.1016 0.3048)
			(end -0.1016 0.2794)
			(stroke
				(width 0.1)
				(type default)
			)
			(layer "B.Fab")
		)
		(fp_line
			(start 0.1016 -0.3048)
			(end 0.1016 -0.2794)
			(stroke
				(width 0.1)
				(type default)
			)
			(layer "B.Fab")
		)
		(fp_line
			(start 0.1016 -0.2794)
			(end -0.1016 -0.2794)
			(stroke
				(width 0.1)
				(type default)
			)
			(layer "B.Fab")
		)
		(fp_line
			(start 0.1016 0.2794)
			(end 0.1016 0.3048)
			(stroke
				(width 0.1)
				(type default)
			)
			(layer "B.Fab")
		)
		(fp_line
			(start 0.1016 0.3048)
			(end 0.6858 0.3048)
			(stroke
				(width 0.1)
				(type default)
			)
			(layer "B.Fab")
		)
		(fp_line
			(start 0.6858 -0.3048)
			(end 0.1016 -0.3048)
			(stroke
				(width 0.1)
				(type default)
			)
			(layer "B.Fab")
		)
		(fp_line
			(start 0.6858 0.3048)
			(end 0.6858 -0.3048)
			(stroke
				(width 0.1)
				(type default)
			)
			(layer "B.Fab")
		)
		(pad "1" smd rect
			(at 0.40005 0)
			(size 0.4572 0.508)
			(layers "B.Cu" "B.Mask" "B.Paste")
			(net "USB3_PCH_RX_DN<4>")
		)
		(pad "2" smd rect
			(at -0.40005 0)
			(size 0.4572 0.508)
			(layers "B.Cu" "B.Mask" "B.Paste")
			(net "USB3_PCH_RX_C_DN<4>")
		)
		(zone
			(layer "In16.Cu")
			(hatch none 0.5)
			(connect_pads
				(clearance 0)
			)
			(min_thickness 0.25)
			(keepout
				(tracks not_allowed)
				(vias allowed)
				(pads allowed)
				(copperpour not_allowed)
				(footprints allowed)
			)
			(placement
				(enabled no)
				(sheetname "")
			)
			(fill
				(thermal_gap 0.5)
				(thermal_bridge_width 0.5)
				(island_removal_mode 0)
			)
			(polygon
				(pts
					(xy 131.62661 -27.0129) (xy 131.06781 -27.0129) (xy 131.06781 -27.6225) (xy 131.62661 -27.6225)
				)
			)
		)
		(zone
			(layer "In16.Cu")
			(hatch none 0.5)
			(connect_pads
				(clearance 0)
			)
			(min_thickness 0.25)
			(keepout
				(tracks not_allowed)
				(vias allowed)
				(pads allowed)
				(copperpour not_allowed)
				(footprints allowed)
			)
			(placement
				(enabled no)
				(sheetname "")
			)
			(fill
				(thermal_gap 0.5)
				(thermal_bridge_width 0.5)
				(island_removal_mode 0)
			)
			(polygon
				(pts
					(xy 132.42671 -27.0129) (xy 131.86791 -27.0129) (xy 131.86791 -27.6225) (xy 132.42671 -27.6225)
				)
			)
		)
	)
	(footprint ""
		(layer "B.Cu")
		(at 339.267038 -48.516286 180)
		(property "Reference" "C1200"
			(at 0 0 0)
			(layer "B.SilkS")
			(hide yes)
			(effects
				(font
					(size 1.27 1.27)
				)
				(justify mirror)
			)
		)
		(property "Value" ""
			(at 0 0 0)
			(layer "B.Fab")
			(effects
				(font
					(size 1.27 1.27)
				)
				(justify mirror)
			)
		)
		(duplicate_pad_numbers_are_jumpers no)
		(fp_line
			(start 0.7874 0.4064)
			(end 0.7874 -0.4064)
			(stroke
				(width 0.1524)
				(type default)
			)
			(layer "B.SilkS")
		)
		(fp_line
			(start 0.7874 -0.4064)
			(end -0.7874 -0.4064)
			(stroke
				(width 0.1524)
				(type default)
			)
			(layer "B.SilkS")
		)
		(fp_line
			(start -0.7874 0.4064)
			(end 0.7874 0.4064)
			(stroke
				(width 0.1524)
				(type default)
			)
			(layer "B.SilkS")
		)
		(fp_line
			(start -0.7874 -0.4064)
			(end -0.7874 0.4064)
			(stroke
				(width 0.1524)
				(type default)
			)
			(layer "B.SilkS")
		)
		(fp_line
			(start 0.67945 0.3048)
			(end 0.67945 -0.305054)
			(stroke
				(width 0.1)
				(type default)
			)
			(layer "B.Fab")
		)
		(fp_line
			(start 0.67945 -0.305054)
			(end 0.12065 -0.305054)
			(stroke
				(width 0.1)
				(type default)
			)
			(layer "B.Fab")
		)
		(fp_line
			(start 0.12065 0.3048)
			(end 0.67945 0.3048)
			(stroke
				(width 0.1)
				(type default)
			)
			(layer "B.Fab")
		)
		(fp_line
			(start 0.12065 0.2794)
			(end 0.12065 0.3048)
			(stroke
				(width 0.1)
				(type default)
			)
			(layer "B.Fab")
		)
		(fp_line
			(start 0.12065 -0.2794)
			(end -0.12065 -0.2794)
			(stroke
				(width 0.1)
				(type default)
			)
			(layer "B.Fab")
		)
		(fp_line
			(start 0.12065 -0.305054)
			(end 0.12065 -0.2794)
			(stroke
				(width 0.1)
				(type default)
			)
			(layer "B.Fab")
		)
		(fp_line
			(start -0.120396 0.3048)
			(end -0.120396 0.2794)
			(stroke
				(width 0.1)
				(type default)
			)
			(layer "B.Fab")
		)
		(fp_line
			(start -0.120396 0.2794)
			(end 0.12065 0.2794)
			(stroke
				(width 0.1)
				(type default)
			)
			(layer "B.Fab")
		)
		(fp_line
			(start -0.12065 -0.2794)
			(end -0.12065 -0.3048)
			(stroke
				(width 0.1)
				(type default)
			)
			(layer "B.Fab")
		)
		(fp_line
			(start -0.12065 -0.3048)
			(end -0.67945 -0.3048)
			(stroke
				(width 0.1)
				(type default)
			)
			(layer "B.Fab")
		)
		(fp_line
			(start -0.67945 0.3048)
			(end -0.120396 0.3048)
			(stroke
				(width 0.1)
				(type default)
			)
			(layer "B.Fab")
		)
		(fp_line
			(start -0.67945 -0.3048)
			(end -0.67945 0.3048)
			(stroke
				(width 0.1)
				(type default)
			)
			(layer "B.Fab")
		)
		(pad "1" smd circle
			(at 0.40005 0)
			(size 0 0)
			(layers "B.Cu" "B.Mask" "B.Paste")
			(net "P1V05_PCH_AUX")
		)
		(pad "2" smd circle
			(at -0.40005 0)
			(size 0 0)
			(layers "B.Cu" "B.Mask" "B.Paste")
			(net "GND")
		)
	)
	(footprint ""
		(layer "B.Cu")
		(at 429.391572 -317.39332 90)
		(property "Reference" "R3885"
			(at 0 0 90)
			(layer "B.SilkS")
			(hide yes)
			(effects
				(font
					(size 1.27 1.27)
				)
				(justify mirror)
			)
		)
		(property "Value" ""
			(at 0 0 90)
			(layer "B.Fab")
			(effects
				(font
					(size 1.27 1.27)
				)
				(justify mirror)
			)
		)
		(duplicate_pad_numbers_are_jumpers no)
		(fp_line
			(start 0.7874 -0.4064)
			(end -0.7874 -0.4064)
			(stroke
				(width 0.1524)
				(type default)
			)
			(layer "B.SilkS")
		)
		(fp_line
			(start -0.7874 -0.4064)
			(end -0.7874 0.4064)
			(stroke
				(width 0.1524)
				(type default)
			)
			(layer "B.SilkS")
		)
		(fp_line
			(start 0.7874 0.4064)
			(end 0.7874 -0.4064)
			(stroke
				(width 0.1524)
				(type default)
			)
			(layer "B.SilkS")
		)
		(fp_line
			(start -0.7874 0.4064)
			(end 0.7874 0.4064)
			(stroke
				(width 0.1524)
				(type default)
			)
			(layer "B.SilkS")
		)
		(fp_line
			(start 0.67945 -0.305054)
			(end 0.12065 -0.305054)
			(stroke
				(width 0.1)
				(type default)
			)
			(layer "B.Fab")
		)
		(fp_line
			(start 0.12065 -0.305054)
			(end 0.12065 -0.2794)
			(stroke
				(width 0.1)
				(type default)
			)
			(layer "B.Fab")
		)
		(fp_line
			(start -0.12065 -0.3048)
			(end -0.67945 -0.3048)
			(stroke
				(width 0.1)
				(type default)
			)
			(layer "B.Fab")
		)
		(fp_line
			(start -0.67945 -0.3048)
			(end -0.67945 0.3048)
			(stroke
				(width 0.1)
				(type default)
			)
			(layer "B.Fab")
		)
		(fp_line
			(start 0.12065 -0.2794)
			(end -0.12065 -0.2794)
			(stroke
				(width 0.1)
				(type default)
			)
			(layer "B.Fab")
		)
		(fp_line
			(start -0.12065 -0.2794)
			(end -0.12065 -0.3048)
			(stroke
				(width 0.1)
				(type default)
			)
			(layer "B.Fab")
		)
		(fp_line
			(start 0.12065 0.2794)
			(end 0.12065 0.3048)
			(stroke
				(width 0.1)
				(type default)
			)
			(layer "B.Fab")
		)
		(fp_line
			(start -0.120396 0.2794)
			(end 0.12065 0.2794)
			(stroke
				(width 0.1)
				(type default)
			)
			(layer "B.Fab")
		)
		(fp_line
			(start 0.67945 0.3048)
			(end 0.67945 -0.305054)
			(stroke
				(width 0.1)
				(type default)
			)
			(layer "B.Fab")
		)
		(fp_line
			(start 0.12065 0.3048)
			(end 0.67945 0.3048)
			(stroke
				(width 0.1)
				(type default)
			)
			(layer "B.Fab")
		)
		(fp_line
			(start -0.120396 0.3048)
			(end -0.120396 0.2794)
			(stroke
				(width 0.1)
				(type default)
			)
			(layer "B.Fab")
		)
		(fp_line
			(start -0.67945 0.3048)
			(end -0.120396 0.3048)
			(stroke
				(width 0.1)
				(type default)
			)
			(layer "B.Fab")
		)
		(pad "1" smd circle
			(at 0.40005 0 270)
			(size 0 0)
			(layers "B.Cu" "B.Mask" "B.Paste")
			(net "I3C_SPD_DDREFGH_CPU0_LVC1_SCL_2")
		)
		(pad "2" smd circle
			(at -0.40005 0 270)
			(size 0 0)
			(layers "B.Cu" "B.Mask" "B.Paste")
			(net "I3C_SPD_DDREFGH_CPU0_LVC1_SCL")
		)
	)
	(footprint ""
		(layer "B.Cu")
		(at 80.430624 -185.874152 90)
		(property "Reference" "R244"
			(at 0 0 90)
			(layer "B.SilkS")
			(hide yes)
			(effects
				(font
					(size 1.27 1.27)
				)
				(justify mirror)
			)
		)
		(property "Value" ""
			(at 0 0 90)
			(layer "B.Fab")
			(effects
				(font
					(size 1.27 1.27)
				)
				(justify mirror)
			)
		)
		(duplicate_pad_numbers_are_jumpers no)
		(fp_line
			(start 0.7874 -0.4064)
			(end -0.7874 -0.4064)
			(stroke
				(width 0.1524)
				(type default)
			)
			(layer "B.SilkS")
		)
		(fp_line
			(start -0.7874 -0.4064)
			(end -0.7874 0.4064)
			(stroke
				(width 0.1524)
				(type default)
			)
			(layer "B.SilkS")
		)
		(fp_line
			(start 0.7874 0.4064)
			(end 0.7874 -0.4064)
			(stroke
				(width 0.1524)
				(type default)
			)
			(layer "B.SilkS")
		)
		(fp_line
			(start -0.7874 0.4064)
			(end 0.7874 0.4064)
			(stroke
				(width 0.1524)
				(type default)
			)
			(layer "B.SilkS")
		)
		(fp_line
			(start 0.67945 -0.305054)
			(end 0.12065 -0.305054)
			(stroke
				(width 0.1)
				(type default)
			)
			(layer "B.Fab")
		)
		(fp_line
			(start 0.12065 -0.305054)
			(end 0.12065 -0.2794)
			(stroke
				(width 0.1)
				(type default)
			)
			(layer "B.Fab")
		)
		(fp_line
			(start -0.12065 -0.3048)
			(end -0.67945 -0.3048)
			(stroke
				(width 0.1)
				(type default)
			)
			(layer "B.Fab")
		)
		(fp_line
			(start -0.67945 -0.3048)
			(end -0.67945 0.3048)
			(stroke
				(width 0.1)
				(type default)
			)
			(layer "B.Fab")
		)
		(fp_line
			(start 0.12065 -0.2794)
			(end -0.12065 -0.2794)
			(stroke
				(width 0.1)
				(type default)
			)
			(layer "B.Fab")
		)
		(fp_line
			(start -0.12065 -0.2794)
			(end -0.12065 -0.3048)
			(stroke
				(width 0.1)
				(type default)
			)
			(layer "B.Fab")
		)
		(fp_line
			(start 0.12065 0.2794)
			(end 0.12065 0.3048)
			(stroke
				(width 0.1)
				(type default)
			)
			(layer "B.Fab")
		)
		(fp_line
			(start -0.120396 0.2794)
			(end 0.12065 0.2794)
			(stroke
				(width 0.1)
				(type default)
			)
			(layer "B.Fab")
		)
		(fp_line
			(start 0.67945 0.3048)
			(end 0.67945 -0.305054)
			(stroke
				(width 0.1)
				(type default)
			)
			(layer "B.Fab")
		)
		(fp_line
			(start 0.12065 0.3048)
			(end 0.67945 0.3048)
			(stroke
				(width 0.1)
				(type default)
			)
			(layer "B.Fab")
		)
		(fp_line
			(start -0.120396 0.3048)
			(end -0.120396 0.2794)
			(stroke
				(width 0.1)
				(type default)
			)
			(layer "B.Fab")
		)
		(fp_line
			(start -0.67945 0.3048)
			(end -0.120396 0.3048)
			(stroke
				(width 0.1)
				(type default)
			)
			(layer "B.Fab")
		)
		(pad "1" smd circle
			(at 0.40005 0 270)
			(size 0 0)
			(layers "B.Cu" "B.Mask" "B.Paste")
			(net "PVNN_TERM_CPU1")
		)
		(pad "2" smd circle
			(at -0.40005 0 270)
			(size 0 0)
			(layers "B.Cu" "B.Mask" "B.Paste")
			(net "H_CPU1_PROCHOT_LVC1_N")
		)
	)
	(footprint ""
		(layer "B.Cu")
		(at 69.353684 -185.791856 90)
		(property "Reference" "R761"
			(at 0 0 90)
			(layer "B.SilkS")
			(hide yes)
			(effects
				(font
					(size 1.27 1.27)
				)
				(justify mirror)
			)
		)
		(property "Value" ""
			(at 0 0 90)
			(layer "B.Fab")
			(effects
				(font
					(size 1.27 1.27)
				)
				(justify mirror)
			)
		)
		(duplicate_pad_numbers_are_jumpers no)
		(fp_line
			(start 0.7874 -0.4064)
			(end -0.7874 -0.4064)
			(stroke
				(width 0.1524)
				(type default)
			)
			(layer "B.SilkS")
		)
		(fp_line
			(start -0.7874 -0.4064)
			(end -0.7874 0.4064)
			(stroke
				(width 0.1524)
				(type default)
			)
			(layer "B.SilkS")
		)
		(fp_line
			(start 0.7874 0.4064)
			(end 0.7874 -0.4064)
			(stroke
				(width 0.1524)
				(type default)
			)
			(layer "B.SilkS")
		)
		(fp_line
			(start -0.7874 0.4064)
			(end 0.7874 0.4064)
			(stroke
				(width 0.1524)
				(type default)
			)
			(layer "B.SilkS")
		)
		(fp_line
			(start 0.67945 -0.305054)
			(end 0.12065 -0.305054)
			(stroke
				(width 0.1)
				(type default)
			)
			(layer "B.Fab")
		)
		(fp_line
			(start 0.12065 -0.305054)
			(end 0.12065 -0.2794)
			(stroke
				(width 0.1)
				(type default)
			)
			(layer "B.Fab")
		)
		(fp_line
			(start -0.12065 -0.3048)
			(end -0.67945 -0.3048)
			(stroke
				(width 0.1)
				(type default)
			)
			(layer "B.Fab")
		)
		(fp_line
			(start -0.67945 -0.3048)
			(end -0.67945 0.3048)
			(stroke
				(width 0.1)
				(type default)
			)
			(layer "B.Fab")
		)
		(fp_line
			(start 0.12065 -0.2794)
			(end -0.12065 -0.2794)
			(stroke
				(width 0.1)
				(type default)
			)
			(layer "B.Fab")
		)
		(fp_line
			(start -0.12065 -0.2794)
			(end -0.12065 -0.3048)
			(stroke
				(width 0.1)
				(type default)
			)
			(layer "B.Fab")
		)
		(fp_line
			(start 0.12065 0.2794)
			(end 0.12065 0.3048)
			(stroke
				(width 0.1)
				(type default)
			)
			(layer "B.Fab")
		)
		(fp_line
			(start -0.120396 0.2794)
			(end 0.12065 0.2794)
			(stroke
				(width 0.1)
				(type default)
			)
			(layer "B.Fab")
		)
		(fp_line
			(start 0.67945 0.3048)
			(end 0.67945 -0.305054)
			(stroke
				(width 0.1)
				(type default)
			)
			(layer "B.Fab")
		)
		(fp_line
			(start 0.12065 0.3048)
			(end 0.67945 0.3048)
			(stroke
				(width 0.1)
				(type default)
			)
			(layer "B.Fab")
		)
		(fp_line
			(start -0.120396 0.3048)
			(end -0.120396 0.2794)
			(stroke
				(width 0.1)
				(type default)
			)
			(layer "B.Fab")
		)
		(fp_line
			(start -0.67945 0.3048)
			(end -0.120396 0.3048)
			(stroke
				(width 0.1)
				(type default)
			)
			(layer "B.Fab")
		)
		(pad "1" smd circle
			(at 0.40005 0 270)
			(size 0 0)
			(layers "B.Cu" "B.Mask" "B.Paste")
			(net "PVNN_TERM_CPU0")
		)
		(pad "2" smd circle
			(at -0.40005 0 270)
			(size 0 0)
			(layers "B.Cu" "B.Mask" "B.Paste")
			(net "DBP_CPU_HOOK9_MBP3_GTL_QS_N")
		)
	)
	(footprint ""
		(layer "B.Cu")
		(at 339.298534 -2.156206 180)
		(property "Reference" "J70"
			(at 4.248404 -1.165606 270)
			(unlocked yes)
			(layer "B.SilkS")
			(effects
				(font
					(size 0.7874 0.5842)
					(thickness 0.1524)
				)
				(justify left mirror)
			)
		)
		(property "Value" ""
			(at 0 0 0)
			(layer "B.Fab")
			(effects
				(font
					(size 1.27 1.27)
				)
				(justify mirror)
			)
		)
		(duplicate_pad_numbers_are_jumpers no)
		(fp_line
			(start 1.2192 2.1082)
			(end 1.2192 -2.1082)
			(stroke
				(width 0.1524)
				(type default)
			)
			(layer "B.SilkS")
		)
		(fp_line
			(start 1.2192 -2.1082)
			(end -1.2192 -2.1082)
			(stroke
				(width 0.1524)
				(type default)
			)
			(layer "B.SilkS")
		)
		(fp_line
			(start -1.2192 2.1082)
			(end 1.2192 2.1082)
			(stroke
				(width 0.1524)
				(type default)
			)
			(layer "B.SilkS")
		)
		(fp_line
			(start -1.2192 -2.1082)
			(end -1.2192 2.1082)
			(stroke
				(width 0.1524)
				(type default)
			)
			(layer "B.SilkS")
		)
		(pad "" np_thru_hole circle
			(at -3.4671 -1.27 90)
			(size 1.0414 1.0414)
			(drill 1.0414)
			(layers "*.Cu" "*.Mask")
			(clearance 0.381)
			(thermal_gap 0.381)
		)
		(pad "" np_thru_hole circle
			(at -3.4671 1.27 90)
			(size 1.0414 1.0414)
			(drill 1.0414)
			(layers "*.Cu" "*.Mask")
			(clearance 0.381)
			(thermal_gap 0.381)
		)
		(pad "" np_thru_hole circle
			(at 2.8829 -1.27 90)
			(size 1.0414 1.0414)
			(drill 1.0414)
			(layers "*.Cu" "*.Mask")
			(clearance 0.381)
			(thermal_gap 0.381)
		)
		(pad "" np_thru_hole circle
			(at 2.8829 1.27 90)
			(size 1.0414 1.0414)
			(drill 1.0414)
			(layers "*.Cu" "*.Mask")
			(clearance 0.381)
			(thermal_gap 0.381)
		)
		(pad "1" smd rect
			(at -0.8255 -0.249936 90)
			(size 0.3048 0.508)
			(layers "B.Cu" "B.Mask" "B.Paste")
			(net "DELTA_L_85_5INCH_BOT_DN")
		)
		(pad "2" smd rect
			(at -0.8255 0.249936 90)
			(size 0.3048 0.508)
			(layers "B.Cu" "B.Mask" "B.Paste")
			(net "DELTA_L_85_5INCH_BOT_DP")
		)
		(pad "3" smd circle
			(at 0 0)
			(size 0 0)
			(layers "B.Cu" "B.Mask" "B.Paste")
			(net "DELTA_L_GND_1")
		)
		(zone
			(layers "F.Cu" "B.Cu" "In1.Cu" "In2.Cu" "In3.Cu" "In4.Cu" "In5.Cu" "In6.Cu"
				"In7.Cu" "In8.Cu" "In9.Cu" "In10.Cu" "In11.Cu" "In12.Cu" "In13.Cu" "In14.Cu"
				"In15.Cu" "In16.Cu"
			)
			(hatch none 0.5)
			(connect_pads
				(clearance 0)
			)
			(min_thickness 0.25)
			(keepout
				(tracks not_allowed)
				(vias allowed)
				(pads allowed)
				(copperpour not_allowed)
				(footprints allowed)
			)
			(placement
				(enabled no)
				(sheetname "")
			)
			(fill
				(thermal_gap 0.5)
				(thermal_bridge_width 0.5)
				(island_removal_mode 0)
			)
			(polygon
				(pts
					(arc
						(start 337.342734 -3.426206)
						(mid 335.488534 -3.426206)
						(end 337.342734 -3.426206)
					)
				)
			)
		)
		(zone
			(layers "F.Cu" "B.Cu" "In1.Cu" "In2.Cu" "In3.Cu" "In4.Cu" "In5.Cu" "In6.Cu"
				"In7.Cu" "In8.Cu" "In9.Cu" "In10.Cu" "In11.Cu" "In12.Cu" "In13.Cu" "In14.Cu"
				"In15.Cu" "In16.Cu"
			)
			(hatch none 0.5)
			(connect_pads
				(clearance 0)
			)
			(min_thickness 0.25)
			(keepout
				(tracks not_allowed)
				(vias allowed)
				(pads allowed)
				(copperpour not_allowed)
				(footprints allowed)
			)
			(placement
				(enabled no)
				(sheetname "")
			)
			(fill
				(thermal_gap 0.5)
				(thermal_bridge_width 0.5)
				(island_removal_mode 0)
			)
			(polygon
				(pts
					(arc
						(start 337.342734 -0.886206)
						(mid 335.488534 -0.886206)
						(end 337.342734 -0.886206)
					)
				)
			)
		)
		(zone
			(layers "F.Cu" "B.Cu" "In1.Cu" "In2.Cu" "In3.Cu" "In4.Cu" "In5.Cu" "In6.Cu"
				"In7.Cu" "In8.Cu" "In9.Cu" "In10.Cu" "In11.Cu" "In12.Cu" "In13.Cu" "In14.Cu"
				"In15.Cu" "In16.Cu"
			)
			(hatch none 0.5)
			(connect_pads
				(clearance 0)
			)
			(min_thickness 0.25)
			(keepout
				(tracks not_allowed)
				(vias allowed)
				(pads allowed)
				(copperpour not_allowed)
				(footprints allowed)
			)
			(placement
				(enabled no)
				(sheetname "")
			)
			(fill
				(thermal_gap 0.5)
				(thermal_bridge_width 0.5)
				(island_removal_mode 0)
			)
			(polygon
				(pts
					(arc
						(start 343.692734 -3.426206)
						(mid 341.838534 -3.426206)
						(end 343.692734 -3.426206)
					)
				)
			)
		)
		(zone
			(layers "F.Cu" "B.Cu" "In1.Cu" "In2.Cu" "In3.Cu" "In4.Cu" "In5.Cu" "In6.Cu"
				"In7.Cu" "In8.Cu" "In9.Cu" "In10.Cu" "In11.Cu" "In12.Cu" "In13.Cu" "In14.Cu"
				"In15.Cu" "In16.Cu"
			)
			(hatch none 0.5)
			(connect_pads
				(clearance 0)
			)
			(min_thickness 0.25)
			(keepout
				(tracks not_allowed)
				(vias allowed)
				(pads allowed)
				(copperpour not_allowed)
				(footprints allowed)
			)
			(placement
				(enabled no)
				(sheetname "")
			)
			(fill
				(thermal_gap 0.5)
				(thermal_bridge_width 0.5)
				(island_removal_mode 0)
			)
			(polygon
				(pts
					(arc
						(start 343.692734 -0.886206)
						(mid 341.838534 -0.886206)
						(end 343.692734 -0.886206)
					)
				)
			)
		)
		(zone
			(layer "B.Cu")
			(hatch none 0.5)
			(connect_pads
				(clearance 0)
			)
			(min_thickness 0.25)
			(keepout
				(tracks not_allowed)
				(vias allowed)
				(pads allowed)
				(copperpour not_allowed)
				(footprints allowed)
			)
			(placement
				(enabled no)
				(sheetname "")
			)
			(fill
				(thermal_gap 0.5)
				(thermal_bridge_width 0.5)
				(island_removal_mode 0)
			)
			(polygon
				(pts
					(xy 340.416134 -1.607566) (xy 340.416134 -1.70307) (xy 339.819234 -1.70307) (xy 339.819234 -2.10947)
					(xy 340.416134 -2.10947) (xy 340.416134 -2.202942) (xy 339.819234 -2.202942) (xy 339.819234 -2.609342)
					(xy 340.416134 -2.609342) (xy 340.416134 -2.704846) (xy 339.717634 -2.704846) (xy 339.717634 -1.607566)
				)
			)
		)
	)
	(footprint ""
		(layer "B.Cu")
		(at 214.43188 -55.971948)
		(property "Reference" "R3764"
			(at 0 0 0)
			(layer "B.SilkS")
			(hide yes)
			(effects
				(font
					(size 1.27 1.27)
				)
				(justify mirror)
			)
		)
		(property "Value" ""
			(at 0 0 0)
			(layer "B.Fab")
			(effects
				(font
					(size 1.27 1.27)
				)
				(justify mirror)
			)
		)
		(duplicate_pad_numbers_are_jumpers no)
		(fp_line
			(start -0.7874 -0.4064)
			(end -0.7874 0.4064)
			(stroke
				(width 0.1524)
				(type default)
			)
			(layer "B.SilkS")
		)
		(fp_line
			(start -0.7874 0.4064)
			(end 0.7874 0.4064)
			(stroke
				(width 0.1524)
				(type default)
			)
			(layer "B.SilkS")
		)
		(fp_line
			(start 0.7874 -0.4064)
			(end -0.7874 -0.4064)
			(stroke
				(width 0.1524)
				(type default)
			)
			(layer "B.SilkS")
		)
		(fp_line
			(start 0.7874 0.4064)
			(end 0.7874 -0.4064)
			(stroke
				(width 0.1524)
				(type default)
			)
			(layer "B.SilkS")
		)
		(fp_line
			(start -0.67945 -0.3048)
			(end -0.67945 0.3048)
			(stroke
				(width 0.1)
				(type default)
			)
			(layer "B.Fab")
		)
		(fp_line
			(start -0.67945 0.3048)
			(end -0.120396 0.3048)
			(stroke
				(width 0.1)
				(type default)
			)
			(layer "B.Fab")
		)
		(fp_line
			(start -0.12065 -0.3048)
			(end -0.67945 -0.3048)
			(stroke
				(width 0.1)
				(type default)
			)
			(layer "B.Fab")
		)
		(fp_line
			(start -0.12065 -0.2794)
			(end -0.12065 -0.3048)
			(stroke
				(width 0.1)
				(type default)
			)
			(layer "B.Fab")
		)
		(fp_line
			(start -0.120396 0.2794)
			(end 0.12065 0.2794)
			(stroke
				(width 0.1)
				(type default)
			)
			(layer "B.Fab")
		)
		(fp_line
			(start -0.120396 0.3048)
			(end -0.120396 0.2794)
			(stroke
				(width 0.1)
				(type default)
			)
			(layer "B.Fab")
		)
		(fp_line
			(start 0.12065 -0.305054)
			(end 0.12065 -0.2794)
			(stroke
				(width 0.1)
				(type default)
			)
			(layer "B.Fab")
		)
		(fp_line
			(start 0.12065 -0.2794)
			(end -0.12065 -0.2794)
			(stroke
				(width 0.1)
				(type default)
			)
			(layer "B.Fab")
		)
		(fp_line
			(start 0.12065 0.2794)
			(end 0.12065 0.3048)
			(stroke
				(width 0.1)
				(type default)
			)
			(layer "B.Fab")
		)
		(fp_line
			(start 0.12065 0.3048)
			(end 0.67945 0.3048)
			(stroke
				(width 0.1)
				(type default)
			)
			(layer "B.Fab")
		)
		(fp_line
			(start 0.67945 -0.305054)
			(end 0.12065 -0.305054)
			(stroke
				(width 0.1)
				(type default)
			)
			(layer "B.Fab")
		)
		(fp_line
			(start 0.67945 0.3048)
			(end 0.67945 -0.305054)
			(stroke
				(width 0.1)
				(type default)
			)
			(layer "B.Fab")
		)
		(pad "1" smd circle
			(at 0.40005 0 180)
			(size 0 0)
			(layers "B.Cu" "B.Mask" "B.Paste")
			(net "GND")
		)
		(pad "2" smd circle
			(at -0.40005 0 180)
			(size 0 0)
			(layers "B.Cu" "B.Mask" "B.Paste")
			(net "INA230_2_A0")
		)
	)
	(footprint ""
		(layer "B.Cu")
		(at 117.0432 -96.916748 -90)
		(property "Reference" "R4621"
			(at 0 0 90)
			(layer "B.SilkS")
			(hide yes)
			(effects
				(font
					(size 1.27 1.27)
				)
				(justify mirror)
			)
		)
		(property "Value" ""
			(at 0 0 90)
			(layer "B.Fab")
			(effects
				(font
					(size 1.27 1.27)
				)
				(justify mirror)
			)
		)
		(duplicate_pad_numbers_are_jumpers no)
		(fp_line
			(start -0.7874 0.4064)
			(end 0.7874 0.4064)
			(stroke
				(width 0.1524)
				(type default)
			)
			(layer "B.SilkS")
		)
		(fp_line
			(start 0.7874 0.4064)
			(end 0.7874 -0.4064)
			(stroke
				(width 0.1524)
				(type default)
			)
			(layer "B.SilkS")
		)
		(fp_line
			(start -0.7874 -0.4064)
			(end -0.7874 0.4064)
			(stroke
				(width 0.1524)
				(type default)
			)
			(layer "B.SilkS")
		)
		(fp_line
			(start 0.7874 -0.4064)
			(end -0.7874 -0.4064)
			(stroke
				(width 0.1524)
				(type default)
			)
			(layer "B.SilkS")
		)
		(fp_line
			(start -0.67945 0.3048)
			(end -0.120396 0.3048)
			(stroke
				(width 0.1)
				(type default)
			)
			(layer "B.Fab")
		)
		(fp_line
			(start -0.120396 0.3048)
			(end -0.120396 0.2794)
			(stroke
				(width 0.1)
				(type default)
			)
			(layer "B.Fab")
		)
		(fp_line
			(start 0.12065 0.3048)
			(end 0.67945 0.3048)
			(stroke
				(width 0.1)
				(type default)
			)
			(layer "B.Fab")
		)
		(fp_line
			(start 0.67945 0.3048)
			(end 0.67945 -0.305054)
			(stroke
				(width 0.1)
				(type default)
			)
			(layer "B.Fab")
		)
		(fp_line
			(start -0.120396 0.2794)
			(end 0.12065 0.2794)
			(stroke
				(width 0.1)
				(type default)
			)
			(layer "B.Fab")
		)
		(fp_line
			(start 0.12065 0.2794)
			(end 0.12065 0.3048)
			(stroke
				(width 0.1)
				(type default)
			)
			(layer "B.Fab")
		)
		(fp_line
			(start -0.12065 -0.2794)
			(end -0.12065 -0.3048)
			(stroke
				(width 0.1)
				(type default)
			)
			(layer "B.Fab")
		)
		(fp_line
			(start 0.12065 -0.2794)
			(end -0.12065 -0.2794)
			(stroke
				(width 0.1)
				(type default)
			)
			(layer "B.Fab")
		)
		(fp_line
			(start -0.67945 -0.3048)
			(end -0.67945 0.3048)
			(stroke
				(width 0.1)
				(type default)
			)
			(layer "B.Fab")
		)
		(fp_line
			(start -0.12065 -0.3048)
			(end -0.67945 -0.3048)
			(stroke
				(width 0.1)
				(type default)
			)
			(layer "B.Fab")
		)
		(fp_line
			(start 0.12065 -0.305054)
			(end 0.12065 -0.2794)
			(stroke
				(width 0.1)
				(type default)
			)
			(layer "B.Fab")
		)
		(fp_line
			(start 0.67945 -0.305054)
			(end 0.12065 -0.305054)
			(stroke
				(width 0.1)
				(type default)
			)
			(layer "B.Fab")
		)
		(pad "1" smd circle
			(at 0.40005 0 90)
			(size 0 0)
			(layers "B.Cu" "B.Mask" "B.Paste")
			(net "H_CPU_CATERR_LVC2_BMC_R_N")
		)
		(pad "2" smd circle
			(at -0.40005 0 90)
			(size 0 0)
			(layers "B.Cu" "B.Mask" "B.Paste")
			(net "H_CPU_CATERR_LVC2_BMC_N")
		)
	)
	(footprint ""
		(layer "B.Cu")
		(at 201.961496 -194.054984)
		(property "Reference" "R737"
			(at 0 0 0)
			(layer "B.SilkS")
			(hide yes)
			(effects
				(font
					(size 1.27 1.27)
				)
				(justify mirror)
			)
		)
		(property "Value" ""
			(at 0 0 0)
			(layer "B.Fab")
			(effects
				(font
					(size 1.27 1.27)
				)
				(justify mirror)
			)
		)
		(duplicate_pad_numbers_are_jumpers no)
		(fp_line
			(start -0.7874 -0.4064)
			(end -0.7874 0.4064)
			(stroke
				(width 0.1524)
				(type default)
			)
			(layer "B.SilkS")
		)
		(fp_line
			(start -0.7874 0.4064)
			(end 0.7874 0.4064)
			(stroke
				(width 0.1524)
				(type default)
			)
			(layer "B.SilkS")
		)
		(fp_line
			(start 0.7874 -0.4064)
			(end -0.7874 -0.4064)
			(stroke
				(width 0.1524)
				(type default)
			)
			(layer "B.SilkS")
		)
		(fp_line
			(start 0.7874 0.4064)
			(end 0.7874 -0.4064)
			(stroke
				(width 0.1524)
				(type default)
			)
			(layer "B.SilkS")
		)
		(fp_line
			(start -0.67945 -0.3048)
			(end -0.67945 0.3048)
			(stroke
				(width 0.1)
				(type default)
			)
			(layer "B.Fab")
		)
		(fp_line
			(start -0.67945 0.3048)
			(end -0.120396 0.3048)
			(stroke
				(width 0.1)
				(type default)
			)
			(layer "B.Fab")
		)
		(fp_line
			(start -0.12065 -0.3048)
			(end -0.67945 -0.3048)
			(stroke
				(width 0.1)
				(type default)
			)
			(layer "B.Fab")
		)
		(fp_line
			(start -0.12065 -0.2794)
			(end -0.12065 -0.3048)
			(stroke
				(width 0.1)
				(type default)
			)
			(layer "B.Fab")
		)
		(fp_line
			(start -0.120396 0.2794)
			(end 0.12065 0.2794)
			(stroke
				(width 0.1)
				(type default)
			)
			(layer "B.Fab")
		)
		(fp_line
			(start -0.120396 0.3048)
			(end -0.120396 0.2794)
			(stroke
				(width 0.1)
				(type default)
			)
			(layer "B.Fab")
		)
		(fp_line
			(start 0.12065 -0.305054)
			(end 0.12065 -0.2794)
			(stroke
				(width 0.1)
				(type default)
			)
			(layer "B.Fab")
		)
		(fp_line
			(start 0.12065 -0.2794)
			(end -0.12065 -0.2794)
			(stroke
				(width 0.1)
				(type default)
			)
			(layer "B.Fab")
		)
		(fp_line
			(start 0.12065 0.2794)
			(end 0.12065 0.3048)
			(stroke
				(width 0.1)
				(type default)
			)
			(layer "B.Fab")
		)
		(fp_line
			(start 0.12065 0.3048)
			(end 0.67945 0.3048)
			(stroke
				(width 0.1)
				(type default)
			)
			(layer "B.Fab")
		)
		(fp_line
			(start 0.67945 -0.305054)
			(end 0.12065 -0.305054)
			(stroke
				(width 0.1)
				(type default)
			)
			(layer "B.Fab")
		)
		(fp_line
			(start 0.67945 0.3048)
			(end 0.67945 -0.305054)
			(stroke
				(width 0.1)
				(type default)
			)
			(layer "B.Fab")
		)
		(pad "1" smd circle
			(at 0.40005 0 180)
			(size 0 0)
			(layers "B.Cu" "B.Mask" "B.Paste")
			(net "FM_CPU1_SKTOCC_LVT3_N")
		)
		(pad "2" smd circle
			(at -0.40005 0 180)
			(size 0 0)
			(layers "B.Cu" "B.Mask" "B.Paste")
			(net "FM_CPU1_SKTOCC_N")
		)
	)
	(footprint ""
		(layer "B.Cu")
		(at 419.91788 -156.632148 -90)
		(property "Reference" "PR97"
			(at 0 0 90)
			(layer "B.SilkS")
			(hide yes)
			(effects
				(font
					(size 1.27 1.27)
				)
				(justify mirror)
			)
		)
		(property "Value" ""
			(at 0 0 90)
			(layer "B.Fab")
			(effects
				(font
					(size 1.27 1.27)
				)
				(justify mirror)
			)
		)
		(duplicate_pad_numbers_are_jumpers no)
		(fp_line
			(start -0.7874 0.4064)
			(end 0.7874 0.4064)
			(stroke
				(width 0.1524)
				(type default)
			)
			(layer "B.SilkS")
		)
		(fp_line
			(start 0.7874 0.4064)
			(end 0.7874 -0.4064)
			(stroke
				(width 0.1524)
				(type default)
			)
			(layer "B.SilkS")
		)
		(fp_line
			(start -0.7874 -0.4064)
			(end -0.7874 0.4064)
			(stroke
				(width 0.1524)
				(type default)
			)
			(layer "B.SilkS")
		)
		(fp_line
			(start 0.7874 -0.4064)
			(end -0.7874 -0.4064)
			(stroke
				(width 0.1524)
				(type default)
			)
			(layer "B.SilkS")
		)
		(fp_line
			(start -0.67945 0.3048)
			(end -0.120396 0.3048)
			(stroke
				(width 0.1)
				(type default)
			)
			(layer "B.Fab")
		)
		(fp_line
			(start -0.120396 0.3048)
			(end -0.120396 0.2794)
			(stroke
				(width 0.1)
				(type default)
			)
			(layer "B.Fab")
		)
		(fp_line
			(start 0.12065 0.3048)
			(end 0.67945 0.3048)
			(stroke
				(width 0.1)
				(type default)
			)
			(layer "B.Fab")
		)
		(fp_line
			(start 0.67945 0.3048)
			(end 0.67945 -0.305054)
			(stroke
				(width 0.1)
				(type default)
			)
			(layer "B.Fab")
		)
		(fp_line
			(start -0.120396 0.2794)
			(end 0.12065 0.2794)
			(stroke
				(width 0.1)
				(type default)
			)
			(layer "B.Fab")
		)
		(fp_line
			(start 0.12065 0.2794)
			(end 0.12065 0.3048)
			(stroke
				(width 0.1)
				(type default)
			)
			(layer "B.Fab")
		)
		(fp_line
			(start -0.12065 -0.2794)
			(end -0.12065 -0.3048)
			(stroke
				(width 0.1)
				(type default)
			)
			(layer "B.Fab")
		)
		(fp_line
			(start 0.12065 -0.2794)
			(end -0.12065 -0.2794)
			(stroke
				(width 0.1)
				(type default)
			)
			(layer "B.Fab")
		)
		(fp_line
			(start -0.67945 -0.3048)
			(end -0.67945 0.3048)
			(stroke
				(width 0.1)
				(type default)
			)
			(layer "B.Fab")
		)
		(fp_line
			(start -0.12065 -0.3048)
			(end -0.67945 -0.3048)
			(stroke
				(width 0.1)
				(type default)
			)
			(layer "B.Fab")
		)
		(fp_line
			(start 0.12065 -0.305054)
			(end 0.12065 -0.2794)
			(stroke
				(width 0.1)
				(type default)
			)
			(layer "B.Fab")
		)
		(fp_line
			(start 0.67945 -0.305054)
			(end 0.12065 -0.305054)
			(stroke
				(width 0.1)
				(type default)
			)
			(layer "B.Fab")
		)
		(pad "1" smd circle
			(at 0.40005 0 90)
			(size 0 0)
			(layers "B.Cu" "B.Mask" "B.Paste")
			(net "PVCCFA_EHV_CPU0_PVCC")
		)
		(pad "2" smd circle
			(at -0.40005 0 90)
			(size 0 0)
			(layers "B.Cu" "B.Mask" "B.Paste")
			(net "PVCCFA_EHV_CPU0_VDD1")
		)
	)
	(footprint ""
		(layer "B.Cu")
		(at 433.077366 -311.86374 90)
		(property "Reference" "R2500"
			(at 0 0 90)
			(layer "B.SilkS")
			(hide yes)
			(effects
				(font
					(size 1.27 1.27)
				)
				(justify mirror)
			)
		)
		(property "Value" ""
			(at 0 0 90)
			(layer "B.Fab")
			(effects
				(font
					(size 1.27 1.27)
				)
				(justify mirror)
			)
		)
		(duplicate_pad_numbers_are_jumpers no)
		(fp_line
			(start 0.7874 -0.4064)
			(end -0.7874 -0.4064)
			(stroke
				(width 0.1524)
				(type default)
			)
			(layer "B.SilkS")
		)
		(fp_line
			(start -0.7874 -0.4064)
			(end -0.7874 0.4064)
			(stroke
				(width 0.1524)
				(type default)
			)
			(layer "B.SilkS")
		)
		(fp_line
			(start 0.7874 0.4064)
			(end 0.7874 -0.4064)
			(stroke
				(width 0.1524)
				(type default)
			)
			(layer "B.SilkS")
		)
		(fp_line
			(start -0.7874 0.4064)
			(end 0.7874 0.4064)
			(stroke
				(width 0.1524)
				(type default)
			)
			(layer "B.SilkS")
		)
		(fp_line
			(start 0.67945 -0.305054)
			(end 0.12065 -0.305054)
			(stroke
				(width 0.1)
				(type default)
			)
			(layer "B.Fab")
		)
		(fp_line
			(start 0.12065 -0.305054)
			(end 0.12065 -0.2794)
			(stroke
				(width 0.1)
				(type default)
			)
			(layer "B.Fab")
		)
		(fp_line
			(start -0.12065 -0.3048)
			(end -0.67945 -0.3048)
			(stroke
				(width 0.1)
				(type default)
			)
			(layer "B.Fab")
		)
		(fp_line
			(start -0.67945 -0.3048)
			(end -0.67945 0.3048)
			(stroke
				(width 0.1)
				(type default)
			)
			(layer "B.Fab")
		)
		(fp_line
			(start 0.12065 -0.2794)
			(end -0.12065 -0.2794)
			(stroke
				(width 0.1)
				(type default)
			)
			(layer "B.Fab")
		)
		(fp_line
			(start -0.12065 -0.2794)
			(end -0.12065 -0.3048)
			(stroke
				(width 0.1)
				(type default)
			)
			(layer "B.Fab")
		)
		(fp_line
			(start 0.12065 0.2794)
			(end 0.12065 0.3048)
			(stroke
				(width 0.1)
				(type default)
			)
			(layer "B.Fab")
		)
		(fp_line
			(start -0.120396 0.2794)
			(end 0.12065 0.2794)
			(stroke
				(width 0.1)
				(type default)
			)
			(layer "B.Fab")
		)
		(fp_line
			(start 0.67945 0.3048)
			(end 0.67945 -0.305054)
			(stroke
				(width 0.1)
				(type default)
			)
			(layer "B.Fab")
		)
		(fp_line
			(start 0.12065 0.3048)
			(end 0.67945 0.3048)
			(stroke
				(width 0.1)
				(type default)
			)
			(layer "B.Fab")
		)
		(fp_line
			(start -0.120396 0.3048)
			(end -0.120396 0.2794)
			(stroke
				(width 0.1)
				(type default)
			)
			(layer "B.Fab")
		)
		(fp_line
			(start -0.67945 0.3048)
			(end -0.120396 0.3048)
			(stroke
				(width 0.1)
				(type default)
			)
			(layer "B.Fab")
		)
		(pad "1" smd circle
			(at 0.40005 0 270)
			(size 0 0)
			(layers "B.Cu" "B.Mask" "B.Paste")
			(net "PWRGD_FAIL_CPU0_EF_R1")
		)
		(pad "2" smd circle
			(at -0.40005 0 270)
			(size 0 0)
			(layers "B.Cu" "B.Mask" "B.Paste")
			(net "PWRGD_FAIL_CPU0_EF_R")
		)
	)
	(footprint ""
		(layer "B.Cu")
		(at 331.312774 -63.123064 45)
		(property "Reference" "C1258"
			(at 0 0 45)
			(layer "B.SilkS")
			(hide yes)
			(effects
				(font
					(size 1.27 1.27)
				)
				(justify mirror)
			)
		)
		(property "Value" ""
			(at 0 0 45)
			(layer "B.Fab")
			(effects
				(font
					(size 1.27 1.27)
				)
				(justify mirror)
			)
		)
		(duplicate_pad_numbers_are_jumpers no)
		(fp_line
			(start -1.523949 -0.762065)
			(end -1.523949 0.762065)
			(stroke
				(width 0.1524)
				(type default)
			)
			(layer "B.SilkS")
		)
		(fp_line
			(start -1.523949 0.762065)
			(end 1.523949 0.762065)
			(stroke
				(width 0.1524)
				(type default)
			)
			(layer "B.SilkS")
		)
		(fp_line
			(start 1.523949 -0.762065)
			(end -1.523949 -0.762065)
			(stroke
				(width 0.1524)
				(type default)
			)
			(layer "B.SilkS")
		)
		(fp_line
			(start 1.523949 0.762065)
			(end 1.523949 -0.762065)
			(stroke
				(width 0.1524)
				(type default)
			)
			(layer "B.SilkS")
		)
		(fp_line
			(start -1.104931 -0.724886)
			(end 1.104931 -0.724886)
			(stroke
				(width 0.1)
				(type default)
			)
			(layer "B.Fab")
		)
		(fp_line
			(start -1.104931 0.724886)
			(end -1.104931 -0.724886)
			(stroke
				(width 0.1)
				(type default)
			)
			(layer "B.Fab")
		)
		(fp_line
			(start 1.104931 -0.724886)
			(end 1.104931 0.724886)
			(stroke
				(width 0.1)
				(type default)
			)
			(layer "B.Fab")
		)
		(fp_line
			(start 1.104931 0.724886)
			(end -1.104931 0.724886)
			(stroke
				(width 0.1)
				(type default)
			)
			(layer "B.Fab")
		)
		(pad "1" smd rect
			(at 0.889 0 45)
			(size 1.016 1.27)
			(layers "B.Cu" "B.Mask" "B.Paste")
			(net "P1V05_PCH_PLL_AUX")
		)
		(pad "2" smd rect
			(at -0.889 0 45)
			(size 1.016 1.27)
			(layers "B.Cu" "B.Mask" "B.Paste")
			(net "GND")
		)
	)
	(footprint ""
		(layer "B.Cu")
		(at 121.830084 -359.596436 -90)
		(property "Reference" "PJ67"
			(at -4.219702 -2.927096 0)
			(unlocked yes)
			(layer "B.SilkS")
			(effects
				(font
					(size 0.7874 0.5842)
					(thickness 0.1524)
				)
				(justify left mirror)
			)
		)
		(property "Value" ""
			(at 0 0 90)
			(layer "B.Fab")
			(effects
				(font
					(size 1.27 1.27)
				)
				(justify mirror)
			)
		)
		(duplicate_pad_numbers_are_jumpers no)
		(pad "1" smd circle
			(at 0.7493 0)
			(size 0 0)
			(layers "B.Cu" "B.Mask" "B.Paste")
			(net "SH_PVPP_HBM_CPU1_N")
		)
		(pad "2" smd rect
			(at -0.7493 0 180)
			(size 0.7112 0.8128)
			(layers "B.Cu" "B.Mask" "B.Paste")
			(net "GND")
		)
		(zone
			(layer "B.Cu")
			(hatch none 0.5)
			(connect_pads
				(clearance 0)
			)
			(min_thickness 0.25)
			(keepout
				(tracks allowed)
				(vias not_allowed)
				(pads allowed)
				(copperpour not_allowed)
				(footprints allowed)
			)
			(placement
				(enabled no)
				(sheetname "")
			)
			(fill
				(thermal_gap 0.5)
				(thermal_bridge_width 0.5)
				(island_removal_mode 0)
			)
			(polygon
				(pts
					(xy 121.418858 -358.415336) (xy 122.236484 -358.415336) (xy 122.236484 -360.802936) (xy 121.418858 -360.802936)
				)
			)
		)
	)
	(footprint ""
		(layer "B.Cu")
		(at 335.741264 -184.827926 90)
		(property "Reference" "R21"
			(at 0 0 90)
			(layer "B.SilkS")
			(hide yes)
			(effects
				(font
					(size 1.27 1.27)
				)
				(justify mirror)
			)
		)
		(property "Value" ""
			(at 0 0 90)
			(layer "B.Fab")
			(effects
				(font
					(size 1.27 1.27)
				)
				(justify mirror)
			)
		)
		(duplicate_pad_numbers_are_jumpers no)
		(fp_line
			(start 0.7874 -0.4064)
			(end -0.7874 -0.4064)
			(stroke
				(width 0.1524)
				(type default)
			)
			(layer "B.SilkS")
		)
		(fp_line
			(start -0.7874 -0.4064)
			(end -0.7874 0.4064)
			(stroke
				(width 0.1524)
				(type default)
			)
			(layer "B.SilkS")
		)
		(fp_line
			(start 0.7874 0.4064)
			(end 0.7874 -0.4064)
			(stroke
				(width 0.1524)
				(type default)
			)
			(layer "B.SilkS")
		)
		(fp_line
			(start -0.7874 0.4064)
			(end 0.7874 0.4064)
			(stroke
				(width 0.1524)
				(type default)
			)
			(layer "B.SilkS")
		)
		(fp_line
			(start 0.67945 -0.305054)
			(end 0.12065 -0.305054)
			(stroke
				(width 0.1)
				(type default)
			)
			(layer "B.Fab")
		)
		(fp_line
			(start 0.12065 -0.305054)
			(end 0.12065 -0.2794)
			(stroke
				(width 0.1)
				(type default)
			)
			(layer "B.Fab")
		)
		(fp_line
			(start -0.12065 -0.3048)
			(end -0.67945 -0.3048)
			(stroke
				(width 0.1)
				(type default)
			)
			(layer "B.Fab")
		)
		(fp_line
			(start -0.67945 -0.3048)
			(end -0.67945 0.3048)
			(stroke
				(width 0.1)
				(type default)
			)
			(layer "B.Fab")
		)
		(fp_line
			(start 0.12065 -0.2794)
			(end -0.12065 -0.2794)
			(stroke
				(width 0.1)
				(type default)
			)
			(layer "B.Fab")
		)
		(fp_line
			(start -0.12065 -0.2794)
			(end -0.12065 -0.3048)
			(stroke
				(width 0.1)
				(type default)
			)
			(layer "B.Fab")
		)
		(fp_line
			(start 0.12065 0.2794)
			(end 0.12065 0.3048)
			(stroke
				(width 0.1)
				(type default)
			)
			(layer "B.Fab")
		)
		(fp_line
			(start -0.120396 0.2794)
			(end 0.12065 0.2794)
			(stroke
				(width 0.1)
				(type default)
			)
			(layer "B.Fab")
		)
		(fp_line
			(start 0.67945 0.3048)
			(end 0.67945 -0.305054)
			(stroke
				(width 0.1)
				(type default)
			)
			(layer "B.Fab")
		)
		(fp_line
			(start 0.12065 0.3048)
			(end 0.67945 0.3048)
			(stroke
				(width 0.1)
				(type default)
			)
			(layer "B.Fab")
		)
		(fp_line
			(start -0.120396 0.3048)
			(end -0.120396 0.2794)
			(stroke
				(width 0.1)
				(type default)
			)
			(layer "B.Fab")
		)
		(fp_line
			(start -0.67945 0.3048)
			(end -0.120396 0.3048)
			(stroke
				(width 0.1)
				(type default)
			)
			(layer "B.Fab")
		)
		(pad "1" smd circle
			(at 0.40005 0 270)
			(size 0 0)
			(layers "B.Cu" "B.Mask" "B.Paste")
			(net "DBP_CPU_MBP1_GTL_N")
		)
		(pad "2" smd circle
			(at -0.40005 0 270)
			(size 0 0)
			(layers "B.Cu" "B.Mask" "B.Paste")
			(net "FM_PCH_TRIGGER1_N")
		)
	)
	(footprint ""
		(layer "B.Cu")
		(at 60.082684 -174.152306)
		(property "Reference" "PC1930"
			(at 0 0 0)
			(layer "B.SilkS")
			(hide yes)
			(effects
				(font
					(size 1.27 1.27)
				)
				(justify mirror)
			)
		)
		(property "Value" ""
			(at 0 0 0)
			(layer "B.Fab")
			(effects
				(font
					(size 1.27 1.27)
				)
				(justify mirror)
			)
		)
		(duplicate_pad_numbers_are_jumpers no)
		(fp_line
			(start -4.533392 -2.249932)
			(end -4.533392 2.249932)
			(stroke
				(width 0.1524)
				(type default)
			)
			(layer "B.SilkS")
		)
		(fp_line
			(start -4.533392 2.249932)
			(end 4.533392 2.249932)
			(stroke
				(width 0.1524)
				(type default)
			)
			(layer "B.SilkS")
		)
		(fp_line
			(start 4.533392 -2.249932)
			(end -4.533392 -2.249932)
			(stroke
				(width 0.1524)
				(type default)
			)
			(layer "B.SilkS")
		)
		(fp_line
			(start 4.533392 2.249932)
			(end 4.533392 -2.249932)
			(stroke
				(width 0.1524)
				(type default)
			)
			(layer "B.SilkS")
		)
		(fp_rect
			(start 4.533392 2.326132)
			(end 5.39242 -2.326132)
			(stroke
				(width 0)
				(type default)
			)
			(fill yes)
			(layer "B.SilkS")
		)
		(fp_line
			(start -3.750056 -2.249932)
			(end -3.750056 2.249932)
			(stroke
				(width 0.1)
				(type default)
			)
			(layer "B.Fab")
		)
		(fp_line
			(start -3.750056 2.249932)
			(end 3.750056 2.249932)
			(stroke
				(width 0.1)
				(type default)
			)
			(layer "B.Fab")
		)
		(fp_line
			(start 3.750056 -2.249932)
			(end -3.750056 -2.249932)
			(stroke
				(width 0.1)
				(type default)
			)
			(layer "B.Fab")
		)
		(fp_line
			(start 3.750056 2.249932)
			(end 3.750056 -2.249932)
			(stroke
				(width 0.1)
				(type default)
			)
			(layer "B.Fab")
		)
		(fp_text user "-"
			(at -4.8514 -0.14605 0)
			(unlocked yes)
			(layer "B.SilkS")
			(effects
				(font
					(size 1.905 1.4224)
					(thickness 0.1524)
				)
				(justify left mirror)
			)
		)
		(fp_text user "+"
			(at 6.322314 0.786384 270)
			(unlocked yes)
			(layer "B.SilkS")
			(effects
				(font
					(size 1.905 1.4224)
					(thickness 0.1524)
				)
				(justify left mirror)
			)
		)
		(fp_text user "-"
			(at -4.8514 -0.14605 0)
			(unlocked yes)
			(layer "B.Fab")
			(effects
				(font
					(size 1.905 1.4224)
					(thickness 0.1524)
				)
				(justify left mirror)
			)
		)
		(fp_text user "+"
			(at 6.322314 0.786384 270)
			(unlocked yes)
			(layer "B.Fab")
			(effects
				(font
					(size 1.905 1.4224)
					(thickness 0.1524)
				)
				(justify left mirror)
			)
		)
		(pad "1" smd rect
			(at 3.199892 0 180)
			(size 2.413 2.8194)
			(layers "B.Cu" "B.Mask" "B.Paste")
			(net "PVCCFA_EHV_CPU1")
		)
		(pad "2" smd rect
			(at -3.199892 0 180)
			(size 2.413 2.8194)
			(layers "B.Cu" "B.Mask" "B.Paste")
			(net "GND")
		)
	)
	(footprint ""
		(layer "B.Cu")
		(at 68.223638 -319.98539 -90)
		(property "Reference" "D46"
			(at -4.247388 -1.898142 0)
			(unlocked yes)
			(layer "B.SilkS")
			(effects
				(font
					(size 0.7874 0.5842)
					(thickness 0.1524)
				)
				(justify left mirror)
			)
		)
		(property "Value" ""
			(at 0 0 90)
			(layer "B.Fab")
			(effects
				(font
					(size 1.27 1.27)
				)
				(justify mirror)
			)
		)
		(duplicate_pad_numbers_are_jumpers no)
		(fp_line
			(start -2.050796 0.700024)
			(end 2.050796 0.700024)
			(stroke
				(width 0.1524)
				(type default)
			)
			(layer "B.SilkS")
		)
		(fp_line
			(start 2.050796 0.700024)
			(end 2.050796 -0.700024)
			(stroke
				(width 0.1524)
				(type default)
			)
			(layer "B.SilkS")
		)
		(fp_line
			(start -2.343404 0.6985)
			(end -2.216404 0.6985)
			(stroke
				(width 0.1524)
				(type default)
			)
			(layer "B.SilkS")
		)
		(fp_line
			(start -2.229104 0.6985)
			(end -2.051304 0.6985)
			(stroke
				(width 0.1524)
				(type default)
			)
			(layer "B.SilkS")
		)
		(fp_line
			(start -2.051304 0.6985)
			(end -2.051304 0.635)
			(stroke
				(width 0.1524)
				(type default)
			)
			(layer "B.SilkS")
		)
		(fp_line
			(start -2.152904 0.635)
			(end -2.152904 -0.6985)
			(stroke
				(width 0.1524)
				(type default)
			)
			(layer "B.SilkS")
		)
		(fp_line
			(start -2.051304 0.635)
			(end -2.152904 0.635)
			(stroke
				(width 0.1524)
				(type default)
			)
			(layer "B.SilkS")
		)
		(fp_line
			(start 0.30607 0.500126)
			(end -0.193802 0)
			(stroke
				(width 0.1524)
				(type default)
			)
			(layer "B.SilkS")
		)
		(fp_line
			(start -0.193802 0)
			(end 0.30607 -0.500126)
			(stroke
				(width 0.1524)
				(type default)
			)
			(layer "B.SilkS")
		)
		(fp_line
			(start -0.293878 -0.500126)
			(end -0.293878 0.500126)
			(stroke
				(width 0.1524)
				(type default)
			)
			(layer "B.SilkS")
		)
		(fp_line
			(start 0.30607 -0.500126)
			(end 0.30607 0.500126)
			(stroke
				(width 0.1524)
				(type default)
			)
			(layer "B.SilkS")
		)
		(fp_line
			(start -2.064004 -0.6731)
			(end -2.064004 -0.6985)
			(stroke
				(width 0.1524)
				(type default)
			)
			(layer "B.SilkS")
		)
		(fp_line
			(start -2.343404 -0.6985)
			(end -2.343404 0.6985)
			(stroke
				(width 0.1524)
				(type default)
			)
			(layer "B.SilkS")
		)
		(fp_line
			(start -2.229104 -0.6985)
			(end -2.229104 0.6985)
			(stroke
				(width 0.1524)
				(type default)
			)
			(layer "B.SilkS")
		)
		(fp_line
			(start -2.152904 -0.6985)
			(end -2.343404 -0.6985)
			(stroke
				(width 0.1524)
				(type default)
			)
			(layer "B.SilkS")
		)
		(fp_line
			(start -2.064004 -0.6985)
			(end -2.229104 -0.6985)
			(stroke
				(width 0.1524)
				(type default)
			)
			(layer "B.SilkS")
		)
		(fp_line
			(start -2.050796 -0.700024)
			(end -2.050796 0.700024)
			(stroke
				(width 0.1524)
				(type default)
			)
			(layer "B.SilkS")
		)
		(fp_line
			(start 2.050796 -0.700024)
			(end -2.050796 -0.700024)
			(stroke
				(width 0.1524)
				(type default)
			)
			(layer "B.SilkS")
		)
		(fp_line
			(start -0.899922 0.700024)
			(end 0.899922 0.700024)
			(stroke
				(width 0.1)
				(type default)
			)
			(layer "B.Fab")
		)
		(fp_line
			(start 0.899922 0.700024)
			(end 0.899922 -0.700024)
			(stroke
				(width 0.1)
				(type default)
			)
			(layer "B.Fab")
		)
		(fp_line
			(start -0.899922 -0.700024)
			(end -0.899922 0.700024)
			(stroke
				(width 0.1)
				(type default)
			)
			(layer "B.Fab")
		)
		(fp_line
			(start 0.899922 -0.700024)
			(end -0.899922 -0.700024)
			(stroke
				(width 0.1)
				(type default)
			)
			(layer "B.Fab")
		)
		(fp_text user "+"
			(at 3.123946 0.762 180)
			(unlocked yes)
			(layer "B.SilkS")
			(effects
				(font
					(size 1.905 1.4224)
					(thickness 0.1524)
				)
				(justify left mirror)
			)
		)
		(fp_text user "-"
			(at -3.880104 0.23495 90)
			(unlocked yes)
			(layer "B.SilkS")
			(effects
				(font
					(size 1.905 1.4224)
					(thickness 0.1524)
				)
				(justify left mirror)
			)
		)
		(fp_text user "+"
			(at 3.123946 0.762 180)
			(unlocked yes)
			(layer "B.Fab")
			(effects
				(font
					(size 1.905 1.4224)
					(thickness 0.1524)
				)
				(justify left mirror)
			)
		)
		(fp_text user "-"
			(at -3.880104 0.23495 90)
			(unlocked yes)
			(layer "B.Fab")
			(effects
				(font
					(size 1.905 1.4224)
					(thickness 0.1524)
				)
				(justify left mirror)
			)
		)
		(pad "1" smd rect
			(at 1.199896 0 180)
			(size 0.6604 1.3716)
			(layers "B.Cu" "B.Mask" "B.Paste")
			(net "PWRGD_FAIL_CPU1_AB_R1")
		)
		(pad "2" smd rect
			(at -1.199896 0)
			(size 0.6604 1.3716)
			(layers "B.Cu" "B.Mask" "B.Paste")
			(net "P3V3_AUX")
		)
	)
	(footprint ""
		(layer "B.Cu")
		(at 334.62849 -51.343814)
		(property "Reference" "C1207"
			(at 0 0 0)
			(layer "B.SilkS")
			(hide yes)
			(effects
				(font
					(size 1.27 1.27)
				)
				(justify mirror)
			)
		)
		(property "Value" ""
			(at 0 0 0)
			(layer "B.Fab")
			(effects
				(font
					(size 1.27 1.27)
				)
				(justify mirror)
			)
		)
		(duplicate_pad_numbers_are_jumpers no)
		(fp_line
			(start -0.7874 -0.4064)
			(end -0.7874 0.4064)
			(stroke
				(width 0.1524)
				(type default)
			)
			(layer "B.SilkS")
		)
		(fp_line
			(start -0.7874 0.4064)
			(end 0.7874 0.4064)
			(stroke
				(width 0.1524)
				(type default)
			)
			(layer "B.SilkS")
		)
		(fp_line
			(start 0.7874 -0.4064)
			(end -0.7874 -0.4064)
			(stroke
				(width 0.1524)
				(type default)
			)
			(layer "B.SilkS")
		)
		(fp_line
			(start 0.7874 0.4064)
			(end 0.7874 -0.4064)
			(stroke
				(width 0.1524)
				(type default)
			)
			(layer "B.SilkS")
		)
		(fp_line
			(start -0.67945 -0.3048)
			(end -0.67945 0.3048)
			(stroke
				(width 0.1)
				(type default)
			)
			(layer "B.Fab")
		)
		(fp_line
			(start -0.67945 0.3048)
			(end -0.120396 0.3048)
			(stroke
				(width 0.1)
				(type default)
			)
			(layer "B.Fab")
		)
		(fp_line
			(start -0.12065 -0.3048)
			(end -0.67945 -0.3048)
			(stroke
				(width 0.1)
				(type default)
			)
			(layer "B.Fab")
		)
		(fp_line
			(start -0.12065 -0.2794)
			(end -0.12065 -0.3048)
			(stroke
				(width 0.1)
				(type default)
			)
			(layer "B.Fab")
		)
		(fp_line
			(start -0.120396 0.2794)
			(end 0.12065 0.2794)
			(stroke
				(width 0.1)
				(type default)
			)
			(layer "B.Fab")
		)
		(fp_line
			(start -0.120396 0.3048)
			(end -0.120396 0.2794)
			(stroke
				(width 0.1)
				(type default)
			)
			(layer "B.Fab")
		)
		(fp_line
			(start 0.12065 -0.305054)
			(end 0.12065 -0.2794)
			(stroke
				(width 0.1)
				(type default)
			)
			(layer "B.Fab")
		)
		(fp_line
			(start 0.12065 -0.2794)
			(end -0.12065 -0.2794)
			(stroke
				(width 0.1)
				(type default)
			)
			(layer "B.Fab")
		)
		(fp_line
			(start 0.12065 0.2794)
			(end 0.12065 0.3048)
			(stroke
				(width 0.1)
				(type default)
			)
			(layer "B.Fab")
		)
		(fp_line
			(start 0.12065 0.3048)
			(end 0.67945 0.3048)
			(stroke
				(width 0.1)
				(type default)
			)
			(layer "B.Fab")
		)
		(fp_line
			(start 0.67945 -0.305054)
			(end 0.12065 -0.305054)
			(stroke
				(width 0.1)
				(type default)
			)
			(layer "B.Fab")
		)
		(fp_line
			(start 0.67945 0.3048)
			(end 0.67945 -0.305054)
			(stroke
				(width 0.1)
				(type default)
			)
			(layer "B.Fab")
		)
		(pad "1" smd circle
			(at 0.40005 0 180)
			(size 0 0)
			(layers "B.Cu" "B.Mask" "B.Paste")
			(net "P1V8_PCH_AUX")
		)
		(pad "2" smd circle
			(at -0.40005 0 180)
			(size 0 0)
			(layers "B.Cu" "B.Mask" "B.Paste")
			(net "GND")
		)
	)
	(footprint ""
		(layer "B.Cu")
		(at 98.50374 -422.156128 90)
		(property "Reference" "R4546"
			(at 0 0 90)
			(layer "B.SilkS")
			(hide yes)
			(effects
				(font
					(size 1.27 1.27)
				)
				(justify mirror)
			)
		)
		(property "Value" ""
			(at 0 0 90)
			(layer "B.Fab")
			(effects
				(font
					(size 1.27 1.27)
				)
				(justify mirror)
			)
		)
		(duplicate_pad_numbers_are_jumpers no)
		(fp_line
			(start 0.7874 -0.4064)
			(end -0.7874 -0.4064)
			(stroke
				(width 0.1524)
				(type default)
			)
			(layer "B.SilkS")
		)
		(fp_line
			(start -0.7874 -0.4064)
			(end -0.7874 0.4064)
			(stroke
				(width 0.1524)
				(type default)
			)
			(layer "B.SilkS")
		)
		(fp_line
			(start 0.7874 0.4064)
			(end 0.7874 -0.4064)
			(stroke
				(width 0.1524)
				(type default)
			)
			(layer "B.SilkS")
		)
		(fp_line
			(start -0.7874 0.4064)
			(end 0.7874 0.4064)
			(stroke
				(width 0.1524)
				(type default)
			)
			(layer "B.SilkS")
		)
		(fp_line
			(start 0.67945 -0.305054)
			(end 0.12065 -0.305054)
			(stroke
				(width 0.1)
				(type default)
			)
			(layer "B.Fab")
		)
		(fp_line
			(start 0.12065 -0.305054)
			(end 0.12065 -0.2794)
			(stroke
				(width 0.1)
				(type default)
			)
			(layer "B.Fab")
		)
		(fp_line
			(start -0.12065 -0.3048)
			(end -0.67945 -0.3048)
			(stroke
				(width 0.1)
				(type default)
			)
			(layer "B.Fab")
		)
		(fp_line
			(start -0.67945 -0.3048)
			(end -0.67945 0.3048)
			(stroke
				(width 0.1)
				(type default)
			)
			(layer "B.Fab")
		)
		(fp_line
			(start 0.12065 -0.2794)
			(end -0.12065 -0.2794)
			(stroke
				(width 0.1)
				(type default)
			)
			(layer "B.Fab")
		)
		(fp_line
			(start -0.12065 -0.2794)
			(end -0.12065 -0.3048)
			(stroke
				(width 0.1)
				(type default)
			)
			(layer "B.Fab")
		)
		(fp_line
			(start 0.12065 0.2794)
			(end 0.12065 0.3048)
			(stroke
				(width 0.1)
				(type default)
			)
			(layer "B.Fab")
		)
		(fp_line
			(start -0.120396 0.2794)
			(end 0.12065 0.2794)
			(stroke
				(width 0.1)
				(type default)
			)
			(layer "B.Fab")
		)
		(fp_line
			(start 0.67945 0.3048)
			(end 0.67945 -0.305054)
			(stroke
				(width 0.1)
				(type default)
			)
			(layer "B.Fab")
		)
		(fp_line
			(start 0.12065 0.3048)
			(end 0.67945 0.3048)
			(stroke
				(width 0.1)
				(type default)
			)
			(layer "B.Fab")
		)
		(fp_line
			(start -0.120396 0.3048)
			(end -0.120396 0.2794)
			(stroke
				(width 0.1)
				(type default)
			)
			(layer "B.Fab")
		)
		(fp_line
			(start -0.67945 0.3048)
			(end -0.120396 0.3048)
			(stroke
				(width 0.1)
				(type default)
			)
			(layer "B.Fab")
		)
		(pad "1" smd circle
			(at 0.40005 0 270)
			(size 0 0)
			(layers "B.Cu" "B.Mask" "B.Paste")
			(net "P3V3_AUX")
		)
		(pad "2" smd circle
			(at -0.40005 0 270)
			(size 0 0)
			(layers "B.Cu" "B.Mask" "B.Paste")
			(net "HGX_DETECT_N_ISO")
		)
	)
	(footprint ""
		(layer "B.Cu")
		(at 258.384802 -105.911396)
		(property "Reference" "R1194"
			(at 0 0 0)
			(layer "B.SilkS")
			(hide yes)
			(effects
				(font
					(size 1.27 1.27)
				)
				(justify mirror)
			)
		)
		(property "Value" ""
			(at 0 0 0)
			(layer "B.Fab")
			(effects
				(font
					(size 1.27 1.27)
				)
				(justify mirror)
			)
		)
		(duplicate_pad_numbers_are_jumpers no)
		(fp_line
			(start -0.7874 -0.4064)
			(end -0.7874 0.4064)
			(stroke
				(width 0.1524)
				(type default)
			)
			(layer "B.SilkS")
		)
		(fp_line
			(start -0.7874 0.4064)
			(end 0.7874 0.4064)
			(stroke
				(width 0.1524)
				(type default)
			)
			(layer "B.SilkS")
		)
		(fp_line
			(start 0.7874 -0.4064)
			(end -0.7874 -0.4064)
			(stroke
				(width 0.1524)
				(type default)
			)
			(layer "B.SilkS")
		)
		(fp_line
			(start 0.7874 0.4064)
			(end 0.7874 -0.4064)
			(stroke
				(width 0.1524)
				(type default)
			)
			(layer "B.SilkS")
		)
		(fp_line
			(start -0.67945 -0.3048)
			(end -0.67945 0.3048)
			(stroke
				(width 0.1)
				(type default)
			)
			(layer "B.Fab")
		)
		(fp_line
			(start -0.67945 0.3048)
			(end -0.120396 0.3048)
			(stroke
				(width 0.1)
				(type default)
			)
			(layer "B.Fab")
		)
		(fp_line
			(start -0.12065 -0.3048)
			(end -0.67945 -0.3048)
			(stroke
				(width 0.1)
				(type default)
			)
			(layer "B.Fab")
		)
		(fp_line
			(start -0.12065 -0.2794)
			(end -0.12065 -0.3048)
			(stroke
				(width 0.1)
				(type default)
			)
			(layer "B.Fab")
		)
		(fp_line
			(start -0.120396 0.2794)
			(end 0.12065 0.2794)
			(stroke
				(width 0.1)
				(type default)
			)
			(layer "B.Fab")
		)
		(fp_line
			(start -0.120396 0.3048)
			(end -0.120396 0.2794)
			(stroke
				(width 0.1)
				(type default)
			)
			(layer "B.Fab")
		)
		(fp_line
			(start 0.12065 -0.305054)
			(end 0.12065 -0.2794)
			(stroke
				(width 0.1)
				(type default)
			)
			(layer "B.Fab")
		)
		(fp_line
			(start 0.12065 -0.2794)
			(end -0.12065 -0.2794)
			(stroke
				(width 0.1)
				(type default)
			)
			(layer "B.Fab")
		)
		(fp_line
			(start 0.12065 0.2794)
			(end 0.12065 0.3048)
			(stroke
				(width 0.1)
				(type default)
			)
			(layer "B.Fab")
		)
		(fp_line
			(start 0.12065 0.3048)
			(end 0.67945 0.3048)
			(stroke
				(width 0.1)
				(type default)
			)
			(layer "B.Fab")
		)
		(fp_line
			(start 0.67945 -0.305054)
			(end 0.12065 -0.305054)
			(stroke
				(width 0.1)
				(type default)
			)
			(layer "B.Fab")
		)
		(fp_line
			(start 0.67945 0.3048)
			(end 0.67945 -0.305054)
			(stroke
				(width 0.1)
				(type default)
			)
			(layer "B.Fab")
		)
		(pad "1" smd circle
			(at 0.40005 0 180)
			(size 0 0)
			(layers "B.Cu" "B.Mask" "B.Paste")
			(net "P3V3_AUX")
		)
		(pad "2" smd circle
			(at -0.40005 0 180)
			(size 0 0)
			(layers "B.Cu" "B.Mask" "B.Paste")
			(net "FM_CK440_MXCK_25M_100M")
		)
	)
	(footprint ""
		(layer "B.Cu")
		(at 433.564792 -193.565272 -90)
		(property "Reference" "R705"
			(at 0 0 90)
			(layer "B.SilkS")
			(hide yes)
			(effects
				(font
					(size 1.27 1.27)
				)
				(justify mirror)
			)
		)
		(property "Value" ""
			(at 0 0 90)
			(layer "B.Fab")
			(effects
				(font
					(size 1.27 1.27)
				)
				(justify mirror)
			)
		)
		(duplicate_pad_numbers_are_jumpers no)
		(fp_line
			(start -0.7874 0.4064)
			(end 0.7874 0.4064)
			(stroke
				(width 0.1524)
				(type default)
			)
			(layer "B.SilkS")
		)
		(fp_line
			(start 0.7874 0.4064)
			(end 0.7874 -0.4064)
			(stroke
				(width 0.1524)
				(type default)
			)
			(layer "B.SilkS")
		)
		(fp_line
			(start -0.7874 -0.4064)
			(end -0.7874 0.4064)
			(stroke
				(width 0.1524)
				(type default)
			)
			(layer "B.SilkS")
		)
		(fp_line
			(start 0.7874 -0.4064)
			(end -0.7874 -0.4064)
			(stroke
				(width 0.1524)
				(type default)
			)
			(layer "B.SilkS")
		)
		(fp_line
			(start -0.67945 0.3048)
			(end -0.120396 0.3048)
			(stroke
				(width 0.1)
				(type default)
			)
			(layer "B.Fab")
		)
		(fp_line
			(start -0.120396 0.3048)
			(end -0.120396 0.2794)
			(stroke
				(width 0.1)
				(type default)
			)
			(layer "B.Fab")
		)
		(fp_line
			(start 0.12065 0.3048)
			(end 0.67945 0.3048)
			(stroke
				(width 0.1)
				(type default)
			)
			(layer "B.Fab")
		)
		(fp_line
			(start 0.67945 0.3048)
			(end 0.67945 -0.305054)
			(stroke
				(width 0.1)
				(type default)
			)
			(layer "B.Fab")
		)
		(fp_line
			(start -0.120396 0.2794)
			(end 0.12065 0.2794)
			(stroke
				(width 0.1)
				(type default)
			)
			(layer "B.Fab")
		)
		(fp_line
			(start 0.12065 0.2794)
			(end 0.12065 0.3048)
			(stroke
				(width 0.1)
				(type default)
			)
			(layer "B.Fab")
		)
		(fp_line
			(start -0.12065 -0.2794)
			(end -0.12065 -0.3048)
			(stroke
				(width 0.1)
				(type default)
			)
			(layer "B.Fab")
		)
		(fp_line
			(start 0.12065 -0.2794)
			(end -0.12065 -0.2794)
			(stroke
				(width 0.1)
				(type default)
			)
			(layer "B.Fab")
		)
		(fp_line
			(start -0.67945 -0.3048)
			(end -0.67945 0.3048)
			(stroke
				(width 0.1)
				(type default)
			)
			(layer "B.Fab")
		)
		(fp_line
			(start -0.12065 -0.3048)
			(end -0.67945 -0.3048)
			(stroke
				(width 0.1)
				(type default)
			)
			(layer "B.Fab")
		)
		(fp_line
			(start 0.12065 -0.305054)
			(end 0.12065 -0.2794)
			(stroke
				(width 0.1)
				(type default)
			)
			(layer "B.Fab")
		)
		(fp_line
			(start 0.67945 -0.305054)
			(end 0.12065 -0.305054)
			(stroke
				(width 0.1)
				(type default)
			)
			(layer "B.Fab")
		)
		(pad "1" smd circle
			(at 0.40005 0 90)
			(size 0 0)
			(layers "B.Cu" "B.Mask" "B.Paste")
			(net "RST_PLD_CPU0_DRAM_GH_N")
		)
		(pad "2" smd circle
			(at -0.40005 0 90)
			(size 0 0)
			(layers "B.Cu" "B.Mask" "B.Paste")
			(net "GND")
		)
	)
	(footprint ""
		(layer "B.Cu")
		(at 12.666472 -183.482996)
		(property "Reference" "R2480"
			(at 0 0 0)
			(layer "B.SilkS")
			(hide yes)
			(effects
				(font
					(size 1.27 1.27)
				)
				(justify mirror)
			)
		)
		(property "Value" ""
			(at 0 0 0)
			(layer "B.Fab")
			(effects
				(font
					(size 1.27 1.27)
				)
				(justify mirror)
			)
		)
		(duplicate_pad_numbers_are_jumpers no)
		(fp_line
			(start -0.7874 -0.4064)
			(end -0.7874 0.4064)
			(stroke
				(width 0.1524)
				(type default)
			)
			(layer "B.SilkS")
		)
		(fp_line
			(start -0.7874 0.4064)
			(end 0.7874 0.4064)
			(stroke
				(width 0.1524)
				(type default)
			)
			(layer "B.SilkS")
		)
		(fp_line
			(start 0.7874 -0.4064)
			(end -0.7874 -0.4064)
			(stroke
				(width 0.1524)
				(type default)
			)
			(layer "B.SilkS")
		)
		(fp_line
			(start 0.7874 0.4064)
			(end 0.7874 -0.4064)
			(stroke
				(width 0.1524)
				(type default)
			)
			(layer "B.SilkS")
		)
		(fp_line
			(start -0.67945 -0.3048)
			(end -0.67945 0.3048)
			(stroke
				(width 0.1)
				(type default)
			)
			(layer "B.Fab")
		)
		(fp_line
			(start -0.67945 0.3048)
			(end -0.120396 0.3048)
			(stroke
				(width 0.1)
				(type default)
			)
			(layer "B.Fab")
		)
		(fp_line
			(start -0.12065 -0.3048)
			(end -0.67945 -0.3048)
			(stroke
				(width 0.1)
				(type default)
			)
			(layer "B.Fab")
		)
		(fp_line
			(start -0.12065 -0.2794)
			(end -0.12065 -0.3048)
			(stroke
				(width 0.1)
				(type default)
			)
			(layer "B.Fab")
		)
		(fp_line
			(start -0.120396 0.2794)
			(end 0.12065 0.2794)
			(stroke
				(width 0.1)
				(type default)
			)
			(layer "B.Fab")
		)
		(fp_line
			(start -0.120396 0.3048)
			(end -0.120396 0.2794)
			(stroke
				(width 0.1)
				(type default)
			)
			(layer "B.Fab")
		)
		(fp_line
			(start 0.12065 -0.305054)
			(end 0.12065 -0.2794)
			(stroke
				(width 0.1)
				(type default)
			)
			(layer "B.Fab")
		)
		(fp_line
			(start 0.12065 -0.2794)
			(end -0.12065 -0.2794)
			(stroke
				(width 0.1)
				(type default)
			)
			(layer "B.Fab")
		)
		(fp_line
			(start 0.12065 0.2794)
			(end 0.12065 0.3048)
			(stroke
				(width 0.1)
				(type default)
			)
			(layer "B.Fab")
		)
		(fp_line
			(start 0.12065 0.3048)
			(end 0.67945 0.3048)
			(stroke
				(width 0.1)
				(type default)
			)
			(layer "B.Fab")
		)
		(fp_line
			(start 0.67945 -0.305054)
			(end 0.12065 -0.305054)
			(stroke
				(width 0.1)
				(type default)
			)
			(layer "B.Fab")
		)
		(fp_line
			(start 0.67945 0.3048)
			(end 0.67945 -0.305054)
			(stroke
				(width 0.1)
				(type default)
			)
			(layer "B.Fab")
		)
		(pad "1" smd circle
			(at 0.40005 0 180)
			(size 0 0)
			(layers "B.Cu" "B.Mask" "B.Paste")
			(net "SMB_PEHPCPU1_LVC3_SDA_R0")
		)
		(pad "2" smd circle
			(at -0.40005 0 180)
			(size 0 0)
			(layers "B.Cu" "B.Mask" "B.Paste")
			(net "SMB_PEHPCPU1_LVC3_SDA")
		)
	)
	(footprint ""
		(layer "B.Cu")
		(at 68.337684 -183.303926 -90)
		(property "Reference" "R156"
			(at 0 0 90)
			(layer "B.SilkS")
			(hide yes)
			(effects
				(font
					(size 1.27 1.27)
				)
				(justify mirror)
			)
		)
		(property "Value" ""
			(at 0 0 90)
			(layer "B.Fab")
			(effects
				(font
					(size 1.27 1.27)
				)
				(justify mirror)
			)
		)
		(duplicate_pad_numbers_are_jumpers no)
		(fp_line
			(start -0.7874 0.4064)
			(end 0.7874 0.4064)
			(stroke
				(width 0.1524)
				(type default)
			)
			(layer "B.SilkS")
		)
		(fp_line
			(start 0.7874 0.4064)
			(end 0.7874 -0.4064)
			(stroke
				(width 0.1524)
				(type default)
			)
			(layer "B.SilkS")
		)
		(fp_line
			(start -0.7874 -0.4064)
			(end -0.7874 0.4064)
			(stroke
				(width 0.1524)
				(type default)
			)
			(layer "B.SilkS")
		)
		(fp_line
			(start 0.7874 -0.4064)
			(end -0.7874 -0.4064)
			(stroke
				(width 0.1524)
				(type default)
			)
			(layer "B.SilkS")
		)
		(fp_line
			(start -0.67945 0.3048)
			(end -0.120396 0.3048)
			(stroke
				(width 0.1)
				(type default)
			)
			(layer "B.Fab")
		)
		(fp_line
			(start -0.120396 0.3048)
			(end -0.120396 0.2794)
			(stroke
				(width 0.1)
				(type default)
			)
			(layer "B.Fab")
		)
		(fp_line
			(start 0.12065 0.3048)
			(end 0.67945 0.3048)
			(stroke
				(width 0.1)
				(type default)
			)
			(layer "B.Fab")
		)
		(fp_line
			(start 0.67945 0.3048)
			(end 0.67945 -0.305054)
			(stroke
				(width 0.1)
				(type default)
			)
			(layer "B.Fab")
		)
		(fp_line
			(start -0.120396 0.2794)
			(end 0.12065 0.2794)
			(stroke
				(width 0.1)
				(type default)
			)
			(layer "B.Fab")
		)
		(fp_line
			(start 0.12065 0.2794)
			(end 0.12065 0.3048)
			(stroke
				(width 0.1)
				(type default)
			)
			(layer "B.Fab")
		)
		(fp_line
			(start -0.12065 -0.2794)
			(end -0.12065 -0.3048)
			(stroke
				(width 0.1)
				(type default)
			)
			(layer "B.Fab")
		)
		(fp_line
			(start 0.12065 -0.2794)
			(end -0.12065 -0.2794)
			(stroke
				(width 0.1)
				(type default)
			)
			(layer "B.Fab")
		)
		(fp_line
			(start -0.67945 -0.3048)
			(end -0.67945 0.3048)
			(stroke
				(width 0.1)
				(type default)
			)
			(layer "B.Fab")
		)
		(fp_line
			(start -0.12065 -0.3048)
			(end -0.67945 -0.3048)
			(stroke
				(width 0.1)
				(type default)
			)
			(layer "B.Fab")
		)
		(fp_line
			(start 0.12065 -0.305054)
			(end 0.12065 -0.2794)
			(stroke
				(width 0.1)
				(type default)
			)
			(layer "B.Fab")
		)
		(fp_line
			(start 0.67945 -0.305054)
			(end 0.12065 -0.305054)
			(stroke
				(width 0.1)
				(type default)
			)
			(layer "B.Fab")
		)
		(pad "1" smd circle
			(at 0.40005 0 90)
			(size 0 0)
			(layers "B.Cu" "B.Mask" "B.Paste")
			(net "PWRGD_CPU1_BUF_R")
		)
		(pad "2" smd circle
			(at -0.40005 0 90)
			(size 0 0)
			(layers "B.Cu" "B.Mask" "B.Paste")
			(net "PWRGD_CPU1_LVC1")
		)
	)
	(footprint ""
		(layer "B.Cu")
		(at 194.159378 -193.43497)
		(property "Reference" "C543"
			(at 0 0 0)
			(layer "B.SilkS")
			(hide yes)
			(effects
				(font
					(size 1.27 1.27)
				)
				(justify mirror)
			)
		)
		(property "Value" ""
			(at 0 0 0)
			(layer "B.Fab")
			(effects
				(font
					(size 1.27 1.27)
				)
				(justify mirror)
			)
		)
		(duplicate_pad_numbers_are_jumpers no)
		(fp_line
			(start -0.7874 -0.4064)
			(end -0.7874 0.4064)
			(stroke
				(width 0.1524)
				(type default)
			)
			(layer "B.SilkS")
		)
		(fp_line
			(start -0.7874 0.4064)
			(end 0.7874 0.4064)
			(stroke
				(width 0.1524)
				(type default)
			)
			(layer "B.SilkS")
		)
		(fp_line
			(start 0.7874 -0.4064)
			(end -0.7874 -0.4064)
			(stroke
				(width 0.1524)
				(type default)
			)
			(layer "B.SilkS")
		)
		(fp_line
			(start 0.7874 0.4064)
			(end 0.7874 -0.4064)
			(stroke
				(width 0.1524)
				(type default)
			)
			(layer "B.SilkS")
		)
		(fp_line
			(start -0.67945 -0.3048)
			(end -0.67945 0.3048)
			(stroke
				(width 0.1)
				(type default)
			)
			(layer "B.Fab")
		)
		(fp_line
			(start -0.67945 0.3048)
			(end -0.120396 0.3048)
			(stroke
				(width 0.1)
				(type default)
			)
			(layer "B.Fab")
		)
		(fp_line
			(start -0.12065 -0.3048)
			(end -0.67945 -0.3048)
			(stroke
				(width 0.1)
				(type default)
			)
			(layer "B.Fab")
		)
		(fp_line
			(start -0.12065 -0.2794)
			(end -0.12065 -0.3048)
			(stroke
				(width 0.1)
				(type default)
			)
			(layer "B.Fab")
		)
		(fp_line
			(start -0.120396 0.2794)
			(end 0.12065 0.2794)
			(stroke
				(width 0.1)
				(type default)
			)
			(layer "B.Fab")
		)
		(fp_line
			(start -0.120396 0.3048)
			(end -0.120396 0.2794)
			(stroke
				(width 0.1)
				(type default)
			)
			(layer "B.Fab")
		)
		(fp_line
			(start 0.12065 -0.305054)
			(end 0.12065 -0.2794)
			(stroke
				(width 0.1)
				(type default)
			)
			(layer "B.Fab")
		)
		(fp_line
			(start 0.12065 -0.2794)
			(end -0.12065 -0.2794)
			(stroke
				(width 0.1)
				(type default)
			)
			(layer "B.Fab")
		)
		(fp_line
			(start 0.12065 0.2794)
			(end 0.12065 0.3048)
			(stroke
				(width 0.1)
				(type default)
			)
			(layer "B.Fab")
		)
		(fp_line
			(start 0.12065 0.3048)
			(end 0.67945 0.3048)
			(stroke
				(width 0.1)
				(type default)
			)
			(layer "B.Fab")
		)
		(fp_line
			(start 0.67945 -0.305054)
			(end 0.12065 -0.305054)
			(stroke
				(width 0.1)
				(type default)
			)
			(layer "B.Fab")
		)
		(fp_line
			(start 0.67945 0.3048)
			(end 0.67945 -0.305054)
			(stroke
				(width 0.1)
				(type default)
			)
			(layer "B.Fab")
		)
		(pad "1" smd circle
			(at 0.40005 0 180)
			(size 0 0)
			(layers "B.Cu" "B.Mask" "B.Paste")
			(net "P3V3_AUX")
		)
		(pad "2" smd circle
			(at -0.40005 0 180)
			(size 0 0)
			(layers "B.Cu" "B.Mask" "B.Paste")
			(net "GND")
		)
	)
	(footprint ""
		(layer "B.Cu")
		(at 131.74726 -28.20924)
		(property "Reference" "C2349"
			(at 0 0 0)
			(layer "B.SilkS")
			(hide yes)
			(effects
				(font
					(size 1.27 1.27)
				)
				(justify mirror)
			)
		)
		(property "Value" ""
			(at 0 0 0)
			(layer "B.Fab")
			(effects
				(font
					(size 1.27 1.27)
				)
				(justify mirror)
			)
		)
		(duplicate_pad_numbers_are_jumpers no)
		(fp_line
			(start -0.40005 0.4064)
			(end 0.40005 0.4064)
			(stroke
				(width 0.1524)
				(type default)
			)
			(layer "B.SilkS")
		)
		(fp_line
			(start 0.40005 -0.4064)
			(end -0.40005 -0.4064)
			(stroke
				(width 0.1524)
				(type default)
			)
			(layer "B.SilkS")
		)
		(fp_line
			(start -0.6858 -0.3048)
			(end -0.6858 0.3048)
			(stroke
				(width 0.1)
				(type default)
			)
			(layer "B.Fab")
		)
		(fp_line
			(start -0.6858 0.3048)
			(end -0.1016 0.3048)
			(stroke
				(width 0.1)
				(type default)
			)
			(layer "B.Fab")
		)
		(fp_line
			(start -0.1016 -0.3048)
			(end -0.6858 -0.3048)
			(stroke
				(width 0.1)
				(type default)
			)
			(layer "B.Fab")
		)
		(fp_line
			(start -0.1016 -0.2794)
			(end -0.1016 -0.3048)
			(stroke
				(width 0.1)
				(type default)
			)
			(layer "B.Fab")
		)
		(fp_line
			(start -0.1016 0.2794)
			(end 0.1016 0.2794)
			(stroke
				(width 0.1)
				(type default)
			)
			(layer "B.Fab")
		)
		(fp_line
			(start -0.1016 0.3048)
			(end -0.1016 0.2794)
			(stroke
				(width 0.1)
				(type default)
			)
			(layer "B.Fab")
		)
		(fp_line
			(start 0.1016 -0.3048)
			(end 0.1016 -0.2794)
			(stroke
				(width 0.1)
				(type default)
			)
			(layer "B.Fab")
		)
		(fp_line
			(start 0.1016 -0.2794)
			(end -0.1016 -0.2794)
			(stroke
				(width 0.1)
				(type default)
			)
			(layer "B.Fab")
		)
		(fp_line
			(start 0.1016 0.2794)
			(end 0.1016 0.3048)
			(stroke
				(width 0.1)
				(type default)
			)
			(layer "B.Fab")
		)
		(fp_line
			(start 0.1016 0.3048)
			(end 0.6858 0.3048)
			(stroke
				(width 0.1)
				(type default)
			)
			(layer "B.Fab")
		)
		(fp_line
			(start 0.6858 -0.3048)
			(end 0.1016 -0.3048)
			(stroke
				(width 0.1)
				(type default)
			)
			(layer "B.Fab")
		)
		(fp_line
			(start 0.6858 0.3048)
			(end 0.6858 -0.3048)
			(stroke
				(width 0.1)
				(type default)
			)
			(layer "B.Fab")
		)
		(pad "1" smd rect
			(at 0.40005 0)
			(size 0.4572 0.508)
			(layers "B.Cu" "B.Mask" "B.Paste")
			(net "USB3_PCH_RX_DP<4>")
		)
		(pad "2" smd rect
			(at -0.40005 0)
			(size 0.4572 0.508)
			(layers "B.Cu" "B.Mask" "B.Paste")
			(net "USB3_PCH_RX_C_DP<4>")
		)
		(zone
			(layer "In16.Cu")
			(hatch none 0.5)
			(connect_pads
				(clearance 0)
			)
			(min_thickness 0.25)
			(keepout
				(tracks not_allowed)
				(vias allowed)
				(pads allowed)
				(copperpour not_allowed)
				(footprints allowed)
			)
			(placement
				(enabled no)
				(sheetname "")
			)
			(fill
				(thermal_gap 0.5)
				(thermal_bridge_width 0.5)
				(island_removal_mode 0)
			)
			(polygon
				(pts
					(xy 131.62661 -27.90444) (xy 131.06781 -27.90444) (xy 131.06781 -28.51404) (xy 131.62661 -28.51404)
				)
			)
		)
		(zone
			(layer "In16.Cu")
			(hatch none 0.5)
			(connect_pads
				(clearance 0)
			)
			(min_thickness 0.25)
			(keepout
				(tracks not_allowed)
				(vias allowed)
				(pads allowed)
				(copperpour not_allowed)
				(footprints allowed)
			)
			(placement
				(enabled no)
				(sheetname "")
			)
			(fill
				(thermal_gap 0.5)
				(thermal_bridge_width 0.5)
				(island_removal_mode 0)
			)
			(polygon
				(pts
					(xy 132.42671 -27.90444) (xy 131.86791 -27.90444) (xy 131.86791 -28.51404) (xy 132.42671 -28.51404)
				)
			)
		)
	)
	(footprint ""
		(layer "B.Cu")
		(at 89.343484 -181.450488 90)
		(property "Reference" "Q16"
			(at 0.79121 4.346956 0)
			(unlocked yes)
			(layer "B.SilkS")
			(effects
				(font
					(size 0.7874 0.5842)
					(thickness 0.1524)
				)
				(justify left mirror)
			)
		)
		(property "Value" ""
			(at 0 0 90)
			(layer "B.Fab")
			(effects
				(font
					(size 1.27 1.27)
				)
				(justify mirror)
			)
		)
		(duplicate_pad_numbers_are_jumpers no)
		(fp_line
			(start 1.332738 -1.100074)
			(end 0.4826 -1.100074)
			(stroke
				(width 0.1524)
				(type default)
			)
			(layer "B.SilkS")
		)
		(fp_line
			(start 0.4826 -1.100074)
			(end 0 -0.541274)
			(stroke
				(width 0.1524)
				(type default)
			)
			(layer "B.SilkS")
		)
		(fp_line
			(start -0.4826 -1.100074)
			(end -1.332738 -1.100074)
			(stroke
				(width 0.1524)
				(type default)
			)
			(layer "B.SilkS")
		)
		(fp_line
			(start -1.332738 -1.100074)
			(end -1.332738 1.100074)
			(stroke
				(width 0.1524)
				(type default)
			)
			(layer "B.SilkS")
		)
		(fp_line
			(start 0 -0.541274)
			(end -0.4826 -1.100074)
			(stroke
				(width 0.1524)
				(type default)
			)
			(layer "B.SilkS")
		)
		(fp_line
			(start 1.332738 1.100074)
			(end 1.332738 -1.100074)
			(stroke
				(width 0.1524)
				(type default)
			)
			(layer "B.SilkS")
		)
		(fp_line
			(start -1.332738 1.100074)
			(end 1.332738 1.100074)
			(stroke
				(width 0.1524)
				(type default)
			)
			(layer "B.SilkS")
		)
		(fp_poly
			(pts
				(xy 1.50749 -2.152904) (xy 1.156462 -1.450848) (xy 0.805434 -2.152904)
			)
			(stroke
				(width 0)
				(type default)
			)
			(fill yes)
			(layer "B.SilkS")
		)
		(fp_line
			(start 0.674878 -1.100074)
			(end -0.674878 -1.100074)
			(stroke
				(width 0.1)
				(type default)
			)
			(layer "B.Fab")
		)
		(fp_line
			(start -0.674878 -1.100074)
			(end -0.674878 1.100074)
			(stroke
				(width 0.1)
				(type default)
			)
			(layer "B.Fab")
		)
		(fp_line
			(start 0.674878 1.100074)
			(end 0.674878 -1.100074)
			(stroke
				(width 0.1)
				(type default)
			)
			(layer "B.Fab")
		)
		(fp_line
			(start -0.674878 1.100074)
			(end 0.674878 1.100074)
			(stroke
				(width 0.1)
				(type default)
			)
			(layer "B.Fab")
		)
		(fp_poly
			(pts
				(xy 2.2352 -0.298958) (xy 2.2352 -1.001014) (xy 1.533144 -0.649986)
			)
			(stroke
				(width 0)
				(type default)
			)
			(fill yes)
			(layer "B.Fab")
		)
		(pad "1" smd rect
			(at 0.94996 -0.649986 180)
			(size 0.4318 0.508)
			(layers "B.Cu" "B.Mask" "B.Paste")
			(net "GND")
		)
		(pad "2" smd rect
			(at 0.94996 0 180)
			(size 0.4318 0.508)
			(layers "B.Cu" "B.Mask" "B.Paste")
			(net "FM_SMB_PEHPCPU1_PCIE_ALERT_R_N")
		)
		(pad "3" smd rect
			(at 0.94996 0.649986 180)
			(size 0.4318 0.508)
			(layers "B.Cu" "B.Mask" "B.Paste")
			(net "FM_PEHPCPU1_ALERT_N")
		)
		(pad "4" smd rect
			(at -0.94996 0.649986 180)
			(size 0.4318 0.508)
			(layers "B.Cu" "B.Mask" "B.Paste")
			(net "GND")
		)
		(pad "5" smd rect
			(at -0.94996 0 180)
			(size 0.4318 0.508)
			(layers "B.Cu" "B.Mask" "B.Paste")
			(net "FM_SMB_CPU1_ALERT_R1")
		)
		(pad "6" smd rect
			(at -0.94996 -0.649986 180)
			(size 0.4318 0.508)
			(layers "B.Cu" "B.Mask" "B.Paste")
			(net "FM_SMB_CPU1_ALERT_R1")
		)
	)
	(footprint ""
		(layer "B.Cu")
		(at 376.468132 -76.696824 180)
		(property "Reference" "PC1239"
			(at 0 0 0)
			(layer "B.SilkS")
			(hide yes)
			(effects
				(font
					(size 1.27 1.27)
				)
				(justify mirror)
			)
		)
		(property "Value" ""
			(at 0 0 0)
			(layer "B.Fab")
			(effects
				(font
					(size 1.27 1.27)
				)
				(justify mirror)
			)
		)
		(duplicate_pad_numbers_are_jumpers no)
		(fp_line
			(start 1.524 0.762)
			(end 1.524 -0.762)
			(stroke
				(width 0.1524)
				(type default)
			)
			(layer "B.SilkS")
		)
		(fp_line
			(start 1.524 -0.762)
			(end -1.524 -0.762)
			(stroke
				(width 0.1524)
				(type default)
			)
			(layer "B.SilkS")
		)
		(fp_line
			(start -1.524 0.762)
			(end 1.524 0.762)
			(stroke
				(width 0.1524)
				(type default)
			)
			(layer "B.SilkS")
		)
		(fp_line
			(start -1.524 -0.762)
			(end -1.524 0.762)
			(stroke
				(width 0.1524)
				(type default)
			)
			(layer "B.SilkS")
		)
		(fp_line
			(start 1.1049 0.724916)
			(end -1.1049 0.724916)
			(stroke
				(width 0.1)
				(type default)
			)
			(layer "B.Fab")
		)
		(fp_line
			(start 1.1049 -0.724916)
			(end 1.1049 0.724916)
			(stroke
				(width 0.1)
				(type default)
			)
			(layer "B.Fab")
		)
		(fp_line
			(start -1.1049 0.724916)
			(end -1.1049 -0.724916)
			(stroke
				(width 0.1)
				(type default)
			)
			(layer "B.Fab")
		)
		(fp_line
			(start -1.1049 -0.724916)
			(end 1.1049 -0.724916)
			(stroke
				(width 0.1)
				(type default)
			)
			(layer "B.Fab")
		)
		(pad "1" smd rect
			(at 0.889 0 180)
			(size 1.016 1.27)
			(layers "B.Cu" "B.Mask" "B.Paste")
			(net "P1V8_PCH_AUX")
		)
		(pad "2" smd rect
			(at -0.889 0 180)
			(size 1.016 1.27)
			(layers "B.Cu" "B.Mask" "B.Paste")
			(net "GND")
		)
	)
	(footprint ""
		(layer "B.Cu")
		(at 178.04384 -32.944308 90)
		(property "Reference" "PC2340"
			(at 0 0 90)
			(layer "B.SilkS")
			(hide yes)
			(effects
				(font
					(size 1.27 1.27)
				)
				(justify mirror)
			)
		)
		(property "Value" ""
			(at 0 0 90)
			(layer "B.Fab")
			(effects
				(font
					(size 1.27 1.27)
				)
				(justify mirror)
			)
		)
		(duplicate_pad_numbers_are_jumpers no)
		(fp_line
			(start 0.7874 -0.4064)
			(end -0.7874 -0.4064)
			(stroke
				(width 0.1524)
				(type default)
			)
			(layer "B.SilkS")
		)
		(fp_line
			(start -0.7874 -0.4064)
			(end -0.7874 0.4064)
			(stroke
				(width 0.1524)
				(type default)
			)
			(layer "B.SilkS")
		)
		(fp_line
			(start 0.7874 0.4064)
			(end 0.7874 -0.4064)
			(stroke
				(width 0.1524)
				(type default)
			)
			(layer "B.SilkS")
		)
		(fp_line
			(start -0.7874 0.4064)
			(end 0.7874 0.4064)
			(stroke
				(width 0.1524)
				(type default)
			)
			(layer "B.SilkS")
		)
		(fp_line
			(start 0.67945 -0.305054)
			(end 0.12065 -0.305054)
			(stroke
				(width 0.1)
				(type default)
			)
			(layer "B.Fab")
		)
		(fp_line
			(start 0.12065 -0.305054)
			(end 0.12065 -0.2794)
			(stroke
				(width 0.1)
				(type default)
			)
			(layer "B.Fab")
		)
		(fp_line
			(start -0.12065 -0.3048)
			(end -0.67945 -0.3048)
			(stroke
				(width 0.1)
				(type default)
			)
			(layer "B.Fab")
		)
		(fp_line
			(start -0.67945 -0.3048)
			(end -0.67945 0.3048)
			(stroke
				(width 0.1)
				(type default)
			)
			(layer "B.Fab")
		)
		(fp_line
			(start 0.12065 -0.2794)
			(end -0.12065 -0.2794)
			(stroke
				(width 0.1)
				(type default)
			)
			(layer "B.Fab")
		)
		(fp_line
			(start -0.12065 -0.2794)
			(end -0.12065 -0.3048)
			(stroke
				(width 0.1)
				(type default)
			)
			(layer "B.Fab")
		)
		(fp_line
			(start 0.12065 0.2794)
			(end 0.12065 0.3048)
			(stroke
				(width 0.1)
				(type default)
			)
			(layer "B.Fab")
		)
		(fp_line
			(start -0.120396 0.2794)
			(end 0.12065 0.2794)
			(stroke
				(width 0.1)
				(type default)
			)
			(layer "B.Fab")
		)
		(fp_line
			(start 0.67945 0.3048)
			(end 0.67945 -0.305054)
			(stroke
				(width 0.1)
				(type default)
			)
			(layer "B.Fab")
		)
		(fp_line
			(start 0.12065 0.3048)
			(end 0.67945 0.3048)
			(stroke
				(width 0.1)
				(type default)
			)
			(layer "B.Fab")
		)
		(fp_line
			(start -0.120396 0.3048)
			(end -0.120396 0.2794)
			(stroke
				(width 0.1)
				(type default)
			)
			(layer "B.Fab")
		)
		(fp_line
			(start -0.67945 0.3048)
			(end -0.120396 0.3048)
			(stroke
				(width 0.1)
				(type default)
			)
			(layer "B.Fab")
		)
		(pad "1" smd circle
			(at 0.40005 0 270)
			(size 0 0)
			(layers "B.Cu" "B.Mask" "B.Paste")
			(net "P12V_SCM_ISET_R")
		)
		(pad "2" smd circle
			(at -0.40005 0 270)
			(size 0 0)
			(layers "B.Cu" "B.Mask" "B.Paste")
			(net "GND")
		)
	)
	(footprint ""
		(layer "B.Cu")
		(at 105.595928 -262.34898)
		(property "Reference" "C312"
			(at 0 0 0)
			(layer "B.SilkS")
			(hide yes)
			(effects
				(font
					(size 1.27 1.27)
				)
				(justify mirror)
			)
		)
		(property "Value" ""
			(at 0 0 0)
			(layer "B.Fab")
			(effects
				(font
					(size 1.27 1.27)
				)
				(justify mirror)
			)
		)
		(duplicate_pad_numbers_are_jumpers no)
		(fp_line
			(start -1.524 -0.762)
			(end -1.524 0.762)
			(stroke
				(width 0.1524)
				(type default)
			)
			(layer "B.SilkS")
		)
		(fp_line
			(start -1.524 0.762)
			(end 1.524 0.762)
			(stroke
				(width 0.1524)
				(type default)
			)
			(layer "B.SilkS")
		)
		(fp_line
			(start 1.524 -0.762)
			(end -1.524 -0.762)
			(stroke
				(width 0.1524)
				(type default)
			)
			(layer "B.SilkS")
		)
		(fp_line
			(start 1.524 0.762)
			(end 1.524 -0.762)
			(stroke
				(width 0.1524)
				(type default)
			)
			(layer "B.SilkS")
		)
		(fp_line
			(start -1.1049 -0.724916)
			(end 1.1049 -0.724916)
			(stroke
				(width 0.1)
				(type default)
			)
			(layer "B.Fab")
		)
		(fp_line
			(start -1.1049 0.724916)
			(end -1.1049 -0.724916)
			(stroke
				(width 0.1)
				(type default)
			)
			(layer "B.Fab")
		)
		(fp_line
			(start 1.1049 -0.724916)
			(end 1.1049 0.724916)
			(stroke
				(width 0.1)
				(type default)
			)
			(layer "B.Fab")
		)
		(fp_line
			(start 1.1049 0.724916)
			(end -1.1049 0.724916)
			(stroke
				(width 0.1)
				(type default)
			)
			(layer "B.Fab")
		)
		(pad "1" smd rect
			(at 0.889 0)
			(size 1.016 1.27)
			(layers "B.Cu" "B.Mask" "B.Paste")
			(net "PVCCIN_CPU1")
		)
		(pad "2" smd rect
			(at -0.889 0)
			(size 1.016 1.27)
			(layers "B.Cu" "B.Mask" "B.Paste")
			(net "GND")
		)
	)
	(footprint ""
		(layer "B.Cu")
		(at 104.463088 -212.049868)
		(property "Reference" "C464"
			(at 0 0 0)
			(layer "B.SilkS")
			(hide yes)
			(effects
				(font
					(size 1.27 1.27)
				)
				(justify mirror)
			)
		)
		(property "Value" ""
			(at 0 0 0)
			(layer "B.Fab")
			(effects
				(font
					(size 1.27 1.27)
				)
				(justify mirror)
			)
		)
		(duplicate_pad_numbers_are_jumpers no)
		(fp_line
			(start -1.524 -0.762)
			(end -1.524 0.762)
			(stroke
				(width 0.1524)
				(type default)
			)
			(layer "B.SilkS")
		)
		(fp_line
			(start -1.524 0.762)
			(end 1.524 0.762)
			(stroke
				(width 0.1524)
				(type default)
			)
			(layer "B.SilkS")
		)
		(fp_line
			(start 1.524 -0.762)
			(end -1.524 -0.762)
			(stroke
				(width 0.1524)
				(type default)
			)
			(layer "B.SilkS")
		)
		(fp_line
			(start 1.524 0.762)
			(end 1.524 -0.762)
			(stroke
				(width 0.1524)
				(type default)
			)
			(layer "B.SilkS")
		)
		(fp_line
			(start -1.1049 -0.724916)
			(end 1.1049 -0.724916)
			(stroke
				(width 0.1)
				(type default)
			)
			(layer "B.Fab")
		)
		(fp_line
			(start -1.1049 0.724916)
			(end -1.1049 -0.724916)
			(stroke
				(width 0.1)
				(type default)
			)
			(layer "B.Fab")
		)
		(fp_line
			(start 1.1049 -0.724916)
			(end 1.1049 0.724916)
			(stroke
				(width 0.1)
				(type default)
			)
			(layer "B.Fab")
		)
		(fp_line
			(start 1.1049 0.724916)
			(end -1.1049 0.724916)
			(stroke
				(width 0.1)
				(type default)
			)
			(layer "B.Fab")
		)
		(pad "1" smd rect
			(at 0.889 0)
			(size 1.016 1.27)
			(layers "B.Cu" "B.Mask" "B.Paste")
			(net "PVCCFA_EHV_CPU1")
		)
		(pad "2" smd rect
			(at -0.889 0)
			(size 1.016 1.27)
			(layers "B.Cu" "B.Mask" "B.Paste")
			(net "GND")
		)
	)
	(footprint ""
		(layer "B.Cu")
		(at 280.110184 -193.669666 -90)
		(property "Reference" "R1392"
			(at 0 0 90)
			(layer "B.SilkS")
			(hide yes)
			(effects
				(font
					(size 1.27 1.27)
				)
				(justify mirror)
			)
		)
		(property "Value" ""
			(at 0 0 90)
			(layer "B.Fab")
			(effects
				(font
					(size 1.27 1.27)
				)
				(justify mirror)
			)
		)
		(duplicate_pad_numbers_are_jumpers no)
		(fp_line
			(start -0.7874 0.4064)
			(end 0.7874 0.4064)
			(stroke
				(width 0.1524)
				(type default)
			)
			(layer "B.SilkS")
		)
		(fp_line
			(start 0.7874 0.4064)
			(end 0.7874 -0.4064)
			(stroke
				(width 0.1524)
				(type default)
			)
			(layer "B.SilkS")
		)
		(fp_line
			(start -0.7874 -0.4064)
			(end -0.7874 0.4064)
			(stroke
				(width 0.1524)
				(type default)
			)
			(layer "B.SilkS")
		)
		(fp_line
			(start 0.7874 -0.4064)
			(end -0.7874 -0.4064)
			(stroke
				(width 0.1524)
				(type default)
			)
			(layer "B.SilkS")
		)
		(fp_line
			(start -0.67945 0.3048)
			(end -0.120396 0.3048)
			(stroke
				(width 0.1)
				(type default)
			)
			(layer "B.Fab")
		)
		(fp_line
			(start -0.120396 0.3048)
			(end -0.120396 0.2794)
			(stroke
				(width 0.1)
				(type default)
			)
			(layer "B.Fab")
		)
		(fp_line
			(start 0.12065 0.3048)
			(end 0.67945 0.3048)
			(stroke
				(width 0.1)
				(type default)
			)
			(layer "B.Fab")
		)
		(fp_line
			(start 0.67945 0.3048)
			(end 0.67945 -0.305054)
			(stroke
				(width 0.1)
				(type default)
			)
			(layer "B.Fab")
		)
		(fp_line
			(start -0.120396 0.2794)
			(end 0.12065 0.2794)
			(stroke
				(width 0.1)
				(type default)
			)
			(layer "B.Fab")
		)
		(fp_line
			(start 0.12065 0.2794)
			(end 0.12065 0.3048)
			(stroke
				(width 0.1)
				(type default)
			)
			(layer "B.Fab")
		)
		(fp_line
			(start -0.12065 -0.2794)
			(end -0.12065 -0.3048)
			(stroke
				(width 0.1)
				(type default)
			)
			(layer "B.Fab")
		)
		(fp_line
			(start 0.12065 -0.2794)
			(end -0.12065 -0.2794)
			(stroke
				(width 0.1)
				(type default)
			)
			(layer "B.Fab")
		)
		(fp_line
			(start -0.67945 -0.3048)
			(end -0.67945 0.3048)
			(stroke
				(width 0.1)
				(type default)
			)
			(layer "B.Fab")
		)
		(fp_line
			(start -0.12065 -0.3048)
			(end -0.67945 -0.3048)
			(stroke
				(width 0.1)
				(type default)
			)
			(layer "B.Fab")
		)
		(fp_line
			(start 0.12065 -0.305054)
			(end 0.12065 -0.2794)
			(stroke
				(width 0.1)
				(type default)
			)
			(layer "B.Fab")
		)
		(fp_line
			(start 0.67945 -0.305054)
			(end 0.12065 -0.305054)
			(stroke
				(width 0.1)
				(type default)
			)
			(layer "B.Fab")
		)
		(pad "1" smd circle
			(at 0.40005 0 90)
			(size 0 0)
			(layers "B.Cu" "B.Mask" "B.Paste")
			(net "GND")
		)
		(pad "2" smd circle
			(at -0.40005 0 90)
			(size 0 0)
			(layers "B.Cu" "B.Mask" "B.Paste")
			(net "FM_S3M_CPU0_LVC1_GPIO_3")
		)
	)
	(footprint ""
		(layer "B.Cu")
		(at 285.23692 -354.163376 -90)
		(property "Reference" "PC1188_P0_4"
			(at 0 0 90)
			(layer "B.SilkS")
			(hide yes)
			(effects
				(font
					(size 1.27 1.27)
				)
				(justify mirror)
			)
		)
		(property "Value" ""
			(at 0 0 90)
			(layer "B.Fab")
			(effects
				(font
					(size 1.27 1.27)
				)
				(justify mirror)
			)
		)
		(duplicate_pad_numbers_are_jumpers no)
		(fp_line
			(start -1.524 0.762)
			(end 1.524 0.762)
			(stroke
				(width 0.1524)
				(type default)
			)
			(layer "B.SilkS")
		)
		(fp_line
			(start 1.524 0.762)
			(end 1.524 -0.762)
			(stroke
				(width 0.1524)
				(type default)
			)
			(layer "B.SilkS")
		)
		(fp_line
			(start -1.524 -0.762)
			(end -1.524 0.762)
			(stroke
				(width 0.1524)
				(type default)
			)
			(layer "B.SilkS")
		)
		(fp_line
			(start 1.524 -0.762)
			(end -1.524 -0.762)
			(stroke
				(width 0.1524)
				(type default)
			)
			(layer "B.SilkS")
		)
		(fp_line
			(start -1.1049 0.724916)
			(end -1.1049 -0.724916)
			(stroke
				(width 0.1)
				(type default)
			)
			(layer "B.Fab")
		)
		(fp_line
			(start 1.1049 0.724916)
			(end -1.1049 0.724916)
			(stroke
				(width 0.1)
				(type default)
			)
			(layer "B.Fab")
		)
		(fp_line
			(start -1.1049 -0.724916)
			(end 1.1049 -0.724916)
			(stroke
				(width 0.1)
				(type default)
			)
			(layer "B.Fab")
		)
		(fp_line
			(start 1.1049 -0.724916)
			(end 1.1049 0.724916)
			(stroke
				(width 0.1)
				(type default)
			)
			(layer "B.Fab")
		)
		(pad "1" smd rect
			(at 0.889 0 270)
			(size 1.016 1.27)
			(layers "B.Cu" "B.Mask" "B.Paste")
			(net "PVCCFA_EHV_FIVRA_CPU0")
		)
		(pad "2" smd rect
			(at -0.889 0 270)
			(size 1.016 1.27)
			(layers "B.Cu" "B.Mask" "B.Paste")
			(net "GND")
		)
	)
	(footprint ""
		(layer "B.Cu")
		(at 386.58165 -190.82131 90)
		(property "Reference" "R1226"
			(at 0 0 90)
			(layer "B.SilkS")
			(hide yes)
			(effects
				(font
					(size 1.27 1.27)
				)
				(justify mirror)
			)
		)
		(property "Value" ""
			(at 0 0 90)
			(layer "B.Fab")
			(effects
				(font
					(size 1.27 1.27)
				)
				(justify mirror)
			)
		)
		(duplicate_pad_numbers_are_jumpers no)
		(fp_line
			(start 0.7874 -0.4064)
			(end -0.7874 -0.4064)
			(stroke
				(width 0.1524)
				(type default)
			)
			(layer "B.SilkS")
		)
		(fp_line
			(start -0.7874 -0.4064)
			(end -0.7874 0.4064)
			(stroke
				(width 0.1524)
				(type default)
			)
			(layer "B.SilkS")
		)
		(fp_line
			(start 0.7874 0.4064)
			(end 0.7874 -0.4064)
			(stroke
				(width 0.1524)
				(type default)
			)
			(layer "B.SilkS")
		)
		(fp_line
			(start -0.7874 0.4064)
			(end 0.7874 0.4064)
			(stroke
				(width 0.1524)
				(type default)
			)
			(layer "B.SilkS")
		)
		(fp_line
			(start 0.67945 -0.305054)
			(end 0.12065 -0.305054)
			(stroke
				(width 0.1)
				(type default)
			)
			(layer "B.Fab")
		)
		(fp_line
			(start 0.12065 -0.305054)
			(end 0.12065 -0.2794)
			(stroke
				(width 0.1)
				(type default)
			)
			(layer "B.Fab")
		)
		(fp_line
			(start -0.12065 -0.3048)
			(end -0.67945 -0.3048)
			(stroke
				(width 0.1)
				(type default)
			)
			(layer "B.Fab")
		)
		(fp_line
			(start -0.67945 -0.3048)
			(end -0.67945 0.3048)
			(stroke
				(width 0.1)
				(type default)
			)
			(layer "B.Fab")
		)
		(fp_line
			(start 0.12065 -0.2794)
			(end -0.12065 -0.2794)
			(stroke
				(width 0.1)
				(type default)
			)
			(layer "B.Fab")
		)
		(fp_line
			(start -0.12065 -0.2794)
			(end -0.12065 -0.3048)
			(stroke
				(width 0.1)
				(type default)
			)
			(layer "B.Fab")
		)
		(fp_line
			(start 0.12065 0.2794)
			(end 0.12065 0.3048)
			(stroke
				(width 0.1)
				(type default)
			)
			(layer "B.Fab")
		)
		(fp_line
			(start -0.120396 0.2794)
			(end 0.12065 0.2794)
			(stroke
				(width 0.1)
				(type default)
			)
			(layer "B.Fab")
		)
		(fp_line
			(start 0.67945 0.3048)
			(end 0.67945 -0.305054)
			(stroke
				(width 0.1)
				(type default)
			)
			(layer "B.Fab")
		)
		(fp_line
			(start 0.12065 0.3048)
			(end 0.67945 0.3048)
			(stroke
				(width 0.1)
				(type default)
			)
			(layer "B.Fab")
		)
		(fp_line
			(start -0.120396 0.3048)
			(end -0.120396 0.2794)
			(stroke
				(width 0.1)
				(type default)
			)
			(layer "B.Fab")
		)
		(fp_line
			(start -0.67945 0.3048)
			(end -0.120396 0.3048)
			(stroke
				(width 0.1)
				(type default)
			)
			(layer "B.Fab")
		)
		(pad "1" smd circle
			(at 0.40005 0 270)
			(size 0 0)
			(layers "B.Cu" "B.Mask" "B.Paste")
			(net "PD_JTAG_CPU0_PLD_TCK")
		)
		(pad "2" smd circle
			(at -0.40005 0 270)
			(size 0 0)
			(layers "B.Cu" "B.Mask" "B.Paste")
			(net "GND")
		)
	)
	(footprint ""
		(layer "B.Cu")
		(at 348.479364 -356.192836 180)
		(property "Reference" "C3271"
			(at 0 0 0)
			(layer "B.SilkS")
			(hide yes)
			(effects
				(font
					(size 1.27 1.27)
				)
				(justify mirror)
			)
		)
		(property "Value" ""
			(at 0 0 0)
			(layer "B.Fab")
			(effects
				(font
					(size 1.27 1.27)
				)
				(justify mirror)
			)
		)
		(duplicate_pad_numbers_are_jumpers no)
		(fp_line
			(start 0.7874 0.4064)
			(end 0.7874 -0.4064)
			(stroke
				(width 0.1524)
				(type default)
			)
			(layer "B.SilkS")
		)
		(fp_line
			(start 0.7874 -0.4064)
			(end -0.7874 -0.4064)
			(stroke
				(width 0.1524)
				(type default)
			)
			(layer "B.SilkS")
		)
		(fp_line
			(start -0.7874 0.4064)
			(end 0.7874 0.4064)
			(stroke
				(width 0.1524)
				(type default)
			)
			(layer "B.SilkS")
		)
		(fp_line
			(start -0.7874 -0.4064)
			(end -0.7874 0.4064)
			(stroke
				(width 0.1524)
				(type default)
			)
			(layer "B.SilkS")
		)
		(fp_line
			(start 0.67945 0.3048)
			(end 0.67945 -0.305054)
			(stroke
				(width 0.1)
				(type default)
			)
			(layer "B.Fab")
		)
		(fp_line
			(start 0.67945 -0.305054)
			(end 0.12065 -0.305054)
			(stroke
				(width 0.1)
				(type default)
			)
			(layer "B.Fab")
		)
		(fp_line
			(start 0.12065 0.3048)
			(end 0.67945 0.3048)
			(stroke
				(width 0.1)
				(type default)
			)
			(layer "B.Fab")
		)
		(fp_line
			(start 0.12065 0.2794)
			(end 0.12065 0.3048)
			(stroke
				(width 0.1)
				(type default)
			)
			(layer "B.Fab")
		)
		(fp_line
			(start 0.12065 -0.2794)
			(end -0.12065 -0.2794)
			(stroke
				(width 0.1)
				(type default)
			)
			(layer "B.Fab")
		)
		(fp_line
			(start 0.12065 -0.305054)
			(end 0.12065 -0.2794)
			(stroke
				(width 0.1)
				(type default)
			)
			(layer "B.Fab")
		)
		(fp_line
			(start -0.120396 0.3048)
			(end -0.120396 0.2794)
			(stroke
				(width 0.1)
				(type default)
			)
			(layer "B.Fab")
		)
		(fp_line
			(start -0.120396 0.2794)
			(end 0.12065 0.2794)
			(stroke
				(width 0.1)
				(type default)
			)
			(layer "B.Fab")
		)
		(fp_line
			(start -0.12065 -0.2794)
			(end -0.12065 -0.3048)
			(stroke
				(width 0.1)
				(type default)
			)
			(layer "B.Fab")
		)
		(fp_line
			(start -0.12065 -0.3048)
			(end -0.67945 -0.3048)
			(stroke
				(width 0.1)
				(type default)
			)
			(layer "B.Fab")
		)
		(fp_line
			(start -0.67945 0.3048)
			(end -0.120396 0.3048)
			(stroke
				(width 0.1)
				(type default)
			)
			(layer "B.Fab")
		)
		(fp_line
			(start -0.67945 -0.3048)
			(end -0.67945 0.3048)
			(stroke
				(width 0.1)
				(type default)
			)
			(layer "B.Fab")
		)
		(pad "1" smd circle
			(at 0.40005 0)
			(size 0 0)
			(layers "B.Cu" "B.Mask" "B.Paste")
			(net "PVNN_TERM_CPU0")
		)
		(pad "2" smd circle
			(at -0.40005 0)
			(size 0 0)
			(layers "B.Cu" "B.Mask" "B.Paste")
			(net "GND")
		)
	)
	(footprint ""
		(layer "B.Cu")
		(at 301.724314 -353.955096 -90)
		(property "Reference" "PC613_P0_2"
			(at 0 0 90)
			(layer "B.SilkS")
			(hide yes)
			(effects
				(font
					(size 1.27 1.27)
				)
				(justify mirror)
			)
		)
		(property "Value" ""
			(at 0 0 90)
			(layer "B.Fab")
			(effects
				(font
					(size 1.27 1.27)
				)
				(justify mirror)
			)
		)
		(duplicate_pad_numbers_are_jumpers no)
		(fp_line
			(start -0.7874 0.4064)
			(end 0.7874 0.4064)
			(stroke
				(width 0.1524)
				(type default)
			)
			(layer "B.SilkS")
		)
		(fp_line
			(start 0.7874 0.4064)
			(end 0.7874 -0.4064)
			(stroke
				(width 0.1524)
				(type default)
			)
			(layer "B.SilkS")
		)
		(fp_line
			(start -0.7874 -0.4064)
			(end -0.7874 0.4064)
			(stroke
				(width 0.1524)
				(type default)
			)
			(layer "B.SilkS")
		)
		(fp_line
			(start 0.7874 -0.4064)
			(end -0.7874 -0.4064)
			(stroke
				(width 0.1524)
				(type default)
			)
			(layer "B.SilkS")
		)
		(fp_line
			(start -0.67945 0.3048)
			(end -0.120396 0.3048)
			(stroke
				(width 0.1)
				(type default)
			)
			(layer "B.Fab")
		)
		(fp_line
			(start -0.120396 0.3048)
			(end -0.120396 0.2794)
			(stroke
				(width 0.1)
				(type default)
			)
			(layer "B.Fab")
		)
		(fp_line
			(start 0.12065 0.3048)
			(end 0.67945 0.3048)
			(stroke
				(width 0.1)
				(type default)
			)
			(layer "B.Fab")
		)
		(fp_line
			(start 0.67945 0.3048)
			(end 0.67945 -0.305054)
			(stroke
				(width 0.1)
				(type default)
			)
			(layer "B.Fab")
		)
		(fp_line
			(start -0.120396 0.2794)
			(end 0.12065 0.2794)
			(stroke
				(width 0.1)
				(type default)
			)
			(layer "B.Fab")
		)
		(fp_line
			(start 0.12065 0.2794)
			(end 0.12065 0.3048)
			(stroke
				(width 0.1)
				(type default)
			)
			(layer "B.Fab")
		)
		(fp_line
			(start -0.12065 -0.2794)
			(end -0.12065 -0.3048)
			(stroke
				(width 0.1)
				(type default)
			)
			(layer "B.Fab")
		)
		(fp_line
			(start 0.12065 -0.2794)
			(end -0.12065 -0.2794)
			(stroke
				(width 0.1)
				(type default)
			)
			(layer "B.Fab")
		)
		(fp_line
			(start -0.67945 -0.3048)
			(end -0.67945 0.3048)
			(stroke
				(width 0.1)
				(type default)
			)
			(layer "B.Fab")
		)
		(fp_line
			(start -0.12065 -0.3048)
			(end -0.67945 -0.3048)
			(stroke
				(width 0.1)
				(type default)
			)
			(layer "B.Fab")
		)
		(fp_line
			(start 0.12065 -0.305054)
			(end 0.12065 -0.2794)
			(stroke
				(width 0.1)
				(type default)
			)
			(layer "B.Fab")
		)
		(fp_line
			(start 0.67945 -0.305054)
			(end 0.12065 -0.305054)
			(stroke
				(width 0.1)
				(type default)
			)
			(layer "B.Fab")
		)
		(pad "1" smd circle
			(at 0.40005 0 90)
			(size 0 0)
			(layers "B.Cu" "B.Mask" "B.Paste")
			(net "PVCCFA_EHV_FIVRA_CPU0")
		)
		(pad "2" smd circle
			(at -0.40005 0 90)
			(size 0 0)
			(layers "B.Cu" "B.Mask" "B.Paste")
			(net "GND")
		)
	)
	(footprint ""
		(layer "B.Cu")
		(at 190.248286 -193.615056 -90)
		(property "Reference" "R815"
			(at 0 0 90)
			(layer "B.SilkS")
			(hide yes)
			(effects
				(font
					(size 1.27 1.27)
				)
				(justify mirror)
			)
		)
		(property "Value" ""
			(at 0 0 90)
			(layer "B.Fab")
			(effects
				(font
					(size 1.27 1.27)
				)
				(justify mirror)
			)
		)
		(duplicate_pad_numbers_are_jumpers no)
		(fp_line
			(start -0.7874 0.4064)
			(end 0.7874 0.4064)
			(stroke
				(width 0.1524)
				(type default)
			)
			(layer "B.SilkS")
		)
		(fp_line
			(start 0.7874 0.4064)
			(end 0.7874 -0.4064)
			(stroke
				(width 0.1524)
				(type default)
			)
			(layer "B.SilkS")
		)
		(fp_line
			(start -0.7874 -0.4064)
			(end -0.7874 0.4064)
			(stroke
				(width 0.1524)
				(type default)
			)
			(layer "B.SilkS")
		)
		(fp_line
			(start 0.7874 -0.4064)
			(end -0.7874 -0.4064)
			(stroke
				(width 0.1524)
				(type default)
			)
			(layer "B.SilkS")
		)
		(fp_line
			(start -0.67945 0.3048)
			(end -0.120396 0.3048)
			(stroke
				(width 0.1)
				(type default)
			)
			(layer "B.Fab")
		)
		(fp_line
			(start -0.120396 0.3048)
			(end -0.120396 0.2794)
			(stroke
				(width 0.1)
				(type default)
			)
			(layer "B.Fab")
		)
		(fp_line
			(start 0.12065 0.3048)
			(end 0.67945 0.3048)
			(stroke
				(width 0.1)
				(type default)
			)
			(layer "B.Fab")
		)
		(fp_line
			(start 0.67945 0.3048)
			(end 0.67945 -0.305054)
			(stroke
				(width 0.1)
				(type default)
			)
			(layer "B.Fab")
		)
		(fp_line
			(start -0.120396 0.2794)
			(end 0.12065 0.2794)
			(stroke
				(width 0.1)
				(type default)
			)
			(layer "B.Fab")
		)
		(fp_line
			(start 0.12065 0.2794)
			(end 0.12065 0.3048)
			(stroke
				(width 0.1)
				(type default)
			)
			(layer "B.Fab")
		)
		(fp_line
			(start -0.12065 -0.2794)
			(end -0.12065 -0.3048)
			(stroke
				(width 0.1)
				(type default)
			)
			(layer "B.Fab")
		)
		(fp_line
			(start 0.12065 -0.2794)
			(end -0.12065 -0.2794)
			(stroke
				(width 0.1)
				(type default)
			)
			(layer "B.Fab")
		)
		(fp_line
			(start -0.67945 -0.3048)
			(end -0.67945 0.3048)
			(stroke
				(width 0.1)
				(type default)
			)
			(layer "B.Fab")
		)
		(fp_line
			(start -0.12065 -0.3048)
			(end -0.67945 -0.3048)
			(stroke
				(width 0.1)
				(type default)
			)
			(layer "B.Fab")
		)
		(fp_line
			(start 0.12065 -0.305054)
			(end 0.12065 -0.2794)
			(stroke
				(width 0.1)
				(type default)
			)
			(layer "B.Fab")
		)
		(fp_line
			(start 0.67945 -0.305054)
			(end 0.12065 -0.305054)
			(stroke
				(width 0.1)
				(type default)
			)
			(layer "B.Fab")
		)
		(pad "1" smd circle
			(at 0.40005 0 90)
			(size 0 0)
			(layers "B.Cu" "B.Mask" "B.Paste")
			(net "RST_PLD_CPU1_DRAM_GH_N")
		)
		(pad "2" smd circle
			(at -0.40005 0 90)
			(size 0 0)
			(layers "B.Cu" "B.Mask" "B.Paste")
			(net "RST_M_GH_CPU1_FPGA_N")
		)
	)
	(footprint ""
		(layer "B.Cu")
		(at 303.472342 -149.533356 180)
		(property "Reference" "C538"
			(at 0 0 0)
			(layer "B.SilkS")
			(hide yes)
			(effects
				(font
					(size 1.27 1.27)
				)
				(justify mirror)
			)
		)
		(property "Value" ""
			(at 0 0 0)
			(layer "B.Fab")
			(effects
				(font
					(size 1.27 1.27)
				)
				(justify mirror)
			)
		)
		(duplicate_pad_numbers_are_jumpers no)
		(fp_line
			(start 0.7874 0.4064)
			(end 0.7874 -0.4064)
			(stroke
				(width 0.1524)
				(type default)
			)
			(layer "B.SilkS")
		)
		(fp_line
			(start 0.7874 -0.4064)
			(end -0.7874 -0.4064)
			(stroke
				(width 0.1524)
				(type default)
			)
			(layer "B.SilkS")
		)
		(fp_line
			(start -0.7874 0.4064)
			(end 0.7874 0.4064)
			(stroke
				(width 0.1524)
				(type default)
			)
			(layer "B.SilkS")
		)
		(fp_line
			(start -0.7874 -0.4064)
			(end -0.7874 0.4064)
			(stroke
				(width 0.1524)
				(type default)
			)
			(layer "B.SilkS")
		)
		(fp_line
			(start 0.67945 0.3048)
			(end 0.67945 -0.305054)
			(stroke
				(width 0.1)
				(type default)
			)
			(layer "B.Fab")
		)
		(fp_line
			(start 0.67945 -0.305054)
			(end 0.12065 -0.305054)
			(stroke
				(width 0.1)
				(type default)
			)
			(layer "B.Fab")
		)
		(fp_line
			(start 0.12065 0.3048)
			(end 0.67945 0.3048)
			(stroke
				(width 0.1)
				(type default)
			)
			(layer "B.Fab")
		)
		(fp_line
			(start 0.12065 0.2794)
			(end 0.12065 0.3048)
			(stroke
				(width 0.1)
				(type default)
			)
			(layer "B.Fab")
		)
		(fp_line
			(start 0.12065 -0.2794)
			(end -0.12065 -0.2794)
			(stroke
				(width 0.1)
				(type default)
			)
			(layer "B.Fab")
		)
		(fp_line
			(start 0.12065 -0.305054)
			(end 0.12065 -0.2794)
			(stroke
				(width 0.1)
				(type default)
			)
			(layer "B.Fab")
		)
		(fp_line
			(start -0.120396 0.3048)
			(end -0.120396 0.2794)
			(stroke
				(width 0.1)
				(type default)
			)
			(layer "B.Fab")
		)
		(fp_line
			(start -0.120396 0.2794)
			(end 0.12065 0.2794)
			(stroke
				(width 0.1)
				(type default)
			)
			(layer "B.Fab")
		)
		(fp_line
			(start -0.12065 -0.2794)
			(end -0.12065 -0.3048)
			(stroke
				(width 0.1)
				(type default)
			)
			(layer "B.Fab")
		)
		(fp_line
			(start -0.12065 -0.3048)
			(end -0.67945 -0.3048)
			(stroke
				(width 0.1)
				(type default)
			)
			(layer "B.Fab")
		)
		(fp_line
			(start -0.67945 0.3048)
			(end -0.120396 0.3048)
			(stroke
				(width 0.1)
				(type default)
			)
			(layer "B.Fab")
		)
		(fp_line
			(start -0.67945 -0.3048)
			(end -0.67945 0.3048)
			(stroke
				(width 0.1)
				(type default)
			)
			(layer "B.Fab")
		)
		(pad "1" smd circle
			(at 0.40005 0)
			(size 0 0)
			(layers "B.Cu" "B.Mask" "B.Paste")
			(net "P3V3_AUX")
		)
		(pad "2" smd circle
			(at -0.40005 0)
			(size 0 0)
			(layers "B.Cu" "B.Mask" "B.Paste")
			(net "GND")
		)
	)
	(footprint ""
		(layer "B.Cu")
		(at 305.470814 -258.379976 -90)
		(property "Reference" "C521"
			(at 0 0 90)
			(layer "B.SilkS")
			(hide yes)
			(effects
				(font
					(size 1.27 1.27)
				)
				(justify mirror)
			)
		)
		(property "Value" ""
			(at 0 0 90)
			(layer "B.Fab")
			(effects
				(font
					(size 1.27 1.27)
				)
				(justify mirror)
			)
		)
		(duplicate_pad_numbers_are_jumpers no)
		(fp_line
			(start -1.524 0.762)
			(end 1.524 0.762)
			(stroke
				(width 0.1524)
				(type default)
			)
			(layer "B.SilkS")
		)
		(fp_line
			(start 1.524 0.762)
			(end 1.524 -0.762)
			(stroke
				(width 0.1524)
				(type default)
			)
			(layer "B.SilkS")
		)
		(fp_line
			(start -1.524 -0.762)
			(end -1.524 0.762)
			(stroke
				(width 0.1524)
				(type default)
			)
			(layer "B.SilkS")
		)
		(fp_line
			(start 1.524 -0.762)
			(end -1.524 -0.762)
			(stroke
				(width 0.1524)
				(type default)
			)
			(layer "B.SilkS")
		)
		(fp_line
			(start -1.1049 0.724916)
			(end -1.1049 -0.724916)
			(stroke
				(width 0.1)
				(type default)
			)
			(layer "B.Fab")
		)
		(fp_line
			(start 1.1049 0.724916)
			(end -1.1049 0.724916)
			(stroke
				(width 0.1)
				(type default)
			)
			(layer "B.Fab")
		)
		(fp_line
			(start -1.1049 -0.724916)
			(end 1.1049 -0.724916)
			(stroke
				(width 0.1)
				(type default)
			)
			(layer "B.Fab")
		)
		(fp_line
			(start 1.1049 -0.724916)
			(end 1.1049 0.724916)
			(stroke
				(width 0.1)
				(type default)
			)
			(layer "B.Fab")
		)
		(pad "1" smd rect
			(at 0.889 0 270)
			(size 1.016 1.27)
			(layers "B.Cu" "B.Mask" "B.Paste")
			(net "PVCCFA_EHV_FIVRA_CPU0")
		)
		(pad "2" smd rect
			(at -0.889 0 270)
			(size 1.016 1.27)
			(layers "B.Cu" "B.Mask" "B.Paste")
			(net "GND")
		)
	)
	(footprint ""
		(layer "B.Cu")
		(at 181.755542 -111.375444)
		(property "Reference" "C1138"
			(at 0 0 0)
			(layer "B.SilkS")
			(hide yes)
			(effects
				(font
					(size 1.27 1.27)
				)
				(justify mirror)
			)
		)
		(property "Value" ""
			(at 0 0 0)
			(layer "B.Fab")
			(effects
				(font
					(size 1.27 1.27)
				)
				(justify mirror)
			)
		)
		(duplicate_pad_numbers_are_jumpers no)
		(fp_line
			(start -0.69215 -0.2921)
			(end -0.69215 0.2921)
			(stroke
				(width 0.1524)
				(type default)
			)
			(layer "B.SilkS")
		)
		(fp_line
			(start -0.69215 0.2921)
			(end 0.69215 0.2921)
			(stroke
				(width 0.1524)
				(type default)
			)
			(layer "B.SilkS")
		)
		(fp_line
			(start 0.69215 -0.2921)
			(end -0.69215 -0.2921)
			(stroke
				(width 0.1524)
				(type default)
			)
			(layer "B.SilkS")
		)
		(fp_line
			(start 0.69215 0.2921)
			(end 0.69215 -0.2921)
			(stroke
				(width 0.1524)
				(type default)
			)
			(layer "B.SilkS")
		)
		(fp_line
			(start -0.51435 -0.2794)
			(end -0.51435 0.2794)
			(stroke
				(width 0.1)
				(type default)
			)
			(layer "B.Fab")
		)
		(fp_line
			(start -0.51435 0.2794)
			(end 0.51435 0.2794)
			(stroke
				(width 0.1)
				(type default)
			)
			(layer "B.Fab")
		)
		(fp_line
			(start 0.51435 -0.2794)
			(end -0.51435 -0.2794)
			(stroke
				(width 0.1)
				(type default)
			)
			(layer "B.Fab")
		)
		(fp_line
			(start 0.51435 0.2794)
			(end 0.51435 -0.2794)
			(stroke
				(width 0.1)
				(type default)
			)
			(layer "B.Fab")
		)
		(pad "1" smd circle
			(at 0.40005 0 180)
			(size 0 0)
			(layers "B.Cu" "B.Mask" "B.Paste")
			(net "P3V3_AUX_FPGA_VCCIO2")
		)
		(pad "2" smd circle
			(at -0.40005 0 180)
			(size 0 0)
			(layers "B.Cu" "B.Mask" "B.Paste")
			(net "GND")
		)
		(zone
			(layer "B.Cu")
			(hatch none 0.5)
			(connect_pads
				(clearance 0)
			)
			(min_thickness 0.25)
			(keepout
				(tracks not_allowed)
				(vias allowed)
				(pads allowed)
				(copperpour not_allowed)
				(footprints allowed)
			)
			(placement
				(enabled no)
				(sheetname "")
			)
			(fill
				(thermal_gap 0.5)
				(thermal_bridge_width 0.5)
				(island_removal_mode 0)
			)
			(polygon
				(pts
					(xy 181.946042 -111.287814) (xy 181.854602 -111.229648) (xy 181.655212 -111.229648) (xy 181.565042 -111.287814)
					(xy 181.565042 -111.463074) (xy 181.655212 -111.521494) (xy 181.854602 -111.521494) (xy 181.946042 -111.463328)
				)
			)
		)
	)
	(footprint ""
		(layer "B.Cu")
		(at 461.445356 -321.549776 -90)
		(property "Reference" "C46"
			(at 0 0 90)
			(layer "B.SilkS")
			(hide yes)
			(effects
				(font
					(size 1.27 1.27)
				)
				(justify mirror)
			)
		)
		(property "Value" ""
			(at 0 0 90)
			(layer "B.Fab")
			(effects
				(font
					(size 1.27 1.27)
				)
				(justify mirror)
			)
		)
		(duplicate_pad_numbers_are_jumpers no)
		(fp_line
			(start -1.524 0.762)
			(end 1.524 0.762)
			(stroke
				(width 0.1524)
				(type default)
			)
			(layer "B.SilkS")
		)
		(fp_line
			(start 1.524 0.762)
			(end 1.524 -0.762)
			(stroke
				(width 0.1524)
				(type default)
			)
			(layer "B.SilkS")
		)
		(fp_line
			(start -1.524 -0.762)
			(end -1.524 0.762)
			(stroke
				(width 0.1524)
				(type default)
			)
			(layer "B.SilkS")
		)
		(fp_line
			(start 1.524 -0.762)
			(end -1.524 -0.762)
			(stroke
				(width 0.1524)
				(type default)
			)
			(layer "B.SilkS")
		)
		(fp_line
			(start -1.1049 0.724916)
			(end -1.1049 -0.724916)
			(stroke
				(width 0.1)
				(type default)
			)
			(layer "B.Fab")
		)
		(fp_line
			(start 1.1049 0.724916)
			(end -1.1049 0.724916)
			(stroke
				(width 0.1)
				(type default)
			)
			(layer "B.Fab")
		)
		(fp_line
			(start -1.1049 -0.724916)
			(end 1.1049 -0.724916)
			(stroke
				(width 0.1)
				(type default)
			)
			(layer "B.Fab")
		)
		(fp_line
			(start 1.1049 -0.724916)
			(end 1.1049 0.724916)
			(stroke
				(width 0.1)
				(type default)
			)
			(layer "B.Fab")
		)
		(pad "1" smd rect
			(at 0.889 0 270)
			(size 1.016 1.27)
			(layers "B.Cu" "B.Mask" "B.Paste")
			(net "P12V_S3_AUX_CPU0_NVDIMM")
		)
		(pad "2" smd rect
			(at -0.889 0 270)
			(size 1.016 1.27)
			(layers "B.Cu" "B.Mask" "B.Paste")
			(net "GND")
		)
	)
	(footprint ""
		(layer "B.Cu")
		(at 245.8212 -102.112318 180)
		(property "Reference" "R1958"
			(at 0 0 0)
			(layer "B.SilkS")
			(hide yes)
			(effects
				(font
					(size 1.27 1.27)
				)
				(justify mirror)
			)
		)
		(property "Value" ""
			(at 0 0 0)
			(layer "B.Fab")
			(effects
				(font
					(size 1.27 1.27)
				)
				(justify mirror)
			)
		)
		(duplicate_pad_numbers_are_jumpers no)
		(fp_line
			(start 0.7874 0.4064)
			(end 0.7874 -0.4064)
			(stroke
				(width 0.1524)
				(type default)
			)
			(layer "B.SilkS")
		)
		(fp_line
			(start 0.7874 -0.4064)
			(end -0.7874 -0.4064)
			(stroke
				(width 0.1524)
				(type default)
			)
			(layer "B.SilkS")
		)
		(fp_line
			(start -0.7874 0.4064)
			(end 0.7874 0.4064)
			(stroke
				(width 0.1524)
				(type default)
			)
			(layer "B.SilkS")
		)
		(fp_line
			(start -0.7874 -0.4064)
			(end -0.7874 0.4064)
			(stroke
				(width 0.1524)
				(type default)
			)
			(layer "B.SilkS")
		)
		(fp_line
			(start 0.67945 0.3048)
			(end 0.67945 -0.305054)
			(stroke
				(width 0.1)
				(type default)
			)
			(layer "B.Fab")
		)
		(fp_line
			(start 0.67945 -0.305054)
			(end 0.12065 -0.305054)
			(stroke
				(width 0.1)
				(type default)
			)
			(layer "B.Fab")
		)
		(fp_line
			(start 0.12065 0.3048)
			(end 0.67945 0.3048)
			(stroke
				(width 0.1)
				(type default)
			)
			(layer "B.Fab")
		)
		(fp_line
			(start 0.12065 0.2794)
			(end 0.12065 0.3048)
			(stroke
				(width 0.1)
				(type default)
			)
			(layer "B.Fab")
		)
		(fp_line
			(start 0.12065 -0.2794)
			(end -0.12065 -0.2794)
			(stroke
				(width 0.1)
				(type default)
			)
			(layer "B.Fab")
		)
		(fp_line
			(start 0.12065 -0.305054)
			(end 0.12065 -0.2794)
			(stroke
				(width 0.1)
				(type default)
			)
			(layer "B.Fab")
		)
		(fp_line
			(start -0.120396 0.3048)
			(end -0.120396 0.2794)
			(stroke
				(width 0.1)
				(type default)
			)
			(layer "B.Fab")
		)
		(fp_line
			(start -0.120396 0.2794)
			(end 0.12065 0.2794)
			(stroke
				(width 0.1)
				(type default)
			)
			(layer "B.Fab")
		)
		(fp_line
			(start -0.12065 -0.2794)
			(end -0.12065 -0.3048)
			(stroke
				(width 0.1)
				(type default)
			)
			(layer "B.Fab")
		)
		(fp_line
			(start -0.12065 -0.3048)
			(end -0.67945 -0.3048)
			(stroke
				(width 0.1)
				(type default)
			)
			(layer "B.Fab")
		)
		(fp_line
			(start -0.67945 0.3048)
			(end -0.120396 0.3048)
			(stroke
				(width 0.1)
				(type default)
			)
			(layer "B.Fab")
		)
		(fp_line
			(start -0.67945 -0.3048)
			(end -0.67945 0.3048)
			(stroke
				(width 0.1)
				(type default)
			)
			(layer "B.Fab")
		)
		(pad "1" smd circle
			(at 0.40005 0)
			(size 0 0)
			(layers "B.Cu" "B.Mask" "B.Paste")
			(net "P3V3_AUX")
		)
		(pad "2" smd circle
			(at -0.40005 0)
			(size 0 0)
			(layers "B.Cu" "B.Mask" "B.Paste")
			(net "PU_CLK_PFT_LOST_N")
		)
	)
	(footprint ""
		(layer "B.Cu")
		(at 173.22292 -13.762228 90)
		(property "Reference" "R2425"
			(at 0 0 90)
			(layer "B.SilkS")
			(hide yes)
			(effects
				(font
					(size 1.27 1.27)
				)
				(justify mirror)
			)
		)
		(property "Value" ""
			(at 0 0 90)
			(layer "B.Fab")
			(effects
				(font
					(size 1.27 1.27)
				)
				(justify mirror)
			)
		)
		(duplicate_pad_numbers_are_jumpers no)
		(fp_line
			(start 0.7874 -0.4064)
			(end -0.7874 -0.4064)
			(stroke
				(width 0.1524)
				(type default)
			)
			(layer "B.SilkS")
		)
		(fp_line
			(start -0.7874 -0.4064)
			(end -0.7874 0.4064)
			(stroke
				(width 0.1524)
				(type default)
			)
			(layer "B.SilkS")
		)
		(fp_line
			(start 0.7874 0.4064)
			(end 0.7874 -0.4064)
			(stroke
				(width 0.1524)
				(type default)
			)
			(layer "B.SilkS")
		)
		(fp_line
			(start -0.7874 0.4064)
			(end 0.7874 0.4064)
			(stroke
				(width 0.1524)
				(type default)
			)
			(layer "B.SilkS")
		)
		(fp_line
			(start 0.67945 -0.305054)
			(end 0.12065 -0.305054)
			(stroke
				(width 0.1)
				(type default)
			)
			(layer "B.Fab")
		)
		(fp_line
			(start 0.12065 -0.305054)
			(end 0.12065 -0.2794)
			(stroke
				(width 0.1)
				(type default)
			)
			(layer "B.Fab")
		)
		(fp_line
			(start -0.12065 -0.3048)
			(end -0.67945 -0.3048)
			(stroke
				(width 0.1)
				(type default)
			)
			(layer "B.Fab")
		)
		(fp_line
			(start -0.67945 -0.3048)
			(end -0.67945 0.3048)
			(stroke
				(width 0.1)
				(type default)
			)
			(layer "B.Fab")
		)
		(fp_line
			(start 0.12065 -0.2794)
			(end -0.12065 -0.2794)
			(stroke
				(width 0.1)
				(type default)
			)
			(layer "B.Fab")
		)
		(fp_line
			(start -0.12065 -0.2794)
			(end -0.12065 -0.3048)
			(stroke
				(width 0.1)
				(type default)
			)
			(layer "B.Fab")
		)
		(fp_line
			(start 0.12065 0.2794)
			(end 0.12065 0.3048)
			(stroke
				(width 0.1)
				(type default)
			)
			(layer "B.Fab")
		)
		(fp_line
			(start -0.120396 0.2794)
			(end 0.12065 0.2794)
			(stroke
				(width 0.1)
				(type default)
			)
			(layer "B.Fab")
		)
		(fp_line
			(start 0.67945 0.3048)
			(end 0.67945 -0.305054)
			(stroke
				(width 0.1)
				(type default)
			)
			(layer "B.Fab")
		)
		(fp_line
			(start 0.12065 0.3048)
			(end 0.67945 0.3048)
			(stroke
				(width 0.1)
				(type default)
			)
			(layer "B.Fab")
		)
		(fp_line
			(start -0.120396 0.3048)
			(end -0.120396 0.2794)
			(stroke
				(width 0.1)
				(type default)
			)
			(layer "B.Fab")
		)
		(fp_line
			(start -0.67945 0.3048)
			(end -0.120396 0.3048)
			(stroke
				(width 0.1)
				(type default)
			)
			(layer "B.Fab")
		)
		(pad "1" smd circle
			(at 0.40005 0 270)
			(size 0 0)
			(layers "B.Cu" "B.Mask" "B.Paste")
			(net "SMB_OCP_V3_2_3V3AUX_SCL")
		)
		(pad "2" smd circle
			(at -0.40005 0 270)
			(size 0 0)
			(layers "B.Cu" "B.Mask" "B.Paste")
			(net "SMB_OCP_V3_2_3V3AUX_SCL_R0")
		)
	)
	(footprint ""
		(layer "B.Cu")
		(at 288.376106 -313.866784 90)
		(property "Reference" "R2499"
			(at 0 0 90)
			(layer "B.SilkS")
			(hide yes)
			(effects
				(font
					(size 1.27 1.27)
				)
				(justify mirror)
			)
		)
		(property "Value" ""
			(at 0 0 90)
			(layer "B.Fab")
			(effects
				(font
					(size 1.27 1.27)
				)
				(justify mirror)
			)
		)
		(duplicate_pad_numbers_are_jumpers no)
		(fp_line
			(start 0.7874 -0.4064)
			(end -0.7874 -0.4064)
			(stroke
				(width 0.1524)
				(type default)
			)
			(layer "B.SilkS")
		)
		(fp_line
			(start -0.7874 -0.4064)
			(end -0.7874 0.4064)
			(stroke
				(width 0.1524)
				(type default)
			)
			(layer "B.SilkS")
		)
		(fp_line
			(start 0.7874 0.4064)
			(end 0.7874 -0.4064)
			(stroke
				(width 0.1524)
				(type default)
			)
			(layer "B.SilkS")
		)
		(fp_line
			(start -0.7874 0.4064)
			(end 0.7874 0.4064)
			(stroke
				(width 0.1524)
				(type default)
			)
			(layer "B.SilkS")
		)
		(fp_line
			(start 0.67945 -0.305054)
			(end 0.12065 -0.305054)
			(stroke
				(width 0.1)
				(type default)
			)
			(layer "B.Fab")
		)
		(fp_line
			(start 0.12065 -0.305054)
			(end 0.12065 -0.2794)
			(stroke
				(width 0.1)
				(type default)
			)
			(layer "B.Fab")
		)
		(fp_line
			(start -0.12065 -0.3048)
			(end -0.67945 -0.3048)
			(stroke
				(width 0.1)
				(type default)
			)
			(layer "B.Fab")
		)
		(fp_line
			(start -0.67945 -0.3048)
			(end -0.67945 0.3048)
			(stroke
				(width 0.1)
				(type default)
			)
			(layer "B.Fab")
		)
		(fp_line
			(start 0.12065 -0.2794)
			(end -0.12065 -0.2794)
			(stroke
				(width 0.1)
				(type default)
			)
			(layer "B.Fab")
		)
		(fp_line
			(start -0.12065 -0.2794)
			(end -0.12065 -0.3048)
			(stroke
				(width 0.1)
				(type default)
			)
			(layer "B.Fab")
		)
		(fp_line
			(start 0.12065 0.2794)
			(end 0.12065 0.3048)
			(stroke
				(width 0.1)
				(type default)
			)
			(layer "B.Fab")
		)
		(fp_line
			(start -0.120396 0.2794)
			(end 0.12065 0.2794)
			(stroke
				(width 0.1)
				(type default)
			)
			(layer "B.Fab")
		)
		(fp_line
			(start 0.67945 0.3048)
			(end 0.67945 -0.305054)
			(stroke
				(width 0.1)
				(type default)
			)
			(layer "B.Fab")
		)
		(fp_line
			(start 0.12065 0.3048)
			(end 0.67945 0.3048)
			(stroke
				(width 0.1)
				(type default)
			)
			(layer "B.Fab")
		)
		(fp_line
			(start -0.120396 0.3048)
			(end -0.120396 0.2794)
			(stroke
				(width 0.1)
				(type default)
			)
			(layer "B.Fab")
		)
		(fp_line
			(start -0.67945 0.3048)
			(end -0.120396 0.3048)
			(stroke
				(width 0.1)
				(type default)
			)
			(layer "B.Fab")
		)
		(pad "1" smd circle
			(at 0.40005 0 270)
			(size 0 0)
			(layers "B.Cu" "B.Mask" "B.Paste")
			(net "PWRGD_FAIL_CPU0_CD_R1")
		)
		(pad "2" smd circle
			(at -0.40005 0 270)
			(size 0 0)
			(layers "B.Cu" "B.Mask" "B.Paste")
			(net "PWRGD_FAIL_CPU0_CD_R")
		)
	)
	(footprint ""
		(layer "B.Cu")
		(at 302.151542 -50.923444 180)
		(property "Reference" "C1244"
			(at 0 0 0)
			(layer "B.SilkS")
			(hide yes)
			(effects
				(font
					(size 1.27 1.27)
				)
				(justify mirror)
			)
		)
		(property "Value" ""
			(at 0 0 0)
			(layer "B.Fab")
			(effects
				(font
					(size 1.27 1.27)
				)
				(justify mirror)
			)
		)
		(duplicate_pad_numbers_are_jumpers no)
		(fp_line
			(start 1.524 0.762)
			(end 1.524 -0.762)
			(stroke
				(width 0.1524)
				(type default)
			)
			(layer "B.SilkS")
		)
		(fp_line
			(start 1.524 -0.762)
			(end -1.524 -0.762)
			(stroke
				(width 0.1524)
				(type default)
			)
			(layer "B.SilkS")
		)
		(fp_line
			(start -1.524 0.762)
			(end 1.524 0.762)
			(stroke
				(width 0.1524)
				(type default)
			)
			(layer "B.SilkS")
		)
		(fp_line
			(start -1.524 -0.762)
			(end -1.524 0.762)
			(stroke
				(width 0.1524)
				(type default)
			)
			(layer "B.SilkS")
		)
		(fp_line
			(start 1.1049 0.724916)
			(end -1.1049 0.724916)
			(stroke
				(width 0.1)
				(type default)
			)
			(layer "B.Fab")
		)
		(fp_line
			(start 1.1049 -0.724916)
			(end 1.1049 0.724916)
			(stroke
				(width 0.1)
				(type default)
			)
			(layer "B.Fab")
		)
		(fp_line
			(start -1.1049 0.724916)
			(end -1.1049 -0.724916)
			(stroke
				(width 0.1)
				(type default)
			)
			(layer "B.Fab")
		)
		(fp_line
			(start -1.1049 -0.724916)
			(end 1.1049 -0.724916)
			(stroke
				(width 0.1)
				(type default)
			)
			(layer "B.Fab")
		)
		(pad "1" smd rect
			(at 0.889 0 180)
			(size 1.016 1.27)
			(layers "B.Cu" "B.Mask" "B.Paste")
			(net "P1V05_PCH_AUX")
		)
		(pad "2" smd rect
			(at -0.889 0 180)
			(size 1.016 1.27)
			(layers "B.Cu" "B.Mask" "B.Paste")
			(net "GND")
		)
	)
	(footprint ""
		(layer "B.Cu")
		(at 254.268986 -86.824566)
		(property "Reference" "R1471"
			(at 0 0 0)
			(layer "B.SilkS")
			(hide yes)
			(effects
				(font
					(size 1.27 1.27)
				)
				(justify mirror)
			)
		)
		(property "Value" ""
			(at 0 0 0)
			(layer "B.Fab")
			(effects
				(font
					(size 1.27 1.27)
				)
				(justify mirror)
			)
		)
		(duplicate_pad_numbers_are_jumpers no)
		(fp_line
			(start -0.7874 -0.4064)
			(end -0.7874 0.4064)
			(stroke
				(width 0.1524)
				(type default)
			)
			(layer "B.SilkS")
		)
		(fp_line
			(start -0.7874 0.4064)
			(end 0.7874 0.4064)
			(stroke
				(width 0.1524)
				(type default)
			)
			(layer "B.SilkS")
		)
		(fp_line
			(start 0.7874 -0.4064)
			(end -0.7874 -0.4064)
			(stroke
				(width 0.1524)
				(type default)
			)
			(layer "B.SilkS")
		)
		(fp_line
			(start 0.7874 0.4064)
			(end 0.7874 -0.4064)
			(stroke
				(width 0.1524)
				(type default)
			)
			(layer "B.SilkS")
		)
		(fp_line
			(start -0.67945 -0.3048)
			(end -0.67945 0.3048)
			(stroke
				(width 0.1)
				(type default)
			)
			(layer "B.Fab")
		)
		(fp_line
			(start -0.67945 0.3048)
			(end -0.120396 0.3048)
			(stroke
				(width 0.1)
				(type default)
			)
			(layer "B.Fab")
		)
		(fp_line
			(start -0.12065 -0.3048)
			(end -0.67945 -0.3048)
			(stroke
				(width 0.1)
				(type default)
			)
			(layer "B.Fab")
		)
		(fp_line
			(start -0.12065 -0.2794)
			(end -0.12065 -0.3048)
			(stroke
				(width 0.1)
				(type default)
			)
			(layer "B.Fab")
		)
		(fp_line
			(start -0.120396 0.2794)
			(end 0.12065 0.2794)
			(stroke
				(width 0.1)
				(type default)
			)
			(layer "B.Fab")
		)
		(fp_line
			(start -0.120396 0.3048)
			(end -0.120396 0.2794)
			(stroke
				(width 0.1)
				(type default)
			)
			(layer "B.Fab")
		)
		(fp_line
			(start 0.12065 -0.305054)
			(end 0.12065 -0.2794)
			(stroke
				(width 0.1)
				(type default)
			)
			(layer "B.Fab")
		)
		(fp_line
			(start 0.12065 -0.2794)
			(end -0.12065 -0.2794)
			(stroke
				(width 0.1)
				(type default)
			)
			(layer "B.Fab")
		)
		(fp_line
			(start 0.12065 0.2794)
			(end 0.12065 0.3048)
			(stroke
				(width 0.1)
				(type default)
			)
			(layer "B.Fab")
		)
		(fp_line
			(start 0.12065 0.3048)
			(end 0.67945 0.3048)
			(stroke
				(width 0.1)
				(type default)
			)
			(layer "B.Fab")
		)
		(fp_line
			(start 0.67945 -0.305054)
			(end 0.12065 -0.305054)
			(stroke
				(width 0.1)
				(type default)
			)
			(layer "B.Fab")
		)
		(fp_line
			(start 0.67945 0.3048)
			(end 0.67945 -0.305054)
			(stroke
				(width 0.1)
				(type default)
			)
			(layer "B.Fab")
		)
		(pad "1" smd circle
			(at 0.40005 0 180)
			(size 0 0)
			(layers "B.Cu" "B.Mask" "B.Paste")
			(net "P3V3_AUX")
		)
		(pad "2" smd circle
			(at -0.40005 0 180)
			(size 0 0)
			(layers "B.Cu" "B.Mask" "B.Paste")
			(net "FM_CLK_CK440_SS_EN")
		)
	)
	(footprint ""
		(layer "B.Cu")
		(at 312.090816 -27.320748 -90)
		(property "Reference" "C1209"
			(at 0 0 90)
			(layer "B.SilkS")
			(hide yes)
			(effects
				(font
					(size 1.27 1.27)
				)
				(justify mirror)
			)
		)
		(property "Value" ""
			(at 0 0 90)
			(layer "B.Fab")
			(effects
				(font
					(size 1.27 1.27)
				)
				(justify mirror)
			)
		)
		(duplicate_pad_numbers_are_jumpers no)
		(fp_line
			(start -0.7874 0.4064)
			(end 0.7874 0.4064)
			(stroke
				(width 0.1524)
				(type default)
			)
			(layer "B.SilkS")
		)
		(fp_line
			(start 0.7874 0.4064)
			(end 0.7874 -0.4064)
			(stroke
				(width 0.1524)
				(type default)
			)
			(layer "B.SilkS")
		)
		(fp_line
			(start -0.7874 -0.4064)
			(end -0.7874 0.4064)
			(stroke
				(width 0.1524)
				(type default)
			)
			(layer "B.SilkS")
		)
		(fp_line
			(start 0.7874 -0.4064)
			(end -0.7874 -0.4064)
			(stroke
				(width 0.1524)
				(type default)
			)
			(layer "B.SilkS")
		)
		(fp_line
			(start -0.67945 0.3048)
			(end -0.120396 0.3048)
			(stroke
				(width 0.1)
				(type default)
			)
			(layer "B.Fab")
		)
		(fp_line
			(start -0.120396 0.3048)
			(end -0.120396 0.2794)
			(stroke
				(width 0.1)
				(type default)
			)
			(layer "B.Fab")
		)
		(fp_line
			(start 0.12065 0.3048)
			(end 0.67945 0.3048)
			(stroke
				(width 0.1)
				(type default)
			)
			(layer "B.Fab")
		)
		(fp_line
			(start 0.67945 0.3048)
			(end 0.67945 -0.305054)
			(stroke
				(width 0.1)
				(type default)
			)
			(layer "B.Fab")
		)
		(fp_line
			(start -0.120396 0.2794)
			(end 0.12065 0.2794)
			(stroke
				(width 0.1)
				(type default)
			)
			(layer "B.Fab")
		)
		(fp_line
			(start 0.12065 0.2794)
			(end 0.12065 0.3048)
			(stroke
				(width 0.1)
				(type default)
			)
			(layer "B.Fab")
		)
		(fp_line
			(start -0.12065 -0.2794)
			(end -0.12065 -0.3048)
			(stroke
				(width 0.1)
				(type default)
			)
			(layer "B.Fab")
		)
		(fp_line
			(start 0.12065 -0.2794)
			(end -0.12065 -0.2794)
			(stroke
				(width 0.1)
				(type default)
			)
			(layer "B.Fab")
		)
		(fp_line
			(start -0.67945 -0.3048)
			(end -0.67945 0.3048)
			(stroke
				(width 0.1)
				(type default)
			)
			(layer "B.Fab")
		)
		(fp_line
			(start -0.12065 -0.3048)
			(end -0.67945 -0.3048)
			(stroke
				(width 0.1)
				(type default)
			)
			(layer "B.Fab")
		)
		(fp_line
			(start 0.12065 -0.305054)
			(end 0.12065 -0.2794)
			(stroke
				(width 0.1)
				(type default)
			)
			(layer "B.Fab")
		)
		(fp_line
			(start 0.67945 -0.305054)
			(end 0.12065 -0.305054)
			(stroke
				(width 0.1)
				(type default)
			)
			(layer "B.Fab")
		)
		(pad "1" smd circle
			(at 0.40005 0 90)
			(size 0 0)
			(layers "B.Cu" "B.Mask" "B.Paste")
			(net "PWRGD_SYS_PWROK_R")
		)
		(pad "2" smd circle
			(at -0.40005 0 90)
			(size 0 0)
			(layers "B.Cu" "B.Mask" "B.Paste")
			(net "GND")
		)
	)
	(footprint ""
		(layer "B.Cu")
		(at 93.571314 -336.278474 -90)
		(property "Reference" "PR330"
			(at 0 0 90)
			(layer "B.SilkS")
			(hide yes)
			(effects
				(font
					(size 1.27 1.27)
				)
				(justify mirror)
			)
		)
		(property "Value" ""
			(at 0 0 90)
			(layer "B.Fab")
			(effects
				(font
					(size 1.27 1.27)
				)
				(justify mirror)
			)
		)
		(duplicate_pad_numbers_are_jumpers no)
		(fp_line
			(start -0.7874 0.4064)
			(end 0.7874 0.4064)
			(stroke
				(width 0.1524)
				(type default)
			)
			(layer "B.SilkS")
		)
		(fp_line
			(start 0.7874 0.4064)
			(end 0.7874 -0.4064)
			(stroke
				(width 0.1524)
				(type default)
			)
			(layer "B.SilkS")
		)
		(fp_line
			(start -0.7874 -0.4064)
			(end -0.7874 0.4064)
			(stroke
				(width 0.1524)
				(type default)
			)
			(layer "B.SilkS")
		)
		(fp_line
			(start 0.7874 -0.4064)
			(end -0.7874 -0.4064)
			(stroke
				(width 0.1524)
				(type default)
			)
			(layer "B.SilkS")
		)
		(fp_line
			(start -0.67945 0.3048)
			(end -0.120396 0.3048)
			(stroke
				(width 0.1)
				(type default)
			)
			(layer "B.Fab")
		)
		(fp_line
			(start -0.120396 0.3048)
			(end -0.120396 0.2794)
			(stroke
				(width 0.1)
				(type default)
			)
			(layer "B.Fab")
		)
		(fp_line
			(start 0.12065 0.3048)
			(end 0.67945 0.3048)
			(stroke
				(width 0.1)
				(type default)
			)
			(layer "B.Fab")
		)
		(fp_line
			(start 0.67945 0.3048)
			(end 0.67945 -0.305054)
			(stroke
				(width 0.1)
				(type default)
			)
			(layer "B.Fab")
		)
		(fp_line
			(start -0.120396 0.2794)
			(end 0.12065 0.2794)
			(stroke
				(width 0.1)
				(type default)
			)
			(layer "B.Fab")
		)
		(fp_line
			(start 0.12065 0.2794)
			(end 0.12065 0.3048)
			(stroke
				(width 0.1)
				(type default)
			)
			(layer "B.Fab")
		)
		(fp_line
			(start -0.12065 -0.2794)
			(end -0.12065 -0.3048)
			(stroke
				(width 0.1)
				(type default)
			)
			(layer "B.Fab")
		)
		(fp_line
			(start 0.12065 -0.2794)
			(end -0.12065 -0.2794)
			(stroke
				(width 0.1)
				(type default)
			)
			(layer "B.Fab")
		)
		(fp_line
			(start -0.67945 -0.3048)
			(end -0.67945 0.3048)
			(stroke
				(width 0.1)
				(type default)
			)
			(layer "B.Fab")
		)
		(fp_line
			(start -0.12065 -0.3048)
			(end -0.67945 -0.3048)
			(stroke
				(width 0.1)
				(type default)
			)
			(layer "B.Fab")
		)
		(fp_line
			(start 0.12065 -0.305054)
			(end 0.12065 -0.2794)
			(stroke
				(width 0.1)
				(type default)
			)
			(layer "B.Fab")
		)
		(fp_line
			(start 0.67945 -0.305054)
			(end 0.12065 -0.305054)
			(stroke
				(width 0.1)
				(type default)
			)
			(layer "B.Fab")
		)
		(pad "1" smd circle
			(at 0.40005 0 90)
			(size 0 0)
			(layers "B.Cu" "B.Mask" "B.Paste")
			(net "PVCCIN_CPU1_VOS1")
		)
		(pad "2" smd circle
			(at -0.40005 0 90)
			(size 0 0)
			(layers "B.Cu" "B.Mask" "B.Paste")
			(net "PVCCIN_CPU1")
		)
	)
	(footprint ""
		(layer "B.Cu")
		(at 29.577538 -167.0177)
		(property "Reference" "PR218"
			(at 0 0 0)
			(layer "B.SilkS")
			(hide yes)
			(effects
				(font
					(size 1.27 1.27)
				)
				(justify mirror)
			)
		)
		(property "Value" ""
			(at 0 0 0)
			(layer "B.Fab")
			(effects
				(font
					(size 1.27 1.27)
				)
				(justify mirror)
			)
		)
		(duplicate_pad_numbers_are_jumpers no)
		(fp_line
			(start -0.7874 -0.4064)
			(end -0.7874 0.4064)
			(stroke
				(width 0.1524)
				(type default)
			)
			(layer "B.SilkS")
		)
		(fp_line
			(start -0.7874 0.4064)
			(end 0.7874 0.4064)
			(stroke
				(width 0.1524)
				(type default)
			)
			(layer "B.SilkS")
		)
		(fp_line
			(start 0.7874 -0.4064)
			(end -0.7874 -0.4064)
			(stroke
				(width 0.1524)
				(type default)
			)
			(layer "B.SilkS")
		)
		(fp_line
			(start 0.7874 0.4064)
			(end 0.7874 -0.4064)
			(stroke
				(width 0.1524)
				(type default)
			)
			(layer "B.SilkS")
		)
		(fp_line
			(start -0.67945 -0.3048)
			(end -0.67945 0.3048)
			(stroke
				(width 0.1)
				(type default)
			)
			(layer "B.Fab")
		)
		(fp_line
			(start -0.67945 0.3048)
			(end -0.120396 0.3048)
			(stroke
				(width 0.1)
				(type default)
			)
			(layer "B.Fab")
		)
		(fp_line
			(start -0.12065 -0.3048)
			(end -0.67945 -0.3048)
			(stroke
				(width 0.1)
				(type default)
			)
			(layer "B.Fab")
		)
		(fp_line
			(start -0.12065 -0.2794)
			(end -0.12065 -0.3048)
			(stroke
				(width 0.1)
				(type default)
			)
			(layer "B.Fab")
		)
		(fp_line
			(start -0.120396 0.2794)
			(end 0.12065 0.2794)
			(stroke
				(width 0.1)
				(type default)
			)
			(layer "B.Fab")
		)
		(fp_line
			(start -0.120396 0.3048)
			(end -0.120396 0.2794)
			(stroke
				(width 0.1)
				(type default)
			)
			(layer "B.Fab")
		)
		(fp_line
			(start 0.12065 -0.305054)
			(end 0.12065 -0.2794)
			(stroke
				(width 0.1)
				(type default)
			)
			(layer "B.Fab")
		)
		(fp_line
			(start 0.12065 -0.2794)
			(end -0.12065 -0.2794)
			(stroke
				(width 0.1)
				(type default)
			)
			(layer "B.Fab")
		)
		(fp_line
			(start 0.12065 0.2794)
			(end 0.12065 0.3048)
			(stroke
				(width 0.1)
				(type default)
			)
			(layer "B.Fab")
		)
		(fp_line
			(start 0.12065 0.3048)
			(end 0.67945 0.3048)
			(stroke
				(width 0.1)
				(type default)
			)
			(layer "B.Fab")
		)
		(fp_line
			(start 0.67945 -0.305054)
			(end 0.12065 -0.305054)
			(stroke
				(width 0.1)
				(type default)
			)
			(layer "B.Fab")
		)
		(fp_line
			(start 0.67945 0.3048)
			(end 0.67945 -0.305054)
			(stroke
				(width 0.1)
				(type default)
			)
			(layer "B.Fab")
		)
		(pad "1" smd circle
			(at 0.40005 0 180)
			(size 0 0)
			(layers "B.Cu" "B.Mask" "B.Paste")
			(net "PVCCD_HV_CPU1_ISENSE_N")
		)
		(pad "2" smd circle
			(at -0.40005 0 180)
			(size 0 0)
			(layers "B.Cu" "B.Mask" "B.Paste")
			(net "GND")
		)
	)
	(footprint ""
		(layer "B.Cu")
		(at 179.63388 -125.313948)
		(property "Reference" "R3458"
			(at 0 0 0)
			(layer "B.SilkS")
			(hide yes)
			(effects
				(font
					(size 1.27 1.27)
				)
				(justify mirror)
			)
		)
		(property "Value" ""
			(at 0 0 0)
			(layer "B.Fab")
			(effects
				(font
					(size 1.27 1.27)
				)
				(justify mirror)
			)
		)
		(duplicate_pad_numbers_are_jumpers no)
		(fp_line
			(start -1.2954 -0.5842)
			(end -1.2954 0.5842)
			(stroke
				(width 0.1524)
				(type default)
			)
			(layer "B.SilkS")
		)
		(fp_line
			(start -1.2954 0.5842)
			(end 1.2954 0.5842)
			(stroke
				(width 0.1524)
				(type default)
			)
			(layer "B.SilkS")
		)
		(fp_line
			(start 1.2954 -0.5842)
			(end -1.2954 -0.5842)
			(stroke
				(width 0.1524)
				(type default)
			)
			(layer "B.SilkS")
		)
		(fp_line
			(start 1.2954 0.5842)
			(end 1.2954 -0.5842)
			(stroke
				(width 0.1524)
				(type default)
			)
			(layer "B.SilkS")
		)
		(fp_line
			(start -1.1938 -0.406654)
			(end -1.1938 0.4064)
			(stroke
				(width 0.1)
				(type default)
			)
			(layer "B.Fab")
		)
		(fp_line
			(start -1.1938 0.4064)
			(end -0.8636 0.4064)
			(stroke
				(width 0.1)
				(type default)
			)
			(layer "B.Fab")
		)
		(fp_line
			(start -0.8636 -0.4572)
			(end -0.8636 -0.406654)
			(stroke
				(width 0.1)
				(type default)
			)
			(layer "B.Fab")
		)
		(fp_line
			(start -0.8636 -0.406654)
			(end -1.1938 -0.406654)
			(stroke
				(width 0.1)
				(type default)
			)
			(layer "B.Fab")
		)
		(fp_line
			(start -0.8636 0.4064)
			(end -0.8636 0.4572)
			(stroke
				(width 0.1)
				(type default)
			)
			(layer "B.Fab")
		)
		(fp_line
			(start -0.8636 0.4572)
			(end 0.8636 0.4572)
			(stroke
				(width 0.1)
				(type default)
			)
			(layer "B.Fab")
		)
		(fp_line
			(start 0.8636 -0.4572)
			(end -0.8636 -0.4572)
			(stroke
				(width 0.1)
				(type default)
			)
			(layer "B.Fab")
		)
		(fp_line
			(start 0.8636 -0.406654)
			(end 0.8636 -0.4572)
			(stroke
				(width 0.1)
				(type default)
			)
			(layer "B.Fab")
		)
		(fp_line
			(start 0.8636 0.4064)
			(end 1.1938 0.4064)
			(stroke
				(width 0.1)
				(type default)
			)
			(layer "B.Fab")
		)
		(fp_line
			(start 0.8636 0.4318)
			(end 0.8636 0.4064)
			(stroke
				(width 0.1)
				(type default)
			)
			(layer "B.Fab")
		)
		(fp_line
			(start 0.8636 0.4572)
			(end 0.8636 0.4318)
			(stroke
				(width 0.1)
				(type default)
			)
			(layer "B.Fab")
		)
		(fp_line
			(start 1.1938 -0.406654)
			(end 0.8636 -0.406654)
			(stroke
				(width 0.1)
				(type default)
			)
			(layer "B.Fab")
		)
		(fp_line
			(start 1.1938 0.4064)
			(end 1.1938 -0.406654)
			(stroke
				(width 0.1)
				(type default)
			)
			(layer "B.Fab")
		)
		(pad "1" smd rect
			(at 0.7366 0 270)
			(size 0.7112 0.8128)
			(layers "B.Cu" "B.Mask" "B.Paste")
			(net "P3V3_AUX")
		)
		(pad "2" smd rect
			(at -0.7366 0 270)
			(size 0.7112 0.8128)
			(layers "B.Cu" "B.Mask" "B.Paste")
			(net "VCC_PLD_CORE")
		)
	)
	(footprint ""
		(layer "B.Cu")
		(at 64.990218 -318.962024 180)
		(property "Reference" "R944"
			(at 0 0 0)
			(layer "B.SilkS")
			(hide yes)
			(effects
				(font
					(size 1.27 1.27)
				)
				(justify mirror)
			)
		)
		(property "Value" ""
			(at 0 0 0)
			(layer "B.Fab")
			(effects
				(font
					(size 1.27 1.27)
				)
				(justify mirror)
			)
		)
		(duplicate_pad_numbers_are_jumpers no)
		(fp_line
			(start 0.7874 0.4064)
			(end 0.7874 -0.4064)
			(stroke
				(width 0.1524)
				(type default)
			)
			(layer "B.SilkS")
		)
		(fp_line
			(start 0.7874 -0.4064)
			(end -0.7874 -0.4064)
			(stroke
				(width 0.1524)
				(type default)
			)
			(layer "B.SilkS")
		)
		(fp_line
			(start -0.7874 0.4064)
			(end 0.7874 0.4064)
			(stroke
				(width 0.1524)
				(type default)
			)
			(layer "B.SilkS")
		)
		(fp_line
			(start -0.7874 -0.4064)
			(end -0.7874 0.4064)
			(stroke
				(width 0.1524)
				(type default)
			)
			(layer "B.SilkS")
		)
		(fp_line
			(start 0.67945 0.3048)
			(end 0.67945 -0.305054)
			(stroke
				(width 0.1)
				(type default)
			)
			(layer "B.Fab")
		)
		(fp_line
			(start 0.67945 -0.305054)
			(end 0.12065 -0.305054)
			(stroke
				(width 0.1)
				(type default)
			)
			(layer "B.Fab")
		)
		(fp_line
			(start 0.12065 0.3048)
			(end 0.67945 0.3048)
			(stroke
				(width 0.1)
				(type default)
			)
			(layer "B.Fab")
		)
		(fp_line
			(start 0.12065 0.2794)
			(end 0.12065 0.3048)
			(stroke
				(width 0.1)
				(type default)
			)
			(layer "B.Fab")
		)
		(fp_line
			(start 0.12065 -0.2794)
			(end -0.12065 -0.2794)
			(stroke
				(width 0.1)
				(type default)
			)
			(layer "B.Fab")
		)
		(fp_line
			(start 0.12065 -0.305054)
			(end 0.12065 -0.2794)
			(stroke
				(width 0.1)
				(type default)
			)
			(layer "B.Fab")
		)
		(fp_line
			(start -0.120396 0.3048)
			(end -0.120396 0.2794)
			(stroke
				(width 0.1)
				(type default)
			)
			(layer "B.Fab")
		)
		(fp_line
			(start -0.120396 0.2794)
			(end 0.12065 0.2794)
			(stroke
				(width 0.1)
				(type default)
			)
			(layer "B.Fab")
		)
		(fp_line
			(start -0.12065 -0.2794)
			(end -0.12065 -0.3048)
			(stroke
				(width 0.1)
				(type default)
			)
			(layer "B.Fab")
		)
		(fp_line
			(start -0.12065 -0.3048)
			(end -0.67945 -0.3048)
			(stroke
				(width 0.1)
				(type default)
			)
			(layer "B.Fab")
		)
		(fp_line
			(start -0.67945 0.3048)
			(end -0.120396 0.3048)
			(stroke
				(width 0.1)
				(type default)
			)
			(layer "B.Fab")
		)
		(fp_line
			(start -0.67945 -0.3048)
			(end -0.67945 0.3048)
			(stroke
				(width 0.1)
				(type default)
			)
			(layer "B.Fab")
		)
		(pad "1" smd circle
			(at 0.40005 0)
			(size 0 0)
			(layers "B.Cu" "B.Mask" "B.Paste")
			(net "P3V3_AUX")
		)
		(pad "2" smd circle
			(at -0.40005 0)
			(size 0 0)
			(layers "B.Cu" "B.Mask" "B.Paste")
			(net "PWRGD_FAIL_CPU1_AB_R1")
		)
	)
	(footprint ""
		(layer "B.Cu")
		(at 39.621206 -318.366648)
		(property "Reference" "R44"
			(at 0 0 0)
			(layer "B.SilkS")
			(hide yes)
			(effects
				(font
					(size 1.27 1.27)
				)
				(justify mirror)
			)
		)
		(property "Value" ""
			(at 0 0 0)
			(layer "B.Fab")
			(effects
				(font
					(size 1.27 1.27)
				)
				(justify mirror)
			)
		)
		(duplicate_pad_numbers_are_jumpers no)
		(fp_line
			(start -0.7874 -0.4064)
			(end -0.7874 0.4064)
			(stroke
				(width 0.1524)
				(type default)
			)
			(layer "B.SilkS")
		)
		(fp_line
			(start -0.7874 0.4064)
			(end 0.7874 0.4064)
			(stroke
				(width 0.1524)
				(type default)
			)
			(layer "B.SilkS")
		)
		(fp_line
			(start 0.7874 -0.4064)
			(end -0.7874 -0.4064)
			(stroke
				(width 0.1524)
				(type default)
			)
			(layer "B.SilkS")
		)
		(fp_line
			(start 0.7874 0.4064)
			(end 0.7874 -0.4064)
			(stroke
				(width 0.1524)
				(type default)
			)
			(layer "B.SilkS")
		)
		(fp_line
			(start -0.67945 -0.3048)
			(end -0.67945 0.3048)
			(stroke
				(width 0.1)
				(type default)
			)
			(layer "B.Fab")
		)
		(fp_line
			(start -0.67945 0.3048)
			(end -0.120396 0.3048)
			(stroke
				(width 0.1)
				(type default)
			)
			(layer "B.Fab")
		)
		(fp_line
			(start -0.12065 -0.3048)
			(end -0.67945 -0.3048)
			(stroke
				(width 0.1)
				(type default)
			)
			(layer "B.Fab")
		)
		(fp_line
			(start -0.12065 -0.2794)
			(end -0.12065 -0.3048)
			(stroke
				(width 0.1)
				(type default)
			)
			(layer "B.Fab")
		)
		(fp_line
			(start -0.120396 0.2794)
			(end 0.12065 0.2794)
			(stroke
				(width 0.1)
				(type default)
			)
			(layer "B.Fab")
		)
		(fp_line
			(start -0.120396 0.3048)
			(end -0.120396 0.2794)
			(stroke
				(width 0.1)
				(type default)
			)
			(layer "B.Fab")
		)
		(fp_line
			(start 0.12065 -0.305054)
			(end 0.12065 -0.2794)
			(stroke
				(width 0.1)
				(type default)
			)
			(layer "B.Fab")
		)
		(fp_line
			(start 0.12065 -0.2794)
			(end -0.12065 -0.2794)
			(stroke
				(width 0.1)
				(type default)
			)
			(layer "B.Fab")
		)
		(fp_line
			(start 0.12065 0.2794)
			(end 0.12065 0.3048)
			(stroke
				(width 0.1)
				(type default)
			)
			(layer "B.Fab")
		)
		(fp_line
			(start 0.12065 0.3048)
			(end 0.67945 0.3048)
			(stroke
				(width 0.1)
				(type default)
			)
			(layer "B.Fab")
		)
		(fp_line
			(start 0.67945 -0.305054)
			(end 0.12065 -0.305054)
			(stroke
				(width 0.1)
				(type default)
			)
			(layer "B.Fab")
		)
		(fp_line
			(start 0.67945 0.3048)
			(end 0.67945 -0.305054)
			(stroke
				(width 0.1)
				(type default)
			)
			(layer "B.Fab")
		)
		(pad "1" smd circle
			(at 0.40005 0 180)
			(size 0 0)
			(layers "B.Cu" "B.Mask" "B.Paste")
			(net "PD_CHB_CPU1_DIMM1_SAA")
		)
		(pad "2" smd circle
			(at -0.40005 0 180)
			(size 0 0)
			(layers "B.Cu" "B.Mask" "B.Paste")
			(net "GND")
		)
	)
	(footprint ""
		(layer "B.Cu")
		(at 97.257108 -190.705232 -90)
		(property "Reference" "R64"
			(at 0 0 90)
			(layer "B.SilkS")
			(hide yes)
			(effects
				(font
					(size 1.27 1.27)
				)
				(justify mirror)
			)
		)
		(property "Value" ""
			(at 0 0 90)
			(layer "B.Fab")
			(effects
				(font
					(size 1.27 1.27)
				)
				(justify mirror)
			)
		)
		(duplicate_pad_numbers_are_jumpers no)
		(fp_line
			(start -0.7874 0.4064)
			(end 0.7874 0.4064)
			(stroke
				(width 0.1524)
				(type default)
			)
			(layer "B.SilkS")
		)
		(fp_line
			(start 0.7874 0.4064)
			(end 0.7874 -0.4064)
			(stroke
				(width 0.1524)
				(type default)
			)
			(layer "B.SilkS")
		)
		(fp_line
			(start -0.7874 -0.4064)
			(end -0.7874 0.4064)
			(stroke
				(width 0.1524)
				(type default)
			)
			(layer "B.SilkS")
		)
		(fp_line
			(start 0.7874 -0.4064)
			(end -0.7874 -0.4064)
			(stroke
				(width 0.1524)
				(type default)
			)
			(layer "B.SilkS")
		)
		(fp_line
			(start -0.67945 0.3048)
			(end -0.120396 0.3048)
			(stroke
				(width 0.1)
				(type default)
			)
			(layer "B.Fab")
		)
		(fp_line
			(start -0.120396 0.3048)
			(end -0.120396 0.2794)
			(stroke
				(width 0.1)
				(type default)
			)
			(layer "B.Fab")
		)
		(fp_line
			(start 0.12065 0.3048)
			(end 0.67945 0.3048)
			(stroke
				(width 0.1)
				(type default)
			)
			(layer "B.Fab")
		)
		(fp_line
			(start 0.67945 0.3048)
			(end 0.67945 -0.305054)
			(stroke
				(width 0.1)
				(type default)
			)
			(layer "B.Fab")
		)
		(fp_line
			(start -0.120396 0.2794)
			(end 0.12065 0.2794)
			(stroke
				(width 0.1)
				(type default)
			)
			(layer "B.Fab")
		)
		(fp_line
			(start 0.12065 0.2794)
			(end 0.12065 0.3048)
			(stroke
				(width 0.1)
				(type default)
			)
			(layer "B.Fab")
		)
		(fp_line
			(start -0.12065 -0.2794)
			(end -0.12065 -0.3048)
			(stroke
				(width 0.1)
				(type default)
			)
			(layer "B.Fab")
		)
		(fp_line
			(start 0.12065 -0.2794)
			(end -0.12065 -0.2794)
			(stroke
				(width 0.1)
				(type default)
			)
			(layer "B.Fab")
		)
		(fp_line
			(start -0.67945 -0.3048)
			(end -0.67945 0.3048)
			(stroke
				(width 0.1)
				(type default)
			)
			(layer "B.Fab")
		)
		(fp_line
			(start -0.12065 -0.3048)
			(end -0.67945 -0.3048)
			(stroke
				(width 0.1)
				(type default)
			)
			(layer "B.Fab")
		)
		(fp_line
			(start 0.12065 -0.305054)
			(end 0.12065 -0.2794)
			(stroke
				(width 0.1)
				(type default)
			)
			(layer "B.Fab")
		)
		(fp_line
			(start 0.67945 -0.305054)
			(end 0.12065 -0.305054)
			(stroke
				(width 0.1)
				(type default)
			)
			(layer "B.Fab")
		)
		(pad "1" smd circle
			(at 0.40005 0 90)
			(size 0 0)
			(layers "B.Cu" "B.Mask" "B.Paste")
			(net "JTAG_MUX_CPU1_GTL_TDI")
		)
		(pad "2" smd circle
			(at -0.40005 0 90)
			(size 0 0)
			(layers "B.Cu" "B.Mask" "B.Paste")
			(net "JTAG_DBP_CPU1_GTL_R_TDI")
		)
	)
	(footprint ""
		(layer "B.Cu")
		(at 181.915308 -407.859484 -90)
		(property "Reference" "R4695"
			(at 0 0 90)
			(layer "B.SilkS")
			(hide yes)
			(effects
				(font
					(size 1.27 1.27)
				)
				(justify mirror)
			)
		)
		(property "Value" ""
			(at 0 0 90)
			(layer "B.Fab")
			(effects
				(font
					(size 1.27 1.27)
				)
				(justify mirror)
			)
		)
		(duplicate_pad_numbers_are_jumpers no)
		(fp_line
			(start -0.7874 0.4064)
			(end 0.7874 0.4064)
			(stroke
				(width 0.1524)
				(type default)
			)
			(layer "B.SilkS")
		)
		(fp_line
			(start 0.7874 0.4064)
			(end 0.7874 -0.4064)
			(stroke
				(width 0.1524)
				(type default)
			)
			(layer "B.SilkS")
		)
		(fp_line
			(start -0.7874 -0.4064)
			(end -0.7874 0.4064)
			(stroke
				(width 0.1524)
				(type default)
			)
			(layer "B.SilkS")
		)
		(fp_line
			(start 0.7874 -0.4064)
			(end -0.7874 -0.4064)
			(stroke
				(width 0.1524)
				(type default)
			)
			(layer "B.SilkS")
		)
		(fp_line
			(start -0.67945 0.3048)
			(end -0.120396 0.3048)
			(stroke
				(width 0.1)
				(type default)
			)
			(layer "B.Fab")
		)
		(fp_line
			(start -0.120396 0.3048)
			(end -0.120396 0.2794)
			(stroke
				(width 0.1)
				(type default)
			)
			(layer "B.Fab")
		)
		(fp_line
			(start 0.12065 0.3048)
			(end 0.67945 0.3048)
			(stroke
				(width 0.1)
				(type default)
			)
			(layer "B.Fab")
		)
		(fp_line
			(start 0.67945 0.3048)
			(end 0.67945 -0.305054)
			(stroke
				(width 0.1)
				(type default)
			)
			(layer "B.Fab")
		)
		(fp_line
			(start -0.120396 0.2794)
			(end 0.12065 0.2794)
			(stroke
				(width 0.1)
				(type default)
			)
			(layer "B.Fab")
		)
		(fp_line
			(start 0.12065 0.2794)
			(end 0.12065 0.3048)
			(stroke
				(width 0.1)
				(type default)
			)
			(layer "B.Fab")
		)
		(fp_line
			(start -0.12065 -0.2794)
			(end -0.12065 -0.3048)
			(stroke
				(width 0.1)
				(type default)
			)
			(layer "B.Fab")
		)
		(fp_line
			(start 0.12065 -0.2794)
			(end -0.12065 -0.2794)
			(stroke
				(width 0.1)
				(type default)
			)
			(layer "B.Fab")
		)
		(fp_line
			(start -0.67945 -0.3048)
			(end -0.67945 0.3048)
			(stroke
				(width 0.1)
				(type default)
			)
			(layer "B.Fab")
		)
		(fp_line
			(start -0.12065 -0.3048)
			(end -0.67945 -0.3048)
			(stroke
				(width 0.1)
				(type default)
			)
			(layer "B.Fab")
		)
		(fp_line
			(start 0.12065 -0.305054)
			(end 0.12065 -0.2794)
			(stroke
				(width 0.1)
				(type default)
			)
			(layer "B.Fab")
		)
		(fp_line
			(start 0.67945 -0.305054)
			(end 0.12065 -0.305054)
			(stroke
				(width 0.1)
				(type default)
			)
			(layer "B.Fab")
		)
		(pad "1" smd circle
			(at 0.40005 0 90)
			(size 0 0)
			(layers "B.Cu" "B.Mask" "B.Paste")
			(net "SMB_SML1_PMBUS_HSC_SCL")
		)
		(pad "2" smd circle
			(at -0.40005 0 90)
			(size 0 0)
			(layers "B.Cu" "B.Mask" "B.Paste")
			(net "SMB_SML1_PMBUS_HSC_MODULE_SCL")
		)
	)
	(footprint ""
		(layer "B.Cu")
		(at 401.832318 -227.224082 90)
		(property "Reference" "R2362"
			(at 0 0 90)
			(layer "B.SilkS")
			(hide yes)
			(effects
				(font
					(size 1.27 1.27)
				)
				(justify mirror)
			)
		)
		(property "Value" ""
			(at 0 0 90)
			(layer "B.Fab")
			(effects
				(font
					(size 1.27 1.27)
				)
				(justify mirror)
			)
		)
		(duplicate_pad_numbers_are_jumpers no)
		(fp_line
			(start 0.7874 -0.4064)
			(end -0.7874 -0.4064)
			(stroke
				(width 0.1524)
				(type default)
			)
			(layer "B.SilkS")
		)
		(fp_line
			(start -0.7874 -0.4064)
			(end -0.7874 0.4064)
			(stroke
				(width 0.1524)
				(type default)
			)
			(layer "B.SilkS")
		)
		(fp_line
			(start 0.7874 0.4064)
			(end 0.7874 -0.4064)
			(stroke
				(width 0.1524)
				(type default)
			)
			(layer "B.SilkS")
		)
		(fp_line
			(start -0.7874 0.4064)
			(end 0.7874 0.4064)
			(stroke
				(width 0.1524)
				(type default)
			)
			(layer "B.SilkS")
		)
		(fp_line
			(start 0.67945 -0.305054)
			(end 0.12065 -0.305054)
			(stroke
				(width 0.1)
				(type default)
			)
			(layer "B.Fab")
		)
		(fp_line
			(start 0.12065 -0.305054)
			(end 0.12065 -0.2794)
			(stroke
				(width 0.1)
				(type default)
			)
			(layer "B.Fab")
		)
		(fp_line
			(start -0.12065 -0.3048)
			(end -0.67945 -0.3048)
			(stroke
				(width 0.1)
				(type default)
			)
			(layer "B.Fab")
		)
		(fp_line
			(start -0.67945 -0.3048)
			(end -0.67945 0.3048)
			(stroke
				(width 0.1)
				(type default)
			)
			(layer "B.Fab")
		)
		(fp_line
			(start 0.12065 -0.2794)
			(end -0.12065 -0.2794)
			(stroke
				(width 0.1)
				(type default)
			)
			(layer "B.Fab")
		)
		(fp_line
			(start -0.12065 -0.2794)
			(end -0.12065 -0.3048)
			(stroke
				(width 0.1)
				(type default)
			)
			(layer "B.Fab")
		)
		(fp_line
			(start 0.12065 0.2794)
			(end 0.12065 0.3048)
			(stroke
				(width 0.1)
				(type default)
			)
			(layer "B.Fab")
		)
		(fp_line
			(start -0.120396 0.2794)
			(end 0.12065 0.2794)
			(stroke
				(width 0.1)
				(type default)
			)
			(layer "B.Fab")
		)
		(fp_line
			(start 0.67945 0.3048)
			(end 0.67945 -0.305054)
			(stroke
				(width 0.1)
				(type default)
			)
			(layer "B.Fab")
		)
		(fp_line
			(start 0.12065 0.3048)
			(end 0.67945 0.3048)
			(stroke
				(width 0.1)
				(type default)
			)
			(layer "B.Fab")
		)
		(fp_line
			(start -0.120396 0.3048)
			(end -0.120396 0.2794)
			(stroke
				(width 0.1)
				(type default)
			)
			(layer "B.Fab")
		)
		(fp_line
			(start -0.67945 0.3048)
			(end -0.120396 0.3048)
			(stroke
				(width 0.1)
				(type default)
			)
			(layer "B.Fab")
		)
		(pad "1" smd circle
			(at 0.40005 0 270)
			(size 0 0)
			(layers "B.Cu" "B.Mask" "B.Paste")
			(net "H_CPU0_PMDOWN_CPU1_R")
		)
		(pad "2" smd circle
			(at -0.40005 0 270)
			(size 0 0)
			(layers "B.Cu" "B.Mask" "B.Paste")
			(net "H_CPU0_PMDOWN_CPU1_R1")
		)
	)
	(footprint ""
		(layer "B.Cu")
		(at 451.947026 -77.51572 90)
		(property "Reference" "R1571"
			(at 0 0 90)
			(layer "B.SilkS")
			(hide yes)
			(effects
				(font
					(size 1.27 1.27)
				)
				(justify mirror)
			)
		)
		(property "Value" ""
			(at 0 0 90)
			(layer "B.Fab")
			(effects
				(font
					(size 1.27 1.27)
				)
				(justify mirror)
			)
		)
		(duplicate_pad_numbers_are_jumpers no)
		(fp_line
			(start 0.7874 -0.4064)
			(end -0.7874 -0.4064)
			(stroke
				(width 0.1524)
				(type default)
			)
			(layer "B.SilkS")
		)
		(fp_line
			(start -0.7874 -0.4064)
			(end -0.7874 0.4064)
			(stroke
				(width 0.1524)
				(type default)
			)
			(layer "B.SilkS")
		)
		(fp_line
			(start 0.7874 0.4064)
			(end 0.7874 -0.4064)
			(stroke
				(width 0.1524)
				(type default)
			)
			(layer "B.SilkS")
		)
		(fp_line
			(start -0.7874 0.4064)
			(end 0.7874 0.4064)
			(stroke
				(width 0.1524)
				(type default)
			)
			(layer "B.SilkS")
		)
		(fp_line
			(start 0.67945 -0.305054)
			(end 0.12065 -0.305054)
			(stroke
				(width 0.1)
				(type default)
			)
			(layer "B.Fab")
		)
		(fp_line
			(start 0.12065 -0.305054)
			(end 0.12065 -0.2794)
			(stroke
				(width 0.1)
				(type default)
			)
			(layer "B.Fab")
		)
		(fp_line
			(start -0.12065 -0.3048)
			(end -0.67945 -0.3048)
			(stroke
				(width 0.1)
				(type default)
			)
			(layer "B.Fab")
		)
		(fp_line
			(start -0.67945 -0.3048)
			(end -0.67945 0.3048)
			(stroke
				(width 0.1)
				(type default)
			)
			(layer "B.Fab")
		)
		(fp_line
			(start 0.12065 -0.2794)
			(end -0.12065 -0.2794)
			(stroke
				(width 0.1)
				(type default)
			)
			(layer "B.Fab")
		)
		(fp_line
			(start -0.12065 -0.2794)
			(end -0.12065 -0.3048)
			(stroke
				(width 0.1)
				(type default)
			)
			(layer "B.Fab")
		)
		(fp_line
			(start 0.12065 0.2794)
			(end 0.12065 0.3048)
			(stroke
				(width 0.1)
				(type default)
			)
			(layer "B.Fab")
		)
		(fp_line
			(start -0.120396 0.2794)
			(end 0.12065 0.2794)
			(stroke
				(width 0.1)
				(type default)
			)
			(layer "B.Fab")
		)
		(fp_line
			(start 0.67945 0.3048)
			(end 0.67945 -0.305054)
			(stroke
				(width 0.1)
				(type default)
			)
			(layer "B.Fab")
		)
		(fp_line
			(start 0.12065 0.3048)
			(end 0.67945 0.3048)
			(stroke
				(width 0.1)
				(type default)
			)
			(layer "B.Fab")
		)
		(fp_line
			(start -0.120396 0.3048)
			(end -0.120396 0.2794)
			(stroke
				(width 0.1)
				(type default)
			)
			(layer "B.Fab")
		)
		(fp_line
			(start -0.67945 0.3048)
			(end -0.120396 0.3048)
			(stroke
				(width 0.1)
				(type default)
			)
			(layer "B.Fab")
		)
		(pad "1" smd circle
			(at 0.40005 0 270)
			(size 0 0)
			(layers "B.Cu" "B.Mask" "B.Paste")
			(net "MB0_P12V_STBY_PWRGD")
		)
		(pad "2" smd circle
			(at -0.40005 0 270)
			(size 0 0)
			(layers "B.Cu" "B.Mask" "B.Paste")
			(net "P3V3_AUX_EN")
		)
	)
	(footprint ""
		(layer "B.Cu")
		(at 119.07012 -237.709456 -90)
		(property "Reference" "C488"
			(at 0 0 90)
			(layer "B.SilkS")
			(hide yes)
			(effects
				(font
					(size 1.27 1.27)
				)
				(justify mirror)
			)
		)
		(property "Value" ""
			(at 0 0 90)
			(layer "B.Fab")
			(effects
				(font
					(size 1.27 1.27)
				)
				(justify mirror)
			)
		)
		(duplicate_pad_numbers_are_jumpers no)
		(fp_line
			(start -1.2954 0.5842)
			(end 1.2954 0.5842)
			(stroke
				(width 0.1524)
				(type default)
			)
			(layer "B.SilkS")
		)
		(fp_line
			(start 1.2954 0.5842)
			(end 1.2954 -0.5842)
			(stroke
				(width 0.1524)
				(type default)
			)
			(layer "B.SilkS")
		)
		(fp_line
			(start -1.2954 -0.5842)
			(end -1.2954 0.5842)
			(stroke
				(width 0.1524)
				(type default)
			)
			(layer "B.SilkS")
		)
		(fp_line
			(start 0 -0.5842)
			(end 0 0.5842)
			(stroke
				(width 0.1524)
				(type default)
			)
			(layer "B.SilkS")
		)
		(fp_line
			(start 1.2954 -0.5842)
			(end -1.2954 -0.5842)
			(stroke
				(width 0.1524)
				(type default)
			)
			(layer "B.SilkS")
		)
		(fp_line
			(start -0.8636 0.4572)
			(end 0.8636 0.4572)
			(stroke
				(width 0.1)
				(type default)
			)
			(layer "B.Fab")
		)
		(fp_line
			(start 0.8636 0.4572)
			(end 0.8636 0.4064)
			(stroke
				(width 0.1)
				(type default)
			)
			(layer "B.Fab")
		)
		(fp_line
			(start -1.1938 0.4064)
			(end -0.8636 0.4064)
			(stroke
				(width 0.1)
				(type default)
			)
			(layer "B.Fab")
		)
		(fp_line
			(start -0.8636 0.4064)
			(end -0.8636 0.4572)
			(stroke
				(width 0.1)
				(type default)
			)
			(layer "B.Fab")
		)
		(fp_line
			(start 0.8636 0.4064)
			(end 1.1938 0.4064)
			(stroke
				(width 0.1)
				(type default)
			)
			(layer "B.Fab")
		)
		(fp_line
			(start 1.1938 0.4064)
			(end 1.1938 -0.4064)
			(stroke
				(width 0.1)
				(type default)
			)
			(layer "B.Fab")
		)
		(fp_line
			(start -1.1938 -0.4064)
			(end -1.1938 0.4064)
			(stroke
				(width 0.1)
				(type default)
			)
			(layer "B.Fab")
		)
		(fp_line
			(start -0.8636 -0.4064)
			(end -1.1938 -0.4064)
			(stroke
				(width 0.1)
				(type default)
			)
			(layer "B.Fab")
		)
		(fp_line
			(start 0.8636 -0.4064)
			(end 0.8636 -0.4572)
			(stroke
				(width 0.1)
				(type default)
			)
			(layer "B.Fab")
		)
		(fp_line
			(start 1.1938 -0.4064)
			(end 0.8636 -0.4064)
			(stroke
				(width 0.1)
				(type default)
			)
			(layer "B.Fab")
		)
		(fp_line
			(start -0.8636 -0.4572)
			(end -0.8636 -0.4064)
			(stroke
				(width 0.1)
				(type default)
			)
			(layer "B.Fab")
		)
		(fp_line
			(start 0.8636 -0.4572)
			(end -0.8636 -0.4572)
			(stroke
				(width 0.1)
				(type default)
			)
			(layer "B.Fab")
		)
		(pad "1" smd rect
			(at 0.7366 0 180)
			(size 0.7112 0.8128)
			(layers "B.Cu" "B.Mask" "B.Paste")
			(net "PVCCINFAON_CPU1")
		)
		(pad "2" smd rect
			(at -0.7366 0 180)
			(size 0.7112 0.8128)
			(layers "B.Cu" "B.Mask" "B.Paste")
			(net "GND")
		)
	)
	(footprint ""
		(layer "B.Cu")
		(at 303.09312 -353.878134 -90)
		(property "Reference" "PC618_P0_2"
			(at 0 0 90)
			(layer "B.SilkS")
			(hide yes)
			(effects
				(font
					(size 1.27 1.27)
				)
				(justify mirror)
			)
		)
		(property "Value" ""
			(at 0 0 90)
			(layer "B.Fab")
			(effects
				(font
					(size 1.27 1.27)
				)
				(justify mirror)
			)
		)
		(duplicate_pad_numbers_are_jumpers no)
		(fp_line
			(start -1.524 0.762)
			(end 1.524 0.762)
			(stroke
				(width 0.1524)
				(type default)
			)
			(layer "B.SilkS")
		)
		(fp_line
			(start 1.524 0.762)
			(end 1.524 -0.762)
			(stroke
				(width 0.1524)
				(type default)
			)
			(layer "B.SilkS")
		)
		(fp_line
			(start -1.524 -0.762)
			(end -1.524 0.762)
			(stroke
				(width 0.1524)
				(type default)
			)
			(layer "B.SilkS")
		)
		(fp_line
			(start 1.524 -0.762)
			(end -1.524 -0.762)
			(stroke
				(width 0.1524)
				(type default)
			)
			(layer "B.SilkS")
		)
		(fp_line
			(start -1.1049 0.724916)
			(end -1.1049 -0.724916)
			(stroke
				(width 0.1)
				(type default)
			)
			(layer "B.Fab")
		)
		(fp_line
			(start 1.1049 0.724916)
			(end -1.1049 0.724916)
			(stroke
				(width 0.1)
				(type default)
			)
			(layer "B.Fab")
		)
		(fp_line
			(start -1.1049 -0.724916)
			(end 1.1049 -0.724916)
			(stroke
				(width 0.1)
				(type default)
			)
			(layer "B.Fab")
		)
		(fp_line
			(start 1.1049 -0.724916)
			(end 1.1049 0.724916)
			(stroke
				(width 0.1)
				(type default)
			)
			(layer "B.Fab")
		)
		(pad "1" smd rect
			(at 0.889 0 270)
			(size 1.016 1.27)
			(layers "B.Cu" "B.Mask" "B.Paste")
			(net "PVCCFA_EHV_FIVRA_CPU0")
		)
		(pad "2" smd rect
			(at -0.889 0 270)
			(size 1.016 1.27)
			(layers "B.Cu" "B.Mask" "B.Paste")
			(net "GND")
		)
	)
	(footprint ""
		(layer "B.Cu")
		(at 423.079164 -366.466374 -90)
		(property "Reference" "PR1324"
			(at 0 0 90)
			(layer "B.SilkS")
			(hide yes)
			(effects
				(font
					(size 1.27 1.27)
				)
				(justify mirror)
			)
		)
		(property "Value" ""
			(at 0 0 90)
			(layer "B.Fab")
			(effects
				(font
					(size 1.27 1.27)
				)
				(justify mirror)
			)
		)
		(duplicate_pad_numbers_are_jumpers no)
		(fp_line
			(start -0.7874 0.4064)
			(end 0.7874 0.4064)
			(stroke
				(width 0.1524)
				(type default)
			)
			(layer "B.SilkS")
		)
		(fp_line
			(start 0.7874 0.4064)
			(end 0.7874 -0.4064)
			(stroke
				(width 0.1524)
				(type default)
			)
			(layer "B.SilkS")
		)
		(fp_line
			(start -0.7874 -0.4064)
			(end -0.7874 0.4064)
			(stroke
				(width 0.1524)
				(type default)
			)
			(layer "B.SilkS")
		)
		(fp_line
			(start 0.7874 -0.4064)
			(end -0.7874 -0.4064)
			(stroke
				(width 0.1524)
				(type default)
			)
			(layer "B.SilkS")
		)
		(fp_line
			(start -0.67945 0.3048)
			(end -0.120396 0.3048)
			(stroke
				(width 0.1)
				(type default)
			)
			(layer "B.Fab")
		)
		(fp_line
			(start -0.120396 0.3048)
			(end -0.120396 0.2794)
			(stroke
				(width 0.1)
				(type default)
			)
			(layer "B.Fab")
		)
		(fp_line
			(start 0.12065 0.3048)
			(end 0.67945 0.3048)
			(stroke
				(width 0.1)
				(type default)
			)
			(layer "B.Fab")
		)
		(fp_line
			(start 0.67945 0.3048)
			(end 0.67945 -0.305054)
			(stroke
				(width 0.1)
				(type default)
			)
			(layer "B.Fab")
		)
		(fp_line
			(start -0.120396 0.2794)
			(end 0.12065 0.2794)
			(stroke
				(width 0.1)
				(type default)
			)
			(layer "B.Fab")
		)
		(fp_line
			(start 0.12065 0.2794)
			(end 0.12065 0.3048)
			(stroke
				(width 0.1)
				(type default)
			)
			(layer "B.Fab")
		)
		(fp_line
			(start -0.12065 -0.2794)
			(end -0.12065 -0.3048)
			(stroke
				(width 0.1)
				(type default)
			)
			(layer "B.Fab")
		)
		(fp_line
			(start 0.12065 -0.2794)
			(end -0.12065 -0.2794)
			(stroke
				(width 0.1)
				(type default)
			)
			(layer "B.Fab")
		)
		(fp_line
			(start -0.67945 -0.3048)
			(end -0.67945 0.3048)
			(stroke
				(width 0.1)
				(type default)
			)
			(layer "B.Fab")
		)
		(fp_line
			(start -0.12065 -0.3048)
			(end -0.67945 -0.3048)
			(stroke
				(width 0.1)
				(type default)
			)
			(layer "B.Fab")
		)
		(fp_line
			(start 0.12065 -0.305054)
			(end 0.12065 -0.2794)
			(stroke
				(width 0.1)
				(type default)
			)
			(layer "B.Fab")
		)
		(fp_line
			(start 0.67945 -0.305054)
			(end 0.12065 -0.305054)
			(stroke
				(width 0.1)
				(type default)
			)
			(layer "B.Fab")
		)
		(pad "1" smd circle
			(at 0.40005 0 90)
			(size 0 0)
			(layers "B.Cu" "B.Mask" "B.Paste")
			(net "PVCCFA_EHV_FIVRA_CPU0_VOS3")
		)
		(pad "2" smd circle
			(at -0.40005 0 90)
			(size 0 0)
			(layers "B.Cu" "B.Mask" "B.Paste")
			(net "PVCCFA_EHV_FIVRA_CPU0")
		)
	)
	(footprint ""
		(layer "B.Cu")
		(at 112.020604 -294.01008)
		(property "Reference" "C341"
			(at 0 0 0)
			(layer "B.SilkS")
			(hide yes)
			(effects
				(font
					(size 1.27 1.27)
				)
				(justify mirror)
			)
		)
		(property "Value" ""
			(at 0 0 0)
			(layer "B.Fab")
			(effects
				(font
					(size 1.27 1.27)
				)
				(justify mirror)
			)
		)
		(duplicate_pad_numbers_are_jumpers no)
		(fp_line
			(start -1.524 -0.762)
			(end -1.524 0.762)
			(stroke
				(width 0.1524)
				(type default)
			)
			(layer "B.SilkS")
		)
		(fp_line
			(start -1.524 0.762)
			(end 1.524 0.762)
			(stroke
				(width 0.1524)
				(type default)
			)
			(layer "B.SilkS")
		)
		(fp_line
			(start 1.524 -0.762)
			(end -1.524 -0.762)
			(stroke
				(width 0.1524)
				(type default)
			)
			(layer "B.SilkS")
		)
		(fp_line
			(start 1.524 0.762)
			(end 1.524 -0.762)
			(stroke
				(width 0.1524)
				(type default)
			)
			(layer "B.SilkS")
		)
		(fp_line
			(start -1.1049 -0.724916)
			(end 1.1049 -0.724916)
			(stroke
				(width 0.1)
				(type default)
			)
			(layer "B.Fab")
		)
		(fp_line
			(start -1.1049 0.724916)
			(end -1.1049 -0.724916)
			(stroke
				(width 0.1)
				(type default)
			)
			(layer "B.Fab")
		)
		(fp_line
			(start 1.1049 -0.724916)
			(end 1.1049 0.724916)
			(stroke
				(width 0.1)
				(type default)
			)
			(layer "B.Fab")
		)
		(fp_line
			(start 1.1049 0.724916)
			(end -1.1049 0.724916)
			(stroke
				(width 0.1)
				(type default)
			)
			(layer "B.Fab")
		)
		(pad "1" smd rect
			(at 0.889 0)
			(size 1.016 1.27)
			(layers "B.Cu" "B.Mask" "B.Paste")
			(net "PVCCIN_CPU1")
		)
		(pad "2" smd rect
			(at -0.889 0)
			(size 1.016 1.27)
			(layers "B.Cu" "B.Mask" "B.Paste")
			(net "GND")
		)
	)
	(footprint ""
		(layer "B.Cu")
		(at 189.28588 -130.266948 -90)
		(property "Reference" "R1741"
			(at 0 0 90)
			(layer "B.SilkS")
			(hide yes)
			(effects
				(font
					(size 1.27 1.27)
				)
				(justify mirror)
			)
		)
		(property "Value" ""
			(at 0 0 90)
			(layer "B.Fab")
			(effects
				(font
					(size 1.27 1.27)
				)
				(justify mirror)
			)
		)
		(duplicate_pad_numbers_are_jumpers no)
		(fp_line
			(start -0.7874 0.4064)
			(end 0.7874 0.4064)
			(stroke
				(width 0.1524)
				(type default)
			)
			(layer "B.SilkS")
		)
		(fp_line
			(start 0.7874 0.4064)
			(end 0.7874 -0.4064)
			(stroke
				(width 0.1524)
				(type default)
			)
			(layer "B.SilkS")
		)
		(fp_line
			(start -0.7874 -0.4064)
			(end -0.7874 0.4064)
			(stroke
				(width 0.1524)
				(type default)
			)
			(layer "B.SilkS")
		)
		(fp_line
			(start 0.7874 -0.4064)
			(end -0.7874 -0.4064)
			(stroke
				(width 0.1524)
				(type default)
			)
			(layer "B.SilkS")
		)
		(fp_line
			(start -0.67945 0.3048)
			(end -0.120396 0.3048)
			(stroke
				(width 0.1)
				(type default)
			)
			(layer "B.Fab")
		)
		(fp_line
			(start -0.120396 0.3048)
			(end -0.120396 0.2794)
			(stroke
				(width 0.1)
				(type default)
			)
			(layer "B.Fab")
		)
		(fp_line
			(start 0.12065 0.3048)
			(end 0.67945 0.3048)
			(stroke
				(width 0.1)
				(type default)
			)
			(layer "B.Fab")
		)
		(fp_line
			(start 0.67945 0.3048)
			(end 0.67945 -0.305054)
			(stroke
				(width 0.1)
				(type default)
			)
			(layer "B.Fab")
		)
		(fp_line
			(start -0.120396 0.2794)
			(end 0.12065 0.2794)
			(stroke
				(width 0.1)
				(type default)
			)
			(layer "B.Fab")
		)
		(fp_line
			(start 0.12065 0.2794)
			(end 0.12065 0.3048)
			(stroke
				(width 0.1)
				(type default)
			)
			(layer "B.Fab")
		)
		(fp_line
			(start -0.12065 -0.2794)
			(end -0.12065 -0.3048)
			(stroke
				(width 0.1)
				(type default)
			)
			(layer "B.Fab")
		)
		(fp_line
			(start 0.12065 -0.2794)
			(end -0.12065 -0.2794)
			(stroke
				(width 0.1)
				(type default)
			)
			(layer "B.Fab")
		)
		(fp_line
			(start -0.67945 -0.3048)
			(end -0.67945 0.3048)
			(stroke
				(width 0.1)
				(type default)
			)
			(layer "B.Fab")
		)
		(fp_line
			(start -0.12065 -0.3048)
			(end -0.67945 -0.3048)
			(stroke
				(width 0.1)
				(type default)
			)
			(layer "B.Fab")
		)
		(fp_line
			(start 0.12065 -0.305054)
			(end 0.12065 -0.2794)
			(stroke
				(width 0.1)
				(type default)
			)
			(layer "B.Fab")
		)
		(fp_line
			(start 0.67945 -0.305054)
			(end 0.12065 -0.305054)
			(stroke
				(width 0.1)
				(type default)
			)
			(layer "B.Fab")
		)
		(pad "1" smd circle
			(at 0.40005 0 90)
			(size 0 0)
			(layers "B.Cu" "B.Mask" "B.Paste")
			(net "FM_RST_PERST_BIT0")
		)
		(pad "2" smd circle
			(at -0.40005 0 90)
			(size 0 0)
			(layers "B.Cu" "B.Mask" "B.Paste")
			(net "P3V3_AUX")
		)
	)
	(footprint ""
		(layer "B.Cu")
		(at 103.901494 -244.82044 -90)
		(property "Reference" "C313"
			(at 0 0 90)
			(layer "B.SilkS")
			(hide yes)
			(effects
				(font
					(size 1.27 1.27)
				)
				(justify mirror)
			)
		)
		(property "Value" ""
			(at 0 0 90)
			(layer "B.Fab")
			(effects
				(font
					(size 1.27 1.27)
				)
				(justify mirror)
			)
		)
		(duplicate_pad_numbers_are_jumpers no)
		(fp_line
			(start -1.524 0.762)
			(end 1.524 0.762)
			(stroke
				(width 0.1524)
				(type default)
			)
			(layer "B.SilkS")
		)
		(fp_line
			(start 1.524 0.762)
			(end 1.524 -0.762)
			(stroke
				(width 0.1524)
				(type default)
			)
			(layer "B.SilkS")
		)
		(fp_line
			(start -1.524 -0.762)
			(end -1.524 0.762)
			(stroke
				(width 0.1524)
				(type default)
			)
			(layer "B.SilkS")
		)
		(fp_line
			(start 1.524 -0.762)
			(end -1.524 -0.762)
			(stroke
				(width 0.1524)
				(type default)
			)
			(layer "B.SilkS")
		)
		(fp_line
			(start -1.1049 0.724916)
			(end -1.1049 -0.724916)
			(stroke
				(width 0.1)
				(type default)
			)
			(layer "B.Fab")
		)
		(fp_line
			(start 1.1049 0.724916)
			(end -1.1049 0.724916)
			(stroke
				(width 0.1)
				(type default)
			)
			(layer "B.Fab")
		)
		(fp_line
			(start -1.1049 -0.724916)
			(end 1.1049 -0.724916)
			(stroke
				(width 0.1)
				(type default)
			)
			(layer "B.Fab")
		)
		(fp_line
			(start 1.1049 -0.724916)
			(end 1.1049 0.724916)
			(stroke
				(width 0.1)
				(type default)
			)
			(layer "B.Fab")
		)
		(pad "1" smd rect
			(at 0.889 0 270)
			(size 1.016 1.27)
			(layers "B.Cu" "B.Mask" "B.Paste")
			(net "PVCCIN_CPU1")
		)
		(pad "2" smd rect
			(at -0.889 0 270)
			(size 1.016 1.27)
			(layers "B.Cu" "B.Mask" "B.Paste")
			(net "GND")
		)
	)
	(footprint ""
		(layer "B.Cu")
		(at 434.089302 -318.868806 90)
		(property "Reference" "R942"
			(at 0 0 90)
			(layer "B.SilkS")
			(hide yes)
			(effects
				(font
					(size 1.27 1.27)
				)
				(justify mirror)
			)
		)
		(property "Value" ""
			(at 0 0 90)
			(layer "B.Fab")
			(effects
				(font
					(size 1.27 1.27)
				)
				(justify mirror)
			)
		)
		(duplicate_pad_numbers_are_jumpers no)
		(fp_line
			(start 0.7874 -0.4064)
			(end -0.7874 -0.4064)
			(stroke
				(width 0.1524)
				(type default)
			)
			(layer "B.SilkS")
		)
		(fp_line
			(start -0.7874 -0.4064)
			(end -0.7874 0.4064)
			(stroke
				(width 0.1524)
				(type default)
			)
			(layer "B.SilkS")
		)
		(fp_line
			(start 0.7874 0.4064)
			(end 0.7874 -0.4064)
			(stroke
				(width 0.1524)
				(type default)
			)
			(layer "B.SilkS")
		)
		(fp_line
			(start -0.7874 0.4064)
			(end 0.7874 0.4064)
			(stroke
				(width 0.1524)
				(type default)
			)
			(layer "B.SilkS")
		)
		(fp_line
			(start 0.67945 -0.305054)
			(end 0.12065 -0.305054)
			(stroke
				(width 0.1)
				(type default)
			)
			(layer "B.Fab")
		)
		(fp_line
			(start 0.12065 -0.305054)
			(end 0.12065 -0.2794)
			(stroke
				(width 0.1)
				(type default)
			)
			(layer "B.Fab")
		)
		(fp_line
			(start -0.12065 -0.3048)
			(end -0.67945 -0.3048)
			(stroke
				(width 0.1)
				(type default)
			)
			(layer "B.Fab")
		)
		(fp_line
			(start -0.67945 -0.3048)
			(end -0.67945 0.3048)
			(stroke
				(width 0.1)
				(type default)
			)
			(layer "B.Fab")
		)
		(fp_line
			(start 0.12065 -0.2794)
			(end -0.12065 -0.2794)
			(stroke
				(width 0.1)
				(type default)
			)
			(layer "B.Fab")
		)
		(fp_line
			(start -0.12065 -0.2794)
			(end -0.12065 -0.3048)
			(stroke
				(width 0.1)
				(type default)
			)
			(layer "B.Fab")
		)
		(fp_line
			(start 0.12065 0.2794)
			(end 0.12065 0.3048)
			(stroke
				(width 0.1)
				(type default)
			)
			(layer "B.Fab")
		)
		(fp_line
			(start -0.120396 0.2794)
			(end 0.12065 0.2794)
			(stroke
				(width 0.1)
				(type default)
			)
			(layer "B.Fab")
		)
		(fp_line
			(start 0.67945 0.3048)
			(end 0.67945 -0.305054)
			(stroke
				(width 0.1)
				(type default)
			)
			(layer "B.Fab")
		)
		(fp_line
			(start 0.12065 0.3048)
			(end 0.67945 0.3048)
			(stroke
				(width 0.1)
				(type default)
			)
			(layer "B.Fab")
		)
		(fp_line
			(start -0.120396 0.3048)
			(end -0.120396 0.2794)
			(stroke
				(width 0.1)
				(type default)
			)
			(layer "B.Fab")
		)
		(fp_line
			(start -0.67945 0.3048)
			(end -0.120396 0.3048)
			(stroke
				(width 0.1)
				(type default)
			)
			(layer "B.Fab")
		)
		(pad "1" smd circle
			(at 0.40005 0 270)
			(size 0 0)
			(layers "B.Cu" "B.Mask" "B.Paste")
			(net "P3V3_AUX")
		)
		(pad "2" smd circle
			(at -0.40005 0 270)
			(size 0 0)
			(layers "B.Cu" "B.Mask" "B.Paste")
			(net "PWRGD_FAIL_CPU0_EF_R1")
		)
	)
	(footprint ""
		(layer "B.Cu")
		(at 209.770218 -193.09461)
		(property "Reference" "C542"
			(at 0 0 0)
			(layer "B.SilkS")
			(hide yes)
			(effects
				(font
					(size 1.27 1.27)
				)
				(justify mirror)
			)
		)
		(property "Value" ""
			(at 0 0 0)
			(layer "B.Fab")
			(effects
				(font
					(size 1.27 1.27)
				)
				(justify mirror)
			)
		)
		(duplicate_pad_numbers_are_jumpers no)
		(fp_line
			(start -0.7874 -0.4064)
			(end -0.7874 0.4064)
			(stroke
				(width 0.1524)
				(type default)
			)
			(layer "B.SilkS")
		)
		(fp_line
			(start -0.7874 0.4064)
			(end 0.7874 0.4064)
			(stroke
				(width 0.1524)
				(type default)
			)
			(layer "B.SilkS")
		)
		(fp_line
			(start 0.7874 -0.4064)
			(end -0.7874 -0.4064)
			(stroke
				(width 0.1524)
				(type default)
			)
			(layer "B.SilkS")
		)
		(fp_line
			(start 0.7874 0.4064)
			(end 0.7874 -0.4064)
			(stroke
				(width 0.1524)
				(type default)
			)
			(layer "B.SilkS")
		)
		(fp_line
			(start -0.67945 -0.3048)
			(end -0.67945 0.3048)
			(stroke
				(width 0.1)
				(type default)
			)
			(layer "B.Fab")
		)
		(fp_line
			(start -0.67945 0.3048)
			(end -0.120396 0.3048)
			(stroke
				(width 0.1)
				(type default)
			)
			(layer "B.Fab")
		)
		(fp_line
			(start -0.12065 -0.3048)
			(end -0.67945 -0.3048)
			(stroke
				(width 0.1)
				(type default)
			)
			(layer "B.Fab")
		)
		(fp_line
			(start -0.12065 -0.2794)
			(end -0.12065 -0.3048)
			(stroke
				(width 0.1)
				(type default)
			)
			(layer "B.Fab")
		)
		(fp_line
			(start -0.120396 0.2794)
			(end 0.12065 0.2794)
			(stroke
				(width 0.1)
				(type default)
			)
			(layer "B.Fab")
		)
		(fp_line
			(start -0.120396 0.3048)
			(end -0.120396 0.2794)
			(stroke
				(width 0.1)
				(type default)
			)
			(layer "B.Fab")
		)
		(fp_line
			(start 0.12065 -0.305054)
			(end 0.12065 -0.2794)
			(stroke
				(width 0.1)
				(type default)
			)
			(layer "B.Fab")
		)
		(fp_line
			(start 0.12065 -0.2794)
			(end -0.12065 -0.2794)
			(stroke
				(width 0.1)
				(type default)
			)
			(layer "B.Fab")
		)
		(fp_line
			(start 0.12065 0.2794)
			(end 0.12065 0.3048)
			(stroke
				(width 0.1)
				(type default)
			)
			(layer "B.Fab")
		)
		(fp_line
			(start 0.12065 0.3048)
			(end 0.67945 0.3048)
			(stroke
				(width 0.1)
				(type default)
			)
			(layer "B.Fab")
		)
		(fp_line
			(start 0.67945 -0.305054)
			(end 0.12065 -0.305054)
			(stroke
				(width 0.1)
				(type default)
			)
			(layer "B.Fab")
		)
		(fp_line
			(start 0.67945 0.3048)
			(end 0.67945 -0.305054)
			(stroke
				(width 0.1)
				(type default)
			)
			(layer "B.Fab")
		)
		(pad "1" smd circle
			(at 0.40005 0 180)
			(size 0 0)
			(layers "B.Cu" "B.Mask" "B.Paste")
			(net "P3V3_AUX")
		)
		(pad "2" smd circle
			(at -0.40005 0 180)
			(size 0 0)
			(layers "B.Cu" "B.Mask" "B.Paste")
			(net "GND")
		)
	)
	(footprint ""
		(layer "B.Cu")
		(at 119.083074 -324.990714 -90)
		(property "Reference" "PC572_P1_1"
			(at 0 0 90)
			(layer "B.SilkS")
			(hide yes)
			(effects
				(font
					(size 1.27 1.27)
				)
				(justify mirror)
			)
		)
		(property "Value" ""
			(at 0 0 90)
			(layer "B.Fab")
			(effects
				(font
					(size 1.27 1.27)
				)
				(justify mirror)
			)
		)
		(duplicate_pad_numbers_are_jumpers no)
		(fp_line
			(start -0.7874 0.4064)
			(end 0.7874 0.4064)
			(stroke
				(width 0.1524)
				(type default)
			)
			(layer "B.SilkS")
		)
		(fp_line
			(start 0.7874 0.4064)
			(end 0.7874 -0.4064)
			(stroke
				(width 0.1524)
				(type default)
			)
			(layer "B.SilkS")
		)
		(fp_line
			(start -0.7874 -0.4064)
			(end -0.7874 0.4064)
			(stroke
				(width 0.1524)
				(type default)
			)
			(layer "B.SilkS")
		)
		(fp_line
			(start 0.7874 -0.4064)
			(end -0.7874 -0.4064)
			(stroke
				(width 0.1524)
				(type default)
			)
			(layer "B.SilkS")
		)
		(fp_line
			(start -0.67945 0.3048)
			(end -0.120396 0.3048)
			(stroke
				(width 0.1)
				(type default)
			)
			(layer "B.Fab")
		)
		(fp_line
			(start -0.120396 0.3048)
			(end -0.120396 0.2794)
			(stroke
				(width 0.1)
				(type default)
			)
			(layer "B.Fab")
		)
		(fp_line
			(start 0.12065 0.3048)
			(end 0.67945 0.3048)
			(stroke
				(width 0.1)
				(type default)
			)
			(layer "B.Fab")
		)
		(fp_line
			(start 0.67945 0.3048)
			(end 0.67945 -0.305054)
			(stroke
				(width 0.1)
				(type default)
			)
			(layer "B.Fab")
		)
		(fp_line
			(start -0.120396 0.2794)
			(end 0.12065 0.2794)
			(stroke
				(width 0.1)
				(type default)
			)
			(layer "B.Fab")
		)
		(fp_line
			(start 0.12065 0.2794)
			(end 0.12065 0.3048)
			(stroke
				(width 0.1)
				(type default)
			)
			(layer "B.Fab")
		)
		(fp_line
			(start -0.12065 -0.2794)
			(end -0.12065 -0.3048)
			(stroke
				(width 0.1)
				(type default)
			)
			(layer "B.Fab")
		)
		(fp_line
			(start 0.12065 -0.2794)
			(end -0.12065 -0.2794)
			(stroke
				(width 0.1)
				(type default)
			)
			(layer "B.Fab")
		)
		(fp_line
			(start -0.67945 -0.3048)
			(end -0.67945 0.3048)
			(stroke
				(width 0.1)
				(type default)
			)
			(layer "B.Fab")
		)
		(fp_line
			(start -0.12065 -0.3048)
			(end -0.67945 -0.3048)
			(stroke
				(width 0.1)
				(type default)
			)
			(layer "B.Fab")
		)
		(fp_line
			(start 0.12065 -0.305054)
			(end 0.12065 -0.2794)
			(stroke
				(width 0.1)
				(type default)
			)
			(layer "B.Fab")
		)
		(fp_line
			(start 0.67945 -0.305054)
			(end 0.12065 -0.305054)
			(stroke
				(width 0.1)
				(type default)
			)
			(layer "B.Fab")
		)
		(pad "1" smd circle
			(at 0.40005 0 90)
			(size 0 0)
			(layers "B.Cu" "B.Mask" "B.Paste")
			(net "PVCCIN_CPU1")
		)
		(pad "2" smd circle
			(at -0.40005 0 90)
			(size 0 0)
			(layers "B.Cu" "B.Mask" "B.Paste")
			(net "GND")
		)
	)
	(footprint ""
		(layer "B.Cu")
		(at 19.588734 -176.423574 -90)
		(property "Reference" "R2385"
			(at 0 0 90)
			(layer "B.SilkS")
			(hide yes)
			(effects
				(font
					(size 1.27 1.27)
				)
				(justify mirror)
			)
		)
		(property "Value" ""
			(at 0 0 90)
			(layer "B.Fab")
			(effects
				(font
					(size 1.27 1.27)
				)
				(justify mirror)
			)
		)
		(duplicate_pad_numbers_are_jumpers no)
		(fp_line
			(start -0.7874 0.4064)
			(end 0.7874 0.4064)
			(stroke
				(width 0.1524)
				(type default)
			)
			(layer "B.SilkS")
		)
		(fp_line
			(start 0.7874 0.4064)
			(end 0.7874 -0.4064)
			(stroke
				(width 0.1524)
				(type default)
			)
			(layer "B.SilkS")
		)
		(fp_line
			(start -0.7874 -0.4064)
			(end -0.7874 0.4064)
			(stroke
				(width 0.1524)
				(type default)
			)
			(layer "B.SilkS")
		)
		(fp_line
			(start 0.7874 -0.4064)
			(end -0.7874 -0.4064)
			(stroke
				(width 0.1524)
				(type default)
			)
			(layer "B.SilkS")
		)
		(fp_line
			(start -0.67945 0.3048)
			(end -0.120396 0.3048)
			(stroke
				(width 0.1)
				(type default)
			)
			(layer "B.Fab")
		)
		(fp_line
			(start -0.120396 0.3048)
			(end -0.120396 0.2794)
			(stroke
				(width 0.1)
				(type default)
			)
			(layer "B.Fab")
		)
		(fp_line
			(start 0.12065 0.3048)
			(end 0.67945 0.3048)
			(stroke
				(width 0.1)
				(type default)
			)
			(layer "B.Fab")
		)
		(fp_line
			(start 0.67945 0.3048)
			(end 0.67945 -0.305054)
			(stroke
				(width 0.1)
				(type default)
			)
			(layer "B.Fab")
		)
		(fp_line
			(start -0.120396 0.2794)
			(end 0.12065 0.2794)
			(stroke
				(width 0.1)
				(type default)
			)
			(layer "B.Fab")
		)
		(fp_line
			(start 0.12065 0.2794)
			(end 0.12065 0.3048)
			(stroke
				(width 0.1)
				(type default)
			)
			(layer "B.Fab")
		)
		(fp_line
			(start -0.12065 -0.2794)
			(end -0.12065 -0.3048)
			(stroke
				(width 0.1)
				(type default)
			)
			(layer "B.Fab")
		)
		(fp_line
			(start 0.12065 -0.2794)
			(end -0.12065 -0.2794)
			(stroke
				(width 0.1)
				(type default)
			)
			(layer "B.Fab")
		)
		(fp_line
			(start -0.67945 -0.3048)
			(end -0.67945 0.3048)
			(stroke
				(width 0.1)
				(type default)
			)
			(layer "B.Fab")
		)
		(fp_line
			(start -0.12065 -0.3048)
			(end -0.67945 -0.3048)
			(stroke
				(width 0.1)
				(type default)
			)
			(layer "B.Fab")
		)
		(fp_line
			(start 0.12065 -0.305054)
			(end 0.12065 -0.2794)
			(stroke
				(width 0.1)
				(type default)
			)
			(layer "B.Fab")
		)
		(fp_line
			(start 0.67945 -0.305054)
			(end 0.12065 -0.305054)
			(stroke
				(width 0.1)
				(type default)
			)
			(layer "B.Fab")
		)
		(pad "1" smd circle
			(at 0.40005 0 90)
			(size 0 0)
			(layers "B.Cu" "B.Mask" "B.Paste")
			(net "FM_PVNN_MAIN_CPU1_EN")
		)
		(pad "2" smd circle
			(at -0.40005 0 90)
			(size 0 0)
			(layers "B.Cu" "B.Mask" "B.Paste")
			(net "GND")
		)
	)
	(footprint ""
		(layer "B.Cu")
		(at 11.961114 -98.296222 180)
		(property "Reference" "C2034"
			(at 0 0 0)
			(layer "B.SilkS")
			(hide yes)
			(effects
				(font
					(size 1.27 1.27)
				)
				(justify mirror)
			)
		)
		(property "Value" ""
			(at 0 0 0)
			(layer "B.Fab")
			(effects
				(font
					(size 1.27 1.27)
				)
				(justify mirror)
			)
		)
		(duplicate_pad_numbers_are_jumpers no)
		(fp_line
			(start 0.7874 0.4064)
			(end 0.7874 -0.4064)
			(stroke
				(width 0.1524)
				(type default)
			)
			(layer "B.SilkS")
		)
		(fp_line
			(start 0.7874 -0.4064)
			(end -0.7874 -0.4064)
			(stroke
				(width 0.1524)
				(type default)
			)
			(layer "B.SilkS")
		)
		(fp_line
			(start -0.7874 0.4064)
			(end 0.7874 0.4064)
			(stroke
				(width 0.1524)
				(type default)
			)
			(layer "B.SilkS")
		)
		(fp_line
			(start -0.7874 -0.4064)
			(end -0.7874 0.4064)
			(stroke
				(width 0.1524)
				(type default)
			)
			(layer "B.SilkS")
		)
		(fp_line
			(start 0.67945 0.3048)
			(end 0.67945 -0.305054)
			(stroke
				(width 0.1)
				(type default)
			)
			(layer "B.Fab")
		)
		(fp_line
			(start 0.67945 -0.305054)
			(end 0.12065 -0.305054)
			(stroke
				(width 0.1)
				(type default)
			)
			(layer "B.Fab")
		)
		(fp_line
			(start 0.12065 0.3048)
			(end 0.67945 0.3048)
			(stroke
				(width 0.1)
				(type default)
			)
			(layer "B.Fab")
		)
		(fp_line
			(start 0.12065 0.2794)
			(end 0.12065 0.3048)
			(stroke
				(width 0.1)
				(type default)
			)
			(layer "B.Fab")
		)
		(fp_line
			(start 0.12065 -0.2794)
			(end -0.12065 -0.2794)
			(stroke
				(width 0.1)
				(type default)
			)
			(layer "B.Fab")
		)
		(fp_line
			(start 0.12065 -0.305054)
			(end 0.12065 -0.2794)
			(stroke
				(width 0.1)
				(type default)
			)
			(layer "B.Fab")
		)
		(fp_line
			(start -0.120396 0.3048)
			(end -0.120396 0.2794)
			(stroke
				(width 0.1)
				(type default)
			)
			(layer "B.Fab")
		)
		(fp_line
			(start -0.120396 0.2794)
			(end 0.12065 0.2794)
			(stroke
				(width 0.1)
				(type default)
			)
			(layer "B.Fab")
		)
		(fp_line
			(start -0.12065 -0.2794)
			(end -0.12065 -0.3048)
			(stroke
				(width 0.1)
				(type default)
			)
			(layer "B.Fab")
		)
		(fp_line
			(start -0.12065 -0.3048)
			(end -0.67945 -0.3048)
			(stroke
				(width 0.1)
				(type default)
			)
			(layer "B.Fab")
		)
		(fp_line
			(start -0.67945 0.3048)
			(end -0.120396 0.3048)
			(stroke
				(width 0.1)
				(type default)
			)
			(layer "B.Fab")
		)
		(fp_line
			(start -0.67945 -0.3048)
			(end -0.67945 0.3048)
			(stroke
				(width 0.1)
				(type default)
			)
			(layer "B.Fab")
		)
		(pad "1" smd circle
			(at 0.40005 0)
			(size 0 0)
			(layers "B.Cu" "B.Mask" "B.Paste")
			(net "P3V3_AUX_USB_HUB")
		)
		(pad "2" smd circle
			(at -0.40005 0)
			(size 0 0)
			(layers "B.Cu" "B.Mask" "B.Paste")
			(net "GND")
		)
	)
	(footprint ""
		(layer "B.Cu")
		(at 323.407278 -186.70651 -90)
		(property "Reference" "R301"
			(at 0 0 90)
			(layer "B.SilkS")
			(hide yes)
			(effects
				(font
					(size 1.27 1.27)
				)
				(justify mirror)
			)
		)
		(property "Value" ""
			(at 0 0 90)
			(layer "B.Fab")
			(effects
				(font
					(size 1.27 1.27)
				)
				(justify mirror)
			)
		)
		(duplicate_pad_numbers_are_jumpers no)
		(fp_line
			(start -0.7874 0.4064)
			(end 0.7874 0.4064)
			(stroke
				(width 0.1524)
				(type default)
			)
			(layer "B.SilkS")
		)
		(fp_line
			(start 0.7874 0.4064)
			(end 0.7874 -0.4064)
			(stroke
				(width 0.1524)
				(type default)
			)
			(layer "B.SilkS")
		)
		(fp_line
			(start -0.7874 -0.4064)
			(end -0.7874 0.4064)
			(stroke
				(width 0.1524)
				(type default)
			)
			(layer "B.SilkS")
		)
		(fp_line
			(start 0.7874 -0.4064)
			(end -0.7874 -0.4064)
			(stroke
				(width 0.1524)
				(type default)
			)
			(layer "B.SilkS")
		)
		(fp_line
			(start -0.67945 0.3048)
			(end -0.120396 0.3048)
			(stroke
				(width 0.1)
				(type default)
			)
			(layer "B.Fab")
		)
		(fp_line
			(start -0.120396 0.3048)
			(end -0.120396 0.2794)
			(stroke
				(width 0.1)
				(type default)
			)
			(layer "B.Fab")
		)
		(fp_line
			(start 0.12065 0.3048)
			(end 0.67945 0.3048)
			(stroke
				(width 0.1)
				(type default)
			)
			(layer "B.Fab")
		)
		(fp_line
			(start 0.67945 0.3048)
			(end 0.67945 -0.305054)
			(stroke
				(width 0.1)
				(type default)
			)
			(layer "B.Fab")
		)
		(fp_line
			(start -0.120396 0.2794)
			(end 0.12065 0.2794)
			(stroke
				(width 0.1)
				(type default)
			)
			(layer "B.Fab")
		)
		(fp_line
			(start 0.12065 0.2794)
			(end 0.12065 0.3048)
			(stroke
				(width 0.1)
				(type default)
			)
			(layer "B.Fab")
		)
		(fp_line
			(start -0.12065 -0.2794)
			(end -0.12065 -0.3048)
			(stroke
				(width 0.1)
				(type default)
			)
			(layer "B.Fab")
		)
		(fp_line
			(start 0.12065 -0.2794)
			(end -0.12065 -0.2794)
			(stroke
				(width 0.1)
				(type default)
			)
			(layer "B.Fab")
		)
		(fp_line
			(start -0.67945 -0.3048)
			(end -0.67945 0.3048)
			(stroke
				(width 0.1)
				(type default)
			)
			(layer "B.Fab")
		)
		(fp_line
			(start -0.12065 -0.3048)
			(end -0.67945 -0.3048)
			(stroke
				(width 0.1)
				(type default)
			)
			(layer "B.Fab")
		)
		(fp_line
			(start 0.12065 -0.305054)
			(end 0.12065 -0.2794)
			(stroke
				(width 0.1)
				(type default)
			)
			(layer "B.Fab")
		)
		(fp_line
			(start 0.67945 -0.305054)
			(end 0.12065 -0.305054)
			(stroke
				(width 0.1)
				(type default)
			)
			(layer "B.Fab")
		)
		(pad "1" smd circle
			(at 0.40005 0 90)
			(size 0 0)
			(layers "B.Cu" "B.Mask" "B.Paste")
			(net "PVNN_TERM_CPU0")
		)
		(pad "2" smd circle
			(at -0.40005 0 90)
			(size 0 0)
			(layers "B.Cu" "B.Mask" "B.Paste")
			(net "H_CPU_RMCA_LVC1_R_N")
		)
	)
	(footprint ""
		(layer "B.Cu")
		(at 74.347324 -190.705232 90)
		(property "Reference" "R52"
			(at 0 0 90)
			(layer "B.SilkS")
			(hide yes)
			(effects
				(font
					(size 1.27 1.27)
				)
				(justify mirror)
			)
		)
		(property "Value" ""
			(at 0 0 90)
			(layer "B.Fab")
			(effects
				(font
					(size 1.27 1.27)
				)
				(justify mirror)
			)
		)
		(duplicate_pad_numbers_are_jumpers no)
		(fp_line
			(start 0.7874 -0.4064)
			(end -0.7874 -0.4064)
			(stroke
				(width 0.1524)
				(type default)
			)
			(layer "B.SilkS")
		)
		(fp_line
			(start -0.7874 -0.4064)
			(end -0.7874 0.4064)
			(stroke
				(width 0.1524)
				(type default)
			)
			(layer "B.SilkS")
		)
		(fp_line
			(start 0.7874 0.4064)
			(end 0.7874 -0.4064)
			(stroke
				(width 0.1524)
				(type default)
			)
			(layer "B.SilkS")
		)
		(fp_line
			(start -0.7874 0.4064)
			(end 0.7874 0.4064)
			(stroke
				(width 0.1524)
				(type default)
			)
			(layer "B.SilkS")
		)
		(fp_line
			(start 0.67945 -0.305054)
			(end 0.12065 -0.305054)
			(stroke
				(width 0.1)
				(type default)
			)
			(layer "B.Fab")
		)
		(fp_line
			(start 0.12065 -0.305054)
			(end 0.12065 -0.2794)
			(stroke
				(width 0.1)
				(type default)
			)
			(layer "B.Fab")
		)
		(fp_line
			(start -0.12065 -0.3048)
			(end -0.67945 -0.3048)
			(stroke
				(width 0.1)
				(type default)
			)
			(layer "B.Fab")
		)
		(fp_line
			(start -0.67945 -0.3048)
			(end -0.67945 0.3048)
			(stroke
				(width 0.1)
				(type default)
			)
			(layer "B.Fab")
		)
		(fp_line
			(start 0.12065 -0.2794)
			(end -0.12065 -0.2794)
			(stroke
				(width 0.1)
				(type default)
			)
			(layer "B.Fab")
		)
		(fp_line
			(start -0.12065 -0.2794)
			(end -0.12065 -0.3048)
			(stroke
				(width 0.1)
				(type default)
			)
			(layer "B.Fab")
		)
		(fp_line
			(start 0.12065 0.2794)
			(end 0.12065 0.3048)
			(stroke
				(width 0.1)
				(type default)
			)
			(layer "B.Fab")
		)
		(fp_line
			(start -0.120396 0.2794)
			(end 0.12065 0.2794)
			(stroke
				(width 0.1)
				(type default)
			)
			(layer "B.Fab")
		)
		(fp_line
			(start 0.67945 0.3048)
			(end 0.67945 -0.305054)
			(stroke
				(width 0.1)
				(type default)
			)
			(layer "B.Fab")
		)
		(fp_line
			(start 0.12065 0.3048)
			(end 0.67945 0.3048)
			(stroke
				(width 0.1)
				(type default)
			)
			(layer "B.Fab")
		)
		(fp_line
			(start -0.120396 0.3048)
			(end -0.120396 0.2794)
			(stroke
				(width 0.1)
				(type default)
			)
			(layer "B.Fab")
		)
		(fp_line
			(start -0.67945 0.3048)
			(end -0.120396 0.3048)
			(stroke
				(width 0.1)
				(type default)
			)
			(layer "B.Fab")
		)
		(pad "1" smd circle
			(at 0.40005 0 270)
			(size 0 0)
			(layers "B.Cu" "B.Mask" "B.Paste")
			(net "DBP_CPU1_MBP1_GTL_R_N")
		)
		(pad "2" smd circle
			(at -0.40005 0 270)
			(size 0 0)
			(layers "B.Cu" "B.Mask" "B.Paste")
			(net "DBP_CPU_MBP1_GTL_N")
		)
	)
	(footprint ""
		(layer "B.Cu")
		(at 234.894628 -123.015248 90)
		(property "Reference" "C209"
			(at 0 0 90)
			(layer "B.SilkS")
			(hide yes)
			(effects
				(font
					(size 1.27 1.27)
				)
				(justify mirror)
			)
		)
		(property "Value" ""
			(at 0 0 90)
			(layer "B.Fab")
			(effects
				(font
					(size 1.27 1.27)
				)
				(justify mirror)
			)
		)
		(duplicate_pad_numbers_are_jumpers no)
		(fp_line
			(start 1.2954 -0.5842)
			(end -1.2954 -0.5842)
			(stroke
				(width 0.1524)
				(type default)
			)
			(layer "B.SilkS")
		)
		(fp_line
			(start 0 -0.5842)
			(end 0 0.5842)
			(stroke
				(width 0.1524)
				(type default)
			)
			(layer "B.SilkS")
		)
		(fp_line
			(start -1.2954 -0.5842)
			(end -1.2954 0.5842)
			(stroke
				(width 0.1524)
				(type default)
			)
			(layer "B.SilkS")
		)
		(fp_line
			(start 1.2954 0.5842)
			(end 1.2954 -0.5842)
			(stroke
				(width 0.1524)
				(type default)
			)
			(layer "B.SilkS")
		)
		(fp_line
			(start -1.2954 0.5842)
			(end 1.2954 0.5842)
			(stroke
				(width 0.1524)
				(type default)
			)
			(layer "B.SilkS")
		)
		(fp_line
			(start 0.8636 -0.4572)
			(end -0.8636 -0.4572)
			(stroke
				(width 0.1)
				(type default)
			)
			(layer "B.Fab")
		)
		(fp_line
			(start -0.8636 -0.4572)
			(end -0.8636 -0.4064)
			(stroke
				(width 0.1)
				(type default)
			)
			(layer "B.Fab")
		)
		(fp_line
			(start 1.1938 -0.4064)
			(end 0.8636 -0.4064)
			(stroke
				(width 0.1)
				(type default)
			)
			(layer "B.Fab")
		)
		(fp_line
			(start 0.8636 -0.4064)
			(end 0.8636 -0.4572)
			(stroke
				(width 0.1)
				(type default)
			)
			(layer "B.Fab")
		)
		(fp_line
			(start -0.8636 -0.4064)
			(end -1.1938 -0.4064)
			(stroke
				(width 0.1)
				(type default)
			)
			(layer "B.Fab")
		)
		(fp_line
			(start -1.1938 -0.4064)
			(end -1.1938 0.4064)
			(stroke
				(width 0.1)
				(type default)
			)
			(layer "B.Fab")
		)
		(fp_line
			(start 1.1938 0.4064)
			(end 1.1938 -0.4064)
			(stroke
				(width 0.1)
				(type default)
			)
			(layer "B.Fab")
		)
		(fp_line
			(start 0.8636 0.4064)
			(end 1.1938 0.4064)
			(stroke
				(width 0.1)
				(type default)
			)
			(layer "B.Fab")
		)
		(fp_line
			(start -0.8636 0.4064)
			(end -0.8636 0.4572)
			(stroke
				(width 0.1)
				(type default)
			)
			(layer "B.Fab")
		)
		(fp_line
			(start -1.1938 0.4064)
			(end -0.8636 0.4064)
			(stroke
				(width 0.1)
				(type default)
			)
			(layer "B.Fab")
		)
		(fp_line
			(start 0.8636 0.4572)
			(end 0.8636 0.4064)
			(stroke
				(width 0.1)
				(type default)
			)
			(layer "B.Fab")
		)
		(fp_line
			(start -0.8636 0.4572)
			(end 0.8636 0.4572)
			(stroke
				(width 0.1)
				(type default)
			)
			(layer "B.Fab")
		)
		(pad "1" smd rect
			(at 0.7366 0)
			(size 0.7112 0.8128)
			(layers "B.Cu" "B.Mask" "B.Paste")
			(net "P3V3_DB2000_VDDA")
		)
		(pad "2" smd rect
			(at -0.7366 0)
			(size 0.7112 0.8128)
			(layers "B.Cu" "B.Mask" "B.Paste")
			(net "GND")
		)
	)
	(footprint ""
		(layer "B.Cu")
		(at 433.073302 -318.868806 90)
		(property "Reference" "R2732"
			(at 0 0 90)
			(layer "B.SilkS")
			(hide yes)
			(effects
				(font
					(size 1.27 1.27)
				)
				(justify mirror)
			)
		)
		(property "Value" ""
			(at 0 0 90)
			(layer "B.Fab")
			(effects
				(font
					(size 1.27 1.27)
				)
				(justify mirror)
			)
		)
		(duplicate_pad_numbers_are_jumpers no)
		(fp_line
			(start 0.7874 -0.4064)
			(end -0.7874 -0.4064)
			(stroke
				(width 0.1524)
				(type default)
			)
			(layer "B.SilkS")
		)
		(fp_line
			(start -0.7874 -0.4064)
			(end -0.7874 0.4064)
			(stroke
				(width 0.1524)
				(type default)
			)
			(layer "B.SilkS")
		)
		(fp_line
			(start 0.7874 0.4064)
			(end 0.7874 -0.4064)
			(stroke
				(width 0.1524)
				(type default)
			)
			(layer "B.SilkS")
		)
		(fp_line
			(start -0.7874 0.4064)
			(end 0.7874 0.4064)
			(stroke
				(width 0.1524)
				(type default)
			)
			(layer "B.SilkS")
		)
		(fp_line
			(start 0.67945 -0.305054)
			(end 0.12065 -0.305054)
			(stroke
				(width 0.1)
				(type default)
			)
			(layer "B.Fab")
		)
		(fp_line
			(start 0.12065 -0.305054)
			(end 0.12065 -0.2794)
			(stroke
				(width 0.1)
				(type default)
			)
			(layer "B.Fab")
		)
		(fp_line
			(start -0.12065 -0.3048)
			(end -0.67945 -0.3048)
			(stroke
				(width 0.1)
				(type default)
			)
			(layer "B.Fab")
		)
		(fp_line
			(start -0.67945 -0.3048)
			(end -0.67945 0.3048)
			(stroke
				(width 0.1)
				(type default)
			)
			(layer "B.Fab")
		)
		(fp_line
			(start 0.12065 -0.2794)
			(end -0.12065 -0.2794)
			(stroke
				(width 0.1)
				(type default)
			)
			(layer "B.Fab")
		)
		(fp_line
			(start -0.12065 -0.2794)
			(end -0.12065 -0.3048)
			(stroke
				(width 0.1)
				(type default)
			)
			(layer "B.Fab")
		)
		(fp_line
			(start 0.12065 0.2794)
			(end 0.12065 0.3048)
			(stroke
				(width 0.1)
				(type default)
			)
			(layer "B.Fab")
		)
		(fp_line
			(start -0.120396 0.2794)
			(end 0.12065 0.2794)
			(stroke
				(width 0.1)
				(type default)
			)
			(layer "B.Fab")
		)
		(fp_line
			(start 0.67945 0.3048)
			(end 0.67945 -0.305054)
			(stroke
				(width 0.1)
				(type default)
			)
			(layer "B.Fab")
		)
		(fp_line
			(start 0.12065 0.3048)
			(end 0.67945 0.3048)
			(stroke
				(width 0.1)
				(type default)
			)
			(layer "B.Fab")
		)
		(fp_line
			(start -0.120396 0.3048)
			(end -0.120396 0.2794)
			(stroke
				(width 0.1)
				(type default)
			)
			(layer "B.Fab")
		)
		(fp_line
			(start -0.67945 0.3048)
			(end -0.120396 0.3048)
			(stroke
				(width 0.1)
				(type default)
			)
			(layer "B.Fab")
		)
		(pad "1" smd circle
			(at 0.40005 0 270)
			(size 0 0)
			(layers "B.Cu" "B.Mask" "B.Paste")
			(net "PWRGD_CHF_CPU0_DIMM1")
		)
		(pad "2" smd circle
			(at -0.40005 0 270)
			(size 0 0)
			(layers "B.Cu" "B.Mask" "B.Paste")
			(net "PWRGD_FAIL_CPU0_EF")
		)
	)
	(footprint ""
		(layer "B.Cu")
		(at 430.77384 -122.281188 180)
		(property "Reference" "PR369"
			(at 0 0 0)
			(layer "B.SilkS")
			(hide yes)
			(effects
				(font
					(size 1.27 1.27)
				)
				(justify mirror)
			)
		)
		(property "Value" ""
			(at 0 0 0)
			(layer "B.Fab")
			(effects
				(font
					(size 1.27 1.27)
				)
				(justify mirror)
			)
		)
		(duplicate_pad_numbers_are_jumpers no)
		(fp_line
			(start 0.7874 0.4064)
			(end 0.7874 -0.4064)
			(stroke
				(width 0.1524)
				(type default)
			)
			(layer "B.SilkS")
		)
		(fp_line
			(start 0.7874 -0.4064)
			(end -0.7874 -0.4064)
			(stroke
				(width 0.1524)
				(type default)
			)
			(layer "B.SilkS")
		)
		(fp_line
			(start -0.7874 0.4064)
			(end 0.7874 0.4064)
			(stroke
				(width 0.1524)
				(type default)
			)
			(layer "B.SilkS")
		)
		(fp_line
			(start -0.7874 -0.4064)
			(end -0.7874 0.4064)
			(stroke
				(width 0.1524)
				(type default)
			)
			(layer "B.SilkS")
		)
		(fp_line
			(start 0.67945 0.3048)
			(end 0.67945 -0.305054)
			(stroke
				(width 0.1)
				(type default)
			)
			(layer "B.Fab")
		)
		(fp_line
			(start 0.67945 -0.305054)
			(end 0.12065 -0.305054)
			(stroke
				(width 0.1)
				(type default)
			)
			(layer "B.Fab")
		)
		(fp_line
			(start 0.12065 0.3048)
			(end 0.67945 0.3048)
			(stroke
				(width 0.1)
				(type default)
			)
			(layer "B.Fab")
		)
		(fp_line
			(start 0.12065 0.2794)
			(end 0.12065 0.3048)
			(stroke
				(width 0.1)
				(type default)
			)
			(layer "B.Fab")
		)
		(fp_line
			(start 0.12065 -0.2794)
			(end -0.12065 -0.2794)
			(stroke
				(width 0.1)
				(type default)
			)
			(layer "B.Fab")
		)
		(fp_line
			(start 0.12065 -0.305054)
			(end 0.12065 -0.2794)
			(stroke
				(width 0.1)
				(type default)
			)
			(layer "B.Fab")
		)
		(fp_line
			(start -0.120396 0.3048)
			(end -0.120396 0.2794)
			(stroke
				(width 0.1)
				(type default)
			)
			(layer "B.Fab")
		)
		(fp_line
			(start -0.120396 0.2794)
			(end 0.12065 0.2794)
			(stroke
				(width 0.1)
				(type default)
			)
			(layer "B.Fab")
		)
		(fp_line
			(start -0.12065 -0.2794)
			(end -0.12065 -0.3048)
			(stroke
				(width 0.1)
				(type default)
			)
			(layer "B.Fab")
		)
		(fp_line
			(start -0.12065 -0.3048)
			(end -0.67945 -0.3048)
			(stroke
				(width 0.1)
				(type default)
			)
			(layer "B.Fab")
		)
		(fp_line
			(start -0.67945 0.3048)
			(end -0.120396 0.3048)
			(stroke
				(width 0.1)
				(type default)
			)
			(layer "B.Fab")
		)
		(fp_line
			(start -0.67945 -0.3048)
			(end -0.67945 0.3048)
			(stroke
				(width 0.1)
				(type default)
			)
			(layer "B.Fab")
		)
		(pad "1" smd circle
			(at 0.40005 0)
			(size 0 0)
			(layers "B.Cu" "B.Mask" "B.Paste")
			(net "PVCCD_HV_CPU0_ISENSE_P")
		)
		(pad "2" smd circle
			(at -0.40005 0)
			(size 0 0)
			(layers "B.Cu" "B.Mask" "B.Paste")
			(net "GND")
		)
	)
	(footprint ""
		(layer "B.Cu")
		(at 150.42388 -22.824948 -90)
		(property "Reference" "R2213"
			(at 0 0 90)
			(layer "B.SilkS")
			(hide yes)
			(effects
				(font
					(size 1.27 1.27)
				)
				(justify mirror)
			)
		)
		(property "Value" ""
			(at 0 0 90)
			(layer "B.Fab")
			(effects
				(font
					(size 1.27 1.27)
				)
				(justify mirror)
			)
		)
		(duplicate_pad_numbers_are_jumpers no)
		(fp_line
			(start -0.7874 0.4064)
			(end 0.7874 0.4064)
			(stroke
				(width 0.1524)
				(type default)
			)
			(layer "B.SilkS")
		)
		(fp_line
			(start 0.7874 0.4064)
			(end 0.7874 -0.4064)
			(stroke
				(width 0.1524)
				(type default)
			)
			(layer "B.SilkS")
		)
		(fp_line
			(start -0.7874 -0.4064)
			(end -0.7874 0.4064)
			(stroke
				(width 0.1524)
				(type default)
			)
			(layer "B.SilkS")
		)
		(fp_line
			(start 0.7874 -0.4064)
			(end -0.7874 -0.4064)
			(stroke
				(width 0.1524)
				(type default)
			)
			(layer "B.SilkS")
		)
		(fp_line
			(start -0.67945 0.3048)
			(end -0.120396 0.3048)
			(stroke
				(width 0.1)
				(type default)
			)
			(layer "B.Fab")
		)
		(fp_line
			(start -0.120396 0.3048)
			(end -0.120396 0.2794)
			(stroke
				(width 0.1)
				(type default)
			)
			(layer "B.Fab")
		)
		(fp_line
			(start 0.12065 0.3048)
			(end 0.67945 0.3048)
			(stroke
				(width 0.1)
				(type default)
			)
			(layer "B.Fab")
		)
		(fp_line
			(start 0.67945 0.3048)
			(end 0.67945 -0.305054)
			(stroke
				(width 0.1)
				(type default)
			)
			(layer "B.Fab")
		)
		(fp_line
			(start -0.120396 0.2794)
			(end 0.12065 0.2794)
			(stroke
				(width 0.1)
				(type default)
			)
			(layer "B.Fab")
		)
		(fp_line
			(start 0.12065 0.2794)
			(end 0.12065 0.3048)
			(stroke
				(width 0.1)
				(type default)
			)
			(layer "B.Fab")
		)
		(fp_line
			(start -0.12065 -0.2794)
			(end -0.12065 -0.3048)
			(stroke
				(width 0.1)
				(type default)
			)
			(layer "B.Fab")
		)
		(fp_line
			(start 0.12065 -0.2794)
			(end -0.12065 -0.2794)
			(stroke
				(width 0.1)
				(type default)
			)
			(layer "B.Fab")
		)
		(fp_line
			(start -0.67945 -0.3048)
			(end -0.67945 0.3048)
			(stroke
				(width 0.1)
				(type default)
			)
			(layer "B.Fab")
		)
		(fp_line
			(start -0.12065 -0.3048)
			(end -0.67945 -0.3048)
			(stroke
				(width 0.1)
				(type default)
			)
			(layer "B.Fab")
		)
		(fp_line
			(start 0.12065 -0.305054)
			(end 0.12065 -0.2794)
			(stroke
				(width 0.1)
				(type default)
			)
			(layer "B.Fab")
		)
		(fp_line
			(start 0.67945 -0.305054)
			(end 0.12065 -0.305054)
			(stroke
				(width 0.1)
				(type default)
			)
			(layer "B.Fab")
		)
		(pad "1" smd circle
			(at 0.40005 0 90)
			(size 0 0)
			(layers "B.Cu" "B.Mask" "B.Paste")
			(net "SMB_S3M_CPU_3V3AUX_SDA")
		)
		(pad "2" smd circle
			(at -0.40005 0 90)
			(size 0 0)
			(layers "B.Cu" "B.Mask" "B.Paste")
			(net "P3V3_AUX")
		)
	)
	(footprint ""
		(layer "B.Cu")
		(at 270.700246 -193.503296 -90)
		(property "Reference" "R841"
			(at 0 0 90)
			(layer "B.SilkS")
			(hide yes)
			(effects
				(font
					(size 1.27 1.27)
				)
				(justify mirror)
			)
		)
		(property "Value" ""
			(at 0 0 90)
			(layer "B.Fab")
			(effects
				(font
					(size 1.27 1.27)
				)
				(justify mirror)
			)
		)
		(duplicate_pad_numbers_are_jumpers no)
		(fp_line
			(start -0.7874 0.4064)
			(end 0.7874 0.4064)
			(stroke
				(width 0.1524)
				(type default)
			)
			(layer "B.SilkS")
		)
		(fp_line
			(start 0.7874 0.4064)
			(end 0.7874 -0.4064)
			(stroke
				(width 0.1524)
				(type default)
			)
			(layer "B.SilkS")
		)
		(fp_line
			(start -0.7874 -0.4064)
			(end -0.7874 0.4064)
			(stroke
				(width 0.1524)
				(type default)
			)
			(layer "B.SilkS")
		)
		(fp_line
			(start 0.7874 -0.4064)
			(end -0.7874 -0.4064)
			(stroke
				(width 0.1524)
				(type default)
			)
			(layer "B.SilkS")
		)
		(fp_line
			(start -0.67945 0.3048)
			(end -0.120396 0.3048)
			(stroke
				(width 0.1)
				(type default)
			)
			(layer "B.Fab")
		)
		(fp_line
			(start -0.120396 0.3048)
			(end -0.120396 0.2794)
			(stroke
				(width 0.1)
				(type default)
			)
			(layer "B.Fab")
		)
		(fp_line
			(start 0.12065 0.3048)
			(end 0.67945 0.3048)
			(stroke
				(width 0.1)
				(type default)
			)
			(layer "B.Fab")
		)
		(fp_line
			(start 0.67945 0.3048)
			(end 0.67945 -0.305054)
			(stroke
				(width 0.1)
				(type default)
			)
			(layer "B.Fab")
		)
		(fp_line
			(start -0.120396 0.2794)
			(end 0.12065 0.2794)
			(stroke
				(width 0.1)
				(type default)
			)
			(layer "B.Fab")
		)
		(fp_line
			(start 0.12065 0.2794)
			(end 0.12065 0.3048)
			(stroke
				(width 0.1)
				(type default)
			)
			(layer "B.Fab")
		)
		(fp_line
			(start -0.12065 -0.2794)
			(end -0.12065 -0.3048)
			(stroke
				(width 0.1)
				(type default)
			)
			(layer "B.Fab")
		)
		(fp_line
			(start 0.12065 -0.2794)
			(end -0.12065 -0.2794)
			(stroke
				(width 0.1)
				(type default)
			)
			(layer "B.Fab")
		)
		(fp_line
			(start -0.67945 -0.3048)
			(end -0.67945 0.3048)
			(stroke
				(width 0.1)
				(type default)
			)
			(layer "B.Fab")
		)
		(fp_line
			(start -0.12065 -0.3048)
			(end -0.67945 -0.3048)
			(stroke
				(width 0.1)
				(type default)
			)
			(layer "B.Fab")
		)
		(fp_line
			(start 0.12065 -0.305054)
			(end 0.12065 -0.2794)
			(stroke
				(width 0.1)
				(type default)
			)
			(layer "B.Fab")
		)
		(fp_line
			(start 0.67945 -0.305054)
			(end 0.12065 -0.305054)
			(stroke
				(width 0.1)
				(type default)
			)
			(layer "B.Fab")
		)
		(pad "1" smd circle
			(at 0.40005 0 90)
			(size 0 0)
			(layers "B.Cu" "B.Mask" "B.Paste")
			(net "PVCCD_HV_CPU0")
		)
		(pad "2" smd circle
			(at -0.40005 0 90)
			(size 0 0)
			(layers "B.Cu" "B.Mask" "B.Paste")
			(net "RST_M_CD_CPU0_FPGA_N")
		)
	)
	(footprint ""
		(layer "B.Cu")
		(at 27.375866 -193.152776 -90)
		(property "Reference" "R821"
			(at 0 0 90)
			(layer "B.SilkS")
			(hide yes)
			(effects
				(font
					(size 1.27 1.27)
				)
				(justify mirror)
			)
		)
		(property "Value" ""
			(at 0 0 90)
			(layer "B.Fab")
			(effects
				(font
					(size 1.27 1.27)
				)
				(justify mirror)
			)
		)
		(duplicate_pad_numbers_are_jumpers no)
		(fp_line
			(start -0.7874 0.4064)
			(end 0.7874 0.4064)
			(stroke
				(width 0.1524)
				(type default)
			)
			(layer "B.SilkS")
		)
		(fp_line
			(start 0.7874 0.4064)
			(end 0.7874 -0.4064)
			(stroke
				(width 0.1524)
				(type default)
			)
			(layer "B.SilkS")
		)
		(fp_line
			(start -0.7874 -0.4064)
			(end -0.7874 0.4064)
			(stroke
				(width 0.1524)
				(type default)
			)
			(layer "B.SilkS")
		)
		(fp_line
			(start 0.7874 -0.4064)
			(end -0.7874 -0.4064)
			(stroke
				(width 0.1524)
				(type default)
			)
			(layer "B.SilkS")
		)
		(fp_line
			(start -0.67945 0.3048)
			(end -0.120396 0.3048)
			(stroke
				(width 0.1)
				(type default)
			)
			(layer "B.Fab")
		)
		(fp_line
			(start -0.120396 0.3048)
			(end -0.120396 0.2794)
			(stroke
				(width 0.1)
				(type default)
			)
			(layer "B.Fab")
		)
		(fp_line
			(start 0.12065 0.3048)
			(end 0.67945 0.3048)
			(stroke
				(width 0.1)
				(type default)
			)
			(layer "B.Fab")
		)
		(fp_line
			(start 0.67945 0.3048)
			(end 0.67945 -0.305054)
			(stroke
				(width 0.1)
				(type default)
			)
			(layer "B.Fab")
		)
		(fp_line
			(start -0.120396 0.2794)
			(end 0.12065 0.2794)
			(stroke
				(width 0.1)
				(type default)
			)
			(layer "B.Fab")
		)
		(fp_line
			(start 0.12065 0.2794)
			(end 0.12065 0.3048)
			(stroke
				(width 0.1)
				(type default)
			)
			(layer "B.Fab")
		)
		(fp_line
			(start -0.12065 -0.2794)
			(end -0.12065 -0.3048)
			(stroke
				(width 0.1)
				(type default)
			)
			(layer "B.Fab")
		)
		(fp_line
			(start 0.12065 -0.2794)
			(end -0.12065 -0.2794)
			(stroke
				(width 0.1)
				(type default)
			)
			(layer "B.Fab")
		)
		(fp_line
			(start -0.67945 -0.3048)
			(end -0.67945 0.3048)
			(stroke
				(width 0.1)
				(type default)
			)
			(layer "B.Fab")
		)
		(fp_line
			(start -0.12065 -0.3048)
			(end -0.67945 -0.3048)
			(stroke
				(width 0.1)
				(type default)
			)
			(layer "B.Fab")
		)
		(fp_line
			(start 0.12065 -0.305054)
			(end 0.12065 -0.2794)
			(stroke
				(width 0.1)
				(type default)
			)
			(layer "B.Fab")
		)
		(fp_line
			(start 0.67945 -0.305054)
			(end 0.12065 -0.305054)
			(stroke
				(width 0.1)
				(type default)
			)
			(layer "B.Fab")
		)
		(pad "1" smd circle
			(at 0.40005 0 90)
			(size 0 0)
			(layers "B.Cu" "B.Mask" "B.Paste")
			(net "PVCCD_HV_CPU1")
		)
		(pad "2" smd circle
			(at -0.40005 0 90)
			(size 0 0)
			(layers "B.Cu" "B.Mask" "B.Paste")
			(net "RST_M_CD_CPU1_FPGA_N")
		)
	)
	(footprint ""
		(layer "B.Cu")
		(at 63.55588 -8.981948 90)
		(property "Reference" "C1838"
			(at 0 0 90)
			(layer "B.SilkS")
			(hide yes)
			(effects
				(font
					(size 1.27 1.27)
				)
				(justify mirror)
			)
		)
		(property "Value" ""
			(at 0 0 90)
			(layer "B.Fab")
			(effects
				(font
					(size 1.27 1.27)
				)
				(justify mirror)
			)
		)
		(duplicate_pad_numbers_are_jumpers no)
		(fp_line
			(start 0.7874 -0.4064)
			(end -0.7874 -0.4064)
			(stroke
				(width 0.1524)
				(type default)
			)
			(layer "B.SilkS")
		)
		(fp_line
			(start -0.7874 -0.4064)
			(end -0.7874 0.4064)
			(stroke
				(width 0.1524)
				(type default)
			)
			(layer "B.SilkS")
		)
		(fp_line
			(start 0.7874 0.4064)
			(end 0.7874 -0.4064)
			(stroke
				(width 0.1524)
				(type default)
			)
			(layer "B.SilkS")
		)
		(fp_line
			(start -0.7874 0.4064)
			(end 0.7874 0.4064)
			(stroke
				(width 0.1524)
				(type default)
			)
			(layer "B.SilkS")
		)
		(fp_line
			(start 0.67945 -0.305054)
			(end 0.12065 -0.305054)
			(stroke
				(width 0.1)
				(type default)
			)
			(layer "B.Fab")
		)
		(fp_line
			(start 0.12065 -0.305054)
			(end 0.12065 -0.2794)
			(stroke
				(width 0.1)
				(type default)
			)
			(layer "B.Fab")
		)
		(fp_line
			(start -0.12065 -0.3048)
			(end -0.67945 -0.3048)
			(stroke
				(width 0.1)
				(type default)
			)
			(layer "B.Fab")
		)
		(fp_line
			(start -0.67945 -0.3048)
			(end -0.67945 0.3048)
			(stroke
				(width 0.1)
				(type default)
			)
			(layer "B.Fab")
		)
		(fp_line
			(start 0.12065 -0.2794)
			(end -0.12065 -0.2794)
			(stroke
				(width 0.1)
				(type default)
			)
			(layer "B.Fab")
		)
		(fp_line
			(start -0.12065 -0.2794)
			(end -0.12065 -0.3048)
			(stroke
				(width 0.1)
				(type default)
			)
			(layer "B.Fab")
		)
		(fp_line
			(start 0.12065 0.2794)
			(end 0.12065 0.3048)
			(stroke
				(width 0.1)
				(type default)
			)
			(layer "B.Fab")
		)
		(fp_line
			(start -0.120396 0.2794)
			(end 0.12065 0.2794)
			(stroke
				(width 0.1)
				(type default)
			)
			(layer "B.Fab")
		)
		(fp_line
			(start 0.67945 0.3048)
			(end 0.67945 -0.305054)
			(stroke
				(width 0.1)
				(type default)
			)
			(layer "B.Fab")
		)
		(fp_line
			(start 0.12065 0.3048)
			(end 0.67945 0.3048)
			(stroke
				(width 0.1)
				(type default)
			)
			(layer "B.Fab")
		)
		(fp_line
			(start -0.120396 0.3048)
			(end -0.120396 0.2794)
			(stroke
				(width 0.1)
				(type default)
			)
			(layer "B.Fab")
		)
		(fp_line
			(start -0.67945 0.3048)
			(end -0.120396 0.3048)
			(stroke
				(width 0.1)
				(type default)
			)
			(layer "B.Fab")
		)
		(pad "1" smd circle
			(at 0.40005 0 270)
			(size 0 0)
			(layers "B.Cu" "B.Mask" "B.Paste")
			(net "P3V3_OCP_V3_2")
		)
		(pad "2" smd circle
			(at -0.40005 0 270)
			(size 0 0)
			(layers "B.Cu" "B.Mask" "B.Paste")
			(net "GND")
		)
	)
	(footprint ""
		(layer "B.Cu")
		(at 124.704602 -324.978776 -90)
		(property "Reference" "PC574_P1_1"
			(at 0 0 90)
			(layer "B.SilkS")
			(hide yes)
			(effects
				(font
					(size 1.27 1.27)
				)
				(justify mirror)
			)
		)
		(property "Value" ""
			(at 0 0 90)
			(layer "B.Fab")
			(effects
				(font
					(size 1.27 1.27)
				)
				(justify mirror)
			)
		)
		(duplicate_pad_numbers_are_jumpers no)
		(fp_line
			(start -0.7874 0.4064)
			(end 0.7874 0.4064)
			(stroke
				(width 0.1524)
				(type default)
			)
			(layer "B.SilkS")
		)
		(fp_line
			(start 0.7874 0.4064)
			(end 0.7874 -0.4064)
			(stroke
				(width 0.1524)
				(type default)
			)
			(layer "B.SilkS")
		)
		(fp_line
			(start -0.7874 -0.4064)
			(end -0.7874 0.4064)
			(stroke
				(width 0.1524)
				(type default)
			)
			(layer "B.SilkS")
		)
		(fp_line
			(start 0.7874 -0.4064)
			(end -0.7874 -0.4064)
			(stroke
				(width 0.1524)
				(type default)
			)
			(layer "B.SilkS")
		)
		(fp_line
			(start -0.67945 0.3048)
			(end -0.120396 0.3048)
			(stroke
				(width 0.1)
				(type default)
			)
			(layer "B.Fab")
		)
		(fp_line
			(start -0.120396 0.3048)
			(end -0.120396 0.2794)
			(stroke
				(width 0.1)
				(type default)
			)
			(layer "B.Fab")
		)
		(fp_line
			(start 0.12065 0.3048)
			(end 0.67945 0.3048)
			(stroke
				(width 0.1)
				(type default)
			)
			(layer "B.Fab")
		)
		(fp_line
			(start 0.67945 0.3048)
			(end 0.67945 -0.305054)
			(stroke
				(width 0.1)
				(type default)
			)
			(layer "B.Fab")
		)
		(fp_line
			(start -0.120396 0.2794)
			(end 0.12065 0.2794)
			(stroke
				(width 0.1)
				(type default)
			)
			(layer "B.Fab")
		)
		(fp_line
			(start 0.12065 0.2794)
			(end 0.12065 0.3048)
			(stroke
				(width 0.1)
				(type default)
			)
			(layer "B.Fab")
		)
		(fp_line
			(start -0.12065 -0.2794)
			(end -0.12065 -0.3048)
			(stroke
				(width 0.1)
				(type default)
			)
			(layer "B.Fab")
		)
		(fp_line
			(start 0.12065 -0.2794)
			(end -0.12065 -0.2794)
			(stroke
				(width 0.1)
				(type default)
			)
			(layer "B.Fab")
		)
		(fp_line
			(start -0.67945 -0.3048)
			(end -0.67945 0.3048)
			(stroke
				(width 0.1)
				(type default)
			)
			(layer "B.Fab")
		)
		(fp_line
			(start -0.12065 -0.3048)
			(end -0.67945 -0.3048)
			(stroke
				(width 0.1)
				(type default)
			)
			(layer "B.Fab")
		)
		(fp_line
			(start 0.12065 -0.305054)
			(end 0.12065 -0.2794)
			(stroke
				(width 0.1)
				(type default)
			)
			(layer "B.Fab")
		)
		(fp_line
			(start 0.67945 -0.305054)
			(end 0.12065 -0.305054)
			(stroke
				(width 0.1)
				(type default)
			)
			(layer "B.Fab")
		)
		(pad "1" smd circle
			(at 0.40005 0 90)
			(size 0 0)
			(layers "B.Cu" "B.Mask" "B.Paste")
			(net "PVCCIN_CPU1")
		)
		(pad "2" smd circle
			(at -0.40005 0 90)
			(size 0 0)
			(layers "B.Cu" "B.Mask" "B.Paste")
			(net "GND")
		)
	)
	(footprint ""
		(layer "B.Cu")
		(at 339.298534 2.923794 180)
		(property "Reference" "J115"
			(at 4.172204 -1.521206 270)
			(unlocked yes)
			(layer "B.SilkS")
			(effects
				(font
					(size 0.7874 0.5842)
					(thickness 0.1524)
				)
				(justify left mirror)
			)
		)
		(property "Value" ""
			(at 0 0 0)
			(layer "B.Fab")
			(effects
				(font
					(size 1.27 1.27)
				)
				(justify mirror)
			)
		)
		(duplicate_pad_numbers_are_jumpers no)
		(fp_line
			(start 1.2192 2.1082)
			(end 1.2192 -2.1082)
			(stroke
				(width 0.1524)
				(type default)
			)
			(layer "B.SilkS")
		)
		(fp_line
			(start 1.2192 -2.1082)
			(end -1.2192 -2.1082)
			(stroke
				(width 0.1524)
				(type default)
			)
			(layer "B.SilkS")
		)
		(fp_line
			(start -1.2192 2.1082)
			(end 1.2192 2.1082)
			(stroke
				(width 0.1524)
				(type default)
			)
			(layer "B.SilkS")
		)
		(fp_line
			(start -1.2192 -2.1082)
			(end -1.2192 2.1082)
			(stroke
				(width 0.1524)
				(type default)
			)
			(layer "B.SilkS")
		)
		(pad "" np_thru_hole circle
			(at -3.4671 -1.27 90)
			(size 1.0414 1.0414)
			(drill 1.0414)
			(layers "*.Cu" "*.Mask")
			(clearance 0.381)
			(thermal_gap 0.381)
		)
		(pad "" np_thru_hole circle
			(at -3.4671 1.27 90)
			(size 1.0414 1.0414)
			(drill 1.0414)
			(layers "*.Cu" "*.Mask")
			(clearance 0.381)
			(thermal_gap 0.381)
		)
		(pad "" np_thru_hole circle
			(at 2.8829 -1.27 90)
			(size 1.0414 1.0414)
			(drill 1.0414)
			(layers "*.Cu" "*.Mask")
			(clearance 0.381)
			(thermal_gap 0.381)
		)
		(pad "" np_thru_hole circle
			(at 2.8829 1.27 90)
			(size 1.0414 1.0414)
			(drill 1.0414)
			(layers "*.Cu" "*.Mask")
			(clearance 0.381)
			(thermal_gap 0.381)
		)
		(pad "1" smd rect
			(at -0.8255 -0.249936 90)
			(size 0.3048 0.508)
			(layers "B.Cu" "B.Mask" "B.Paste")
			(net "DELTA_L_85_5INCH_IN6_DP")
		)
		(pad "2" smd rect
			(at -0.8255 0.249936 90)
			(size 0.3048 0.508)
			(layers "B.Cu" "B.Mask" "B.Paste")
			(net "DELTA_L_85_5INCH_IN6_DN")
		)
		(pad "3" smd circle
			(at 0 0)
			(size 0 0)
			(layers "B.Cu" "B.Mask" "B.Paste")
			(net "DELTA_L_GND_1")
		)
		(zone
			(layers "F.Cu" "B.Cu" "In1.Cu" "In2.Cu" "In3.Cu" "In4.Cu" "In5.Cu" "In6.Cu"
				"In7.Cu" "In8.Cu" "In9.Cu" "In10.Cu" "In11.Cu" "In12.Cu" "In13.Cu" "In14.Cu"
				"In15.Cu" "In16.Cu"
			)
			(hatch none 0.5)
			(connect_pads
				(clearance 0)
			)
			(min_thickness 0.25)
			(keepout
				(tracks not_allowed)
				(vias allowed)
				(pads allowed)
				(copperpour not_allowed)
				(footprints allowed)
			)
			(placement
				(enabled no)
				(sheetname "")
			)
			(fill
				(thermal_gap 0.5)
				(thermal_bridge_width 0.5)
				(island_removal_mode 0)
			)
			(polygon
				(pts
					(arc
						(start 337.342734 1.653794)
						(mid 335.488534 1.653794)
						(end 337.342734 1.653794)
					)
				)
			)
		)
		(zone
			(layers "F.Cu" "B.Cu" "In1.Cu" "In2.Cu" "In3.Cu" "In4.Cu" "In5.Cu" "In6.Cu"
				"In7.Cu" "In8.Cu" "In9.Cu" "In10.Cu" "In11.Cu" "In12.Cu" "In13.Cu" "In14.Cu"
				"In15.Cu" "In16.Cu"
			)
			(hatch none 0.5)
			(connect_pads
				(clearance 0)
			)
			(min_thickness 0.25)
			(keepout
				(tracks not_allowed)
				(vias allowed)
				(pads allowed)
				(copperpour not_allowed)
				(footprints allowed)
			)
			(placement
				(enabled no)
				(sheetname "")
			)
			(fill
				(thermal_gap 0.5)
				(thermal_bridge_width 0.5)
				(island_removal_mode 0)
			)
			(polygon
				(pts
					(arc
						(start 337.342734 4.193794)
						(mid 335.488534 4.193794)
						(end 337.342734 4.193794)
					)
				)
			)
		)
		(zone
			(layers "F.Cu" "B.Cu" "In1.Cu" "In2.Cu" "In3.Cu" "In4.Cu" "In5.Cu" "In6.Cu"
				"In7.Cu" "In8.Cu" "In9.Cu" "In10.Cu" "In11.Cu" "In12.Cu" "In13.Cu" "In14.Cu"
				"In15.Cu" "In16.Cu"
			)
			(hatch none 0.5)
			(connect_pads
				(clearance 0)
			)
			(min_thickness 0.25)
			(keepout
				(tracks not_allowed)
				(vias allowed)
				(pads allowed)
				(copperpour not_allowed)
				(footprints allowed)
			)
			(placement
				(enabled no)
				(sheetname "")
			)
			(fill
				(thermal_gap 0.5)
				(thermal_bridge_width 0.5)
				(island_removal_mode 0)
			)
			(polygon
				(pts
					(arc
						(start 343.692734 1.653794)
						(mid 341.838534 1.653794)
						(end 343.692734 1.653794)
					)
				)
			)
		)
		(zone
			(layers "F.Cu" "B.Cu" "In1.Cu" "In2.Cu" "In3.Cu" "In4.Cu" "In5.Cu" "In6.Cu"
				"In7.Cu" "In8.Cu" "In9.Cu" "In10.Cu" "In11.Cu" "In12.Cu" "In13.Cu" "In14.Cu"
				"In15.Cu" "In16.Cu"
			)
			(hatch none 0.5)
			(connect_pads
				(clearance 0)
			)
			(min_thickness 0.25)
			(keepout
				(tracks not_allowed)
				(vias allowed)
				(pads allowed)
				(copperpour not_allowed)
				(footprints allowed)
			)
			(placement
				(enabled no)
				(sheetname "")
			)
			(fill
				(thermal_gap 0.5)
				(thermal_bridge_width 0.5)
				(island_removal_mode 0)
			)
			(polygon
				(pts
					(arc
						(start 343.692734 4.193794)
						(mid 341.838534 4.193794)
						(end 343.692734 4.193794)
					)
				)
			)
		)
		(zone
			(layer "B.Cu")
			(hatch none 0.5)
			(connect_pads
				(clearance 0)
			)
			(min_thickness 0.25)
			(keepout
				(tracks not_allowed)
				(vias allowed)
				(pads allowed)
				(copperpour not_allowed)
				(footprints allowed)
			)
			(placement
				(enabled no)
				(sheetname "")
			)
			(fill
				(thermal_gap 0.5)
				(thermal_bridge_width 0.5)
				(island_removal_mode 0)
			)
			(polygon
				(pts
					(xy 340.416134 3.472434) (xy 340.416134 3.37693) (xy 339.819234 3.37693) (xy 339.819234 2.97053)
					(xy 340.416134 2.97053) (xy 340.416134 2.877058) (xy 339.819234 2.877058) (xy 339.819234 2.470658)
					(xy 340.416134 2.470658) (xy 340.416134 2.375154) (xy 339.717634 2.375154) (xy 339.717634 3.472434)
				)
			)
		)
	)
	(footprint ""
		(layer "B.Cu")
		(at 269.684246 -193.503296 -90)
		(property "Reference" "R837"
			(at 0 0 90)
			(layer "B.SilkS")
			(hide yes)
			(effects
				(font
					(size 1.27 1.27)
				)
				(justify mirror)
			)
		)
		(property "Value" ""
			(at 0 0 90)
			(layer "B.Fab")
			(effects
				(font
					(size 1.27 1.27)
				)
				(justify mirror)
			)
		)
		(duplicate_pad_numbers_are_jumpers no)
		(fp_line
			(start -0.7874 0.4064)
			(end 0.7874 0.4064)
			(stroke
				(width 0.1524)
				(type default)
			)
			(layer "B.SilkS")
		)
		(fp_line
			(start 0.7874 0.4064)
			(end 0.7874 -0.4064)
			(stroke
				(width 0.1524)
				(type default)
			)
			(layer "B.SilkS")
		)
		(fp_line
			(start -0.7874 -0.4064)
			(end -0.7874 0.4064)
			(stroke
				(width 0.1524)
				(type default)
			)
			(layer "B.SilkS")
		)
		(fp_line
			(start 0.7874 -0.4064)
			(end -0.7874 -0.4064)
			(stroke
				(width 0.1524)
				(type default)
			)
			(layer "B.SilkS")
		)
		(fp_line
			(start -0.67945 0.3048)
			(end -0.120396 0.3048)
			(stroke
				(width 0.1)
				(type default)
			)
			(layer "B.Fab")
		)
		(fp_line
			(start -0.120396 0.3048)
			(end -0.120396 0.2794)
			(stroke
				(width 0.1)
				(type default)
			)
			(layer "B.Fab")
		)
		(fp_line
			(start 0.12065 0.3048)
			(end 0.67945 0.3048)
			(stroke
				(width 0.1)
				(type default)
			)
			(layer "B.Fab")
		)
		(fp_line
			(start 0.67945 0.3048)
			(end 0.67945 -0.305054)
			(stroke
				(width 0.1)
				(type default)
			)
			(layer "B.Fab")
		)
		(fp_line
			(start -0.120396 0.2794)
			(end 0.12065 0.2794)
			(stroke
				(width 0.1)
				(type default)
			)
			(layer "B.Fab")
		)
		(fp_line
			(start 0.12065 0.2794)
			(end 0.12065 0.3048)
			(stroke
				(width 0.1)
				(type default)
			)
			(layer "B.Fab")
		)
		(fp_line
			(start -0.12065 -0.2794)
			(end -0.12065 -0.3048)
			(stroke
				(width 0.1)
				(type default)
			)
			(layer "B.Fab")
		)
		(fp_line
			(start 0.12065 -0.2794)
			(end -0.12065 -0.2794)
			(stroke
				(width 0.1)
				(type default)
			)
			(layer "B.Fab")
		)
		(fp_line
			(start -0.67945 -0.3048)
			(end -0.67945 0.3048)
			(stroke
				(width 0.1)
				(type default)
			)
			(layer "B.Fab")
		)
		(fp_line
			(start -0.12065 -0.3048)
			(end -0.67945 -0.3048)
			(stroke
				(width 0.1)
				(type default)
			)
			(layer "B.Fab")
		)
		(fp_line
			(start 0.12065 -0.305054)
			(end 0.12065 -0.2794)
			(stroke
				(width 0.1)
				(type default)
			)
			(layer "B.Fab")
		)
		(fp_line
			(start 0.67945 -0.305054)
			(end 0.12065 -0.305054)
			(stroke
				(width 0.1)
				(type default)
			)
			(layer "B.Fab")
		)
		(pad "1" smd circle
			(at 0.40005 0 90)
			(size 0 0)
			(layers "B.Cu" "B.Mask" "B.Paste")
			(net "RST_PLD_CPU0_DRAM_CD_N")
		)
		(pad "2" smd circle
			(at -0.40005 0 90)
			(size 0 0)
			(layers "B.Cu" "B.Mask" "B.Paste")
			(net "RST_M_CD_CPU0_FPGA_N")
		)
	)
	(footprint ""
		(layer "B.Cu")
		(at 434.77688 -124.932948 90)
		(property "Reference" "PR4232"
			(at 0 0 90)
			(layer "B.SilkS")
			(hide yes)
			(effects
				(font
					(size 1.27 1.27)
				)
				(justify mirror)
			)
		)
		(property "Value" ""
			(at 0 0 90)
			(layer "B.Fab")
			(effects
				(font
					(size 1.27 1.27)
				)
				(justify mirror)
			)
		)
		(duplicate_pad_numbers_are_jumpers no)
		(fp_line
			(start 0.7874 -0.4064)
			(end -0.7874 -0.4064)
			(stroke
				(width 0.1524)
				(type default)
			)
			(layer "B.SilkS")
		)
		(fp_line
			(start -0.7874 -0.4064)
			(end -0.7874 0.4064)
			(stroke
				(width 0.1524)
				(type default)
			)
			(layer "B.SilkS")
		)
		(fp_line
			(start 0.7874 0.4064)
			(end 0.7874 -0.4064)
			(stroke
				(width 0.1524)
				(type default)
			)
			(layer "B.SilkS")
		)
		(fp_line
			(start -0.7874 0.4064)
			(end 0.7874 0.4064)
			(stroke
				(width 0.1524)
				(type default)
			)
			(layer "B.SilkS")
		)
		(fp_line
			(start 0.67945 -0.305054)
			(end 0.12065 -0.305054)
			(stroke
				(width 0.1)
				(type default)
			)
			(layer "B.Fab")
		)
		(fp_line
			(start 0.12065 -0.305054)
			(end 0.12065 -0.2794)
			(stroke
				(width 0.1)
				(type default)
			)
			(layer "B.Fab")
		)
		(fp_line
			(start -0.12065 -0.3048)
			(end -0.67945 -0.3048)
			(stroke
				(width 0.1)
				(type default)
			)
			(layer "B.Fab")
		)
		(fp_line
			(start -0.67945 -0.3048)
			(end -0.67945 0.3048)
			(stroke
				(width 0.1)
				(type default)
			)
			(layer "B.Fab")
		)
		(fp_line
			(start 0.12065 -0.2794)
			(end -0.12065 -0.2794)
			(stroke
				(width 0.1)
				(type default)
			)
			(layer "B.Fab")
		)
		(fp_line
			(start -0.12065 -0.2794)
			(end -0.12065 -0.3048)
			(stroke
				(width 0.1)
				(type default)
			)
			(layer "B.Fab")
		)
		(fp_line
			(start 0.12065 0.2794)
			(end 0.12065 0.3048)
			(stroke
				(width 0.1)
				(type default)
			)
			(layer "B.Fab")
		)
		(fp_line
			(start -0.120396 0.2794)
			(end 0.12065 0.2794)
			(stroke
				(width 0.1)
				(type default)
			)
			(layer "B.Fab")
		)
		(fp_line
			(start 0.67945 0.3048)
			(end 0.67945 -0.305054)
			(stroke
				(width 0.1)
				(type default)
			)
			(layer "B.Fab")
		)
		(fp_line
			(start 0.12065 0.3048)
			(end 0.67945 0.3048)
			(stroke
				(width 0.1)
				(type default)
			)
			(layer "B.Fab")
		)
		(fp_line
			(start -0.120396 0.3048)
			(end -0.120396 0.2794)
			(stroke
				(width 0.1)
				(type default)
			)
			(layer "B.Fab")
		)
		(fp_line
			(start -0.67945 0.3048)
			(end -0.120396 0.3048)
			(stroke
				(width 0.1)
				(type default)
			)
			(layer "B.Fab")
		)
		(pad "1" smd circle
			(at 0.40005 0 270)
			(size 0 0)
			(layers "B.Cu" "B.Mask" "B.Paste")
			(net "NC_PVCCD_HV_CPU0_ACSP4")
		)
		(pad "2" smd circle
			(at -0.40005 0 270)
			(size 0 0)
			(layers "B.Cu" "B.Mask" "B.Paste")
			(net "GND")
		)
	)
	(footprint ""
		(layer "B.Cu")
		(at 325.688706 -74.871072 180)
		(property "Reference" "PJ63"
			(at -1.089914 1.737106 0)
			(unlocked yes)
			(layer "B.SilkS")
			(effects
				(font
					(size 0.7874 0.5842)
					(thickness 0.1524)
				)
				(justify left mirror)
			)
		)
		(property "Value" ""
			(at 0 0 0)
			(layer "B.Fab")
			(effects
				(font
					(size 1.27 1.27)
				)
				(justify mirror)
			)
		)
		(duplicate_pad_numbers_are_jumpers no)
		(pad "1" smd circle
			(at 0.7493 0 270)
			(size 0 0)
			(layers "B.Cu" "B.Mask" "B.Paste")
			(net "SH_P1V05_PCH_AUX_N")
		)
		(pad "2" smd rect
			(at -0.7493 0 90)
			(size 0.7112 0.8128)
			(layers "B.Cu" "B.Mask" "B.Paste")
			(net "GND")
		)
		(zone
			(layer "B.Cu")
			(hatch none 0.5)
			(connect_pads
				(clearance 0)
			)
			(min_thickness 0.25)
			(keepout
				(tracks allowed)
				(vias not_allowed)
				(pads allowed)
				(copperpour not_allowed)
				(footprints allowed)
			)
			(placement
				(enabled no)
				(sheetname "")
			)
			(fill
				(thermal_gap 0.5)
				(thermal_bridge_width 0.5)
				(island_removal_mode 0)
			)
			(polygon
				(pts
					(xy 324.507606 -75.282552) (xy 324.507606 -74.464926) (xy 326.895206 -74.464926) (xy 326.895206 -75.282552)
				)
			)
		)
	)
	(footprint ""
		(layer "B.Cu")
		(at 182.546752 -192.699894 -90)
		(property "Reference" "R327"
			(at 0 0 90)
			(layer "B.SilkS")
			(hide yes)
			(effects
				(font
					(size 1.27 1.27)
				)
				(justify mirror)
			)
		)
		(property "Value" ""
			(at 0 0 90)
			(layer "B.Fab")
			(effects
				(font
					(size 1.27 1.27)
				)
				(justify mirror)
			)
		)
		(duplicate_pad_numbers_are_jumpers no)
		(fp_line
			(start -0.7874 0.4064)
			(end 0.7874 0.4064)
			(stroke
				(width 0.1524)
				(type default)
			)
			(layer "B.SilkS")
		)
		(fp_line
			(start 0.7874 0.4064)
			(end 0.7874 -0.4064)
			(stroke
				(width 0.1524)
				(type default)
			)
			(layer "B.SilkS")
		)
		(fp_line
			(start -0.7874 -0.4064)
			(end -0.7874 0.4064)
			(stroke
				(width 0.1524)
				(type default)
			)
			(layer "B.SilkS")
		)
		(fp_line
			(start 0.7874 -0.4064)
			(end -0.7874 -0.4064)
			(stroke
				(width 0.1524)
				(type default)
			)
			(layer "B.SilkS")
		)
		(fp_line
			(start -0.67945 0.3048)
			(end -0.120396 0.3048)
			(stroke
				(width 0.1)
				(type default)
			)
			(layer "B.Fab")
		)
		(fp_line
			(start -0.120396 0.3048)
			(end -0.120396 0.2794)
			(stroke
				(width 0.1)
				(type default)
			)
			(layer "B.Fab")
		)
		(fp_line
			(start 0.12065 0.3048)
			(end 0.67945 0.3048)
			(stroke
				(width 0.1)
				(type default)
			)
			(layer "B.Fab")
		)
		(fp_line
			(start 0.67945 0.3048)
			(end 0.67945 -0.305054)
			(stroke
				(width 0.1)
				(type default)
			)
			(layer "B.Fab")
		)
		(fp_line
			(start -0.120396 0.2794)
			(end 0.12065 0.2794)
			(stroke
				(width 0.1)
				(type default)
			)
			(layer "B.Fab")
		)
		(fp_line
			(start 0.12065 0.2794)
			(end 0.12065 0.3048)
			(stroke
				(width 0.1)
				(type default)
			)
			(layer "B.Fab")
		)
		(fp_line
			(start -0.12065 -0.2794)
			(end -0.12065 -0.3048)
			(stroke
				(width 0.1)
				(type default)
			)
			(layer "B.Fab")
		)
		(fp_line
			(start 0.12065 -0.2794)
			(end -0.12065 -0.2794)
			(stroke
				(width 0.1)
				(type default)
			)
			(layer "B.Fab")
		)
		(fp_line
			(start -0.67945 -0.3048)
			(end -0.67945 0.3048)
			(stroke
				(width 0.1)
				(type default)
			)
			(layer "B.Fab")
		)
		(fp_line
			(start -0.12065 -0.3048)
			(end -0.67945 -0.3048)
			(stroke
				(width 0.1)
				(type default)
			)
			(layer "B.Fab")
		)
		(fp_line
			(start 0.12065 -0.305054)
			(end 0.12065 -0.2794)
			(stroke
				(width 0.1)
				(type default)
			)
			(layer "B.Fab")
		)
		(fp_line
			(start 0.67945 -0.305054)
			(end 0.12065 -0.305054)
			(stroke
				(width 0.1)
				(type default)
			)
			(layer "B.Fab")
		)
		(pad "1" smd circle
			(at 0.40005 0 90)
			(size 0 0)
			(layers "B.Cu" "B.Mask" "B.Paste")
			(net "P3V3_AUX")
		)
		(pad "2" smd circle
			(at -0.40005 0 90)
			(size 0 0)
			(layers "B.Cu" "B.Mask" "B.Paste")
			(net "FM_S3M_CPU1_CPLD_CONFIG_N")
		)
	)
	(footprint ""
		(layer "B.Cu")
		(at 35.567366 -192.924176 -90)
		(property "Reference" "R703"
			(at 0 0 90)
			(layer "B.SilkS")
			(hide yes)
			(effects
				(font
					(size 1.27 1.27)
				)
				(justify mirror)
			)
		)
		(property "Value" ""
			(at 0 0 90)
			(layer "B.Fab")
			(effects
				(font
					(size 1.27 1.27)
				)
				(justify mirror)
			)
		)
		(duplicate_pad_numbers_are_jumpers no)
		(fp_line
			(start -0.7874 0.4064)
			(end 0.7874 0.4064)
			(stroke
				(width 0.1524)
				(type default)
			)
			(layer "B.SilkS")
		)
		(fp_line
			(start 0.7874 0.4064)
			(end 0.7874 -0.4064)
			(stroke
				(width 0.1524)
				(type default)
			)
			(layer "B.SilkS")
		)
		(fp_line
			(start -0.7874 -0.4064)
			(end -0.7874 0.4064)
			(stroke
				(width 0.1524)
				(type default)
			)
			(layer "B.SilkS")
		)
		(fp_line
			(start 0.7874 -0.4064)
			(end -0.7874 -0.4064)
			(stroke
				(width 0.1524)
				(type default)
			)
			(layer "B.SilkS")
		)
		(fp_line
			(start -0.67945 0.3048)
			(end -0.120396 0.3048)
			(stroke
				(width 0.1)
				(type default)
			)
			(layer "B.Fab")
		)
		(fp_line
			(start -0.120396 0.3048)
			(end -0.120396 0.2794)
			(stroke
				(width 0.1)
				(type default)
			)
			(layer "B.Fab")
		)
		(fp_line
			(start 0.12065 0.3048)
			(end 0.67945 0.3048)
			(stroke
				(width 0.1)
				(type default)
			)
			(layer "B.Fab")
		)
		(fp_line
			(start 0.67945 0.3048)
			(end 0.67945 -0.305054)
			(stroke
				(width 0.1)
				(type default)
			)
			(layer "B.Fab")
		)
		(fp_line
			(start -0.120396 0.2794)
			(end 0.12065 0.2794)
			(stroke
				(width 0.1)
				(type default)
			)
			(layer "B.Fab")
		)
		(fp_line
			(start 0.12065 0.2794)
			(end 0.12065 0.3048)
			(stroke
				(width 0.1)
				(type default)
			)
			(layer "B.Fab")
		)
		(fp_line
			(start -0.12065 -0.2794)
			(end -0.12065 -0.3048)
			(stroke
				(width 0.1)
				(type default)
			)
			(layer "B.Fab")
		)
		(fp_line
			(start 0.12065 -0.2794)
			(end -0.12065 -0.2794)
			(stroke
				(width 0.1)
				(type default)
			)
			(layer "B.Fab")
		)
		(fp_line
			(start -0.67945 -0.3048)
			(end -0.67945 0.3048)
			(stroke
				(width 0.1)
				(type default)
			)
			(layer "B.Fab")
		)
		(fp_line
			(start -0.12065 -0.3048)
			(end -0.67945 -0.3048)
			(stroke
				(width 0.1)
				(type default)
			)
			(layer "B.Fab")
		)
		(fp_line
			(start 0.12065 -0.305054)
			(end 0.12065 -0.2794)
			(stroke
				(width 0.1)
				(type default)
			)
			(layer "B.Fab")
		)
		(fp_line
			(start 0.67945 -0.305054)
			(end 0.12065 -0.305054)
			(stroke
				(width 0.1)
				(type default)
			)
			(layer "B.Fab")
		)
		(pad "1" smd circle
			(at 0.40005 0 90)
			(size 0 0)
			(layers "B.Cu" "B.Mask" "B.Paste")
			(net "RST_PLD_CPU1_DRAM_AB_N")
		)
		(pad "2" smd circle
			(at -0.40005 0 90)
			(size 0 0)
			(layers "B.Cu" "B.Mask" "B.Paste")
			(net "GND")
		)
	)
	(footprint ""
		(layer "B.Cu")
		(at 181.464458 -317.26505 90)
		(property "Reference" "R3901"
			(at 0 0 90)
			(layer "B.SilkS")
			(hide yes)
			(effects
				(font
					(size 1.27 1.27)
				)
				(justify mirror)
			)
		)
		(property "Value" ""
			(at 0 0 90)
			(layer "B.Fab")
			(effects
				(font
					(size 1.27 1.27)
				)
				(justify mirror)
			)
		)
		(duplicate_pad_numbers_are_jumpers no)
		(fp_line
			(start 0.7874 -0.4064)
			(end -0.7874 -0.4064)
			(stroke
				(width 0.1524)
				(type default)
			)
			(layer "B.SilkS")
		)
		(fp_line
			(start -0.7874 -0.4064)
			(end -0.7874 0.4064)
			(stroke
				(width 0.1524)
				(type default)
			)
			(layer "B.SilkS")
		)
		(fp_line
			(start 0.7874 0.4064)
			(end 0.7874 -0.4064)
			(stroke
				(width 0.1524)
				(type default)
			)
			(layer "B.SilkS")
		)
		(fp_line
			(start -0.7874 0.4064)
			(end 0.7874 0.4064)
			(stroke
				(width 0.1524)
				(type default)
			)
			(layer "B.SilkS")
		)
		(fp_line
			(start 0.67945 -0.305054)
			(end 0.12065 -0.305054)
			(stroke
				(width 0.1)
				(type default)
			)
			(layer "B.Fab")
		)
		(fp_line
			(start 0.12065 -0.305054)
			(end 0.12065 -0.2794)
			(stroke
				(width 0.1)
				(type default)
			)
			(layer "B.Fab")
		)
		(fp_line
			(start -0.12065 -0.3048)
			(end -0.67945 -0.3048)
			(stroke
				(width 0.1)
				(type default)
			)
			(layer "B.Fab")
		)
		(fp_line
			(start -0.67945 -0.3048)
			(end -0.67945 0.3048)
			(stroke
				(width 0.1)
				(type default)
			)
			(layer "B.Fab")
		)
		(fp_line
			(start 0.12065 -0.2794)
			(end -0.12065 -0.2794)
			(stroke
				(width 0.1)
				(type default)
			)
			(layer "B.Fab")
		)
		(fp_line
			(start -0.12065 -0.2794)
			(end -0.12065 -0.3048)
			(stroke
				(width 0.1)
				(type default)
			)
			(layer "B.Fab")
		)
		(fp_line
			(start 0.12065 0.2794)
			(end 0.12065 0.3048)
			(stroke
				(width 0.1)
				(type default)
			)
			(layer "B.Fab")
		)
		(fp_line
			(start -0.120396 0.2794)
			(end 0.12065 0.2794)
			(stroke
				(width 0.1)
				(type default)
			)
			(layer "B.Fab")
		)
		(fp_line
			(start 0.67945 0.3048)
			(end 0.67945 -0.305054)
			(stroke
				(width 0.1)
				(type default)
			)
			(layer "B.Fab")
		)
		(fp_line
			(start 0.12065 0.3048)
			(end 0.67945 0.3048)
			(stroke
				(width 0.1)
				(type default)
			)
			(layer "B.Fab")
		)
		(fp_line
			(start -0.120396 0.3048)
			(end -0.120396 0.2794)
			(stroke
				(width 0.1)
				(type default)
			)
			(layer "B.Fab")
		)
		(fp_line
			(start -0.67945 0.3048)
			(end -0.120396 0.3048)
			(stroke
				(width 0.1)
				(type default)
			)
			(layer "B.Fab")
		)
		(pad "1" smd circle
			(at 0.40005 0 270)
			(size 0 0)
			(layers "B.Cu" "B.Mask" "B.Paste")
			(net "I3C_SPD_DDREFGH_CPU1_LVC1_SCL_2")
		)
		(pad "2" smd circle
			(at -0.40005 0 270)
			(size 0 0)
			(layers "B.Cu" "B.Mask" "B.Paste")
			(net "I3C_SPD_DDREFGH_CPU1_LVC1_SCL")
		)
	)
	(footprint ""
		(layer "B.Cu")
		(at 85.892894 -182.06466 -90)
		(property "Reference" "R757"
			(at 0 0 90)
			(layer "B.SilkS")
			(hide yes)
			(effects
				(font
					(size 1.27 1.27)
				)
				(justify mirror)
			)
		)
		(property "Value" ""
			(at 0 0 90)
			(layer "B.Fab")
			(effects
				(font
					(size 1.27 1.27)
				)
				(justify mirror)
			)
		)
		(duplicate_pad_numbers_are_jumpers no)
		(fp_line
			(start -0.7874 0.4064)
			(end 0.7874 0.4064)
			(stroke
				(width 0.1524)
				(type default)
			)
			(layer "B.SilkS")
		)
		(fp_line
			(start 0.7874 0.4064)
			(end 0.7874 -0.4064)
			(stroke
				(width 0.1524)
				(type default)
			)
			(layer "B.SilkS")
		)
		(fp_line
			(start -0.7874 -0.4064)
			(end -0.7874 0.4064)
			(stroke
				(width 0.1524)
				(type default)
			)
			(layer "B.SilkS")
		)
		(fp_line
			(start 0.7874 -0.4064)
			(end -0.7874 -0.4064)
			(stroke
				(width 0.1524)
				(type default)
			)
			(layer "B.SilkS")
		)
		(fp_line
			(start -0.67945 0.3048)
			(end -0.120396 0.3048)
			(stroke
				(width 0.1)
				(type default)
			)
			(layer "B.Fab")
		)
		(fp_line
			(start -0.120396 0.3048)
			(end -0.120396 0.2794)
			(stroke
				(width 0.1)
				(type default)
			)
			(layer "B.Fab")
		)
		(fp_line
			(start 0.12065 0.3048)
			(end 0.67945 0.3048)
			(stroke
				(width 0.1)
				(type default)
			)
			(layer "B.Fab")
		)
		(fp_line
			(start 0.67945 0.3048)
			(end 0.67945 -0.305054)
			(stroke
				(width 0.1)
				(type default)
			)
			(layer "B.Fab")
		)
		(fp_line
			(start -0.120396 0.2794)
			(end 0.12065 0.2794)
			(stroke
				(width 0.1)
				(type default)
			)
			(layer "B.Fab")
		)
		(fp_line
			(start 0.12065 0.2794)
			(end 0.12065 0.3048)
			(stroke
				(width 0.1)
				(type default)
			)
			(layer "B.Fab")
		)
		(fp_line
			(start -0.12065 -0.2794)
			(end -0.12065 -0.3048)
			(stroke
				(width 0.1)
				(type default)
			)
			(layer "B.Fab")
		)
		(fp_line
			(start 0.12065 -0.2794)
			(end -0.12065 -0.2794)
			(stroke
				(width 0.1)
				(type default)
			)
			(layer "B.Fab")
		)
		(fp_line
			(start -0.67945 -0.3048)
			(end -0.67945 0.3048)
			(stroke
				(width 0.1)
				(type default)
			)
			(layer "B.Fab")
		)
		(fp_line
			(start -0.12065 -0.3048)
			(end -0.67945 -0.3048)
			(stroke
				(width 0.1)
				(type default)
			)
			(layer "B.Fab")
		)
		(fp_line
			(start 0.12065 -0.305054)
			(end 0.12065 -0.2794)
			(stroke
				(width 0.1)
				(type default)
			)
			(layer "B.Fab")
		)
		(fp_line
			(start 0.67945 -0.305054)
			(end 0.12065 -0.305054)
			(stroke
				(width 0.1)
				(type default)
			)
			(layer "B.Fab")
		)
		(pad "1" smd circle
			(at 0.40005 0 90)
			(size 0 0)
			(layers "B.Cu" "B.Mask" "B.Paste")
			(net "PVNN_TERM_CPU0")
		)
		(pad "2" smd circle
			(at -0.40005 0 90)
			(size 0 0)
			(layers "B.Cu" "B.Mask" "B.Paste")
			(net "JTAG_DBP_CPU_QS_GTL_TMS")
		)
	)
	(footprint ""
		(layer "B.Cu")
		(at 193.71818 -423.669206 90)
		(property "Reference" "R4705"
			(at 0 0 90)
			(layer "B.SilkS")
			(hide yes)
			(effects
				(font
					(size 1.27 1.27)
				)
				(justify mirror)
			)
		)
		(property "Value" ""
			(at 0 0 90)
			(layer "B.Fab")
			(effects
				(font
					(size 1.27 1.27)
				)
				(justify mirror)
			)
		)
		(duplicate_pad_numbers_are_jumpers no)
		(fp_line
			(start 0.7874 -0.4064)
			(end -0.7874 -0.4064)
			(stroke
				(width 0.1524)
				(type default)
			)
			(layer "B.SilkS")
		)
		(fp_line
			(start -0.7874 -0.4064)
			(end -0.7874 0.4064)
			(stroke
				(width 0.1524)
				(type default)
			)
			(layer "B.SilkS")
		)
		(fp_line
			(start 0.7874 0.4064)
			(end 0.7874 -0.4064)
			(stroke
				(width 0.1524)
				(type default)
			)
			(layer "B.SilkS")
		)
		(fp_line
			(start -0.7874 0.4064)
			(end 0.7874 0.4064)
			(stroke
				(width 0.1524)
				(type default)
			)
			(layer "B.SilkS")
		)
		(fp_line
			(start 0.67945 -0.305054)
			(end 0.12065 -0.305054)
			(stroke
				(width 0.1)
				(type default)
			)
			(layer "B.Fab")
		)
		(fp_line
			(start 0.12065 -0.305054)
			(end 0.12065 -0.2794)
			(stroke
				(width 0.1)
				(type default)
			)
			(layer "B.Fab")
		)
		(fp_line
			(start -0.12065 -0.3048)
			(end -0.67945 -0.3048)
			(stroke
				(width 0.1)
				(type default)
			)
			(layer "B.Fab")
		)
		(fp_line
			(start -0.67945 -0.3048)
			(end -0.67945 0.3048)
			(stroke
				(width 0.1)
				(type default)
			)
			(layer "B.Fab")
		)
		(fp_line
			(start 0.12065 -0.2794)
			(end -0.12065 -0.2794)
			(stroke
				(width 0.1)
				(type default)
			)
			(layer "B.Fab")
		)
		(fp_line
			(start -0.12065 -0.2794)
			(end -0.12065 -0.3048)
			(stroke
				(width 0.1)
				(type default)
			)
			(layer "B.Fab")
		)
		(fp_line
			(start 0.12065 0.2794)
			(end 0.12065 0.3048)
			(stroke
				(width 0.1)
				(type default)
			)
			(layer "B.Fab")
		)
		(fp_line
			(start -0.120396 0.2794)
			(end 0.12065 0.2794)
			(stroke
				(width 0.1)
				(type default)
			)
			(layer "B.Fab")
		)
		(fp_line
			(start 0.67945 0.3048)
			(end 0.67945 -0.305054)
			(stroke
				(width 0.1)
				(type default)
			)
			(layer "B.Fab")
		)
		(fp_line
			(start 0.12065 0.3048)
			(end 0.67945 0.3048)
			(stroke
				(width 0.1)
				(type default)
			)
			(layer "B.Fab")
		)
		(fp_line
			(start -0.120396 0.3048)
			(end -0.120396 0.2794)
			(stroke
				(width 0.1)
				(type default)
			)
			(layer "B.Fab")
		)
		(fp_line
			(start -0.67945 0.3048)
			(end -0.120396 0.3048)
			(stroke
				(width 0.1)
				(type default)
			)
			(layer "B.Fab")
		)
		(pad "1" smd circle
			(at 0.40005 0 270)
			(size 0 0)
			(layers "B.Cu" "B.Mask" "B.Paste")
			(net "LED_P12V_PSU_R2")
		)
		(pad "2" smd circle
			(at -0.40005 0 270)
			(size 0 0)
			(layers "B.Cu" "B.Mask" "B.Paste")
			(net "LED_P12V_PSU_R3")
		)
	)
	(footprint ""
		(layer "B.Cu")
		(at 39.526972 -129.81813 180)
		(property "Reference" "R2345"
			(at 0 0 0)
			(layer "B.SilkS")
			(hide yes)
			(effects
				(font
					(size 1.27 1.27)
				)
				(justify mirror)
			)
		)
		(property "Value" ""
			(at 0 0 0)
			(layer "B.Fab")
			(effects
				(font
					(size 1.27 1.27)
				)
				(justify mirror)
			)
		)
		(duplicate_pad_numbers_are_jumpers no)
		(fp_line
			(start 0.7874 0.4064)
			(end 0.7874 -0.4064)
			(stroke
				(width 0.1524)
				(type default)
			)
			(layer "B.SilkS")
		)
		(fp_line
			(start 0.7874 -0.4064)
			(end -0.7874 -0.4064)
			(stroke
				(width 0.1524)
				(type default)
			)
			(layer "B.SilkS")
		)
		(fp_line
			(start -0.7874 0.4064)
			(end 0.7874 0.4064)
			(stroke
				(width 0.1524)
				(type default)
			)
			(layer "B.SilkS")
		)
		(fp_line
			(start -0.7874 -0.4064)
			(end -0.7874 0.4064)
			(stroke
				(width 0.1524)
				(type default)
			)
			(layer "B.SilkS")
		)
		(fp_line
			(start 0.67945 0.3048)
			(end 0.67945 -0.305054)
			(stroke
				(width 0.1)
				(type default)
			)
			(layer "B.Fab")
		)
		(fp_line
			(start 0.67945 -0.305054)
			(end 0.12065 -0.305054)
			(stroke
				(width 0.1)
				(type default)
			)
			(layer "B.Fab")
		)
		(fp_line
			(start 0.12065 0.3048)
			(end 0.67945 0.3048)
			(stroke
				(width 0.1)
				(type default)
			)
			(layer "B.Fab")
		)
		(fp_line
			(start 0.12065 0.2794)
			(end 0.12065 0.3048)
			(stroke
				(width 0.1)
				(type default)
			)
			(layer "B.Fab")
		)
		(fp_line
			(start 0.12065 -0.2794)
			(end -0.12065 -0.2794)
			(stroke
				(width 0.1)
				(type default)
			)
			(layer "B.Fab")
		)
		(fp_line
			(start 0.12065 -0.305054)
			(end 0.12065 -0.2794)
			(stroke
				(width 0.1)
				(type default)
			)
			(layer "B.Fab")
		)
		(fp_line
			(start -0.120396 0.3048)
			(end -0.120396 0.2794)
			(stroke
				(width 0.1)
				(type default)
			)
			(layer "B.Fab")
		)
		(fp_line
			(start -0.120396 0.2794)
			(end 0.12065 0.2794)
			(stroke
				(width 0.1)
				(type default)
			)
			(layer "B.Fab")
		)
		(fp_line
			(start -0.12065 -0.2794)
			(end -0.12065 -0.3048)
			(stroke
				(width 0.1)
				(type default)
			)
			(layer "B.Fab")
		)
		(fp_line
			(start -0.12065 -0.3048)
			(end -0.67945 -0.3048)
			(stroke
				(width 0.1)
				(type default)
			)
			(layer "B.Fab")
		)
		(fp_line
			(start -0.67945 0.3048)
			(end -0.120396 0.3048)
			(stroke
				(width 0.1)
				(type default)
			)
			(layer "B.Fab")
		)
		(fp_line
			(start -0.67945 -0.3048)
			(end -0.67945 0.3048)
			(stroke
				(width 0.1)
				(type default)
			)
			(layer "B.Fab")
		)
		(pad "1" smd circle
			(at 0.40005 0)
			(size 0 0)
			(layers "B.Cu" "B.Mask" "B.Paste")
			(net "PVNN_TERM_CPU1")
		)
		(pad "2" smd circle
			(at -0.40005 0)
			(size 0 0)
			(layers "B.Cu" "B.Mask" "B.Paste")
			(net "SVID_CLK0_CPU1_R")
		)
	)
	(footprint ""
		(layer "B.Cu")
		(at 330.280518 -187.67933 90)
		(property "Reference" "R183"
			(at 0 0 90)
			(layer "B.SilkS")
			(hide yes)
			(effects
				(font
					(size 1.27 1.27)
				)
				(justify mirror)
			)
		)
		(property "Value" ""
			(at 0 0 90)
			(layer "B.Fab")
			(effects
				(font
					(size 1.27 1.27)
				)
				(justify mirror)
			)
		)
		(duplicate_pad_numbers_are_jumpers no)
		(fp_line
			(start 0.7874 -0.4064)
			(end -0.7874 -0.4064)
			(stroke
				(width 0.1524)
				(type default)
			)
			(layer "B.SilkS")
		)
		(fp_line
			(start -0.7874 -0.4064)
			(end -0.7874 0.4064)
			(stroke
				(width 0.1524)
				(type default)
			)
			(layer "B.SilkS")
		)
		(fp_line
			(start 0.7874 0.4064)
			(end 0.7874 -0.4064)
			(stroke
				(width 0.1524)
				(type default)
			)
			(layer "B.SilkS")
		)
		(fp_line
			(start -0.7874 0.4064)
			(end 0.7874 0.4064)
			(stroke
				(width 0.1524)
				(type default)
			)
			(layer "B.SilkS")
		)
		(fp_line
			(start 0.67945 -0.305054)
			(end 0.12065 -0.305054)
			(stroke
				(width 0.1)
				(type default)
			)
			(layer "B.Fab")
		)
		(fp_line
			(start 0.12065 -0.305054)
			(end 0.12065 -0.2794)
			(stroke
				(width 0.1)
				(type default)
			)
			(layer "B.Fab")
		)
		(fp_line
			(start -0.12065 -0.3048)
			(end -0.67945 -0.3048)
			(stroke
				(width 0.1)
				(type default)
			)
			(layer "B.Fab")
		)
		(fp_line
			(start -0.67945 -0.3048)
			(end -0.67945 0.3048)
			(stroke
				(width 0.1)
				(type default)
			)
			(layer "B.Fab")
		)
		(fp_line
			(start 0.12065 -0.2794)
			(end -0.12065 -0.2794)
			(stroke
				(width 0.1)
				(type default)
			)
			(layer "B.Fab")
		)
		(fp_line
			(start -0.12065 -0.2794)
			(end -0.12065 -0.3048)
			(stroke
				(width 0.1)
				(type default)
			)
			(layer "B.Fab")
		)
		(fp_line
			(start 0.12065 0.2794)
			(end 0.12065 0.3048)
			(stroke
				(width 0.1)
				(type default)
			)
			(layer "B.Fab")
		)
		(fp_line
			(start -0.120396 0.2794)
			(end 0.12065 0.2794)
			(stroke
				(width 0.1)
				(type default)
			)
			(layer "B.Fab")
		)
		(fp_line
			(start 0.67945 0.3048)
			(end 0.67945 -0.305054)
			(stroke
				(width 0.1)
				(type default)
			)
			(layer "B.Fab")
		)
		(fp_line
			(start 0.12065 0.3048)
			(end 0.67945 0.3048)
			(stroke
				(width 0.1)
				(type default)
			)
			(layer "B.Fab")
		)
		(fp_line
			(start -0.120396 0.3048)
			(end -0.120396 0.2794)
			(stroke
				(width 0.1)
				(type default)
			)
			(layer "B.Fab")
		)
		(fp_line
			(start -0.67945 0.3048)
			(end -0.120396 0.3048)
			(stroke
				(width 0.1)
				(type default)
			)
			(layer "B.Fab")
		)
		(pad "1" smd circle
			(at 0.40005 0 270)
			(size 0 0)
			(layers "B.Cu" "B.Mask" "B.Paste")
			(net "PWRGD_CPU0_BUF_R")
		)
		(pad "2" smd circle
			(at -0.40005 0 270)
			(size 0 0)
			(layers "B.Cu" "B.Mask" "B.Paste")
			(net "PVNN_TERM_CPU0")
		)
	)
	(footprint ""
		(layer "B.Cu")
		(at 112.9284 -411.716728 -90)
		(property "Reference" "C2334"
			(at 0 0 90)
			(layer "B.SilkS")
			(hide yes)
			(effects
				(font
					(size 1.27 1.27)
				)
				(justify mirror)
			)
		)
		(property "Value" ""
			(at 0 0 90)
			(layer "B.Fab")
			(effects
				(font
					(size 1.27 1.27)
				)
				(justify mirror)
			)
		)
		(duplicate_pad_numbers_are_jumpers no)
		(fp_line
			(start -0.7874 0.4064)
			(end 0.7874 0.4064)
			(stroke
				(width 0.1524)
				(type default)
			)
			(layer "B.SilkS")
		)
		(fp_line
			(start 0.7874 0.4064)
			(end 0.7874 -0.4064)
			(stroke
				(width 0.1524)
				(type default)
			)
			(layer "B.SilkS")
		)
		(fp_line
			(start -0.7874 -0.4064)
			(end -0.7874 0.4064)
			(stroke
				(width 0.1524)
				(type default)
			)
			(layer "B.SilkS")
		)
		(fp_line
			(start 0.7874 -0.4064)
			(end -0.7874 -0.4064)
			(stroke
				(width 0.1524)
				(type default)
			)
			(layer "B.SilkS")
		)
		(fp_line
			(start -0.67945 0.3048)
			(end -0.120396 0.3048)
			(stroke
				(width 0.1)
				(type default)
			)
			(layer "B.Fab")
		)
		(fp_line
			(start -0.120396 0.3048)
			(end -0.120396 0.2794)
			(stroke
				(width 0.1)
				(type default)
			)
			(layer "B.Fab")
		)
		(fp_line
			(start 0.12065 0.3048)
			(end 0.67945 0.3048)
			(stroke
				(width 0.1)
				(type default)
			)
			(layer "B.Fab")
		)
		(fp_line
			(start 0.67945 0.3048)
			(end 0.67945 -0.305054)
			(stroke
				(width 0.1)
				(type default)
			)
			(layer "B.Fab")
		)
		(fp_line
			(start -0.120396 0.2794)
			(end 0.12065 0.2794)
			(stroke
				(width 0.1)
				(type default)
			)
			(layer "B.Fab")
		)
		(fp_line
			(start 0.12065 0.2794)
			(end 0.12065 0.3048)
			(stroke
				(width 0.1)
				(type default)
			)
			(layer "B.Fab")
		)
		(fp_line
			(start -0.12065 -0.2794)
			(end -0.12065 -0.3048)
			(stroke
				(width 0.1)
				(type default)
			)
			(layer "B.Fab")
		)
		(fp_line
			(start 0.12065 -0.2794)
			(end -0.12065 -0.2794)
			(stroke
				(width 0.1)
				(type default)
			)
			(layer "B.Fab")
		)
		(fp_line
			(start -0.67945 -0.3048)
			(end -0.67945 0.3048)
			(stroke
				(width 0.1)
				(type default)
			)
			(layer "B.Fab")
		)
		(fp_line
			(start -0.12065 -0.3048)
			(end -0.67945 -0.3048)
			(stroke
				(width 0.1)
				(type default)
			)
			(layer "B.Fab")
		)
		(fp_line
			(start 0.12065 -0.305054)
			(end 0.12065 -0.2794)
			(stroke
				(width 0.1)
				(type default)
			)
			(layer "B.Fab")
		)
		(fp_line
			(start 0.67945 -0.305054)
			(end 0.12065 -0.305054)
			(stroke
				(width 0.1)
				(type default)
			)
			(layer "B.Fab")
		)
		(pad "1" smd circle
			(at 0.40005 0 90)
			(size 0 0)
			(layers "B.Cu" "B.Mask" "B.Paste")
			(net "P3V3_9ZXL045_VDDA")
		)
		(pad "2" smd circle
			(at -0.40005 0 90)
			(size 0 0)
			(layers "B.Cu" "B.Mask" "B.Paste")
			(net "GND")
		)
	)
	(footprint ""
		(layer "B.Cu")
		(at 103.901494 -248.49836 -90)
		(property "Reference" "C451"
			(at 0 0 90)
			(layer "B.SilkS")
			(hide yes)
			(effects
				(font
					(size 1.27 1.27)
				)
				(justify mirror)
			)
		)
		(property "Value" ""
			(at 0 0 90)
			(layer "B.Fab")
			(effects
				(font
					(size 1.27 1.27)
				)
				(justify mirror)
			)
		)
		(duplicate_pad_numbers_are_jumpers no)
		(fp_line
			(start -1.524 0.762)
			(end 1.524 0.762)
			(stroke
				(width 0.1524)
				(type default)
			)
			(layer "B.SilkS")
		)
		(fp_line
			(start 1.524 0.762)
			(end 1.524 -0.762)
			(stroke
				(width 0.1524)
				(type default)
			)
			(layer "B.SilkS")
		)
		(fp_line
			(start -1.524 -0.762)
			(end -1.524 0.762)
			(stroke
				(width 0.1524)
				(type default)
			)
			(layer "B.SilkS")
		)
		(fp_line
			(start 1.524 -0.762)
			(end -1.524 -0.762)
			(stroke
				(width 0.1524)
				(type default)
			)
			(layer "B.SilkS")
		)
		(fp_line
			(start -1.1049 0.724916)
			(end -1.1049 -0.724916)
			(stroke
				(width 0.1)
				(type default)
			)
			(layer "B.Fab")
		)
		(fp_line
			(start 1.1049 0.724916)
			(end -1.1049 0.724916)
			(stroke
				(width 0.1)
				(type default)
			)
			(layer "B.Fab")
		)
		(fp_line
			(start -1.1049 -0.724916)
			(end 1.1049 -0.724916)
			(stroke
				(width 0.1)
				(type default)
			)
			(layer "B.Fab")
		)
		(fp_line
			(start 1.1049 -0.724916)
			(end 1.1049 0.724916)
			(stroke
				(width 0.1)
				(type default)
			)
			(layer "B.Fab")
		)
		(pad "1" smd rect
			(at 0.889 0 270)
			(size 1.016 1.27)
			(layers "B.Cu" "B.Mask" "B.Paste")
			(net "PVCCD_HV_CPU1")
		)
		(pad "2" smd rect
			(at -0.889 0 270)
			(size 1.016 1.27)
			(layers "B.Cu" "B.Mask" "B.Paste")
			(net "GND")
		)
	)
	(footprint ""
		(layer "B.Cu")
		(at 346.4687 -64.088264 90)
		(property "Reference" "C159"
			(at 0 0 90)
			(layer "B.SilkS")
			(hide yes)
			(effects
				(font
					(size 1.27 1.27)
				)
				(justify mirror)
			)
		)
		(property "Value" ""
			(at 0 0 90)
			(layer "B.Fab")
			(effects
				(font
					(size 1.27 1.27)
				)
				(justify mirror)
			)
		)
		(duplicate_pad_numbers_are_jumpers no)
		(fp_line
			(start 0.299974 -0.150114)
			(end -0.299974 -0.150114)
			(stroke
				(width 0.1)
				(type default)
			)
			(layer "B.Fab")
		)
		(fp_line
			(start -0.299974 -0.150114)
			(end -0.299974 0.150114)
			(stroke
				(width 0.1)
				(type default)
			)
			(layer "B.Fab")
		)
		(fp_line
			(start 0.299974 0.150114)
			(end 0.299974 -0.150114)
			(stroke
				(width 0.1)
				(type default)
			)
			(layer "B.Fab")
		)
		(fp_line
			(start -0.299974 0.150114)
			(end 0.299974 0.150114)
			(stroke
				(width 0.1)
				(type default)
			)
			(layer "B.Fab")
		)
		(pad "1" smd rect
			(at 0.2667 0 270)
			(size 0.3048 0.381)
			(layers "B.Cu" "B.Mask" "B.Paste")
			(net "DMI_CPU0_PCH_RX_C_DN<5>")
		)
		(pad "2" smd rect
			(at -0.2667 0 270)
			(size 0.3048 0.381)
			(layers "B.Cu" "B.Mask" "B.Paste")
			(net "DMI_CPU0_PCH_RX_DN<5>")
		)
	)
	(footprint ""
		(layer "B.Cu")
		(at 366.310418 -294.009826)
		(property "Reference" "C380"
			(at 0 0 0)
			(layer "B.SilkS")
			(hide yes)
			(effects
				(font
					(size 1.27 1.27)
				)
				(justify mirror)
			)
		)
		(property "Value" ""
			(at 0 0 0)
			(layer "B.Fab")
			(effects
				(font
					(size 1.27 1.27)
				)
				(justify mirror)
			)
		)
		(duplicate_pad_numbers_are_jumpers no)
		(fp_line
			(start -1.524 -0.762)
			(end -1.524 0.762)
			(stroke
				(width 0.1524)
				(type default)
			)
			(layer "B.SilkS")
		)
		(fp_line
			(start -1.524 0.762)
			(end 1.524 0.762)
			(stroke
				(width 0.1524)
				(type default)
			)
			(layer "B.SilkS")
		)
		(fp_line
			(start 1.524 -0.762)
			(end -1.524 -0.762)
			(stroke
				(width 0.1524)
				(type default)
			)
			(layer "B.SilkS")
		)
		(fp_line
			(start 1.524 0.762)
			(end 1.524 -0.762)
			(stroke
				(width 0.1524)
				(type default)
			)
			(layer "B.SilkS")
		)
		(fp_line
			(start -1.1049 -0.724916)
			(end 1.1049 -0.724916)
			(stroke
				(width 0.1)
				(type default)
			)
			(layer "B.Fab")
		)
		(fp_line
			(start -1.1049 0.724916)
			(end -1.1049 -0.724916)
			(stroke
				(width 0.1)
				(type default)
			)
			(layer "B.Fab")
		)
		(fp_line
			(start 1.1049 -0.724916)
			(end 1.1049 0.724916)
			(stroke
				(width 0.1)
				(type default)
			)
			(layer "B.Fab")
		)
		(fp_line
			(start 1.1049 0.724916)
			(end -1.1049 0.724916)
			(stroke
				(width 0.1)
				(type default)
			)
			(layer "B.Fab")
		)
		(pad "1" smd rect
			(at 0.889 0)
			(size 1.016 1.27)
			(layers "B.Cu" "B.Mask" "B.Paste")
			(net "PVCCIN_CPU0")
		)
		(pad "2" smd rect
			(at -0.889 0)
			(size 1.016 1.27)
			(layers "B.Cu" "B.Mask" "B.Paste")
			(net "GND")
		)
	)
	(footprint ""
		(layer "B.Cu")
		(at 356.354888 -333.639922 90)
		(property "Reference" "PC304_P0_2"
			(at 0 0 90)
			(layer "B.SilkS")
			(hide yes)
			(effects
				(font
					(size 1.27 1.27)
				)
				(justify mirror)
			)
		)
		(property "Value" ""
			(at 0 0 90)
			(layer "B.Fab")
			(effects
				(font
					(size 1.27 1.27)
				)
				(justify mirror)
			)
		)
		(duplicate_pad_numbers_are_jumpers no)
		(fp_line
			(start 1.524 -0.762)
			(end -1.524 -0.762)
			(stroke
				(width 0.1524)
				(type default)
			)
			(layer "B.SilkS")
		)
		(fp_line
			(start -1.524 -0.762)
			(end -1.524 0.762)
			(stroke
				(width 0.1524)
				(type default)
			)
			(layer "B.SilkS")
		)
		(fp_line
			(start 1.524 0.762)
			(end 1.524 -0.762)
			(stroke
				(width 0.1524)
				(type default)
			)
			(layer "B.SilkS")
		)
		(fp_line
			(start -1.524 0.762)
			(end 1.524 0.762)
			(stroke
				(width 0.1524)
				(type default)
			)
			(layer "B.SilkS")
		)
		(fp_line
			(start 1.1049 -0.724916)
			(end 1.1049 0.724916)
			(stroke
				(width 0.1)
				(type default)
			)
			(layer "B.Fab")
		)
		(fp_line
			(start -1.1049 -0.724916)
			(end 1.1049 -0.724916)
			(stroke
				(width 0.1)
				(type default)
			)
			(layer "B.Fab")
		)
		(fp_line
			(start 1.1049 0.724916)
			(end -1.1049 0.724916)
			(stroke
				(width 0.1)
				(type default)
			)
			(layer "B.Fab")
		)
		(fp_line
			(start -1.1049 0.724916)
			(end -1.1049 -0.724916)
			(stroke
				(width 0.1)
				(type default)
			)
			(layer "B.Fab")
		)
		(pad "1" smd rect
			(at 0.889 0 90)
			(size 1.016 1.27)
			(layers "B.Cu" "B.Mask" "B.Paste")
			(net "SW_P12V_PVCCIN_CPU0_FLT")
		)
		(pad "2" smd rect
			(at -0.889 0 90)
			(size 1.016 1.27)
			(layers "B.Cu" "B.Mask" "B.Paste")
			(net "GND")
		)
	)
	(footprint ""
		(layer "B.Cu")
		(at 292.231572 -354.163376 -90)
		(property "Reference" "PC1186_P0_4"
			(at 0 0 90)
			(layer "B.SilkS")
			(hide yes)
			(effects
				(font
					(size 1.27 1.27)
				)
				(justify mirror)
			)
		)
		(property "Value" ""
			(at 0 0 90)
			(layer "B.Fab")
			(effects
				(font
					(size 1.27 1.27)
				)
				(justify mirror)
			)
		)
		(duplicate_pad_numbers_are_jumpers no)
		(fp_line
			(start -1.524 0.762)
			(end 1.524 0.762)
			(stroke
				(width 0.1524)
				(type default)
			)
			(layer "B.SilkS")
		)
		(fp_line
			(start 1.524 0.762)
			(end 1.524 -0.762)
			(stroke
				(width 0.1524)
				(type default)
			)
			(layer "B.SilkS")
		)
		(fp_line
			(start -1.524 -0.762)
			(end -1.524 0.762)
			(stroke
				(width 0.1524)
				(type default)
			)
			(layer "B.SilkS")
		)
		(fp_line
			(start 1.524 -0.762)
			(end -1.524 -0.762)
			(stroke
				(width 0.1524)
				(type default)
			)
			(layer "B.SilkS")
		)
		(fp_line
			(start -1.1049 0.724916)
			(end -1.1049 -0.724916)
			(stroke
				(width 0.1)
				(type default)
			)
			(layer "B.Fab")
		)
		(fp_line
			(start 1.1049 0.724916)
			(end -1.1049 0.724916)
			(stroke
				(width 0.1)
				(type default)
			)
			(layer "B.Fab")
		)
		(fp_line
			(start -1.1049 -0.724916)
			(end 1.1049 -0.724916)
			(stroke
				(width 0.1)
				(type default)
			)
			(layer "B.Fab")
		)
		(fp_line
			(start 1.1049 -0.724916)
			(end 1.1049 0.724916)
			(stroke
				(width 0.1)
				(type default)
			)
			(layer "B.Fab")
		)
		(pad "1" smd rect
			(at 0.889 0 270)
			(size 1.016 1.27)
			(layers "B.Cu" "B.Mask" "B.Paste")
			(net "PVCCFA_EHV_FIVRA_CPU0")
		)
		(pad "2" smd rect
			(at -0.889 0 270)
			(size 1.016 1.27)
			(layers "B.Cu" "B.Mask" "B.Paste")
			(net "GND")
		)
	)
	(footprint ""
		(layer "B.Cu")
		(at 71.385684 -185.791856 90)
		(property "Reference" "R560"
			(at 0 0 90)
			(layer "B.SilkS")
			(hide yes)
			(effects
				(font
					(size 1.27 1.27)
				)
				(justify mirror)
			)
		)
		(property "Value" ""
			(at 0 0 90)
			(layer "B.Fab")
			(effects
				(font
					(size 1.27 1.27)
				)
				(justify mirror)
			)
		)
		(duplicate_pad_numbers_are_jumpers no)
		(fp_line
			(start 0.7874 -0.4064)
			(end -0.7874 -0.4064)
			(stroke
				(width 0.1524)
				(type default)
			)
			(layer "B.SilkS")
		)
		(fp_line
			(start -0.7874 -0.4064)
			(end -0.7874 0.4064)
			(stroke
				(width 0.1524)
				(type default)
			)
			(layer "B.SilkS")
		)
		(fp_line
			(start 0.7874 0.4064)
			(end 0.7874 -0.4064)
			(stroke
				(width 0.1524)
				(type default)
			)
			(layer "B.SilkS")
		)
		(fp_line
			(start -0.7874 0.4064)
			(end 0.7874 0.4064)
			(stroke
				(width 0.1524)
				(type default)
			)
			(layer "B.SilkS")
		)
		(fp_line
			(start 0.67945 -0.305054)
			(end 0.12065 -0.305054)
			(stroke
				(width 0.1)
				(type default)
			)
			(layer "B.Fab")
		)
		(fp_line
			(start 0.12065 -0.305054)
			(end 0.12065 -0.2794)
			(stroke
				(width 0.1)
				(type default)
			)
			(layer "B.Fab")
		)
		(fp_line
			(start -0.12065 -0.3048)
			(end -0.67945 -0.3048)
			(stroke
				(width 0.1)
				(type default)
			)
			(layer "B.Fab")
		)
		(fp_line
			(start -0.67945 -0.3048)
			(end -0.67945 0.3048)
			(stroke
				(width 0.1)
				(type default)
			)
			(layer "B.Fab")
		)
		(fp_line
			(start 0.12065 -0.2794)
			(end -0.12065 -0.2794)
			(stroke
				(width 0.1)
				(type default)
			)
			(layer "B.Fab")
		)
		(fp_line
			(start -0.12065 -0.2794)
			(end -0.12065 -0.3048)
			(stroke
				(width 0.1)
				(type default)
			)
			(layer "B.Fab")
		)
		(fp_line
			(start 0.12065 0.2794)
			(end 0.12065 0.3048)
			(stroke
				(width 0.1)
				(type default)
			)
			(layer "B.Fab")
		)
		(fp_line
			(start -0.120396 0.2794)
			(end 0.12065 0.2794)
			(stroke
				(width 0.1)
				(type default)
			)
			(layer "B.Fab")
		)
		(fp_line
			(start 0.67945 0.3048)
			(end 0.67945 -0.305054)
			(stroke
				(width 0.1)
				(type default)
			)
			(layer "B.Fab")
		)
		(fp_line
			(start 0.12065 0.3048)
			(end 0.67945 0.3048)
			(stroke
				(width 0.1)
				(type default)
			)
			(layer "B.Fab")
		)
		(fp_line
			(start -0.120396 0.3048)
			(end -0.120396 0.2794)
			(stroke
				(width 0.1)
				(type default)
			)
			(layer "B.Fab")
		)
		(fp_line
			(start -0.67945 0.3048)
			(end -0.120396 0.3048)
			(stroke
				(width 0.1)
				(type default)
			)
			(layer "B.Fab")
		)
		(pad "1" smd circle
			(at 0.40005 0 270)
			(size 0 0)
			(layers "B.Cu" "B.Mask" "B.Paste")
			(net "SVID_ALERT1_CPU1_R_N")
		)
		(pad "2" smd circle
			(at -0.40005 0 270)
			(size 0 0)
			(layers "B.Cu" "B.Mask" "B.Paste")
			(net "PVNN_TERM_CPU1")
		)
	)
	(footprint ""
		(layer "B.Cu")
		(at 17.596358 -318.666622)
		(property "Reference" "R80"
			(at 0 0 0)
			(layer "B.SilkS")
			(hide yes)
			(effects
				(font
					(size 1.27 1.27)
				)
				(justify mirror)
			)
		)
		(property "Value" ""
			(at 0 0 0)
			(layer "B.Fab")
			(effects
				(font
					(size 1.27 1.27)
				)
				(justify mirror)
			)
		)
		(duplicate_pad_numbers_are_jumpers no)
		(fp_line
			(start -0.7874 -0.4064)
			(end -0.7874 0.4064)
			(stroke
				(width 0.1524)
				(type default)
			)
			(layer "B.SilkS")
		)
		(fp_line
			(start -0.7874 0.4064)
			(end 0.7874 0.4064)
			(stroke
				(width 0.1524)
				(type default)
			)
			(layer "B.SilkS")
		)
		(fp_line
			(start 0.7874 -0.4064)
			(end -0.7874 -0.4064)
			(stroke
				(width 0.1524)
				(type default)
			)
			(layer "B.SilkS")
		)
		(fp_line
			(start 0.7874 0.4064)
			(end 0.7874 -0.4064)
			(stroke
				(width 0.1524)
				(type default)
			)
			(layer "B.SilkS")
		)
		(fp_line
			(start -0.67945 -0.3048)
			(end -0.67945 0.3048)
			(stroke
				(width 0.1)
				(type default)
			)
			(layer "B.Fab")
		)
		(fp_line
			(start -0.67945 0.3048)
			(end -0.120396 0.3048)
			(stroke
				(width 0.1)
				(type default)
			)
			(layer "B.Fab")
		)
		(fp_line
			(start -0.12065 -0.3048)
			(end -0.67945 -0.3048)
			(stroke
				(width 0.1)
				(type default)
			)
			(layer "B.Fab")
		)
		(fp_line
			(start -0.12065 -0.2794)
			(end -0.12065 -0.3048)
			(stroke
				(width 0.1)
				(type default)
			)
			(layer "B.Fab")
		)
		(fp_line
			(start -0.120396 0.2794)
			(end 0.12065 0.2794)
			(stroke
				(width 0.1)
				(type default)
			)
			(layer "B.Fab")
		)
		(fp_line
			(start -0.120396 0.3048)
			(end -0.120396 0.2794)
			(stroke
				(width 0.1)
				(type default)
			)
			(layer "B.Fab")
		)
		(fp_line
			(start 0.12065 -0.305054)
			(end 0.12065 -0.2794)
			(stroke
				(width 0.1)
				(type default)
			)
			(layer "B.Fab")
		)
		(fp_line
			(start 0.12065 -0.2794)
			(end -0.12065 -0.2794)
			(stroke
				(width 0.1)
				(type default)
			)
			(layer "B.Fab")
		)
		(fp_line
			(start 0.12065 0.2794)
			(end 0.12065 0.3048)
			(stroke
				(width 0.1)
				(type default)
			)
			(layer "B.Fab")
		)
		(fp_line
			(start 0.12065 0.3048)
			(end 0.67945 0.3048)
			(stroke
				(width 0.1)
				(type default)
			)
			(layer "B.Fab")
		)
		(fp_line
			(start 0.67945 -0.305054)
			(end 0.12065 -0.305054)
			(stroke
				(width 0.1)
				(type default)
			)
			(layer "B.Fab")
		)
		(fp_line
			(start 0.67945 0.3048)
			(end 0.67945 -0.305054)
			(stroke
				(width 0.1)
				(type default)
			)
			(layer "B.Fab")
		)
		(pad "1" smd circle
			(at 0.40005 0 180)
			(size 0 0)
			(layers "B.Cu" "B.Mask" "B.Paste")
			(net "PD_CHD_CPU1_DIMM2_SAA")
		)
		(pad "2" smd circle
			(at -0.40005 0 180)
			(size 0 0)
			(layers "B.Cu" "B.Mask" "B.Paste")
			(net "GND")
		)
	)
	(footprint ""
		(layer "B.Cu")
		(at 170.555666 -109.775498)
		(property "Reference" "C1901"
			(at 0 0 0)
			(layer "B.SilkS")
			(hide yes)
			(effects
				(font
					(size 1.27 1.27)
				)
				(justify mirror)
			)
		)
		(property "Value" ""
			(at 0 0 0)
			(layer "B.Fab")
			(effects
				(font
					(size 1.27 1.27)
				)
				(justify mirror)
			)
		)
		(duplicate_pad_numbers_are_jumpers no)
		(fp_line
			(start -0.69215 -0.2921)
			(end -0.69215 0.2921)
			(stroke
				(width 0.1524)
				(type default)
			)
			(layer "B.SilkS")
		)
		(fp_line
			(start -0.69215 0.2921)
			(end 0.69215 0.2921)
			(stroke
				(width 0.1524)
				(type default)
			)
			(layer "B.SilkS")
		)
		(fp_line
			(start 0.69215 -0.2921)
			(end -0.69215 -0.2921)
			(stroke
				(width 0.1524)
				(type default)
			)
			(layer "B.SilkS")
		)
		(fp_line
			(start 0.69215 0.2921)
			(end 0.69215 -0.2921)
			(stroke
				(width 0.1524)
				(type default)
			)
			(layer "B.SilkS")
		)
		(fp_line
			(start -0.51435 -0.2794)
			(end -0.51435 0.2794)
			(stroke
				(width 0.1)
				(type default)
			)
			(layer "B.Fab")
		)
		(fp_line
			(start -0.51435 0.2794)
			(end 0.51435 0.2794)
			(stroke
				(width 0.1)
				(type default)
			)
			(layer "B.Fab")
		)
		(fp_line
			(start 0.51435 -0.2794)
			(end -0.51435 -0.2794)
			(stroke
				(width 0.1)
				(type default)
			)
			(layer "B.Fab")
		)
		(fp_line
			(start 0.51435 0.2794)
			(end 0.51435 -0.2794)
			(stroke
				(width 0.1)
				(type default)
			)
			(layer "B.Fab")
		)
		(pad "1" smd circle
			(at 0.40005 0 180)
			(size 0 0)
			(layers "B.Cu" "B.Mask" "B.Paste")
			(net "P3V3_AUX_FPGA_VCCIO0")
		)
		(pad "2" smd circle
			(at -0.40005 0 180)
			(size 0 0)
			(layers "B.Cu" "B.Mask" "B.Paste")
			(net "GND")
		)
		(zone
			(layer "B.Cu")
			(hatch none 0.5)
			(connect_pads
				(clearance 0)
			)
			(min_thickness 0.25)
			(keepout
				(tracks not_allowed)
				(vias allowed)
				(pads allowed)
				(copperpour not_allowed)
				(footprints allowed)
			)
			(placement
				(enabled no)
				(sheetname "")
			)
			(fill
				(thermal_gap 0.5)
				(thermal_bridge_width 0.5)
				(island_removal_mode 0)
			)
			(polygon
				(pts
					(xy 170.746166 -109.687868) (xy 170.654726 -109.629702) (xy 170.455336 -109.629702) (xy 170.365166 -109.687868)
					(xy 170.365166 -109.863128) (xy 170.455336 -109.921548) (xy 170.654726 -109.921548) (xy 170.746166 -109.863382)
				)
			)
		)
	)
	(footprint ""
		(layer "B.Cu")
		(at 22.989032 -172.181774 180)
		(property "Reference" "R2582"
			(at 0 0 0)
			(layer "B.SilkS")
			(hide yes)
			(effects
				(font
					(size 1.27 1.27)
				)
				(justify mirror)
			)
		)
		(property "Value" ""
			(at 0 0 0)
			(layer "B.Fab")
			(effects
				(font
					(size 1.27 1.27)
				)
				(justify mirror)
			)
		)
		(duplicate_pad_numbers_are_jumpers no)
		(fp_line
			(start 0.7874 0.4064)
			(end 0.7874 -0.4064)
			(stroke
				(width 0.1524)
				(type default)
			)
			(layer "B.SilkS")
		)
		(fp_line
			(start 0.7874 -0.4064)
			(end -0.7874 -0.4064)
			(stroke
				(width 0.1524)
				(type default)
			)
			(layer "B.SilkS")
		)
		(fp_line
			(start -0.7874 0.4064)
			(end 0.7874 0.4064)
			(stroke
				(width 0.1524)
				(type default)
			)
			(layer "B.SilkS")
		)
		(fp_line
			(start -0.7874 -0.4064)
			(end -0.7874 0.4064)
			(stroke
				(width 0.1524)
				(type default)
			)
			(layer "B.SilkS")
		)
		(fp_line
			(start 0.67945 0.3048)
			(end 0.67945 -0.305054)
			(stroke
				(width 0.1)
				(type default)
			)
			(layer "B.Fab")
		)
		(fp_line
			(start 0.67945 -0.305054)
			(end 0.12065 -0.305054)
			(stroke
				(width 0.1)
				(type default)
			)
			(layer "B.Fab")
		)
		(fp_line
			(start 0.12065 0.3048)
			(end 0.67945 0.3048)
			(stroke
				(width 0.1)
				(type default)
			)
			(layer "B.Fab")
		)
		(fp_line
			(start 0.12065 0.2794)
			(end 0.12065 0.3048)
			(stroke
				(width 0.1)
				(type default)
			)
			(layer "B.Fab")
		)
		(fp_line
			(start 0.12065 -0.2794)
			(end -0.12065 -0.2794)
			(stroke
				(width 0.1)
				(type default)
			)
			(layer "B.Fab")
		)
		(fp_line
			(start 0.12065 -0.305054)
			(end 0.12065 -0.2794)
			(stroke
				(width 0.1)
				(type default)
			)
			(layer "B.Fab")
		)
		(fp_line
			(start -0.120396 0.3048)
			(end -0.120396 0.2794)
			(stroke
				(width 0.1)
				(type default)
			)
			(layer "B.Fab")
		)
		(fp_line
			(start -0.120396 0.2794)
			(end 0.12065 0.2794)
			(stroke
				(width 0.1)
				(type default)
			)
			(layer "B.Fab")
		)
		(fp_line
			(start -0.12065 -0.2794)
			(end -0.12065 -0.3048)
			(stroke
				(width 0.1)
				(type default)
			)
			(layer "B.Fab")
		)
		(fp_line
			(start -0.12065 -0.3048)
			(end -0.67945 -0.3048)
			(stroke
				(width 0.1)
				(type default)
			)
			(layer "B.Fab")
		)
		(fp_line
			(start -0.67945 0.3048)
			(end -0.120396 0.3048)
			(stroke
				(width 0.1)
				(type default)
			)
			(layer "B.Fab")
		)
		(fp_line
			(start -0.67945 -0.3048)
			(end -0.67945 0.3048)
			(stroke
				(width 0.1)
				(type default)
			)
			(layer "B.Fab")
		)
		(pad "1" smd circle
			(at 0.40005 0)
			(size 0 0)
			(layers "B.Cu" "B.Mask" "B.Paste")
			(net "SMB_VR_3V3AUX_SDA_R")
		)
		(pad "2" smd circle
			(at -0.40005 0)
			(size 0 0)
			(layers "B.Cu" "B.Mask" "B.Paste")
			(net "SMB_DIO_PVCCD_HV_CPU1")
		)
	)
	(footprint ""
		(layer "B.Cu")
		(at 208.30794 -316.258448 90)
		(property "Reference" "R3905"
			(at 0 0 90)
			(layer "B.SilkS")
			(hide yes)
			(effects
				(font
					(size 1.27 1.27)
				)
				(justify mirror)
			)
		)
		(property "Value" ""
			(at 0 0 90)
			(layer "B.Fab")
			(effects
				(font
					(size 1.27 1.27)
				)
				(justify mirror)
			)
		)
		(duplicate_pad_numbers_are_jumpers no)
		(fp_line
			(start 0.7874 -0.4064)
			(end -0.7874 -0.4064)
			(stroke
				(width 0.1524)
				(type default)
			)
			(layer "B.SilkS")
		)
		(fp_line
			(start -0.7874 -0.4064)
			(end -0.7874 0.4064)
			(stroke
				(width 0.1524)
				(type default)
			)
			(layer "B.SilkS")
		)
		(fp_line
			(start 0.7874 0.4064)
			(end 0.7874 -0.4064)
			(stroke
				(width 0.1524)
				(type default)
			)
			(layer "B.SilkS")
		)
		(fp_line
			(start -0.7874 0.4064)
			(end 0.7874 0.4064)
			(stroke
				(width 0.1524)
				(type default)
			)
			(layer "B.SilkS")
		)
		(fp_line
			(start 0.67945 -0.305054)
			(end 0.12065 -0.305054)
			(stroke
				(width 0.1)
				(type default)
			)
			(layer "B.Fab")
		)
		(fp_line
			(start 0.12065 -0.305054)
			(end 0.12065 -0.2794)
			(stroke
				(width 0.1)
				(type default)
			)
			(layer "B.Fab")
		)
		(fp_line
			(start -0.12065 -0.3048)
			(end -0.67945 -0.3048)
			(stroke
				(width 0.1)
				(type default)
			)
			(layer "B.Fab")
		)
		(fp_line
			(start -0.67945 -0.3048)
			(end -0.67945 0.3048)
			(stroke
				(width 0.1)
				(type default)
			)
			(layer "B.Fab")
		)
		(fp_line
			(start 0.12065 -0.2794)
			(end -0.12065 -0.2794)
			(stroke
				(width 0.1)
				(type default)
			)
			(layer "B.Fab")
		)
		(fp_line
			(start -0.12065 -0.2794)
			(end -0.12065 -0.3048)
			(stroke
				(width 0.1)
				(type default)
			)
			(layer "B.Fab")
		)
		(fp_line
			(start 0.12065 0.2794)
			(end 0.12065 0.3048)
			(stroke
				(width 0.1)
				(type default)
			)
			(layer "B.Fab")
		)
		(fp_line
			(start -0.120396 0.2794)
			(end 0.12065 0.2794)
			(stroke
				(width 0.1)
				(type default)
			)
			(layer "B.Fab")
		)
		(fp_line
			(start 0.67945 0.3048)
			(end 0.67945 -0.305054)
			(stroke
				(width 0.1)
				(type default)
			)
			(layer "B.Fab")
		)
		(fp_line
			(start 0.12065 0.3048)
			(end 0.67945 0.3048)
			(stroke
				(width 0.1)
				(type default)
			)
			(layer "B.Fab")
		)
		(fp_line
			(start -0.120396 0.3048)
			(end -0.120396 0.2794)
			(stroke
				(width 0.1)
				(type default)
			)
			(layer "B.Fab")
		)
		(fp_line
			(start -0.67945 0.3048)
			(end -0.120396 0.3048)
			(stroke
				(width 0.1)
				(type default)
			)
			(layer "B.Fab")
		)
		(pad "1" smd circle
			(at 0.40005 0 270)
			(size 0 0)
			(layers "B.Cu" "B.Mask" "B.Paste")
			(net "I3C_SPD_DDREFGH_CPU1_LVC1_SCL_6")
		)
		(pad "2" smd circle
			(at -0.40005 0 270)
			(size 0 0)
			(layers "B.Cu" "B.Mask" "B.Paste")
			(net "I3C_SPD_DDREFGH_CPU1_LVC1_SCL")
		)
	)
	(footprint ""
		(layer "B.Cu")
		(at 61.462412 -177.636678)
		(property "Reference" "PC435"
			(at 0 0 0)
			(layer "B.SilkS")
			(hide yes)
			(effects
				(font
					(size 1.27 1.27)
				)
				(justify mirror)
			)
		)
		(property "Value" ""
			(at 0 0 0)
			(layer "B.Fab")
			(effects
				(font
					(size 1.27 1.27)
				)
				(justify mirror)
			)
		)
		(duplicate_pad_numbers_are_jumpers no)
		(fp_line
			(start -1.524 -0.762)
			(end -1.524 0.762)
			(stroke
				(width 0.1524)
				(type default)
			)
			(layer "B.SilkS")
		)
		(fp_line
			(start -1.524 0.762)
			(end 1.524 0.762)
			(stroke
				(width 0.1524)
				(type default)
			)
			(layer "B.SilkS")
		)
		(fp_line
			(start 1.524 -0.762)
			(end -1.524 -0.762)
			(stroke
				(width 0.1524)
				(type default)
			)
			(layer "B.SilkS")
		)
		(fp_line
			(start 1.524 0.762)
			(end 1.524 -0.762)
			(stroke
				(width 0.1524)
				(type default)
			)
			(layer "B.SilkS")
		)
		(fp_line
			(start -1.1049 -0.724916)
			(end 1.1049 -0.724916)
			(stroke
				(width 0.1)
				(type default)
			)
			(layer "B.Fab")
		)
		(fp_line
			(start -1.1049 0.724916)
			(end -1.1049 -0.724916)
			(stroke
				(width 0.1)
				(type default)
			)
			(layer "B.Fab")
		)
		(fp_line
			(start 1.1049 -0.724916)
			(end 1.1049 0.724916)
			(stroke
				(width 0.1)
				(type default)
			)
			(layer "B.Fab")
		)
		(fp_line
			(start 1.1049 0.724916)
			(end -1.1049 0.724916)
			(stroke
				(width 0.1)
				(type default)
			)
			(layer "B.Fab")
		)
		(pad "1" smd rect
			(at 0.889 0)
			(size 1.016 1.27)
			(layers "B.Cu" "B.Mask" "B.Paste")
			(net "PVCCFA_EHV_CPU1")
		)
		(pad "2" smd rect
			(at -0.889 0)
			(size 1.016 1.27)
			(layers "B.Cu" "B.Mask" "B.Paste")
			(net "GND")
		)
	)
	(footprint ""
		(layer "B.Cu")
		(at 456.543918 -316.58306 90)
		(property "Reference" "R943"
			(at 0 0 90)
			(layer "B.SilkS")
			(hide yes)
			(effects
				(font
					(size 1.27 1.27)
				)
				(justify mirror)
			)
		)
		(property "Value" ""
			(at 0 0 90)
			(layer "B.Fab")
			(effects
				(font
					(size 1.27 1.27)
				)
				(justify mirror)
			)
		)
		(duplicate_pad_numbers_are_jumpers no)
		(fp_line
			(start 0.7874 -0.4064)
			(end -0.7874 -0.4064)
			(stroke
				(width 0.1524)
				(type default)
			)
			(layer "B.SilkS")
		)
		(fp_line
			(start -0.7874 -0.4064)
			(end -0.7874 0.4064)
			(stroke
				(width 0.1524)
				(type default)
			)
			(layer "B.SilkS")
		)
		(fp_line
			(start 0.7874 0.4064)
			(end 0.7874 -0.4064)
			(stroke
				(width 0.1524)
				(type default)
			)
			(layer "B.SilkS")
		)
		(fp_line
			(start -0.7874 0.4064)
			(end 0.7874 0.4064)
			(stroke
				(width 0.1524)
				(type default)
			)
			(layer "B.SilkS")
		)
		(fp_line
			(start 0.67945 -0.305054)
			(end 0.12065 -0.305054)
			(stroke
				(width 0.1)
				(type default)
			)
			(layer "B.Fab")
		)
		(fp_line
			(start 0.12065 -0.305054)
			(end 0.12065 -0.2794)
			(stroke
				(width 0.1)
				(type default)
			)
			(layer "B.Fab")
		)
		(fp_line
			(start -0.12065 -0.3048)
			(end -0.67945 -0.3048)
			(stroke
				(width 0.1)
				(type default)
			)
			(layer "B.Fab")
		)
		(fp_line
			(start -0.67945 -0.3048)
			(end -0.67945 0.3048)
			(stroke
				(width 0.1)
				(type default)
			)
			(layer "B.Fab")
		)
		(fp_line
			(start 0.12065 -0.2794)
			(end -0.12065 -0.2794)
			(stroke
				(width 0.1)
				(type default)
			)
			(layer "B.Fab")
		)
		(fp_line
			(start -0.12065 -0.2794)
			(end -0.12065 -0.3048)
			(stroke
				(width 0.1)
				(type default)
			)
			(layer "B.Fab")
		)
		(fp_line
			(start 0.12065 0.2794)
			(end 0.12065 0.3048)
			(stroke
				(width 0.1)
				(type default)
			)
			(layer "B.Fab")
		)
		(fp_line
			(start -0.120396 0.2794)
			(end 0.12065 0.2794)
			(stroke
				(width 0.1)
				(type default)
			)
			(layer "B.Fab")
		)
		(fp_line
			(start 0.67945 0.3048)
			(end 0.67945 -0.305054)
			(stroke
				(width 0.1)
				(type default)
			)
			(layer "B.Fab")
		)
		(fp_line
			(start 0.12065 0.3048)
			(end 0.67945 0.3048)
			(stroke
				(width 0.1)
				(type default)
			)
			(layer "B.Fab")
		)
		(fp_line
			(start -0.120396 0.3048)
			(end -0.120396 0.2794)
			(stroke
				(width 0.1)
				(type default)
			)
			(layer "B.Fab")
		)
		(fp_line
			(start -0.67945 0.3048)
			(end -0.120396 0.3048)
			(stroke
				(width 0.1)
				(type default)
			)
			(layer "B.Fab")
		)
		(pad "1" smd circle
			(at 0.40005 0 270)
			(size 0 0)
			(layers "B.Cu" "B.Mask" "B.Paste")
			(net "P3V3_AUX")
		)
		(pad "2" smd circle
			(at -0.40005 0 270)
			(size 0 0)
			(layers "B.Cu" "B.Mask" "B.Paste")
			(net "PWRGD_FAIL_CPU0_GH_R1")
		)
	)
	(footprint ""
		(layer "B.Cu")
		(at 440.395868 -16.700246)
		(property "Reference" "C1235"
			(at 0 0 0)
			(layer "B.SilkS")
			(hide yes)
			(effects
				(font
					(size 1.27 1.27)
				)
				(justify mirror)
			)
		)
		(property "Value" ""
			(at 0 0 0)
			(layer "B.Fab")
			(effects
				(font
					(size 1.27 1.27)
				)
				(justify mirror)
			)
		)
		(duplicate_pad_numbers_are_jumpers no)
		(fp_line
			(start -0.7874 -0.4064)
			(end -0.7874 0.4064)
			(stroke
				(width 0.1524)
				(type default)
			)
			(layer "B.SilkS")
		)
		(fp_line
			(start -0.7874 0.4064)
			(end 0.7874 0.4064)
			(stroke
				(width 0.1524)
				(type default)
			)
			(layer "B.SilkS")
		)
		(fp_line
			(start 0.7874 -0.4064)
			(end -0.7874 -0.4064)
			(stroke
				(width 0.1524)
				(type default)
			)
			(layer "B.SilkS")
		)
		(fp_line
			(start 0.7874 0.4064)
			(end 0.7874 -0.4064)
			(stroke
				(width 0.1524)
				(type default)
			)
			(layer "B.SilkS")
		)
		(fp_line
			(start -0.67945 -0.3048)
			(end -0.67945 0.3048)
			(stroke
				(width 0.1)
				(type default)
			)
			(layer "B.Fab")
		)
		(fp_line
			(start -0.67945 0.3048)
			(end -0.120396 0.3048)
			(stroke
				(width 0.1)
				(type default)
			)
			(layer "B.Fab")
		)
		(fp_line
			(start -0.12065 -0.3048)
			(end -0.67945 -0.3048)
			(stroke
				(width 0.1)
				(type default)
			)
			(layer "B.Fab")
		)
		(fp_line
			(start -0.12065 -0.2794)
			(end -0.12065 -0.3048)
			(stroke
				(width 0.1)
				(type default)
			)
			(layer "B.Fab")
		)
		(fp_line
			(start -0.120396 0.2794)
			(end 0.12065 0.2794)
			(stroke
				(width 0.1)
				(type default)
			)
			(layer "B.Fab")
		)
		(fp_line
			(start -0.120396 0.3048)
			(end -0.120396 0.2794)
			(stroke
				(width 0.1)
				(type default)
			)
			(layer "B.Fab")
		)
		(fp_line
			(start 0.12065 -0.305054)
			(end 0.12065 -0.2794)
			(stroke
				(width 0.1)
				(type default)
			)
			(layer "B.Fab")
		)
		(fp_line
			(start 0.12065 -0.2794)
			(end -0.12065 -0.2794)
			(stroke
				(width 0.1)
				(type default)
			)
			(layer "B.Fab")
		)
		(fp_line
			(start 0.12065 0.2794)
			(end 0.12065 0.3048)
			(stroke
				(width 0.1)
				(type default)
			)
			(layer "B.Fab")
		)
		(fp_line
			(start 0.12065 0.3048)
			(end 0.67945 0.3048)
			(stroke
				(width 0.1)
				(type default)
			)
			(layer "B.Fab")
		)
		(fp_line
			(start 0.67945 -0.305054)
			(end 0.12065 -0.305054)
			(stroke
				(width 0.1)
				(type default)
			)
			(layer "B.Fab")
		)
		(fp_line
			(start 0.67945 0.3048)
			(end 0.67945 -0.305054)
			(stroke
				(width 0.1)
				(type default)
			)
			(layer "B.Fab")
		)
		(pad "1" smd circle
			(at 0.40005 0 180)
			(size 0 0)
			(layers "B.Cu" "B.Mask" "B.Paste")
			(net "P12V_OCP_SFF")
		)
		(pad "2" smd circle
			(at -0.40005 0 180)
			(size 0 0)
			(layers "B.Cu" "B.Mask" "B.Paste")
			(net "GND")
		)
	)
	(footprint ""
		(layer "B.Cu")
		(at 292.075362 -317.203836 90)
		(property "Reference" "R3878"
			(at 0 0 90)
			(layer "B.SilkS")
			(hide yes)
			(effects
				(font
					(size 1.27 1.27)
				)
				(justify mirror)
			)
		)
		(property "Value" ""
			(at 0 0 90)
			(layer "B.Fab")
			(effects
				(font
					(size 1.27 1.27)
				)
				(justify mirror)
			)
		)
		(duplicate_pad_numbers_are_jumpers no)
		(fp_line
			(start 0.7874 -0.4064)
			(end -0.7874 -0.4064)
			(stroke
				(width 0.1524)
				(type default)
			)
			(layer "B.SilkS")
		)
		(fp_line
			(start -0.7874 -0.4064)
			(end -0.7874 0.4064)
			(stroke
				(width 0.1524)
				(type default)
			)
			(layer "B.SilkS")
		)
		(fp_line
			(start 0.7874 0.4064)
			(end 0.7874 -0.4064)
			(stroke
				(width 0.1524)
				(type default)
			)
			(layer "B.SilkS")
		)
		(fp_line
			(start -0.7874 0.4064)
			(end 0.7874 0.4064)
			(stroke
				(width 0.1524)
				(type default)
			)
			(layer "B.SilkS")
		)
		(fp_line
			(start 0.67945 -0.305054)
			(end 0.12065 -0.305054)
			(stroke
				(width 0.1)
				(type default)
			)
			(layer "B.Fab")
		)
		(fp_line
			(start 0.12065 -0.305054)
			(end 0.12065 -0.2794)
			(stroke
				(width 0.1)
				(type default)
			)
			(layer "B.Fab")
		)
		(fp_line
			(start -0.12065 -0.3048)
			(end -0.67945 -0.3048)
			(stroke
				(width 0.1)
				(type default)
			)
			(layer "B.Fab")
		)
		(fp_line
			(start -0.67945 -0.3048)
			(end -0.67945 0.3048)
			(stroke
				(width 0.1)
				(type default)
			)
			(layer "B.Fab")
		)
		(fp_line
			(start 0.12065 -0.2794)
			(end -0.12065 -0.2794)
			(stroke
				(width 0.1)
				(type default)
			)
			(layer "B.Fab")
		)
		(fp_line
			(start -0.12065 -0.2794)
			(end -0.12065 -0.3048)
			(stroke
				(width 0.1)
				(type default)
			)
			(layer "B.Fab")
		)
		(fp_line
			(start 0.12065 0.2794)
			(end 0.12065 0.3048)
			(stroke
				(width 0.1)
				(type default)
			)
			(layer "B.Fab")
		)
		(fp_line
			(start -0.120396 0.2794)
			(end 0.12065 0.2794)
			(stroke
				(width 0.1)
				(type default)
			)
			(layer "B.Fab")
		)
		(fp_line
			(start 0.67945 0.3048)
			(end 0.67945 -0.305054)
			(stroke
				(width 0.1)
				(type default)
			)
			(layer "B.Fab")
		)
		(fp_line
			(start 0.12065 0.3048)
			(end 0.67945 0.3048)
			(stroke
				(width 0.1)
				(type default)
			)
			(layer "B.Fab")
		)
		(fp_line
			(start -0.120396 0.3048)
			(end -0.120396 0.2794)
			(stroke
				(width 0.1)
				(type default)
			)
			(layer "B.Fab")
		)
		(fp_line
			(start -0.67945 0.3048)
			(end -0.120396 0.3048)
			(stroke
				(width 0.1)
				(type default)
			)
			(layer "B.Fab")
		)
		(pad "1" smd circle
			(at 0.40005 0 270)
			(size 0 0)
			(layers "B.Cu" "B.Mask" "B.Paste")
			(net "I3C_SPD_DDRABCD_CPU0_LVC1_SCL_3")
		)
		(pad "2" smd circle
			(at -0.40005 0 270)
			(size 0 0)
			(layers "B.Cu" "B.Mask" "B.Paste")
			(net "I3C_SPD_DDRABCD_CPU0_LVC1_SCL")
		)
	)
	(footprint ""
		(layer "B.Cu")
		(at 57.517792 -257.918712 -90)
		(property "Reference" "C466"
			(at 0 0 90)
			(layer "B.SilkS")
			(hide yes)
			(effects
				(font
					(size 1.27 1.27)
				)
				(justify mirror)
			)
		)
		(property "Value" ""
			(at 0 0 90)
			(layer "B.Fab")
			(effects
				(font
					(size 1.27 1.27)
				)
				(justify mirror)
			)
		)
		(duplicate_pad_numbers_are_jumpers no)
		(fp_line
			(start -1.524 0.762)
			(end 1.524 0.762)
			(stroke
				(width 0.1524)
				(type default)
			)
			(layer "B.SilkS")
		)
		(fp_line
			(start 1.524 0.762)
			(end 1.524 -0.762)
			(stroke
				(width 0.1524)
				(type default)
			)
			(layer "B.SilkS")
		)
		(fp_line
			(start -1.524 -0.762)
			(end -1.524 0.762)
			(stroke
				(width 0.1524)
				(type default)
			)
			(layer "B.SilkS")
		)
		(fp_line
			(start 1.524 -0.762)
			(end -1.524 -0.762)
			(stroke
				(width 0.1524)
				(type default)
			)
			(layer "B.SilkS")
		)
		(fp_line
			(start -1.1049 0.724916)
			(end -1.1049 -0.724916)
			(stroke
				(width 0.1)
				(type default)
			)
			(layer "B.Fab")
		)
		(fp_line
			(start 1.1049 0.724916)
			(end -1.1049 0.724916)
			(stroke
				(width 0.1)
				(type default)
			)
			(layer "B.Fab")
		)
		(fp_line
			(start -1.1049 -0.724916)
			(end 1.1049 -0.724916)
			(stroke
				(width 0.1)
				(type default)
			)
			(layer "B.Fab")
		)
		(fp_line
			(start 1.1049 -0.724916)
			(end 1.1049 0.724916)
			(stroke
				(width 0.1)
				(type default)
			)
			(layer "B.Fab")
		)
		(pad "1" smd rect
			(at 0.889 0 270)
			(size 1.016 1.27)
			(layers "B.Cu" "B.Mask" "B.Paste")
			(net "PVCCFA_EHV_FIVRA_CPU1")
		)
		(pad "2" smd rect
			(at -0.889 0 270)
			(size 1.016 1.27)
			(layers "B.Cu" "B.Mask" "B.Paste")
			(net "GND")
		)
	)
	(footprint ""
		(layer "B.Cu")
		(at 236.20095 -51.209448)
		(property "Reference" "R2296"
			(at 0 0 0)
			(layer "B.SilkS")
			(hide yes)
			(effects
				(font
					(size 1.27 1.27)
				)
				(justify mirror)
			)
		)
		(property "Value" ""
			(at 0 0 0)
			(layer "B.Fab")
			(effects
				(font
					(size 1.27 1.27)
				)
				(justify mirror)
			)
		)
		(duplicate_pad_numbers_are_jumpers no)
		(fp_line
			(start -0.7874 -0.4064)
			(end -0.7874 0.4064)
			(stroke
				(width 0.1524)
				(type default)
			)
			(layer "B.SilkS")
		)
		(fp_line
			(start -0.7874 0.4064)
			(end 0.7874 0.4064)
			(stroke
				(width 0.1524)
				(type default)
			)
			(layer "B.SilkS")
		)
		(fp_line
			(start 0.7874 -0.4064)
			(end -0.7874 -0.4064)
			(stroke
				(width 0.1524)
				(type default)
			)
			(layer "B.SilkS")
		)
		(fp_line
			(start 0.7874 0.4064)
			(end 0.7874 -0.4064)
			(stroke
				(width 0.1524)
				(type default)
			)
			(layer "B.SilkS")
		)
		(fp_line
			(start -0.67945 -0.3048)
			(end -0.67945 0.3048)
			(stroke
				(width 0.1)
				(type default)
			)
			(layer "B.Fab")
		)
		(fp_line
			(start -0.67945 0.3048)
			(end -0.120396 0.3048)
			(stroke
				(width 0.1)
				(type default)
			)
			(layer "B.Fab")
		)
		(fp_line
			(start -0.12065 -0.3048)
			(end -0.67945 -0.3048)
			(stroke
				(width 0.1)
				(type default)
			)
			(layer "B.Fab")
		)
		(fp_line
			(start -0.12065 -0.2794)
			(end -0.12065 -0.3048)
			(stroke
				(width 0.1)
				(type default)
			)
			(layer "B.Fab")
		)
		(fp_line
			(start -0.120396 0.2794)
			(end 0.12065 0.2794)
			(stroke
				(width 0.1)
				(type default)
			)
			(layer "B.Fab")
		)
		(fp_line
			(start -0.120396 0.3048)
			(end -0.120396 0.2794)
			(stroke
				(width 0.1)
				(type default)
			)
			(layer "B.Fab")
		)
		(fp_line
			(start 0.12065 -0.305054)
			(end 0.12065 -0.2794)
			(stroke
				(width 0.1)
				(type default)
			)
			(layer "B.Fab")
		)
		(fp_line
			(start 0.12065 -0.2794)
			(end -0.12065 -0.2794)
			(stroke
				(width 0.1)
				(type default)
			)
			(layer "B.Fab")
		)
		(fp_line
			(start 0.12065 0.2794)
			(end 0.12065 0.3048)
			(stroke
				(width 0.1)
				(type default)
			)
			(layer "B.Fab")
		)
		(fp_line
			(start 0.12065 0.3048)
			(end 0.67945 0.3048)
			(stroke
				(width 0.1)
				(type default)
			)
			(layer "B.Fab")
		)
		(fp_line
			(start 0.67945 -0.305054)
			(end 0.12065 -0.305054)
			(stroke
				(width 0.1)
				(type default)
			)
			(layer "B.Fab")
		)
		(fp_line
			(start 0.67945 0.3048)
			(end 0.67945 -0.305054)
			(stroke
				(width 0.1)
				(type default)
			)
			(layer "B.Fab")
		)
		(pad "1" smd circle
			(at 0.40005 0 180)
			(size 0 0)
			(layers "B.Cu" "B.Mask" "B.Paste")
			(net "E1S_0_PWRDIS")
		)
		(pad "2" smd circle
			(at -0.40005 0 180)
			(size 0 0)
			(layers "B.Cu" "B.Mask" "B.Paste")
			(net "GND")
		)
	)
	(footprint ""
		(layer "B.Cu")
		(at 23.145242 -316.36589 90)
		(property "Reference" "R3895"
			(at 0 0 90)
			(layer "B.SilkS")
			(hide yes)
			(effects
				(font
					(size 1.27 1.27)
				)
				(justify mirror)
			)
		)
		(property "Value" ""
			(at 0 0 90)
			(layer "B.Fab")
			(effects
				(font
					(size 1.27 1.27)
				)
				(justify mirror)
			)
		)
		(duplicate_pad_numbers_are_jumpers no)
		(fp_line
			(start 0.7874 -0.4064)
			(end -0.7874 -0.4064)
			(stroke
				(width 0.1524)
				(type default)
			)
			(layer "B.SilkS")
		)
		(fp_line
			(start -0.7874 -0.4064)
			(end -0.7874 0.4064)
			(stroke
				(width 0.1524)
				(type default)
			)
			(layer "B.SilkS")
		)
		(fp_line
			(start 0.7874 0.4064)
			(end 0.7874 -0.4064)
			(stroke
				(width 0.1524)
				(type default)
			)
			(layer "B.SilkS")
		)
		(fp_line
			(start -0.7874 0.4064)
			(end 0.7874 0.4064)
			(stroke
				(width 0.1524)
				(type default)
			)
			(layer "B.SilkS")
		)
		(fp_line
			(start 0.67945 -0.305054)
			(end 0.12065 -0.305054)
			(stroke
				(width 0.1)
				(type default)
			)
			(layer "B.Fab")
		)
		(fp_line
			(start 0.12065 -0.305054)
			(end 0.12065 -0.2794)
			(stroke
				(width 0.1)
				(type default)
			)
			(layer "B.Fab")
		)
		(fp_line
			(start -0.12065 -0.3048)
			(end -0.67945 -0.3048)
			(stroke
				(width 0.1)
				(type default)
			)
			(layer "B.Fab")
		)
		(fp_line
			(start -0.67945 -0.3048)
			(end -0.67945 0.3048)
			(stroke
				(width 0.1)
				(type default)
			)
			(layer "B.Fab")
		)
		(fp_line
			(start 0.12065 -0.2794)
			(end -0.12065 -0.2794)
			(stroke
				(width 0.1)
				(type default)
			)
			(layer "B.Fab")
		)
		(fp_line
			(start -0.12065 -0.2794)
			(end -0.12065 -0.3048)
			(stroke
				(width 0.1)
				(type default)
			)
			(layer "B.Fab")
		)
		(fp_line
			(start 0.12065 0.2794)
			(end 0.12065 0.3048)
			(stroke
				(width 0.1)
				(type default)
			)
			(layer "B.Fab")
		)
		(fp_line
			(start -0.120396 0.2794)
			(end 0.12065 0.2794)
			(stroke
				(width 0.1)
				(type default)
			)
			(layer "B.Fab")
		)
		(fp_line
			(start 0.67945 0.3048)
			(end 0.67945 -0.305054)
			(stroke
				(width 0.1)
				(type default)
			)
			(layer "B.Fab")
		)
		(fp_line
			(start 0.12065 0.3048)
			(end 0.67945 0.3048)
			(stroke
				(width 0.1)
				(type default)
			)
			(layer "B.Fab")
		)
		(fp_line
			(start -0.120396 0.3048)
			(end -0.120396 0.2794)
			(stroke
				(width 0.1)
				(type default)
			)
			(layer "B.Fab")
		)
		(fp_line
			(start -0.67945 0.3048)
			(end -0.120396 0.3048)
			(stroke
				(width 0.1)
				(type default)
			)
			(layer "B.Fab")
		)
		(pad "1" smd circle
			(at 0.40005 0 270)
			(size 0 0)
			(layers "B.Cu" "B.Mask" "B.Paste")
			(net "I3C_SPD_DDRABCD_CPU1_LVC1_SCL_4")
		)
		(pad "2" smd circle
			(at -0.40005 0 270)
			(size 0 0)
			(layers "B.Cu" "B.Mask" "B.Paste")
			(net "I3C_SPD_DDRABCD_CPU1_LVC1_SCL")
		)
	)
	(footprint ""
		(layer "B.Cu")
		(at 350.435418 -296.054526 180)
		(property "Reference" "C386"
			(at 0 0 0)
			(layer "B.SilkS")
			(hide yes)
			(effects
				(font
					(size 1.27 1.27)
				)
				(justify mirror)
			)
		)
		(property "Value" ""
			(at 0 0 0)
			(layer "B.Fab")
			(effects
				(font
					(size 1.27 1.27)
				)
				(justify mirror)
			)
		)
		(duplicate_pad_numbers_are_jumpers no)
		(fp_line
			(start 1.524 0.762)
			(end 1.524 -0.762)
			(stroke
				(width 0.1524)
				(type default)
			)
			(layer "B.SilkS")
		)
		(fp_line
			(start 1.524 -0.762)
			(end -1.524 -0.762)
			(stroke
				(width 0.1524)
				(type default)
			)
			(layer "B.SilkS")
		)
		(fp_line
			(start -1.524 0.762)
			(end 1.524 0.762)
			(stroke
				(width 0.1524)
				(type default)
			)
			(layer "B.SilkS")
		)
		(fp_line
			(start -1.524 -0.762)
			(end -1.524 0.762)
			(stroke
				(width 0.1524)
				(type default)
			)
			(layer "B.SilkS")
		)
		(fp_line
			(start 1.1049 0.724916)
			(end -1.1049 0.724916)
			(stroke
				(width 0.1)
				(type default)
			)
			(layer "B.Fab")
		)
		(fp_line
			(start 1.1049 -0.724916)
			(end 1.1049 0.724916)
			(stroke
				(width 0.1)
				(type default)
			)
			(layer "B.Fab")
		)
		(fp_line
			(start -1.1049 0.724916)
			(end -1.1049 -0.724916)
			(stroke
				(width 0.1)
				(type default)
			)
			(layer "B.Fab")
		)
		(fp_line
			(start -1.1049 -0.724916)
			(end 1.1049 -0.724916)
			(stroke
				(width 0.1)
				(type default)
			)
			(layer "B.Fab")
		)
		(pad "1" smd rect
			(at 0.889 0 180)
			(size 1.016 1.27)
			(layers "B.Cu" "B.Mask" "B.Paste")
			(net "PVCCIN_CPU0")
		)
		(pad "2" smd rect
			(at -0.889 0 180)
			(size 1.016 1.27)
			(layers "B.Cu" "B.Mask" "B.Paste")
			(net "GND")
		)
	)
	(footprint ""
		(layer "B.Cu")
		(at 364.342934 -248.498106 -90)
		(property "Reference" "C373"
			(at 0 0 90)
			(layer "B.SilkS")
			(hide yes)
			(effects
				(font
					(size 1.27 1.27)
				)
				(justify mirror)
			)
		)
		(property "Value" ""
			(at 0 0 90)
			(layer "B.Fab")
			(effects
				(font
					(size 1.27 1.27)
				)
				(justify mirror)
			)
		)
		(duplicate_pad_numbers_are_jumpers no)
		(fp_line
			(start -1.524 0.762)
			(end 1.524 0.762)
			(stroke
				(width 0.1524)
				(type default)
			)
			(layer "B.SilkS")
		)
		(fp_line
			(start 1.524 0.762)
			(end 1.524 -0.762)
			(stroke
				(width 0.1524)
				(type default)
			)
			(layer "B.SilkS")
		)
		(fp_line
			(start -1.524 -0.762)
			(end -1.524 0.762)
			(stroke
				(width 0.1524)
				(type default)
			)
			(layer "B.SilkS")
		)
		(fp_line
			(start 1.524 -0.762)
			(end -1.524 -0.762)
			(stroke
				(width 0.1524)
				(type default)
			)
			(layer "B.SilkS")
		)
		(fp_line
			(start -1.1049 0.724916)
			(end -1.1049 -0.724916)
			(stroke
				(width 0.1)
				(type default)
			)
			(layer "B.Fab")
		)
		(fp_line
			(start 1.1049 0.724916)
			(end -1.1049 0.724916)
			(stroke
				(width 0.1)
				(type default)
			)
			(layer "B.Fab")
		)
		(fp_line
			(start -1.1049 -0.724916)
			(end 1.1049 -0.724916)
			(stroke
				(width 0.1)
				(type default)
			)
			(layer "B.Fab")
		)
		(fp_line
			(start 1.1049 -0.724916)
			(end 1.1049 0.724916)
			(stroke
				(width 0.1)
				(type default)
			)
			(layer "B.Fab")
		)
		(pad "1" smd rect
			(at 0.889 0 270)
			(size 1.016 1.27)
			(layers "B.Cu" "B.Mask" "B.Paste")
			(net "PVCCIN_CPU0")
		)
		(pad "2" smd rect
			(at -0.889 0 270)
			(size 1.016 1.27)
			(layers "B.Cu" "B.Mask" "B.Paste")
			(net "GND")
		)
	)
	(footprint ""
		(layer "B.Cu")
		(at 185.142886 -193.599816 -90)
		(property "Reference" "R822"
			(at 0 0 90)
			(layer "B.SilkS")
			(hide yes)
			(effects
				(font
					(size 1.27 1.27)
				)
				(justify mirror)
			)
		)
		(property "Value" ""
			(at 0 0 90)
			(layer "B.Fab")
			(effects
				(font
					(size 1.27 1.27)
				)
				(justify mirror)
			)
		)
		(duplicate_pad_numbers_are_jumpers no)
		(fp_line
			(start -0.7874 0.4064)
			(end 0.7874 0.4064)
			(stroke
				(width 0.1524)
				(type default)
			)
			(layer "B.SilkS")
		)
		(fp_line
			(start 0.7874 0.4064)
			(end 0.7874 -0.4064)
			(stroke
				(width 0.1524)
				(type default)
			)
			(layer "B.SilkS")
		)
		(fp_line
			(start -0.7874 -0.4064)
			(end -0.7874 0.4064)
			(stroke
				(width 0.1524)
				(type default)
			)
			(layer "B.SilkS")
		)
		(fp_line
			(start 0.7874 -0.4064)
			(end -0.7874 -0.4064)
			(stroke
				(width 0.1524)
				(type default)
			)
			(layer "B.SilkS")
		)
		(fp_line
			(start -0.67945 0.3048)
			(end -0.120396 0.3048)
			(stroke
				(width 0.1)
				(type default)
			)
			(layer "B.Fab")
		)
		(fp_line
			(start -0.120396 0.3048)
			(end -0.120396 0.2794)
			(stroke
				(width 0.1)
				(type default)
			)
			(layer "B.Fab")
		)
		(fp_line
			(start 0.12065 0.3048)
			(end 0.67945 0.3048)
			(stroke
				(width 0.1)
				(type default)
			)
			(layer "B.Fab")
		)
		(fp_line
			(start 0.67945 0.3048)
			(end 0.67945 -0.305054)
			(stroke
				(width 0.1)
				(type default)
			)
			(layer "B.Fab")
		)
		(fp_line
			(start -0.120396 0.2794)
			(end 0.12065 0.2794)
			(stroke
				(width 0.1)
				(type default)
			)
			(layer "B.Fab")
		)
		(fp_line
			(start 0.12065 0.2794)
			(end 0.12065 0.3048)
			(stroke
				(width 0.1)
				(type default)
			)
			(layer "B.Fab")
		)
		(fp_line
			(start -0.12065 -0.2794)
			(end -0.12065 -0.3048)
			(stroke
				(width 0.1)
				(type default)
			)
			(layer "B.Fab")
		)
		(fp_line
			(start 0.12065 -0.2794)
			(end -0.12065 -0.2794)
			(stroke
				(width 0.1)
				(type default)
			)
			(layer "B.Fab")
		)
		(fp_line
			(start -0.67945 -0.3048)
			(end -0.67945 0.3048)
			(stroke
				(width 0.1)
				(type default)
			)
			(layer "B.Fab")
		)
		(fp_line
			(start -0.12065 -0.3048)
			(end -0.67945 -0.3048)
			(stroke
				(width 0.1)
				(type default)
			)
			(layer "B.Fab")
		)
		(fp_line
			(start 0.12065 -0.305054)
			(end 0.12065 -0.2794)
			(stroke
				(width 0.1)
				(type default)
			)
			(layer "B.Fab")
		)
		(fp_line
			(start 0.67945 -0.305054)
			(end 0.12065 -0.305054)
			(stroke
				(width 0.1)
				(type default)
			)
			(layer "B.Fab")
		)
		(pad "1" smd circle
			(at 0.40005 0 90)
			(size 0 0)
			(layers "B.Cu" "B.Mask" "B.Paste")
			(net "PVCCD_HV_CPU1")
		)
		(pad "2" smd circle
			(at -0.40005 0 90)
			(size 0 0)
			(layers "B.Cu" "B.Mask" "B.Paste")
			(net "RST_M_EF_CPU1_FPGA_N")
		)
	)
	(footprint ""
		(layer "B.Cu")
		(at 17.75206 -193.843656 180)
		(property "Reference" "C560"
			(at 0 0 0)
			(layer "B.SilkS")
			(hide yes)
			(effects
				(font
					(size 1.27 1.27)
				)
				(justify mirror)
			)
		)
		(property "Value" ""
			(at 0 0 0)
			(layer "B.Fab")
			(effects
				(font
					(size 1.27 1.27)
				)
				(justify mirror)
			)
		)
		(duplicate_pad_numbers_are_jumpers no)
		(fp_line
			(start 0.7874 0.4064)
			(end 0.7874 -0.4064)
			(stroke
				(width 0.1524)
				(type default)
			)
			(layer "B.SilkS")
		)
		(fp_line
			(start 0.7874 -0.4064)
			(end -0.7874 -0.4064)
			(stroke
				(width 0.1524)
				(type default)
			)
			(layer "B.SilkS")
		)
		(fp_line
			(start -0.7874 0.4064)
			(end 0.7874 0.4064)
			(stroke
				(width 0.1524)
				(type default)
			)
			(layer "B.SilkS")
		)
		(fp_line
			(start -0.7874 -0.4064)
			(end -0.7874 0.4064)
			(stroke
				(width 0.1524)
				(type default)
			)
			(layer "B.SilkS")
		)
		(fp_line
			(start 0.67945 0.3048)
			(end 0.67945 -0.305054)
			(stroke
				(width 0.1)
				(type default)
			)
			(layer "B.Fab")
		)
		(fp_line
			(start 0.67945 -0.305054)
			(end 0.12065 -0.305054)
			(stroke
				(width 0.1)
				(type default)
			)
			(layer "B.Fab")
		)
		(fp_line
			(start 0.12065 0.3048)
			(end 0.67945 0.3048)
			(stroke
				(width 0.1)
				(type default)
			)
			(layer "B.Fab")
		)
		(fp_line
			(start 0.12065 0.2794)
			(end 0.12065 0.3048)
			(stroke
				(width 0.1)
				(type default)
			)
			(layer "B.Fab")
		)
		(fp_line
			(start 0.12065 -0.2794)
			(end -0.12065 -0.2794)
			(stroke
				(width 0.1)
				(type default)
			)
			(layer "B.Fab")
		)
		(fp_line
			(start 0.12065 -0.305054)
			(end 0.12065 -0.2794)
			(stroke
				(width 0.1)
				(type default)
			)
			(layer "B.Fab")
		)
		(fp_line
			(start -0.120396 0.3048)
			(end -0.120396 0.2794)
			(stroke
				(width 0.1)
				(type default)
			)
			(layer "B.Fab")
		)
		(fp_line
			(start -0.120396 0.2794)
			(end 0.12065 0.2794)
			(stroke
				(width 0.1)
				(type default)
			)
			(layer "B.Fab")
		)
		(fp_line
			(start -0.12065 -0.2794)
			(end -0.12065 -0.3048)
			(stroke
				(width 0.1)
				(type default)
			)
			(layer "B.Fab")
		)
		(fp_line
			(start -0.12065 -0.3048)
			(end -0.67945 -0.3048)
			(stroke
				(width 0.1)
				(type default)
			)
			(layer "B.Fab")
		)
		(fp_line
			(start -0.67945 0.3048)
			(end -0.120396 0.3048)
			(stroke
				(width 0.1)
				(type default)
			)
			(layer "B.Fab")
		)
		(fp_line
			(start -0.67945 -0.3048)
			(end -0.67945 0.3048)
			(stroke
				(width 0.1)
				(type default)
			)
			(layer "B.Fab")
		)
		(pad "1" smd circle
			(at 0.40005 0)
			(size 0 0)
			(layers "B.Cu" "B.Mask" "B.Paste")
			(net "PVNN_TERM_CPU1")
		)
		(pad "2" smd circle
			(at -0.40005 0)
			(size 0 0)
			(layers "B.Cu" "B.Mask" "B.Paste")
			(net "GND")
		)
	)
	(footprint ""
		(layer "B.Cu")
		(at 349.675704 -64.18072)
		(property "Reference" "C156"
			(at 0 0 0)
			(layer "B.SilkS")
			(hide yes)
			(effects
				(font
					(size 1.27 1.27)
				)
				(justify mirror)
			)
		)
		(property "Value" ""
			(at 0 0 0)
			(layer "B.Fab")
			(effects
				(font
					(size 1.27 1.27)
				)
				(justify mirror)
			)
		)
		(duplicate_pad_numbers_are_jumpers no)
		(fp_line
			(start -0.299974 -0.150114)
			(end -0.299974 0.150114)
			(stroke
				(width 0.1)
				(type default)
			)
			(layer "B.Fab")
		)
		(fp_line
			(start -0.299974 0.150114)
			(end 0.299974 0.150114)
			(stroke
				(width 0.1)
				(type default)
			)
			(layer "B.Fab")
		)
		(fp_line
			(start 0.299974 -0.150114)
			(end -0.299974 -0.150114)
			(stroke
				(width 0.1)
				(type default)
			)
			(layer "B.Fab")
		)
		(fp_line
			(start 0.299974 0.150114)
			(end 0.299974 -0.150114)
			(stroke
				(width 0.1)
				(type default)
			)
			(layer "B.Fab")
		)
		(pad "1" smd rect
			(at 0.2667 0 180)
			(size 0.3048 0.381)
			(layers "B.Cu" "B.Mask" "B.Paste")
			(net "DMI_CPU0_PCH_RX_C_DP<7>")
		)
		(pad "2" smd rect
			(at -0.2667 0 180)
			(size 0.3048 0.381)
			(layers "B.Cu" "B.Mask" "B.Paste")
			(net "DMI_CPU0_PCH_RX_DP<7>")
		)
	)
	(footprint ""
		(layer "B.Cu")
		(at 158.697168 -318.336422)
		(property "Reference" "R3900"
			(at 0 0 0)
			(layer "B.SilkS")
			(hide yes)
			(effects
				(font
					(size 1.27 1.27)
				)
				(justify mirror)
			)
		)
		(property "Value" ""
			(at 0 0 0)
			(layer "B.Fab")
			(effects
				(font
					(size 1.27 1.27)
				)
				(justify mirror)
			)
		)
		(duplicate_pad_numbers_are_jumpers no)
		(fp_line
			(start -0.7874 -0.4064)
			(end -0.7874 0.4064)
			(stroke
				(width 0.1524)
				(type default)
			)
			(layer "B.SilkS")
		)
		(fp_line
			(start -0.7874 0.4064)
			(end 0.7874 0.4064)
			(stroke
				(width 0.1524)
				(type default)
			)
			(layer "B.SilkS")
		)
		(fp_line
			(start 0.7874 -0.4064)
			(end -0.7874 -0.4064)
			(stroke
				(width 0.1524)
				(type default)
			)
			(layer "B.SilkS")
		)
		(fp_line
			(start 0.7874 0.4064)
			(end 0.7874 -0.4064)
			(stroke
				(width 0.1524)
				(type default)
			)
			(layer "B.SilkS")
		)
		(fp_line
			(start -0.67945 -0.3048)
			(end -0.67945 0.3048)
			(stroke
				(width 0.1)
				(type default)
			)
			(layer "B.Fab")
		)
		(fp_line
			(start -0.67945 0.3048)
			(end -0.120396 0.3048)
			(stroke
				(width 0.1)
				(type default)
			)
			(layer "B.Fab")
		)
		(fp_line
			(start -0.12065 -0.3048)
			(end -0.67945 -0.3048)
			(stroke
				(width 0.1)
				(type default)
			)
			(layer "B.Fab")
		)
		(fp_line
			(start -0.12065 -0.2794)
			(end -0.12065 -0.3048)
			(stroke
				(width 0.1)
				(type default)
			)
			(layer "B.Fab")
		)
		(fp_line
			(start -0.120396 0.2794)
			(end 0.12065 0.2794)
			(stroke
				(width 0.1)
				(type default)
			)
			(layer "B.Fab")
		)
		(fp_line
			(start -0.120396 0.3048)
			(end -0.120396 0.2794)
			(stroke
				(width 0.1)
				(type default)
			)
			(layer "B.Fab")
		)
		(fp_line
			(start 0.12065 -0.305054)
			(end 0.12065 -0.2794)
			(stroke
				(width 0.1)
				(type default)
			)
			(layer "B.Fab")
		)
		(fp_line
			(start 0.12065 -0.2794)
			(end -0.12065 -0.2794)
			(stroke
				(width 0.1)
				(type default)
			)
			(layer "B.Fab")
		)
		(fp_line
			(start 0.12065 0.2794)
			(end 0.12065 0.3048)
			(stroke
				(width 0.1)
				(type default)
			)
			(layer "B.Fab")
		)
		(fp_line
			(start 0.12065 0.3048)
			(end 0.67945 0.3048)
			(stroke
				(width 0.1)
				(type default)
			)
			(layer "B.Fab")
		)
		(fp_line
			(start 0.67945 -0.305054)
			(end 0.12065 -0.305054)
			(stroke
				(width 0.1)
				(type default)
			)
			(layer "B.Fab")
		)
		(fp_line
			(start 0.67945 0.3048)
			(end 0.67945 -0.305054)
			(stroke
				(width 0.1)
				(type default)
			)
			(layer "B.Fab")
		)
		(pad "1" smd circle
			(at 0.40005 0 180)
			(size 0 0)
			(layers "B.Cu" "B.Mask" "B.Paste")
			(net "I3C_SPD_DDREFGH_CPU1_LVC1_SCL_1")
		)
		(pad "2" smd circle
			(at -0.40005 0 180)
			(size 0 0)
			(layers "B.Cu" "B.Mask" "B.Paste")
			(net "I3C_SPD_DDREFGH_CPU1_LVC1_SCL")
		)
	)
	(footprint ""
		(layer "B.Cu")
		(at 485.20985 -148.045932 -90)
		(property "Reference" "X18"
			(at 3.762248 3.089656 270)
			(unlocked yes)
			(layer "B.SilkS")
			(effects
				(font
					(size 0.7874 0.5842)
					(thickness 0.1524)
				)
				(justify left mirror)
			)
		)
		(property "Value" ""
			(at 0 0 90)
			(layer "B.Fab")
			(effects
				(font
					(size 1.27 1.27)
				)
				(justify mirror)
			)
		)
		(property "Device Type" "TP_TDR_4P_FTS_MPKT4_H025P0200_I"
			(at -1.30175 1.27 180)
			(unlocked yes)
			(layer "B.Fab")
			(hide yes)
			(effects
				(font
					(size 0.635 0.4064)
					(thickness 0.1524)
				)
				(justify mirror)
			)
		)
		(property "User Part Number" "TP15"
			(at -1.30175 1.27 180)
			(unlocked yes)
			(layer "Cmts.User")
			(hide yes)
			(effects
				(font
					(size 0.635 0.4064)
					(thickness 0.1524)
				)
				(justify mirror)
			)
		)
		(duplicate_pad_numbers_are_jumpers no)
		(fp_line
			(start -2.54 3.81)
			(end -2.54 3.6703)
			(stroke
				(width 0.1524)
				(type default)
			)
			(layer "B.SilkS")
		)
		(fp_line
			(start 0 3.81)
			(end -2.54 3.81)
			(stroke
				(width 0.1524)
				(type default)
			)
			(layer "B.SilkS")
		)
		(fp_line
			(start 0 3.175)
			(end 0 3.81)
			(stroke
				(width 0.1524)
				(type default)
			)
			(layer "B.SilkS")
		)
		(fp_line
			(start -2.54 1.4097)
			(end -2.54 1.1303)
			(stroke
				(width 0.1524)
				(type default)
			)
			(layer "B.SilkS")
		)
		(fp_line
			(start 0 0.635)
			(end 0 1.905)
			(stroke
				(width 0.1524)
				(type default)
			)
			(layer "B.SilkS")
		)
		(fp_line
			(start -2.54 -1.1303)
			(end -2.54 -1.27)
			(stroke
				(width 0.1524)
				(type default)
			)
			(layer "B.SilkS")
		)
		(fp_line
			(start -2.54 -1.27)
			(end 0 -1.27)
			(stroke
				(width 0.1524)
				(type default)
			)
			(layer "B.SilkS")
		)
		(fp_line
			(start 0 -1.27)
			(end 0 -0.635)
			(stroke
				(width 0.1524)
				(type default)
			)
			(layer "B.SilkS")
		)
		(fp_poly
			(pts
				(xy 2.958846 -0.84582) (xy 2.958846 0.67818) (xy 1.434846 -0.08382)
			)
			(stroke
				(width 0)
				(type default)
			)
			(fill yes)
			(layer "B.SilkS")
		)
		(fp_line
			(start -2.54 3.81)
			(end -2.54 -1.27)
			(stroke
				(width 0.1)
				(type default)
			)
			(layer "B.Fab")
		)
		(fp_line
			(start 0 3.81)
			(end -2.54 3.81)
			(stroke
				(width 0.1)
				(type default)
			)
			(layer "B.Fab")
		)
		(fp_line
			(start -2.54 -1.27)
			(end 0 -1.27)
			(stroke
				(width 0.1)
				(type default)
			)
			(layer "B.Fab")
		)
		(fp_line
			(start 0 -1.27)
			(end 0 3.81)
			(stroke
				(width 0.1)
				(type default)
			)
			(layer "B.Fab")
		)
		(fp_poly
			(pts
				(xy 0.761746 0) (xy 2.285746 -0.762) (xy 2.285746 0.762)
			)
			(stroke
				(width 0)
				(type default)
			)
			(fill yes)
			(layer "B.Fab")
		)
		(pad "1" thru_hole circle
			(at 0 0 90)
			(size 1.0033 1.0033)
			(drill 0.249936)
			(layers "*.Cu" "*.Mask")
			(remove_unused_layers no)
			(net "TDR_DIFF_100_BOT_DP")
			(clearance 0.10795)
			(padstack
				(mode front_inner_back)
				(layer "Inner"
					(shape circle)
					(size 0.8001 0.8001)
					(clearance 0.1524)
				)
				(layer "B.Cu"
					(shape circle)
					(size 1.0033 1.0033)
					(thermal_gap 0.10795)
					(clearance 0.10795)
				)
			)
		)
		(pad "2" thru_hole circle
			(at -2.54 0 90)
			(size 1.9939 1.9939)
			(drill 0.249936)
			(layers "*.Cu" "*.Mask")
			(remove_unused_layers no)
			(net "T1_GND")
			(clearance 0.10795)
			(padstack
				(mode front_inner_back)
				(layer "Inner"
					(shape circle)
					(size 0.8001 0.8001)
					(clearance 0.1524)
				)
				(layer "B.Cu"
					(shape circle)
					(size 1.9939 1.9939)
					(thermal_gap 0.10795)
					(clearance 0.10795)
				)
			)
		)
		(pad "3" thru_hole circle
			(at -2.54 2.54 90)
			(size 1.9939 1.9939)
			(drill 0.249936)
			(layers "*.Cu" "*.Mask")
			(remove_unused_layers no)
			(net "T1_GND")
			(clearance 0.10795)
			(padstack
				(mode front_inner_back)
				(layer "Inner"
					(shape circle)
					(size 0.8001 0.8001)
					(clearance 0.1524)
				)
				(layer "B.Cu"
					(shape circle)
					(size 1.9939 1.9939)
					(thermal_gap 0.10795)
					(clearance 0.10795)
				)
			)
		)
		(pad "4" thru_hole circle
			(at 0 2.54 90)
			(size 1.0033 1.0033)
			(drill 0.249936)
			(layers "*.Cu" "*.Mask")
			(remove_unused_layers no)
			(net "TDR_DIFF_100_BOT_DN")
			(clearance 0.10795)
			(padstack
				(mode front_inner_back)
				(layer "Inner"
					(shape circle)
					(size 0.8001 0.8001)
					(clearance 0.1524)
				)
				(layer "B.Cu"
					(shape circle)
					(size 1.0033 1.0033)
					(thermal_gap 0.10795)
					(clearance 0.10795)
				)
			)
		)
	)
	(footprint ""
		(layer "B.Cu")
		(at 138.152378 -333.6163 -90)
		(property "Reference" "PC499_P1_8"
			(at 0 0 90)
			(layer "B.SilkS")
			(hide yes)
			(effects
				(font
					(size 1.27 1.27)
				)
				(justify mirror)
			)
		)
		(property "Value" ""
			(at 0 0 90)
			(layer "B.Fab")
			(effects
				(font
					(size 1.27 1.27)
				)
				(justify mirror)
			)
		)
		(duplicate_pad_numbers_are_jumpers no)
		(fp_line
			(start -1.524 0.762)
			(end 1.524 0.762)
			(stroke
				(width 0.1524)
				(type default)
			)
			(layer "B.SilkS")
		)
		(fp_line
			(start 1.524 0.762)
			(end 1.524 -0.762)
			(stroke
				(width 0.1524)
				(type default)
			)
			(layer "B.SilkS")
		)
		(fp_line
			(start -1.524 -0.762)
			(end -1.524 0.762)
			(stroke
				(width 0.1524)
				(type default)
			)
			(layer "B.SilkS")
		)
		(fp_line
			(start 1.524 -0.762)
			(end -1.524 -0.762)
			(stroke
				(width 0.1524)
				(type default)
			)
			(layer "B.SilkS")
		)
		(fp_line
			(start -1.1049 0.724916)
			(end -1.1049 -0.724916)
			(stroke
				(width 0.1)
				(type default)
			)
			(layer "B.Fab")
		)
		(fp_line
			(start 1.1049 0.724916)
			(end -1.1049 0.724916)
			(stroke
				(width 0.1)
				(type default)
			)
			(layer "B.Fab")
		)
		(fp_line
			(start -1.1049 -0.724916)
			(end 1.1049 -0.724916)
			(stroke
				(width 0.1)
				(type default)
			)
			(layer "B.Fab")
		)
		(fp_line
			(start 1.1049 -0.724916)
			(end 1.1049 0.724916)
			(stroke
				(width 0.1)
				(type default)
			)
			(layer "B.Fab")
		)
		(pad "1" smd rect
			(at 0.889 0 270)
			(size 1.016 1.27)
			(layers "B.Cu" "B.Mask" "B.Paste")
			(net "PVCCIN_CPU1")
		)
		(pad "2" smd rect
			(at -0.889 0 270)
			(size 1.016 1.27)
			(layers "B.Cu" "B.Mask" "B.Paste")
			(net "GND")
		)
	)
	(footprint ""
		(layer "B.Cu")
		(at 87.489284 -190.705232 -90)
		(property "Reference" "R65"
			(at 0 0 90)
			(layer "B.SilkS")
			(hide yes)
			(effects
				(font
					(size 1.27 1.27)
				)
				(justify mirror)
			)
		)
		(property "Value" ""
			(at 0 0 90)
			(layer "B.Fab")
			(effects
				(font
					(size 1.27 1.27)
				)
				(justify mirror)
			)
		)
		(duplicate_pad_numbers_are_jumpers no)
		(fp_line
			(start -0.7874 0.4064)
			(end 0.7874 0.4064)
			(stroke
				(width 0.1524)
				(type default)
			)
			(layer "B.SilkS")
		)
		(fp_line
			(start 0.7874 0.4064)
			(end 0.7874 -0.4064)
			(stroke
				(width 0.1524)
				(type default)
			)
			(layer "B.SilkS")
		)
		(fp_line
			(start -0.7874 -0.4064)
			(end -0.7874 0.4064)
			(stroke
				(width 0.1524)
				(type default)
			)
			(layer "B.SilkS")
		)
		(fp_line
			(start 0.7874 -0.4064)
			(end -0.7874 -0.4064)
			(stroke
				(width 0.1524)
				(type default)
			)
			(layer "B.SilkS")
		)
		(fp_line
			(start -0.67945 0.3048)
			(end -0.120396 0.3048)
			(stroke
				(width 0.1)
				(type default)
			)
			(layer "B.Fab")
		)
		(fp_line
			(start -0.120396 0.3048)
			(end -0.120396 0.2794)
			(stroke
				(width 0.1)
				(type default)
			)
			(layer "B.Fab")
		)
		(fp_line
			(start 0.12065 0.3048)
			(end 0.67945 0.3048)
			(stroke
				(width 0.1)
				(type default)
			)
			(layer "B.Fab")
		)
		(fp_line
			(start 0.67945 0.3048)
			(end 0.67945 -0.305054)
			(stroke
				(width 0.1)
				(type default)
			)
			(layer "B.Fab")
		)
		(fp_line
			(start -0.120396 0.2794)
			(end 0.12065 0.2794)
			(stroke
				(width 0.1)
				(type default)
			)
			(layer "B.Fab")
		)
		(fp_line
			(start 0.12065 0.2794)
			(end 0.12065 0.3048)
			(stroke
				(width 0.1)
				(type default)
			)
			(layer "B.Fab")
		)
		(fp_line
			(start -0.12065 -0.2794)
			(end -0.12065 -0.3048)
			(stroke
				(width 0.1)
				(type default)
			)
			(layer "B.Fab")
		)
		(fp_line
			(start 0.12065 -0.2794)
			(end -0.12065 -0.2794)
			(stroke
				(width 0.1)
				(type default)
			)
			(layer "B.Fab")
		)
		(fp_line
			(start -0.67945 -0.3048)
			(end -0.67945 0.3048)
			(stroke
				(width 0.1)
				(type default)
			)
			(layer "B.Fab")
		)
		(fp_line
			(start -0.12065 -0.3048)
			(end -0.67945 -0.3048)
			(stroke
				(width 0.1)
				(type default)
			)
			(layer "B.Fab")
		)
		(fp_line
			(start 0.12065 -0.305054)
			(end 0.12065 -0.2794)
			(stroke
				(width 0.1)
				(type default)
			)
			(layer "B.Fab")
		)
		(fp_line
			(start 0.67945 -0.305054)
			(end 0.12065 -0.305054)
			(stroke
				(width 0.1)
				(type default)
			)
			(layer "B.Fab")
		)
		(pad "1" smd circle
			(at 0.40005 0 90)
			(size 0 0)
			(layers "B.Cu" "B.Mask" "B.Paste")
			(net "JTAG_DBP_CPU_GTL_TCK")
		)
		(pad "2" smd circle
			(at -0.40005 0 90)
			(size 0 0)
			(layers "B.Cu" "B.Mask" "B.Paste")
			(net "JTAG_DBP_CPU1_GTL_R_TCK")
		)
	)
	(footprint ""
		(layer "B.Cu")
		(at 216.986358 -194.41795)
		(property "Reference" "U16"
			(at 2.2606 -2.352548 0)
			(unlocked yes)
			(layer "B.SilkS")
			(effects
				(font
					(size 0.7874 0.5842)
					(thickness 0.1524)
				)
				(justify left mirror)
			)
		)
		(property "Value" ""
			(at 0 0 0)
			(layer "B.Fab")
			(effects
				(font
					(size 1.27 1.27)
				)
				(justify mirror)
			)
		)
		(duplicate_pad_numbers_are_jumpers no)
		(fp_line
			(start -2.032 -1.549908)
			(end -2.032 1.549908)
			(stroke
				(width 0.1524)
				(type default)
			)
			(layer "B.SilkS")
		)
		(fp_line
			(start -2.032 1.549908)
			(end 2.032 1.549908)
			(stroke
				(width 0.1524)
				(type default)
			)
			(layer "B.SilkS")
		)
		(fp_line
			(start 2.032 -1.549908)
			(end -2.032 -1.549908)
			(stroke
				(width 0.1524)
				(type default)
			)
			(layer "B.SilkS")
		)
		(fp_line
			(start 2.032 1.549908)
			(end 2.032 -1.549908)
			(stroke
				(width 0.1524)
				(type default)
			)
			(layer "B.SilkS")
		)
		(fp_poly
			(pts
				(xy 2.9464 -1.2192) (xy 2.9464 -0.7112) (xy 2.1844 -0.9652)
			)
			(stroke
				(width 0)
				(type default)
			)
			(fill yes)
			(layer "B.SilkS")
		)
		(fp_line
			(start -0.849884 -1.549908)
			(end 0.849884 -1.549908)
			(stroke
				(width 0.1)
				(type default)
			)
			(layer "B.Fab")
		)
		(fp_line
			(start -0.849884 1.549908)
			(end -0.849884 -1.549908)
			(stroke
				(width 0.1)
				(type default)
			)
			(layer "B.Fab")
		)
		(fp_line
			(start 0.849884 -1.549908)
			(end 0.849884 1.549908)
			(stroke
				(width 0.1)
				(type default)
			)
			(layer "B.Fab")
		)
		(fp_line
			(start 0.849884 1.549908)
			(end -0.849884 1.549908)
			(stroke
				(width 0.1)
				(type default)
			)
			(layer "B.Fab")
		)
		(fp_poly
			(pts
				(xy 2.9464 -1.2192) (xy 2.9464 -0.7112) (xy 2.1844 -0.9652)
			)
			(stroke
				(width 0)
				(type default)
			)
			(fill yes)
			(layer "B.Fab")
		)
		(pad "1" smd rect
			(at 1.225042 -0.94996 270)
			(size 0.4572 1.3208)
			(layers "B.Cu" "B.Mask" "B.Paste")
			(net "JTAG_CPU0_MUX_GTL_TDO")
		)
		(pad "2" smd rect
			(at 1.225042 0 270)
			(size 0.4572 1.3208)
			(layers "B.Cu" "B.Mask" "B.Paste")
			(net "JTAG_MUX_CPU1_GTL_TDI")
		)
		(pad "3" smd rect
			(at 1.225042 0.94996 270)
			(size 0.4572 1.3208)
			(layers "B.Cu" "B.Mask" "B.Paste")
			(net "GND")
		)
		(pad "4" smd rect
			(at -1.225042 0.94996 270)
			(size 0.4572 1.3208)
			(layers "B.Cu" "B.Mask" "B.Paste")
			(net "FM_CPU_EN_R")
		)
		(pad "5" smd rect
			(at -1.225042 -0.94996 270)
			(size 0.4572 1.3208)
			(layers "B.Cu" "B.Mask" "B.Paste")
			(net "P3V3_AUX")
		)
	)
	(footprint ""
		(layer "B.Cu")
		(at 120.458484 -359.596436 -90)
		(property "Reference" "PJ66"
			(at -4.067302 -0.128016 0)
			(unlocked yes)
			(layer "B.SilkS")
			(effects
				(font
					(size 0.7874 0.5842)
					(thickness 0.1524)
				)
				(justify left mirror)
			)
		)
		(property "Value" ""
			(at 0 0 90)
			(layer "B.Fab")
			(effects
				(font
					(size 1.27 1.27)
				)
				(justify mirror)
			)
		)
		(duplicate_pad_numbers_are_jumpers no)
		(pad "1" smd circle
			(at 0.7493 0)
			(size 0 0)
			(layers "B.Cu" "B.Mask" "B.Paste")
			(net "SH_PVPP_HBM_CPU1_P")
		)
		(pad "2" smd rect
			(at -0.7493 0 180)
			(size 0.7112 0.8128)
			(layers "B.Cu" "B.Mask" "B.Paste")
			(net "PVPP_HBM_CPU1")
		)
		(zone
			(layer "B.Cu")
			(hatch none 0.5)
			(connect_pads
				(clearance 0)
			)
			(min_thickness 0.25)
			(keepout
				(tracks allowed)
				(vias not_allowed)
				(pads allowed)
				(copperpour not_allowed)
				(footprints allowed)
			)
			(placement
				(enabled no)
				(sheetname "")
			)
			(fill
				(thermal_gap 0.5)
				(thermal_bridge_width 0.5)
				(island_removal_mode 0)
			)
			(polygon
				(pts
					(xy 120.047258 -358.415336) (xy 120.864884 -358.415336) (xy 120.864884 -360.802936) (xy 120.047258 -360.802936)
				)
			)
		)
	)
	(footprint ""
		(layer "B.Cu")
		(at 211.632546 -321.554856 -90)
		(property "Reference" "C76"
			(at 0 0 90)
			(layer "B.SilkS")
			(hide yes)
			(effects
				(font
					(size 1.27 1.27)
				)
				(justify mirror)
			)
		)
		(property "Value" ""
			(at 0 0 90)
			(layer "B.Fab")
			(effects
				(font
					(size 1.27 1.27)
				)
				(justify mirror)
			)
		)
		(duplicate_pad_numbers_are_jumpers no)
		(fp_line
			(start -1.524 0.762)
			(end 1.524 0.762)
			(stroke
				(width 0.1524)
				(type default)
			)
			(layer "B.SilkS")
		)
		(fp_line
			(start 1.524 0.762)
			(end 1.524 -0.762)
			(stroke
				(width 0.1524)
				(type default)
			)
			(layer "B.SilkS")
		)
		(fp_line
			(start -1.524 -0.762)
			(end -1.524 0.762)
			(stroke
				(width 0.1524)
				(type default)
			)
			(layer "B.SilkS")
		)
		(fp_line
			(start 1.524 -0.762)
			(end -1.524 -0.762)
			(stroke
				(width 0.1524)
				(type default)
			)
			(layer "B.SilkS")
		)
		(fp_line
			(start -1.1049 0.724916)
			(end -1.1049 -0.724916)
			(stroke
				(width 0.1)
				(type default)
			)
			(layer "B.Fab")
		)
		(fp_line
			(start 1.1049 0.724916)
			(end -1.1049 0.724916)
			(stroke
				(width 0.1)
				(type default)
			)
			(layer "B.Fab")
		)
		(fp_line
			(start -1.1049 -0.724916)
			(end 1.1049 -0.724916)
			(stroke
				(width 0.1)
				(type default)
			)
			(layer "B.Fab")
		)
		(fp_line
			(start 1.1049 -0.724916)
			(end 1.1049 0.724916)
			(stroke
				(width 0.1)
				(type default)
			)
			(layer "B.Fab")
		)
		(pad "1" smd rect
			(at 0.889 0 270)
			(size 1.016 1.27)
			(layers "B.Cu" "B.Mask" "B.Paste")
			(net "P12V_S3_AUX_CPU1_NVDIMM")
		)
		(pad "2" smd rect
			(at -0.889 0 270)
			(size 1.016 1.27)
			(layers "B.Cu" "B.Mask" "B.Paste")
			(net "GND")
		)
	)
	(footprint ""
		(layer "B.Cu")
		(at 203.991464 -316.386718 90)
		(property "Reference" "R3906"
			(at 0 0 90)
			(layer "B.SilkS")
			(hide yes)
			(effects
				(font
					(size 1.27 1.27)
				)
				(justify mirror)
			)
		)
		(property "Value" ""
			(at 0 0 90)
			(layer "B.Fab")
			(effects
				(font
					(size 1.27 1.27)
				)
				(justify mirror)
			)
		)
		(duplicate_pad_numbers_are_jumpers no)
		(fp_line
			(start 0.7874 -0.4064)
			(end -0.7874 -0.4064)
			(stroke
				(width 0.1524)
				(type default)
			)
			(layer "B.SilkS")
		)
		(fp_line
			(start -0.7874 -0.4064)
			(end -0.7874 0.4064)
			(stroke
				(width 0.1524)
				(type default)
			)
			(layer "B.SilkS")
		)
		(fp_line
			(start 0.7874 0.4064)
			(end 0.7874 -0.4064)
			(stroke
				(width 0.1524)
				(type default)
			)
			(layer "B.SilkS")
		)
		(fp_line
			(start -0.7874 0.4064)
			(end 0.7874 0.4064)
			(stroke
				(width 0.1524)
				(type default)
			)
			(layer "B.SilkS")
		)
		(fp_line
			(start 0.67945 -0.305054)
			(end 0.12065 -0.305054)
			(stroke
				(width 0.1)
				(type default)
			)
			(layer "B.Fab")
		)
		(fp_line
			(start 0.12065 -0.305054)
			(end 0.12065 -0.2794)
			(stroke
				(width 0.1)
				(type default)
			)
			(layer "B.Fab")
		)
		(fp_line
			(start -0.12065 -0.3048)
			(end -0.67945 -0.3048)
			(stroke
				(width 0.1)
				(type default)
			)
			(layer "B.Fab")
		)
		(fp_line
			(start -0.67945 -0.3048)
			(end -0.67945 0.3048)
			(stroke
				(width 0.1)
				(type default)
			)
			(layer "B.Fab")
		)
		(fp_line
			(start 0.12065 -0.2794)
			(end -0.12065 -0.2794)
			(stroke
				(width 0.1)
				(type default)
			)
			(layer "B.Fab")
		)
		(fp_line
			(start -0.12065 -0.2794)
			(end -0.12065 -0.3048)
			(stroke
				(width 0.1)
				(type default)
			)
			(layer "B.Fab")
		)
		(fp_line
			(start 0.12065 0.2794)
			(end 0.12065 0.3048)
			(stroke
				(width 0.1)
				(type default)
			)
			(layer "B.Fab")
		)
		(fp_line
			(start -0.120396 0.2794)
			(end 0.12065 0.2794)
			(stroke
				(width 0.1)
				(type default)
			)
			(layer "B.Fab")
		)
		(fp_line
			(start 0.67945 0.3048)
			(end 0.67945 -0.305054)
			(stroke
				(width 0.1)
				(type default)
			)
			(layer "B.Fab")
		)
		(fp_line
			(start 0.12065 0.3048)
			(end 0.67945 0.3048)
			(stroke
				(width 0.1)
				(type default)
			)
			(layer "B.Fab")
		)
		(fp_line
			(start -0.120396 0.3048)
			(end -0.120396 0.2794)
			(stroke
				(width 0.1)
				(type default)
			)
			(layer "B.Fab")
		)
		(fp_line
			(start -0.67945 0.3048)
			(end -0.120396 0.3048)
			(stroke
				(width 0.1)
				(type default)
			)
			(layer "B.Fab")
		)
		(pad "1" smd circle
			(at 0.40005 0 270)
			(size 0 0)
			(layers "B.Cu" "B.Mask" "B.Paste")
			(net "I3C_SPD_DDREFGH_CPU1_LVC1_SCL_7")
		)
		(pad "2" smd circle
			(at -0.40005 0 270)
			(size 0 0)
			(layers "B.Cu" "B.Mask" "B.Paste")
			(net "I3C_SPD_DDREFGH_CPU1_LVC1_SCL")
		)
	)
	(footprint ""
		(layer "B.Cu")
		(at 421.853614 -319.263776 180)
		(property "Reference" "C35"
			(at 0 0 0)
			(layer "B.SilkS")
			(hide yes)
			(effects
				(font
					(size 1.27 1.27)
				)
				(justify mirror)
			)
		)
		(property "Value" ""
			(at 0 0 0)
			(layer "B.Fab")
			(effects
				(font
					(size 1.27 1.27)
				)
				(justify mirror)
			)
		)
		(duplicate_pad_numbers_are_jumpers no)
		(fp_line
			(start 0.7874 0.4064)
			(end 0.7874 -0.4064)
			(stroke
				(width 0.1524)
				(type default)
			)
			(layer "B.SilkS")
		)
		(fp_line
			(start 0.7874 -0.4064)
			(end -0.7874 -0.4064)
			(stroke
				(width 0.1524)
				(type default)
			)
			(layer "B.SilkS")
		)
		(fp_line
			(start -0.7874 0.4064)
			(end 0.7874 0.4064)
			(stroke
				(width 0.1524)
				(type default)
			)
			(layer "B.SilkS")
		)
		(fp_line
			(start -0.7874 -0.4064)
			(end -0.7874 0.4064)
			(stroke
				(width 0.1524)
				(type default)
			)
			(layer "B.SilkS")
		)
		(fp_line
			(start 0.67945 0.3048)
			(end 0.67945 -0.305054)
			(stroke
				(width 0.1)
				(type default)
			)
			(layer "B.Fab")
		)
		(fp_line
			(start 0.67945 -0.305054)
			(end 0.12065 -0.305054)
			(stroke
				(width 0.1)
				(type default)
			)
			(layer "B.Fab")
		)
		(fp_line
			(start 0.12065 0.3048)
			(end 0.67945 0.3048)
			(stroke
				(width 0.1)
				(type default)
			)
			(layer "B.Fab")
		)
		(fp_line
			(start 0.12065 0.2794)
			(end 0.12065 0.3048)
			(stroke
				(width 0.1)
				(type default)
			)
			(layer "B.Fab")
		)
		(fp_line
			(start 0.12065 -0.2794)
			(end -0.12065 -0.2794)
			(stroke
				(width 0.1)
				(type default)
			)
			(layer "B.Fab")
		)
		(fp_line
			(start 0.12065 -0.305054)
			(end 0.12065 -0.2794)
			(stroke
				(width 0.1)
				(type default)
			)
			(layer "B.Fab")
		)
		(fp_line
			(start -0.120396 0.3048)
			(end -0.120396 0.2794)
			(stroke
				(width 0.1)
				(type default)
			)
			(layer "B.Fab")
		)
		(fp_line
			(start -0.120396 0.2794)
			(end 0.12065 0.2794)
			(stroke
				(width 0.1)
				(type default)
			)
			(layer "B.Fab")
		)
		(fp_line
			(start -0.12065 -0.2794)
			(end -0.12065 -0.3048)
			(stroke
				(width 0.1)
				(type default)
			)
			(layer "B.Fab")
		)
		(fp_line
			(start -0.12065 -0.3048)
			(end -0.67945 -0.3048)
			(stroke
				(width 0.1)
				(type default)
			)
			(layer "B.Fab")
		)
		(fp_line
			(start -0.67945 0.3048)
			(end -0.120396 0.3048)
			(stroke
				(width 0.1)
				(type default)
			)
			(layer "B.Fab")
		)
		(fp_line
			(start -0.67945 -0.3048)
			(end -0.67945 0.3048)
			(stroke
				(width 0.1)
				(type default)
			)
			(layer "B.Fab")
		)
		(pad "1" smd circle
			(at 0.40005 0)
			(size 0 0)
			(layers "B.Cu" "B.Mask" "B.Paste")
			(net "P3V3_AUX")
		)
		(pad "2" smd circle
			(at -0.40005 0)
			(size 0 0)
			(layers "B.Cu" "B.Mask" "B.Paste")
			(net "GND")
		)
	)
	(footprint ""
		(layer "B.Cu")
		(at 325.168768 -345.774264 -90)
		(property "Reference" "PR137"
			(at 0 0 90)
			(layer "B.SilkS")
			(hide yes)
			(effects
				(font
					(size 1.27 1.27)
				)
				(justify mirror)
			)
		)
		(property "Value" ""
			(at 0 0 90)
			(layer "B.Fab")
			(effects
				(font
					(size 1.27 1.27)
				)
				(justify mirror)
			)
		)
		(duplicate_pad_numbers_are_jumpers no)
		(fp_line
			(start -0.7874 0.4064)
			(end 0.7874 0.4064)
			(stroke
				(width 0.1524)
				(type default)
			)
			(layer "B.SilkS")
		)
		(fp_line
			(start 0.7874 0.4064)
			(end 0.7874 -0.4064)
			(stroke
				(width 0.1524)
				(type default)
			)
			(layer "B.SilkS")
		)
		(fp_line
			(start -0.7874 -0.4064)
			(end -0.7874 0.4064)
			(stroke
				(width 0.1524)
				(type default)
			)
			(layer "B.SilkS")
		)
		(fp_line
			(start 0.7874 -0.4064)
			(end -0.7874 -0.4064)
			(stroke
				(width 0.1524)
				(type default)
			)
			(layer "B.SilkS")
		)
		(fp_line
			(start -0.67945 0.3048)
			(end -0.120396 0.3048)
			(stroke
				(width 0.1)
				(type default)
			)
			(layer "B.Fab")
		)
		(fp_line
			(start -0.120396 0.3048)
			(end -0.120396 0.2794)
			(stroke
				(width 0.1)
				(type default)
			)
			(layer "B.Fab")
		)
		(fp_line
			(start 0.12065 0.3048)
			(end 0.67945 0.3048)
			(stroke
				(width 0.1)
				(type default)
			)
			(layer "B.Fab")
		)
		(fp_line
			(start 0.67945 0.3048)
			(end 0.67945 -0.305054)
			(stroke
				(width 0.1)
				(type default)
			)
			(layer "B.Fab")
		)
		(fp_line
			(start -0.120396 0.2794)
			(end 0.12065 0.2794)
			(stroke
				(width 0.1)
				(type default)
			)
			(layer "B.Fab")
		)
		(fp_line
			(start 0.12065 0.2794)
			(end 0.12065 0.3048)
			(stroke
				(width 0.1)
				(type default)
			)
			(layer "B.Fab")
		)
		(fp_line
			(start -0.12065 -0.2794)
			(end -0.12065 -0.3048)
			(stroke
				(width 0.1)
				(type default)
			)
			(layer "B.Fab")
		)
		(fp_line
			(start 0.12065 -0.2794)
			(end -0.12065 -0.2794)
			(stroke
				(width 0.1)
				(type default)
			)
			(layer "B.Fab")
		)
		(fp_line
			(start -0.67945 -0.3048)
			(end -0.67945 0.3048)
			(stroke
				(width 0.1)
				(type default)
			)
			(layer "B.Fab")
		)
		(fp_line
			(start -0.12065 -0.3048)
			(end -0.67945 -0.3048)
			(stroke
				(width 0.1)
				(type default)
			)
			(layer "B.Fab")
		)
		(fp_line
			(start 0.12065 -0.305054)
			(end 0.12065 -0.2794)
			(stroke
				(width 0.1)
				(type default)
			)
			(layer "B.Fab")
		)
		(fp_line
			(start 0.67945 -0.305054)
			(end 0.12065 -0.305054)
			(stroke
				(width 0.1)
				(type default)
			)
			(layer "B.Fab")
		)
		(pad "1" smd circle
			(at 0.40005 0 90)
			(size 0 0)
			(layers "B.Cu" "B.Mask" "B.Paste")
			(net "PVCCIN_CPU0_VOS7")
		)
		(pad "2" smd circle
			(at -0.40005 0 90)
			(size 0 0)
			(layers "B.Cu" "B.Mask" "B.Paste")
			(net "PVCCIN_CPU0")
		)
	)
	(footprint ""
		(layer "B.Cu")
		(at 245.835424 -100.121212)
		(property "Reference" "R734"
			(at 0 0 0)
			(layer "B.SilkS")
			(hide yes)
			(effects
				(font
					(size 1.27 1.27)
				)
				(justify mirror)
			)
		)
		(property "Value" ""
			(at 0 0 0)
			(layer "B.Fab")
			(effects
				(font
					(size 1.27 1.27)
				)
				(justify mirror)
			)
		)
		(duplicate_pad_numbers_are_jumpers no)
		(fp_line
			(start -0.7874 -0.4064)
			(end -0.7874 0.4064)
			(stroke
				(width 0.1524)
				(type default)
			)
			(layer "B.SilkS")
		)
		(fp_line
			(start -0.7874 0.4064)
			(end 0.7874 0.4064)
			(stroke
				(width 0.1524)
				(type default)
			)
			(layer "B.SilkS")
		)
		(fp_line
			(start 0.7874 -0.4064)
			(end -0.7874 -0.4064)
			(stroke
				(width 0.1524)
				(type default)
			)
			(layer "B.SilkS")
		)
		(fp_line
			(start 0.7874 0.4064)
			(end 0.7874 -0.4064)
			(stroke
				(width 0.1524)
				(type default)
			)
			(layer "B.SilkS")
		)
		(fp_line
			(start -0.67945 -0.3048)
			(end -0.67945 0.3048)
			(stroke
				(width 0.1)
				(type default)
			)
			(layer "B.Fab")
		)
		(fp_line
			(start -0.67945 0.3048)
			(end -0.120396 0.3048)
			(stroke
				(width 0.1)
				(type default)
			)
			(layer "B.Fab")
		)
		(fp_line
			(start -0.12065 -0.3048)
			(end -0.67945 -0.3048)
			(stroke
				(width 0.1)
				(type default)
			)
			(layer "B.Fab")
		)
		(fp_line
			(start -0.12065 -0.2794)
			(end -0.12065 -0.3048)
			(stroke
				(width 0.1)
				(type default)
			)
			(layer "B.Fab")
		)
		(fp_line
			(start -0.120396 0.2794)
			(end 0.12065 0.2794)
			(stroke
				(width 0.1)
				(type default)
			)
			(layer "B.Fab")
		)
		(fp_line
			(start -0.120396 0.3048)
			(end -0.120396 0.2794)
			(stroke
				(width 0.1)
				(type default)
			)
			(layer "B.Fab")
		)
		(fp_line
			(start 0.12065 -0.305054)
			(end 0.12065 -0.2794)
			(stroke
				(width 0.1)
				(type default)
			)
			(layer "B.Fab")
		)
		(fp_line
			(start 0.12065 -0.2794)
			(end -0.12065 -0.2794)
			(stroke
				(width 0.1)
				(type default)
			)
			(layer "B.Fab")
		)
		(fp_line
			(start 0.12065 0.2794)
			(end 0.12065 0.3048)
			(stroke
				(width 0.1)
				(type default)
			)
			(layer "B.Fab")
		)
		(fp_line
			(start 0.12065 0.3048)
			(end 0.67945 0.3048)
			(stroke
				(width 0.1)
				(type default)
			)
			(layer "B.Fab")
		)
		(fp_line
			(start 0.67945 -0.305054)
			(end 0.12065 -0.305054)
			(stroke
				(width 0.1)
				(type default)
			)
			(layer "B.Fab")
		)
		(fp_line
			(start 0.67945 0.3048)
			(end 0.67945 -0.305054)
			(stroke
				(width 0.1)
				(type default)
			)
			(layer "B.Fab")
		)
		(pad "1" smd circle
			(at 0.40005 0 180)
			(size 0 0)
			(layers "B.Cu" "B.Mask" "B.Paste")
			(net "CLK_CK440_SMB_ADDR1")
		)
		(pad "2" smd circle
			(at -0.40005 0 180)
			(size 0 0)
			(layers "B.Cu" "B.Mask" "B.Paste")
			(net "GND")
		)
	)
	(footprint ""
		(layer "B.Cu")
		(at 160.30702 -14.549628 -90)
		(property "Reference" "R592"
			(at 0 0 90)
			(layer "B.SilkS")
			(hide yes)
			(effects
				(font
					(size 1.27 1.27)
				)
				(justify mirror)
			)
		)
		(property "Value" ""
			(at 0 0 90)
			(layer "B.Fab")
			(effects
				(font
					(size 1.27 1.27)
				)
				(justify mirror)
			)
		)
		(duplicate_pad_numbers_are_jumpers no)
		(fp_line
			(start -0.7874 0.4064)
			(end 0.7874 0.4064)
			(stroke
				(width 0.1524)
				(type default)
			)
			(layer "B.SilkS")
		)
		(fp_line
			(start 0.7874 0.4064)
			(end 0.7874 -0.4064)
			(stroke
				(width 0.1524)
				(type default)
			)
			(layer "B.SilkS")
		)
		(fp_line
			(start -0.7874 -0.4064)
			(end -0.7874 0.4064)
			(stroke
				(width 0.1524)
				(type default)
			)
			(layer "B.SilkS")
		)
		(fp_line
			(start 0.7874 -0.4064)
			(end -0.7874 -0.4064)
			(stroke
				(width 0.1524)
				(type default)
			)
			(layer "B.SilkS")
		)
		(fp_line
			(start -0.67945 0.3048)
			(end -0.120396 0.3048)
			(stroke
				(width 0.1)
				(type default)
			)
			(layer "B.Fab")
		)
		(fp_line
			(start -0.120396 0.3048)
			(end -0.120396 0.2794)
			(stroke
				(width 0.1)
				(type default)
			)
			(layer "B.Fab")
		)
		(fp_line
			(start 0.12065 0.3048)
			(end 0.67945 0.3048)
			(stroke
				(width 0.1)
				(type default)
			)
			(layer "B.Fab")
		)
		(fp_line
			(start 0.67945 0.3048)
			(end 0.67945 -0.305054)
			(stroke
				(width 0.1)
				(type default)
			)
			(layer "B.Fab")
		)
		(fp_line
			(start -0.120396 0.2794)
			(end 0.12065 0.2794)
			(stroke
				(width 0.1)
				(type default)
			)
			(layer "B.Fab")
		)
		(fp_line
			(start 0.12065 0.2794)
			(end 0.12065 0.3048)
			(stroke
				(width 0.1)
				(type default)
			)
			(layer "B.Fab")
		)
		(fp_line
			(start -0.12065 -0.2794)
			(end -0.12065 -0.3048)
			(stroke
				(width 0.1)
				(type default)
			)
			(layer "B.Fab")
		)
		(fp_line
			(start 0.12065 -0.2794)
			(end -0.12065 -0.2794)
			(stroke
				(width 0.1)
				(type default)
			)
			(layer "B.Fab")
		)
		(fp_line
			(start -0.67945 -0.3048)
			(end -0.67945 0.3048)
			(stroke
				(width 0.1)
				(type default)
			)
			(layer "B.Fab")
		)
		(fp_line
			(start -0.12065 -0.3048)
			(end -0.67945 -0.3048)
			(stroke
				(width 0.1)
				(type default)
			)
			(layer "B.Fab")
		)
		(fp_line
			(start 0.12065 -0.305054)
			(end 0.12065 -0.2794)
			(stroke
				(width 0.1)
				(type default)
			)
			(layer "B.Fab")
		)
		(fp_line
			(start 0.67945 -0.305054)
			(end 0.12065 -0.305054)
			(stroke
				(width 0.1)
				(type default)
			)
			(layer "B.Fab")
		)
		(pad "1" smd circle
			(at 0.40005 0 90)
			(size 0 0)
			(layers "B.Cu" "B.Mask" "B.Paste")
			(net "SMB_FAN_3V3AUX_SCL")
		)
		(pad "2" smd circle
			(at -0.40005 0 90)
			(size 0 0)
			(layers "B.Cu" "B.Mask" "B.Paste")
			(net "P3V3_AUX")
		)
	)
	(footprint ""
		(layer "B.Cu")
		(at 164.64788 -113.756948 180)
		(property "Reference" "R3486"
			(at 0 0 0)
			(layer "B.SilkS")
			(hide yes)
			(effects
				(font
					(size 1.27 1.27)
				)
				(justify mirror)
			)
		)
		(property "Value" ""
			(at 0 0 0)
			(layer "B.Fab")
			(effects
				(font
					(size 1.27 1.27)
				)
				(justify mirror)
			)
		)
		(duplicate_pad_numbers_are_jumpers no)
		(fp_line
			(start 0.7874 0.4064)
			(end 0.7874 -0.4064)
			(stroke
				(width 0.1524)
				(type default)
			)
			(layer "B.SilkS")
		)
		(fp_line
			(start 0.7874 -0.4064)
			(end -0.7874 -0.4064)
			(stroke
				(width 0.1524)
				(type default)
			)
			(layer "B.SilkS")
		)
		(fp_line
			(start -0.7874 0.4064)
			(end 0.7874 0.4064)
			(stroke
				(width 0.1524)
				(type default)
			)
			(layer "B.SilkS")
		)
		(fp_line
			(start -0.7874 -0.4064)
			(end -0.7874 0.4064)
			(stroke
				(width 0.1524)
				(type default)
			)
			(layer "B.SilkS")
		)
		(fp_line
			(start 0.67945 0.3048)
			(end 0.67945 -0.305054)
			(stroke
				(width 0.1)
				(type default)
			)
			(layer "B.Fab")
		)
		(fp_line
			(start 0.67945 -0.305054)
			(end 0.12065 -0.305054)
			(stroke
				(width 0.1)
				(type default)
			)
			(layer "B.Fab")
		)
		(fp_line
			(start 0.12065 0.3048)
			(end 0.67945 0.3048)
			(stroke
				(width 0.1)
				(type default)
			)
			(layer "B.Fab")
		)
		(fp_line
			(start 0.12065 0.2794)
			(end 0.12065 0.3048)
			(stroke
				(width 0.1)
				(type default)
			)
			(layer "B.Fab")
		)
		(fp_line
			(start 0.12065 -0.2794)
			(end -0.12065 -0.2794)
			(stroke
				(width 0.1)
				(type default)
			)
			(layer "B.Fab")
		)
		(fp_line
			(start 0.12065 -0.305054)
			(end 0.12065 -0.2794)
			(stroke
				(width 0.1)
				(type default)
			)
			(layer "B.Fab")
		)
		(fp_line
			(start -0.120396 0.3048)
			(end -0.120396 0.2794)
			(stroke
				(width 0.1)
				(type default)
			)
			(layer "B.Fab")
		)
		(fp_line
			(start -0.120396 0.2794)
			(end 0.12065 0.2794)
			(stroke
				(width 0.1)
				(type default)
			)
			(layer "B.Fab")
		)
		(fp_line
			(start -0.12065 -0.2794)
			(end -0.12065 -0.3048)
			(stroke
				(width 0.1)
				(type default)
			)
			(layer "B.Fab")
		)
		(fp_line
			(start -0.12065 -0.3048)
			(end -0.67945 -0.3048)
			(stroke
				(width 0.1)
				(type default)
			)
			(layer "B.Fab")
		)
		(fp_line
			(start -0.67945 0.3048)
			(end -0.120396 0.3048)
			(stroke
				(width 0.1)
				(type default)
			)
			(layer "B.Fab")
		)
		(fp_line
			(start -0.67945 -0.3048)
			(end -0.67945 0.3048)
			(stroke
				(width 0.1)
				(type default)
			)
			(layer "B.Fab")
		)
		(pad "1" smd circle
			(at 0.40005 0)
			(size 0 0)
			(layers "B.Cu" "B.Mask" "B.Paste")
			(net "GPU_PRSNT_N_ISO")
		)
		(pad "2" smd circle
			(at -0.40005 0)
			(size 0 0)
			(layers "B.Cu" "B.Mask" "B.Paste")
			(net "GPU_PRSNT_N_ISO_R")
		)
	)
	(footprint ""
		(layer "B.Cu")
		(at 367.778538 -189.56147)
		(property "Reference" "C561"
			(at 0 0 0)
			(layer "B.SilkS")
			(hide yes)
			(effects
				(font
					(size 1.27 1.27)
				)
				(justify mirror)
			)
		)
		(property "Value" ""
			(at 0 0 0)
			(layer "B.Fab")
			(effects
				(font
					(size 1.27 1.27)
				)
				(justify mirror)
			)
		)
		(duplicate_pad_numbers_are_jumpers no)
		(fp_line
			(start -0.7874 -0.4064)
			(end -0.7874 0.4064)
			(stroke
				(width 0.1524)
				(type default)
			)
			(layer "B.SilkS")
		)
		(fp_line
			(start -0.7874 0.4064)
			(end 0.7874 0.4064)
			(stroke
				(width 0.1524)
				(type default)
			)
			(layer "B.SilkS")
		)
		(fp_line
			(start 0.7874 -0.4064)
			(end -0.7874 -0.4064)
			(stroke
				(width 0.1524)
				(type default)
			)
			(layer "B.SilkS")
		)
		(fp_line
			(start 0.7874 0.4064)
			(end 0.7874 -0.4064)
			(stroke
				(width 0.1524)
				(type default)
			)
			(layer "B.SilkS")
		)
		(fp_line
			(start -0.67945 -0.3048)
			(end -0.67945 0.3048)
			(stroke
				(width 0.1)
				(type default)
			)
			(layer "B.Fab")
		)
		(fp_line
			(start -0.67945 0.3048)
			(end -0.120396 0.3048)
			(stroke
				(width 0.1)
				(type default)
			)
			(layer "B.Fab")
		)
		(fp_line
			(start -0.12065 -0.3048)
			(end -0.67945 -0.3048)
			(stroke
				(width 0.1)
				(type default)
			)
			(layer "B.Fab")
		)
		(fp_line
			(start -0.12065 -0.2794)
			(end -0.12065 -0.3048)
			(stroke
				(width 0.1)
				(type default)
			)
			(layer "B.Fab")
		)
		(fp_line
			(start -0.120396 0.2794)
			(end 0.12065 0.2794)
			(stroke
				(width 0.1)
				(type default)
			)
			(layer "B.Fab")
		)
		(fp_line
			(start -0.120396 0.3048)
			(end -0.120396 0.2794)
			(stroke
				(width 0.1)
				(type default)
			)
			(layer "B.Fab")
		)
		(fp_line
			(start 0.12065 -0.305054)
			(end 0.12065 -0.2794)
			(stroke
				(width 0.1)
				(type default)
			)
			(layer "B.Fab")
		)
		(fp_line
			(start 0.12065 -0.2794)
			(end -0.12065 -0.2794)
			(stroke
				(width 0.1)
				(type default)
			)
			(layer "B.Fab")
		)
		(fp_line
			(start 0.12065 0.2794)
			(end 0.12065 0.3048)
			(stroke
				(width 0.1)
				(type default)
			)
			(layer "B.Fab")
		)
		(fp_line
			(start 0.12065 0.3048)
			(end 0.67945 0.3048)
			(stroke
				(width 0.1)
				(type default)
			)
			(layer "B.Fab")
		)
		(fp_line
			(start 0.67945 -0.305054)
			(end 0.12065 -0.305054)
			(stroke
				(width 0.1)
				(type default)
			)
			(layer "B.Fab")
		)
		(fp_line
			(start 0.67945 0.3048)
			(end 0.67945 -0.305054)
			(stroke
				(width 0.1)
				(type default)
			)
			(layer "B.Fab")
		)
		(pad "1" smd circle
			(at 0.40005 0 180)
			(size 0 0)
			(layers "B.Cu" "B.Mask" "B.Paste")
			(net "P3V3_AUX")
		)
		(pad "2" smd circle
			(at -0.40005 0 180)
			(size 0 0)
			(layers "B.Cu" "B.Mask" "B.Paste")
			(net "GND")
		)
	)
	(footprint ""
		(layer "B.Cu")
		(at 163.851082 -8.916924 90)
		(property "Reference" "R589"
			(at 0 0 90)
			(layer "B.SilkS")
			(hide yes)
			(effects
				(font
					(size 1.27 1.27)
				)
				(justify mirror)
			)
		)
		(property "Value" ""
			(at 0 0 90)
			(layer "B.Fab")
			(effects
				(font
					(size 1.27 1.27)
				)
				(justify mirror)
			)
		)
		(duplicate_pad_numbers_are_jumpers no)
		(fp_line
			(start 0.7874 -0.4064)
			(end -0.7874 -0.4064)
			(stroke
				(width 0.1524)
				(type default)
			)
			(layer "B.SilkS")
		)
		(fp_line
			(start -0.7874 -0.4064)
			(end -0.7874 0.4064)
			(stroke
				(width 0.1524)
				(type default)
			)
			(layer "B.SilkS")
		)
		(fp_line
			(start 0.7874 0.4064)
			(end 0.7874 -0.4064)
			(stroke
				(width 0.1524)
				(type default)
			)
			(layer "B.SilkS")
		)
		(fp_line
			(start -0.7874 0.4064)
			(end 0.7874 0.4064)
			(stroke
				(width 0.1524)
				(type default)
			)
			(layer "B.SilkS")
		)
		(fp_line
			(start 0.67945 -0.305054)
			(end 0.12065 -0.305054)
			(stroke
				(width 0.1)
				(type default)
			)
			(layer "B.Fab")
		)
		(fp_line
			(start 0.12065 -0.305054)
			(end 0.12065 -0.2794)
			(stroke
				(width 0.1)
				(type default)
			)
			(layer "B.Fab")
		)
		(fp_line
			(start -0.12065 -0.3048)
			(end -0.67945 -0.3048)
			(stroke
				(width 0.1)
				(type default)
			)
			(layer "B.Fab")
		)
		(fp_line
			(start -0.67945 -0.3048)
			(end -0.67945 0.3048)
			(stroke
				(width 0.1)
				(type default)
			)
			(layer "B.Fab")
		)
		(fp_line
			(start 0.12065 -0.2794)
			(end -0.12065 -0.2794)
			(stroke
				(width 0.1)
				(type default)
			)
			(layer "B.Fab")
		)
		(fp_line
			(start -0.12065 -0.2794)
			(end -0.12065 -0.3048)
			(stroke
				(width 0.1)
				(type default)
			)
			(layer "B.Fab")
		)
		(fp_line
			(start 0.12065 0.2794)
			(end 0.12065 0.3048)
			(stroke
				(width 0.1)
				(type default)
			)
			(layer "B.Fab")
		)
		(fp_line
			(start -0.120396 0.2794)
			(end 0.12065 0.2794)
			(stroke
				(width 0.1)
				(type default)
			)
			(layer "B.Fab")
		)
		(fp_line
			(start 0.67945 0.3048)
			(end 0.67945 -0.305054)
			(stroke
				(width 0.1)
				(type default)
			)
			(layer "B.Fab")
		)
		(fp_line
			(start 0.12065 0.3048)
			(end 0.67945 0.3048)
			(stroke
				(width 0.1)
				(type default)
			)
			(layer "B.Fab")
		)
		(fp_line
			(start -0.120396 0.3048)
			(end -0.120396 0.2794)
			(stroke
				(width 0.1)
				(type default)
			)
			(layer "B.Fab")
		)
		(fp_line
			(start -0.67945 0.3048)
			(end -0.120396 0.3048)
			(stroke
				(width 0.1)
				(type default)
			)
			(layer "B.Fab")
		)
		(pad "1" smd circle
			(at 0.40005 0 270)
			(size 0 0)
			(layers "B.Cu" "B.Mask" "B.Paste")
			(net "SMB_PCIE0_3V3AUX_SDA")
		)
		(pad "2" smd circle
			(at -0.40005 0 270)
			(size 0 0)
			(layers "B.Cu" "B.Mask" "B.Paste")
			(net "SMB_PCIE0_3V3AUX_SDA_R")
		)
	)
	(footprint ""
		(layer "B.Cu")
		(at 292.04285 -362.795058 90)
		(property "Reference" "PC1182_P0_4"
			(at 0 0 90)
			(layer "B.SilkS")
			(hide yes)
			(effects
				(font
					(size 1.27 1.27)
				)
				(justify mirror)
			)
		)
		(property "Value" ""
			(at 0 0 90)
			(layer "B.Fab")
			(effects
				(font
					(size 1.27 1.27)
				)
				(justify mirror)
			)
		)
		(duplicate_pad_numbers_are_jumpers no)
		(fp_line
			(start 1.524 -0.762)
			(end -1.524 -0.762)
			(stroke
				(width 0.1524)
				(type default)
			)
			(layer "B.SilkS")
		)
		(fp_line
			(start -1.524 -0.762)
			(end -1.524 0.762)
			(stroke
				(width 0.1524)
				(type default)
			)
			(layer "B.SilkS")
		)
		(fp_line
			(start 1.524 0.762)
			(end 1.524 -0.762)
			(stroke
				(width 0.1524)
				(type default)
			)
			(layer "B.SilkS")
		)
		(fp_line
			(start -1.524 0.762)
			(end 1.524 0.762)
			(stroke
				(width 0.1524)
				(type default)
			)
			(layer "B.SilkS")
		)
		(fp_line
			(start 1.1049 -0.724916)
			(end 1.1049 0.724916)
			(stroke
				(width 0.1)
				(type default)
			)
			(layer "B.Fab")
		)
		(fp_line
			(start -1.1049 -0.724916)
			(end 1.1049 -0.724916)
			(stroke
				(width 0.1)
				(type default)
			)
			(layer "B.Fab")
		)
		(fp_line
			(start 1.1049 0.724916)
			(end -1.1049 0.724916)
			(stroke
				(width 0.1)
				(type default)
			)
			(layer "B.Fab")
		)
		(fp_line
			(start -1.1049 0.724916)
			(end -1.1049 -0.724916)
			(stroke
				(width 0.1)
				(type default)
			)
			(layer "B.Fab")
		)
		(pad "1" smd rect
			(at 0.889 0 90)
			(size 1.016 1.27)
			(layers "B.Cu" "B.Mask" "B.Paste")
			(net "SW_P12V_PVCCFA_EHV_FIVRA_CPU0_L")
		)
		(pad "2" smd rect
			(at -0.889 0 90)
			(size 1.016 1.27)
			(layers "B.Cu" "B.Mask" "B.Paste")
			(net "GND")
		)
	)
	(footprint ""
		(layer "B.Cu")
		(at 183.172608 -398.651222)
		(property "Reference" "PR3932"
			(at 0 0 0)
			(layer "B.SilkS")
			(hide yes)
			(effects
				(font
					(size 1.27 1.27)
				)
				(justify mirror)
			)
		)
		(property "Value" ""
			(at 0 0 0)
			(layer "B.Fab")
			(effects
				(font
					(size 1.27 1.27)
				)
				(justify mirror)
			)
		)
		(duplicate_pad_numbers_are_jumpers no)
		(fp_line
			(start -0.7874 -0.4064)
			(end -0.7874 0.4064)
			(stroke
				(width 0.1524)
				(type default)
			)
			(layer "B.SilkS")
		)
		(fp_line
			(start -0.7874 0.4064)
			(end 0.7874 0.4064)
			(stroke
				(width 0.1524)
				(type default)
			)
			(layer "B.SilkS")
		)
		(fp_line
			(start 0.7874 -0.4064)
			(end -0.7874 -0.4064)
			(stroke
				(width 0.1524)
				(type default)
			)
			(layer "B.SilkS")
		)
		(fp_line
			(start 0.7874 0.4064)
			(end 0.7874 -0.4064)
			(stroke
				(width 0.1524)
				(type default)
			)
			(layer "B.SilkS")
		)
		(fp_line
			(start -0.67945 -0.3048)
			(end -0.67945 0.3048)
			(stroke
				(width 0.1)
				(type default)
			)
			(layer "B.Fab")
		)
		(fp_line
			(start -0.67945 0.3048)
			(end -0.120396 0.3048)
			(stroke
				(width 0.1)
				(type default)
			)
			(layer "B.Fab")
		)
		(fp_line
			(start -0.12065 -0.3048)
			(end -0.67945 -0.3048)
			(stroke
				(width 0.1)
				(type default)
			)
			(layer "B.Fab")
		)
		(fp_line
			(start -0.12065 -0.2794)
			(end -0.12065 -0.3048)
			(stroke
				(width 0.1)
				(type default)
			)
			(layer "B.Fab")
		)
		(fp_line
			(start -0.120396 0.2794)
			(end 0.12065 0.2794)
			(stroke
				(width 0.1)
				(type default)
			)
			(layer "B.Fab")
		)
		(fp_line
			(start -0.120396 0.3048)
			(end -0.120396 0.2794)
			(stroke
				(width 0.1)
				(type default)
			)
			(layer "B.Fab")
		)
		(fp_line
			(start 0.12065 -0.305054)
			(end 0.12065 -0.2794)
			(stroke
				(width 0.1)
				(type default)
			)
			(layer "B.Fab")
		)
		(fp_line
			(start 0.12065 -0.2794)
			(end -0.12065 -0.2794)
			(stroke
				(width 0.1)
				(type default)
			)
			(layer "B.Fab")
		)
		(fp_line
			(start 0.12065 0.2794)
			(end 0.12065 0.3048)
			(stroke
				(width 0.1)
				(type default)
			)
			(layer "B.Fab")
		)
		(fp_line
			(start 0.12065 0.3048)
			(end 0.67945 0.3048)
			(stroke
				(width 0.1)
				(type default)
			)
			(layer "B.Fab")
		)
		(fp_line
			(start 0.67945 -0.305054)
			(end 0.12065 -0.305054)
			(stroke
				(width 0.1)
				(type default)
			)
			(layer "B.Fab")
		)
		(fp_line
			(start 0.67945 0.3048)
			(end 0.67945 -0.305054)
			(stroke
				(width 0.1)
				(type default)
			)
			(layer "B.Fab")
		)
		(pad "1" smd circle
			(at 0.40005 0 180)
			(size 0 0)
			(layers "B.Cu" "B.Mask" "B.Paste")
			(net "HSC_VOSEN")
		)
		(pad "2" smd circle
			(at -0.40005 0 180)
			(size 0 0)
			(layers "B.Cu" "B.Mask" "B.Paste")
			(net "AGND_HSC")
		)
	)
	(footprint ""
		(layer "B.Cu")
		(at 160.83788 -123.916948)
		(property "Reference" "R988"
			(at 0 0 0)
			(layer "B.SilkS")
			(hide yes)
			(effects
				(font
					(size 1.27 1.27)
				)
				(justify mirror)
			)
		)
		(property "Value" ""
			(at 0 0 0)
			(layer "B.Fab")
			(effects
				(font
					(size 1.27 1.27)
				)
				(justify mirror)
			)
		)
		(duplicate_pad_numbers_are_jumpers no)
		(fp_line
			(start -0.7874 -0.4064)
			(end -0.7874 0.4064)
			(stroke
				(width 0.1524)
				(type default)
			)
			(layer "B.SilkS")
		)
		(fp_line
			(start -0.7874 0.4064)
			(end 0.7874 0.4064)
			(stroke
				(width 0.1524)
				(type default)
			)
			(layer "B.SilkS")
		)
		(fp_line
			(start 0.7874 -0.4064)
			(end -0.7874 -0.4064)
			(stroke
				(width 0.1524)
				(type default)
			)
			(layer "B.SilkS")
		)
		(fp_line
			(start 0.7874 0.4064)
			(end 0.7874 -0.4064)
			(stroke
				(width 0.1524)
				(type default)
			)
			(layer "B.SilkS")
		)
		(fp_line
			(start -0.67945 -0.3048)
			(end -0.67945 0.3048)
			(stroke
				(width 0.1)
				(type default)
			)
			(layer "B.Fab")
		)
		(fp_line
			(start -0.67945 0.3048)
			(end -0.120396 0.3048)
			(stroke
				(width 0.1)
				(type default)
			)
			(layer "B.Fab")
		)
		(fp_line
			(start -0.12065 -0.3048)
			(end -0.67945 -0.3048)
			(stroke
				(width 0.1)
				(type default)
			)
			(layer "B.Fab")
		)
		(fp_line
			(start -0.12065 -0.2794)
			(end -0.12065 -0.3048)
			(stroke
				(width 0.1)
				(type default)
			)
			(layer "B.Fab")
		)
		(fp_line
			(start -0.120396 0.2794)
			(end 0.12065 0.2794)
			(stroke
				(width 0.1)
				(type default)
			)
			(layer "B.Fab")
		)
		(fp_line
			(start -0.120396 0.3048)
			(end -0.120396 0.2794)
			(stroke
				(width 0.1)
				(type default)
			)
			(layer "B.Fab")
		)
		(fp_line
			(start 0.12065 -0.305054)
			(end 0.12065 -0.2794)
			(stroke
				(width 0.1)
				(type default)
			)
			(layer "B.Fab")
		)
		(fp_line
			(start 0.12065 -0.2794)
			(end -0.12065 -0.2794)
			(stroke
				(width 0.1)
				(type default)
			)
			(layer "B.Fab")
		)
		(fp_line
			(start 0.12065 0.2794)
			(end 0.12065 0.3048)
			(stroke
				(width 0.1)
				(type default)
			)
			(layer "B.Fab")
		)
		(fp_line
			(start 0.12065 0.3048)
			(end 0.67945 0.3048)
			(stroke
				(width 0.1)
				(type default)
			)
			(layer "B.Fab")
		)
		(fp_line
			(start 0.67945 -0.305054)
			(end 0.12065 -0.305054)
			(stroke
				(width 0.1)
				(type default)
			)
			(layer "B.Fab")
		)
		(fp_line
			(start 0.67945 0.3048)
			(end 0.67945 -0.305054)
			(stroke
				(width 0.1)
				(type default)
			)
			(layer "B.Fab")
		)
		(pad "1" smd circle
			(at 0.40005 0 180)
			(size 0 0)
			(layers "B.Cu" "B.Mask" "B.Paste")
			(net "FM_PVCCFA_EHV_FIVRA_CPU1_R_EN")
		)
		(pad "2" smd circle
			(at -0.40005 0 180)
			(size 0 0)
			(layers "B.Cu" "B.Mask" "B.Paste")
			(net "FM_PVCCFA_EHV_FIVRA_CPU1_EN")
		)
	)
	(footprint ""
		(layer "B.Cu")
		(at 126.89586 -22.794468 90)
		(property "Reference" "R4292"
			(at 0 0 90)
			(layer "B.SilkS")
			(hide yes)
			(effects
				(font
					(size 1.27 1.27)
				)
				(justify mirror)
			)
		)
		(property "Value" ""
			(at 0 0 90)
			(layer "B.Fab")
			(effects
				(font
					(size 1.27 1.27)
				)
				(justify mirror)
			)
		)
		(duplicate_pad_numbers_are_jumpers no)
		(fp_line
			(start 0.7874 -0.4064)
			(end -0.7874 -0.4064)
			(stroke
				(width 0.1524)
				(type default)
			)
			(layer "B.SilkS")
		)
		(fp_line
			(start -0.7874 -0.4064)
			(end -0.7874 0.4064)
			(stroke
				(width 0.1524)
				(type default)
			)
			(layer "B.SilkS")
		)
		(fp_line
			(start 0.7874 0.4064)
			(end 0.7874 -0.4064)
			(stroke
				(width 0.1524)
				(type default)
			)
			(layer "B.SilkS")
		)
		(fp_line
			(start -0.7874 0.4064)
			(end 0.7874 0.4064)
			(stroke
				(width 0.1524)
				(type default)
			)
			(layer "B.SilkS")
		)
		(fp_line
			(start 0.67945 -0.305054)
			(end 0.12065 -0.305054)
			(stroke
				(width 0.1)
				(type default)
			)
			(layer "B.Fab")
		)
		(fp_line
			(start 0.12065 -0.305054)
			(end 0.12065 -0.2794)
			(stroke
				(width 0.1)
				(type default)
			)
			(layer "B.Fab")
		)
		(fp_line
			(start -0.12065 -0.3048)
			(end -0.67945 -0.3048)
			(stroke
				(width 0.1)
				(type default)
			)
			(layer "B.Fab")
		)
		(fp_line
			(start -0.67945 -0.3048)
			(end -0.67945 0.3048)
			(stroke
				(width 0.1)
				(type default)
			)
			(layer "B.Fab")
		)
		(fp_line
			(start 0.12065 -0.2794)
			(end -0.12065 -0.2794)
			(stroke
				(width 0.1)
				(type default)
			)
			(layer "B.Fab")
		)
		(fp_line
			(start -0.12065 -0.2794)
			(end -0.12065 -0.3048)
			(stroke
				(width 0.1)
				(type default)
			)
			(layer "B.Fab")
		)
		(fp_line
			(start 0.12065 0.2794)
			(end 0.12065 0.3048)
			(stroke
				(width 0.1)
				(type default)
			)
			(layer "B.Fab")
		)
		(fp_line
			(start -0.120396 0.2794)
			(end 0.12065 0.2794)
			(stroke
				(width 0.1)
				(type default)
			)
			(layer "B.Fab")
		)
		(fp_line
			(start 0.67945 0.3048)
			(end 0.67945 -0.305054)
			(stroke
				(width 0.1)
				(type default)
			)
			(layer "B.Fab")
		)
		(fp_line
			(start 0.12065 0.3048)
			(end 0.67945 0.3048)
			(stroke
				(width 0.1)
				(type default)
			)
			(layer "B.Fab")
		)
		(fp_line
			(start -0.120396 0.3048)
			(end -0.120396 0.2794)
			(stroke
				(width 0.1)
				(type default)
			)
			(layer "B.Fab")
		)
		(fp_line
			(start -0.67945 0.3048)
			(end -0.120396 0.3048)
			(stroke
				(width 0.1)
				(type default)
			)
			(layer "B.Fab")
		)
		(pad "1" smd circle
			(at 0.40005 0 270)
			(size 0 0)
			(layers "B.Cu" "B.Mask" "B.Paste")
			(net "FM_USB3_1_EN_N")
		)
		(pad "2" smd circle
			(at -0.40005 0 270)
			(size 0 0)
			(layers "B.Cu" "B.Mask" "B.Paste")
			(net "GND")
		)
	)
	(footprint ""
		(layer "B.Cu")
		(at 365.438436 -324.911466 -90)
		(property "Reference" "PC291_P0_3"
			(at 0 0 90)
			(layer "B.SilkS")
			(hide yes)
			(effects
				(font
					(size 1.27 1.27)
				)
				(justify mirror)
			)
		)
		(property "Value" ""
			(at 0 0 90)
			(layer "B.Fab")
			(effects
				(font
					(size 1.27 1.27)
				)
				(justify mirror)
			)
		)
		(duplicate_pad_numbers_are_jumpers no)
		(fp_line
			(start -1.524 0.762)
			(end 1.524 0.762)
			(stroke
				(width 0.1524)
				(type default)
			)
			(layer "B.SilkS")
		)
		(fp_line
			(start 1.524 0.762)
			(end 1.524 -0.762)
			(stroke
				(width 0.1524)
				(type default)
			)
			(layer "B.SilkS")
		)
		(fp_line
			(start -1.524 -0.762)
			(end -1.524 0.762)
			(stroke
				(width 0.1524)
				(type default)
			)
			(layer "B.SilkS")
		)
		(fp_line
			(start 1.524 -0.762)
			(end -1.524 -0.762)
			(stroke
				(width 0.1524)
				(type default)
			)
			(layer "B.SilkS")
		)
		(fp_line
			(start -1.1049 0.724916)
			(end -1.1049 -0.724916)
			(stroke
				(width 0.1)
				(type default)
			)
			(layer "B.Fab")
		)
		(fp_line
			(start 1.1049 0.724916)
			(end -1.1049 0.724916)
			(stroke
				(width 0.1)
				(type default)
			)
			(layer "B.Fab")
		)
		(fp_line
			(start -1.1049 -0.724916)
			(end 1.1049 -0.724916)
			(stroke
				(width 0.1)
				(type default)
			)
			(layer "B.Fab")
		)
		(fp_line
			(start 1.1049 -0.724916)
			(end 1.1049 0.724916)
			(stroke
				(width 0.1)
				(type default)
			)
			(layer "B.Fab")
		)
		(pad "1" smd rect
			(at 0.889 0 270)
			(size 1.016 1.27)
			(layers "B.Cu" "B.Mask" "B.Paste")
			(net "PVCCIN_CPU0")
		)
		(pad "2" smd rect
			(at -0.889 0 270)
			(size 1.016 1.27)
			(layers "B.Cu" "B.Mask" "B.Paste")
			(net "GND")
		)
	)
	(footprint ""
		(layer "B.Cu")
		(at 365.037624 -183.101488 90)
		(property "Reference" "Q15"
			(at 2.23901 -2.577084 0)
			(unlocked yes)
			(layer "B.SilkS")
			(effects
				(font
					(size 0.7874 0.5842)
					(thickness 0.1524)
				)
				(justify left mirror)
			)
		)
		(property "Value" ""
			(at 0 0 90)
			(layer "B.Fab")
			(effects
				(font
					(size 1.27 1.27)
				)
				(justify mirror)
			)
		)
		(duplicate_pad_numbers_are_jumpers no)
		(fp_line
			(start 1.332738 -1.100074)
			(end 0.4826 -1.100074)
			(stroke
				(width 0.1524)
				(type default)
			)
			(layer "B.SilkS")
		)
		(fp_line
			(start 0.4826 -1.100074)
			(end 0 -0.541274)
			(stroke
				(width 0.1524)
				(type default)
			)
			(layer "B.SilkS")
		)
		(fp_line
			(start -0.4826 -1.100074)
			(end -1.332738 -1.100074)
			(stroke
				(width 0.1524)
				(type default)
			)
			(layer "B.SilkS")
		)
		(fp_line
			(start -1.332738 -1.100074)
			(end -1.332738 1.100074)
			(stroke
				(width 0.1524)
				(type default)
			)
			(layer "B.SilkS")
		)
		(fp_line
			(start 0 -0.541274)
			(end -0.4826 -1.100074)
			(stroke
				(width 0.1524)
				(type default)
			)
			(layer "B.SilkS")
		)
		(fp_line
			(start 1.332738 1.100074)
			(end 1.332738 -1.100074)
			(stroke
				(width 0.1524)
				(type default)
			)
			(layer "B.SilkS")
		)
		(fp_line
			(start -1.332738 1.100074)
			(end 1.332738 1.100074)
			(stroke
				(width 0.1524)
				(type default)
			)
			(layer "B.SilkS")
		)
		(fp_poly
			(pts
				(xy 2.2352 -0.298958) (xy 1.533144 -0.649986) (xy 2.2352 -1.001014)
			)
			(stroke
				(width 0)
				(type default)
			)
			(fill yes)
			(layer "B.SilkS")
		)
		(fp_line
			(start 0.674878 -1.100074)
			(end -0.674878 -1.100074)
			(stroke
				(width 0.1)
				(type default)
			)
			(layer "B.Fab")
		)
		(fp_line
			(start -0.674878 -1.100074)
			(end -0.674878 1.100074)
			(stroke
				(width 0.1)
				(type default)
			)
			(layer "B.Fab")
		)
		(fp_line
			(start 0.674878 1.100074)
			(end 0.674878 -1.100074)
			(stroke
				(width 0.1)
				(type default)
			)
			(layer "B.Fab")
		)
		(fp_line
			(start -0.674878 1.100074)
			(end 0.674878 1.100074)
			(stroke
				(width 0.1)
				(type default)
			)
			(layer "B.Fab")
		)
		(fp_poly
			(pts
				(xy 2.2352 -0.298958) (xy 2.2352 -1.001014) (xy 1.533144 -0.649986)
			)
			(stroke
				(width 0)
				(type default)
			)
			(fill yes)
			(layer "B.Fab")
		)
		(pad "1" smd rect
			(at 0.94996 -0.649986 180)
			(size 0.4318 0.508)
			(layers "B.Cu" "B.Mask" "B.Paste")
			(net "GND")
		)
		(pad "2" smd rect
			(at 0.94996 0 180)
			(size 0.4318 0.508)
			(layers "B.Cu" "B.Mask" "B.Paste")
			(net "FM_SMB_PEHPCPU0_PCIE_ALERT_R_N")
		)
		(pad "3" smd rect
			(at 0.94996 0.649986 180)
			(size 0.4318 0.508)
			(layers "B.Cu" "B.Mask" "B.Paste")
			(net "FM_PEHPCPU0_ALERT_N")
		)
		(pad "4" smd rect
			(at -0.94996 0.649986 180)
			(size 0.4318 0.508)
			(layers "B.Cu" "B.Mask" "B.Paste")
			(net "GND")
		)
		(pad "5" smd rect
			(at -0.94996 0 180)
			(size 0.4318 0.508)
			(layers "B.Cu" "B.Mask" "B.Paste")
			(net "FM_SMB_CPU0_ALERT_R1")
		)
		(pad "6" smd rect
			(at -0.94996 -0.649986 180)
			(size 0.4318 0.508)
			(layers "B.Cu" "B.Mask" "B.Paste")
			(net "FM_SMB_CPU0_ALERT_R1")
		)
	)
	(footprint ""
		(layer "B.Cu")
		(at 318.554862 -191.122046 180)
		(property "Reference" "R1009"
			(at 0 0 0)
			(layer "B.SilkS")
			(hide yes)
			(effects
				(font
					(size 1.27 1.27)
				)
				(justify mirror)
			)
		)
		(property "Value" ""
			(at 0 0 0)
			(layer "B.Fab")
			(effects
				(font
					(size 1.27 1.27)
				)
				(justify mirror)
			)
		)
		(duplicate_pad_numbers_are_jumpers no)
		(fp_line
			(start 0.7874 0.4064)
			(end 0.7874 -0.4064)
			(stroke
				(width 0.1524)
				(type default)
			)
			(layer "B.SilkS")
		)
		(fp_line
			(start 0.7874 -0.4064)
			(end -0.7874 -0.4064)
			(stroke
				(width 0.1524)
				(type default)
			)
			(layer "B.SilkS")
		)
		(fp_line
			(start -0.7874 0.4064)
			(end 0.7874 0.4064)
			(stroke
				(width 0.1524)
				(type default)
			)
			(layer "B.SilkS")
		)
		(fp_line
			(start -0.7874 -0.4064)
			(end -0.7874 0.4064)
			(stroke
				(width 0.1524)
				(type default)
			)
			(layer "B.SilkS")
		)
		(fp_line
			(start 0.67945 0.3048)
			(end 0.67945 -0.305054)
			(stroke
				(width 0.1)
				(type default)
			)
			(layer "B.Fab")
		)
		(fp_line
			(start 0.67945 -0.305054)
			(end 0.12065 -0.305054)
			(stroke
				(width 0.1)
				(type default)
			)
			(layer "B.Fab")
		)
		(fp_line
			(start 0.12065 0.3048)
			(end 0.67945 0.3048)
			(stroke
				(width 0.1)
				(type default)
			)
			(layer "B.Fab")
		)
		(fp_line
			(start 0.12065 0.2794)
			(end 0.12065 0.3048)
			(stroke
				(width 0.1)
				(type default)
			)
			(layer "B.Fab")
		)
		(fp_line
			(start 0.12065 -0.2794)
			(end -0.12065 -0.2794)
			(stroke
				(width 0.1)
				(type default)
			)
			(layer "B.Fab")
		)
		(fp_line
			(start 0.12065 -0.305054)
			(end 0.12065 -0.2794)
			(stroke
				(width 0.1)
				(type default)
			)
			(layer "B.Fab")
		)
		(fp_line
			(start -0.120396 0.3048)
			(end -0.120396 0.2794)
			(stroke
				(width 0.1)
				(type default)
			)
			(layer "B.Fab")
		)
		(fp_line
			(start -0.120396 0.2794)
			(end 0.12065 0.2794)
			(stroke
				(width 0.1)
				(type default)
			)
			(layer "B.Fab")
		)
		(fp_line
			(start -0.12065 -0.2794)
			(end -0.12065 -0.3048)
			(stroke
				(width 0.1)
				(type default)
			)
			(layer "B.Fab")
		)
		(fp_line
			(start -0.12065 -0.3048)
			(end -0.67945 -0.3048)
			(stroke
				(width 0.1)
				(type default)
			)
			(layer "B.Fab")
		)
		(fp_line
			(start -0.67945 0.3048)
			(end -0.120396 0.3048)
			(stroke
				(width 0.1)
				(type default)
			)
			(layer "B.Fab")
		)
		(fp_line
			(start -0.67945 -0.3048)
			(end -0.67945 0.3048)
			(stroke
				(width 0.1)
				(type default)
			)
			(layer "B.Fab")
		)
		(pad "1" smd circle
			(at 0.40005 0)
			(size 0 0)
			(layers "B.Cu" "B.Mask" "B.Paste")
			(net "PVNN_TERM_CPU0")
		)
		(pad "2" smd circle
			(at -0.40005 0)
			(size 0 0)
			(layers "B.Cu" "B.Mask" "B.Paste")
			(net "PU_TAP_ODT_CPU0_EN")
		)
	)
	(footprint ""
		(layer "B.Cu")
		(at 175.174402 -103.098346 90)
		(property "Reference" "R160"
			(at 0 0 90)
			(layer "B.SilkS")
			(hide yes)
			(effects
				(font
					(size 1.27 1.27)
				)
				(justify mirror)
			)
		)
		(property "Value" ""
			(at 0 0 90)
			(layer "B.Fab")
			(effects
				(font
					(size 1.27 1.27)
				)
				(justify mirror)
			)
		)
		(duplicate_pad_numbers_are_jumpers no)
		(fp_line
			(start 0.7874 -0.4064)
			(end -0.7874 -0.4064)
			(stroke
				(width 0.1524)
				(type default)
			)
			(layer "B.SilkS")
		)
		(fp_line
			(start -0.7874 -0.4064)
			(end -0.7874 0.4064)
			(stroke
				(width 0.1524)
				(type default)
			)
			(layer "B.SilkS")
		)
		(fp_line
			(start 0.7874 0.4064)
			(end 0.7874 -0.4064)
			(stroke
				(width 0.1524)
				(type default)
			)
			(layer "B.SilkS")
		)
		(fp_line
			(start -0.7874 0.4064)
			(end 0.7874 0.4064)
			(stroke
				(width 0.1524)
				(type default)
			)
			(layer "B.SilkS")
		)
		(fp_line
			(start 0.67945 -0.305054)
			(end 0.12065 -0.305054)
			(stroke
				(width 0.1)
				(type default)
			)
			(layer "B.Fab")
		)
		(fp_line
			(start 0.12065 -0.305054)
			(end 0.12065 -0.2794)
			(stroke
				(width 0.1)
				(type default)
			)
			(layer "B.Fab")
		)
		(fp_line
			(start -0.12065 -0.3048)
			(end -0.67945 -0.3048)
			(stroke
				(width 0.1)
				(type default)
			)
			(layer "B.Fab")
		)
		(fp_line
			(start -0.67945 -0.3048)
			(end -0.67945 0.3048)
			(stroke
				(width 0.1)
				(type default)
			)
			(layer "B.Fab")
		)
		(fp_line
			(start 0.12065 -0.2794)
			(end -0.12065 -0.2794)
			(stroke
				(width 0.1)
				(type default)
			)
			(layer "B.Fab")
		)
		(fp_line
			(start -0.12065 -0.2794)
			(end -0.12065 -0.3048)
			(stroke
				(width 0.1)
				(type default)
			)
			(layer "B.Fab")
		)
		(fp_line
			(start 0.12065 0.2794)
			(end 0.12065 0.3048)
			(stroke
				(width 0.1)
				(type default)
			)
			(layer "B.Fab")
		)
		(fp_line
			(start -0.120396 0.2794)
			(end 0.12065 0.2794)
			(stroke
				(width 0.1)
				(type default)
			)
			(layer "B.Fab")
		)
		(fp_line
			(start 0.67945 0.3048)
			(end 0.67945 -0.305054)
			(stroke
				(width 0.1)
				(type default)
			)
			(layer "B.Fab")
		)
		(fp_line
			(start 0.12065 0.3048)
			(end 0.67945 0.3048)
			(stroke
				(width 0.1)
				(type default)
			)
			(layer "B.Fab")
		)
		(fp_line
			(start -0.120396 0.3048)
			(end -0.120396 0.2794)
			(stroke
				(width 0.1)
				(type default)
			)
			(layer "B.Fab")
		)
		(fp_line
			(start -0.67945 0.3048)
			(end -0.120396 0.3048)
			(stroke
				(width 0.1)
				(type default)
			)
			(layer "B.Fab")
		)
		(pad "1" smd circle
			(at 0.40005 0 270)
			(size 0 0)
			(layers "B.Cu" "B.Mask" "B.Paste")
			(net "PWRGD_DRAMPWRGD_CPU0_AB_R_LVC1")
		)
		(pad "2" smd circle
			(at -0.40005 0 270)
			(size 0 0)
			(layers "B.Cu" "B.Mask" "B.Paste")
			(net "PWRGD_DRAMPWRGD_CPU0_AB_LVC1_R2")
		)
	)
	(footprint ""
		(layer "B.Cu")
		(at 111.310166 -212.049868)
		(property "Reference" "C463"
			(at 0 0 0)
			(layer "B.SilkS")
			(hide yes)
			(effects
				(font
					(size 1.27 1.27)
				)
				(justify mirror)
			)
		)
		(property "Value" ""
			(at 0 0 0)
			(layer "B.Fab")
			(effects
				(font
					(size 1.27 1.27)
				)
				(justify mirror)
			)
		)
		(duplicate_pad_numbers_are_jumpers no)
		(fp_line
			(start -1.524 -0.762)
			(end -1.524 0.762)
			(stroke
				(width 0.1524)
				(type default)
			)
			(layer "B.SilkS")
		)
		(fp_line
			(start -1.524 0.762)
			(end 1.524 0.762)
			(stroke
				(width 0.1524)
				(type default)
			)
			(layer "B.SilkS")
		)
		(fp_line
			(start 1.524 -0.762)
			(end -1.524 -0.762)
			(stroke
				(width 0.1524)
				(type default)
			)
			(layer "B.SilkS")
		)
		(fp_line
			(start 1.524 0.762)
			(end 1.524 -0.762)
			(stroke
				(width 0.1524)
				(type default)
			)
			(layer "B.SilkS")
		)
		(fp_line
			(start -1.1049 -0.724916)
			(end 1.1049 -0.724916)
			(stroke
				(width 0.1)
				(type default)
			)
			(layer "B.Fab")
		)
		(fp_line
			(start -1.1049 0.724916)
			(end -1.1049 -0.724916)
			(stroke
				(width 0.1)
				(type default)
			)
			(layer "B.Fab")
		)
		(fp_line
			(start 1.1049 -0.724916)
			(end 1.1049 0.724916)
			(stroke
				(width 0.1)
				(type default)
			)
			(layer "B.Fab")
		)
		(fp_line
			(start 1.1049 0.724916)
			(end -1.1049 0.724916)
			(stroke
				(width 0.1)
				(type default)
			)
			(layer "B.Fab")
		)
		(pad "1" smd rect
			(at 0.889 0)
			(size 1.016 1.27)
			(layers "B.Cu" "B.Mask" "B.Paste")
			(net "PVCCD_HV_CPU1")
		)
		(pad "2" smd rect
			(at -0.889 0)
			(size 1.016 1.27)
			(layers "B.Cu" "B.Mask" "B.Paste")
			(net "GND")
		)
	)
	(footprint ""
		(layer "B.Cu")
		(at 10.558272 -183.482996)
		(property "Reference" "R968"
			(at 0 0 0)
			(layer "B.SilkS")
			(hide yes)
			(effects
				(font
					(size 1.27 1.27)
				)
				(justify mirror)
			)
		)
		(property "Value" ""
			(at 0 0 0)
			(layer "B.Fab")
			(effects
				(font
					(size 1.27 1.27)
				)
				(justify mirror)
			)
		)
		(duplicate_pad_numbers_are_jumpers no)
		(fp_line
			(start -0.7874 -0.4064)
			(end -0.7874 0.4064)
			(stroke
				(width 0.1524)
				(type default)
			)
			(layer "B.SilkS")
		)
		(fp_line
			(start -0.7874 0.4064)
			(end 0.7874 0.4064)
			(stroke
				(width 0.1524)
				(type default)
			)
			(layer "B.SilkS")
		)
		(fp_line
			(start 0.7874 -0.4064)
			(end -0.7874 -0.4064)
			(stroke
				(width 0.1524)
				(type default)
			)
			(layer "B.SilkS")
		)
		(fp_line
			(start 0.7874 0.4064)
			(end 0.7874 -0.4064)
			(stroke
				(width 0.1524)
				(type default)
			)
			(layer "B.SilkS")
		)
		(fp_line
			(start -0.67945 -0.3048)
			(end -0.67945 0.3048)
			(stroke
				(width 0.1)
				(type default)
			)
			(layer "B.Fab")
		)
		(fp_line
			(start -0.67945 0.3048)
			(end -0.120396 0.3048)
			(stroke
				(width 0.1)
				(type default)
			)
			(layer "B.Fab")
		)
		(fp_line
			(start -0.12065 -0.3048)
			(end -0.67945 -0.3048)
			(stroke
				(width 0.1)
				(type default)
			)
			(layer "B.Fab")
		)
		(fp_line
			(start -0.12065 -0.2794)
			(end -0.12065 -0.3048)
			(stroke
				(width 0.1)
				(type default)
			)
			(layer "B.Fab")
		)
		(fp_line
			(start -0.120396 0.2794)
			(end 0.12065 0.2794)
			(stroke
				(width 0.1)
				(type default)
			)
			(layer "B.Fab")
		)
		(fp_line
			(start -0.120396 0.3048)
			(end -0.120396 0.2794)
			(stroke
				(width 0.1)
				(type default)
			)
			(layer "B.Fab")
		)
		(fp_line
			(start 0.12065 -0.305054)
			(end 0.12065 -0.2794)
			(stroke
				(width 0.1)
				(type default)
			)
			(layer "B.Fab")
		)
		(fp_line
			(start 0.12065 -0.2794)
			(end -0.12065 -0.2794)
			(stroke
				(width 0.1)
				(type default)
			)
			(layer "B.Fab")
		)
		(fp_line
			(start 0.12065 0.2794)
			(end 0.12065 0.3048)
			(stroke
				(width 0.1)
				(type default)
			)
			(layer "B.Fab")
		)
		(fp_line
			(start 0.12065 0.3048)
			(end 0.67945 0.3048)
			(stroke
				(width 0.1)
				(type default)
			)
			(layer "B.Fab")
		)
		(fp_line
			(start 0.67945 -0.305054)
			(end 0.12065 -0.305054)
			(stroke
				(width 0.1)
				(type default)
			)
			(layer "B.Fab")
		)
		(fp_line
			(start 0.67945 0.3048)
			(end 0.67945 -0.305054)
			(stroke
				(width 0.1)
				(type default)
			)
			(layer "B.Fab")
		)
		(pad "1" smd circle
			(at 0.40005 0 180)
			(size 0 0)
			(layers "B.Cu" "B.Mask" "B.Paste")
			(net "P3V3_AUX")
		)
		(pad "2" smd circle
			(at -0.40005 0 180)
			(size 0 0)
			(layers "B.Cu" "B.Mask" "B.Paste")
			(net "SMB_PEHPCPU1_LVC3_SDA")
		)
	)
	(footprint ""
		(layer "B.Cu")
		(at 351.26803 -359.103168 180)
		(property "Reference" "R2373"
			(at 0 0 0)
			(layer "B.SilkS")
			(hide yes)
			(effects
				(font
					(size 1.27 1.27)
				)
				(justify mirror)
			)
		)
		(property "Value" ""
			(at 0 0 0)
			(layer "B.Fab")
			(effects
				(font
					(size 1.27 1.27)
				)
				(justify mirror)
			)
		)
		(duplicate_pad_numbers_are_jumpers no)
		(fp_line
			(start 0.7874 0.4064)
			(end 0.7874 -0.4064)
			(stroke
				(width 0.1524)
				(type default)
			)
			(layer "B.SilkS")
		)
		(fp_line
			(start 0.7874 -0.4064)
			(end -0.7874 -0.4064)
			(stroke
				(width 0.1524)
				(type default)
			)
			(layer "B.SilkS")
		)
		(fp_line
			(start -0.7874 0.4064)
			(end 0.7874 0.4064)
			(stroke
				(width 0.1524)
				(type default)
			)
			(layer "B.SilkS")
		)
		(fp_line
			(start -0.7874 -0.4064)
			(end -0.7874 0.4064)
			(stroke
				(width 0.1524)
				(type default)
			)
			(layer "B.SilkS")
		)
		(fp_line
			(start 0.67945 0.3048)
			(end 0.67945 -0.305054)
			(stroke
				(width 0.1)
				(type default)
			)
			(layer "B.Fab")
		)
		(fp_line
			(start 0.67945 -0.305054)
			(end 0.12065 -0.305054)
			(stroke
				(width 0.1)
				(type default)
			)
			(layer "B.Fab")
		)
		(fp_line
			(start 0.12065 0.3048)
			(end 0.67945 0.3048)
			(stroke
				(width 0.1)
				(type default)
			)
			(layer "B.Fab")
		)
		(fp_line
			(start 0.12065 0.2794)
			(end 0.12065 0.3048)
			(stroke
				(width 0.1)
				(type default)
			)
			(layer "B.Fab")
		)
		(fp_line
			(start 0.12065 -0.2794)
			(end -0.12065 -0.2794)
			(stroke
				(width 0.1)
				(type default)
			)
			(layer "B.Fab")
		)
		(fp_line
			(start 0.12065 -0.305054)
			(end 0.12065 -0.2794)
			(stroke
				(width 0.1)
				(type default)
			)
			(layer "B.Fab")
		)
		(fp_line
			(start -0.120396 0.3048)
			(end -0.120396 0.2794)
			(stroke
				(width 0.1)
				(type default)
			)
			(layer "B.Fab")
		)
		(fp_line
			(start -0.120396 0.2794)
			(end 0.12065 0.2794)
			(stroke
				(width 0.1)
				(type default)
			)
			(layer "B.Fab")
		)
		(fp_line
			(start -0.12065 -0.2794)
			(end -0.12065 -0.3048)
			(stroke
				(width 0.1)
				(type default)
			)
			(layer "B.Fab")
		)
		(fp_line
			(start -0.12065 -0.3048)
			(end -0.67945 -0.3048)
			(stroke
				(width 0.1)
				(type default)
			)
			(layer "B.Fab")
		)
		(fp_line
			(start -0.67945 0.3048)
			(end -0.120396 0.3048)
			(stroke
				(width 0.1)
				(type default)
			)
			(layer "B.Fab")
		)
		(fp_line
			(start -0.67945 -0.3048)
			(end -0.67945 0.3048)
			(stroke
				(width 0.1)
				(type default)
			)
			(layer "B.Fab")
		)
		(pad "1" smd circle
			(at 0.40005 0)
			(size 0 0)
			(layers "B.Cu" "B.Mask" "B.Paste")
			(net "P3V3_AUX")
		)
		(pad "2" smd circle
			(at -0.40005 0)
			(size 0 0)
			(layers "B.Cu" "B.Mask" "B.Paste")
			(net "IRQ_PVCCIN_CPU0_VRHOT_R_N")
		)
	)
	(footprint ""
		(layer "B.Cu")
		(at 77.142594 -45.028866)
		(property "Reference" "R3571"
			(at 0 0 0)
			(layer "B.SilkS")
			(hide yes)
			(effects
				(font
					(size 1.27 1.27)
				)
				(justify mirror)
			)
		)
		(property "Value" ""
			(at 0 0 0)
			(layer "B.Fab")
			(effects
				(font
					(size 1.27 1.27)
				)
				(justify mirror)
			)
		)
		(duplicate_pad_numbers_are_jumpers no)
		(fp_line
			(start -0.7874 -0.4064)
			(end -0.7874 0.4064)
			(stroke
				(width 0.1524)
				(type default)
			)
			(layer "B.SilkS")
		)
		(fp_line
			(start -0.7874 0.4064)
			(end 0.7874 0.4064)
			(stroke
				(width 0.1524)
				(type default)
			)
			(layer "B.SilkS")
		)
		(fp_line
			(start 0.7874 -0.4064)
			(end -0.7874 -0.4064)
			(stroke
				(width 0.1524)
				(type default)
			)
			(layer "B.SilkS")
		)
		(fp_line
			(start 0.7874 0.4064)
			(end 0.7874 -0.4064)
			(stroke
				(width 0.1524)
				(type default)
			)
			(layer "B.SilkS")
		)
		(fp_line
			(start -0.67945 -0.3048)
			(end -0.67945 0.3048)
			(stroke
				(width 0.1)
				(type default)
			)
			(layer "B.Fab")
		)
		(fp_line
			(start -0.67945 0.3048)
			(end -0.120396 0.3048)
			(stroke
				(width 0.1)
				(type default)
			)
			(layer "B.Fab")
		)
		(fp_line
			(start -0.12065 -0.3048)
			(end -0.67945 -0.3048)
			(stroke
				(width 0.1)
				(type default)
			)
			(layer "B.Fab")
		)
		(fp_line
			(start -0.12065 -0.2794)
			(end -0.12065 -0.3048)
			(stroke
				(width 0.1)
				(type default)
			)
			(layer "B.Fab")
		)
		(fp_line
			(start -0.120396 0.2794)
			(end 0.12065 0.2794)
			(stroke
				(width 0.1)
				(type default)
			)
			(layer "B.Fab")
		)
		(fp_line
			(start -0.120396 0.3048)
			(end -0.120396 0.2794)
			(stroke
				(width 0.1)
				(type default)
			)
			(layer "B.Fab")
		)
		(fp_line
			(start 0.12065 -0.305054)
			(end 0.12065 -0.2794)
			(stroke
				(width 0.1)
				(type default)
			)
			(layer "B.Fab")
		)
		(fp_line
			(start 0.12065 -0.2794)
			(end -0.12065 -0.2794)
			(stroke
				(width 0.1)
				(type default)
			)
			(layer "B.Fab")
		)
		(fp_line
			(start 0.12065 0.2794)
			(end 0.12065 0.3048)
			(stroke
				(width 0.1)
				(type default)
			)
			(layer "B.Fab")
		)
		(fp_line
			(start 0.12065 0.3048)
			(end 0.67945 0.3048)
			(stroke
				(width 0.1)
				(type default)
			)
			(layer "B.Fab")
		)
		(fp_line
			(start 0.67945 -0.305054)
			(end 0.12065 -0.305054)
			(stroke
				(width 0.1)
				(type default)
			)
			(layer "B.Fab")
		)
		(fp_line
			(start 0.67945 0.3048)
			(end 0.67945 -0.305054)
			(stroke
				(width 0.1)
				(type default)
			)
			(layer "B.Fab")
		)
		(pad "1" smd circle
			(at 0.40005 0 180)
			(size 0 0)
			(layers "B.Cu" "B.Mask" "B.Paste")
			(net "P3V3_OCP_V3_2")
		)
		(pad "2" smd circle
			(at -0.40005 0 180)
			(size 0 0)
			(layers "B.Cu" "B.Mask" "B.Paste")
			(net "VSENSE_P12V_INA230_3_INN")
		)
	)
	(footprint ""
		(layer "B.Cu")
		(at 297.942 -259.171948 180)
		(property "Reference" "R186"
			(at 0 0 0)
			(layer "B.SilkS")
			(hide yes)
			(effects
				(font
					(size 1.27 1.27)
				)
				(justify mirror)
			)
		)
		(property "Value" ""
			(at 0 0 0)
			(layer "B.Fab")
			(effects
				(font
					(size 1.27 1.27)
				)
				(justify mirror)
			)
		)
		(duplicate_pad_numbers_are_jumpers no)
		(fp_line
			(start 0.7874 0.4064)
			(end 0.7874 -0.4064)
			(stroke
				(width 0.1524)
				(type default)
			)
			(layer "B.SilkS")
		)
		(fp_line
			(start 0.7874 -0.4064)
			(end -0.7874 -0.4064)
			(stroke
				(width 0.1524)
				(type default)
			)
			(layer "B.SilkS")
		)
		(fp_line
			(start -0.7874 0.4064)
			(end 0.7874 0.4064)
			(stroke
				(width 0.1524)
				(type default)
			)
			(layer "B.SilkS")
		)
		(fp_line
			(start -0.7874 -0.4064)
			(end -0.7874 0.4064)
			(stroke
				(width 0.1524)
				(type default)
			)
			(layer "B.SilkS")
		)
		(fp_line
			(start 0.67945 0.3048)
			(end 0.67945 -0.305054)
			(stroke
				(width 0.1)
				(type default)
			)
			(layer "B.Fab")
		)
		(fp_line
			(start 0.67945 -0.305054)
			(end 0.12065 -0.305054)
			(stroke
				(width 0.1)
				(type default)
			)
			(layer "B.Fab")
		)
		(fp_line
			(start 0.12065 0.3048)
			(end 0.67945 0.3048)
			(stroke
				(width 0.1)
				(type default)
			)
			(layer "B.Fab")
		)
		(fp_line
			(start 0.12065 0.2794)
			(end 0.12065 0.3048)
			(stroke
				(width 0.1)
				(type default)
			)
			(layer "B.Fab")
		)
		(fp_line
			(start 0.12065 -0.2794)
			(end -0.12065 -0.2794)
			(stroke
				(width 0.1)
				(type default)
			)
			(layer "B.Fab")
		)
		(fp_line
			(start 0.12065 -0.305054)
			(end 0.12065 -0.2794)
			(stroke
				(width 0.1)
				(type default)
			)
			(layer "B.Fab")
		)
		(fp_line
			(start -0.120396 0.3048)
			(end -0.120396 0.2794)
			(stroke
				(width 0.1)
				(type default)
			)
			(layer "B.Fab")
		)
		(fp_line
			(start -0.120396 0.2794)
			(end 0.12065 0.2794)
			(stroke
				(width 0.1)
				(type default)
			)
			(layer "B.Fab")
		)
		(fp_line
			(start -0.12065 -0.2794)
			(end -0.12065 -0.3048)
			(stroke
				(width 0.1)
				(type default)
			)
			(layer "B.Fab")
		)
		(fp_line
			(start -0.12065 -0.3048)
			(end -0.67945 -0.3048)
			(stroke
				(width 0.1)
				(type default)
			)
			(layer "B.Fab")
		)
		(fp_line
			(start -0.67945 0.3048)
			(end -0.120396 0.3048)
			(stroke
				(width 0.1)
				(type default)
			)
			(layer "B.Fab")
		)
		(fp_line
			(start -0.67945 -0.3048)
			(end -0.67945 0.3048)
			(stroke
				(width 0.1)
				(type default)
			)
			(layer "B.Fab")
		)
		(pad "1" smd circle
			(at 0.40005 0)
			(size 0 0)
			(layers "B.Cu" "B.Mask" "B.Paste")
			(net "RST_CPU0_BUF_R_N")
		)
		(pad "2" smd circle
			(at -0.40005 0)
			(size 0 0)
			(layers "B.Cu" "B.Mask" "B.Paste")
			(net "RST_CPU0_LVC1_N")
		)
	)
	(footprint ""
		(layer "B.Cu")
		(at 171.21632 -13.762228 90)
		(property "Reference" "R4535"
			(at 0 0 90)
			(layer "B.SilkS")
			(hide yes)
			(effects
				(font
					(size 1.27 1.27)
				)
				(justify mirror)
			)
		)
		(property "Value" ""
			(at 0 0 90)
			(layer "B.Fab")
			(effects
				(font
					(size 1.27 1.27)
				)
				(justify mirror)
			)
		)
		(duplicate_pad_numbers_are_jumpers no)
		(fp_line
			(start 0.4064 -0.4064)
			(end -0.11176 -0.4064)
			(stroke
				(width 0.1524)
				(type default)
			)
			(layer "B.SilkS")
		)
		(fp_line
			(start -0.7874 -0.16002)
			(end -0.7874 0.4064)
			(stroke
				(width 0.1524)
				(type default)
			)
			(layer "B.SilkS")
		)
		(fp_line
			(start 0.7874 0.4064)
			(end 0.7874 -0.0508)
			(stroke
				(width 0.1524)
				(type default)
			)
			(layer "B.SilkS")
		)
		(fp_line
			(start -0.7874 0.4064)
			(end 0.7874 0.4064)
			(stroke
				(width 0.1524)
				(type default)
			)
			(layer "B.SilkS")
		)
		(fp_line
			(start 0.67945 -0.305054)
			(end 0.12065 -0.305054)
			(stroke
				(width 0.1)
				(type default)
			)
			(layer "B.Fab")
		)
		(fp_line
			(start 0.12065 -0.305054)
			(end 0.12065 -0.2794)
			(stroke
				(width 0.1)
				(type default)
			)
			(layer "B.Fab")
		)
		(fp_line
			(start -0.12065 -0.3048)
			(end -0.67945 -0.3048)
			(stroke
				(width 0.1)
				(type default)
			)
			(layer "B.Fab")
		)
		(fp_line
			(start -0.67945 -0.3048)
			(end -0.67945 0.3048)
			(stroke
				(width 0.1)
				(type default)
			)
			(layer "B.Fab")
		)
		(fp_line
			(start 0.12065 -0.2794)
			(end -0.12065 -0.2794)
			(stroke
				(width 0.1)
				(type default)
			)
			(layer "B.Fab")
		)
		(fp_line
			(start -0.12065 -0.2794)
			(end -0.12065 -0.3048)
			(stroke
				(width 0.1)
				(type default)
			)
			(layer "B.Fab")
		)
		(fp_line
			(start 0.12065 0.2794)
			(end 0.12065 0.3048)
			(stroke
				(width 0.1)
				(type default)
			)
			(layer "B.Fab")
		)
		(fp_line
			(start -0.120396 0.2794)
			(end 0.12065 0.2794)
			(stroke
				(width 0.1)
				(type default)
			)
			(layer "B.Fab")
		)
		(fp_line
			(start 0.67945 0.3048)
			(end 0.67945 -0.305054)
			(stroke
				(width 0.1)
				(type default)
			)
			(layer "B.Fab")
		)
		(fp_line
			(start 0.12065 0.3048)
			(end 0.67945 0.3048)
			(stroke
				(width 0.1)
				(type default)
			)
			(layer "B.Fab")
		)
		(fp_line
			(start -0.120396 0.3048)
			(end -0.120396 0.2794)
			(stroke
				(width 0.1)
				(type default)
			)
			(layer "B.Fab")
		)
		(fp_line
			(start -0.67945 0.3048)
			(end -0.120396 0.3048)
			(stroke
				(width 0.1)
				(type default)
			)
			(layer "B.Fab")
		)
		(pad "1" smd circle
			(at 0.40005 0 270)
			(size 0 0)
			(layers "B.Cu" "B.Mask" "B.Paste")
			(net "CLK_100M_BMC_P3E_DP")
		)
		(pad "2" smd circle
			(at -0.40005 0 270)
			(size 0 0)
			(layers "B.Cu" "B.Mask" "B.Paste")
			(net "CLK_100M_BMC_P3E_DP_R")
		)
	)
	(footprint ""
		(layer "B.Cu")
		(at 517.258808 -148.1328 -90)
		(property "Reference" "X23"
			(at 3.671824 3.308096 270)
			(unlocked yes)
			(layer "B.SilkS")
			(effects
				(font
					(size 0.7874 0.5842)
					(thickness 0.1524)
				)
				(justify left mirror)
			)
		)
		(property "Value" ""
			(at 0 0 90)
			(layer "B.Fab")
			(effects
				(font
					(size 1.27 1.27)
				)
				(justify mirror)
			)
		)
		(property "Device Type" "TP_TDR_4P_FTS_TH-TP_TDR_4P_DIPA"
			(at -1.30175 1.27 180)
			(unlocked yes)
			(layer "B.Fab")
			(hide yes)
			(effects
				(font
					(size 0.635 0.4064)
					(thickness 0.1524)
				)
				(justify mirror)
			)
		)
		(property "User Part Number" "N_A"
			(at -1.30175 1.27 180)
			(unlocked yes)
			(layer "Cmts.User")
			(hide yes)
			(effects
				(font
					(size 0.635 0.4064)
					(thickness 0.1524)
				)
				(justify mirror)
			)
		)
		(duplicate_pad_numbers_are_jumpers no)
		(fp_line
			(start -2.54 3.81)
			(end -2.54 3.6703)
			(stroke
				(width 0.1524)
				(type default)
			)
			(layer "B.SilkS")
		)
		(fp_line
			(start 0 3.81)
			(end -2.54 3.81)
			(stroke
				(width 0.1524)
				(type default)
			)
			(layer "B.SilkS")
		)
		(fp_line
			(start 0 3.175)
			(end 0 3.81)
			(stroke
				(width 0.1524)
				(type default)
			)
			(layer "B.SilkS")
		)
		(fp_line
			(start -2.54 1.4097)
			(end -2.54 1.1303)
			(stroke
				(width 0.1524)
				(type default)
			)
			(layer "B.SilkS")
		)
		(fp_line
			(start 0 0.635)
			(end 0 1.905)
			(stroke
				(width 0.1524)
				(type default)
			)
			(layer "B.SilkS")
		)
		(fp_line
			(start -2.54 -1.1303)
			(end -2.54 -1.27)
			(stroke
				(width 0.1524)
				(type default)
			)
			(layer "B.SilkS")
		)
		(fp_line
			(start -2.54 -1.27)
			(end 0 -1.27)
			(stroke
				(width 0.1524)
				(type default)
			)
			(layer "B.SilkS")
		)
		(fp_line
			(start 0 -1.27)
			(end 0 -0.635)
			(stroke
				(width 0.1524)
				(type default)
			)
			(layer "B.SilkS")
		)
		(fp_poly
			(pts
				(xy 2.895346 -0.6985) (xy 2.895346 0.8255) (xy 1.371346 0.0635)
			)
			(stroke
				(width 0)
				(type default)
			)
			(fill yes)
			(layer "B.SilkS")
		)
		(fp_line
			(start -2.54 3.81)
			(end -2.54 -1.27)
			(stroke
				(width 0.1)
				(type default)
			)
			(layer "B.Fab")
		)
		(fp_line
			(start 0 3.81)
			(end -2.54 3.81)
			(stroke
				(width 0.1)
				(type default)
			)
			(layer "B.Fab")
		)
		(fp_line
			(start -2.54 -1.27)
			(end 0 -1.27)
			(stroke
				(width 0.1)
				(type default)
			)
			(layer "B.Fab")
		)
		(fp_line
			(start 0 -1.27)
			(end 0 3.81)
			(stroke
				(width 0.1)
				(type default)
			)
			(layer "B.Fab")
		)
		(fp_poly
			(pts
				(xy 0.761746 0) (xy 2.285746 -0.762) (xy 2.285746 0.762)
			)
			(stroke
				(width 0)
				(type default)
			)
			(fill yes)
			(layer "B.Fab")
		)
		(pad "1" thru_hole circle
			(at 0 0 90)
			(size 1.0033 1.0033)
			(drill 0.249936)
			(layers "*.Cu" "*.Mask")
			(remove_unused_layers no)
			(net "TDR_DIFF_100_IN4_DN")
			(clearance 0.10795)
			(padstack
				(mode front_inner_back)
				(layer "Inner"
					(shape circle)
					(size 0.8001 0.8001)
					(clearance 0.1524)
				)
				(layer "B.Cu"
					(shape circle)
					(size 1.0033 1.0033)
					(thermal_gap 0.10795)
					(clearance 0.10795)
				)
			)
		)
		(pad "2" thru_hole circle
			(at -2.54 0 90)
			(size 1.9939 1.9939)
			(drill 0.249936)
			(layers "*.Cu" "*.Mask")
			(remove_unused_layers no)
			(net "T1_GND")
			(clearance 0.10795)
			(padstack
				(mode front_inner_back)
				(layer "Inner"
					(shape circle)
					(size 0.8001 0.8001)
					(clearance 0.1524)
				)
				(layer "B.Cu"
					(shape circle)
					(size 1.9939 1.9939)
					(thermal_gap 0.10795)
					(clearance 0.10795)
				)
			)
		)
		(pad "3" thru_hole circle
			(at -2.54 2.54 90)
			(size 1.9939 1.9939)
			(drill 0.249936)
			(layers "*.Cu" "*.Mask")
			(remove_unused_layers no)
			(net "T1_GND")
			(clearance 0.10795)
			(padstack
				(mode front_inner_back)
				(layer "Inner"
					(shape circle)
					(size 0.8001 0.8001)
					(clearance 0.1524)
				)
				(layer "B.Cu"
					(shape circle)
					(size 1.9939 1.9939)
					(thermal_gap 0.10795)
					(clearance 0.10795)
				)
			)
		)
		(pad "4" thru_hole circle
			(at 0 2.54 90)
			(size 1.0033 1.0033)
			(drill 0.249936)
			(layers "*.Cu" "*.Mask")
			(remove_unused_layers no)
			(net "TDR_DIFF_100_IN4_DP")
			(clearance 0.10795)
			(padstack
				(mode front_inner_back)
				(layer "Inner"
					(shape circle)
					(size 0.8001 0.8001)
					(clearance 0.1524)
				)
				(layer "B.Cu"
					(shape circle)
					(size 1.0033 1.0033)
					(thermal_gap 0.10795)
					(clearance 0.10795)
				)
			)
		)
	)
	(footprint ""
		(layer "B.Cu")
		(at 52.358544 -152.603454)
		(property "Reference" "PR1796"
			(at 0 0 0)
			(layer "B.SilkS")
			(hide yes)
			(effects
				(font
					(size 1.27 1.27)
				)
				(justify mirror)
			)
		)
		(property "Value" ""
			(at 0 0 0)
			(layer "B.Fab")
			(effects
				(font
					(size 1.27 1.27)
				)
				(justify mirror)
			)
		)
		(duplicate_pad_numbers_are_jumpers no)
		(fp_line
			(start -0.7874 -0.4064)
			(end -0.7874 0.4064)
			(stroke
				(width 0.1524)
				(type default)
			)
			(layer "B.SilkS")
		)
		(fp_line
			(start -0.7874 0.4064)
			(end 0.7874 0.4064)
			(stroke
				(width 0.1524)
				(type default)
			)
			(layer "B.SilkS")
		)
		(fp_line
			(start 0.7874 -0.4064)
			(end -0.7874 -0.4064)
			(stroke
				(width 0.1524)
				(type default)
			)
			(layer "B.SilkS")
		)
		(fp_line
			(start 0.7874 0.4064)
			(end 0.7874 -0.4064)
			(stroke
				(width 0.1524)
				(type default)
			)
			(layer "B.SilkS")
		)
		(fp_line
			(start -0.67945 -0.3048)
			(end -0.67945 0.3048)
			(stroke
				(width 0.1)
				(type default)
			)
			(layer "B.Fab")
		)
		(fp_line
			(start -0.67945 0.3048)
			(end -0.120396 0.3048)
			(stroke
				(width 0.1)
				(type default)
			)
			(layer "B.Fab")
		)
		(fp_line
			(start -0.12065 -0.3048)
			(end -0.67945 -0.3048)
			(stroke
				(width 0.1)
				(type default)
			)
			(layer "B.Fab")
		)
		(fp_line
			(start -0.12065 -0.2794)
			(end -0.12065 -0.3048)
			(stroke
				(width 0.1)
				(type default)
			)
			(layer "B.Fab")
		)
		(fp_line
			(start -0.120396 0.2794)
			(end 0.12065 0.2794)
			(stroke
				(width 0.1)
				(type default)
			)
			(layer "B.Fab")
		)
		(fp_line
			(start -0.120396 0.3048)
			(end -0.120396 0.2794)
			(stroke
				(width 0.1)
				(type default)
			)
			(layer "B.Fab")
		)
		(fp_line
			(start 0.12065 -0.305054)
			(end 0.12065 -0.2794)
			(stroke
				(width 0.1)
				(type default)
			)
			(layer "B.Fab")
		)
		(fp_line
			(start 0.12065 -0.2794)
			(end -0.12065 -0.2794)
			(stroke
				(width 0.1)
				(type default)
			)
			(layer "B.Fab")
		)
		(fp_line
			(start 0.12065 0.2794)
			(end 0.12065 0.3048)
			(stroke
				(width 0.1)
				(type default)
			)
			(layer "B.Fab")
		)
		(fp_line
			(start 0.12065 0.3048)
			(end 0.67945 0.3048)
			(stroke
				(width 0.1)
				(type default)
			)
			(layer "B.Fab")
		)
		(fp_line
			(start 0.67945 -0.305054)
			(end 0.12065 -0.305054)
			(stroke
				(width 0.1)
				(type default)
			)
			(layer "B.Fab")
		)
		(fp_line
			(start 0.67945 0.3048)
			(end 0.67945 -0.305054)
			(stroke
				(width 0.1)
				(type default)
			)
			(layer "B.Fab")
		)
		(pad "1" smd circle
			(at 0.40005 0 180)
			(size 0 0)
			(layers "B.Cu" "B.Mask" "B.Paste")
			(net "PVCCINFAON_CPU1_VOS1")
		)
		(pad "2" smd circle
			(at -0.40005 0 180)
			(size 0 0)
			(layers "B.Cu" "B.Mask" "B.Paste")
			(net "PVCCINFAON_CPU1")
		)
	)
	(footprint ""
		(layer "B.Cu")
		(at 143.793718 -337.86318)
		(property "Reference" "C1392"
			(at 0 0 0)
			(layer "B.SilkS")
			(hide yes)
			(effects
				(font
					(size 1.27 1.27)
				)
				(justify mirror)
			)
		)
		(property "Value" ""
			(at 0 0 0)
			(layer "B.Fab")
			(effects
				(font
					(size 1.27 1.27)
				)
				(justify mirror)
			)
		)
		(duplicate_pad_numbers_are_jumpers no)
		(fp_line
			(start -1.524 -0.762)
			(end -1.524 0.762)
			(stroke
				(width 0.1524)
				(type default)
			)
			(layer "B.SilkS")
		)
		(fp_line
			(start -1.524 0.762)
			(end 1.524 0.762)
			(stroke
				(width 0.1524)
				(type default)
			)
			(layer "B.SilkS")
		)
		(fp_line
			(start 1.524 -0.762)
			(end -1.524 -0.762)
			(stroke
				(width 0.1524)
				(type default)
			)
			(layer "B.SilkS")
		)
		(fp_line
			(start 1.524 0.762)
			(end 1.524 -0.762)
			(stroke
				(width 0.1524)
				(type default)
			)
			(layer "B.SilkS")
		)
		(fp_line
			(start -1.1049 -0.724916)
			(end 1.1049 -0.724916)
			(stroke
				(width 0.1)
				(type default)
			)
			(layer "B.Fab")
		)
		(fp_line
			(start -1.1049 0.724916)
			(end -1.1049 -0.724916)
			(stroke
				(width 0.1)
				(type default)
			)
			(layer "B.Fab")
		)
		(fp_line
			(start 1.1049 -0.724916)
			(end 1.1049 0.724916)
			(stroke
				(width 0.1)
				(type default)
			)
			(layer "B.Fab")
		)
		(fp_line
			(start 1.1049 0.724916)
			(end -1.1049 0.724916)
			(stroke
				(width 0.1)
				(type default)
			)
			(layer "B.Fab")
		)
		(pad "1" smd rect
			(at 0.889 0)
			(size 1.016 1.27)
			(layers "B.Cu" "B.Mask" "B.Paste")
			(net "PVPP_HBM_CPU1")
		)
		(pad "2" smd rect
			(at -0.889 0)
			(size 1.016 1.27)
			(layers "B.Cu" "B.Mask" "B.Paste")
			(net "GND")
		)
	)
	(footprint ""
		(layer "B.Cu")
		(at 348.770194 -54.496208 90)
		(property "Reference" "C1261"
			(at 0 0 90)
			(layer "B.SilkS")
			(hide yes)
			(effects
				(font
					(size 1.27 1.27)
				)
				(justify mirror)
			)
		)
		(property "Value" ""
			(at 0 0 90)
			(layer "B.Fab")
			(effects
				(font
					(size 1.27 1.27)
				)
				(justify mirror)
			)
		)
		(duplicate_pad_numbers_are_jumpers no)
		(fp_line
			(start 1.2954 -0.5842)
			(end -1.2954 -0.5842)
			(stroke
				(width 0.1524)
				(type default)
			)
			(layer "B.SilkS")
		)
		(fp_line
			(start 0 -0.5842)
			(end 0 0.5842)
			(stroke
				(width 0.1524)
				(type default)
			)
			(layer "B.SilkS")
		)
		(fp_line
			(start -1.2954 -0.5842)
			(end -1.2954 0.5842)
			(stroke
				(width 0.1524)
				(type default)
			)
			(layer "B.SilkS")
		)
		(fp_line
			(start 1.2954 0.5842)
			(end 1.2954 -0.5842)
			(stroke
				(width 0.1524)
				(type default)
			)
			(layer "B.SilkS")
		)
		(fp_line
			(start -1.2954 0.5842)
			(end 1.2954 0.5842)
			(stroke
				(width 0.1524)
				(type default)
			)
			(layer "B.SilkS")
		)
		(fp_line
			(start 0.8636 -0.4572)
			(end -0.8636 -0.4572)
			(stroke
				(width 0.1)
				(type default)
			)
			(layer "B.Fab")
		)
		(fp_line
			(start -0.8636 -0.4572)
			(end -0.8636 -0.4064)
			(stroke
				(width 0.1)
				(type default)
			)
			(layer "B.Fab")
		)
		(fp_line
			(start 1.1938 -0.4064)
			(end 0.8636 -0.4064)
			(stroke
				(width 0.1)
				(type default)
			)
			(layer "B.Fab")
		)
		(fp_line
			(start 0.8636 -0.4064)
			(end 0.8636 -0.4572)
			(stroke
				(width 0.1)
				(type default)
			)
			(layer "B.Fab")
		)
		(fp_line
			(start -0.8636 -0.4064)
			(end -1.1938 -0.4064)
			(stroke
				(width 0.1)
				(type default)
			)
			(layer "B.Fab")
		)
		(fp_line
			(start -1.1938 -0.4064)
			(end -1.1938 0.4064)
			(stroke
				(width 0.1)
				(type default)
			)
			(layer "B.Fab")
		)
		(fp_line
			(start 1.1938 0.4064)
			(end 1.1938 -0.4064)
			(stroke
				(width 0.1)
				(type default)
			)
			(layer "B.Fab")
		)
		(fp_line
			(start 0.8636 0.4064)
			(end 1.1938 0.4064)
			(stroke
				(width 0.1)
				(type default)
			)
			(layer "B.Fab")
		)
		(fp_line
			(start -0.8636 0.4064)
			(end -0.8636 0.4572)
			(stroke
				(width 0.1)
				(type default)
			)
			(layer "B.Fab")
		)
		(fp_line
			(start -1.1938 0.4064)
			(end -0.8636 0.4064)
			(stroke
				(width 0.1)
				(type default)
			)
			(layer "B.Fab")
		)
		(fp_line
			(start 0.8636 0.4572)
			(end 0.8636 0.4064)
			(stroke
				(width 0.1)
				(type default)
			)
			(layer "B.Fab")
		)
		(fp_line
			(start -0.8636 0.4572)
			(end 0.8636 0.4572)
			(stroke
				(width 0.1)
				(type default)
			)
			(layer "B.Fab")
		)
		(pad "1" smd rect
			(at 0.7366 0)
			(size 0.7112 0.8128)
			(layers "B.Cu" "B.Mask" "B.Paste")
			(net "P1V8_PCH_PLL_AUX")
		)
		(pad "2" smd rect
			(at -0.7366 0)
			(size 0.7112 0.8128)
			(layers "B.Cu" "B.Mask" "B.Paste")
			(net "GND")
		)
	)
	(footprint ""
		(layer "B.Cu")
		(at 31.396432 -169.5958 180)
		(property "Reference" "PR220"
			(at 0 0 0)
			(layer "B.SilkS")
			(hide yes)
			(effects
				(font
					(size 1.27 1.27)
				)
				(justify mirror)
			)
		)
		(property "Value" ""
			(at 0 0 0)
			(layer "B.Fab")
			(effects
				(font
					(size 1.27 1.27)
				)
				(justify mirror)
			)
		)
		(duplicate_pad_numbers_are_jumpers no)
		(fp_line
			(start 0.7874 0.4064)
			(end 0.7874 -0.4064)
			(stroke
				(width 0.1524)
				(type default)
			)
			(layer "B.SilkS")
		)
		(fp_line
			(start 0.7874 -0.4064)
			(end -0.7874 -0.4064)
			(stroke
				(width 0.1524)
				(type default)
			)
			(layer "B.SilkS")
		)
		(fp_line
			(start -0.7874 0.4064)
			(end 0.7874 0.4064)
			(stroke
				(width 0.1524)
				(type default)
			)
			(layer "B.SilkS")
		)
		(fp_line
			(start -0.7874 -0.4064)
			(end -0.7874 0.4064)
			(stroke
				(width 0.1524)
				(type default)
			)
			(layer "B.SilkS")
		)
		(fp_line
			(start 0.67945 0.3048)
			(end 0.67945 -0.305054)
			(stroke
				(width 0.1)
				(type default)
			)
			(layer "B.Fab")
		)
		(fp_line
			(start 0.67945 -0.305054)
			(end 0.12065 -0.305054)
			(stroke
				(width 0.1)
				(type default)
			)
			(layer "B.Fab")
		)
		(fp_line
			(start 0.12065 0.3048)
			(end 0.67945 0.3048)
			(stroke
				(width 0.1)
				(type default)
			)
			(layer "B.Fab")
		)
		(fp_line
			(start 0.12065 0.2794)
			(end 0.12065 0.3048)
			(stroke
				(width 0.1)
				(type default)
			)
			(layer "B.Fab")
		)
		(fp_line
			(start 0.12065 -0.2794)
			(end -0.12065 -0.2794)
			(stroke
				(width 0.1)
				(type default)
			)
			(layer "B.Fab")
		)
		(fp_line
			(start 0.12065 -0.305054)
			(end 0.12065 -0.2794)
			(stroke
				(width 0.1)
				(type default)
			)
			(layer "B.Fab")
		)
		(fp_line
			(start -0.120396 0.3048)
			(end -0.120396 0.2794)
			(stroke
				(width 0.1)
				(type default)
			)
			(layer "B.Fab")
		)
		(fp_line
			(start -0.120396 0.2794)
			(end 0.12065 0.2794)
			(stroke
				(width 0.1)
				(type default)
			)
			(layer "B.Fab")
		)
		(fp_line
			(start -0.12065 -0.2794)
			(end -0.12065 -0.3048)
			(stroke
				(width 0.1)
				(type default)
			)
			(layer "B.Fab")
		)
		(fp_line
			(start -0.12065 -0.3048)
			(end -0.67945 -0.3048)
			(stroke
				(width 0.1)
				(type default)
			)
			(layer "B.Fab")
		)
		(fp_line
			(start -0.67945 0.3048)
			(end -0.120396 0.3048)
			(stroke
				(width 0.1)
				(type default)
			)
			(layer "B.Fab")
		)
		(fp_line
			(start -0.67945 -0.3048)
			(end -0.67945 0.3048)
			(stroke
				(width 0.1)
				(type default)
			)
			(layer "B.Fab")
		)
		(pad "1" smd circle
			(at 0.40005 0)
			(size 0 0)
			(layers "B.Cu" "B.Mask" "B.Paste")
			(net "PVCCD_HV_CPU1_VCC")
		)
		(pad "2" smd circle
			(at -0.40005 0)
			(size 0 0)
			(layers "B.Cu" "B.Mask" "B.Paste")
			(net "P3V3_AUX")
		)
	)
	(footprint ""
		(layer "B.Cu")
		(at 401.832318 -230.94823 90)
		(property "Reference" "R1959"
			(at 0 0 90)
			(layer "B.SilkS")
			(hide yes)
			(effects
				(font
					(size 1.27 1.27)
				)
				(justify mirror)
			)
		)
		(property "Value" ""
			(at 0 0 90)
			(layer "B.Fab")
			(effects
				(font
					(size 1.27 1.27)
				)
				(justify mirror)
			)
		)
		(duplicate_pad_numbers_are_jumpers no)
		(fp_line
			(start 0.7874 -0.4064)
			(end -0.7874 -0.4064)
			(stroke
				(width 0.1524)
				(type default)
			)
			(layer "B.SilkS")
		)
		(fp_line
			(start -0.7874 -0.4064)
			(end -0.7874 0.4064)
			(stroke
				(width 0.1524)
				(type default)
			)
			(layer "B.SilkS")
		)
		(fp_line
			(start 0.7874 0.4064)
			(end 0.7874 -0.4064)
			(stroke
				(width 0.1524)
				(type default)
			)
			(layer "B.SilkS")
		)
		(fp_line
			(start -0.7874 0.4064)
			(end 0.7874 0.4064)
			(stroke
				(width 0.1524)
				(type default)
			)
			(layer "B.SilkS")
		)
		(fp_line
			(start 0.67945 -0.305054)
			(end 0.12065 -0.305054)
			(stroke
				(width 0.1)
				(type default)
			)
			(layer "B.Fab")
		)
		(fp_line
			(start 0.12065 -0.305054)
			(end 0.12065 -0.2794)
			(stroke
				(width 0.1)
				(type default)
			)
			(layer "B.Fab")
		)
		(fp_line
			(start -0.12065 -0.3048)
			(end -0.67945 -0.3048)
			(stroke
				(width 0.1)
				(type default)
			)
			(layer "B.Fab")
		)
		(fp_line
			(start -0.67945 -0.3048)
			(end -0.67945 0.3048)
			(stroke
				(width 0.1)
				(type default)
			)
			(layer "B.Fab")
		)
		(fp_line
			(start 0.12065 -0.2794)
			(end -0.12065 -0.2794)
			(stroke
				(width 0.1)
				(type default)
			)
			(layer "B.Fab")
		)
		(fp_line
			(start -0.12065 -0.2794)
			(end -0.12065 -0.3048)
			(stroke
				(width 0.1)
				(type default)
			)
			(layer "B.Fab")
		)
		(fp_line
			(start 0.12065 0.2794)
			(end 0.12065 0.3048)
			(stroke
				(width 0.1)
				(type default)
			)
			(layer "B.Fab")
		)
		(fp_line
			(start -0.120396 0.2794)
			(end 0.12065 0.2794)
			(stroke
				(width 0.1)
				(type default)
			)
			(layer "B.Fab")
		)
		(fp_line
			(start 0.67945 0.3048)
			(end 0.67945 -0.305054)
			(stroke
				(width 0.1)
				(type default)
			)
			(layer "B.Fab")
		)
		(fp_line
			(start 0.12065 0.3048)
			(end 0.67945 0.3048)
			(stroke
				(width 0.1)
				(type default)
			)
			(layer "B.Fab")
		)
		(fp_line
			(start -0.120396 0.3048)
			(end -0.120396 0.2794)
			(stroke
				(width 0.1)
				(type default)
			)
			(layer "B.Fab")
		)
		(fp_line
			(start -0.67945 0.3048)
			(end -0.120396 0.3048)
			(stroke
				(width 0.1)
				(type default)
			)
			(layer "B.Fab")
		)
		(pad "1" smd circle
			(at 0.40005 0 270)
			(size 0 0)
			(layers "B.Cu" "B.Mask" "B.Paste")
			(net "H_CPU0_PMDOWN_PCH_R2")
		)
		(pad "2" smd circle
			(at -0.40005 0 270)
			(size 0 0)
			(layers "B.Cu" "B.Mask" "B.Paste")
			(net "H_CPU0_PMDOWN_PCH_R")
		)
	)
	(footprint ""
		(layer "B.Cu")
		(at 85.340952 -328.298048 -90)
		(property "Reference" "PC519_P1_6"
			(at 0 0 90)
			(layer "B.SilkS")
			(hide yes)
			(effects
				(font
					(size 1.27 1.27)
				)
				(justify mirror)
			)
		)
		(property "Value" ""
			(at 0 0 90)
			(layer "B.Fab")
			(effects
				(font
					(size 1.27 1.27)
				)
				(justify mirror)
			)
		)
		(duplicate_pad_numbers_are_jumpers no)
		(fp_line
			(start -1.524 0.762)
			(end 1.524 0.762)
			(stroke
				(width 0.1524)
				(type default)
			)
			(layer "B.SilkS")
		)
		(fp_line
			(start 1.524 0.762)
			(end 1.524 -0.762)
			(stroke
				(width 0.1524)
				(type default)
			)
			(layer "B.SilkS")
		)
		(fp_line
			(start -1.524 -0.762)
			(end -1.524 0.762)
			(stroke
				(width 0.1524)
				(type default)
			)
			(layer "B.SilkS")
		)
		(fp_line
			(start 1.524 -0.762)
			(end -1.524 -0.762)
			(stroke
				(width 0.1524)
				(type default)
			)
			(layer "B.SilkS")
		)
		(fp_line
			(start -1.1049 0.724916)
			(end -1.1049 -0.724916)
			(stroke
				(width 0.1)
				(type default)
			)
			(layer "B.Fab")
		)
		(fp_line
			(start 1.1049 0.724916)
			(end -1.1049 0.724916)
			(stroke
				(width 0.1)
				(type default)
			)
			(layer "B.Fab")
		)
		(fp_line
			(start -1.1049 -0.724916)
			(end 1.1049 -0.724916)
			(stroke
				(width 0.1)
				(type default)
			)
			(layer "B.Fab")
		)
		(fp_line
			(start 1.1049 -0.724916)
			(end 1.1049 0.724916)
			(stroke
				(width 0.1)
				(type default)
			)
			(layer "B.Fab")
		)
		(pad "1" smd rect
			(at 0.889 0 270)
			(size 1.016 1.27)
			(layers "B.Cu" "B.Mask" "B.Paste")
			(net "PVCCIN_CPU1")
		)
		(pad "2" smd rect
			(at -0.889 0 270)
			(size 1.016 1.27)
			(layers "B.Cu" "B.Mask" "B.Paste")
			(net "GND")
		)
	)
	(footprint ""
		(layer "B.Cu")
		(at 490.14253 -427.53788 180)
		(property "Reference" "DB6"
			(at 2.845308 -7.762748 270)
			(unlocked yes)
			(layer "B.SilkS")
			(effects
				(font
					(size 0.7874 0.5842)
					(thickness 0.1524)
				)
				(justify left mirror)
			)
		)
		(property "Value" ""
			(at 0 0 0)
			(layer "B.Fab")
			(effects
				(font
					(size 1.27 1.27)
				)
				(justify mirror)
			)
		)
		(duplicate_pad_numbers_are_jumpers no)
		(fp_line
			(start 3.330702 -4.771136)
			(end -3.330702 -4.771136)
			(stroke
				(width 0.1524)
				(type default)
			)
			(layer "B.SilkS")
		)
		(fp_line
			(start 0 4.011168)
			(end 3.330702 -4.771136)
			(stroke
				(width 0.1524)
				(type default)
			)
			(layer "B.SilkS")
		)
		(fp_line
			(start -3.330702 -4.771136)
			(end 0 4.011168)
			(stroke
				(width 0.1524)
				(type default)
			)
			(layer "B.SilkS")
		)
		(fp_line
			(start 3.330702 -4.771136)
			(end -3.330702 -4.771136)
			(stroke
				(width 0.1)
				(type default)
			)
			(layer "B.Fab")
		)
		(fp_line
			(start 0 4.011168)
			(end 3.330702 -4.771136)
			(stroke
				(width 0.1)
				(type default)
			)
			(layer "B.Fab")
		)
		(fp_line
			(start -3.330702 -4.771136)
			(end 0 4.011168)
			(stroke
				(width 0.1)
				(type default)
			)
			(layer "B.Fab")
		)
		(pad "1" thru_hole circle
			(at 0 0)
			(size 2.159 2.159)
			(drill 1.7018)
			(layers "*.Cu" "*.Mask")
			(remove_unused_layers no)
			(net "T1_GND")
			(clearance 0.0254)
			(thermal_gap 0.0254)
		)
		(pad "2" thru_hole circle
			(at 1.27 -3.348736)
			(size 2.159 2.159)
			(drill 1.7018)
			(layers "*.Cu" "*.Mask")
			(remove_unused_layers no)
			(net "TDR_SE_40_OHM_BOT")
			(clearance 0.0254)
			(thermal_gap 0.0254)
		)
		(pad "3" thru_hole circle
			(at -1.27 -3.348736)
			(size 2.159 2.159)
			(drill 1.7018)
			(layers "*.Cu" "*.Mask")
			(remove_unused_layers no)
			(net "TDR_SE_40_OHM_BOT")
			(clearance 0.0254)
			(thermal_gap 0.0254)
		)
	)
	(footprint ""
		(layer "B.Cu")
		(at 164.64788 -121.376948)
		(property "Reference" "R1408"
			(at 0 0 0)
			(layer "B.SilkS")
			(hide yes)
			(effects
				(font
					(size 1.27 1.27)
				)
				(justify mirror)
			)
		)
		(property "Value" ""
			(at 0 0 0)
			(layer "B.Fab")
			(effects
				(font
					(size 1.27 1.27)
				)
				(justify mirror)
			)
		)
		(duplicate_pad_numbers_are_jumpers no)
		(fp_line
			(start -0.7874 -0.4064)
			(end -0.7874 0.4064)
			(stroke
				(width 0.1524)
				(type default)
			)
			(layer "B.SilkS")
		)
		(fp_line
			(start -0.7874 0.4064)
			(end 0.7874 0.4064)
			(stroke
				(width 0.1524)
				(type default)
			)
			(layer "B.SilkS")
		)
		(fp_line
			(start 0.7874 -0.4064)
			(end -0.7874 -0.4064)
			(stroke
				(width 0.1524)
				(type default)
			)
			(layer "B.SilkS")
		)
		(fp_line
			(start 0.7874 0.4064)
			(end 0.7874 -0.4064)
			(stroke
				(width 0.1524)
				(type default)
			)
			(layer "B.SilkS")
		)
		(fp_line
			(start -0.67945 -0.3048)
			(end -0.67945 0.3048)
			(stroke
				(width 0.1)
				(type default)
			)
			(layer "B.Fab")
		)
		(fp_line
			(start -0.67945 0.3048)
			(end -0.120396 0.3048)
			(stroke
				(width 0.1)
				(type default)
			)
			(layer "B.Fab")
		)
		(fp_line
			(start -0.12065 -0.3048)
			(end -0.67945 -0.3048)
			(stroke
				(width 0.1)
				(type default)
			)
			(layer "B.Fab")
		)
		(fp_line
			(start -0.12065 -0.2794)
			(end -0.12065 -0.3048)
			(stroke
				(width 0.1)
				(type default)
			)
			(layer "B.Fab")
		)
		(fp_line
			(start -0.120396 0.2794)
			(end 0.12065 0.2794)
			(stroke
				(width 0.1)
				(type default)
			)
			(layer "B.Fab")
		)
		(fp_line
			(start -0.120396 0.3048)
			(end -0.120396 0.2794)
			(stroke
				(width 0.1)
				(type default)
			)
			(layer "B.Fab")
		)
		(fp_line
			(start 0.12065 -0.305054)
			(end 0.12065 -0.2794)
			(stroke
				(width 0.1)
				(type default)
			)
			(layer "B.Fab")
		)
		(fp_line
			(start 0.12065 -0.2794)
			(end -0.12065 -0.2794)
			(stroke
				(width 0.1)
				(type default)
			)
			(layer "B.Fab")
		)
		(fp_line
			(start 0.12065 0.2794)
			(end 0.12065 0.3048)
			(stroke
				(width 0.1)
				(type default)
			)
			(layer "B.Fab")
		)
		(fp_line
			(start 0.12065 0.3048)
			(end 0.67945 0.3048)
			(stroke
				(width 0.1)
				(type default)
			)
			(layer "B.Fab")
		)
		(fp_line
			(start 0.67945 -0.305054)
			(end 0.12065 -0.305054)
			(stroke
				(width 0.1)
				(type default)
			)
			(layer "B.Fab")
		)
		(fp_line
			(start 0.67945 0.3048)
			(end 0.67945 -0.305054)
			(stroke
				(width 0.1)
				(type default)
			)
			(layer "B.Fab")
		)
		(pad "1" smd circle
			(at 0.40005 0 180)
			(size 0 0)
			(layers "B.Cu" "B.Mask" "B.Paste")
			(net "FM_PVCCINFAON_CPU1_R_EN")
		)
		(pad "2" smd circle
			(at -0.40005 0 180)
			(size 0 0)
			(layers "B.Cu" "B.Mask" "B.Paste")
			(net "GND")
		)
	)
	(footprint ""
		(layer "B.Cu")
		(at 412.611316 -353.25939 -90)
		(property "Reference" "PC615_P0_1"
			(at 0 0 90)
			(layer "B.SilkS")
			(hide yes)
			(effects
				(font
					(size 1.27 1.27)
				)
				(justify mirror)
			)
		)
		(property "Value" ""
			(at 0 0 90)
			(layer "B.Fab")
			(effects
				(font
					(size 1.27 1.27)
				)
				(justify mirror)
			)
		)
		(duplicate_pad_numbers_are_jumpers no)
		(fp_line
			(start -1.524 0.762)
			(end 1.524 0.762)
			(stroke
				(width 0.1524)
				(type default)
			)
			(layer "B.SilkS")
		)
		(fp_line
			(start 1.524 0.762)
			(end 1.524 -0.762)
			(stroke
				(width 0.1524)
				(type default)
			)
			(layer "B.SilkS")
		)
		(fp_line
			(start -1.524 -0.762)
			(end -1.524 0.762)
			(stroke
				(width 0.1524)
				(type default)
			)
			(layer "B.SilkS")
		)
		(fp_line
			(start 1.524 -0.762)
			(end -1.524 -0.762)
			(stroke
				(width 0.1524)
				(type default)
			)
			(layer "B.SilkS")
		)
		(fp_line
			(start -1.1049 0.724916)
			(end -1.1049 -0.724916)
			(stroke
				(width 0.1)
				(type default)
			)
			(layer "B.Fab")
		)
		(fp_line
			(start 1.1049 0.724916)
			(end -1.1049 0.724916)
			(stroke
				(width 0.1)
				(type default)
			)
			(layer "B.Fab")
		)
		(fp_line
			(start -1.1049 -0.724916)
			(end 1.1049 -0.724916)
			(stroke
				(width 0.1)
				(type default)
			)
			(layer "B.Fab")
		)
		(fp_line
			(start 1.1049 -0.724916)
			(end 1.1049 0.724916)
			(stroke
				(width 0.1)
				(type default)
			)
			(layer "B.Fab")
		)
		(pad "1" smd rect
			(at 0.889 0 270)
			(size 1.016 1.27)
			(layers "B.Cu" "B.Mask" "B.Paste")
			(net "PVCCFA_EHV_FIVRA_CPU0")
		)
		(pad "2" smd rect
			(at -0.889 0 270)
			(size 1.016 1.27)
			(layers "B.Cu" "B.Mask" "B.Paste")
			(net "GND")
		)
	)
	(footprint ""
		(layer "B.Cu")
		(at 348.13494 -333.639922 90)
		(property "Reference" "PC305_P0_1"
			(at 0 0 90)
			(layer "B.SilkS")
			(hide yes)
			(effects
				(font
					(size 1.27 1.27)
				)
				(justify mirror)
			)
		)
		(property "Value" ""
			(at 0 0 90)
			(layer "B.Fab")
			(effects
				(font
					(size 1.27 1.27)
				)
				(justify mirror)
			)
		)
		(duplicate_pad_numbers_are_jumpers no)
		(fp_line
			(start 1.524 -0.762)
			(end -1.524 -0.762)
			(stroke
				(width 0.1524)
				(type default)
			)
			(layer "B.SilkS")
		)
		(fp_line
			(start -1.524 -0.762)
			(end -1.524 0.762)
			(stroke
				(width 0.1524)
				(type default)
			)
			(layer "B.SilkS")
		)
		(fp_line
			(start 1.524 0.762)
			(end 1.524 -0.762)
			(stroke
				(width 0.1524)
				(type default)
			)
			(layer "B.SilkS")
		)
		(fp_line
			(start -1.524 0.762)
			(end 1.524 0.762)
			(stroke
				(width 0.1524)
				(type default)
			)
			(layer "B.SilkS")
		)
		(fp_line
			(start 1.1049 -0.724916)
			(end 1.1049 0.724916)
			(stroke
				(width 0.1)
				(type default)
			)
			(layer "B.Fab")
		)
		(fp_line
			(start -1.1049 -0.724916)
			(end 1.1049 -0.724916)
			(stroke
				(width 0.1)
				(type default)
			)
			(layer "B.Fab")
		)
		(fp_line
			(start 1.1049 0.724916)
			(end -1.1049 0.724916)
			(stroke
				(width 0.1)
				(type default)
			)
			(layer "B.Fab")
		)
		(fp_line
			(start -1.1049 0.724916)
			(end -1.1049 -0.724916)
			(stroke
				(width 0.1)
				(type default)
			)
			(layer "B.Fab")
		)
		(pad "1" smd rect
			(at 0.889 0 90)
			(size 1.016 1.27)
			(layers "B.Cu" "B.Mask" "B.Paste")
			(net "SW_P12V_PVCCIN_CPU0_FLT")
		)
		(pad "2" smd rect
			(at -0.889 0 90)
			(size 1.016 1.27)
			(layers "B.Cu" "B.Mask" "B.Paste")
			(net "GND")
		)
	)
	(footprint ""
		(layer "B.Cu")
		(at 123.640342 -366.723168 90)
		(property "Reference" "PC1268"
			(at 0 0 90)
			(layer "B.SilkS")
			(hide yes)
			(effects
				(font
					(size 1.27 1.27)
				)
				(justify mirror)
			)
		)
		(property "Value" ""
			(at 0 0 90)
			(layer "B.Fab")
			(effects
				(font
					(size 1.27 1.27)
				)
				(justify mirror)
			)
		)
		(duplicate_pad_numbers_are_jumpers no)
		(fp_line
			(start 1.524 -0.762)
			(end -1.524 -0.762)
			(stroke
				(width 0.1524)
				(type default)
			)
			(layer "B.SilkS")
		)
		(fp_line
			(start -1.524 -0.762)
			(end -1.524 0.762)
			(stroke
				(width 0.1524)
				(type default)
			)
			(layer "B.SilkS")
		)
		(fp_line
			(start 1.524 0.762)
			(end 1.524 -0.762)
			(stroke
				(width 0.1524)
				(type default)
			)
			(layer "B.SilkS")
		)
		(fp_line
			(start -1.524 0.762)
			(end 1.524 0.762)
			(stroke
				(width 0.1524)
				(type default)
			)
			(layer "B.SilkS")
		)
		(fp_line
			(start 1.1049 -0.724916)
			(end 1.1049 0.724916)
			(stroke
				(width 0.1)
				(type default)
			)
			(layer "B.Fab")
		)
		(fp_line
			(start -1.1049 -0.724916)
			(end 1.1049 -0.724916)
			(stroke
				(width 0.1)
				(type default)
			)
			(layer "B.Fab")
		)
		(fp_line
			(start 1.1049 0.724916)
			(end -1.1049 0.724916)
			(stroke
				(width 0.1)
				(type default)
			)
			(layer "B.Fab")
		)
		(fp_line
			(start -1.1049 0.724916)
			(end -1.1049 -0.724916)
			(stroke
				(width 0.1)
				(type default)
			)
			(layer "B.Fab")
		)
		(pad "1" smd rect
			(at 0.889 0 90)
			(size 1.016 1.27)
			(layers "B.Cu" "B.Mask" "B.Paste")
			(net "PVPP_HBM_CPU1")
		)
		(pad "2" smd rect
			(at -0.889 0 90)
			(size 1.016 1.27)
			(layers "B.Cu" "B.Mask" "B.Paste")
			(net "GND")
		)
	)
	(footprint ""
		(layer "B.Cu")
		(at 137.50798 -22.943058 90)
		(property "Reference" "R4468"
			(at 0 0 90)
			(layer "B.SilkS")
			(hide yes)
			(effects
				(font
					(size 1.27 1.27)
				)
				(justify mirror)
			)
		)
		(property "Value" ""
			(at 0 0 90)
			(layer "B.Fab")
			(effects
				(font
					(size 1.27 1.27)
				)
				(justify mirror)
			)
		)
		(duplicate_pad_numbers_are_jumpers no)
		(fp_line
			(start 0.7874 -0.4064)
			(end -0.7874 -0.4064)
			(stroke
				(width 0.1524)
				(type default)
			)
			(layer "B.SilkS")
		)
		(fp_line
			(start -0.7874 -0.4064)
			(end -0.7874 0.00762)
			(stroke
				(width 0.1524)
				(type default)
			)
			(layer "B.SilkS")
		)
		(fp_line
			(start 0.7874 0.02794)
			(end 0.7874 -0.4064)
			(stroke
				(width 0.1524)
				(type default)
			)
			(layer "B.SilkS")
		)
		(fp_line
			(start -0.41275 0.4064)
			(end 0.44323 0.4064)
			(stroke
				(width 0.1524)
				(type default)
			)
			(layer "B.SilkS")
		)
		(fp_line
			(start 0.67945 -0.305054)
			(end 0.12065 -0.305054)
			(stroke
				(width 0.1)
				(type default)
			)
			(layer "B.Fab")
		)
		(fp_line
			(start 0.12065 -0.305054)
			(end 0.12065 -0.2794)
			(stroke
				(width 0.1)
				(type default)
			)
			(layer "B.Fab")
		)
		(fp_line
			(start -0.12065 -0.3048)
			(end -0.67945 -0.3048)
			(stroke
				(width 0.1)
				(type default)
			)
			(layer "B.Fab")
		)
		(fp_line
			(start -0.67945 -0.3048)
			(end -0.67945 0.3048)
			(stroke
				(width 0.1)
				(type default)
			)
			(layer "B.Fab")
		)
		(fp_line
			(start 0.12065 -0.2794)
			(end -0.12065 -0.2794)
			(stroke
				(width 0.1)
				(type default)
			)
			(layer "B.Fab")
		)
		(fp_line
			(start -0.12065 -0.2794)
			(end -0.12065 -0.3048)
			(stroke
				(width 0.1)
				(type default)
			)
			(layer "B.Fab")
		)
		(fp_line
			(start 0.12065 0.2794)
			(end 0.12065 0.3048)
			(stroke
				(width 0.1)
				(type default)
			)
			(layer "B.Fab")
		)
		(fp_line
			(start -0.120396 0.2794)
			(end 0.12065 0.2794)
			(stroke
				(width 0.1)
				(type default)
			)
			(layer "B.Fab")
		)
		(fp_line
			(start 0.67945 0.3048)
			(end 0.67945 -0.305054)
			(stroke
				(width 0.1)
				(type default)
			)
			(layer "B.Fab")
		)
		(fp_line
			(start 0.12065 0.3048)
			(end 0.67945 0.3048)
			(stroke
				(width 0.1)
				(type default)
			)
			(layer "B.Fab")
		)
		(fp_line
			(start -0.120396 0.3048)
			(end -0.120396 0.2794)
			(stroke
				(width 0.1)
				(type default)
			)
			(layer "B.Fab")
		)
		(fp_line
			(start -0.67945 0.3048)
			(end -0.120396 0.3048)
			(stroke
				(width 0.1)
				(type default)
			)
			(layer "B.Fab")
		)
		(pad "1" smd circle
			(at 0.40005 0 270)
			(size 0 0)
			(layers "B.Cu" "B.Mask" "B.Paste")
			(net "USB2_HUB_2_BUF_EXT_R_DN")
		)
		(pad "2" smd circle
			(at -0.40005 0 270)
			(size 0 0)
			(layers "B.Cu" "B.Mask" "B.Paste")
			(net "USB2_HUB_2_BUF_EXT_DN")
		)
	)
	(footprint ""
		(layer "B.Cu")
		(at 216.00541 -403.668738 -90)
		(property "Reference" "PR3980"
			(at 0 0 90)
			(layer "B.SilkS")
			(hide yes)
			(effects
				(font
					(size 1.27 1.27)
				)
				(justify mirror)
			)
		)
		(property "Value" ""
			(at 0 0 90)
			(layer "B.Fab")
			(effects
				(font
					(size 1.27 1.27)
				)
				(justify mirror)
			)
		)
		(duplicate_pad_numbers_are_jumpers no)
		(fp_line
			(start -0.7874 0.4064)
			(end 0.7874 0.4064)
			(stroke
				(width 0.1524)
				(type default)
			)
			(layer "B.SilkS")
		)
		(fp_line
			(start 0.7874 0.4064)
			(end 0.7874 -0.4064)
			(stroke
				(width 0.1524)
				(type default)
			)
			(layer "B.SilkS")
		)
		(fp_line
			(start -0.7874 -0.4064)
			(end -0.7874 0.4064)
			(stroke
				(width 0.1524)
				(type default)
			)
			(layer "B.SilkS")
		)
		(fp_line
			(start 0.7874 -0.4064)
			(end -0.7874 -0.4064)
			(stroke
				(width 0.1524)
				(type default)
			)
			(layer "B.SilkS")
		)
		(fp_line
			(start -0.67945 0.3048)
			(end -0.120396 0.3048)
			(stroke
				(width 0.1)
				(type default)
			)
			(layer "B.Fab")
		)
		(fp_line
			(start -0.120396 0.3048)
			(end -0.120396 0.2794)
			(stroke
				(width 0.1)
				(type default)
			)
			(layer "B.Fab")
		)
		(fp_line
			(start 0.12065 0.3048)
			(end 0.67945 0.3048)
			(stroke
				(width 0.1)
				(type default)
			)
			(layer "B.Fab")
		)
		(fp_line
			(start 0.67945 0.3048)
			(end 0.67945 -0.305054)
			(stroke
				(width 0.1)
				(type default)
			)
			(layer "B.Fab")
		)
		(fp_line
			(start -0.120396 0.2794)
			(end 0.12065 0.2794)
			(stroke
				(width 0.1)
				(type default)
			)
			(layer "B.Fab")
		)
		(fp_line
			(start 0.12065 0.2794)
			(end 0.12065 0.3048)
			(stroke
				(width 0.1)
				(type default)
			)
			(layer "B.Fab")
		)
		(fp_line
			(start -0.12065 -0.2794)
			(end -0.12065 -0.3048)
			(stroke
				(width 0.1)
				(type default)
			)
			(layer "B.Fab")
		)
		(fp_line
			(start 0.12065 -0.2794)
			(end -0.12065 -0.2794)
			(stroke
				(width 0.1)
				(type default)
			)
			(layer "B.Fab")
		)
		(fp_line
			(start -0.67945 -0.3048)
			(end -0.67945 0.3048)
			(stroke
				(width 0.1)
				(type default)
			)
			(layer "B.Fab")
		)
		(fp_line
			(start -0.12065 -0.3048)
			(end -0.67945 -0.3048)
			(stroke
				(width 0.1)
				(type default)
			)
			(layer "B.Fab")
		)
		(fp_line
			(start 0.12065 -0.305054)
			(end 0.12065 -0.2794)
			(stroke
				(width 0.1)
				(type default)
			)
			(layer "B.Fab")
		)
		(fp_line
			(start 0.67945 -0.305054)
			(end 0.12065 -0.305054)
			(stroke
				(width 0.1)
				(type default)
			)
			(layer "B.Fab")
		)
		(pad "1" smd circle
			(at 0.40005 0 90)
			(size 0 0)
			(layers "B.Cu" "B.Mask" "B.Paste")
			(net "HSC_VDD_R_3")
		)
		(pad "2" smd circle
			(at -0.40005 0 90)
			(size 0 0)
			(layers "B.Cu" "B.Mask" "B.Paste")
			(net "HSC_VDD")
		)
	)
	(footprint ""
		(layer "B.Cu")
		(at 315.11748 -56.276748 180)
		(property "Reference" "R1486"
			(at 0 0 0)
			(layer "B.SilkS")
			(hide yes)
			(effects
				(font
					(size 1.27 1.27)
				)
				(justify mirror)
			)
		)
		(property "Value" ""
			(at 0 0 0)
			(layer "B.Fab")
			(effects
				(font
					(size 1.27 1.27)
				)
				(justify mirror)
			)
		)
		(duplicate_pad_numbers_are_jumpers no)
		(fp_line
			(start 0.7874 0.4064)
			(end 0.7874 -0.4064)
			(stroke
				(width 0.1524)
				(type default)
			)
			(layer "B.SilkS")
		)
		(fp_line
			(start 0.7874 -0.4064)
			(end -0.7874 -0.4064)
			(stroke
				(width 0.1524)
				(type default)
			)
			(layer "B.SilkS")
		)
		(fp_line
			(start -0.7874 0.4064)
			(end 0.7874 0.4064)
			(stroke
				(width 0.1524)
				(type default)
			)
			(layer "B.SilkS")
		)
		(fp_line
			(start -0.7874 -0.4064)
			(end -0.7874 0.4064)
			(stroke
				(width 0.1524)
				(type default)
			)
			(layer "B.SilkS")
		)
		(fp_line
			(start 0.67945 0.3048)
			(end 0.67945 -0.305054)
			(stroke
				(width 0.1)
				(type default)
			)
			(layer "B.Fab")
		)
		(fp_line
			(start 0.67945 -0.305054)
			(end 0.12065 -0.305054)
			(stroke
				(width 0.1)
				(type default)
			)
			(layer "B.Fab")
		)
		(fp_line
			(start 0.12065 0.3048)
			(end 0.67945 0.3048)
			(stroke
				(width 0.1)
				(type default)
			)
			(layer "B.Fab")
		)
		(fp_line
			(start 0.12065 0.2794)
			(end 0.12065 0.3048)
			(stroke
				(width 0.1)
				(type default)
			)
			(layer "B.Fab")
		)
		(fp_line
			(start 0.12065 -0.2794)
			(end -0.12065 -0.2794)
			(stroke
				(width 0.1)
				(type default)
			)
			(layer "B.Fab")
		)
		(fp_line
			(start 0.12065 -0.305054)
			(end 0.12065 -0.2794)
			(stroke
				(width 0.1)
				(type default)
			)
			(layer "B.Fab")
		)
		(fp_line
			(start -0.120396 0.3048)
			(end -0.120396 0.2794)
			(stroke
				(width 0.1)
				(type default)
			)
			(layer "B.Fab")
		)
		(fp_line
			(start -0.120396 0.2794)
			(end 0.12065 0.2794)
			(stroke
				(width 0.1)
				(type default)
			)
			(layer "B.Fab")
		)
		(fp_line
			(start -0.12065 -0.2794)
			(end -0.12065 -0.3048)
			(stroke
				(width 0.1)
				(type default)
			)
			(layer "B.Fab")
		)
		(fp_line
			(start -0.12065 -0.3048)
			(end -0.67945 -0.3048)
			(stroke
				(width 0.1)
				(type default)
			)
			(layer "B.Fab")
		)
		(fp_line
			(start -0.67945 0.3048)
			(end -0.120396 0.3048)
			(stroke
				(width 0.1)
				(type default)
			)
			(layer "B.Fab")
		)
		(fp_line
			(start -0.67945 -0.3048)
			(end -0.67945 0.3048)
			(stroke
				(width 0.1)
				(type default)
			)
			(layer "B.Fab")
		)
		(pad "1" smd circle
			(at 0.40005 0)
			(size 0 0)
			(layers "B.Cu" "B.Mask" "B.Paste")
			(net "PVNN_TERM_CPU0")
		)
		(pad "2" smd circle
			(at -0.40005 0)
			(size 0 0)
			(layers "B.Cu" "B.Mask" "B.Paste")
			(net "FM_PCH_TRIGGER1_R_N")
		)
	)
	(footprint ""
		(layer "B.Cu")
		(at 235.9406 -301.023528)
		(property "Reference" ""
			(at 0 0 0)
			(layer "B.SilkS")
			(hide yes)
			(effects
				(font
					(size 1.27 1.27)
				)
				(justify mirror)
			)
		)
		(property "Value" ""
			(at 0 0 0)
			(layer "B.Fab")
			(effects
				(font
					(size 1.27 1.27)
				)
				(justify mirror)
			)
		)
		(duplicate_pad_numbers_are_jumpers no)
		(pad "1" smd circle
			(at 0 0 180)
			(size 0.9906 0.9906)
			(layers "B.Cu" "B.Mask" "B.Paste")
			(net "Net_293")
		)
		(zone
			(layer "B.Cu")
			(hatch none 0.5)
			(connect_pads
				(clearance 0)
			)
			(min_thickness 0.25)
			(keepout
				(tracks not_allowed)
				(vias allowed)
				(pads allowed)
				(copperpour not_allowed)
				(footprints allowed)
			)
			(placement
				(enabled no)
				(sheetname "")
			)
			(fill
				(thermal_gap 0.5)
				(thermal_bridge_width 0.5)
				(island_removal_mode 0)
			)
			(polygon
				(pts
					(arc
						(start 237.5662 -301.023528)
						(mid 234.315 -301.023528)
						(end 237.5662 -301.023528)
					)
				)
			)
		)
	)
	(footprint ""
		(layer "B.Cu")
		(at 160.935162 -41.832784 90)
		(property "Reference" "R4450"
			(at 0 0 90)
			(layer "B.SilkS")
			(hide yes)
			(effects
				(font
					(size 1.27 1.27)
				)
				(justify mirror)
			)
		)
		(property "Value" ""
			(at 0 0 90)
			(layer "B.Fab")
			(effects
				(font
					(size 1.27 1.27)
				)
				(justify mirror)
			)
		)
		(duplicate_pad_numbers_are_jumpers no)
		(fp_line
			(start 0.7874 -0.4064)
			(end -0.7874 -0.4064)
			(stroke
				(width 0.1524)
				(type default)
			)
			(layer "B.SilkS")
		)
		(fp_line
			(start -0.7874 -0.4064)
			(end -0.7874 0.4064)
			(stroke
				(width 0.1524)
				(type default)
			)
			(layer "B.SilkS")
		)
		(fp_line
			(start 0.7874 0.4064)
			(end 0.7874 -0.4064)
			(stroke
				(width 0.1524)
				(type default)
			)
			(layer "B.SilkS")
		)
		(fp_line
			(start -0.7874 0.4064)
			(end 0.7874 0.4064)
			(stroke
				(width 0.1524)
				(type default)
			)
			(layer "B.SilkS")
		)
		(fp_line
			(start 0.67945 -0.305054)
			(end 0.12065 -0.305054)
			(stroke
				(width 0.1)
				(type default)
			)
			(layer "B.Fab")
		)
		(fp_line
			(start 0.12065 -0.305054)
			(end 0.12065 -0.2794)
			(stroke
				(width 0.1)
				(type default)
			)
			(layer "B.Fab")
		)
		(fp_line
			(start -0.12065 -0.3048)
			(end -0.67945 -0.3048)
			(stroke
				(width 0.1)
				(type default)
			)
			(layer "B.Fab")
		)
		(fp_line
			(start -0.67945 -0.3048)
			(end -0.67945 0.3048)
			(stroke
				(width 0.1)
				(type default)
			)
			(layer "B.Fab")
		)
		(fp_line
			(start 0.12065 -0.2794)
			(end -0.12065 -0.2794)
			(stroke
				(width 0.1)
				(type default)
			)
			(layer "B.Fab")
		)
		(fp_line
			(start -0.12065 -0.2794)
			(end -0.12065 -0.3048)
			(stroke
				(width 0.1)
				(type default)
			)
			(layer "B.Fab")
		)
		(fp_line
			(start 0.12065 0.2794)
			(end 0.12065 0.3048)
			(stroke
				(width 0.1)
				(type default)
			)
			(layer "B.Fab")
		)
		(fp_line
			(start -0.120396 0.2794)
			(end 0.12065 0.2794)
			(stroke
				(width 0.1)
				(type default)
			)
			(layer "B.Fab")
		)
		(fp_line
			(start 0.67945 0.3048)
			(end 0.67945 -0.305054)
			(stroke
				(width 0.1)
				(type default)
			)
			(layer "B.Fab")
		)
		(fp_line
			(start 0.12065 0.3048)
			(end 0.67945 0.3048)
			(stroke
				(width 0.1)
				(type default)
			)
			(layer "B.Fab")
		)
		(fp_line
			(start -0.120396 0.3048)
			(end -0.120396 0.2794)
			(stroke
				(width 0.1)
				(type default)
			)
			(layer "B.Fab")
		)
		(fp_line
			(start -0.67945 0.3048)
			(end -0.120396 0.3048)
			(stroke
				(width 0.1)
				(type default)
			)
			(layer "B.Fab")
		)
		(pad "1" smd circle
			(at 0.40005 0 270)
			(size 0 0)
			(layers "B.Cu" "B.Mask" "B.Paste")
			(net "P3V3_AUX")
		)
		(pad "2" smd circle
			(at -0.40005 0 270)
			(size 0 0)
			(layers "B.Cu" "B.Mask" "B.Paste")
			(net "P3V3_AUX_USB_HUB_2")
		)
	)
	(footprint ""
		(layer "B.Cu")
		(at 234.889294 -132.470906 90)
		(property "Reference" "R575"
			(at 0 0 90)
			(layer "B.SilkS")
			(hide yes)
			(effects
				(font
					(size 1.27 1.27)
				)
				(justify mirror)
			)
		)
		(property "Value" ""
			(at 0 0 90)
			(layer "B.Fab")
			(effects
				(font
					(size 1.27 1.27)
				)
				(justify mirror)
			)
		)
		(duplicate_pad_numbers_are_jumpers no)
		(fp_line
			(start 0.7874 -0.4064)
			(end -0.7874 -0.4064)
			(stroke
				(width 0.1524)
				(type default)
			)
			(layer "B.SilkS")
		)
		(fp_line
			(start -0.7874 -0.4064)
			(end -0.7874 0.4064)
			(stroke
				(width 0.1524)
				(type default)
			)
			(layer "B.SilkS")
		)
		(fp_line
			(start 0.7874 0.4064)
			(end 0.7874 -0.4064)
			(stroke
				(width 0.1524)
				(type default)
			)
			(layer "B.SilkS")
		)
		(fp_line
			(start -0.7874 0.4064)
			(end 0.7874 0.4064)
			(stroke
				(width 0.1524)
				(type default)
			)
			(layer "B.SilkS")
		)
		(fp_line
			(start 0.67945 -0.305054)
			(end 0.12065 -0.305054)
			(stroke
				(width 0.1)
				(type default)
			)
			(layer "B.Fab")
		)
		(fp_line
			(start 0.12065 -0.305054)
			(end 0.12065 -0.2794)
			(stroke
				(width 0.1)
				(type default)
			)
			(layer "B.Fab")
		)
		(fp_line
			(start -0.12065 -0.3048)
			(end -0.67945 -0.3048)
			(stroke
				(width 0.1)
				(type default)
			)
			(layer "B.Fab")
		)
		(fp_line
			(start -0.67945 -0.3048)
			(end -0.67945 0.3048)
			(stroke
				(width 0.1)
				(type default)
			)
			(layer "B.Fab")
		)
		(fp_line
			(start 0.12065 -0.2794)
			(end -0.12065 -0.2794)
			(stroke
				(width 0.1)
				(type default)
			)
			(layer "B.Fab")
		)
		(fp_line
			(start -0.12065 -0.2794)
			(end -0.12065 -0.3048)
			(stroke
				(width 0.1)
				(type default)
			)
			(layer "B.Fab")
		)
		(fp_line
			(start 0.12065 0.2794)
			(end 0.12065 0.3048)
			(stroke
				(width 0.1)
				(type default)
			)
			(layer "B.Fab")
		)
		(fp_line
			(start -0.120396 0.2794)
			(end 0.12065 0.2794)
			(stroke
				(width 0.1)
				(type default)
			)
			(layer "B.Fab")
		)
		(fp_line
			(start 0.67945 0.3048)
			(end 0.67945 -0.305054)
			(stroke
				(width 0.1)
				(type default)
			)
			(layer "B.Fab")
		)
		(fp_line
			(start 0.12065 0.3048)
			(end 0.67945 0.3048)
			(stroke
				(width 0.1)
				(type default)
			)
			(layer "B.Fab")
		)
		(fp_line
			(start -0.120396 0.3048)
			(end -0.120396 0.2794)
			(stroke
				(width 0.1)
				(type default)
			)
			(layer "B.Fab")
		)
		(fp_line
			(start -0.67945 0.3048)
			(end -0.120396 0.3048)
			(stroke
				(width 0.1)
				(type default)
			)
			(layer "B.Fab")
		)
		(pad "1" smd circle
			(at 0.40005 0 270)
			(size 0 0)
			(layers "B.Cu" "B.Mask" "B.Paste")
			(net "FM_PLD_CLKS_DEV_EN")
		)
		(pad "2" smd circle
			(at -0.40005 0 270)
			(size 0 0)
			(layers "B.Cu" "B.Mask" "B.Paste")
			(net "FM_DB2000_DEV_EN")
		)
	)
	(footprint ""
		(layer "B.Cu")
		(at 345.794076 -59.029854 45)
		(property "Reference" "C158"
			(at 0 0 45)
			(layer "B.SilkS")
			(hide yes)
			(effects
				(font
					(size 1.27 1.27)
				)
				(justify mirror)
			)
		)
		(property "Value" ""
			(at 0 0 45)
			(layer "B.Fab")
			(effects
				(font
					(size 1.27 1.27)
				)
				(justify mirror)
			)
		)
		(duplicate_pad_numbers_are_jumpers no)
		(fp_line
			(start -0.299941 -0.15015)
			(end -0.299941 0.15015)
			(stroke
				(width 0.1)
				(type default)
			)
			(layer "B.Fab")
		)
		(fp_line
			(start -0.299941 0.15015)
			(end 0.299941 0.15015)
			(stroke
				(width 0.1)
				(type default)
			)
			(layer "B.Fab")
		)
		(fp_line
			(start 0.299941 -0.15015)
			(end -0.299941 -0.15015)
			(stroke
				(width 0.1)
				(type default)
			)
			(layer "B.Fab")
		)
		(fp_line
			(start 0.299941 0.15015)
			(end 0.299941 -0.15015)
			(stroke
				(width 0.1)
				(type default)
			)
			(layer "B.Fab")
		)
		(pad "1" smd rect
			(at 0.266699 0 225)
			(size 0.3048 0.381)
			(layers "B.Cu" "B.Mask" "B.Paste")
			(net "DMI_CPU0_PCH_RX_C_DP<6>")
		)
		(pad "2" smd rect
			(at -0.266699 0 225)
			(size 0.3048 0.381)
			(layers "B.Cu" "B.Mask" "B.Paste")
			(net "DMI_CPU0_PCH_RX_DP<6>")
		)
	)
	(footprint ""
		(layer "B.Cu")
		(at 181.457346 -321.554856 -90)
		(property "Reference" "C88"
			(at 0 0 90)
			(layer "B.SilkS")
			(hide yes)
			(effects
				(font
					(size 1.27 1.27)
				)
				(justify mirror)
			)
		)
		(property "Value" ""
			(at 0 0 90)
			(layer "B.Fab")
			(effects
				(font
					(size 1.27 1.27)
				)
				(justify mirror)
			)
		)
		(duplicate_pad_numbers_are_jumpers no)
		(fp_line
			(start -1.524 0.762)
			(end 1.524 0.762)
			(stroke
				(width 0.1524)
				(type default)
			)
			(layer "B.SilkS")
		)
		(fp_line
			(start 1.524 0.762)
			(end 1.524 -0.762)
			(stroke
				(width 0.1524)
				(type default)
			)
			(layer "B.SilkS")
		)
		(fp_line
			(start -1.524 -0.762)
			(end -1.524 0.762)
			(stroke
				(width 0.1524)
				(type default)
			)
			(layer "B.SilkS")
		)
		(fp_line
			(start 1.524 -0.762)
			(end -1.524 -0.762)
			(stroke
				(width 0.1524)
				(type default)
			)
			(layer "B.SilkS")
		)
		(fp_line
			(start -1.1049 0.724916)
			(end -1.1049 -0.724916)
			(stroke
				(width 0.1)
				(type default)
			)
			(layer "B.Fab")
		)
		(fp_line
			(start 1.1049 0.724916)
			(end -1.1049 0.724916)
			(stroke
				(width 0.1)
				(type default)
			)
			(layer "B.Fab")
		)
		(fp_line
			(start -1.1049 -0.724916)
			(end 1.1049 -0.724916)
			(stroke
				(width 0.1)
				(type default)
			)
			(layer "B.Fab")
		)
		(fp_line
			(start 1.1049 -0.724916)
			(end 1.1049 0.724916)
			(stroke
				(width 0.1)
				(type default)
			)
			(layer "B.Fab")
		)
		(pad "1" smd rect
			(at 0.889 0 270)
			(size 1.016 1.27)
			(layers "B.Cu" "B.Mask" "B.Paste")
			(net "P12V_S3_AUX_CPU1_NVDIMM")
		)
		(pad "2" smd rect
			(at -0.889 0 270)
			(size 1.016 1.27)
			(layers "B.Cu" "B.Mask" "B.Paste")
			(net "GND")
		)
	)
	(footprint ""
		(layer "B.Cu")
		(at 22.219412 -184.31256 180)
		(property "Reference" "PR3338"
			(at 0 0 0)
			(layer "B.SilkS")
			(hide yes)
			(effects
				(font
					(size 1.27 1.27)
				)
				(justify mirror)
			)
		)
		(property "Value" ""
			(at 0 0 0)
			(layer "B.Fab")
			(effects
				(font
					(size 1.27 1.27)
				)
				(justify mirror)
			)
		)
		(duplicate_pad_numbers_are_jumpers no)
		(fp_line
			(start 0.7874 0.4064)
			(end 0.7874 -0.4064)
			(stroke
				(width 0.1524)
				(type default)
			)
			(layer "B.SilkS")
		)
		(fp_line
			(start 0.7874 -0.4064)
			(end -0.7874 -0.4064)
			(stroke
				(width 0.1524)
				(type default)
			)
			(layer "B.SilkS")
		)
		(fp_line
			(start -0.7874 0.4064)
			(end 0.7874 0.4064)
			(stroke
				(width 0.1524)
				(type default)
			)
			(layer "B.SilkS")
		)
		(fp_line
			(start -0.7874 -0.4064)
			(end -0.7874 0.4064)
			(stroke
				(width 0.1524)
				(type default)
			)
			(layer "B.SilkS")
		)
		(fp_line
			(start 0.67945 0.3048)
			(end 0.67945 -0.305054)
			(stroke
				(width 0.1)
				(type default)
			)
			(layer "B.Fab")
		)
		(fp_line
			(start 0.67945 -0.305054)
			(end 0.12065 -0.305054)
			(stroke
				(width 0.1)
				(type default)
			)
			(layer "B.Fab")
		)
		(fp_line
			(start 0.12065 0.3048)
			(end 0.67945 0.3048)
			(stroke
				(width 0.1)
				(type default)
			)
			(layer "B.Fab")
		)
		(fp_line
			(start 0.12065 0.2794)
			(end 0.12065 0.3048)
			(stroke
				(width 0.1)
				(type default)
			)
			(layer "B.Fab")
		)
		(fp_line
			(start 0.12065 -0.2794)
			(end -0.12065 -0.2794)
			(stroke
				(width 0.1)
				(type default)
			)
			(layer "B.Fab")
		)
		(fp_line
			(start 0.12065 -0.305054)
			(end 0.12065 -0.2794)
			(stroke
				(width 0.1)
				(type default)
			)
			(layer "B.Fab")
		)
		(fp_line
			(start -0.120396 0.3048)
			(end -0.120396 0.2794)
			(stroke
				(width 0.1)
				(type default)
			)
			(layer "B.Fab")
		)
		(fp_line
			(start -0.120396 0.2794)
			(end 0.12065 0.2794)
			(stroke
				(width 0.1)
				(type default)
			)
			(layer "B.Fab")
		)
		(fp_line
			(start -0.12065 -0.2794)
			(end -0.12065 -0.3048)
			(stroke
				(width 0.1)
				(type default)
			)
			(layer "B.Fab")
		)
		(fp_line
			(start -0.12065 -0.3048)
			(end -0.67945 -0.3048)
			(stroke
				(width 0.1)
				(type default)
			)
			(layer "B.Fab")
		)
		(fp_line
			(start -0.67945 0.3048)
			(end -0.120396 0.3048)
			(stroke
				(width 0.1)
				(type default)
			)
			(layer "B.Fab")
		)
		(fp_line
			(start -0.67945 -0.3048)
			(end -0.67945 0.3048)
			(stroke
				(width 0.1)
				(type default)
			)
			(layer "B.Fab")
		)
		(pad "1" smd circle
			(at 0.40005 0)
			(size 0 0)
			(layers "B.Cu" "B.Mask" "B.Paste")
			(net "P3V3_AUX")
		)
		(pad "2" smd circle
			(at -0.40005 0)
			(size 0 0)
			(layers "B.Cu" "B.Mask" "B.Paste")
			(net "PVNN_MAIN_CPU1_VCC")
		)
	)
	(footprint ""
		(layer "B.Cu")
		(at 453.34174 -71.244968 90)
		(property "Reference" "PC71"
			(at 0 0 90)
			(layer "B.SilkS")
			(hide yes)
			(effects
				(font
					(size 1.27 1.27)
				)
				(justify mirror)
			)
		)
		(property "Value" ""
			(at 0 0 90)
			(layer "B.Fab")
			(effects
				(font
					(size 1.27 1.27)
				)
				(justify mirror)
			)
		)
		(duplicate_pad_numbers_are_jumpers no)
		(fp_line
			(start 1.524 -0.762)
			(end -1.524 -0.762)
			(stroke
				(width 0.1524)
				(type default)
			)
			(layer "B.SilkS")
		)
		(fp_line
			(start -1.524 -0.762)
			(end -1.524 0.762)
			(stroke
				(width 0.1524)
				(type default)
			)
			(layer "B.SilkS")
		)
		(fp_line
			(start 1.524 0.762)
			(end 1.524 -0.762)
			(stroke
				(width 0.1524)
				(type default)
			)
			(layer "B.SilkS")
		)
		(fp_line
			(start -1.524 0.762)
			(end 1.524 0.762)
			(stroke
				(width 0.1524)
				(type default)
			)
			(layer "B.SilkS")
		)
		(fp_line
			(start 1.1049 -0.724916)
			(end 1.1049 0.724916)
			(stroke
				(width 0.1)
				(type default)
			)
			(layer "B.Fab")
		)
		(fp_line
			(start -1.1049 -0.724916)
			(end 1.1049 -0.724916)
			(stroke
				(width 0.1)
				(type default)
			)
			(layer "B.Fab")
		)
		(fp_line
			(start 1.1049 0.724916)
			(end -1.1049 0.724916)
			(stroke
				(width 0.1)
				(type default)
			)
			(layer "B.Fab")
		)
		(fp_line
			(start -1.1049 0.724916)
			(end -1.1049 -0.724916)
			(stroke
				(width 0.1)
				(type default)
			)
			(layer "B.Fab")
		)
		(pad "1" smd rect
			(at 0.889 0 90)
			(size 1.016 1.27)
			(layers "B.Cu" "B.Mask" "B.Paste")
			(net "SW_P3V3_AUX_FLT")
		)
		(pad "2" smd rect
			(at -0.889 0 90)
			(size 1.016 1.27)
			(layers "B.Cu" "B.Mask" "B.Paste")
			(net "GND")
		)
	)
	(footprint ""
		(layer "B.Cu")
		(at 368.075972 -184.400952 90)
		(property "Reference" "R967"
			(at 0 0 90)
			(layer "B.SilkS")
			(hide yes)
			(effects
				(font
					(size 1.27 1.27)
				)
				(justify mirror)
			)
		)
		(property "Value" ""
			(at 0 0 90)
			(layer "B.Fab")
			(effects
				(font
					(size 1.27 1.27)
				)
				(justify mirror)
			)
		)
		(duplicate_pad_numbers_are_jumpers no)
		(fp_line
			(start 0.7874 -0.4064)
			(end -0.7874 -0.4064)
			(stroke
				(width 0.1524)
				(type default)
			)
			(layer "B.SilkS")
		)
		(fp_line
			(start -0.7874 -0.4064)
			(end -0.7874 0.4064)
			(stroke
				(width 0.1524)
				(type default)
			)
			(layer "B.SilkS")
		)
		(fp_line
			(start 0.7874 0.4064)
			(end 0.7874 -0.4064)
			(stroke
				(width 0.1524)
				(type default)
			)
			(layer "B.SilkS")
		)
		(fp_line
			(start -0.7874 0.4064)
			(end 0.7874 0.4064)
			(stroke
				(width 0.1524)
				(type default)
			)
			(layer "B.SilkS")
		)
		(fp_line
			(start 0.67945 -0.305054)
			(end 0.12065 -0.305054)
			(stroke
				(width 0.1)
				(type default)
			)
			(layer "B.Fab")
		)
		(fp_line
			(start 0.12065 -0.305054)
			(end 0.12065 -0.2794)
			(stroke
				(width 0.1)
				(type default)
			)
			(layer "B.Fab")
		)
		(fp_line
			(start -0.12065 -0.3048)
			(end -0.67945 -0.3048)
			(stroke
				(width 0.1)
				(type default)
			)
			(layer "B.Fab")
		)
		(fp_line
			(start -0.67945 -0.3048)
			(end -0.67945 0.3048)
			(stroke
				(width 0.1)
				(type default)
			)
			(layer "B.Fab")
		)
		(fp_line
			(start 0.12065 -0.2794)
			(end -0.12065 -0.2794)
			(stroke
				(width 0.1)
				(type default)
			)
			(layer "B.Fab")
		)
		(fp_line
			(start -0.12065 -0.2794)
			(end -0.12065 -0.3048)
			(stroke
				(width 0.1)
				(type default)
			)
			(layer "B.Fab")
		)
		(fp_line
			(start 0.12065 0.2794)
			(end 0.12065 0.3048)
			(stroke
				(width 0.1)
				(type default)
			)
			(layer "B.Fab")
		)
		(fp_line
			(start -0.120396 0.2794)
			(end 0.12065 0.2794)
			(stroke
				(width 0.1)
				(type default)
			)
			(layer "B.Fab")
		)
		(fp_line
			(start 0.67945 0.3048)
			(end 0.67945 -0.305054)
			(stroke
				(width 0.1)
				(type default)
			)
			(layer "B.Fab")
		)
		(fp_line
			(start 0.12065 0.3048)
			(end 0.67945 0.3048)
			(stroke
				(width 0.1)
				(type default)
			)
			(layer "B.Fab")
		)
		(fp_line
			(start -0.120396 0.3048)
			(end -0.120396 0.2794)
			(stroke
				(width 0.1)
				(type default)
			)
			(layer "B.Fab")
		)
		(fp_line
			(start -0.67945 0.3048)
			(end -0.120396 0.3048)
			(stroke
				(width 0.1)
				(type default)
			)
			(layer "B.Fab")
		)
		(pad "1" smd circle
			(at 0.40005 0 270)
			(size 0 0)
			(layers "B.Cu" "B.Mask" "B.Paste")
			(net "P3V3_AUX")
		)
		(pad "2" smd circle
			(at -0.40005 0 270)
			(size 0 0)
			(layers "B.Cu" "B.Mask" "B.Paste")
			(net "SMB_PEHPCPU0_LVC3_SDA")
		)
	)
	(footprint ""
		(layer "B.Cu")
		(at 339.27669 -47.512986 180)
		(property "Reference" "C1228"
			(at 0 0 0)
			(layer "B.SilkS")
			(hide yes)
			(effects
				(font
					(size 1.27 1.27)
				)
				(justify mirror)
			)
		)
		(property "Value" ""
			(at 0 0 0)
			(layer "B.Fab")
			(effects
				(font
					(size 1.27 1.27)
				)
				(justify mirror)
			)
		)
		(duplicate_pad_numbers_are_jumpers no)
		(fp_line
			(start 0.7874 0.4064)
			(end 0.7874 -0.4064)
			(stroke
				(width 0.1524)
				(type default)
			)
			(layer "B.SilkS")
		)
		(fp_line
			(start 0.7874 -0.4064)
			(end -0.7874 -0.4064)
			(stroke
				(width 0.1524)
				(type default)
			)
			(layer "B.SilkS")
		)
		(fp_line
			(start -0.7874 0.4064)
			(end 0.7874 0.4064)
			(stroke
				(width 0.1524)
				(type default)
			)
			(layer "B.SilkS")
		)
		(fp_line
			(start -0.7874 -0.4064)
			(end -0.7874 0.4064)
			(stroke
				(width 0.1524)
				(type default)
			)
			(layer "B.SilkS")
		)
		(fp_line
			(start 0.67945 0.3048)
			(end 0.67945 -0.305054)
			(stroke
				(width 0.1)
				(type default)
			)
			(layer "B.Fab")
		)
		(fp_line
			(start 0.67945 -0.305054)
			(end 0.12065 -0.305054)
			(stroke
				(width 0.1)
				(type default)
			)
			(layer "B.Fab")
		)
		(fp_line
			(start 0.12065 0.3048)
			(end 0.67945 0.3048)
			(stroke
				(width 0.1)
				(type default)
			)
			(layer "B.Fab")
		)
		(fp_line
			(start 0.12065 0.2794)
			(end 0.12065 0.3048)
			(stroke
				(width 0.1)
				(type default)
			)
			(layer "B.Fab")
		)
		(fp_line
			(start 0.12065 -0.2794)
			(end -0.12065 -0.2794)
			(stroke
				(width 0.1)
				(type default)
			)
			(layer "B.Fab")
		)
		(fp_line
			(start 0.12065 -0.305054)
			(end 0.12065 -0.2794)
			(stroke
				(width 0.1)
				(type default)
			)
			(layer "B.Fab")
		)
		(fp_line
			(start -0.120396 0.3048)
			(end -0.120396 0.2794)
			(stroke
				(width 0.1)
				(type default)
			)
			(layer "B.Fab")
		)
		(fp_line
			(start -0.120396 0.2794)
			(end 0.12065 0.2794)
			(stroke
				(width 0.1)
				(type default)
			)
			(layer "B.Fab")
		)
		(fp_line
			(start -0.12065 -0.2794)
			(end -0.12065 -0.3048)
			(stroke
				(width 0.1)
				(type default)
			)
			(layer "B.Fab")
		)
		(fp_line
			(start -0.12065 -0.3048)
			(end -0.67945 -0.3048)
			(stroke
				(width 0.1)
				(type default)
			)
			(layer "B.Fab")
		)
		(fp_line
			(start -0.67945 0.3048)
			(end -0.120396 0.3048)
			(stroke
				(width 0.1)
				(type default)
			)
			(layer "B.Fab")
		)
		(fp_line
			(start -0.67945 -0.3048)
			(end -0.67945 0.3048)
			(stroke
				(width 0.1)
				(type default)
			)
			(layer "B.Fab")
		)
		(pad "1" smd circle
			(at 0.40005 0)
			(size 0 0)
			(layers "B.Cu" "B.Mask" "B.Paste")
			(net "P1V05_PCH_AUX")
		)
		(pad "2" smd circle
			(at -0.40005 0)
			(size 0 0)
			(layers "B.Cu" "B.Mask" "B.Paste")
			(net "GND")
		)
	)
	(footprint ""
		(layer "B.Cu")
		(at 374.002046 -328.298048 -90)
		(property "Reference" "PC267_P0_5"
			(at 0 0 90)
			(layer "B.SilkS")
			(hide yes)
			(effects
				(font
					(size 1.27 1.27)
				)
				(justify mirror)
			)
		)
		(property "Value" ""
			(at 0 0 90)
			(layer "B.Fab")
			(effects
				(font
					(size 1.27 1.27)
				)
				(justify mirror)
			)
		)
		(duplicate_pad_numbers_are_jumpers no)
		(fp_line
			(start -1.524 0.762)
			(end 1.524 0.762)
			(stroke
				(width 0.1524)
				(type default)
			)
			(layer "B.SilkS")
		)
		(fp_line
			(start 1.524 0.762)
			(end 1.524 -0.762)
			(stroke
				(width 0.1524)
				(type default)
			)
			(layer "B.SilkS")
		)
		(fp_line
			(start -1.524 -0.762)
			(end -1.524 0.762)
			(stroke
				(width 0.1524)
				(type default)
			)
			(layer "B.SilkS")
		)
		(fp_line
			(start 1.524 -0.762)
			(end -1.524 -0.762)
			(stroke
				(width 0.1524)
				(type default)
			)
			(layer "B.SilkS")
		)
		(fp_line
			(start -1.1049 0.724916)
			(end -1.1049 -0.724916)
			(stroke
				(width 0.1)
				(type default)
			)
			(layer "B.Fab")
		)
		(fp_line
			(start 1.1049 0.724916)
			(end -1.1049 0.724916)
			(stroke
				(width 0.1)
				(type default)
			)
			(layer "B.Fab")
		)
		(fp_line
			(start -1.1049 -0.724916)
			(end 1.1049 -0.724916)
			(stroke
				(width 0.1)
				(type default)
			)
			(layer "B.Fab")
		)
		(fp_line
			(start 1.1049 -0.724916)
			(end 1.1049 0.724916)
			(stroke
				(width 0.1)
				(type default)
			)
			(layer "B.Fab")
		)
		(pad "1" smd rect
			(at 0.889 0 270)
			(size 1.016 1.27)
			(layers "B.Cu" "B.Mask" "B.Paste")
			(net "PVCCIN_CPU0")
		)
		(pad "2" smd rect
			(at -0.889 0 270)
			(size 1.016 1.27)
			(layers "B.Cu" "B.Mask" "B.Paste")
			(net "GND")
		)
	)
	(footprint ""
		(layer "B.Cu")
		(at 343.8779 -35.222688 -90)
		(property "Reference" "R3938"
			(at 0 0 90)
			(layer "B.SilkS")
			(hide yes)
			(effects
				(font
					(size 1.27 1.27)
				)
				(justify mirror)
			)
		)
		(property "Value" ""
			(at 0 0 90)
			(layer "B.Fab")
			(effects
				(font
					(size 1.27 1.27)
				)
				(justify mirror)
			)
		)
		(duplicate_pad_numbers_are_jumpers no)
		(fp_line
			(start -0.7874 0.4064)
			(end 0.7874 0.4064)
			(stroke
				(width 0.1524)
				(type default)
			)
			(layer "B.SilkS")
		)
		(fp_line
			(start 0.7874 0.4064)
			(end 0.7874 -0.4064)
			(stroke
				(width 0.1524)
				(type default)
			)
			(layer "B.SilkS")
		)
		(fp_line
			(start -0.7874 -0.4064)
			(end -0.7874 0.4064)
			(stroke
				(width 0.1524)
				(type default)
			)
			(layer "B.SilkS")
		)
		(fp_line
			(start 0.7874 -0.4064)
			(end -0.7874 -0.4064)
			(stroke
				(width 0.1524)
				(type default)
			)
			(layer "B.SilkS")
		)
		(fp_line
			(start -0.67945 0.3048)
			(end -0.120396 0.3048)
			(stroke
				(width 0.1)
				(type default)
			)
			(layer "B.Fab")
		)
		(fp_line
			(start -0.120396 0.3048)
			(end -0.120396 0.2794)
			(stroke
				(width 0.1)
				(type default)
			)
			(layer "B.Fab")
		)
		(fp_line
			(start 0.12065 0.3048)
			(end 0.67945 0.3048)
			(stroke
				(width 0.1)
				(type default)
			)
			(layer "B.Fab")
		)
		(fp_line
			(start 0.67945 0.3048)
			(end 0.67945 -0.305054)
			(stroke
				(width 0.1)
				(type default)
			)
			(layer "B.Fab")
		)
		(fp_line
			(start -0.120396 0.2794)
			(end 0.12065 0.2794)
			(stroke
				(width 0.1)
				(type default)
			)
			(layer "B.Fab")
		)
		(fp_line
			(start 0.12065 0.2794)
			(end 0.12065 0.3048)
			(stroke
				(width 0.1)
				(type default)
			)
			(layer "B.Fab")
		)
		(fp_line
			(start -0.12065 -0.2794)
			(end -0.12065 -0.3048)
			(stroke
				(width 0.1)
				(type default)
			)
			(layer "B.Fab")
		)
		(fp_line
			(start 0.12065 -0.2794)
			(end -0.12065 -0.2794)
			(stroke
				(width 0.1)
				(type default)
			)
			(layer "B.Fab")
		)
		(fp_line
			(start -0.67945 -0.3048)
			(end -0.67945 0.3048)
			(stroke
				(width 0.1)
				(type default)
			)
			(layer "B.Fab")
		)
		(fp_line
			(start -0.12065 -0.3048)
			(end -0.67945 -0.3048)
			(stroke
				(width 0.1)
				(type default)
			)
			(layer "B.Fab")
		)
		(fp_line
			(start 0.12065 -0.305054)
			(end 0.12065 -0.2794)
			(stroke
				(width 0.1)
				(type default)
			)
			(layer "B.Fab")
		)
		(fp_line
			(start 0.67945 -0.305054)
			(end 0.12065 -0.305054)
			(stroke
				(width 0.1)
				(type default)
			)
			(layer "B.Fab")
		)
		(pad "1" smd circle
			(at 0.40005 0 90)
			(size 0 0)
			(layers "B.Cu" "B.Mask" "B.Paste")
			(net "PU_OC2_USB_N")
		)
		(pad "2" smd circle
			(at -0.40005 0 90)
			(size 0 0)
			(layers "B.Cu" "B.Mask" "B.Paste")
			(net "P3V3_AUX")
		)
	)
	(footprint ""
		(layer "B.Cu")
		(at 149.278848 -188.21019)
		(property "Reference" "R289"
			(at 0 0 0)
			(layer "B.SilkS")
			(hide yes)
			(effects
				(font
					(size 1.27 1.27)
				)
				(justify mirror)
			)
		)
		(property "Value" ""
			(at 0 0 0)
			(layer "B.Fab")
			(effects
				(font
					(size 1.27 1.27)
				)
				(justify mirror)
			)
		)
		(duplicate_pad_numbers_are_jumpers no)
		(fp_line
			(start -0.7874 -0.4064)
			(end -0.7874 0.4064)
			(stroke
				(width 0.1524)
				(type default)
			)
			(layer "B.SilkS")
		)
		(fp_line
			(start -0.7874 0.4064)
			(end 0.7874 0.4064)
			(stroke
				(width 0.1524)
				(type default)
			)
			(layer "B.SilkS")
		)
		(fp_line
			(start 0.7874 -0.4064)
			(end -0.7874 -0.4064)
			(stroke
				(width 0.1524)
				(type default)
			)
			(layer "B.SilkS")
		)
		(fp_line
			(start 0.7874 0.4064)
			(end 0.7874 -0.4064)
			(stroke
				(width 0.1524)
				(type default)
			)
			(layer "B.SilkS")
		)
		(fp_line
			(start -0.67945 -0.3048)
			(end -0.67945 0.3048)
			(stroke
				(width 0.1)
				(type default)
			)
			(layer "B.Fab")
		)
		(fp_line
			(start -0.67945 0.3048)
			(end -0.120396 0.3048)
			(stroke
				(width 0.1)
				(type default)
			)
			(layer "B.Fab")
		)
		(fp_line
			(start -0.12065 -0.3048)
			(end -0.67945 -0.3048)
			(stroke
				(width 0.1)
				(type default)
			)
			(layer "B.Fab")
		)
		(fp_line
			(start -0.12065 -0.2794)
			(end -0.12065 -0.3048)
			(stroke
				(width 0.1)
				(type default)
			)
			(layer "B.Fab")
		)
		(fp_line
			(start -0.120396 0.2794)
			(end 0.12065 0.2794)
			(stroke
				(width 0.1)
				(type default)
			)
			(layer "B.Fab")
		)
		(fp_line
			(start -0.120396 0.3048)
			(end -0.120396 0.2794)
			(stroke
				(width 0.1)
				(type default)
			)
			(layer "B.Fab")
		)
		(fp_line
			(start 0.12065 -0.305054)
			(end 0.12065 -0.2794)
			(stroke
				(width 0.1)
				(type default)
			)
			(layer "B.Fab")
		)
		(fp_line
			(start 0.12065 -0.2794)
			(end -0.12065 -0.2794)
			(stroke
				(width 0.1)
				(type default)
			)
			(layer "B.Fab")
		)
		(fp_line
			(start 0.12065 0.2794)
			(end 0.12065 0.3048)
			(stroke
				(width 0.1)
				(type default)
			)
			(layer "B.Fab")
		)
		(fp_line
			(start 0.12065 0.3048)
			(end 0.67945 0.3048)
			(stroke
				(width 0.1)
				(type default)
			)
			(layer "B.Fab")
		)
		(fp_line
			(start 0.67945 -0.305054)
			(end 0.12065 -0.305054)
			(stroke
				(width 0.1)
				(type default)
			)
			(layer "B.Fab")
		)
		(fp_line
			(start 0.67945 0.3048)
			(end 0.67945 -0.305054)
			(stroke
				(width 0.1)
				(type default)
			)
			(layer "B.Fab")
		)
		(pad "1" smd circle
			(at 0.40005 0 180)
			(size 0 0)
			(layers "B.Cu" "B.Mask" "B.Paste")
			(net "PD_CPU1_TXT_PLTEN")
		)
		(pad "2" smd circle
			(at -0.40005 0 180)
			(size 0 0)
			(layers "B.Cu" "B.Mask" "B.Paste")
			(net "GND")
		)
	)
	(footprint ""
		(layer "B.Cu")
		(at 190.367158 -13.60043 -90)
		(property "Reference" "R593"
			(at 0 0 90)
			(layer "B.SilkS")
			(hide yes)
			(effects
				(font
					(size 1.27 1.27)
				)
				(justify mirror)
			)
		)
		(property "Value" ""
			(at 0 0 90)
			(layer "B.Fab")
			(effects
				(font
					(size 1.27 1.27)
				)
				(justify mirror)
			)
		)
		(duplicate_pad_numbers_are_jumpers no)
		(fp_line
			(start -0.7874 0.4064)
			(end 0.7874 0.4064)
			(stroke
				(width 0.1524)
				(type default)
			)
			(layer "B.SilkS")
		)
		(fp_line
			(start 0.7874 0.4064)
			(end 0.7874 -0.4064)
			(stroke
				(width 0.1524)
				(type default)
			)
			(layer "B.SilkS")
		)
		(fp_line
			(start -0.7874 -0.4064)
			(end -0.7874 0.4064)
			(stroke
				(width 0.1524)
				(type default)
			)
			(layer "B.SilkS")
		)
		(fp_line
			(start 0.7874 -0.4064)
			(end -0.7874 -0.4064)
			(stroke
				(width 0.1524)
				(type default)
			)
			(layer "B.SilkS")
		)
		(fp_line
			(start -0.67945 0.3048)
			(end -0.120396 0.3048)
			(stroke
				(width 0.1)
				(type default)
			)
			(layer "B.Fab")
		)
		(fp_line
			(start -0.120396 0.3048)
			(end -0.120396 0.2794)
			(stroke
				(width 0.1)
				(type default)
			)
			(layer "B.Fab")
		)
		(fp_line
			(start 0.12065 0.3048)
			(end 0.67945 0.3048)
			(stroke
				(width 0.1)
				(type default)
			)
			(layer "B.Fab")
		)
		(fp_line
			(start 0.67945 0.3048)
			(end 0.67945 -0.305054)
			(stroke
				(width 0.1)
				(type default)
			)
			(layer "B.Fab")
		)
		(fp_line
			(start -0.120396 0.2794)
			(end 0.12065 0.2794)
			(stroke
				(width 0.1)
				(type default)
			)
			(layer "B.Fab")
		)
		(fp_line
			(start 0.12065 0.2794)
			(end 0.12065 0.3048)
			(stroke
				(width 0.1)
				(type default)
			)
			(layer "B.Fab")
		)
		(fp_line
			(start -0.12065 -0.2794)
			(end -0.12065 -0.3048)
			(stroke
				(width 0.1)
				(type default)
			)
			(layer "B.Fab")
		)
		(fp_line
			(start 0.12065 -0.2794)
			(end -0.12065 -0.2794)
			(stroke
				(width 0.1)
				(type default)
			)
			(layer "B.Fab")
		)
		(fp_line
			(start -0.67945 -0.3048)
			(end -0.67945 0.3048)
			(stroke
				(width 0.1)
				(type default)
			)
			(layer "B.Fab")
		)
		(fp_line
			(start -0.12065 -0.3048)
			(end -0.67945 -0.3048)
			(stroke
				(width 0.1)
				(type default)
			)
			(layer "B.Fab")
		)
		(fp_line
			(start 0.12065 -0.305054)
			(end 0.12065 -0.2794)
			(stroke
				(width 0.1)
				(type default)
			)
			(layer "B.Fab")
		)
		(fp_line
			(start 0.67945 -0.305054)
			(end 0.12065 -0.305054)
			(stroke
				(width 0.1)
				(type default)
			)
			(layer "B.Fab")
		)
		(pad "1" smd circle
			(at 0.40005 0 90)
			(size 0 0)
			(layers "B.Cu" "B.Mask" "B.Paste")
			(net "I3C_SPD_DDRABCD_CPU0_BMC_R_SCL")
		)
		(pad "2" smd circle
			(at -0.40005 0 90)
			(size 0 0)
			(layers "B.Cu" "B.Mask" "B.Paste")
			(net "I3C_SPD_DDRABCD_CPU0_BMC_SCL")
		)
	)
	(footprint ""
		(layer "B.Cu")
		(at 329.170538 -184.58815 -90)
		(property "Reference" "R296"
			(at 0 0 90)
			(layer "B.SilkS")
			(hide yes)
			(effects
				(font
					(size 1.27 1.27)
				)
				(justify mirror)
			)
		)
		(property "Value" ""
			(at 0 0 90)
			(layer "B.Fab")
			(effects
				(font
					(size 1.27 1.27)
				)
				(justify mirror)
			)
		)
		(duplicate_pad_numbers_are_jumpers no)
		(fp_line
			(start -0.7874 0.4064)
			(end 0.7874 0.4064)
			(stroke
				(width 0.1524)
				(type default)
			)
			(layer "B.SilkS")
		)
		(fp_line
			(start 0.7874 0.4064)
			(end 0.7874 -0.4064)
			(stroke
				(width 0.1524)
				(type default)
			)
			(layer "B.SilkS")
		)
		(fp_line
			(start -0.7874 -0.4064)
			(end -0.7874 0.4064)
			(stroke
				(width 0.1524)
				(type default)
			)
			(layer "B.SilkS")
		)
		(fp_line
			(start 0.7874 -0.4064)
			(end -0.7874 -0.4064)
			(stroke
				(width 0.1524)
				(type default)
			)
			(layer "B.SilkS")
		)
		(fp_line
			(start -0.67945 0.3048)
			(end -0.120396 0.3048)
			(stroke
				(width 0.1)
				(type default)
			)
			(layer "B.Fab")
		)
		(fp_line
			(start -0.120396 0.3048)
			(end -0.120396 0.2794)
			(stroke
				(width 0.1)
				(type default)
			)
			(layer "B.Fab")
		)
		(fp_line
			(start 0.12065 0.3048)
			(end 0.67945 0.3048)
			(stroke
				(width 0.1)
				(type default)
			)
			(layer "B.Fab")
		)
		(fp_line
			(start 0.67945 0.3048)
			(end 0.67945 -0.305054)
			(stroke
				(width 0.1)
				(type default)
			)
			(layer "B.Fab")
		)
		(fp_line
			(start -0.120396 0.2794)
			(end 0.12065 0.2794)
			(stroke
				(width 0.1)
				(type default)
			)
			(layer "B.Fab")
		)
		(fp_line
			(start 0.12065 0.2794)
			(end 0.12065 0.3048)
			(stroke
				(width 0.1)
				(type default)
			)
			(layer "B.Fab")
		)
		(fp_line
			(start -0.12065 -0.2794)
			(end -0.12065 -0.3048)
			(stroke
				(width 0.1)
				(type default)
			)
			(layer "B.Fab")
		)
		(fp_line
			(start 0.12065 -0.2794)
			(end -0.12065 -0.2794)
			(stroke
				(width 0.1)
				(type default)
			)
			(layer "B.Fab")
		)
		(fp_line
			(start -0.67945 -0.3048)
			(end -0.67945 0.3048)
			(stroke
				(width 0.1)
				(type default)
			)
			(layer "B.Fab")
		)
		(fp_line
			(start -0.12065 -0.3048)
			(end -0.67945 -0.3048)
			(stroke
				(width 0.1)
				(type default)
			)
			(layer "B.Fab")
		)
		(fp_line
			(start 0.12065 -0.305054)
			(end 0.12065 -0.2794)
			(stroke
				(width 0.1)
				(type default)
			)
			(layer "B.Fab")
		)
		(fp_line
			(start 0.67945 -0.305054)
			(end 0.12065 -0.305054)
			(stroke
				(width 0.1)
				(type default)
			)
			(layer "B.Fab")
		)
		(pad "1" smd circle
			(at 0.40005 0 90)
			(size 0 0)
			(layers "B.Cu" "B.Mask" "B.Paste")
			(net "PVNN_TERM_CPU0")
		)
		(pad "2" smd circle
			(at -0.40005 0 90)
			(size 0 0)
			(layers "B.Cu" "B.Mask" "B.Paste")
			(net "H_CPU_CATERR_LVC1_R_N")
		)
	)
	(footprint ""
		(layer "B.Cu")
		(at 130.761486 -337.145884 90)
		(property "Reference" "PC512_P1_5"
			(at 0 0 90)
			(layer "B.SilkS")
			(hide yes)
			(effects
				(font
					(size 1.27 1.27)
				)
				(justify mirror)
			)
		)
		(property "Value" ""
			(at 0 0 90)
			(layer "B.Fab")
			(effects
				(font
					(size 1.27 1.27)
				)
				(justify mirror)
			)
		)
		(duplicate_pad_numbers_are_jumpers no)
		(fp_line
			(start 1.524 -0.762)
			(end -1.524 -0.762)
			(stroke
				(width 0.1524)
				(type default)
			)
			(layer "B.SilkS")
		)
		(fp_line
			(start -1.524 -0.762)
			(end -1.524 0.762)
			(stroke
				(width 0.1524)
				(type default)
			)
			(layer "B.SilkS")
		)
		(fp_line
			(start 1.524 0.762)
			(end 1.524 -0.762)
			(stroke
				(width 0.1524)
				(type default)
			)
			(layer "B.SilkS")
		)
		(fp_line
			(start -1.524 0.762)
			(end 1.524 0.762)
			(stroke
				(width 0.1524)
				(type default)
			)
			(layer "B.SilkS")
		)
		(fp_line
			(start 1.1049 -0.724916)
			(end 1.1049 0.724916)
			(stroke
				(width 0.1)
				(type default)
			)
			(layer "B.Fab")
		)
		(fp_line
			(start -1.1049 -0.724916)
			(end 1.1049 -0.724916)
			(stroke
				(width 0.1)
				(type default)
			)
			(layer "B.Fab")
		)
		(fp_line
			(start 1.1049 0.724916)
			(end -1.1049 0.724916)
			(stroke
				(width 0.1)
				(type default)
			)
			(layer "B.Fab")
		)
		(fp_line
			(start -1.1049 0.724916)
			(end -1.1049 -0.724916)
			(stroke
				(width 0.1)
				(type default)
			)
			(layer "B.Fab")
		)
		(pad "1" smd rect
			(at 0.889 0 90)
			(size 1.016 1.27)
			(layers "B.Cu" "B.Mask" "B.Paste")
			(net "SW_P12V_PVCCIN_CPU1_FLT")
		)
		(pad "2" smd rect
			(at -0.889 0 90)
			(size 1.016 1.27)
			(layers "B.Cu" "B.Mask" "B.Paste")
			(net "GND")
		)
	)
	(footprint ""
		(layer "B.Cu")
		(at 448.549014 -321.549776 -90)
		(property "Reference" "C39"
			(at 0 0 90)
			(layer "B.SilkS")
			(hide yes)
			(effects
				(font
					(size 1.27 1.27)
				)
				(justify mirror)
			)
		)
		(property "Value" ""
			(at 0 0 90)
			(layer "B.Fab")
			(effects
				(font
					(size 1.27 1.27)
				)
				(justify mirror)
			)
		)
		(duplicate_pad_numbers_are_jumpers no)
		(fp_line
			(start -1.524 0.762)
			(end 1.524 0.762)
			(stroke
				(width 0.1524)
				(type default)
			)
			(layer "B.SilkS")
		)
		(fp_line
			(start 1.524 0.762)
			(end 1.524 -0.762)
			(stroke
				(width 0.1524)
				(type default)
			)
			(layer "B.SilkS")
		)
		(fp_line
			(start -1.524 -0.762)
			(end -1.524 0.762)
			(stroke
				(width 0.1524)
				(type default)
			)
			(layer "B.SilkS")
		)
		(fp_line
			(start 1.524 -0.762)
			(end -1.524 -0.762)
			(stroke
				(width 0.1524)
				(type default)
			)
			(layer "B.SilkS")
		)
		(fp_line
			(start -1.1049 0.724916)
			(end -1.1049 -0.724916)
			(stroke
				(width 0.1)
				(type default)
			)
			(layer "B.Fab")
		)
		(fp_line
			(start 1.1049 0.724916)
			(end -1.1049 0.724916)
			(stroke
				(width 0.1)
				(type default)
			)
			(layer "B.Fab")
		)
		(fp_line
			(start -1.1049 -0.724916)
			(end 1.1049 -0.724916)
			(stroke
				(width 0.1)
				(type default)
			)
			(layer "B.Fab")
		)
		(fp_line
			(start 1.1049 -0.724916)
			(end 1.1049 0.724916)
			(stroke
				(width 0.1)
				(type default)
			)
			(layer "B.Fab")
		)
		(pad "1" smd rect
			(at 0.889 0 270)
			(size 1.016 1.27)
			(layers "B.Cu" "B.Mask" "B.Paste")
			(net "P12V_S3_AUX_CPU0_NVDIMM")
		)
		(pad "2" smd rect
			(at -0.889 0 270)
			(size 1.016 1.27)
			(layers "B.Cu" "B.Mask" "B.Paste")
			(net "GND")
		)
	)
	(footprint ""
		(layer "B.Cu")
		(at 193.60388 -106.225848 180)
		(property "Reference" "R1312"
			(at 0 0 0)
			(layer "B.SilkS")
			(hide yes)
			(effects
				(font
					(size 1.27 1.27)
				)
				(justify mirror)
			)
		)
		(property "Value" ""
			(at 0 0 0)
			(layer "B.Fab")
			(effects
				(font
					(size 1.27 1.27)
				)
				(justify mirror)
			)
		)
		(duplicate_pad_numbers_are_jumpers no)
		(fp_line
			(start 0.7874 0.4064)
			(end 0.7874 -0.4064)
			(stroke
				(width 0.1524)
				(type default)
			)
			(layer "B.SilkS")
		)
		(fp_line
			(start 0.7874 -0.4064)
			(end -0.7874 -0.4064)
			(stroke
				(width 0.1524)
				(type default)
			)
			(layer "B.SilkS")
		)
		(fp_line
			(start -0.7874 0.4064)
			(end 0.7874 0.4064)
			(stroke
				(width 0.1524)
				(type default)
			)
			(layer "B.SilkS")
		)
		(fp_line
			(start -0.7874 -0.4064)
			(end -0.7874 0.4064)
			(stroke
				(width 0.1524)
				(type default)
			)
			(layer "B.SilkS")
		)
		(fp_line
			(start 0.67945 0.3048)
			(end 0.67945 -0.305054)
			(stroke
				(width 0.1)
				(type default)
			)
			(layer "B.Fab")
		)
		(fp_line
			(start 0.67945 -0.305054)
			(end 0.12065 -0.305054)
			(stroke
				(width 0.1)
				(type default)
			)
			(layer "B.Fab")
		)
		(fp_line
			(start 0.12065 0.3048)
			(end 0.67945 0.3048)
			(stroke
				(width 0.1)
				(type default)
			)
			(layer "B.Fab")
		)
		(fp_line
			(start 0.12065 0.2794)
			(end 0.12065 0.3048)
			(stroke
				(width 0.1)
				(type default)
			)
			(layer "B.Fab")
		)
		(fp_line
			(start 0.12065 -0.2794)
			(end -0.12065 -0.2794)
			(stroke
				(width 0.1)
				(type default)
			)
			(layer "B.Fab")
		)
		(fp_line
			(start 0.12065 -0.305054)
			(end 0.12065 -0.2794)
			(stroke
				(width 0.1)
				(type default)
			)
			(layer "B.Fab")
		)
		(fp_line
			(start -0.120396 0.3048)
			(end -0.120396 0.2794)
			(stroke
				(width 0.1)
				(type default)
			)
			(layer "B.Fab")
		)
		(fp_line
			(start -0.120396 0.2794)
			(end 0.12065 0.2794)
			(stroke
				(width 0.1)
				(type default)
			)
			(layer "B.Fab")
		)
		(fp_line
			(start -0.12065 -0.2794)
			(end -0.12065 -0.3048)
			(stroke
				(width 0.1)
				(type default)
			)
			(layer "B.Fab")
		)
		(fp_line
			(start -0.12065 -0.3048)
			(end -0.67945 -0.3048)
			(stroke
				(width 0.1)
				(type default)
			)
			(layer "B.Fab")
		)
		(fp_line
			(start -0.67945 0.3048)
			(end -0.120396 0.3048)
			(stroke
				(width 0.1)
				(type default)
			)
			(layer "B.Fab")
		)
		(fp_line
			(start -0.67945 -0.3048)
			(end -0.67945 0.3048)
			(stroke
				(width 0.1)
				(type default)
			)
			(layer "B.Fab")
		)
		(pad "1" smd circle
			(at 0.40005 0)
			(size 0 0)
			(layers "B.Cu" "B.Mask" "B.Paste")
			(net "FM_RST_PERST_BIT2")
		)
		(pad "2" smd circle
			(at -0.40005 0)
			(size 0 0)
			(layers "B.Cu" "B.Mask" "B.Paste")
			(net "GND")
		)
	)
	(footprint ""
		(layer "B.Cu")
		(at 304.697638 -192.450466 90)
		(property "Reference" "R328"
			(at 0 0 90)
			(layer "B.SilkS")
			(hide yes)
			(effects
				(font
					(size 1.27 1.27)
				)
				(justify mirror)
			)
		)
		(property "Value" ""
			(at 0 0 90)
			(layer "B.Fab")
			(effects
				(font
					(size 1.27 1.27)
				)
				(justify mirror)
			)
		)
		(duplicate_pad_numbers_are_jumpers no)
		(fp_line
			(start 0.7874 -0.4064)
			(end -0.7874 -0.4064)
			(stroke
				(width 0.1524)
				(type default)
			)
			(layer "B.SilkS")
		)
		(fp_line
			(start -0.7874 -0.4064)
			(end -0.7874 0.4064)
			(stroke
				(width 0.1524)
				(type default)
			)
			(layer "B.SilkS")
		)
		(fp_line
			(start 0.7874 0.4064)
			(end 0.7874 -0.4064)
			(stroke
				(width 0.1524)
				(type default)
			)
			(layer "B.SilkS")
		)
		(fp_line
			(start -0.7874 0.4064)
			(end 0.7874 0.4064)
			(stroke
				(width 0.1524)
				(type default)
			)
			(layer "B.SilkS")
		)
		(fp_line
			(start 0.67945 -0.305054)
			(end 0.12065 -0.305054)
			(stroke
				(width 0.1)
				(type default)
			)
			(layer "B.Fab")
		)
		(fp_line
			(start 0.12065 -0.305054)
			(end 0.12065 -0.2794)
			(stroke
				(width 0.1)
				(type default)
			)
			(layer "B.Fab")
		)
		(fp_line
			(start -0.12065 -0.3048)
			(end -0.67945 -0.3048)
			(stroke
				(width 0.1)
				(type default)
			)
			(layer "B.Fab")
		)
		(fp_line
			(start -0.67945 -0.3048)
			(end -0.67945 0.3048)
			(stroke
				(width 0.1)
				(type default)
			)
			(layer "B.Fab")
		)
		(fp_line
			(start 0.12065 -0.2794)
			(end -0.12065 -0.2794)
			(stroke
				(width 0.1)
				(type default)
			)
			(layer "B.Fab")
		)
		(fp_line
			(start -0.12065 -0.2794)
			(end -0.12065 -0.3048)
			(stroke
				(width 0.1)
				(type default)
			)
			(layer "B.Fab")
		)
		(fp_line
			(start 0.12065 0.2794)
			(end 0.12065 0.3048)
			(stroke
				(width 0.1)
				(type default)
			)
			(layer "B.Fab")
		)
		(fp_line
			(start -0.120396 0.2794)
			(end 0.12065 0.2794)
			(stroke
				(width 0.1)
				(type default)
			)
			(layer "B.Fab")
		)
		(fp_line
			(start 0.67945 0.3048)
			(end 0.67945 -0.305054)
			(stroke
				(width 0.1)
				(type default)
			)
			(layer "B.Fab")
		)
		(fp_line
			(start 0.12065 0.3048)
			(end 0.67945 0.3048)
			(stroke
				(width 0.1)
				(type default)
			)
			(layer "B.Fab")
		)
		(fp_line
			(start -0.120396 0.3048)
			(end -0.120396 0.2794)
			(stroke
				(width 0.1)
				(type default)
			)
			(layer "B.Fab")
		)
		(fp_line
			(start -0.67945 0.3048)
			(end -0.120396 0.3048)
			(stroke
				(width 0.1)
				(type default)
			)
			(layer "B.Fab")
		)
		(pad "1" smd circle
			(at 0.40005 0 270)
			(size 0 0)
			(layers "B.Cu" "B.Mask" "B.Paste")
			(net "SVID_DIO0_CPU0_R")
		)
		(pad "2" smd circle
			(at -0.40005 0 270)
			(size 0 0)
			(layers "B.Cu" "B.Mask" "B.Paste")
			(net "PVNN_TERM_CPU0")
		)
	)
	(footprint ""
		(layer "B.Cu")
		(at 54.880002 -148.963634 180)
		(property "Reference" "PC451_P1_2"
			(at 0 0 0)
			(layer "B.SilkS")
			(hide yes)
			(effects
				(font
					(size 1.27 1.27)
				)
				(justify mirror)
			)
		)
		(property "Value" ""
			(at 0 0 0)
			(layer "B.Fab")
			(effects
				(font
					(size 1.27 1.27)
				)
				(justify mirror)
			)
		)
		(duplicate_pad_numbers_are_jumpers no)
		(fp_line
			(start 1.524 0.762)
			(end 1.524 -0.762)
			(stroke
				(width 0.1524)
				(type default)
			)
			(layer "B.SilkS")
		)
		(fp_line
			(start 1.524 -0.762)
			(end -1.524 -0.762)
			(stroke
				(width 0.1524)
				(type default)
			)
			(layer "B.SilkS")
		)
		(fp_line
			(start -1.524 0.762)
			(end 1.524 0.762)
			(stroke
				(width 0.1524)
				(type default)
			)
			(layer "B.SilkS")
		)
		(fp_line
			(start -1.524 -0.762)
			(end -1.524 0.762)
			(stroke
				(width 0.1524)
				(type default)
			)
			(layer "B.SilkS")
		)
		(fp_line
			(start 1.1049 0.724916)
			(end -1.1049 0.724916)
			(stroke
				(width 0.1)
				(type default)
			)
			(layer "B.Fab")
		)
		(fp_line
			(start 1.1049 -0.724916)
			(end 1.1049 0.724916)
			(stroke
				(width 0.1)
				(type default)
			)
			(layer "B.Fab")
		)
		(fp_line
			(start -1.1049 0.724916)
			(end -1.1049 -0.724916)
			(stroke
				(width 0.1)
				(type default)
			)
			(layer "B.Fab")
		)
		(fp_line
			(start -1.1049 -0.724916)
			(end 1.1049 -0.724916)
			(stroke
				(width 0.1)
				(type default)
			)
			(layer "B.Fab")
		)
		(pad "1" smd rect
			(at 0.889 0 180)
			(size 1.016 1.27)
			(layers "B.Cu" "B.Mask" "B.Paste")
			(net "SW_P12V_PVCCINFAON_CPU1_FLT")
		)
		(pad "2" smd rect
			(at -0.889 0 180)
			(size 1.016 1.27)
			(layers "B.Cu" "B.Mask" "B.Paste")
			(net "GND")
		)
	)
	(footprint ""
		(layer "B.Cu")
		(at 140.89888 -9.362948 -90)
		(property "Reference" "R1798"
			(at 0 0 90)
			(layer "B.SilkS")
			(hide yes)
			(effects
				(font
					(size 1.27 1.27)
				)
				(justify mirror)
			)
		)
		(property "Value" ""
			(at 0 0 90)
			(layer "B.Fab")
			(effects
				(font
					(size 1.27 1.27)
				)
				(justify mirror)
			)
		)
		(duplicate_pad_numbers_are_jumpers no)
		(fp_line
			(start -0.7874 0.4064)
			(end 0.7874 0.4064)
			(stroke
				(width 0.1524)
				(type default)
			)
			(layer "B.SilkS")
		)
		(fp_line
			(start 0.7874 0.4064)
			(end 0.7874 -0.4064)
			(stroke
				(width 0.1524)
				(type default)
			)
			(layer "B.SilkS")
		)
		(fp_line
			(start -0.7874 -0.4064)
			(end -0.7874 0.4064)
			(stroke
				(width 0.1524)
				(type default)
			)
			(layer "B.SilkS")
		)
		(fp_line
			(start 0.7874 -0.4064)
			(end -0.7874 -0.4064)
			(stroke
				(width 0.1524)
				(type default)
			)
			(layer "B.SilkS")
		)
		(fp_line
			(start -0.67945 0.3048)
			(end -0.120396 0.3048)
			(stroke
				(width 0.1)
				(type default)
			)
			(layer "B.Fab")
		)
		(fp_line
			(start -0.120396 0.3048)
			(end -0.120396 0.2794)
			(stroke
				(width 0.1)
				(type default)
			)
			(layer "B.Fab")
		)
		(fp_line
			(start 0.12065 0.3048)
			(end 0.67945 0.3048)
			(stroke
				(width 0.1)
				(type default)
			)
			(layer "B.Fab")
		)
		(fp_line
			(start 0.67945 0.3048)
			(end 0.67945 -0.305054)
			(stroke
				(width 0.1)
				(type default)
			)
			(layer "B.Fab")
		)
		(fp_line
			(start -0.120396 0.2794)
			(end 0.12065 0.2794)
			(stroke
				(width 0.1)
				(type default)
			)
			(layer "B.Fab")
		)
		(fp_line
			(start 0.12065 0.2794)
			(end 0.12065 0.3048)
			(stroke
				(width 0.1)
				(type default)
			)
			(layer "B.Fab")
		)
		(fp_line
			(start -0.12065 -0.2794)
			(end -0.12065 -0.3048)
			(stroke
				(width 0.1)
				(type default)
			)
			(layer "B.Fab")
		)
		(fp_line
			(start 0.12065 -0.2794)
			(end -0.12065 -0.2794)
			(stroke
				(width 0.1)
				(type default)
			)
			(layer "B.Fab")
		)
		(fp_line
			(start -0.67945 -0.3048)
			(end -0.67945 0.3048)
			(stroke
				(width 0.1)
				(type default)
			)
			(layer "B.Fab")
		)
		(fp_line
			(start -0.12065 -0.3048)
			(end -0.67945 -0.3048)
			(stroke
				(width 0.1)
				(type default)
			)
			(layer "B.Fab")
		)
		(fp_line
			(start 0.12065 -0.305054)
			(end 0.12065 -0.2794)
			(stroke
				(width 0.1)
				(type default)
			)
			(layer "B.Fab")
		)
		(fp_line
			(start 0.67945 -0.305054)
			(end 0.12065 -0.305054)
			(stroke
				(width 0.1)
				(type default)
			)
			(layer "B.Fab")
		)
		(pad "1" smd circle
			(at 0.40005 0 90)
			(size 0 0)
			(layers "B.Cu" "B.Mask" "B.Paste")
			(net "ROT_P1_RST_IND_N_R")
		)
		(pad "2" smd circle
			(at -0.40005 0 90)
			(size 0 0)
			(layers "B.Cu" "B.Mask" "B.Paste")
			(net "ROT_P1_RST_IND_N")
		)
	)
	(footprint ""
		(layer "B.Cu")
		(at 87.48776 -188.918088 90)
		(property "Reference" "R774"
			(at 0 0 90)
			(layer "B.SilkS")
			(hide yes)
			(effects
				(font
					(size 1.27 1.27)
				)
				(justify mirror)
			)
		)
		(property "Value" ""
			(at 0 0 90)
			(layer "B.Fab")
			(effects
				(font
					(size 1.27 1.27)
				)
				(justify mirror)
			)
		)
		(duplicate_pad_numbers_are_jumpers no)
		(fp_line
			(start 0.7874 -0.4064)
			(end -0.7874 -0.4064)
			(stroke
				(width 0.1524)
				(type default)
			)
			(layer "B.SilkS")
		)
		(fp_line
			(start -0.7874 -0.4064)
			(end -0.7874 0.4064)
			(stroke
				(width 0.1524)
				(type default)
			)
			(layer "B.SilkS")
		)
		(fp_line
			(start 0.7874 0.4064)
			(end 0.7874 -0.4064)
			(stroke
				(width 0.1524)
				(type default)
			)
			(layer "B.SilkS")
		)
		(fp_line
			(start -0.7874 0.4064)
			(end 0.7874 0.4064)
			(stroke
				(width 0.1524)
				(type default)
			)
			(layer "B.SilkS")
		)
		(fp_line
			(start 0.67945 -0.305054)
			(end 0.12065 -0.305054)
			(stroke
				(width 0.1)
				(type default)
			)
			(layer "B.Fab")
		)
		(fp_line
			(start 0.12065 -0.305054)
			(end 0.12065 -0.2794)
			(stroke
				(width 0.1)
				(type default)
			)
			(layer "B.Fab")
		)
		(fp_line
			(start -0.12065 -0.3048)
			(end -0.67945 -0.3048)
			(stroke
				(width 0.1)
				(type default)
			)
			(layer "B.Fab")
		)
		(fp_line
			(start -0.67945 -0.3048)
			(end -0.67945 0.3048)
			(stroke
				(width 0.1)
				(type default)
			)
			(layer "B.Fab")
		)
		(fp_line
			(start 0.12065 -0.2794)
			(end -0.12065 -0.2794)
			(stroke
				(width 0.1)
				(type default)
			)
			(layer "B.Fab")
		)
		(fp_line
			(start -0.12065 -0.2794)
			(end -0.12065 -0.3048)
			(stroke
				(width 0.1)
				(type default)
			)
			(layer "B.Fab")
		)
		(fp_line
			(start 0.12065 0.2794)
			(end 0.12065 0.3048)
			(stroke
				(width 0.1)
				(type default)
			)
			(layer "B.Fab")
		)
		(fp_line
			(start -0.120396 0.2794)
			(end 0.12065 0.2794)
			(stroke
				(width 0.1)
				(type default)
			)
			(layer "B.Fab")
		)
		(fp_line
			(start 0.67945 0.3048)
			(end 0.67945 -0.305054)
			(stroke
				(width 0.1)
				(type default)
			)
			(layer "B.Fab")
		)
		(fp_line
			(start 0.12065 0.3048)
			(end 0.67945 0.3048)
			(stroke
				(width 0.1)
				(type default)
			)
			(layer "B.Fab")
		)
		(fp_line
			(start -0.120396 0.3048)
			(end -0.120396 0.2794)
			(stroke
				(width 0.1)
				(type default)
			)
			(layer "B.Fab")
		)
		(fp_line
			(start -0.67945 0.3048)
			(end -0.120396 0.3048)
			(stroke
				(width 0.1)
				(type default)
			)
			(layer "B.Fab")
		)
		(pad "1" smd circle
			(at 0.40005 0 270)
			(size 0 0)
			(layers "B.Cu" "B.Mask" "B.Paste")
			(net "JTAG_DBP_CPU_GTL_TCK")
		)
		(pad "2" smd circle
			(at -0.40005 0 270)
			(size 0 0)
			(layers "B.Cu" "B.Mask" "B.Paste")
			(net "GND")
		)
	)
	(footprint ""
		(layer "B.Cu")
		(at 192.052448 -401.772882 180)
		(property "Reference" "R2587"
			(at 0 0 0)
			(layer "B.SilkS")
			(hide yes)
			(effects
				(font
					(size 1.27 1.27)
				)
				(justify mirror)
			)
		)
		(property "Value" ""
			(at 0 0 0)
			(layer "B.Fab")
			(effects
				(font
					(size 1.27 1.27)
				)
				(justify mirror)
			)
		)
		(duplicate_pad_numbers_are_jumpers no)
		(fp_line
			(start 0.7874 0.4064)
			(end 0.7874 -0.4064)
			(stroke
				(width 0.1524)
				(type default)
			)
			(layer "B.SilkS")
		)
		(fp_line
			(start 0.7874 -0.4064)
			(end -0.7874 -0.4064)
			(stroke
				(width 0.1524)
				(type default)
			)
			(layer "B.SilkS")
		)
		(fp_line
			(start -0.7874 0.4064)
			(end 0.7874 0.4064)
			(stroke
				(width 0.1524)
				(type default)
			)
			(layer "B.SilkS")
		)
		(fp_line
			(start -0.7874 -0.4064)
			(end -0.7874 0.4064)
			(stroke
				(width 0.1524)
				(type default)
			)
			(layer "B.SilkS")
		)
		(fp_line
			(start 0.67945 0.3048)
			(end 0.67945 -0.305054)
			(stroke
				(width 0.1)
				(type default)
			)
			(layer "B.Fab")
		)
		(fp_line
			(start 0.67945 -0.305054)
			(end 0.12065 -0.305054)
			(stroke
				(width 0.1)
				(type default)
			)
			(layer "B.Fab")
		)
		(fp_line
			(start 0.12065 0.3048)
			(end 0.67945 0.3048)
			(stroke
				(width 0.1)
				(type default)
			)
			(layer "B.Fab")
		)
		(fp_line
			(start 0.12065 0.2794)
			(end 0.12065 0.3048)
			(stroke
				(width 0.1)
				(type default)
			)
			(layer "B.Fab")
		)
		(fp_line
			(start 0.12065 -0.2794)
			(end -0.12065 -0.2794)
			(stroke
				(width 0.1)
				(type default)
			)
			(layer "B.Fab")
		)
		(fp_line
			(start 0.12065 -0.305054)
			(end 0.12065 -0.2794)
			(stroke
				(width 0.1)
				(type default)
			)
			(layer "B.Fab")
		)
		(fp_line
			(start -0.120396 0.3048)
			(end -0.120396 0.2794)
			(stroke
				(width 0.1)
				(type default)
			)
			(layer "B.Fab")
		)
		(fp_line
			(start -0.120396 0.2794)
			(end 0.12065 0.2794)
			(stroke
				(width 0.1)
				(type default)
			)
			(layer "B.Fab")
		)
		(fp_line
			(start -0.12065 -0.2794)
			(end -0.12065 -0.3048)
			(stroke
				(width 0.1)
				(type default)
			)
			(layer "B.Fab")
		)
		(fp_line
			(start -0.12065 -0.3048)
			(end -0.67945 -0.3048)
			(stroke
				(width 0.1)
				(type default)
			)
			(layer "B.Fab")
		)
		(fp_line
			(start -0.67945 0.3048)
			(end -0.120396 0.3048)
			(stroke
				(width 0.1)
				(type default)
			)
			(layer "B.Fab")
		)
		(fp_line
			(start -0.67945 -0.3048)
			(end -0.67945 0.3048)
			(stroke
				(width 0.1)
				(type default)
			)
			(layer "B.Fab")
		)
		(pad "1" smd circle
			(at 0.40005 0)
			(size 0 0)
			(layers "B.Cu" "B.Mask" "B.Paste")
			(net "HSC_VDD")
		)
		(pad "2" smd circle
			(at -0.40005 0)
			(size 0 0)
			(layers "B.Cu" "B.Mask" "B.Paste")
			(net "IRQ_HSC_FAULT_N")
		)
	)
	(footprint ""
		(layer "B.Cu")
		(at 282.11272 -193.710814 -90)
		(property "Reference" "R96"
			(at 0 0 90)
			(layer "B.SilkS")
			(hide yes)
			(effects
				(font
					(size 1.27 1.27)
				)
				(justify mirror)
			)
		)
		(property "Value" ""
			(at 0 0 90)
			(layer "B.Fab")
			(effects
				(font
					(size 1.27 1.27)
				)
				(justify mirror)
			)
		)
		(duplicate_pad_numbers_are_jumpers no)
		(fp_line
			(start -0.7874 0.4064)
			(end 0.7874 0.4064)
			(stroke
				(width 0.1524)
				(type default)
			)
			(layer "B.SilkS")
		)
		(fp_line
			(start 0.7874 0.4064)
			(end 0.7874 -0.4064)
			(stroke
				(width 0.1524)
				(type default)
			)
			(layer "B.SilkS")
		)
		(fp_line
			(start -0.7874 -0.4064)
			(end -0.7874 0.4064)
			(stroke
				(width 0.1524)
				(type default)
			)
			(layer "B.SilkS")
		)
		(fp_line
			(start 0.7874 -0.4064)
			(end -0.7874 -0.4064)
			(stroke
				(width 0.1524)
				(type default)
			)
			(layer "B.SilkS")
		)
		(fp_line
			(start -0.67945 0.3048)
			(end -0.120396 0.3048)
			(stroke
				(width 0.1)
				(type default)
			)
			(layer "B.Fab")
		)
		(fp_line
			(start -0.120396 0.3048)
			(end -0.120396 0.2794)
			(stroke
				(width 0.1)
				(type default)
			)
			(layer "B.Fab")
		)
		(fp_line
			(start 0.12065 0.3048)
			(end 0.67945 0.3048)
			(stroke
				(width 0.1)
				(type default)
			)
			(layer "B.Fab")
		)
		(fp_line
			(start 0.67945 0.3048)
			(end 0.67945 -0.305054)
			(stroke
				(width 0.1)
				(type default)
			)
			(layer "B.Fab")
		)
		(fp_line
			(start -0.120396 0.2794)
			(end 0.12065 0.2794)
			(stroke
				(width 0.1)
				(type default)
			)
			(layer "B.Fab")
		)
		(fp_line
			(start 0.12065 0.2794)
			(end 0.12065 0.3048)
			(stroke
				(width 0.1)
				(type default)
			)
			(layer "B.Fab")
		)
		(fp_line
			(start -0.12065 -0.2794)
			(end -0.12065 -0.3048)
			(stroke
				(width 0.1)
				(type default)
			)
			(layer "B.Fab")
		)
		(fp_line
			(start 0.12065 -0.2794)
			(end -0.12065 -0.2794)
			(stroke
				(width 0.1)
				(type default)
			)
			(layer "B.Fab")
		)
		(fp_line
			(start -0.67945 -0.3048)
			(end -0.67945 0.3048)
			(stroke
				(width 0.1)
				(type default)
			)
			(layer "B.Fab")
		)
		(fp_line
			(start -0.12065 -0.3048)
			(end -0.67945 -0.3048)
			(stroke
				(width 0.1)
				(type default)
			)
			(layer "B.Fab")
		)
		(fp_line
			(start 0.12065 -0.305054)
			(end 0.12065 -0.2794)
			(stroke
				(width 0.1)
				(type default)
			)
			(layer "B.Fab")
		)
		(fp_line
			(start 0.67945 -0.305054)
			(end 0.12065 -0.305054)
			(stroke
				(width 0.1)
				(type default)
			)
			(layer "B.Fab")
		)
		(pad "1" smd circle
			(at 0.40005 0 90)
			(size 0 0)
			(layers "B.Cu" "B.Mask" "B.Paste")
			(net "PVNN_TERM_CPU0")
		)
		(pad "2" smd circle
			(at -0.40005 0 90)
			(size 0 0)
			(layers "B.Cu" "B.Mask" "B.Paste")
			(net "PU_CPU0_UPI2_AC_COUPLING")
		)
	)
	(footprint ""
		(layer "B.Cu")
		(at 431.5841 -128.791208 -90)
		(property "Reference" "PR4235"
			(at 0 0 90)
			(layer "B.SilkS")
			(hide yes)
			(effects
				(font
					(size 1.27 1.27)
				)
				(justify mirror)
			)
		)
		(property "Value" ""
			(at 0 0 90)
			(layer "B.Fab")
			(effects
				(font
					(size 1.27 1.27)
				)
				(justify mirror)
			)
		)
		(duplicate_pad_numbers_are_jumpers no)
		(fp_line
			(start -0.7874 0.4064)
			(end 0.7874 0.4064)
			(stroke
				(width 0.1524)
				(type default)
			)
			(layer "B.SilkS")
		)
		(fp_line
			(start 0.7874 0.4064)
			(end 0.7874 -0.4064)
			(stroke
				(width 0.1524)
				(type default)
			)
			(layer "B.SilkS")
		)
		(fp_line
			(start -0.7874 -0.4064)
			(end -0.7874 0.4064)
			(stroke
				(width 0.1524)
				(type default)
			)
			(layer "B.SilkS")
		)
		(fp_line
			(start 0.7874 -0.4064)
			(end -0.7874 -0.4064)
			(stroke
				(width 0.1524)
				(type default)
			)
			(layer "B.SilkS")
		)
		(fp_line
			(start -0.67945 0.3048)
			(end -0.120396 0.3048)
			(stroke
				(width 0.1)
				(type default)
			)
			(layer "B.Fab")
		)
		(fp_line
			(start -0.120396 0.3048)
			(end -0.120396 0.2794)
			(stroke
				(width 0.1)
				(type default)
			)
			(layer "B.Fab")
		)
		(fp_line
			(start 0.12065 0.3048)
			(end 0.67945 0.3048)
			(stroke
				(width 0.1)
				(type default)
			)
			(layer "B.Fab")
		)
		(fp_line
			(start 0.67945 0.3048)
			(end 0.67945 -0.305054)
			(stroke
				(width 0.1)
				(type default)
			)
			(layer "B.Fab")
		)
		(fp_line
			(start -0.120396 0.2794)
			(end 0.12065 0.2794)
			(stroke
				(width 0.1)
				(type default)
			)
			(layer "B.Fab")
		)
		(fp_line
			(start 0.12065 0.2794)
			(end 0.12065 0.3048)
			(stroke
				(width 0.1)
				(type default)
			)
			(layer "B.Fab")
		)
		(fp_line
			(start -0.12065 -0.2794)
			(end -0.12065 -0.3048)
			(stroke
				(width 0.1)
				(type default)
			)
			(layer "B.Fab")
		)
		(fp_line
			(start 0.12065 -0.2794)
			(end -0.12065 -0.2794)
			(stroke
				(width 0.1)
				(type default)
			)
			(layer "B.Fab")
		)
		(fp_line
			(start -0.67945 -0.3048)
			(end -0.67945 0.3048)
			(stroke
				(width 0.1)
				(type default)
			)
			(layer "B.Fab")
		)
		(fp_line
			(start -0.12065 -0.3048)
			(end -0.67945 -0.3048)
			(stroke
				(width 0.1)
				(type default)
			)
			(layer "B.Fab")
		)
		(fp_line
			(start 0.12065 -0.305054)
			(end 0.12065 -0.2794)
			(stroke
				(width 0.1)
				(type default)
			)
			(layer "B.Fab")
		)
		(fp_line
			(start 0.67945 -0.305054)
			(end 0.12065 -0.305054)
			(stroke
				(width 0.1)
				(type default)
			)
			(layer "B.Fab")
		)
		(pad "1" smd circle
			(at 0.40005 0 90)
			(size 0 0)
			(layers "B.Cu" "B.Mask" "B.Paste")
			(net "NC_PVCCD_HV_CPU0_ACSP7")
		)
		(pad "2" smd circle
			(at -0.40005 0 90)
			(size 0 0)
			(layers "B.Cu" "B.Mask" "B.Paste")
			(net "GND")
		)
	)
	(footprint ""
		(layer "B.Cu")
		(at 302.300132 -55.971948 180)
		(property "Reference" "C1231"
			(at 0 0 0)
			(layer "B.SilkS")
			(hide yes)
			(effects
				(font
					(size 1.27 1.27)
				)
				(justify mirror)
			)
		)
		(property "Value" ""
			(at 0 0 0)
			(layer "B.Fab")
			(effects
				(font
					(size 1.27 1.27)
				)
				(justify mirror)
			)
		)
		(duplicate_pad_numbers_are_jumpers no)
		(fp_line
			(start 0.7874 0.4064)
			(end 0.7874 -0.4064)
			(stroke
				(width 0.1524)
				(type default)
			)
			(layer "B.SilkS")
		)
		(fp_line
			(start 0.7874 -0.4064)
			(end -0.7874 -0.4064)
			(stroke
				(width 0.1524)
				(type default)
			)
			(layer "B.SilkS")
		)
		(fp_line
			(start -0.7874 0.4064)
			(end 0.7874 0.4064)
			(stroke
				(width 0.1524)
				(type default)
			)
			(layer "B.SilkS")
		)
		(fp_line
			(start -0.7874 -0.4064)
			(end -0.7874 0.4064)
			(stroke
				(width 0.1524)
				(type default)
			)
			(layer "B.SilkS")
		)
		(fp_line
			(start 0.67945 0.3048)
			(end 0.67945 -0.305054)
			(stroke
				(width 0.1)
				(type default)
			)
			(layer "B.Fab")
		)
		(fp_line
			(start 0.67945 -0.305054)
			(end 0.12065 -0.305054)
			(stroke
				(width 0.1)
				(type default)
			)
			(layer "B.Fab")
		)
		(fp_line
			(start 0.12065 0.3048)
			(end 0.67945 0.3048)
			(stroke
				(width 0.1)
				(type default)
			)
			(layer "B.Fab")
		)
		(fp_line
			(start 0.12065 0.2794)
			(end 0.12065 0.3048)
			(stroke
				(width 0.1)
				(type default)
			)
			(layer "B.Fab")
		)
		(fp_line
			(start 0.12065 -0.2794)
			(end -0.12065 -0.2794)
			(stroke
				(width 0.1)
				(type default)
			)
			(layer "B.Fab")
		)
		(fp_line
			(start 0.12065 -0.305054)
			(end 0.12065 -0.2794)
			(stroke
				(width 0.1)
				(type default)
			)
			(layer "B.Fab")
		)
		(fp_line
			(start -0.120396 0.3048)
			(end -0.120396 0.2794)
			(stroke
				(width 0.1)
				(type default)
			)
			(layer "B.Fab")
		)
		(fp_line
			(start -0.120396 0.2794)
			(end 0.12065 0.2794)
			(stroke
				(width 0.1)
				(type default)
			)
			(layer "B.Fab")
		)
		(fp_line
			(start -0.12065 -0.2794)
			(end -0.12065 -0.3048)
			(stroke
				(width 0.1)
				(type default)
			)
			(layer "B.Fab")
		)
		(fp_line
			(start -0.12065 -0.3048)
			(end -0.67945 -0.3048)
			(stroke
				(width 0.1)
				(type default)
			)
			(layer "B.Fab")
		)
		(fp_line
			(start -0.67945 0.3048)
			(end -0.120396 0.3048)
			(stroke
				(width 0.1)
				(type default)
			)
			(layer "B.Fab")
		)
		(fp_line
			(start -0.67945 -0.3048)
			(end -0.67945 0.3048)
			(stroke
				(width 0.1)
				(type default)
			)
			(layer "B.Fab")
		)
		(pad "1" smd circle
			(at 0.40005 0)
			(size 0 0)
			(layers "B.Cu" "B.Mask" "B.Paste")
			(net "P1V05_PCH_AUX")
		)
		(pad "2" smd circle
			(at -0.40005 0)
			(size 0 0)
			(layers "B.Cu" "B.Mask" "B.Paste")
			(net "GND")
		)
	)
	(footprint ""
		(layer "B.Cu")
		(at 477.81591 -427.280578 180)
		(property "Reference" "DB15"
			(at 2.527554 -8.29691 270)
			(unlocked yes)
			(layer "B.SilkS")
			(effects
				(font
					(size 0.7874 0.5842)
					(thickness 0.1524)
				)
				(justify left mirror)
			)
		)
		(property "Value" ""
			(at 0 0 0)
			(layer "B.Fab")
			(effects
				(font
					(size 1.27 1.27)
				)
				(justify mirror)
			)
		)
		(duplicate_pad_numbers_are_jumpers no)
		(fp_line
			(start 3.330702 -4.771136)
			(end -3.330702 -4.771136)
			(stroke
				(width 0.1524)
				(type default)
			)
			(layer "B.SilkS")
		)
		(fp_line
			(start 0 4.011168)
			(end 3.330702 -4.771136)
			(stroke
				(width 0.1524)
				(type default)
			)
			(layer "B.SilkS")
		)
		(fp_line
			(start -3.330702 -4.771136)
			(end 0 4.011168)
			(stroke
				(width 0.1524)
				(type default)
			)
			(layer "B.SilkS")
		)
		(fp_line
			(start 3.330702 -4.771136)
			(end -3.330702 -4.771136)
			(stroke
				(width 0.1)
				(type default)
			)
			(layer "B.Fab")
		)
		(fp_line
			(start 0 4.011168)
			(end 3.330702 -4.771136)
			(stroke
				(width 0.1)
				(type default)
			)
			(layer "B.Fab")
		)
		(fp_line
			(start -3.330702 -4.771136)
			(end 0 4.011168)
			(stroke
				(width 0.1)
				(type default)
			)
			(layer "B.Fab")
		)
		(pad "1" thru_hole circle
			(at 0 0)
			(size 2.159 2.159)
			(drill 1.7018)
			(layers "*.Cu" "*.Mask")
			(remove_unused_layers no)
			(net "T1_GND")
			(clearance 0.0254)
			(thermal_gap 0.0254)
		)
		(pad "2" thru_hole circle
			(at 1.27 -3.348736)
			(size 2.159 2.159)
			(drill 1.7018)
			(layers "*.Cu" "*.Mask")
			(remove_unused_layers no)
			(net "TDR_SE_50_OHM_IN5")
			(clearance 0.0254)
			(thermal_gap 0.0254)
		)
		(pad "3" thru_hole circle
			(at -1.27 -3.348736)
			(size 2.159 2.159)
			(drill 1.7018)
			(layers "*.Cu" "*.Mask")
			(remove_unused_layers no)
			(net "TDR_SE_50_OHM_IN5")
			(clearance 0.0254)
			(thermal_gap 0.0254)
		)
	)
	(footprint ""
		(layer "B.Cu")
		(at 187.88888 -101.564948)
		(property "Reference" "R3347"
			(at 0 0 0)
			(layer "B.SilkS")
			(hide yes)
			(effects
				(font
					(size 1.27 1.27)
				)
				(justify mirror)
			)
		)
		(property "Value" ""
			(at 0 0 0)
			(layer "B.Fab")
			(effects
				(font
					(size 1.27 1.27)
				)
				(justify mirror)
			)
		)
		(duplicate_pad_numbers_are_jumpers no)
		(fp_line
			(start -1.2954 -0.5842)
			(end -1.2954 0.5842)
			(stroke
				(width 0.1524)
				(type default)
			)
			(layer "B.SilkS")
		)
		(fp_line
			(start -1.2954 0.5842)
			(end 1.2954 0.5842)
			(stroke
				(width 0.1524)
				(type default)
			)
			(layer "B.SilkS")
		)
		(fp_line
			(start 1.2954 -0.5842)
			(end -1.2954 -0.5842)
			(stroke
				(width 0.1524)
				(type default)
			)
			(layer "B.SilkS")
		)
		(fp_line
			(start 1.2954 0.5842)
			(end 1.2954 -0.5842)
			(stroke
				(width 0.1524)
				(type default)
			)
			(layer "B.SilkS")
		)
		(fp_line
			(start -1.1938 -0.406654)
			(end -1.1938 0.4064)
			(stroke
				(width 0.1)
				(type default)
			)
			(layer "B.Fab")
		)
		(fp_line
			(start -1.1938 0.4064)
			(end -0.8636 0.4064)
			(stroke
				(width 0.1)
				(type default)
			)
			(layer "B.Fab")
		)
		(fp_line
			(start -0.8636 -0.4572)
			(end -0.8636 -0.406654)
			(stroke
				(width 0.1)
				(type default)
			)
			(layer "B.Fab")
		)
		(fp_line
			(start -0.8636 -0.406654)
			(end -1.1938 -0.406654)
			(stroke
				(width 0.1)
				(type default)
			)
			(layer "B.Fab")
		)
		(fp_line
			(start -0.8636 0.4064)
			(end -0.8636 0.4572)
			(stroke
				(width 0.1)
				(type default)
			)
			(layer "B.Fab")
		)
		(fp_line
			(start -0.8636 0.4572)
			(end 0.8636 0.4572)
			(stroke
				(width 0.1)
				(type default)
			)
			(layer "B.Fab")
		)
		(fp_line
			(start 0.8636 -0.4572)
			(end -0.8636 -0.4572)
			(stroke
				(width 0.1)
				(type default)
			)
			(layer "B.Fab")
		)
		(fp_line
			(start 0.8636 -0.406654)
			(end 0.8636 -0.4572)
			(stroke
				(width 0.1)
				(type default)
			)
			(layer "B.Fab")
		)
		(fp_line
			(start 0.8636 0.4064)
			(end 1.1938 0.4064)
			(stroke
				(width 0.1)
				(type default)
			)
			(layer "B.Fab")
		)
		(fp_line
			(start 0.8636 0.4318)
			(end 0.8636 0.4064)
			(stroke
				(width 0.1)
				(type default)
			)
			(layer "B.Fab")
		)
		(fp_line
			(start 0.8636 0.4572)
			(end 0.8636 0.4318)
			(stroke
				(width 0.1)
				(type default)
			)
			(layer "B.Fab")
		)
		(fp_line
			(start 1.1938 -0.406654)
			(end 0.8636 -0.406654)
			(stroke
				(width 0.1)
				(type default)
			)
			(layer "B.Fab")
		)
		(fp_line
			(start 1.1938 0.4064)
			(end 1.1938 -0.406654)
			(stroke
				(width 0.1)
				(type default)
			)
			(layer "B.Fab")
		)
		(pad "1" smd rect
			(at 0.7366 0 270)
			(size 0.7112 0.8128)
			(layers "B.Cu" "B.Mask" "B.Paste")
			(net "P3V3_AUX")
		)
		(pad "2" smd rect
			(at -0.7366 0 270)
			(size 0.7112 0.8128)
			(layers "B.Cu" "B.Mask" "B.Paste")
			(net "P3V3_AUX_FPGA_VCCIO2")
		)
	)
	(gr_poly
		(pts
			(xy 34.97072 -252.966728) (xy 30.5816 -252.966728) (xy 30.5816 -255.455928) (xy 34.97072 -255.455928)
		)
		(stroke
			(width 0)
			(type solid)
		)
		(fill yes)
		(layer "F.Cu")
		(net "GND")
	)
	(gr_poly
		(pts
			(xy 73.15708 -144.114266) (xy 73.15708 -143.42491) (xy 73.118472 -143.386302) (xy 71.90994 -143.386302)
			(xy 71.90994 -144.152874) (xy 73.118472 -144.152874)
		)
		(stroke
			(width 0)
			(type solid)
		)
		(fill yes)
		(layer "F.Cu")
		(net "PVCCINFAON_CPU1")
	)
	(gr_poly
		(pts
			(xy 74.233278 -277.773384) (xy 74.183494 -277.763478) (xy 74.07656 -277.778972) (xy 74.039476 -277.965916)
			(xy 74.132186 -278.021288) (xy 74.18197 -278.031194)
		)
		(stroke
			(width 0)
			(type solid)
		)
		(fill yes)
		(layer "F.Cu")
		(net "M_A_CPU1_SA_DQ<31>")
	)
	(gr_poly
		(pts
			(xy 74.34961 -277.187914) (xy 74.299826 -277.178008) (xy 74.193146 -277.193502) (xy 74.156062 -277.380446)
			(xy 74.248518 -277.435818) (xy 74.298302 -277.445724)
		)
		(stroke
			(width 0)
			(type solid)
		)
		(fill yes)
		(layer "F.Cu")
		(net "M_A_CPU1_SA_DQ<31>")
	)
	(gr_poly
		(pts
			(xy 74.3966 -277.732744) (xy 74.433938 -277.5458) (xy 74.341228 -277.490428) (xy 74.291444 -277.480522)
			(xy 74.240136 -277.738332) (xy 74.28992 -277.748238)
		)
		(stroke
			(width 0)
			(type solid)
		)
		(fill yes)
		(layer "F.Cu")
		(net "M_A_CPU1_SA_DQ<31>")
	)
	(gr_poly
		(pts
			(xy 74.466196 -276.602444) (xy 74.416412 -276.592538) (xy 74.309732 -276.608286) (xy 74.272394 -276.794976)
			(xy 74.365104 -276.850348) (xy 74.414888 -276.860254)
		)
		(stroke
			(width 0)
			(type solid)
		)
		(fill yes)
		(layer "F.Cu")
		(net "M_A_CPU1_SA_DQ<31>")
	)
	(gr_poly
		(pts
			(xy 74.513186 -277.147274) (xy 74.55027 -276.96033) (xy 74.457814 -276.904958) (xy 74.40803 -276.895052)
			(xy 74.356722 -277.153116) (xy 74.406506 -277.163022)
		)
		(stroke
			(width 0)
			(type solid)
		)
		(fill yes)
		(layer "F.Cu")
		(net "M_A_CPU1_SA_DQ<31>")
	)
	(gr_poly
		(pts
			(xy 74.53249 -277.83282) (xy 74.482706 -277.822914) (xy 74.376026 -277.838662) (xy 74.338688 -278.025352)
			(xy 74.431398 -278.080724) (xy 74.481182 -278.09063)
		)
		(stroke
			(width 0)
			(type solid)
		)
		(fill yes)
		(layer "F.Cu")
		(net "M_A_CPU1_SA_DQ<29>")
	)
	(gr_poly
		(pts
			(xy 74.649076 -277.24735) (xy 74.599038 -277.237444) (xy 74.492358 -277.253192) (xy 74.455274 -277.440136)
			(xy 74.54773 -277.495254) (xy 74.597768 -277.50516)
		)
		(stroke
			(width 0)
			(type solid)
		)
		(fill yes)
		(layer "F.Cu")
		(net "M_A_CPU1_SA_DQ<29>")
	)
	(gr_poly
		(pts
			(xy 74.696066 -277.79218) (xy 74.73315 -277.605236) (xy 74.64044 -277.550118) (xy 74.590656 -277.540212)
			(xy 74.539348 -277.798022) (xy 74.589386 -277.807928)
		)
		(stroke
			(width 0)
			(type solid)
		)
		(fill yes)
		(layer "F.Cu")
		(net "M_A_CPU1_SA_DQ<29>")
	)
	(gr_poly
		(pts
			(xy 74.765408 -276.66188) (xy 74.715624 -276.651974) (xy 74.608944 -276.667722) (xy 74.571606 -276.854666)
			(xy 74.664316 -276.909784) (xy 74.7141 -276.919944)
		)
		(stroke
			(width 0)
			(type solid)
		)
		(fill yes)
		(layer "F.Cu")
		(net "M_A_CPU1_SA_DQ<29>")
	)
	(gr_poly
		(pts
			(xy 74.802492 -275.773642) (xy 74.757788 -275.749766) (xy 74.651108 -275.733764) (xy 74.561192 -275.901658)
			(xy 74.633836 -275.981668) (xy 74.67854 -276.005544)
		)
		(stroke
			(width 0)
			(type solid)
		)
		(fill yes)
		(layer "F.Cu")
		(net "M_A_CPU1_SA_DQ<31>")
	)
	(gr_poly
		(pts
			(xy 74.812398 -277.20671) (xy 74.849482 -277.02002) (xy 74.757026 -276.964648) (xy 74.707242 -276.954742)
			(xy 74.655934 -277.212552) (xy 74.705718 -277.222458)
		)
		(stroke
			(width 0)
			(type solid)
		)
		(fill yes)
		(layer "F.Cu")
		(net "M_A_CPU1_SA_DQ<29>")
	)
	(gr_poly
		(pts
			(xy 74.831956 -277.89251) (xy 74.782172 -277.882604) (xy 74.675492 -277.898098) (xy 74.638154 -278.085042)
			(xy 74.730864 -278.140414) (xy 74.780648 -278.15032)
		)
		(stroke
			(width 0)
			(type solid)
		)
		(fill yes)
		(layer "F.Cu")
		(net "M_A_CPU1_SA_DQ<30>")
	)
	(gr_poly
		(pts
			(xy 74.878946 -278.437086) (xy 74.91603 -278.250396) (xy 74.823574 -278.195024) (xy 74.77379 -278.185118)
			(xy 74.722482 -278.442928) (xy 74.772266 -278.452834)
		)
		(stroke
			(width 0)
			(type solid)
		)
		(fill yes)
		(layer "F.Cu")
		(net "M_A_CPU1_SA_DQ<30>")
	)
	(gr_poly
		(pts
			(xy 74.948288 -277.30704) (xy 74.898504 -277.297134) (xy 74.791824 -277.312628) (xy 74.754486 -277.499572)
			(xy 74.847196 -277.554944) (xy 74.89698 -277.56485)
		)
		(stroke
			(width 0)
			(type solid)
		)
		(fill yes)
		(layer "F.Cu")
		(net "M_A_CPU1_SA_DQ<30>")
	)
	(gr_poly
		(pts
			(xy 74.995278 -277.85187) (xy 75.032616 -277.664926) (xy 74.939906 -277.609554) (xy 74.890122 -277.599648)
			(xy 74.838814 -277.857458) (xy 74.888598 -277.867364)
		)
		(stroke
			(width 0)
			(type solid)
		)
		(fill yes)
		(layer "F.Cu")
		(net "M_A_CPU1_SA_DQ<30>")
	)
	(gr_poly
		(pts
			(xy 75.060556 -275.614384) (xy 74.987912 -275.534374) (xy 74.943208 -275.510498) (xy 74.819256 -275.7424)
			(xy 74.86396 -275.766276) (xy 74.97064 -275.782278)
		)
		(stroke
			(width 0)
			(type solid)
		)
		(fill yes)
		(layer "F.Cu")
		(net "M_A_CPU1_SA_DQ<31>")
	)
	(gr_poly
		(pts
			(xy 75.06462 -276.72157) (xy 75.014836 -276.711664) (xy 74.908156 -276.727412) (xy 74.871072 -276.914102)
			(xy 74.963528 -276.969474) (xy 75.013312 -276.97938)
		)
		(stroke
			(width 0)
			(type solid)
		)
		(fill yes)
		(layer "F.Cu")
		(net "M_A_CPU1_SA_DQ<30>")
	)
	(gr_poly
		(pts
			(xy 75.071732 -275.91766) (xy 75.026774 -275.89353) (xy 74.920094 -275.877782) (xy 74.830432 -276.045676)
			(xy 74.902822 -276.125432) (xy 74.94778 -276.149562)
		)
		(stroke
			(width 0)
			(type solid)
		)
		(fill yes)
		(layer "F.Cu")
		(net "M_A_CPU1_SA_DQ<29>")
	)
	(gr_poly
		(pts
			(xy 75.083924 -275.247354) (xy 75.038966 -275.223224) (xy 74.932286 -275.207476) (xy 74.842624 -275.37537)
			(xy 74.915014 -275.455126) (xy 74.959972 -275.479256)
		)
		(stroke
			(width 0)
			(type solid)
		)
		(fill yes)
		(layer "F.Cu")
		(net "M_A_CPU1_SA_DQ<31>")
	)
	(gr_poly
		(pts
			(xy 75.11161 -277.2664) (xy 75.148948 -277.079456) (xy 75.056238 -277.024084) (xy 75.006454 -277.014178)
			(xy 74.955146 -277.271988) (xy 75.00493 -277.281894)
		)
		(stroke
			(width 0)
			(type solid)
		)
		(fill yes)
		(layer "F.Cu")
		(net "M_A_CPU1_SA_DQ<30>")
	)
	(gr_poly
		(pts
			(xy 75.130914 -277.951946) (xy 75.08113 -277.94204) (xy 74.97445 -277.957788) (xy 74.937366 -278.144478)
			(xy 75.029822 -278.19985) (xy 75.07986 -278.209756)
		)
		(stroke
			(width 0)
			(type solid)
		)
		(fill yes)
		(layer "F.Cu")
		(net "M_A_CPU1_SA_DQ<28>")
	)
	(gr_poly
		(pts
			(xy 75.178158 -278.496776) (xy 75.215242 -278.309832) (xy 75.122532 -278.25446) (xy 75.072748 -278.244554)
			(xy 75.02144 -278.502618) (xy 75.071478 -278.51227)
		)
		(stroke
			(width 0)
			(type solid)
		)
		(fill yes)
		(layer "F.Cu")
		(net "M_A_CPU1_SA_DQ<28>")
	)
	(gr_poly
		(pts
			(xy 75.2475 -277.366476) (xy 75.197716 -277.35657) (xy 75.090782 -277.372318) (xy 75.053698 -277.559008)
			(xy 75.146408 -277.61438) (xy 75.196192 -277.624286)
		)
		(stroke
			(width 0)
			(type solid)
		)
		(fill yes)
		(layer "F.Cu")
		(net "M_A_CPU1_SA_DQ<28>")
	)
	(gr_poly
		(pts
			(xy 75.29449 -277.911306) (xy 75.331574 -277.724362) (xy 75.239118 -277.66899) (xy 75.189334 -277.659084)
			(xy 75.138026 -277.917148) (xy 75.18781 -277.927054)
		)
		(stroke
			(width 0)
			(type solid)
		)
		(fill yes)
		(layer "F.Cu")
		(net "M_A_CPU1_SA_DQ<28>")
	)
	(gr_poly
		(pts
			(xy 75.329796 -275.758148) (xy 75.257152 -275.678392) (xy 75.212448 -275.654262) (xy 75.088496 -275.886164)
			(xy 75.1332 -275.910294) (xy 75.23988 -275.926042)
		)
		(stroke
			(width 0)
			(type solid)
		)
		(fill yes)
		(layer "F.Cu")
		(net "M_A_CPU1_SA_DQ<29>")
	)
	(gr_poly
		(pts
			(xy 75.340718 -276.061424) (xy 75.296014 -276.037548) (xy 75.189334 -276.021546) (xy 75.099418 -276.18944)
			(xy 75.172062 -276.26945) (xy 75.216766 -276.293326)
		)
		(stroke
			(width 0)
			(type solid)
		)
		(fill yes)
		(layer "F.Cu")
		(net "M_A_CPU1_SA_DQ<30>")
	)
	(gr_poly
		(pts
			(xy 75.341988 -275.087842) (xy 75.269344 -275.008086) (xy 75.22464 -274.98421) (xy 75.100688 -275.215858)
			(xy 75.145392 -275.239988) (xy 75.252072 -275.255736)
		)
		(stroke
			(width 0)
			(type solid)
		)
		(fill yes)
		(layer "F.Cu")
		(net "M_A_CPU1_SA_DQ<31>")
	)
	(gr_poly
		(pts
			(xy 75.35291 -275.391118) (xy 75.308206 -275.367242) (xy 75.201526 -275.35124) (xy 75.111864 -275.519134)
			(xy 75.184254 -275.599144) (xy 75.229212 -275.62302)
		)
		(stroke
			(width 0)
			(type solid)
		)
		(fill yes)
		(layer "F.Cu")
		(net "M_A_CPU1_SA_DQ<29>")
	)
	(gr_poly
		(pts
			(xy 75.363832 -276.781006) (xy 75.314048 -276.7711) (xy 75.207368 -276.786848) (xy 75.170284 -276.973792)
			(xy 75.26274 -277.02891) (xy 75.312524 -277.038816)
		)
		(stroke
			(width 0)
			(type solid)
		)
		(fill yes)
		(layer "F.Cu")
		(net "M_A_CPU1_SA_DQ<28>")
	)
	(gr_poly
		(pts
			(xy 75.365356 -274.720812) (xy 75.320398 -274.696936) (xy 75.213718 -274.680934) (xy 75.124056 -274.849082)
			(xy 75.196446 -274.928838) (xy 75.241404 -274.952714)
		)
		(stroke
			(width 0)
			(type solid)
		)
		(fill yes)
		(layer "F.Cu")
		(net "M_A_CPU1_SA_DQ<31>")
	)
	(gr_poly
		(pts
			(xy 75.410822 -277.325836) (xy 75.44816 -277.138892) (xy 75.35545 -277.083774) (xy 75.305666 -277.073868)
			(xy 75.254358 -277.331678) (xy 75.304142 -277.341584)
		)
		(stroke
			(width 0)
			(type solid)
		)
		(fill yes)
		(layer "F.Cu")
		(net "M_A_CPU1_SA_DQ<28>")
	)
	(gr_poly
		(pts
			(xy 75.598782 -275.901912) (xy 75.526138 -275.822156) (xy 75.481434 -275.79828) (xy 75.357482 -276.030182)
			(xy 75.40244 -276.054058) (xy 75.508866 -276.07006)
		)
		(stroke
			(width 0)
			(type solid)
		)
		(fill yes)
		(layer "F.Cu")
		(net "M_A_CPU1_SA_DQ<30>")
	)
	(gr_poly
		(pts
			(xy 75.609958 -276.205442) (xy 75.565254 -276.181312) (xy 75.458574 -276.165564) (xy 75.368658 -276.333458)
			(xy 75.441302 -276.413214) (xy 75.486006 -276.437344)
		)
		(stroke
			(width 0)
			(type solid)
		)
		(fill yes)
		(layer "F.Cu")
		(net "M_A_CPU1_SA_DQ<28>")
	)
	(gr_poly
		(pts
			(xy 75.610974 -275.231606) (xy 75.538584 -275.15185) (xy 75.493626 -275.127974) (xy 75.369674 -275.359876)
			(xy 75.414632 -275.383752) (xy 75.521312 -275.399754)
		)
		(stroke
			(width 0)
			(type solid)
		)
		(fill yes)
		(layer "F.Cu")
		(net "M_A_CPU1_SA_DQ<29>")
	)
	(gr_poly
		(pts
			(xy 75.62215 -275.535136) (xy 75.577446 -275.511006) (xy 75.470766 -275.495004) (xy 75.38085 -275.663152)
			(xy 75.453494 -275.742908) (xy 75.498198 -275.766784)
		)
		(stroke
			(width 0)
			(type solid)
		)
		(fill yes)
		(layer "F.Cu")
		(net "M_A_CPU1_SA_DQ<30>")
	)
	(gr_poly
		(pts
			(xy 75.62342 -274.561554) (xy 75.550776 -274.481544) (xy 75.506072 -274.457668) (xy 75.38212 -274.68957)
			(xy 75.426824 -274.713446) (xy 75.533504 -274.729448)
		)
		(stroke
			(width 0)
			(type solid)
		)
		(fill yes)
		(layer "F.Cu")
		(net "M_A_CPU1_SA_DQ<31>")
	)
	(gr_poly
		(pts
			(xy 75.634342 -274.86483) (xy 75.589638 -274.8407) (xy 75.482958 -274.824952) (xy 75.393042 -274.992846)
			(xy 75.465686 -275.072602) (xy 75.51039 -275.096478)
		)
		(stroke
			(width 0)
			(type solid)
		)
		(fill yes)
		(layer "F.Cu")
		(net "M_A_CPU1_SA_DQ<29>")
	)
	(gr_poly
		(pts
			(xy 75.646788 -274.194524) (xy 75.60183 -274.170648) (xy 75.49515 -274.154646) (xy 75.405488 -274.32254)
			(xy 75.477878 -274.402296) (xy 75.522836 -274.426426)
		)
		(stroke
			(width 0)
			(type solid)
		)
		(fill yes)
		(layer "F.Cu")
		(net "M_A_CPU1_SA_DQ<31>")
	)
	(gr_poly
		(pts
			(xy 75.868022 -276.04593) (xy 75.795632 -275.966174) (xy 75.750674 -275.942298) (xy 75.626722 -276.173946)
			(xy 75.67168 -276.198076) (xy 75.77836 -276.214078)
		)
		(stroke
			(width 0)
			(type solid)
		)
		(fill yes)
		(layer "F.Cu")
		(net "M_A_CPU1_SA_DQ<28>")
	)
	(gr_poly
		(pts
			(xy 75.880214 -275.375624) (xy 75.80757 -275.295868) (xy 75.762866 -275.271738) (xy 75.638914 -275.50364)
			(xy 75.683618 -275.527516) (xy 75.790298 -275.543518)
		)
		(stroke
			(width 0)
			(type solid)
		)
		(fill yes)
		(layer "F.Cu")
		(net "M_A_CPU1_SA_DQ<30>")
	)
	(gr_poly
		(pts
			(xy 75.89139 -275.6789) (xy 75.846686 -275.655024) (xy 75.740006 -275.639022) (xy 75.65009 -275.80717)
			(xy 75.722734 -275.886926) (xy 75.767438 -275.910802)
		)
		(stroke
			(width 0)
			(type solid)
		)
		(fill yes)
		(layer "F.Cu")
		(net "M_A_CPU1_SA_DQ<28>")
	)
	(gr_poly
		(pts
			(xy 75.892406 -274.705318) (xy 75.819762 -274.625562) (xy 75.775058 -274.601432) (xy 75.651106 -274.833334)
			(xy 75.696064 -274.857464) (xy 75.802744 -274.873212)
		)
		(stroke
			(width 0)
			(type solid)
		)
		(fill yes)
		(layer "F.Cu")
		(net "M_A_CPU1_SA_DQ<29>")
	)
	(gr_poly
		(pts
			(xy 75.903582 -275.008594) (xy 75.858624 -274.984718) (xy 75.751944 -274.968716) (xy 75.662282 -275.13661)
			(xy 75.734926 -275.21662) (xy 75.77963 -275.240496)
		)
		(stroke
			(width 0)
			(type solid)
		)
		(fill yes)
		(layer "F.Cu")
		(net "M_A_CPU1_SA_DQ<30>")
	)
	(gr_poly
		(pts
			(xy 75.904598 -274.035012) (xy 75.832208 -273.955256) (xy 75.78725 -273.93138) (xy 75.663552 -274.163028)
			(xy 75.708256 -274.187158) (xy 75.814936 -274.20316)
		)
		(stroke
			(width 0)
			(type solid)
		)
		(fill yes)
		(layer "F.Cu")
		(net "M_A_CPU1_SA_DQ<31>")
	)
	(gr_poly
		(pts
			(xy 75.915774 -274.338288) (xy 75.87107 -274.314412) (xy 75.76439 -274.29841) (xy 75.674474 -274.466304)
			(xy 75.747118 -274.546314) (xy 75.791822 -274.57019)
		)
		(stroke
			(width 0)
			(type solid)
		)
		(fill yes)
		(layer "F.Cu")
		(net "M_A_CPU1_SA_DQ<29>")
	)
	(gr_poly
		(pts
			(xy 75.927966 -273.667982) (xy 75.883262 -273.644106) (xy 75.776582 -273.628104) (xy 75.686666 -273.796252)
			(xy 75.75931 -273.876008) (xy 75.804014 -273.899884)
		)
		(stroke
			(width 0)
			(type solid)
		)
		(fill yes)
		(layer "F.Cu")
		(net "M_A_CPU1_SA_DQ<31>")
	)
	(gr_poly
		(pts
			(xy 76.04887 -281.31262) (xy 75.999086 -281.302714) (xy 75.892406 -281.318208) (xy 75.855322 -281.505152)
			(xy 75.947778 -281.560524) (xy 75.997562 -281.57043)
		)
		(stroke
			(width 0)
			(type solid)
		)
		(fill yes)
		(layer "F.Cu")
		(net "M_A_CPU1_SA_DQ<27>")
	)
	(gr_poly
		(pts
			(xy 76.149454 -275.519642) (xy 76.077064 -275.439886) (xy 76.032106 -275.415756) (xy 75.908154 -275.647658)
			(xy 75.953112 -275.671534) (xy 76.059792 -275.687536)
		)
		(stroke
			(width 0)
			(type solid)
		)
		(fill yes)
		(layer "F.Cu")
		(net "M_A_CPU1_SA_DQ<28>")
	)
	(gr_poly
		(pts
			(xy 76.161646 -274.849082) (xy 76.089002 -274.769326) (xy 76.044298 -274.74545) (xy 75.920346 -274.977352)
			(xy 75.96505 -275.001228) (xy 76.07173 -275.01723)
		)
		(stroke
			(width 0)
			(type solid)
		)
		(fill yes)
		(layer "F.Cu")
		(net "M_A_CPU1_SA_DQ<30>")
	)
	(gr_poly
		(pts
			(xy 76.165456 -280.72715) (xy 76.115672 -280.717244) (xy 76.008992 -280.732992) (xy 75.971654 -280.919682)
			(xy 76.064364 -280.975054) (xy 76.114148 -280.98496)
		)
		(stroke
			(width 0)
			(type solid)
		)
		(fill yes)
		(layer "F.Cu")
		(net "M_A_CPU1_SA_DQ<27>")
	)
	(gr_poly
		(pts
			(xy 76.172822 -275.152612) (xy 76.128118 -275.128736) (xy 76.021438 -275.112734) (xy 75.931776 -275.280628)
			(xy 76.004166 -275.360638) (xy 76.049124 -275.384514)
		)
		(stroke
			(width 0)
			(type solid)
		)
		(fill yes)
		(layer "F.Cu")
		(net "M_A_CPU1_SA_DQ<28>")
	)
	(gr_poly
		(pts
			(xy 76.173838 -274.178776) (xy 76.101194 -274.09902) (xy 76.05649 -274.075144) (xy 75.932538 -274.307046)
			(xy 75.977242 -274.330922) (xy 76.083922 -274.346924)
		)
		(stroke
			(width 0)
			(type solid)
		)
		(fill yes)
		(layer "F.Cu")
		(net "M_A_CPU1_SA_DQ<29>")
	)
	(gr_poly
		(pts
			(xy 76.185014 -274.482306) (xy 76.140056 -274.458176) (xy 76.033376 -274.442174) (xy 75.943714 -274.610322)
			(xy 76.016104 -274.690078) (xy 76.061062 -274.713954)
		)
		(stroke
			(width 0)
			(type solid)
		)
		(fill yes)
		(layer "F.Cu")
		(net "M_A_CPU1_SA_DQ<30>")
	)
	(gr_poly
		(pts
			(xy 76.197206 -273.812) (xy 76.152248 -273.78787) (xy 76.045568 -273.771868) (xy 75.955906 -273.940016)
			(xy 76.028296 -274.019772) (xy 76.073254 -274.043648)
		)
		(stroke
			(width 0)
			(type solid)
		)
		(fill yes)
		(layer "F.Cu")
		(net "M_A_CPU1_SA_DQ<29>")
	)
	(gr_poly
		(pts
			(xy 76.212446 -281.27198) (xy 76.24953 -281.085036) (xy 76.157074 -281.029664) (xy 76.10729 -281.019758)
			(xy 76.055982 -281.277568) (xy 76.105766 -281.287728)
		)
		(stroke
			(width 0)
			(type solid)
		)
		(fill yes)
		(layer "F.Cu")
		(net "M_A_CPU1_SA_DQ<27>")
	)
	(gr_poly
		(pts
			(xy 76.282042 -280.14168) (xy 76.232004 -280.131774) (xy 76.125324 -280.147522) (xy 76.08824 -280.334212)
			(xy 76.180696 -280.389584) (xy 76.230734 -280.39949)
		)
		(stroke
			(width 0)
			(type solid)
		)
		(fill yes)
		(layer "F.Cu")
		(net "M_A_CPU1_SA_DQ<27>")
	)
	(gr_poly
		(pts
			(xy 76.329032 -280.68651) (xy 76.366116 -280.499566) (xy 76.273406 -280.444448) (xy 76.223622 -280.434542)
			(xy 76.172314 -280.692352) (xy 76.222098 -280.702258)
		)
		(stroke
			(width 0)
			(type solid)
		)
		(fill yes)
		(layer "F.Cu")
		(net "M_A_CPU1_SA_DQ<27>")
	)
	(gr_poly
		(pts
			(xy 76.398374 -279.55621) (xy 76.34859 -279.546304) (xy 76.24191 -279.562052) (xy 76.204826 -279.748996)
			(xy 76.297282 -279.804114) (xy 76.347066 -279.81402)
		)
		(stroke
			(width 0)
			(type solid)
		)
		(fill yes)
		(layer "F.Cu")
		(net "M_A_CPU1_SA_DQ<27>")
	)
	(gr_poly
		(pts
			(xy 76.43114 -274.9931) (xy 76.358496 -274.913344) (xy 76.313792 -274.889468) (xy 76.18984 -275.12137)
			(xy 76.234544 -275.145246) (xy 76.341224 -275.161248)
		)
		(stroke
			(width 0)
			(type solid)
		)
		(fill yes)
		(layer "F.Cu")
		(net "M_A_CPU1_SA_DQ<28>")
	)
	(gr_poly
		(pts
			(xy 76.443078 -274.322794) (xy 76.370434 -274.243038) (xy 76.32573 -274.218908) (xy 76.201778 -274.45081)
			(xy 76.246482 -274.474686) (xy 76.353162 -274.490688)
		)
		(stroke
			(width 0)
			(type solid)
		)
		(fill yes)
		(layer "F.Cu")
		(net "M_A_CPU1_SA_DQ<30>")
	)
	(gr_poly
		(pts
			(xy 76.445364 -280.10104) (xy 76.482702 -279.91435) (xy 76.389992 -279.858978) (xy 76.340208 -279.849072)
			(xy 76.2889 -280.106882) (xy 76.338684 -280.116788)
		)
		(stroke
			(width 0)
			(type solid)
		)
		(fill yes)
		(layer "F.Cu")
		(net "M_A_CPU1_SA_DQ<27>")
	)
	(gr_poly
		(pts
			(xy 76.454508 -274.626324) (xy 76.40955 -274.602448) (xy 76.30287 -274.586446) (xy 76.213208 -274.75434)
			(xy 76.285598 -274.834096) (xy 76.330556 -274.858226)
		)
		(stroke
			(width 0)
			(type solid)
		)
		(fill yes)
		(layer "F.Cu")
		(net "M_A_CPU1_SA_DQ<28>")
	)
	(gr_poly
		(pts
			(xy 76.464668 -280.786586) (xy 76.414884 -280.77668) (xy 76.308204 -280.792428) (xy 76.270866 -280.979372)
			(xy 76.363576 -281.03449) (xy 76.41336 -281.044396)
		)
		(stroke
			(width 0)
			(type solid)
		)
		(fill yes)
		(layer "F.Cu")
		(net "M_A_CPU1_SA_DQ<25>")
	)
	(gr_poly
		(pts
			(xy 76.466192 -273.955764) (xy 76.421488 -273.931888) (xy 76.314808 -273.915886) (xy 76.225146 -274.08378)
			(xy 76.297536 -274.16379) (xy 76.342494 -274.187666)
		)
		(stroke
			(width 0)
			(type solid)
		)
		(fill yes)
		(layer "F.Cu")
		(net "M_A_CPU1_SA_DQ<30>")
	)
	(gr_poly
		(pts
			(xy 76.482448 -273.199606) (xy 76.43622 -273.10207) (xy 76.400152 -273.066256) (xy 76.214224 -273.252184)
			(xy 76.250292 -273.287998) (xy 76.347574 -273.334226)
		)
		(stroke
			(width 0)
			(type solid)
		)
		(fill yes)
		(layer "F.Cu")
		(net "M_A_CPU1_SA_DQ<31>")
	)
	(gr_poly
		(pts
			(xy 76.511658 -281.331416) (xy 76.548742 -281.144726) (xy 76.456286 -281.089354) (xy 76.406502 -281.079448)
			(xy 76.355194 -281.337258) (xy 76.404978 -281.347164)
		)
		(stroke
			(width 0)
			(type solid)
		)
		(fill yes)
		(layer "F.Cu")
		(net "M_A_CPU1_SA_DQ<25>")
	)
	(gr_poly
		(pts
			(xy 76.51496 -278.970994) (xy 76.465176 -278.961088) (xy 76.358496 -278.976582) (xy 76.321158 -279.163526)
			(xy 76.413868 -279.218898) (xy 76.463652 -279.228804)
		)
		(stroke
			(width 0)
			(type solid)
		)
		(fill yes)
		(layer "F.Cu")
		(net "M_A_CPU1_SA_DQ<27>")
	)
	(gr_poly
		(pts
			(xy 76.52512 -266.2809) (xy 76.489306 -266.244832) (xy 76.39177 -266.198604) (xy 76.25715 -266.333224)
			(xy 76.303378 -266.43076) (xy 76.339446 -266.466574)
		)
		(stroke
			(width 0)
			(type solid)
		)
		(fill yes)
		(layer "F.Cu")
		(net "M_A_CPU1_SA_CB<5>")
	)
	(gr_poly
		(pts
			(xy 76.56195 -279.51557) (xy 76.599034 -279.32888) (xy 76.506578 -279.273508) (xy 76.45654 -279.263602)
			(xy 76.405486 -279.521412) (xy 76.45527 -279.531318)
		)
		(stroke
			(width 0)
			(type solid)
		)
		(fill yes)
		(layer "F.Cu")
		(net "M_A_CPU1_SA_DQ<27>")
	)
	(gr_poly
		(pts
			(xy 76.581254 -280.20137) (xy 76.53147 -280.191464) (xy 76.424536 -280.206958) (xy 76.387452 -280.393902)
			(xy 76.480162 -280.449274) (xy 76.529946 -280.45918)
		)
		(stroke
			(width 0)
			(type solid)
		)
		(fill yes)
		(layer "F.Cu")
		(net "M_A_CPU1_SA_DQ<25>")
	)
	(gr_poly
		(pts
			(xy 76.60259 -265.987276) (xy 76.556362 -265.889994) (xy 76.520548 -265.853926) (xy 76.33462 -266.039854)
			(xy 76.370434 -266.075922) (xy 76.46797 -266.12215)
		)
		(stroke
			(width 0)
			(type solid)
		)
		(fill yes)
		(layer "F.Cu")
		(net "M_A_CPU1_SA_CB<7>")
	)
	(gr_poly
		(pts
			(xy 76.611226 -272.855182) (xy 76.575412 -272.819368) (xy 76.477876 -272.772886) (xy 76.343256 -272.90776)
			(xy 76.389484 -273.005042) (xy 76.425298 -273.04111)
		)
		(stroke
			(width 0)
			(type solid)
		)
		(fill yes)
		(layer "F.Cu")
		(net "M_A_CPU1_SA_DQ<31>")
	)
	(gr_poly
		(pts
			(xy 76.628244 -280.745946) (xy 76.665328 -280.559256) (xy 76.572872 -280.503884) (xy 76.522834 -280.493978)
			(xy 76.471526 -280.751788) (xy 76.521564 -280.761694)
		)
		(stroke
			(width 0)
			(type solid)
		)
		(fill yes)
		(layer "F.Cu")
		(net "M_A_CPU1_SA_DQ<25>")
	)
	(gr_poly
		(pts
			(xy 76.631292 -278.385524) (xy 76.581508 -278.375618) (xy 76.474828 -278.391112) (xy 76.437744 -278.578056)
			(xy 76.5302 -278.633428) (xy 76.579984 -278.643334)
		)
		(stroke
			(width 0)
			(type solid)
		)
		(fill yes)
		(layer "F.Cu")
		(net "M_A_CPU1_SA_DQ<27>")
	)
	(gr_poly
		(pts
			(xy 76.647548 -281.431492) (xy 76.597764 -281.421586) (xy 76.49083 -281.437334) (xy 76.453746 -281.624278)
			(xy 76.546456 -281.679396) (xy 76.59624 -281.689556)
		)
		(stroke
			(width 0)
			(type solid)
		)
		(fill yes)
		(layer "F.Cu")
		(net "M_A_CPU1_SA_DQ<26>")
	)
	(gr_poly
		(pts
			(xy 76.678282 -278.930354) (xy 76.71562 -278.74341) (xy 76.62291 -278.688038) (xy 76.573126 -278.678132)
			(xy 76.521818 -278.935942) (xy 76.571602 -278.945848)
		)
		(stroke
			(width 0)
			(type solid)
		)
		(fill yes)
		(layer "F.Cu")
		(net "M_A_CPU1_SA_DQ<27>")
	)
	(gr_poly
		(pts
			(xy 76.697586 -279.6159) (xy 76.647802 -279.605994) (xy 76.541122 -279.621488) (xy 76.504038 -279.808432)
			(xy 76.596494 -279.863804) (xy 76.646278 -279.87371)
		)
		(stroke
			(width 0)
			(type solid)
		)
		(fill yes)
		(layer "F.Cu")
		(net "M_A_CPU1_SA_DQ<25>")
	)
	(gr_poly
		(pts
			(xy 76.698094 -273.415252) (xy 76.651866 -273.31797) (xy 76.616052 -273.281902) (xy 76.430124 -273.46783)
			(xy 76.465938 -273.503898) (xy 76.563474 -273.550126)
		)
		(stroke
			(width 0)
			(type solid)
		)
		(fill yes)
		(layer "F.Cu")
		(net "M_A_CPU1_SA_DQ<29>")
	)
	(gr_poly
		(pts
			(xy 76.712572 -274.466812) (xy 76.639928 -274.387056) (xy 76.595224 -274.36318) (xy 76.471272 -274.594828)
			(xy 76.515976 -274.618958) (xy 76.622656 -274.63496)
		)
		(stroke
			(width 0)
			(type solid)
		)
		(fill yes)
		(layer "F.Cu")
		(net "M_A_CPU1_SA_DQ<28>")
	)
	(gr_poly
		(pts
			(xy 76.731622 -265.642852) (xy 76.695554 -265.607038) (xy 76.598272 -265.56081) (xy 76.463398 -265.69543)
			(xy 76.509626 -265.792966) (xy 76.545694 -265.82878)
		)
		(stroke
			(width 0)
			(type solid)
		)
		(fill yes)
		(layer "F.Cu")
		(net "M_A_CPU1_SA_CB<7>")
	)
	(gr_poly
		(pts
			(xy 76.732384 -223.210374) (xy 76.681584 -223.210374) (xy 76.579984 -223.246696) (xy 76.579984 -223.437196)
			(xy 76.681584 -223.473518) (xy 76.732384 -223.473518)
		)
		(stroke
			(width 0)
			(type solid)
		)
		(fill yes)
		(layer "F.Cu")
		(net "M_A_CPU1_SB_DQ<16>")
	)
	(gr_poly
		(pts
			(xy 76.732384 -222.613474) (xy 76.681584 -222.613474) (xy 76.579984 -222.649796) (xy 76.579984 -222.840296)
			(xy 76.681584 -222.876618) (xy 76.732384 -222.876618)
		)
		(stroke
			(width 0)
			(type solid)
		)
		(fill yes)
		(layer "F.Cu")
		(net "M_A_CPU1_SB_DQ<16>")
	)
	(gr_poly
		(pts
			(xy 76.732384 -222.016574) (xy 76.681584 -222.016574) (xy 76.579984 -222.052896) (xy 76.579984 -222.243396)
			(xy 76.681584 -222.279718) (xy 76.732384 -222.279718)
		)
		(stroke
			(width 0)
			(type solid)
		)
		(fill yes)
		(layer "F.Cu")
		(net "M_A_CPU1_SB_DQ<16>")
	)
	(gr_poly
		(pts
			(xy 76.732384 -221.419674) (xy 76.681584 -221.419674) (xy 76.579984 -221.455996) (xy 76.579984 -221.646496)
			(xy 76.681584 -221.682818) (xy 76.732384 -221.682818)
		)
		(stroke
			(width 0)
			(type solid)
		)
		(fill yes)
		(layer "F.Cu")
		(net "M_A_CPU1_SB_DQ<16>")
	)
	(gr_poly
		(pts
			(xy 76.732384 -220.822774) (xy 76.681584 -220.822774) (xy 76.579984 -220.859096) (xy 76.579984 -221.049596)
			(xy 76.681584 -221.085918) (xy 76.732384 -221.085918)
		)
		(stroke
			(width 0)
			(type solid)
		)
		(fill yes)
		(layer "F.Cu")
		(net "M_A_CPU1_SB_DQ<16>")
	)
	(gr_poly
		(pts
			(xy 76.732384 -220.225874) (xy 76.681584 -220.225874) (xy 76.579984 -220.262196) (xy 76.579984 -220.452696)
			(xy 76.681584 -220.489018) (xy 76.732384 -220.489018)
		)
		(stroke
			(width 0)
			(type solid)
		)
		(fill yes)
		(layer "F.Cu")
		(net "M_A_CPU1_SB_DQ<16>")
	)
	(gr_poly
		(pts
			(xy 76.73594 -274.099782) (xy 76.690982 -274.075906) (xy 76.584302 -274.059904) (xy 76.49464 -274.228052)
			(xy 76.56703 -274.307808) (xy 76.611988 -274.331684)
		)
		(stroke
			(width 0)
			(type solid)
		)
		(fill yes)
		(layer "F.Cu")
		(net "M_A_CPU1_SA_DQ<28>")
	)
	(gr_poly
		(pts
			(xy 76.74102 -266.496546) (xy 76.704952 -266.460732) (xy 76.60767 -266.414504) (xy 76.47305 -266.549124)
			(xy 76.519278 -266.64666) (xy 76.555092 -266.682474)
		)
		(stroke
			(width 0)
			(type solid)
		)
		(fill yes)
		(layer "F.Cu")
		(net "M_A_CPU1_SA_CB<6>")
	)
	(gr_poly
		(pts
			(xy 76.744322 -280.16073) (xy 76.78166 -279.973786) (xy 76.68895 -279.918414) (xy 76.639166 -279.908508)
			(xy 76.587858 -280.166318) (xy 76.637642 -280.176224)
		)
		(stroke
			(width 0)
			(type solid)
		)
		(fill yes)
		(layer "F.Cu")
		(net "M_A_CPU1_SA_DQ<25>")
	)
	(gr_poly
		(pts
			(xy 76.747878 -277.800054) (xy 76.698094 -277.790148) (xy 76.591414 -277.805896) (xy 76.554076 -277.992586)
			(xy 76.646786 -278.047958) (xy 76.69657 -278.057864)
		)
		(stroke
			(width 0)
			(type solid)
		)
		(fill yes)
		(layer "F.Cu")
		(net "M_A_CPU1_SA_DQ<27>")
	)
	(gr_poly
		(pts
			(xy 76.763626 -280.846276) (xy 76.713842 -280.83637) (xy 76.607162 -280.851864) (xy 76.570078 -281.038808)
			(xy 76.662534 -281.09418) (xy 76.712318 -281.104086)
		)
		(stroke
			(width 0)
			(type solid)
		)
		(fill yes)
		(layer "F.Cu")
		(net "M_A_CPU1_SA_DQ<26>")
	)
	(gr_poly
		(pts
			(xy 76.794868 -278.344884) (xy 76.831952 -278.15794) (xy 76.739496 -278.102568) (xy 76.689712 -278.092662)
			(xy 76.638404 -278.350472) (xy 76.688188 -278.360378)
		)
		(stroke
			(width 0)
			(type solid)
		)
		(fill yes)
		(layer "F.Cu")
		(net "M_A_CPU1_SA_DQ<27>")
	)
	(gr_poly
		(pts
			(xy 76.810616 -281.390852) (xy 76.847954 -281.204162) (xy 76.755244 -281.14879) (xy 76.70546 -281.138884)
			(xy 76.654152 -281.396694) (xy 76.703936 -281.4066)
		)
		(stroke
			(width 0)
			(type solid)
		)
		(fill yes)
		(layer "F.Cu")
		(net "M_A_CPU1_SA_DQ<26>")
	)
	(gr_poly
		(pts
			(xy 76.814172 -279.03043) (xy 76.764388 -279.020524) (xy 76.657708 -279.036272) (xy 76.62037 -279.222962)
			(xy 76.71308 -279.278334) (xy 76.762864 -279.28824)
		)
		(stroke
			(width 0)
			(type solid)
		)
		(fill yes)
		(layer "F.Cu")
		(net "M_A_CPU1_SA_DQ<25>")
	)
	(gr_poly
		(pts
			(xy 76.81849 -266.203176) (xy 76.772262 -266.10564) (xy 76.736194 -266.069826) (xy 76.550266 -266.255754)
			(xy 76.586334 -266.291568) (xy 76.683616 -266.337796)
		)
		(stroke
			(width 0)
			(type solid)
		)
		(fill yes)
		(layer "F.Cu")
		(net "M_A_CPU1_SA_CB<5>")
	)
	(gr_poly
		(pts
			(xy 76.827126 -273.070828) (xy 76.791058 -273.035014) (xy 76.693522 -272.988786) (xy 76.558902 -273.123406)
			(xy 76.60513 -273.220942) (xy 76.641198 -273.256756)
		)
		(stroke
			(width 0)
			(type solid)
		)
		(fill yes)
		(layer "F.Cu")
		(net "M_A_CPU1_SA_DQ<29>")
	)
	(gr_poly
		(pts
			(xy 76.827888 -267.05687) (xy 76.78166 -266.959334) (xy 76.745846 -266.923266) (xy 76.559918 -267.109194)
			(xy 76.595732 -267.145262) (xy 76.693268 -267.19149)
		)
		(stroke
			(width 0)
			(type solid)
		)
		(fill yes)
		(layer "F.Cu")
		(net "M_A_CPU1_SA_CB<4>")
	)
	(gr_poly
		(pts
			(xy 76.861162 -279.57526) (xy 76.898246 -279.388316) (xy 76.80579 -279.332944) (xy 76.756006 -279.323038)
			(xy 76.704698 -279.580848) (xy 76.754482 -279.590754)
		)
		(stroke
			(width 0)
			(type solid)
		)
		(fill yes)
		(layer "F.Cu")
		(net "M_A_CPU1_SA_DQ<25>")
	)
	(gr_poly
		(pts
			(xy 76.864464 -277.214584) (xy 76.81468 -277.204678) (xy 76.707746 -277.220426) (xy 76.670662 -277.407116)
			(xy 76.763372 -277.462488) (xy 76.813156 -277.472394)
		)
		(stroke
			(width 0)
			(type solid)
		)
		(fill yes)
		(layer "F.Cu")
		(net "M_A_CPU1_SA_DQ<27>")
	)
	(gr_poly
		(pts
			(xy 76.880466 -280.260806) (xy 76.830682 -280.2509) (xy 76.724002 -280.266394) (xy 76.686664 -280.453338)
			(xy 76.779374 -280.50871) (xy 76.829158 -280.518616)
		)
		(stroke
			(width 0)
			(type solid)
		)
		(fill yes)
		(layer "F.Cu")
		(net "M_A_CPU1_SA_DQ<26>")
	)
	(gr_poly
		(pts
			(xy 76.884784 -223.138746) (xy 76.884784 -222.948246) (xy 76.783184 -222.912178) (xy 76.732384 -222.912178)
			(xy 76.732384 -223.174814) (xy 76.783184 -223.174814)
		)
		(stroke
			(width 0)
			(type solid)
		)
		(fill yes)
		(layer "F.Cu")
		(net "M_A_CPU1_SB_DQ<16>")
	)
	(gr_poly
		(pts
			(xy 76.884784 -222.541846) (xy 76.884784 -222.351346) (xy 76.783184 -222.315278) (xy 76.732384 -222.315278)
			(xy 76.732384 -222.577914) (xy 76.783184 -222.577914)
		)
		(stroke
			(width 0)
			(type solid)
		)
		(fill yes)
		(layer "F.Cu")
		(net "M_A_CPU1_SB_DQ<16>")
	)
	(gr_poly
		(pts
			(xy 76.884784 -221.944946) (xy 76.884784 -221.754446) (xy 76.783184 -221.718378) (xy 76.732384 -221.718378)
			(xy 76.732384 -221.981014) (xy 76.783184 -221.981014)
		)
		(stroke
			(width 0)
			(type solid)
		)
		(fill yes)
		(layer "F.Cu")
		(net "M_A_CPU1_SB_DQ<16>")
	)
	(gr_poly
		(pts
			(xy 76.884784 -221.348046) (xy 76.884784 -221.157546) (xy 76.783184 -221.121478) (xy 76.732384 -221.121478)
			(xy 76.732384 -221.384114) (xy 76.783184 -221.384114)
		)
		(stroke
			(width 0)
			(type solid)
		)
		(fill yes)
		(layer "F.Cu")
		(net "M_A_CPU1_SB_DQ<16>")
	)
	(gr_poly
		(pts
			(xy 76.884784 -220.751146) (xy 76.884784 -220.560646) (xy 76.783184 -220.524578) (xy 76.732384 -220.524578)
			(xy 76.732384 -220.787214) (xy 76.783184 -220.787214)
		)
		(stroke
			(width 0)
			(type solid)
		)
		(fill yes)
		(layer "F.Cu")
		(net "M_A_CPU1_SB_DQ<16>")
	)
	(gr_poly
		(pts
			(xy 76.904342 -272.777458) (xy 76.858114 -272.680176) (xy 76.8223 -272.644108) (xy 76.636372 -272.830036)
			(xy 76.672186 -272.86585) (xy 76.769722 -272.912078)
		)
		(stroke
			(width 0)
			(type solid)
		)
		(fill yes)
		(layer "F.Cu")
		(net "M_A_CPU1_SA_DQ<31>")
	)
	(gr_poly
		(pts
			(xy 76.911454 -277.759414) (xy 76.948538 -277.57247) (xy 76.856082 -277.517352) (xy 76.806044 -277.507446)
			(xy 76.754736 -277.765256) (xy 76.804774 -277.775162)
		)
		(stroke
			(width 0)
			(type solid)
		)
		(fill yes)
		(layer "F.Cu")
		(net "M_A_CPU1_SA_DQ<27>")
	)
	(gr_poly
		(pts
			(xy 76.927202 -280.805636) (xy 76.964286 -280.618692) (xy 76.87183 -280.56332) (xy 76.822046 -280.553414)
			(xy 76.770738 -280.811224) (xy 76.820522 -280.82113)
		)
		(stroke
			(width 0)
			(type solid)
		)
		(fill yes)
		(layer "F.Cu")
		(net "M_A_CPU1_SA_DQ<26>")
	)
	(gr_poly
		(pts
			(xy 76.930758 -278.44496) (xy 76.88072 -278.435054) (xy 76.77404 -278.450802) (xy 76.736956 -278.637492)
			(xy 76.829412 -278.692864) (xy 76.87945 -278.70277)
		)
		(stroke
			(width 0)
			(type solid)
		)
		(fill yes)
		(layer "F.Cu")
		(net "M_A_CPU1_SA_DQ<25>")
	)
	(gr_poly
		(pts
			(xy 76.94676 -281.491182) (xy 76.896976 -281.481276) (xy 76.790042 -281.497024) (xy 76.752958 -281.683714)
			(xy 76.845668 -281.739086) (xy 76.895452 -281.748992)
		)
		(stroke
			(width 0)
			(type solid)
		)
		(fill yes)
		(layer "F.Cu")
		(net "M_A_CPU1_SA_DQ<24>")
	)
	(gr_poly
		(pts
			(xy 76.947268 -265.858752) (xy 76.911454 -265.822938) (xy 76.813918 -265.776456) (xy 76.679298 -265.91133)
			(xy 76.725526 -266.008612) (xy 76.76134 -266.04468)
		)
		(stroke
			(width 0)
			(type solid)
		)
		(fill yes)
		(layer "F.Cu")
		(net "M_A_CPU1_SA_CB<5>")
	)
	(gr_poly
		(pts
			(xy 76.956666 -266.712446) (xy 76.920852 -266.676378) (xy 76.823316 -266.63015) (xy 76.688696 -266.76477)
			(xy 76.734924 -266.862306) (xy 76.770992 -266.89812)
		)
		(stroke
			(width 0)
			(type solid)
		)
		(fill yes)
		(layer "F.Cu")
		(net "M_A_CPU1_SA_CB<4>")
	)
	(gr_poly
		(pts
			(xy 76.977494 -278.98979) (xy 77.014578 -278.802846) (xy 76.921868 -278.747728) (xy 76.872084 -278.737822)
			(xy 76.820776 -278.995632) (xy 76.87056 -279.005538)
		)
		(stroke
			(width 0)
			(type solid)
		)
		(fill yes)
		(layer "F.Cu")
		(net "M_A_CPU1_SA_DQ<25>")
	)
	(gr_poly
		(pts
			(xy 76.996798 -279.675336) (xy 76.94676 -279.66543) (xy 76.84008 -279.681178) (xy 76.802996 -279.867868)
			(xy 76.895452 -279.92324) (xy 76.94549 -279.933146)
		)
		(stroke
			(width 0)
			(type solid)
		)
		(fill yes)
		(layer "F.Cu")
		(net "M_A_CPU1_SA_DQ<26>")
	)
	(gr_poly
		(pts
			(xy 77.024738 -265.565382) (xy 76.97851 -265.467846) (xy 76.942442 -265.432032) (xy 76.756768 -265.617706)
			(xy 76.792582 -265.653774) (xy 76.890118 -265.700002)
		)
		(stroke
			(width 0)
			(type solid)
		)
		(fill yes)
		(layer "F.Cu")
		(net "M_A_CPU1_SA_CB<7>")
	)
	(gr_poly
		(pts
			(xy 77.033374 -272.433034) (xy 76.997306 -272.39722) (xy 76.900024 -272.350992) (xy 76.76515 -272.485612)
			(xy 76.811378 -272.583148) (xy 76.847446 -272.618962)
		)
		(stroke
			(width 0)
			(type solid)
		)
		(fill yes)
		(layer "F.Cu")
		(net "M_A_CPU1_SA_DQ<31>")
	)
	(gr_poly
		(pts
			(xy 77.034136 -266.418822) (xy 76.987908 -266.32154) (xy 76.952094 -266.285472) (xy 76.766166 -266.4714)
			(xy 76.80198 -266.507468) (xy 76.899516 -266.553696)
		)
		(stroke
			(width 0)
			(type solid)
		)
		(fill yes)
		(layer "F.Cu")
		(net "M_A_CPU1_SA_CB<6>")
	)
	(gr_poly
		(pts
			(xy 77.037184 -223.210374) (xy 76.986384 -223.210374) (xy 76.884784 -223.246696) (xy 76.884784 -223.437196)
			(xy 76.986384 -223.473518) (xy 77.037184 -223.473518)
		)
		(stroke
			(width 0)
			(type solid)
		)
		(fill yes)
		(layer "F.Cu")
		(net "M_A_CPU1_SB_DQ<18>")
	)
	(gr_poly
		(pts
			(xy 77.037184 -222.613474) (xy 76.986384 -222.613474) (xy 76.884784 -222.649796) (xy 76.884784 -222.840296)
			(xy 76.986384 -222.876618) (xy 77.037184 -222.876618)
		)
		(stroke
			(width 0)
			(type solid)
		)
		(fill yes)
		(layer "F.Cu")
		(net "M_A_CPU1_SB_DQ<18>")
	)
	(gr_poly
		(pts
			(xy 77.037184 -222.016574) (xy 76.986384 -222.016574) (xy 76.884784 -222.052896) (xy 76.884784 -222.243396)
			(xy 76.986384 -222.279718) (xy 77.037184 -222.279718)
		)
		(stroke
			(width 0)
			(type solid)
		)
		(fill yes)
		(layer "F.Cu")
		(net "M_A_CPU1_SB_DQ<18>")
	)
	(gr_poly
		(pts
			(xy 77.037184 -221.419674) (xy 76.986384 -221.419674) (xy 76.884784 -221.455996) (xy 76.884784 -221.646496)
			(xy 76.986384 -221.682818) (xy 77.037184 -221.682818)
		)
		(stroke
			(width 0)
			(type solid)
		)
		(fill yes)
		(layer "F.Cu")
		(net "M_A_CPU1_SB_DQ<18>")
	)
	(gr_poly
		(pts
			(xy 77.037184 -220.822774) (xy 76.986384 -220.822774) (xy 76.884784 -220.859096) (xy 76.884784 -221.049596)
			(xy 76.986384 -221.085918) (xy 77.037184 -221.085918)
		)
		(stroke
			(width 0)
			(type solid)
		)
		(fill yes)
		(layer "F.Cu")
		(net "M_A_CPU1_SB_DQ<18>")
	)
	(gr_poly
		(pts
			(xy 77.037184 -220.225874) (xy 76.986384 -220.225874) (xy 76.884784 -220.262196) (xy 76.884784 -220.452696)
			(xy 76.986384 -220.489018) (xy 77.037184 -220.489018)
		)
		(stroke
			(width 0)
			(type solid)
		)
		(fill yes)
		(layer "F.Cu")
		(net "M_A_CPU1_SB_DQ<18>")
	)
	(gr_poly
		(pts
			(xy 77.043026 -273.286982) (xy 77.007212 -273.251168) (xy 76.909676 -273.204686) (xy 76.775056 -273.33956)
			(xy 76.821284 -273.436842) (xy 76.857098 -273.47291)
		)
		(stroke
			(width 0)
			(type solid)
		)
		(fill yes)
		(layer "F.Cu")
		(net "M_A_CPU1_SA_DQ<30>")
	)
	(gr_poly
		(pts
			(xy 77.043788 -280.220166) (xy 77.080872 -280.033222) (xy 76.988162 -279.97785) (xy 76.938378 -279.967944)
			(xy 76.88707 -280.225754) (xy 76.936854 -280.23566)
		)
		(stroke
			(width 0)
			(type solid)
		)
		(fill yes)
		(layer "F.Cu")
		(net "M_A_CPU1_SA_DQ<26>")
	)
	(gr_poly
		(pts
			(xy 77.04709 -277.85949) (xy 76.997306 -277.849584) (xy 76.890626 -277.865332) (xy 76.853542 -278.052276)
			(xy 76.945998 -278.107394) (xy 76.995782 -278.1173)
		)
		(stroke
			(width 0)
			(type solid)
		)
		(fill yes)
		(layer "F.Cu")
		(net "M_A_CPU1_SA_DQ<25>")
	)
	(gr_poly
		(pts
			(xy 77.063092 -280.905712) (xy 77.013308 -280.895806) (xy 76.906628 -280.911554) (xy 76.869544 -281.098244)
			(xy 76.962 -281.153616) (xy 77.011784 -281.163522)
		)
		(stroke
			(width 0)
			(type solid)
		)
		(fill yes)
		(layer "F.Cu")
		(net "M_A_CPU1_SA_DQ<24>")
	)
	(gr_poly
		(pts
			(xy 77.093826 -278.40432) (xy 77.131164 -278.21763) (xy 77.038454 -278.162258) (xy 76.98867 -278.152352)
			(xy 76.937362 -278.410162) (xy 76.987146 -278.420068)
		)
		(stroke
			(width 0)
			(type solid)
		)
		(fill yes)
		(layer "F.Cu")
		(net "M_A_CPU1_SA_DQ<25>")
	)
	(gr_poly
		(pts
			(xy 77.110082 -281.450542) (xy 77.14742 -281.263598) (xy 77.05471 -281.20848) (xy 77.004926 -281.198574)
			(xy 76.953618 -281.456384) (xy 77.003402 -281.46629)
		)
		(stroke
			(width 0)
			(type solid)
		)
		(fill yes)
		(layer "F.Cu")
		(net "M_A_CPU1_SA_DQ<24>")
	)
	(gr_poly
		(pts
			(xy 77.113384 -279.089866) (xy 77.0636 -279.07996) (xy 76.95692 -279.095708) (xy 76.919582 -279.282398)
			(xy 77.012292 -279.33777) (xy 77.062076 -279.347676)
		)
		(stroke
			(width 0)
			(type solid)
		)
		(fill yes)
		(layer "F.Cu")
		(net "M_A_CPU1_SA_DQ<26>")
	)
	(gr_poly
		(pts
			(xy 77.120242 -272.993358) (xy 77.074014 -272.895822) (xy 77.037946 -272.860008) (xy 76.852272 -273.045682)
			(xy 76.888086 -273.08175) (xy 76.985622 -273.127978)
		)
		(stroke
			(width 0)
			(type solid)
		)
		(fill yes)
		(layer "F.Cu")
		(net "M_A_CPU1_SA_DQ<29>")
	)
	(gr_poly
		(pts
			(xy 77.134212 -276.62251) (xy 77.089254 -276.598634) (xy 76.982574 -276.582632) (xy 76.892912 -276.750526)
			(xy 76.965302 -276.830282) (xy 77.01026 -276.854412)
		)
		(stroke
			(width 0)
			(type solid)
		)
		(fill yes)
		(layer "F.Cu")
		(net "M_A_CPU1_SA_DQ<27>")
	)
	(gr_poly
		(pts
			(xy 77.153516 -265.220958) (xy 77.117702 -265.18489) (xy 77.020166 -265.138662) (xy 76.885546 -265.273536)
			(xy 76.931774 -265.370818) (xy 76.967588 -265.406886)
		)
		(stroke
			(width 0)
			(type solid)
		)
		(fill yes)
		(layer "F.Cu")
		(net "M_A_CPU1_SA_CB<7>")
	)
	(gr_poly
		(pts
			(xy 77.16012 -279.634696) (xy 77.197204 -279.447752) (xy 77.104748 -279.392634) (xy 77.054964 -279.382728)
			(xy 77.003656 -279.640538) (xy 77.05344 -279.650444)
		)
		(stroke
			(width 0)
			(type solid)
		)
		(fill yes)
		(layer "F.Cu")
		(net "M_A_CPU1_SA_DQ<26>")
	)
	(gr_poly
		(pts
			(xy 77.163168 -266.074398) (xy 77.1271 -266.038584) (xy 77.029818 -265.992356) (xy 76.894944 -266.126976)
			(xy 76.941172 -266.224512) (xy 76.97724 -266.260326)
		)
		(stroke
			(width 0)
			(type solid)
		)
		(fill yes)
		(layer "F.Cu")
		(net "M_A_CPU1_SA_CB<6>")
	)
	(gr_poly
		(pts
			(xy 77.177392 -269.511018) (xy 77.141578 -269.47495) (xy 77.044042 -269.428722) (xy 76.909422 -269.563596)
			(xy 76.95565 -269.660878) (xy 76.991464 -269.696946)
		)
		(stroke
			(width 0)
			(type solid)
		)
		(fill yes)
		(layer "F.Cu")
		(net "M_A_CPU1_SA_CB<2>")
	)
	(gr_poly
		(pts
			(xy 77.179678 -280.320242) (xy 77.129894 -280.310336) (xy 77.023214 -280.326084) (xy 76.985876 -280.513028)
			(xy 77.078586 -280.568146) (xy 77.12837 -280.578052)
		)
		(stroke
			(width 0)
			(type solid)
		)
		(fill yes)
		(layer "F.Cu")
		(net "M_A_CPU1_SA_DQ<24>")
	)
	(gr_poly
		(pts
			(xy 77.189584 -223.138746) (xy 77.189584 -222.948246) (xy 77.087984 -222.912178) (xy 77.037184 -222.912178)
			(xy 77.037184 -223.174814) (xy 77.087984 -223.174814)
		)
		(stroke
			(width 0)
			(type solid)
		)
		(fill yes)
		(layer "F.Cu")
		(net "M_A_CPU1_SB_DQ<18>")
	)
	(gr_poly
		(pts
			(xy 77.189584 -222.541846) (xy 77.189584 -222.351346) (xy 77.087984 -222.315278) (xy 77.037184 -222.315278)
			(xy 77.037184 -222.577914) (xy 77.087984 -222.577914)
		)
		(stroke
			(width 0)
			(type solid)
		)
		(fill yes)
		(layer "F.Cu")
		(net "M_A_CPU1_SB_DQ<18>")
	)
	(gr_poly
		(pts
			(xy 77.189584 -221.944946) (xy 77.189584 -221.754446) (xy 77.087984 -221.718378) (xy 77.037184 -221.718378)
			(xy 77.037184 -221.981014) (xy 77.087984 -221.981014)
		)
		(stroke
			(width 0)
			(type solid)
		)
		(fill yes)
		(layer "F.Cu")
		(net "M_A_CPU1_SB_DQ<18>")
	)
	(gr_poly
		(pts
			(xy 77.189584 -221.348046) (xy 77.189584 -221.157546) (xy 77.087984 -221.121478) (xy 77.037184 -221.121478)
			(xy 77.037184 -221.384114) (xy 77.087984 -221.384114)
		)
		(stroke
			(width 0)
			(type solid)
		)
		(fill yes)
		(layer "F.Cu")
		(net "M_A_CPU1_SB_DQ<18>")
	)
	(gr_poly
		(pts
			(xy 77.189584 -220.751146) (xy 77.189584 -220.560646) (xy 77.087984 -220.524578) (xy 77.037184 -220.524578)
			(xy 77.037184 -220.787214) (xy 77.087984 -220.787214)
		)
		(stroke
			(width 0)
			(type solid)
		)
		(fill yes)
		(layer "F.Cu")
		(net "M_A_CPU1_SB_DQ<18>")
	)
	(gr_poly
		(pts
			(xy 77.189584 -220.154246) (xy 77.189584 -219.963746) (xy 77.087984 -219.927678) (xy 77.037184 -219.927678)
			(xy 77.037184 -220.190314) (xy 77.087984 -220.190314)
		)
		(stroke
			(width 0)
			(type solid)
		)
		(fill yes)
		(layer "F.Cu")
		(net "M_A_CPU1_SB_DQ<18>")
	)
	(gr_poly
		(pts
			(xy 77.189584 -219.557346) (xy 77.189584 -219.366846) (xy 77.087984 -219.330778) (xy 77.037184 -219.330778)
			(xy 77.037184 -219.593414) (xy 77.087984 -219.593414)
		)
		(stroke
			(width 0)
			(type solid)
		)
		(fill yes)
		(layer "F.Cu")
		(net "M_A_CPU1_SB_DQ<18>")
	)
	(gr_poly
		(pts
			(xy 77.210666 -277.81885) (xy 77.24775 -277.63216) (xy 77.155294 -277.576788) (xy 77.10551 -277.566882)
			(xy 77.054202 -277.824692) (xy 77.103986 -277.834598)
		)
		(stroke
			(width 0)
			(type solid)
		)
		(fill yes)
		(layer "F.Cu")
		(net "M_A_CPU1_SA_DQ<25>")
	)
	(gr_poly
		(pts
			(xy 77.226668 -280.865072) (xy 77.263752 -280.678382) (xy 77.171296 -280.62301) (xy 77.121512 -280.613104)
			(xy 77.070204 -280.870914) (xy 77.119988 -280.88082)
		)
		(stroke
			(width 0)
			(type solid)
		)
		(fill yes)
		(layer "F.Cu")
		(net "M_A_CPU1_SA_DQ<24>")
	)
	(gr_poly
		(pts
			(xy 77.22997 -278.504396) (xy 77.180186 -278.49449) (xy 77.073252 -278.510238) (xy 77.036168 -278.697182)
			(xy 77.128878 -278.7523) (xy 77.178662 -278.762206)
		)
		(stroke
			(width 0)
			(type solid)
		)
		(fill yes)
		(layer "F.Cu")
		(net "M_A_CPU1_SA_DQ<26>")
	)
	(gr_poly
		(pts
			(xy 77.240384 -265.781028) (xy 77.194156 -265.683492) (xy 77.158342 -265.647678) (xy 76.972414 -265.833606)
			(xy 77.008228 -265.86942) (xy 77.105764 -265.915648)
		)
		(stroke
			(width 0)
			(type solid)
		)
		(fill yes)
		(layer "F.Cu")
		(net "M_A_CPU1_SA_CB<5>")
	)
	(gr_poly
		(pts
			(xy 77.241908 -224.3201) (xy 77.288136 -224.222564) (xy 77.153262 -224.087944) (xy 77.05598 -224.134172)
			(xy 77.019912 -224.169986) (xy 77.20584 -224.355914)
		)
		(stroke
			(width 0)
			(type solid)
		)
		(fill yes)
		(layer "F.Cu")
		(net "M_A_CPU1_SB_DQ<16>")
	)
	(gr_poly
		(pts
			(xy 77.24902 -272.648934) (xy 77.213206 -272.612866) (xy 77.11567 -272.566638) (xy 76.98105 -272.701512)
			(xy 77.027278 -272.798794) (xy 77.063092 -272.834862)
		)
		(stroke
			(width 0)
			(type solid)
		)
		(fill yes)
		(layer "F.Cu")
		(net "M_A_CPU1_SA_DQ<29>")
	)
	(gr_poly
		(pts
			(xy 77.250036 -266.634722) (xy 77.203808 -266.537186) (xy 77.16774 -266.501372) (xy 76.981812 -266.6873)
			(xy 77.01788 -266.723114) (xy 77.115162 -266.769342)
		)
		(stroke
			(width 0)
			(type solid)
		)
		(fill yes)
		(layer "F.Cu")
		(net "M_A_CPU1_SA_CB<4>")
	)
	(gr_poly
		(pts
			(xy 77.254862 -269.217394) (xy 77.208634 -269.120112) (xy 77.17282 -269.084044) (xy 76.986892 -269.269972)
			(xy 77.022706 -269.30604) (xy 77.120242 -269.352268)
		)
		(stroke
			(width 0)
			(type solid)
		)
		(fill yes)
		(layer "F.Cu")
		(net "M_A_CPU1_SA_CB<1>")
	)
	(gr_poly
		(pts
			(xy 77.258672 -273.502628) (xy 77.222858 -273.466814) (xy 77.125322 -273.420332) (xy 76.990702 -273.555206)
			(xy 77.03693 -273.652488) (xy 77.072744 -273.688556)
		)
		(stroke
			(width 0)
			(type solid)
		)
		(fill yes)
		(layer "F.Cu")
		(net "M_A_CPU1_SA_DQ<28>")
	)
	(gr_poly
		(pts
			(xy 77.276706 -279.049226) (xy 77.31379 -278.862536) (xy 77.221334 -278.807164) (xy 77.171296 -278.797258)
			(xy 77.119988 -279.055068) (xy 77.170026 -279.064974)
		)
		(stroke
			(width 0)
			(type solid)
		)
		(fill yes)
		(layer "F.Cu")
		(net "M_A_CPU1_SA_DQ<26>")
	)
	(gr_poly
		(pts
			(xy 77.29601 -279.734772) (xy 77.246226 -279.724866) (xy 77.139546 -279.740614) (xy 77.102462 -279.927558)
			(xy 77.194918 -279.98293) (xy 77.244702 -279.992836)
		)
		(stroke
			(width 0)
			(type solid)
		)
		(fill yes)
		(layer "F.Cu")
		(net "M_A_CPU1_SA_DQ<24>")
	)
	(gr_poly
		(pts
			(xy 77.32649 -272.35531) (xy 77.280262 -272.258028) (xy 77.244448 -272.22196) (xy 77.05852 -272.407888)
			(xy 77.094334 -272.443956) (xy 77.19187 -272.490184)
		)
		(stroke
			(width 0)
			(type solid)
		)
		(fill yes)
		(layer "F.Cu")
		(net "M_A_CPU1_SA_DQ<31>")
	)
	(gr_poly
		(pts
			(xy 77.336142 -273.209258) (xy 77.289914 -273.111976) (xy 77.2541 -273.075908) (xy 77.068172 -273.261836)
			(xy 77.103986 -273.29765) (xy 77.201522 -273.343878)
		)
		(stroke
			(width 0)
			(type solid)
		)
		(fill yes)
		(layer "F.Cu")
		(net "M_A_CPU1_SA_DQ<30>")
	)
	(gr_poly
		(pts
			(xy 77.341984 -223.210374) (xy 77.291184 -223.210374) (xy 77.189584 -223.246696) (xy 77.189584 -223.437196)
			(xy 77.291184 -223.473518) (xy 77.341984 -223.473518)
		)
		(stroke
			(width 0)
			(type solid)
		)
		(fill yes)
		(layer "F.Cu")
		(net "M_A_CPU1_SB_DQ<17>")
	)
	(gr_poly
		(pts
			(xy 77.341984 -222.613474) (xy 77.291184 -222.613474) (xy 77.189584 -222.649796) (xy 77.189584 -222.840296)
			(xy 77.291184 -222.876618) (xy 77.341984 -222.876618)
		)
		(stroke
			(width 0)
			(type solid)
		)
		(fill yes)
		(layer "F.Cu")
		(net "M_A_CPU1_SB_DQ<17>")
	)
	(gr_poly
		(pts
			(xy 77.341984 -222.016574) (xy 77.291184 -222.016574) (xy 77.189584 -222.052896) (xy 77.189584 -222.243396)
			(xy 77.291184 -222.279718) (xy 77.341984 -222.279718)
		)
		(stroke
			(width 0)
			(type solid)
		)
		(fill yes)
		(layer "F.Cu")
		(net "M_A_CPU1_SB_DQ<17>")
	)
	(gr_poly
		(pts
			(xy 77.341984 -221.419674) (xy 77.291184 -221.419674) (xy 77.189584 -221.455996) (xy 77.189584 -221.646496)
			(xy 77.291184 -221.682818) (xy 77.341984 -221.682818)
		)
		(stroke
			(width 0)
			(type solid)
		)
		(fill yes)
		(layer "F.Cu")
		(net "M_A_CPU1_SB_DQ<17>")
	)
	(gr_poly
		(pts
			(xy 77.341984 -220.822774) (xy 77.291184 -220.822774) (xy 77.189584 -220.859096) (xy 77.189584 -221.049596)
			(xy 77.291184 -221.085918) (xy 77.341984 -221.085918)
		)
		(stroke
			(width 0)
			(type solid)
		)
		(fill yes)
		(layer "F.Cu")
		(net "M_A_CPU1_SB_DQ<17>")
	)
	(gr_poly
		(pts
			(xy 77.341984 -220.225874) (xy 77.291184 -220.225874) (xy 77.189584 -220.262196) (xy 77.189584 -220.452696)
			(xy 77.291184 -220.489018) (xy 77.341984 -220.489018)
		)
		(stroke
			(width 0)
			(type solid)
		)
		(fill yes)
		(layer "F.Cu")
		(net "M_A_CPU1_SB_DQ<17>")
	)
	(gr_poly
		(pts
			(xy 77.341984 -219.628974) (xy 77.291184 -219.628974) (xy 77.189584 -219.665296) (xy 77.189584 -219.855796)
			(xy 77.291184 -219.892118) (xy 77.341984 -219.892118)
		)
		(stroke
			(width 0)
			(type solid)
		)
		(fill yes)
		(layer "F.Cu")
		(net "M_A_CPU1_SB_DQ<17>")
	)
	(gr_poly
		(pts
			(xy 77.343 -280.279602) (xy 77.380338 -280.092912) (xy 77.287628 -280.03754) (xy 77.237844 -280.027634)
			(xy 77.186536 -280.285444) (xy 77.23632 -280.29535)
		)
		(stroke
			(width 0)
			(type solid)
		)
		(fill yes)
		(layer "F.Cu")
		(net "M_A_CPU1_SA_DQ<24>")
	)
	(gr_poly
		(pts
			(xy 77.346048 -277.918926) (xy 77.296264 -277.90902) (xy 77.189584 -277.924768) (xy 77.1525 -278.111712)
			(xy 77.244956 -278.167084) (xy 77.29474 -278.17699)
		)
		(stroke
			(width 0)
			(type solid)
		)
		(fill yes)
		(layer "F.Cu")
		(net "M_A_CPU1_SA_DQ<26>")
	)
	(gr_poly
		(pts
			(xy 77.369416 -265.436604) (xy 77.333348 -265.40079) (xy 77.236066 -265.354562) (xy 77.101192 -265.489182)
			(xy 77.14742 -265.586718) (xy 77.183488 -265.622532)
		)
		(stroke
			(width 0)
			(type solid)
		)
		(fill yes)
		(layer "F.Cu")
		(net "M_A_CPU1_SA_CB<5>")
	)
	(gr_poly
		(pts
			(xy 77.378814 -266.290298) (xy 77.343 -266.254484) (xy 77.245464 -266.208002) (xy 77.110844 -266.342876)
			(xy 77.157072 -266.440158) (xy 77.192886 -266.476226)
		)
		(stroke
			(width 0)
			(type solid)
		)
		(fill yes)
		(layer "F.Cu")
		(net "M_A_CPU1_SA_CB<4>")
	)
	(gr_poly
		(pts
			(xy 77.3811 -224.602802) (xy 77.416914 -224.566988) (xy 77.230986 -224.38106) (xy 77.195172 -224.417128)
			(xy 77.148944 -224.51441) (xy 77.283564 -224.649284)
		)
		(stroke
			(width 0)
			(type solid)
		)
		(fill yes)
		(layer "F.Cu")
		(net "M_A_CPU1_SB_DQ<16>")
	)
	(gr_poly
		(pts
			(xy 77.38364 -268.873224) (xy 77.347826 -268.837156) (xy 77.25029 -268.790928) (xy 77.11567 -268.925548)
			(xy 77.161898 -269.023084) (xy 77.197966 -269.058898)
		)
		(stroke
			(width 0)
			(type solid)
		)
		(fill yes)
		(layer "F.Cu")
		(net "M_A_CPU1_SA_CB<1>")
	)
	(gr_poly
		(pts
			(xy 77.392276 -276.462998) (xy 77.319632 -276.383242) (xy 77.274928 -276.359366) (xy 77.150976 -276.591014)
			(xy 77.19568 -276.615144) (xy 77.30236 -276.631146)
		)
		(stroke
			(width 0)
			(type solid)
		)
		(fill yes)
		(layer "F.Cu")
		(net "M_A_CPU1_SA_DQ<27>")
	)
	(gr_poly
		(pts
			(xy 77.393038 -278.463756) (xy 77.430376 -278.277066) (xy 77.337666 -278.221694) (xy 77.287882 -278.211788)
			(xy 77.236574 -278.469598) (xy 77.286358 -278.479504)
		)
		(stroke
			(width 0)
			(type solid)
		)
		(fill yes)
		(layer "F.Cu")
		(net "M_A_CPU1_SA_DQ<26>")
	)
	(gr_poly
		(pts
			(xy 77.393038 -269.726664) (xy 77.357224 -269.690596) (xy 77.259688 -269.644368) (xy 77.125068 -269.779242)
			(xy 77.171296 -269.876524) (xy 77.20711 -269.912592)
		)
		(stroke
			(width 0)
			(type solid)
		)
		(fill yes)
		(layer "F.Cu")
		(net "M_A_CPU1_SA_CB<0>")
	)
	(gr_poly
		(pts
			(xy 77.403198 -276.766274) (xy 77.358494 -276.742398) (xy 77.251814 -276.726396) (xy 77.162152 -276.89429)
			(xy 77.234542 -276.9743) (xy 77.2795 -276.998176)
		)
		(stroke
			(width 0)
			(type solid)
		)
		(fill yes)
		(layer "F.Cu")
		(net "M_A_CPU1_SA_DQ<25>")
	)
	(gr_poly
		(pts
			(xy 77.412596 -279.149556) (xy 77.362812 -279.13965) (xy 77.256132 -279.155144) (xy 77.218794 -279.342088)
			(xy 77.311504 -279.39746) (xy 77.361288 -279.407366)
		)
		(stroke
			(width 0)
			(type solid)
		)
		(fill yes)
		(layer "F.Cu")
		(net "M_A_CPU1_SA_DQ<24>")
	)
	(gr_poly
		(pts
			(xy 77.415644 -276.095968) (xy 77.370686 -276.072092) (xy 77.264006 -276.05609) (xy 77.174344 -276.224238)
			(xy 77.246734 -276.303994) (xy 77.291692 -276.32787)
		)
		(stroke
			(width 0)
			(type solid)
		)
		(fill yes)
		(layer "F.Cu")
		(net "M_A_CPU1_SA_DQ<27>")
	)
	(gr_poly
		(pts
			(xy 77.446886 -265.143234) (xy 77.400658 -265.045698) (xy 77.36459 -265.009884) (xy 77.178662 -265.195812)
			(xy 77.21473 -265.231626) (xy 77.312012 -265.277854)
		)
		(stroke
			(width 0)
			(type solid)
		)
		(fill yes)
		(layer "F.Cu")
		(net "M_A_CPU1_SA_CB<7>")
	)
	(gr_poly
		(pts
			(xy 77.455268 -272.01114) (xy 77.419454 -271.975072) (xy 77.321918 -271.928844) (xy 77.187298 -272.063464)
			(xy 77.233526 -272.161) (xy 77.269594 -272.196814)
		)
		(stroke
			(width 0)
			(type solid)
		)
		(fill yes)
		(layer "F.Cu")
		(net "M_A_CPU1_SA_DQ<31>")
	)
	(gr_poly
		(pts
			(xy 77.456284 -265.996928) (xy 77.410056 -265.899392) (xy 77.373988 -265.863578) (xy 77.188314 -266.049252)
			(xy 77.224128 -266.08532) (xy 77.321664 -266.131548)
		)
		(stroke
			(width 0)
			(type solid)
		)
		(fill yes)
		(layer "F.Cu")
		(net "M_A_CPU1_SA_CB<6>")
	)
	(gr_poly
		(pts
			(xy 77.457554 -224.104454) (xy 77.503782 -224.006918) (xy 77.368908 -223.872298) (xy 77.271626 -223.918526)
			(xy 77.235558 -223.95434) (xy 77.421486 -224.140268)
		)
		(stroke
			(width 0)
			(type solid)
		)
		(fill yes)
		(layer "F.Cu")
		(net "M_A_CPU1_SB_DQ<18>")
	)
	(gr_poly
		(pts
			(xy 77.459586 -279.694386) (xy 77.49667 -279.507442) (xy 77.404214 -279.45207) (xy 77.35443 -279.442164)
			(xy 77.303122 -279.699974) (xy 77.352906 -279.70988)
		)
		(stroke
			(width 0)
			(type solid)
		)
		(fill yes)
		(layer "F.Cu")
		(net "M_A_CPU1_SA_DQ<24>")
	)
	(gr_poly
		(pts
			(xy 77.461364 -268.579854) (xy 77.415136 -268.482318) (xy 77.379068 -268.446504) (xy 77.19314 -268.632432)
			(xy 77.229208 -268.668246) (xy 77.32649 -268.714474)
		)
		(stroke
			(width 0)
			(type solid)
		)
		(fill yes)
		(layer "F.Cu")
		(net "M_A_CPU1_SA_CB<3>")
	)
	(gr_poly
		(pts
			(xy 77.465174 -272.864834) (xy 77.429106 -272.82902) (xy 77.331824 -272.782792) (xy 77.19695 -272.917412)
			(xy 77.243178 -273.014948) (xy 77.279246 -273.050762)
		)
		(stroke
			(width 0)
			(type solid)
		)
		(fill yes)
		(layer "F.Cu")
		(net "M_A_CPU1_SA_DQ<30>")
	)
	(gr_poly
		(pts
			(xy 77.46619 -246.323612) (xy 77.46619 -246.272812) (xy 77.2033 -246.272812) (xy 77.2033 -246.323612)
			(xy 77.239368 -246.425212) (xy 77.429868 -246.425212)
		)
		(stroke
			(width 0)
			(type solid)
		)
		(fill yes)
		(layer "F.Cu")
		(net "M_A_CPU1_SB_CS_N<3>")
	)
	(gr_poly
		(pts
			(xy 77.46619 -246.018812) (xy 77.46619 -245.968012) (xy 77.2033 -245.968012) (xy 77.2033 -246.018812)
			(xy 77.239368 -246.120412) (xy 77.429868 -246.120412)
		)
		(stroke
			(width 0)
			(type solid)
		)
		(fill yes)
		(layer "F.Cu")
		(net "M_A_CPU1_SB_CS_N<1>")
	)
	(gr_poly
		(pts
			(xy 77.470762 -269.433294) (xy 77.42428 -269.335758) (xy 77.388466 -269.299944) (xy 77.202538 -269.485872)
			(xy 77.238606 -269.521686) (xy 77.335888 -269.567914)
		)
		(stroke
			(width 0)
			(type solid)
		)
		(fill yes)
		(layer "F.Cu")
		(net "M_A_CPU1_SA_CB<2>")
	)
	(gr_poly
		(pts
			(xy 77.494384 -223.138746) (xy 77.494384 -222.948246) (xy 77.392784 -222.912178) (xy 77.341984 -222.912178)
			(xy 77.341984 -223.174814) (xy 77.392784 -223.174814)
		)
		(stroke
			(width 0)
			(type solid)
		)
		(fill yes)
		(layer "F.Cu")
		(net "M_A_CPU1_SB_DQ<17>")
	)
	(gr_poly
		(pts
			(xy 77.494384 -222.541846) (xy 77.494384 -222.351346) (xy 77.392784 -222.315278) (xy 77.341984 -222.315278)
			(xy 77.341984 -222.577914) (xy 77.392784 -222.577914)
		)
		(stroke
			(width 0)
			(type solid)
		)
		(fill yes)
		(layer "F.Cu")
		(net "M_A_CPU1_SB_DQ<17>")
	)
	(gr_poly
		(pts
			(xy 77.494384 -221.944946) (xy 77.494384 -221.754446) (xy 77.392784 -221.718378) (xy 77.341984 -221.718378)
			(xy 77.341984 -221.981014) (xy 77.392784 -221.981014)
		)
		(stroke
			(width 0)
			(type solid)
		)
		(fill yes)
		(layer "F.Cu")
		(net "M_A_CPU1_SB_DQ<17>")
	)
	(gr_poly
		(pts
			(xy 77.494384 -221.348046) (xy 77.494384 -221.157546) (xy 77.392784 -221.121478) (xy 77.341984 -221.121478)
			(xy 77.341984 -221.384114) (xy 77.392784 -221.384114)
		)
		(stroke
			(width 0)
			(type solid)
		)
		(fill yes)
		(layer "F.Cu")
		(net "M_A_CPU1_SB_DQ<17>")
	)
	(gr_poly
		(pts
			(xy 77.494384 -220.751146) (xy 77.494384 -220.560646) (xy 77.392784 -220.524578) (xy 77.341984 -220.524578)
			(xy 77.341984 -220.787214) (xy 77.392784 -220.787214)
		)
		(stroke
			(width 0)
			(type solid)
		)
		(fill yes)
		(layer "F.Cu")
		(net "M_A_CPU1_SB_DQ<17>")
	)
	(gr_poly
		(pts
			(xy 77.494384 -220.154246) (xy 77.494384 -219.963746) (xy 77.392784 -219.927678) (xy 77.341984 -219.927678)
			(xy 77.341984 -220.190314) (xy 77.392784 -220.190314)
		)
		(stroke
			(width 0)
			(type solid)
		)
		(fill yes)
		(layer "F.Cu")
		(net "M_A_CPU1_SB_DQ<17>")
	)
	(gr_poly
		(pts
			(xy 77.494384 -219.557346) (xy 77.494384 -219.366846) (xy 77.392784 -219.330778) (xy 77.341984 -219.330778)
			(xy 77.341984 -219.593414) (xy 77.392784 -219.593414)
		)
		(stroke
			(width 0)
			(type solid)
		)
		(fill yes)
		(layer "F.Cu")
		(net "M_A_CPU1_SB_DQ<17>")
	)
	(gr_poly
		(pts
			(xy 77.509624 -277.87854) (xy 77.546708 -277.691596) (xy 77.454252 -277.636224) (xy 77.404468 -277.626318)
			(xy 77.35316 -277.884128) (xy 77.402944 -277.894034)
		)
		(stroke
			(width 0)
			(type solid)
		)
		(fill yes)
		(layer "F.Cu")
		(net "M_A_CPU1_SA_DQ<26>")
	)
	(gr_poly
		(pts
			(xy 77.528928 -278.564086) (xy 77.479144 -278.55418) (xy 77.372464 -278.569928) (xy 77.33538 -278.756618)
			(xy 77.427836 -278.81199) (xy 77.477874 -278.821896)
		)
		(stroke
			(width 0)
			(type solid)
		)
		(fill yes)
		(layer "F.Cu")
		(net "M_A_CPU1_SA_DQ<24>")
	)
	(gr_poly
		(pts
			(xy 77.54239 -272.57121) (xy 77.495908 -272.473674) (xy 77.460094 -272.43786) (xy 77.274166 -272.623788)
			(xy 77.310234 -272.659602) (xy 77.407516 -272.70583)
		)
		(stroke
			(width 0)
			(type solid)
		)
		(fill yes)
		(layer "F.Cu")
		(net "M_A_CPU1_SA_DQ<29>")
	)
	(gr_poly
		(pts
			(xy 77.551788 -273.424904) (xy 77.50556 -273.327622) (xy 77.469746 -273.291554) (xy 77.283818 -273.477482)
			(xy 77.319632 -273.513296) (xy 77.417168 -273.559524)
		)
		(stroke
			(width 0)
			(type solid)
		)
		(fill yes)
		(layer "F.Cu")
		(net "M_A_CPU1_SA_DQ<28>")
	)
	(gr_poly
		(pts
			(xy 77.575664 -264.79881) (xy 77.53985 -264.762996) (xy 77.442314 -264.716768) (xy 77.307694 -264.851388)
			(xy 77.353922 -264.94867) (xy 77.389736 -264.984738)
		)
		(stroke
			(width 0)
			(type solid)
		)
		(fill yes)
		(layer "F.Cu")
		(net "M_A_CPU1_SA_CB<7>")
	)
	(gr_poly
		(pts
			(xy 77.576172 -279.108916) (xy 77.613256 -278.921972) (xy 77.520546 -278.8666) (xy 77.470762 -278.856694)
			(xy 77.419454 -279.114504) (xy 77.469238 -279.12441)
		)
		(stroke
			(width 0)
			(type solid)
		)
		(fill yes)
		(layer "F.Cu")
		(net "M_A_CPU1_SA_DQ<24>")
	)
	(gr_poly
		(pts
			(xy 77.578712 -284.600904) (xy 77.527912 -284.600904) (xy 77.426312 -284.637226) (xy 77.426312 -284.827726)
			(xy 77.527912 -284.863794) (xy 77.578712 -284.863794)
		)
		(stroke
			(width 0)
			(type solid)
		)
		(fill yes)
		(layer "F.Cu")
		(net "M_A_CPU1_SA_DQ<23>")
	)
	(gr_poly
		(pts
			(xy 77.578712 -284.004004) (xy 77.527912 -284.004004) (xy 77.426312 -284.040326) (xy 77.426312 -284.230826)
			(xy 77.527912 -284.266894) (xy 77.578712 -284.266894)
		)
		(stroke
			(width 0)
			(type solid)
		)
		(fill yes)
		(layer "F.Cu")
		(net "M_A_CPU1_SA_DQ<23>")
	)
	(gr_poly
		(pts
			(xy 77.578712 -283.407104) (xy 77.527912 -283.407104) (xy 77.426312 -283.443426) (xy 77.426312 -283.633926)
			(xy 77.527912 -283.669994) (xy 77.578712 -283.669994)
		)
		(stroke
			(width 0)
			(type solid)
		)
		(fill yes)
		(layer "F.Cu")
		(net "M_A_CPU1_SA_DQ<23>")
	)
	(gr_poly
		(pts
			(xy 77.578712 -282.810204) (xy 77.527912 -282.810204) (xy 77.426312 -282.846526) (xy 77.426312 -283.037026)
			(xy 77.527912 -283.073094) (xy 77.578712 -283.073094)
		)
		(stroke
			(width 0)
			(type solid)
		)
		(fill yes)
		(layer "F.Cu")
		(net "M_A_CPU1_SA_DQ<23>")
	)
	(gr_poly
		(pts
			(xy 77.578712 -282.213304) (xy 77.527912 -282.213304) (xy 77.426312 -282.249626) (xy 77.426312 -282.440126)
			(xy 77.527912 -282.476194) (xy 77.578712 -282.476194)
		)
		(stroke
			(width 0)
			(type solid)
		)
		(fill yes)
		(layer "F.Cu")
		(net "M_A_CPU1_SA_DQ<23>")
	)
	(gr_poly
		(pts
			(xy 77.578712 -281.616404) (xy 77.527912 -281.616404) (xy 77.426312 -281.652726) (xy 77.426312 -281.843226)
			(xy 77.527912 -281.879294) (xy 77.578712 -281.879294)
		)
		(stroke
			(width 0)
			(type solid)
		)
		(fill yes)
		(layer "F.Cu")
		(net "M_A_CPU1_SA_DQ<23>")
	)
	(gr_poly
		(pts
			(xy 77.585062 -265.652504) (xy 77.549248 -265.616436) (xy 77.451712 -265.570208) (xy 77.317092 -265.705082)
			(xy 77.36332 -265.802364) (xy 77.399134 -265.838432)
		)
		(stroke
			(width 0)
			(type solid)
		)
		(fill yes)
		(layer "F.Cu")
		(net "M_A_CPU1_SA_CB<6>")
	)
	(gr_poly
		(pts
			(xy 77.590142 -268.23543) (xy 77.554328 -268.199362) (xy 77.456792 -268.153134) (xy 77.322172 -268.288008)
			(xy 77.3684 -268.38529) (xy 77.404214 -268.421358)
		)
		(stroke
			(width 0)
			(type solid)
		)
		(fill yes)
		(layer "F.Cu")
		(net "M_A_CPU1_SA_CB<3>")
	)
	(gr_poly
		(pts
			(xy 77.596746 -224.387156) (xy 77.63256 -224.351342) (xy 77.446632 -224.165414) (xy 77.410818 -224.201482)
			(xy 77.36459 -224.298764) (xy 77.49921 -224.433638)
		)
		(stroke
			(width 0)
			(type solid)
		)
		(fill yes)
		(layer "F.Cu")
		(net "M_A_CPU1_SB_DQ<18>")
	)
	(gr_poly
		(pts
			(xy 77.59954 -269.08887) (xy 77.563726 -269.053056) (xy 77.46619 -269.006828) (xy 77.33157 -269.141448)
			(xy 77.377798 -269.238984) (xy 77.413612 -269.274798)
		)
		(stroke
			(width 0)
			(type solid)
		)
		(fill yes)
		(layer "F.Cu")
		(net "M_A_CPU1_SA_CB<2>")
	)
	(gr_poly
		(pts
			(xy 77.645514 -277.978616) (xy 77.59573 -277.96871) (xy 77.48905 -277.984458) (xy 77.451712 -278.171148)
			(xy 77.544422 -278.22652) (xy 77.594206 -278.236426)
		)
		(stroke
			(width 0)
			(type solid)
		)
		(fill yes)
		(layer "F.Cu")
		(net "M_A_CPU1_SA_DQ<24>")
	)
	(gr_poly
		(pts
			(xy 77.646784 -222.613474) (xy 77.595984 -222.613474) (xy 77.494384 -222.649796) (xy 77.494384 -222.840296)
			(xy 77.595984 -222.876618) (xy 77.646784 -222.876618)
		)
		(stroke
			(width 0)
			(type solid)
		)
		(fill yes)
		(layer "F.Cu")
		(net "M_A_CPU1_SB_DQ<19>")
	)
	(gr_poly
		(pts
			(xy 77.646784 -222.016574) (xy 77.595984 -222.016574) (xy 77.494384 -222.052896) (xy 77.494384 -222.243396)
			(xy 77.595984 -222.279718) (xy 77.646784 -222.279718)
		)
		(stroke
			(width 0)
			(type solid)
		)
		(fill yes)
		(layer "F.Cu")
		(net "M_A_CPU1_SB_DQ<19>")
	)
	(gr_poly
		(pts
			(xy 77.646784 -221.419674) (xy 77.595984 -221.419674) (xy 77.494384 -221.455996) (xy 77.494384 -221.646496)
			(xy 77.595984 -221.682818) (xy 77.646784 -221.682818)
		)
		(stroke
			(width 0)
			(type solid)
		)
		(fill yes)
		(layer "F.Cu")
		(net "M_A_CPU1_SB_DQ<19>")
	)
	(gr_poly
		(pts
			(xy 77.646784 -220.822774) (xy 77.595984 -220.822774) (xy 77.494384 -220.859096) (xy 77.494384 -221.049596)
			(xy 77.595984 -221.085918) (xy 77.646784 -221.085918)
		)
		(stroke
			(width 0)
			(type solid)
		)
		(fill yes)
		(layer "F.Cu")
		(net "M_A_CPU1_SB_DQ<19>")
	)
	(gr_poly
		(pts
			(xy 77.646784 -220.225874) (xy 77.595984 -220.225874) (xy 77.494384 -220.262196) (xy 77.494384 -220.452696)
			(xy 77.595984 -220.489018) (xy 77.646784 -220.489018)
		)
		(stroke
			(width 0)
			(type solid)
		)
		(fill yes)
		(layer "F.Cu")
		(net "M_A_CPU1_SB_DQ<19>")
	)
	(gr_poly
		(pts
			(xy 77.646784 -219.628974) (xy 77.595984 -219.628974) (xy 77.494384 -219.665296) (xy 77.494384 -219.855796)
			(xy 77.595984 -219.892118) (xy 77.646784 -219.892118)
		)
		(stroke
			(width 0)
			(type solid)
		)
		(fill yes)
		(layer "F.Cu")
		(net "M_A_CPU1_SB_DQ<19>")
	)
	(gr_poly
		(pts
			(xy 77.646784 -219.032074) (xy 77.595984 -219.032074) (xy 77.494384 -219.068396) (xy 77.494384 -219.258896)
			(xy 77.595984 -219.295218) (xy 77.646784 -219.295218)
		)
		(stroke
			(width 0)
			(type solid)
		)
		(fill yes)
		(layer "F.Cu")
		(net "M_A_CPU1_SB_DQ<19>")
	)
	(gr_poly
		(pts
			(xy 77.646784 -218.435174) (xy 77.595984 -218.435174) (xy 77.494384 -218.471496) (xy 77.494384 -218.661996)
			(xy 77.595984 -218.698318) (xy 77.646784 -218.698318)
		)
		(stroke
			(width 0)
			(type solid)
		)
		(fill yes)
		(layer "F.Cu")
		(net "M_A_CPU1_SB_DQ<19>")
	)
	(gr_poly
		(pts
			(xy 77.661262 -276.606762) (xy 77.588872 -276.527006) (xy 77.543914 -276.50313) (xy 77.419962 -276.735032)
			(xy 77.46492 -276.758908) (xy 77.5716 -276.77491)
		)
		(stroke
			(width 0)
			(type solid)
		)
		(fill yes)
		(layer "F.Cu")
		(net "M_A_CPU1_SA_DQ<25>")
	)
	(gr_poly
		(pts
			(xy 77.662532 -265.35888) (xy 77.616304 -265.261598) (xy 77.58049 -265.22553) (xy 77.394562 -265.411458)
			(xy 77.430376 -265.447526) (xy 77.527912 -265.493754)
		)
		(stroke
			(width 0)
			(type solid)
		)
		(fill yes)
		(layer "F.Cu")
		(net "M_A_CPU1_SA_CB<5>")
	)
	(gr_poly
		(pts
			(xy 77.663802 -224.742248) (xy 77.71003 -224.644712) (xy 77.57541 -224.510092) (xy 77.477874 -224.55632)
			(xy 77.44206 -224.592134) (xy 77.627988 -224.778062)
		)
		(stroke
			(width 0)
			(type solid)
		)
		(fill yes)
		(layer "F.Cu")
		(net "M_A_CPU1_SB_DQ<16>")
	)
	(gr_poly
		(pts
			(xy 77.671168 -272.226786) (xy 77.635354 -272.190972) (xy 77.537818 -272.144744) (xy 77.403198 -272.279364)
			(xy 77.449426 -272.3769) (xy 77.48524 -272.412714)
		)
		(stroke
			(width 0)
			(type solid)
		)
		(fill yes)
		(layer "F.Cu")
		(net "M_A_CPU1_SA_DQ<29>")
	)
	(gr_poly
		(pts
			(xy 77.67193 -266.212574) (xy 77.625702 -266.115038) (xy 77.589888 -266.079224) (xy 77.40396 -266.265152)
			(xy 77.439774 -266.300966) (xy 77.53731 -266.347194)
		)
		(stroke
			(width 0)
			(type solid)
		)
		(fill yes)
		(layer "F.Cu")
		(net "M_A_CPU1_SA_CB<4>")
	)
	(gr_poly
		(pts
			(xy 77.672184 -276.910038) (xy 77.62748 -276.886162) (xy 77.5208 -276.87016) (xy 77.430884 -277.038054)
			(xy 77.503528 -277.118064) (xy 77.548232 -277.14194)
		)
		(stroke
			(width 0)
			(type solid)
		)
		(fill yes)
		(layer "F.Cu")
		(net "M_A_CPU1_SA_DQ<26>")
	)
	(gr_poly
		(pts
			(xy 77.6732 -223.888808) (xy 77.719428 -223.791272) (xy 77.584554 -223.656652) (xy 77.487272 -223.70288)
			(xy 77.451204 -223.738694) (xy 77.637132 -223.924622)
		)
		(stroke
			(width 0)
			(type solid)
		)
		(fill yes)
		(layer "F.Cu")
		(net "M_A_CPU1_SB_DQ<17>")
	)
	(gr_poly
		(pts
			(xy 77.673454 -275.93671) (xy 77.601064 -275.8567) (xy 77.556106 -275.832824) (xy 77.432408 -276.064726)
			(xy 77.477112 -276.088602) (xy 77.583792 -276.104604)
		)
		(stroke
			(width 0)
			(type solid)
		)
		(fill yes)
		(layer "F.Cu")
		(net "M_A_CPU1_SA_DQ<27>")
	)
	(gr_poly
		(pts
			(xy 77.67701 -268.7955) (xy 77.630782 -268.697964) (xy 77.594714 -268.66215) (xy 77.408786 -268.848078)
			(xy 77.444854 -268.883892) (xy 77.542136 -268.93012)
		)
		(stroke
			(width 0)
			(type solid)
		)
		(fill yes)
		(layer "F.Cu")
		(net "M_A_CPU1_SA_CB<1>")
	)
	(gr_poly
		(pts
			(xy 77.68082 -273.08048) (xy 77.644752 -273.044666) (xy 77.54747 -272.998438) (xy 77.412596 -273.133058)
			(xy 77.458824 -273.230594) (xy 77.494892 -273.266408)
		)
		(stroke
			(width 0)
			(type solid)
		)
		(fill yes)
		(layer "F.Cu")
		(net "M_A_CPU1_SA_DQ<28>")
	)
	(gr_poly
		(pts
			(xy 77.68463 -276.239986) (xy 77.639926 -276.215856) (xy 77.533246 -276.199854) (xy 77.44333 -276.368002)
			(xy 77.515974 -276.447758) (xy 77.560678 -276.471634)
		)
		(stroke
			(width 0)
			(type solid)
		)
		(fill yes)
		(layer "F.Cu")
		(net "M_A_CPU1_SA_DQ<25>")
	)
	(gr_poly
		(pts
			(xy 77.686408 -269.64894) (xy 77.639926 -269.551404) (xy 77.604112 -269.51559) (xy 77.418184 -269.701518)
			(xy 77.454252 -269.737332) (xy 77.551534 -269.78356)
		)
		(stroke
			(width 0)
			(type solid)
		)
		(fill yes)
		(layer "F.Cu")
		(net "M_A_CPU1_SA_CB<0>")
	)
	(gr_poly
		(pts
			(xy 77.692504 -278.523446) (xy 77.729588 -278.336502) (xy 77.637132 -278.28113) (xy 77.587348 -278.271224)
			(xy 77.53604 -278.529288) (xy 77.585824 -278.539194)
		)
		(stroke
			(width 0)
			(type solid)
		)
		(fill yes)
		(layer "F.Cu")
		(net "M_A_CPU1_SA_DQ<24>")
	)
	(gr_poly
		(pts
			(xy 77.696822 -275.56968) (xy 77.652118 -275.545804) (xy 77.545438 -275.529802) (xy 77.455776 -275.697696)
			(xy 77.528166 -275.777452) (xy 77.57287 -275.801582)
		)
		(stroke
			(width 0)
			(type solid)
		)
		(fill yes)
		(layer "F.Cu")
		(net "M_A_CPU1_SA_DQ<27>")
	)
	(gr_poly
		(pts
			(xy 77.731112 -284.529022) (xy 77.731112 -284.338522) (xy 77.629512 -284.302454) (xy 77.578712 -284.302454)
			(xy 77.578712 -284.565344) (xy 77.629512 -284.565344)
		)
		(stroke
			(width 0)
			(type solid)
		)
		(fill yes)
		(layer "F.Cu")
		(net "M_A_CPU1_SA_DQ<23>")
	)
	(gr_poly
		(pts
			(xy 77.731112 -283.932122) (xy 77.731112 -283.741622) (xy 77.629512 -283.705554) (xy 77.578712 -283.705554)
			(xy 77.578712 -283.968444) (xy 77.629512 -283.968444)
		)
		(stroke
			(width 0)
			(type solid)
		)
		(fill yes)
		(layer "F.Cu")
		(net "M_A_CPU1_SA_DQ<23>")
	)
	(gr_poly
		(pts
			(xy 77.731112 -283.335222) (xy 77.731112 -283.144722) (xy 77.629512 -283.108654) (xy 77.578712 -283.108654)
			(xy 77.578712 -283.371544) (xy 77.629512 -283.371544)
		)
		(stroke
			(width 0)
			(type solid)
		)
		(fill yes)
		(layer "F.Cu")
		(net "M_A_CPU1_SA_DQ<23>")
	)
	(gr_poly
		(pts
			(xy 77.731112 -282.738322) (xy 77.731112 -282.547822) (xy 77.629512 -282.511754) (xy 77.578712 -282.511754)
			(xy 77.578712 -282.774644) (xy 77.629512 -282.774644)
		)
		(stroke
			(width 0)
			(type solid)
		)
		(fill yes)
		(layer "F.Cu")
		(net "M_A_CPU1_SA_DQ<23>")
	)
	(gr_poly
		(pts
			(xy 77.731112 -282.141422) (xy 77.731112 -281.950922) (xy 77.629512 -281.914854) (xy 77.578712 -281.914854)
			(xy 77.578712 -282.177744) (xy 77.629512 -282.177744)
		)
		(stroke
			(width 0)
			(type solid)
		)
		(fill yes)
		(layer "F.Cu")
		(net "M_A_CPU1_SA_DQ<23>")
	)
	(gr_poly
		(pts
			(xy 77.748638 -271.933416) (xy 77.70241 -271.83588) (xy 77.666342 -271.800066) (xy 77.480414 -271.985994)
			(xy 77.516482 -272.021808) (xy 77.613764 -272.068036)
		)
		(stroke
			(width 0)
			(type solid)
		)
		(fill yes)
		(layer "F.Cu")
		(net "M_A_CPU1_SA_DQ<31>")
	)
	(gr_poly
		(pts
			(xy 77.75829 -272.78711) (xy 77.712062 -272.689828) (xy 77.676248 -272.65376) (xy 77.49032 -272.839688)
			(xy 77.526134 -272.875756) (xy 77.62367 -272.921984)
		)
		(stroke
			(width 0)
			(type solid)
		)
		(fill yes)
		(layer "F.Cu")
		(net "M_A_CPU1_SA_DQ<30>")
	)
	(gr_poly
		(pts
			(xy 77.76464 -246.831612) (xy 77.728572 -246.730012) (xy 77.538072 -246.730012) (xy 77.50175 -246.831612)
			(xy 77.50175 -246.882412) (xy 77.76464 -246.882412)
		)
		(stroke
			(width 0)
			(type solid)
		)
		(fill yes)
		(layer "F.Cu")
		(net "M_A_CPU1_SB_CS_N<2>")
	)
	(gr_poly
		(pts
			(xy 77.76464 -246.526812) (xy 77.728572 -246.425212) (xy 77.538072 -246.425212) (xy 77.50175 -246.526812)
			(xy 77.50175 -246.577612) (xy 77.76464 -246.577612)
		)
		(stroke
			(width 0)
			(type solid)
		)
		(fill yes)
		(layer "F.Cu")
		(net "M_A_CPU1_SB_CS_N<0>")
	)
	(gr_poly
		(pts
			(xy 77.76464 -246.222012) (xy 77.728572 -246.120412) (xy 77.538072 -246.120412) (xy 77.50175 -246.222012)
			(xy 77.50175 -246.272812) (xy 77.76464 -246.272812)
		)
		(stroke
			(width 0)
			(type solid)
		)
		(fill yes)
		(layer "F.Cu")
		(net "M_A_CPU1_SB_CS_N<3>")
	)
	(gr_poly
		(pts
			(xy 77.76464 -245.917212) (xy 77.728572 -245.815612) (xy 77.538072 -245.815612) (xy 77.50175 -245.917212)
			(xy 77.50175 -245.968012) (xy 77.76464 -245.968012)
		)
		(stroke
			(width 0)
			(type solid)
		)
		(fill yes)
		(layer "F.Cu")
		(net "M_A_CPU1_SB_CS_N<1>")
	)
	(gr_poly
		(pts
			(xy 77.780642 -280.42997) (xy 77.730858 -280.41981) (xy 77.624178 -280.435558) (xy 77.58684 -280.622248)
			(xy 77.67955 -280.67762) (xy 77.729334 -280.68778)
		)
		(stroke
			(width 0)
			(type solid)
		)
		(fill yes)
		(layer "F.Cu")
		(net "M_A_CPU1_SA_DQ<23>")
	)
	(gr_poly
		(pts
			(xy 77.79131 -265.01471) (xy 77.755496 -264.978642) (xy 77.65796 -264.932414) (xy 77.52334 -265.067034)
			(xy 77.569568 -265.16457) (xy 77.605636 -265.200384)
		)
		(stroke
			(width 0)
			(type solid)
		)
		(fill yes)
		(layer "F.Cu")
		(net "M_A_CPU1_SA_CB<5>")
	)
	(gr_poly
		(pts
			(xy 77.799184 -223.138746) (xy 77.799184 -222.948246) (xy 77.697584 -222.912178) (xy 77.646784 -222.912178)
			(xy 77.646784 -223.174814) (xy 77.697584 -223.174814)
		)
		(stroke
			(width 0)
			(type solid)
		)
		(fill yes)
		(layer "F.Cu")
		(net "M_A_CPU1_SB_DQ<19>")
	)
	(gr_poly
		(pts
			(xy 77.799184 -222.541846) (xy 77.799184 -222.351346) (xy 77.697584 -222.315278) (xy 77.646784 -222.315278)
			(xy 77.646784 -222.577914) (xy 77.697584 -222.577914)
		)
		(stroke
			(width 0)
			(type solid)
		)
		(fill yes)
		(layer "F.Cu")
		(net "M_A_CPU1_SB_DQ<19>")
	)
	(gr_poly
		(pts
			(xy 77.799184 -221.944946) (xy 77.799184 -221.754446) (xy 77.697584 -221.718378) (xy 77.646784 -221.718378)
			(xy 77.646784 -221.981014) (xy 77.697584 -221.981014)
		)
		(stroke
			(width 0)
			(type solid)
		)
		(fill yes)
		(layer "F.Cu")
		(net "M_A_CPU1_SB_DQ<19>")
	)
	(gr_poly
		(pts
			(xy 77.799184 -221.348046) (xy 77.799184 -221.157546) (xy 77.697584 -221.121478) (xy 77.646784 -221.121478)
			(xy 77.646784 -221.384114) (xy 77.697584 -221.384114)
		)
		(stroke
			(width 0)
			(type solid)
		)
		(fill yes)
		(layer "F.Cu")
		(net "M_A_CPU1_SB_DQ<19>")
	)
	(gr_poly
		(pts
			(xy 77.799184 -220.751146) (xy 77.799184 -220.560646) (xy 77.697584 -220.524578) (xy 77.646784 -220.524578)
			(xy 77.646784 -220.787214) (xy 77.697584 -220.787214)
		)
		(stroke
			(width 0)
			(type solid)
		)
		(fill yes)
		(layer "F.Cu")
		(net "M_A_CPU1_SB_DQ<19>")
	)
	(gr_poly
		(pts
			(xy 77.799184 -220.154246) (xy 77.799184 -219.963746) (xy 77.697584 -219.927678) (xy 77.646784 -219.927678)
			(xy 77.646784 -220.190314) (xy 77.697584 -220.190314)
		)
		(stroke
			(width 0)
			(type solid)
		)
		(fill yes)
		(layer "F.Cu")
		(net "M_A_CPU1_SB_DQ<19>")
	)
	(gr_poly
		(pts
			(xy 77.799184 -219.557346) (xy 77.799184 -219.366846) (xy 77.697584 -219.330778) (xy 77.646784 -219.330778)
			(xy 77.646784 -219.593414) (xy 77.697584 -219.593414)
		)
		(stroke
			(width 0)
			(type solid)
		)
		(fill yes)
		(layer "F.Cu")
		(net "M_A_CPU1_SB_DQ<19>")
	)
	(gr_poly
		(pts
			(xy 77.799184 -218.960446) (xy 77.799184 -218.769946) (xy 77.697584 -218.733878) (xy 77.646784 -218.733878)
			(xy 77.646784 -218.996514) (xy 77.697584 -218.996514)
		)
		(stroke
			(width 0)
			(type solid)
		)
		(fill yes)
		(layer "F.Cu")
		(net "M_A_CPU1_SB_DQ<19>")
	)
	(gr_poly
		(pts
			(xy 77.800962 -265.86815) (xy 77.764894 -265.832336) (xy 77.667612 -265.786108) (xy 77.532738 -265.920728)
			(xy 77.578966 -266.018264) (xy 77.615034 -266.054078)
		)
		(stroke
			(width 0)
			(type solid)
		)
		(fill yes)
		(layer "F.Cu")
		(net "M_A_CPU1_SA_CB<4>")
	)
	(gr_poly
		(pts
			(xy 77.802994 -225.02495) (xy 77.839062 -224.989136) (xy 77.653134 -224.803208) (xy 77.61732 -224.839022)
			(xy 77.570838 -224.936558) (xy 77.705712 -225.071178)
		)
		(stroke
			(width 0)
			(type solid)
		)
		(fill yes)
		(layer "F.Cu")
		(net "M_A_CPU1_SB_DQ<16>")
	)
	(gr_poly
		(pts
			(xy 77.805788 -268.451076) (xy 77.769974 -268.415008) (xy 77.672438 -268.36878) (xy 77.537818 -268.503654)
			(xy 77.584046 -268.600936) (xy 77.61986 -268.637004)
		)
		(stroke
			(width 0)
			(type solid)
		)
		(fill yes)
		(layer "F.Cu")
		(net "M_A_CPU1_SA_CB<1>")
	)
	(gr_poly
		(pts
			(xy 77.80909 -277.937976) (xy 77.846174 -277.751032) (xy 77.753464 -277.695914) (xy 77.70368 -277.686008)
			(xy 77.652372 -277.943818) (xy 77.70241 -277.953724)
		)
		(stroke
			(width 0)
			(type solid)
		)
		(fill yes)
		(layer "F.Cu")
		(net "M_A_CPU1_SA_DQ<24>")
	)
	(gr_poly
		(pts
			(xy 77.812392 -224.17151) (xy 77.848206 -224.135696) (xy 77.662278 -223.949768) (xy 77.626464 -223.985836)
			(xy 77.580236 -224.083118) (xy 77.714856 -224.217992)
		)
		(stroke
			(width 0)
			(type solid)
		)
		(fill yes)
		(layer "F.Cu")
		(net "M_A_CPU1_SB_DQ<17>")
	)
	(gr_poly
		(pts
			(xy 77.815186 -269.304516) (xy 77.779372 -269.268702) (xy 77.681836 -269.222474) (xy 77.547216 -269.357094)
			(xy 77.593444 -269.45463) (xy 77.629258 -269.490444)
		)
		(stroke
			(width 0)
			(type solid)
		)
		(fill yes)
		(layer "F.Cu")
		(net "M_A_CPU1_SA_CB<0>")
	)
	(gr_poly
		(pts
			(xy 77.827378 -280.974546) (xy 77.864716 -280.787856) (xy 77.77226 -280.732484) (xy 77.722222 -280.722578)
			(xy 77.670914 -280.980388) (xy 77.720698 -280.990294)
		)
		(stroke
			(width 0)
			(type solid)
		)
		(fill yes)
		(layer "F.Cu")
		(net "M_A_CPU1_SA_DQ<23>")
	)
	(gr_poly
		(pts
			(xy 77.86878 -264.721086) (xy 77.822552 -264.623804) (xy 77.786738 -264.587736) (xy 77.60081 -264.773664)
			(xy 77.636624 -264.809478) (xy 77.73416 -264.85596)
		)
		(stroke
			(width 0)
			(type solid)
		)
		(fill yes)
		(layer "F.Cu")
		(net "M_A_CPU1_SA_CB<7>")
	)
	(gr_poly
		(pts
			(xy 77.877416 -271.588992) (xy 77.841602 -271.552924) (xy 77.744066 -271.506696) (xy 77.609446 -271.64157)
			(xy 77.655674 -271.738852) (xy 77.691488 -271.77492)
		)
		(stroke
			(width 0)
			(type solid)
		)
		(fill yes)
		(layer "F.Cu")
		(net "M_A_CPU1_SA_DQ<31>")
	)
	(gr_poly
		(pts
			(xy 77.878432 -265.57478) (xy 77.832204 -265.477244) (xy 77.796136 -265.44143) (xy 77.610208 -265.627358)
			(xy 77.646276 -265.663172) (xy 77.743558 -265.7094)
		)
		(stroke
			(width 0)
			(type solid)
		)
		(fill yes)
		(layer "F.Cu")
		(net "M_A_CPU1_SA_CB<6>")
	)
	(gr_poly
		(pts
			(xy 77.879448 -224.526602) (xy 77.925676 -224.429066) (xy 77.791056 -224.294446) (xy 77.69352 -224.340674)
			(xy 77.657706 -224.376488) (xy 77.843634 -224.562416)
		)
		(stroke
			(width 0)
			(type solid)
		)
		(fill yes)
		(layer "F.Cu")
		(net "M_A_CPU1_SB_DQ<18>")
	)
	(gr_poly
		(pts
			(xy 77.883258 -268.157706) (xy 77.83703 -268.06017) (xy 77.801216 -268.024356) (xy 77.615288 -268.210284)
			(xy 77.651356 -268.246098) (xy 77.748638 -268.292326)
		)
		(stroke
			(width 0)
			(type solid)
		)
		(fill yes)
		(layer "F.Cu")
		(net "M_A_CPU1_SA_CB<3>")
	)
	(gr_poly
		(pts
			(xy 77.883512 -284.600904) (xy 77.832712 -284.600904) (xy 77.731112 -284.637226) (xy 77.731112 -284.827726)
			(xy 77.832712 -284.863794) (xy 77.883512 -284.863794)
		)
		(stroke
			(width 0)
			(type solid)
		)
		(fill yes)
		(layer "F.Cu")
		(net "M_A_CPU1_SA_DQ<21>")
	)
	(gr_poly
		(pts
			(xy 77.883512 -284.004004) (xy 77.832712 -284.004004) (xy 77.731112 -284.040326) (xy 77.731112 -284.230826)
			(xy 77.832712 -284.266894) (xy 77.883512 -284.266894)
		)
		(stroke
			(width 0)
			(type solid)
		)
		(fill yes)
		(layer "F.Cu")
		(net "M_A_CPU1_SA_DQ<21>")
	)
	(gr_poly
		(pts
			(xy 77.883512 -283.407104) (xy 77.832712 -283.407104) (xy 77.731112 -283.443426) (xy 77.731112 -283.633926)
			(xy 77.832712 -283.669994) (xy 77.883512 -283.669994)
		)
		(stroke
			(width 0)
			(type solid)
		)
		(fill yes)
		(layer "F.Cu")
		(net "M_A_CPU1_SA_DQ<21>")
	)
	(gr_poly
		(pts
			(xy 77.883512 -282.810204) (xy 77.832712 -282.810204) (xy 77.731112 -282.846526) (xy 77.731112 -283.037026)
			(xy 77.832712 -283.073094) (xy 77.883512 -283.073094)
		)
		(stroke
			(width 0)
			(type solid)
		)
		(fill yes)
		(layer "F.Cu")
		(net "M_A_CPU1_SA_DQ<21>")
	)
	(gr_poly
		(pts
			(xy 77.883512 -282.213304) (xy 77.832712 -282.213304) (xy 77.731112 -282.249626) (xy 77.731112 -282.440126)
			(xy 77.832712 -282.476194) (xy 77.883512 -282.476194)
		)
		(stroke
			(width 0)
			(type solid)
		)
		(fill yes)
		(layer "F.Cu")
		(net "M_A_CPU1_SA_DQ<21>")
	)
	(gr_poly
		(pts
			(xy 77.883512 -281.616404) (xy 77.832712 -281.616404) (xy 77.731112 -281.652726) (xy 77.731112 -281.843226)
			(xy 77.832712 -281.879294) (xy 77.883512 -281.879294)
		)
		(stroke
			(width 0)
			(type solid)
		)
		(fill yes)
		(layer "F.Cu")
		(net "M_A_CPU1_SA_DQ<21>")
	)
	(gr_poly
		(pts
			(xy 77.887068 -272.44294) (xy 77.851254 -272.406872) (xy 77.753718 -272.360644) (xy 77.619098 -272.495264)
			(xy 77.665326 -272.5928) (xy 77.701394 -272.628614)
		)
		(stroke
			(width 0)
			(type solid)
		)
		(fill yes)
		(layer "F.Cu")
		(net "M_A_CPU1_SA_DQ<30>")
	)
	(gr_poly
		(pts
			(xy 77.892656 -269.011146) (xy 77.846428 -268.913864) (xy 77.810614 -268.877796) (xy 77.624686 -269.063724)
			(xy 77.6605 -269.099792) (xy 77.758036 -269.14602)
		)
		(stroke
			(width 0)
			(type solid)
		)
		(fill yes)
		(layer "F.Cu")
		(net "M_A_CPU1_SA_CB<2>")
	)
	(gr_poly
		(pts
			(xy 77.897482 -279.8445) (xy 77.847698 -279.834594) (xy 77.741018 -279.850088) (xy 77.70368 -280.037032)
			(xy 77.79639 -280.092404) (xy 77.846174 -280.10231)
		)
		(stroke
			(width 0)
			(type solid)
		)
		(fill yes)
		(layer "F.Cu")
		(net "M_A_CPU1_SA_DQ<23>")
	)
	(gr_poly
		(pts
			(xy 77.930248 -276.750526) (xy 77.857604 -276.67077) (xy 77.8129 -276.646894) (xy 77.688948 -276.878542)
			(xy 77.733906 -276.902672) (xy 77.840332 -276.918674)
		)
		(stroke
			(width 0)
			(type solid)
		)
		(fill yes)
		(layer "F.Cu")
		(net "M_A_CPU1_SA_DQ<26>")
	)
	(gr_poly
		(pts
			(xy 77.942694 -276.080474) (xy 77.87005 -276.000718) (xy 77.825346 -275.976588) (xy 77.701394 -276.20849)
			(xy 77.746098 -276.232366) (xy 77.852778 -276.248368)
		)
		(stroke
			(width 0)
			(type solid)
		)
		(fill yes)
		(layer "F.Cu")
		(net "M_A_CPU1_SA_DQ<25>")
	)
	(gr_poly
		(pts
			(xy 77.944218 -280.38933) (xy 77.981556 -280.202386) (xy 77.888846 -280.147014) (xy 77.839062 -280.137108)
			(xy 77.787754 -280.394918) (xy 77.837538 -280.404824)
		)
		(stroke
			(width 0)
			(type solid)
		)
		(fill yes)
		(layer "F.Cu")
		(net "M_A_CPU1_SA_DQ<23>")
	)
	(gr_poly
		(pts
			(xy 77.95387 -276.383496) (xy 77.908912 -276.35962) (xy 77.802232 -276.343618) (xy 77.71257 -276.511766)
			(xy 77.785214 -276.591522) (xy 77.829918 -276.615398)
		)
		(stroke
			(width 0)
			(type solid)
		)
		(fill yes)
		(layer "F.Cu")
		(net "M_A_CPU1_SA_DQ<26>")
	)
	(gr_poly
		(pts
			(xy 77.954886 -275.410168) (xy 77.882496 -275.330412) (xy 77.837538 -275.306536) (xy 77.713586 -275.538184)
			(xy 77.758544 -275.562314) (xy 77.865224 -275.578316)
		)
		(stroke
			(width 0)
			(type solid)
		)
		(fill yes)
		(layer "F.Cu")
		(net "M_A_CPU1_SA_DQ<27>")
	)
	(gr_poly
		(pts
			(xy 77.964284 -272.149062) (xy 77.918056 -272.05178) (xy 77.882242 -272.015712) (xy 77.696314 -272.20164)
			(xy 77.732128 -272.237708) (xy 77.829664 -272.283936)
		)
		(stroke
			(width 0)
			(type solid)
		)
		(fill yes)
		(layer "F.Cu")
		(net "M_A_CPU1_SA_DQ<29>")
	)
	(gr_poly
		(pts
			(xy 77.966062 -275.713444) (xy 77.921104 -275.689568) (xy 77.814424 -275.673566) (xy 77.724762 -275.84146)
			(xy 77.797152 -275.92147) (xy 77.84211 -275.945346)
		)
		(stroke
			(width 0)
			(type solid)
		)
		(fill yes)
		(layer "F.Cu")
		(net "M_A_CPU1_SA_DQ<25>")
	)
	(gr_poly
		(pts
			(xy 77.973936 -273.002756) (xy 77.927708 -272.905474) (xy 77.891894 -272.869406) (xy 77.705966 -273.055334)
			(xy 77.74178 -273.091402) (xy 77.839316 -273.13763)
		)
		(stroke
			(width 0)
			(type solid)
		)
		(fill yes)
		(layer "F.Cu")
		(net "M_A_CPU1_SA_DQ<28>")
	)
	(gr_poly
		(pts
			(xy 77.978254 -275.043138) (xy 77.93355 -275.019262) (xy 77.82687 -275.00326) (xy 77.736954 -275.171408)
			(xy 77.809598 -275.251164) (xy 77.854302 -275.27504)
		)
		(stroke
			(width 0)
			(type solid)
		)
		(fill yes)
		(layer "F.Cu")
		(net "M_A_CPU1_SA_DQ<27>")
	)
	(gr_poly
		(pts
			(xy 77.997812 -264.376662) (xy 77.961744 -264.340848) (xy 77.864462 -264.29462) (xy 77.729588 -264.42924)
			(xy 77.775816 -264.526776) (xy 77.811884 -264.56259)
		)
		(stroke
			(width 0)
			(type solid)
		)
		(fill yes)
		(layer "F.Cu")
		(net "M_A_CPU1_SA_CB<7>")
	)
	(gr_poly
		(pts
			(xy 78.00721 -265.230356) (xy 77.971396 -265.194542) (xy 77.87386 -265.148314) (xy 77.73924 -265.282934)
			(xy 77.785468 -265.380216) (xy 77.821282 -265.416284)
		)
		(stroke
			(width 0)
			(type solid)
		)
		(fill yes)
		(layer "F.Cu")
		(net "M_A_CPU1_SA_CB<6>")
	)
	(gr_poly
		(pts
			(xy 78.01229 -267.813282) (xy 77.976222 -267.777468) (xy 77.87894 -267.73124) (xy 77.744066 -267.86586)
			(xy 77.790548 -267.963396) (xy 77.826362 -267.99921)
		)
		(stroke
			(width 0)
			(type solid)
		)
		(fill yes)
		(layer "F.Cu")
		(net "M_A_CPU1_SA_CB<3>")
	)
	(gr_poly
		(pts
			(xy 78.014322 -279.25903) (xy 77.964538 -279.249124) (xy 77.857858 -279.264872) (xy 77.82052 -279.451562)
			(xy 77.91323 -279.506934) (xy 77.963014 -279.51684)
		)
		(stroke
			(width 0)
			(type solid)
		)
		(fill yes)
		(layer "F.Cu")
		(net "M_A_CPU1_SA_DQ<23>")
	)
	(gr_poly
		(pts
			(xy 78.01864 -224.809304) (xy 78.054708 -224.77349) (xy 77.86878 -224.587562) (xy 77.832966 -224.623376)
			(xy 77.786484 -224.720912) (xy 77.921358 -224.855532)
		)
		(stroke
			(width 0)
			(type solid)
		)
		(fill yes)
		(layer "F.Cu")
		(net "M_A_CPU1_SB_DQ<18>")
	)
	(gr_poly
		(pts
			(xy 78.021688 -268.666722) (xy 77.98562 -268.630908) (xy 77.888338 -268.58468) (xy 77.753464 -268.7193)
			(xy 77.799692 -268.816836) (xy 77.83576 -268.85265)
		)
		(stroke
			(width 0)
			(type solid)
		)
		(fill yes)
		(layer "F.Cu")
		(net "M_A_CPU1_SA_CB<2>")
	)
	(gr_poly
		(pts
			(xy 78.028038 -223.955864) (xy 78.063852 -223.92005) (xy 77.877924 -223.734122) (xy 77.84211 -223.77019)
			(xy 77.795882 -223.867472) (xy 77.930502 -224.002346)
		)
		(stroke
			(width 0)
			(type solid)
		)
		(fill yes)
		(layer "F.Cu")
		(net "M_A_CPU1_SB_DQ<19>")
	)
	(gr_poly
		(pts
			(xy 78.035912 -285.125922) (xy 78.035912 -284.935422) (xy 77.934312 -284.899354) (xy 77.883512 -284.899354)
			(xy 77.883512 -285.162244) (xy 77.934312 -285.162244)
		)
		(stroke
			(width 0)
			(type solid)
		)
		(fill yes)
		(layer "F.Cu")
		(net "M_A_CPU1_SA_DQ<21>")
	)
	(gr_poly
		(pts
			(xy 78.035912 -284.529022) (xy 78.035912 -284.338522) (xy 77.934312 -284.302454) (xy 77.883512 -284.302454)
			(xy 77.883512 -284.565344) (xy 77.934312 -284.565344)
		)
		(stroke
			(width 0)
			(type solid)
		)
		(fill yes)
		(layer "F.Cu")
		(net "M_A_CPU1_SA_DQ<21>")
	)
	(gr_poly
		(pts
			(xy 78.035912 -283.932122) (xy 78.035912 -283.741622) (xy 77.934312 -283.705554) (xy 77.883512 -283.705554)
			(xy 77.883512 -283.968444) (xy 77.934312 -283.968444)
		)
		(stroke
			(width 0)
			(type solid)
		)
		(fill yes)
		(layer "F.Cu")
		(net "M_A_CPU1_SA_DQ<21>")
	)
	(gr_poly
		(pts
			(xy 78.035912 -283.335222) (xy 78.035912 -283.144722) (xy 77.934312 -283.108654) (xy 77.883512 -283.108654)
			(xy 77.883512 -283.371544) (xy 77.934312 -283.371544)
		)
		(stroke
			(width 0)
			(type solid)
		)
		(fill yes)
		(layer "F.Cu")
		(net "M_A_CPU1_SA_DQ<21>")
	)
	(gr_poly
		(pts
			(xy 78.035912 -282.738322) (xy 78.035912 -282.547822) (xy 77.934312 -282.511754) (xy 77.883512 -282.511754)
			(xy 77.883512 -282.774644) (xy 77.934312 -282.774644)
		)
		(stroke
			(width 0)
			(type solid)
		)
		(fill yes)
		(layer "F.Cu")
		(net "M_A_CPU1_SA_DQ<21>")
	)
	(gr_poly
		(pts
			(xy 78.035912 -282.141422) (xy 78.035912 -281.950922) (xy 77.934312 -281.914854) (xy 77.883512 -281.914854)
			(xy 77.883512 -282.177744) (xy 77.934312 -282.177744)
		)
		(stroke
			(width 0)
			(type solid)
		)
		(fill yes)
		(layer "F.Cu")
		(net "M_A_CPU1_SA_DQ<21>")
	)
	(gr_poly
		(pts
			(xy 78.061058 -279.80386) (xy 78.098396 -279.61717) (xy 78.005686 -279.561798) (xy 77.955902 -279.551892)
			(xy 77.904594 -279.809702) (xy 77.954378 -279.819608)
		)
		(stroke
			(width 0)
			(type solid)
		)
		(fill yes)
		(layer "F.Cu")
		(net "M_A_CPU1_SA_DQ<23>")
	)
	(gr_poly
		(pts
			(xy 78.06309 -249.066812) (xy 78.06309 -249.016012) (xy 77.8002 -249.016012) (xy 77.8002 -249.066812)
			(xy 77.836268 -249.168412) (xy 78.026768 -249.168412)
		)
		(stroke
			(width 0)
			(type solid)
		)
		(fill yes)
		(layer "F.Cu")
		(net "M_A_CPU1_SB_CA<1>")
	)
	(gr_poly
		(pts
			(xy 78.06309 -247.542812) (xy 78.06309 -247.492012) (xy 77.8002 -247.492012) (xy 77.8002 -247.542812)
			(xy 77.836268 -247.644412) (xy 78.026768 -247.644412)
		)
		(stroke
			(width 0)
			(type solid)
		)
		(fill yes)
		(layer "F.Cu")
		(net "M_A_CPU1_SB_CA<6>")
	)
	(gr_poly
		(pts
			(xy 78.06309 -247.238012) (xy 78.06309 -247.187212) (xy 77.8002 -247.187212) (xy 77.8002 -247.238012)
			(xy 77.836268 -247.339612) (xy 78.026768 -247.339612)
		)
		(stroke
			(width 0)
			(type solid)
		)
		(fill yes)
		(layer "F.Cu")
		(net "M_A_CPU1_SB_PAR")
	)
	(gr_poly
		(pts
			(xy 78.06309 -246.933212) (xy 78.06309 -246.882412) (xy 77.8002 -246.882412) (xy 77.8002 -246.933212)
			(xy 77.836268 -247.034812) (xy 78.026768 -247.034812)
		)
		(stroke
			(width 0)
			(type solid)
		)
		(fill yes)
		(layer "F.Cu")
		(net "M_A_CPU1_SB_CS_N<2>")
	)
	(gr_poly
		(pts
			(xy 78.06309 -246.628412) (xy 78.06309 -246.577612) (xy 77.8002 -246.577612) (xy 77.8002 -246.628412)
			(xy 77.836268 -246.730012) (xy 78.026768 -246.730012)
		)
		(stroke
			(width 0)
			(type solid)
		)
		(fill yes)
		(layer "F.Cu")
		(net "M_A_CPU1_SB_CS_N<0>")
	)
	(gr_poly
		(pts
			(xy 78.06309 -246.323612) (xy 78.06309 -246.272812) (xy 77.8002 -246.272812) (xy 77.8002 -246.323612)
			(xy 77.836268 -246.425212) (xy 78.026768 -246.425212)
		)
		(stroke
			(width 0)
			(type solid)
		)
		(fill yes)
		(layer "F.Cu")
		(net "M_A_CPU1_SB_CS_N<3>")
	)
	(gr_poly
		(pts
			(xy 78.06309 -246.018812) (xy 78.06309 -245.968012) (xy 77.8002 -245.968012) (xy 77.8002 -246.018812)
			(xy 77.836268 -246.120412) (xy 78.026768 -246.120412)
		)
		(stroke
			(width 0)
			(type solid)
		)
		(fill yes)
		(layer "F.Cu")
		(net "M_A_CPU1_SB_CS_N<1>")
	)
	(gr_poly
		(pts
			(xy 78.079854 -280.489406) (xy 78.03007 -280.4795) (xy 77.92339 -280.495248) (xy 77.886052 -280.681938)
			(xy 77.978762 -280.73731) (xy 78.028546 -280.747216)
		)
		(stroke
			(width 0)
			(type solid)
		)
		(fill yes)
		(layer "F.Cu")
		(net "M_A_CPU1_SA_DQ<21>")
	)
	(gr_poly
		(pts
			(xy 78.08468 -264.936986) (xy 78.038452 -264.83945) (xy 78.002384 -264.803636) (xy 77.816456 -264.989564)
			(xy 77.852524 -265.025378) (xy 77.949806 -265.071606)
		)
		(stroke
			(width 0)
			(type solid)
		)
		(fill yes)
		(layer "F.Cu")
		(net "M_A_CPU1_SA_CB<5>")
	)
	(gr_poly
		(pts
			(xy 78.08595 -225.164142) (xy 78.132178 -225.06686) (xy 77.997558 -224.931986) (xy 77.900022 -224.978214)
			(xy 77.864208 -225.014282) (xy 78.050136 -225.20021)
		)
		(stroke
			(width 0)
			(type solid)
		)
		(fill yes)
		(layer "F.Cu")
		(net "M_A_CPU1_SB_DQ<16>")
	)
	(gr_poly
		(pts
			(xy 78.093316 -271.804638) (xy 78.057248 -271.768824) (xy 77.959966 -271.722596) (xy 77.825092 -271.857216)
			(xy 77.87132 -271.954752) (xy 77.907388 -271.990566)
		)
		(stroke
			(width 0)
			(type solid)
		)
		(fill yes)
		(layer "F.Cu")
		(net "M_A_CPU1_SA_DQ<29>")
	)
	(gr_poly
		(pts
			(xy 78.094078 -265.790426) (xy 78.04785 -265.693144) (xy 78.012036 -265.657076) (xy 77.826108 -265.843004)
			(xy 77.861922 -265.879072) (xy 77.959458 -265.9253)
		)
		(stroke
			(width 0)
			(type solid)
		)
		(fill yes)
		(layer "F.Cu")
		(net "M_A_CPU1_SA_CB<4>")
	)
	(gr_poly
		(pts
			(xy 78.095094 -224.310956) (xy 78.141322 -224.21342) (xy 78.006702 -224.0788) (xy 77.909166 -224.125028)
			(xy 77.873352 -224.160842) (xy 78.05928 -224.34677)
		)
		(stroke
			(width 0)
			(type solid)
		)
		(fill yes)
		(layer "F.Cu")
		(net "M_A_CPU1_SB_DQ<17>")
	)
	(gr_poly
		(pts
			(xy 78.098904 -268.373352) (xy 78.052676 -268.275816) (xy 78.016862 -268.240002) (xy 77.830934 -268.42593)
			(xy 77.867002 -268.461744) (xy 77.964284 -268.507972)
		)
		(stroke
			(width 0)
			(type solid)
		)
		(fill yes)
		(layer "F.Cu")
		(net "M_A_CPU1_SA_CB<1>")
	)
	(gr_poly
		(pts
			(xy 78.102714 -272.658586) (xy 78.0669 -272.622518) (xy 77.969364 -272.57629) (xy 77.834744 -272.71091)
			(xy 77.880972 -272.808446) (xy 77.91704 -272.84426)
		)
		(stroke
			(width 0)
			(type solid)
		)
		(fill yes)
		(layer "F.Cu")
		(net "M_A_CPU1_SA_DQ<28>")
	)
	(gr_poly
		(pts
			(xy 78.108302 -269.226792) (xy 78.062074 -269.12951) (xy 78.02626 -269.093442) (xy 77.840332 -269.27937)
			(xy 77.876146 -269.315438) (xy 77.973682 -269.361666)
		)
		(stroke
			(width 0)
			(type solid)
		)
		(fill yes)
		(layer "F.Cu")
		(net "M_A_CPU1_SA_CB<0>")
	)
	(gr_poly
		(pts
			(xy 78.126336 -281.034236) (xy 78.163674 -280.847546) (xy 78.071218 -280.792174) (xy 78.02118 -280.782268)
			(xy 77.969872 -281.040078) (xy 78.019656 -281.049984)
		)
		(stroke
			(width 0)
			(type solid)
		)
		(fill yes)
		(layer "F.Cu")
		(net "M_A_CPU1_SA_DQ<21>")
	)
	(gr_poly
		(pts
			(xy 78.131162 -278.673814) (xy 78.081378 -278.663908) (xy 77.974698 -278.679402) (xy 77.93736 -278.866346)
			(xy 78.029816 -278.921718) (xy 78.079854 -278.931624)
		)
		(stroke
			(width 0)
			(type solid)
		)
		(fill yes)
		(layer "F.Cu")
		(net "M_A_CPU1_SA_DQ<23>")
	)
	(gr_poly
		(pts
			(xy 78.170532 -271.511268) (xy 78.124304 -271.413732) (xy 78.08849 -271.377918) (xy 77.902562 -271.563846)
			(xy 77.93863 -271.59966) (xy 78.035912 -271.645888)
		)
		(stroke
			(width 0)
			(type solid)
		)
		(fill yes)
		(layer "F.Cu")
		(net "M_A_CPU1_SA_DQ<31>")
	)
	(gr_poly
		(pts
			(xy 78.177898 -279.218644) (xy 78.215236 -279.0317) (xy 78.122526 -278.976328) (xy 78.072742 -278.966422)
			(xy 78.021434 -279.224232) (xy 78.071218 -279.234138)
		)
		(stroke
			(width 0)
			(type solid)
		)
		(fill yes)
		(layer "F.Cu")
		(net "M_A_CPU1_SA_DQ<23>")
	)
	(gr_poly
		(pts
			(xy 78.180438 -272.365216) (xy 78.13421 -272.26768) (xy 78.098142 -272.231866) (xy 77.912214 -272.417794)
			(xy 77.948282 -272.453608) (xy 78.045564 -272.499836)
		)
		(stroke
			(width 0)
			(type solid)
		)
		(fill yes)
		(layer "F.Cu")
		(net "M_A_CPU1_SA_DQ<30>")
	)
	(gr_poly
		(pts
			(xy 78.188312 -285.794704) (xy 78.137512 -285.794704) (xy 78.035912 -285.831026) (xy 78.035912 -286.021526)
			(xy 78.137512 -286.057594) (xy 78.188312 -286.057594)
		)
		(stroke
			(width 0)
			(type solid)
		)
		(fill yes)
		(layer "F.Cu")
		(net "M_A_CPU1_SA_DQ<22>")
	)
	(gr_poly
		(pts
			(xy 78.188312 -285.197804) (xy 78.137512 -285.197804) (xy 78.035912 -285.234126) (xy 78.035912 -285.424626)
			(xy 78.137512 -285.460694) (xy 78.188312 -285.460694)
		)
		(stroke
			(width 0)
			(type solid)
		)
		(fill yes)
		(layer "F.Cu")
		(net "M_A_CPU1_SA_DQ<22>")
	)
	(gr_poly
		(pts
			(xy 78.188312 -284.600904) (xy 78.137512 -284.600904) (xy 78.035912 -284.637226) (xy 78.035912 -284.827726)
			(xy 78.137512 -284.863794) (xy 78.188312 -284.863794)
		)
		(stroke
			(width 0)
			(type solid)
		)
		(fill yes)
		(layer "F.Cu")
		(net "M_A_CPU1_SA_DQ<22>")
	)
	(gr_poly
		(pts
			(xy 78.188312 -284.004004) (xy 78.137512 -284.004004) (xy 78.035912 -284.040326) (xy 78.035912 -284.230826)
			(xy 78.137512 -284.266894) (xy 78.188312 -284.266894)
		)
		(stroke
			(width 0)
			(type solid)
		)
		(fill yes)
		(layer "F.Cu")
		(net "M_A_CPU1_SA_DQ<22>")
	)
	(gr_poly
		(pts
			(xy 78.188312 -283.407104) (xy 78.137512 -283.407104) (xy 78.035912 -283.443426) (xy 78.035912 -283.633926)
			(xy 78.137512 -283.669994) (xy 78.188312 -283.669994)
		)
		(stroke
			(width 0)
			(type solid)
		)
		(fill yes)
		(layer "F.Cu")
		(net "M_A_CPU1_SA_DQ<22>")
	)
	(gr_poly
		(pts
			(xy 78.188312 -282.810204) (xy 78.137512 -282.810204) (xy 78.035912 -282.846526) (xy 78.035912 -283.037026)
			(xy 78.137512 -283.073094) (xy 78.188312 -283.073094)
		)
		(stroke
			(width 0)
			(type solid)
		)
		(fill yes)
		(layer "F.Cu")
		(net "M_A_CPU1_SA_DQ<22>")
	)
	(gr_poly
		(pts
			(xy 78.188312 -282.213304) (xy 78.137512 -282.213304) (xy 78.035912 -282.249626) (xy 78.035912 -282.440126)
			(xy 78.137512 -282.476194) (xy 78.188312 -282.476194)
		)
		(stroke
			(width 0)
			(type solid)
		)
		(fill yes)
		(layer "F.Cu")
		(net "M_A_CPU1_SA_DQ<22>")
	)
	(gr_poly
		(pts
			(xy 78.19263 -232.140506) (xy 78.238858 -232.04297) (xy 78.103984 -231.90835) (xy 78.006702 -231.954578)
			(xy 77.970634 -231.990392) (xy 78.156562 -232.17632)
		)
		(stroke
			(width 0)
			(type solid)
		)
		(fill yes)
		(layer "F.Cu")
		(net "M_A_CPU1_SB_DQ<9>")
	)
	(gr_poly
		(pts
			(xy 78.196694 -279.90419) (xy 78.146656 -279.894284) (xy 78.039976 -279.909778) (xy 78.002638 -280.096722)
			(xy 78.095348 -280.152094) (xy 78.145132 -280.162)
		)
		(stroke
			(width 0)
			(type solid)
		)
		(fill yes)
		(layer "F.Cu")
		(net "M_A_CPU1_SA_DQ<21>")
	)
	(gr_poly
		(pts
			(xy 78.199234 -276.89429) (xy 78.12659 -276.814534) (xy 78.081886 -276.790404) (xy 77.957934 -277.022306)
			(xy 78.002638 -277.046182) (xy 78.109318 -277.062184)
		)
		(stroke
			(width 0)
			(type solid)
		)
		(fill yes)
		(layer "F.Cu")
		(net "M_A_CPU1_SA_DQ<24>")
	)
	(gr_poly
		(pts
			(xy 78.211426 -276.224238) (xy 78.138782 -276.144228) (xy 78.094078 -276.120352) (xy 77.970126 -276.352254)
			(xy 78.01483 -276.37613) (xy 78.12151 -276.392132)
		)
		(stroke
			(width 0)
			(type solid)
		)
		(fill yes)
		(layer "F.Cu")
		(net "M_A_CPU1_SA_DQ<26>")
	)
	(gr_poly
		(pts
			(xy 78.213458 -264.592562) (xy 78.177644 -264.556494) (xy 78.080108 -264.510266) (xy 77.945488 -264.64514)
			(xy 77.991716 -264.742422) (xy 78.02753 -264.77849)
		)
		(stroke
			(width 0)
			(type solid)
		)
		(fill yes)
		(layer "F.Cu")
		(net "M_A_CPU1_SA_CB<5>")
	)
	(gr_poly
		(pts
			(xy 78.222348 -276.52726) (xy 78.177644 -276.503384) (xy 78.070964 -276.487382) (xy 77.981302 -276.655276)
			(xy 78.053692 -276.735286) (xy 78.09865 -276.759162)
		)
		(stroke
			(width 0)
			(type solid)
		)
		(fill yes)
		(layer "F.Cu")
		(net "M_A_CPU1_SA_DQ<24>")
	)
	(gr_poly
		(pts
			(xy 78.222856 -265.446256) (xy 78.187042 -265.410188) (xy 78.089506 -265.36396) (xy 77.954886 -265.49858)
			(xy 78.001114 -265.596116) (xy 78.037182 -265.63193)
		)
		(stroke
			(width 0)
			(type solid)
		)
		(fill yes)
		(layer "F.Cu")
		(net "M_A_CPU1_SA_CB<4>")
	)
	(gr_poly
		(pts
			(xy 78.224126 -275.553932) (xy 78.151482 -275.474176) (xy 78.106778 -275.4503) (xy 77.982826 -275.682202)
			(xy 78.02753 -275.706078) (xy 78.13421 -275.72208)
		)
		(stroke
			(width 0)
			(type solid)
		)
		(fill yes)
		(layer "F.Cu")
		(net "M_A_CPU1_SA_DQ<25>")
	)
	(gr_poly
		(pts
			(xy 78.227936 -268.028928) (xy 78.191868 -267.993114) (xy 78.094586 -267.946886) (xy 77.959712 -268.081506)
			(xy 78.006194 -268.179042) (xy 78.042008 -268.214856)
		)
		(stroke
			(width 0)
			(type solid)
		)
		(fill yes)
		(layer "F.Cu")
		(net "M_A_CPU1_SA_CB<1>")
	)
	(gr_poly
		(pts
			(xy 78.230222 -229.5906) (xy 78.27645 -229.493064) (xy 78.14183 -229.358444) (xy 78.044548 -229.404672)
			(xy 78.00848 -229.440486) (xy 78.194408 -229.626414)
		)
		(stroke
			(width 0)
			(type solid)
		)
		(fill yes)
		(layer "F.Cu")
		(net "M_A_CPU1_SB_DQ<12>")
	)
	(gr_poly
		(pts
			(xy 78.234286 -224.593658) (xy 78.270354 -224.557844) (xy 78.084426 -224.371916) (xy 78.048612 -224.40773)
			(xy 78.00213 -224.505266) (xy 78.137004 -224.639886)
		)
		(stroke
			(width 0)
			(type solid)
		)
		(fill yes)
		(layer "F.Cu")
		(net "M_A_CPU1_SB_DQ<17>")
	)
	(gr_poly
		(pts
			(xy 78.234794 -275.857208) (xy 78.19009 -275.833078) (xy 78.08341 -275.81733) (xy 77.993748 -275.985224)
			(xy 78.066138 -276.06498) (xy 78.111096 -276.08911)
		)
		(stroke
			(width 0)
			(type solid)
		)
		(fill yes)
		(layer "F.Cu")
		(net "M_A_CPU1_SA_DQ<26>")
	)
	(gr_poly
		(pts
			(xy 78.237334 -268.882368) (xy 78.201266 -268.846554) (xy 78.103984 -268.800326) (xy 77.96911 -268.934946)
			(xy 78.015338 -269.032482) (xy 78.051406 -269.068296)
		)
		(stroke
			(width 0)
			(type solid)
		)
		(fill yes)
		(layer "F.Cu")
		(net "M_A_CPU1_SA_CB<0>")
	)
	(gr_poly
		(pts
			(xy 78.243176 -280.44902) (xy 78.280514 -280.262076) (xy 78.188058 -280.206704) (xy 78.138274 -280.196798)
			(xy 78.086712 -280.454608) (xy 78.136496 -280.464514)
		)
		(stroke
			(width 0)
			(type solid)
		)
		(fill yes)
		(layer "F.Cu")
		(net "M_A_CPU1_SA_DQ<21>")
	)
	(gr_poly
		(pts
			(xy 78.24724 -275.186902) (xy 78.202536 -275.163026) (xy 78.095856 -275.147024) (xy 78.006194 -275.315172)
			(xy 78.078584 -275.394928) (xy 78.123542 -275.418804)
		)
		(stroke
			(width 0)
			(type solid)
		)
		(fill yes)
		(layer "F.Cu")
		(net "M_A_CPU1_SA_DQ<25>")
	)
	(gr_poly
		(pts
			(xy 78.248002 -278.088344) (xy 78.198218 -278.078438) (xy 78.091538 -278.094186) (xy 78.0542 -278.280876)
			(xy 78.146656 -278.336248) (xy 78.196694 -278.346154)
		)
		(stroke
			(width 0)
			(type solid)
		)
		(fill yes)
		(layer "F.Cu")
		(net "M_A_CPU1_SA_DQ<23>")
	)
	(gr_poly
		(pts
			(xy 78.290928 -264.299192) (xy 78.2447 -264.201656) (xy 78.208886 -264.165588) (xy 78.022958 -264.351516)
			(xy 78.058772 -264.387584) (xy 78.156308 -264.433812)
		)
		(stroke
			(width 0)
			(type solid)
		)
		(fill yes)
		(layer "F.Cu")
		(net "M_A_CPU1_SA_CB<7>")
	)
	(gr_poly
		(pts
			(xy 78.294738 -278.633174) (xy 78.332076 -278.446484) (xy 78.239366 -278.391112) (xy 78.189582 -278.381206)
			(xy 78.138274 -278.639016) (xy 78.188058 -278.648922)
		)
		(stroke
			(width 0)
			(type solid)
		)
		(fill yes)
		(layer "F.Cu")
		(net "M_A_CPU1_SA_DQ<23>")
	)
	(gr_poly
		(pts
			(xy 78.299564 -271.166844) (xy 78.263496 -271.13103) (xy 78.166214 -271.084802) (xy 78.03134 -271.219422)
			(xy 78.077822 -271.316958) (xy 78.113636 -271.352772)
		)
		(stroke
			(width 0)
			(type solid)
		)
		(fill yes)
		(layer "F.Cu")
		(net "M_A_CPU1_SA_DQ<31>")
	)
	(gr_poly
		(pts
			(xy 78.300326 -265.152632) (xy 78.254098 -265.05535) (xy 78.218284 -265.019282) (xy 78.032356 -265.20521)
			(xy 78.06817 -265.241024) (xy 78.165706 -265.287506)
		)
		(stroke
			(width 0)
			(type solid)
		)
		(fill yes)
		(layer "F.Cu")
		(net "M_A_CPU1_SA_CB<6>")
	)
	(gr_poly
		(pts
			(xy 78.301596 -224.948496) (xy 78.347824 -224.851214) (xy 78.213204 -224.71634) (xy 78.115668 -224.762568)
			(xy 78.079854 -224.798636) (xy 78.265782 -224.984564)
		)
		(stroke
			(width 0)
			(type solid)
		)
		(fill yes)
		(layer "F.Cu")
		(net "M_A_CPU1_SB_DQ<18>")
	)
	(gr_poly
		(pts
			(xy 78.305406 -267.735558) (xy 78.259178 -267.638276) (xy 78.223364 -267.602208) (xy 78.037436 -267.788136)
			(xy 78.07325 -267.824204) (xy 78.170786 -267.870432)
		)
		(stroke
			(width 0)
			(type solid)
		)
		(fill yes)
		(layer "F.Cu")
		(net "M_A_CPU1_SA_CB<3>")
	)
	(gr_poly
		(pts
			(xy 78.309216 -272.020792) (xy 78.273402 -271.984724) (xy 78.175866 -271.938496) (xy 78.041246 -272.07337)
			(xy 78.087474 -272.170652) (xy 78.123288 -272.20672)
		)
		(stroke
			(width 0)
			(type solid)
		)
		(fill yes)
		(layer "F.Cu")
		(net "M_A_CPU1_SA_DQ<30>")
	)
	(gr_poly
		(pts
			(xy 78.31074 -224.09531) (xy 78.356968 -223.997774) (xy 78.222348 -223.863154) (xy 78.124812 -223.909382)
			(xy 78.088998 -223.945196) (xy 78.274926 -224.131124)
		)
		(stroke
			(width 0)
			(type solid)
		)
		(fill yes)
		(layer "F.Cu")
		(net "M_A_CPU1_SB_DQ<19>")
	)
	(gr_poly
		(pts
			(xy 78.313534 -279.31872) (xy 78.263496 -279.308814) (xy 78.156816 -279.324562) (xy 78.119732 -279.511252)
			(xy 78.212188 -279.566624) (xy 78.261972 -279.57653)
		)
		(stroke
			(width 0)
			(type solid)
		)
		(fill yes)
		(layer "F.Cu")
		(net "M_A_CPU1_SA_DQ<21>")
	)
	(gr_poly
		(pts
			(xy 78.314804 -268.589252) (xy 78.268576 -268.491716) (xy 78.232508 -268.455902) (xy 78.046834 -268.641576)
			(xy 78.082648 -268.677644) (xy 78.180184 -268.723872)
		)
		(stroke
			(width 0)
			(type solid)
		)
		(fill yes)
		(layer "F.Cu")
		(net "M_A_CPU1_SA_CB<2>")
	)
	(gr_poly
		(pts
			(xy 78.331822 -232.423208) (xy 78.367636 -232.387394) (xy 78.181708 -232.201466) (xy 78.145894 -232.237534)
			(xy 78.099666 -232.334816) (xy 78.234286 -232.46969)
		)
		(stroke
			(width 0)
			(type solid)
		)
		(fill yes)
		(layer "F.Cu")
		(net "M_A_CPU1_SB_DQ<9>")
	)
	(gr_poly
		(pts
			(xy 78.337664 -226.724718) (xy 78.286864 -226.724718) (xy 78.185264 -226.760786) (xy 78.185264 -226.951286)
			(xy 78.286864 -226.987354) (xy 78.337664 -226.987354)
		)
		(stroke
			(width 0)
			(type solid)
		)
		(fill yes)
		(layer "F.Cu")
		(net "M_A_CPU1_SB_DQ<16>")
	)
	(gr_poly
		(pts
			(xy 78.337664 -226.127818) (xy 78.286864 -226.127818) (xy 78.185264 -226.163886) (xy 78.185264 -226.354386)
			(xy 78.286864 -226.390454) (xy 78.337664 -226.390454)
		)
		(stroke
			(width 0)
			(type solid)
		)
		(fill yes)
		(layer "F.Cu")
		(net "M_A_CPU1_SB_DQ<16>")
	)
	(gr_poly
		(pts
			(xy 78.340712 -286.319722) (xy 78.340712 -286.129222) (xy 78.239112 -286.093154) (xy 78.188312 -286.093154)
			(xy 78.188312 -286.356044) (xy 78.239112 -286.356044)
		)
		(stroke
			(width 0)
			(type solid)
		)
		(fill yes)
		(layer "F.Cu")
		(net "M_A_CPU1_SA_DQ<22>")
	)
	(gr_poly
		(pts
			(xy 78.340712 -285.722822) (xy 78.340712 -285.532322) (xy 78.239112 -285.496254) (xy 78.188312 -285.496254)
			(xy 78.188312 -285.759144) (xy 78.239112 -285.759144)
		)
		(stroke
			(width 0)
			(type solid)
		)
		(fill yes)
		(layer "F.Cu")
		(net "M_A_CPU1_SA_DQ<22>")
	)
	(gr_poly
		(pts
			(xy 78.340712 -285.125922) (xy 78.340712 -284.935422) (xy 78.239112 -284.899354) (xy 78.188312 -284.899354)
			(xy 78.188312 -285.162244) (xy 78.239112 -285.162244)
		)
		(stroke
			(width 0)
			(type solid)
		)
		(fill yes)
		(layer "F.Cu")
		(net "M_A_CPU1_SA_DQ<22>")
	)
	(gr_poly
		(pts
			(xy 78.340712 -284.529022) (xy 78.340712 -284.338522) (xy 78.239112 -284.302454) (xy 78.188312 -284.302454)
			(xy 78.188312 -284.565344) (xy 78.239112 -284.565344)
		)
		(stroke
			(width 0)
			(type solid)
		)
		(fill yes)
		(layer "F.Cu")
		(net "M_A_CPU1_SA_DQ<22>")
	)
	(gr_poly
		(pts
			(xy 78.340712 -283.932122) (xy 78.340712 -283.741622) (xy 78.239112 -283.705554) (xy 78.188312 -283.705554)
			(xy 78.188312 -283.968444) (xy 78.239112 -283.968444)
		)
		(stroke
			(width 0)
			(type solid)
		)
		(fill yes)
		(layer "F.Cu")
		(net "M_A_CPU1_SA_DQ<22>")
	)
	(gr_poly
		(pts
			(xy 78.340712 -283.335222) (xy 78.340712 -283.144722) (xy 78.239112 -283.108654) (xy 78.188312 -283.108654)
			(xy 78.188312 -283.371544) (xy 78.239112 -283.371544)
		)
		(stroke
			(width 0)
			(type solid)
		)
		(fill yes)
		(layer "F.Cu")
		(net "M_A_CPU1_SA_DQ<22>")
	)
	(gr_poly
		(pts
			(xy 78.340712 -282.738322) (xy 78.340712 -282.547822) (xy 78.239112 -282.511754) (xy 78.188312 -282.511754)
			(xy 78.188312 -282.774644) (xy 78.239112 -282.774644)
		)
		(stroke
			(width 0)
			(type solid)
		)
		(fill yes)
		(layer "F.Cu")
		(net "M_A_CPU1_SA_DQ<22>")
	)
	(gr_poly
		(pts
			(xy 78.340712 -282.141422) (xy 78.340712 -281.950922) (xy 78.239112 -281.914854) (xy 78.188312 -281.914854)
			(xy 78.188312 -282.177744) (xy 78.239112 -282.177744)
		)
		(stroke
			(width 0)
			(type solid)
		)
		(fill yes)
		(layer "F.Cu")
		(net "M_A_CPU1_SA_DQ<22>")
	)
	(gr_poly
		(pts
			(xy 78.360016 -279.86355) (xy 78.397354 -279.67686) (xy 78.304898 -279.621488) (xy 78.255114 -279.611582)
			(xy 78.203552 -279.869392) (xy 78.253336 -279.879298)
		)
		(stroke
			(width 0)
			(type solid)
		)
		(fill yes)
		(layer "F.Cu")
		(net "M_A_CPU1_SA_DQ<21>")
	)
	(gr_poly
		(pts
			(xy 78.36154 -249.270266) (xy 78.325472 -249.168666) (xy 78.134972 -249.168666) (xy 78.09865 -249.270266)
			(xy 78.09865 -249.321066) (xy 78.36154 -249.321066)
		)
		(stroke
			(width 0)
			(type solid)
		)
		(fill yes)
		(layer "F.Cu")
		(net "M_A_CPU1_SB_CA<0>")
	)
	(gr_poly
		(pts
			(xy 78.36154 -248.965212) (xy 78.325472 -248.863612) (xy 78.134972 -248.863612) (xy 78.09865 -248.965212)
			(xy 78.09865 -249.016012) (xy 78.36154 -249.016012)
		)
		(stroke
			(width 0)
			(type solid)
		)
		(fill yes)
		(layer "F.Cu")
		(net "M_A_CPU1_SB_CA<1>")
	)
	(gr_poly
		(pts
			(xy 78.36154 -248.660412) (xy 78.325472 -248.558812) (xy 78.134972 -248.558812) (xy 78.09865 -248.660412)
			(xy 78.09865 -248.711212) (xy 78.36154 -248.711212)
		)
		(stroke
			(width 0)
			(type solid)
		)
		(fill yes)
		(layer "F.Cu")
		(net "M_A_CPU1_SB_CA<2>")
	)
	(gr_poly
		(pts
			(xy 78.36154 -248.355612) (xy 78.325472 -248.254012) (xy 78.134972 -248.254012) (xy 78.09865 -248.355612)
			(xy 78.09865 -248.406412) (xy 78.36154 -248.406412)
		)
		(stroke
			(width 0)
			(type solid)
		)
		(fill yes)
		(layer "F.Cu")
		(net "M_A_CPU1_SB_CA<3>")
	)
	(gr_poly
		(pts
			(xy 78.36154 -248.050812) (xy 78.325472 -247.949212) (xy 78.134972 -247.949212) (xy 78.09865 -248.050812)
			(xy 78.09865 -248.101612) (xy 78.36154 -248.101612)
		)
		(stroke
			(width 0)
			(type solid)
		)
		(fill yes)
		(layer "F.Cu")
		(net "M_A_CPU1_SB_CA<4>")
	)
	(gr_poly
		(pts
			(xy 78.36154 -247.746012) (xy 78.325472 -247.644412) (xy 78.134972 -247.644412) (xy 78.09865 -247.746012)
			(xy 78.09865 -247.796812) (xy 78.36154 -247.796812)
		)
		(stroke
			(width 0)
			(type solid)
		)
		(fill yes)
		(layer "F.Cu")
		(net "M_A_CPU1_SB_CA<5>")
	)
	(gr_poly
		(pts
			(xy 78.36154 -247.441212) (xy 78.325472 -247.339612) (xy 78.134972 -247.339612) (xy 78.09865 -247.441212)
			(xy 78.09865 -247.492012) (xy 78.36154 -247.492012)
		)
		(stroke
			(width 0)
			(type solid)
		)
		(fill yes)
		(layer "F.Cu")
		(net "M_A_CPU1_SB_CA<6>")
	)
	(gr_poly
		(pts
			(xy 78.36154 -247.136412) (xy 78.325472 -247.034812) (xy 78.134972 -247.034812) (xy 78.09865 -247.136412)
			(xy 78.09865 -247.187212) (xy 78.36154 -247.187212)
		)
		(stroke
			(width 0)
			(type solid)
		)
		(fill yes)
		(layer "F.Cu")
		(net "M_A_CPU1_SB_PAR")
	)
	(gr_poly
		(pts
			(xy 78.36154 -246.831612) (xy 78.325472 -246.730012) (xy 78.134972 -246.730012) (xy 78.09865 -246.831612)
			(xy 78.09865 -246.882412) (xy 78.36154 -246.882412)
		)
		(stroke
			(width 0)
			(type solid)
		)
		(fill yes)
		(layer "F.Cu")
		(net "M_A_CPU1_SB_CS_N<2>")
	)
	(gr_poly
		(pts
			(xy 78.36154 -246.526812) (xy 78.325472 -246.425212) (xy 78.134972 -246.425212) (xy 78.09865 -246.526812)
			(xy 78.09865 -246.577612) (xy 78.36154 -246.577612)
		)
		(stroke
			(width 0)
			(type solid)
		)
		(fill yes)
		(layer "F.Cu")
		(net "M_A_CPU1_SB_CS_N<0>")
	)
	(gr_poly
		(pts
			(xy 78.36154 -246.222012) (xy 78.325472 -246.120412) (xy 78.134972 -246.120412) (xy 78.09865 -246.222012)
			(xy 78.09865 -246.272812) (xy 78.36154 -246.272812)
		)
		(stroke
			(width 0)
			(type solid)
		)
		(fill yes)
		(layer "F.Cu")
		(net "M_A_CPU1_SB_CS_N<3>")
	)
	(gr_poly
		(pts
			(xy 78.36154 -245.917212) (xy 78.325472 -245.815612) (xy 78.134972 -245.815612) (xy 78.09865 -245.917212)
			(xy 78.09865 -245.968012) (xy 78.36154 -245.968012)
		)
		(stroke
			(width 0)
			(type solid)
		)
		(fill yes)
		(layer "F.Cu")
		(net "M_A_CPU1_SB_CS_N<1>")
	)
	(gr_poly
		(pts
			(xy 78.369414 -229.873302) (xy 78.405482 -229.837488) (xy 78.219554 -229.65156) (xy 78.18374 -229.687374)
			(xy 78.137258 -229.78491) (xy 78.272132 -229.91953)
		)
		(stroke
			(width 0)
			(type solid)
		)
		(fill yes)
		(layer "F.Cu")
		(net "M_A_CPU1_SB_DQ<12>")
	)
	(gr_poly
		(pts
			(xy 78.378812 -280.54935) (xy 78.329028 -280.53919) (xy 78.222348 -280.554938) (xy 78.18501 -280.741628)
			(xy 78.27772 -280.797) (xy 78.327504 -280.806906)
		)
		(stroke
			(width 0)
			(type solid)
		)
		(fill yes)
		(layer "F.Cu")
		(net "M_A_CPU1_SA_DQ<22>")
	)
	(gr_poly
		(pts
			(xy 78.386432 -271.727168) (xy 78.340204 -271.629632) (xy 78.304136 -271.593818) (xy 78.118462 -271.779492)
			(xy 78.154276 -271.81556) (xy 78.251812 -271.861788)
		)
		(stroke
			(width 0)
			(type solid)
		)
		(fill yes)
		(layer "F.Cu")
		(net "M_A_CPU1_SA_DQ<29>")
	)
	(gr_poly
		(pts
			(xy 78.396084 -272.580862) (xy 78.349856 -272.483326) (xy 78.313788 -272.447512) (xy 78.12786 -272.63344)
			(xy 78.163928 -272.669254) (xy 78.26121 -272.715482)
		)
		(stroke
			(width 0)
			(type solid)
		)
		(fill yes)
		(layer "F.Cu")
		(net "M_A_CPU1_SA_DQ<28>")
	)
	(gr_poly
		(pts
			(xy 78.398878 -232.7783) (xy 78.445106 -232.680764) (xy 78.310486 -232.546144) (xy 78.21295 -232.592372)
			(xy 78.177136 -232.628186) (xy 78.363064 -232.814114)
		)
		(stroke
			(width 0)
			(type solid)
		)
		(fill yes)
		(layer "F.Cu")
		(net "M_A_CPU1_SB_DQ<10>")
	)
	(gr_poly
		(pts
			(xy 78.408276 -231.92486) (xy 78.454504 -231.827324) (xy 78.31963 -231.692704) (xy 78.222348 -231.738932)
			(xy 78.18628 -231.774746) (xy 78.372208 -231.960674)
		)
		(stroke
			(width 0)
			(type solid)
		)
		(fill yes)
		(layer "F.Cu")
		(net "M_A_CPU1_SB_DQ<11>")
	)
	(gr_poly
		(pts
			(xy 78.411578 -278.047958) (xy 78.448916 -277.861014) (xy 78.356206 -277.805642) (xy 78.306422 -277.795736)
			(xy 78.25486 -278.053546) (xy 78.304898 -278.063452)
		)
		(stroke
			(width 0)
			(type solid)
		)
		(fill yes)
		(layer "F.Cu")
		(net "M_A_CPU1_SA_DQ<23>")
	)
	(gr_poly
		(pts
			(xy 78.419706 -263.954768) (xy 78.383892 -263.9187) (xy 78.286356 -263.872472) (xy 78.151736 -264.007092)
			(xy 78.197964 -264.104628) (xy 78.234032 -264.140442)
		)
		(stroke
			(width 0)
			(type solid)
		)
		(fill yes)
		(layer "F.Cu")
		(net "M_A_CPU1_SA_CB<7>")
	)
	(gr_poly
		(pts
			(xy 78.425548 -281.09418) (xy 78.462886 -280.907236) (xy 78.370176 -280.851864) (xy 78.320392 -280.841958)
			(xy 78.269084 -281.099768) (xy 78.318868 -281.109674)
		)
		(stroke
			(width 0)
			(type solid)
		)
		(fill yes)
		(layer "F.Cu")
		(net "M_A_CPU1_SA_DQ<22>")
	)
	(gr_poly
		(pts
			(xy 78.429358 -264.808208) (xy 78.39329 -264.772394) (xy 78.296008 -264.726166) (xy 78.161134 -264.860786)
			(xy 78.207362 -264.958322) (xy 78.24343 -264.994136)
		)
		(stroke
			(width 0)
			(type solid)
		)
		(fill yes)
		(layer "F.Cu")
		(net "M_A_CPU1_SA_CB<6>")
	)
	(gr_poly
		(pts
			(xy 78.430374 -278.733504) (xy 78.38059 -278.723598) (xy 78.273656 -278.739092) (xy 78.236572 -278.926036)
			(xy 78.329028 -278.981408) (xy 78.378812 -278.991314)
		)
		(stroke
			(width 0)
			(type solid)
		)
		(fill yes)
		(layer "F.Cu")
		(net "M_A_CPU1_SA_DQ<21>")
	)
	(gr_poly
		(pts
			(xy 78.43393 -274.484846) (xy 78.398116 -274.448778) (xy 78.30058 -274.40255) (xy 78.16596 -274.537424)
			(xy 78.212188 -274.634706) (xy 78.248002 -274.670774)
		)
		(stroke
			(width 0)
			(type solid)
		)
		(fill yes)
		(layer "F.Cu")
		(net "M_A_CPU1_SA_DQ<27>")
	)
	(gr_poly
		(pts
			(xy 78.434438 -267.391134) (xy 78.39837 -267.35532) (xy 78.300834 -267.309092) (xy 78.166214 -267.443712)
			(xy 78.212442 -267.541248) (xy 78.24851 -267.577062)
		)
		(stroke
			(width 0)
			(type solid)
		)
		(fill yes)
		(layer "F.Cu")
		(net "M_A_CPU1_SA_CB<3>")
	)
	(gr_poly
		(pts
			(xy 78.440788 -225.231452) (xy 78.476602 -225.195384) (xy 78.290928 -225.00971) (xy 78.25486 -225.045524)
			(xy 78.208632 -225.14306) (xy 78.343252 -225.27768)
		)
		(stroke
			(width 0)
			(type solid)
		)
		(fill yes)
		(layer "F.Cu")
		(net "M_A_CPU1_SB_DQ<18>")
	)
	(gr_poly
		(pts
			(xy 78.443582 -268.244828) (xy 78.407768 -268.20876) (xy 78.310232 -268.162532) (xy 78.175612 -268.297406)
			(xy 78.22184 -268.394688) (xy 78.257654 -268.430756)
		)
		(stroke
			(width 0)
			(type solid)
		)
		(fill yes)
		(layer "F.Cu")
		(net "M_A_CPU1_SA_CB<2>")
	)
	(gr_poly
		(pts
			(xy 78.446122 -229.3747) (xy 78.49235 -229.277164) (xy 78.35773 -229.142544) (xy 78.260194 -229.188772)
			(xy 78.22438 -229.22484) (xy 78.410054 -229.410514)
		)
		(stroke
			(width 0)
			(type solid)
		)
		(fill yes)
		(layer "F.Cu")
		(net "M_A_CPU1_SB_DQ<14>")
	)
	(gr_poly
		(pts
			(xy 78.449932 -224.378012) (xy 78.486 -224.342198) (xy 78.300072 -224.15627) (xy 78.264258 -224.192084)
			(xy 78.217776 -224.28962) (xy 78.35265 -224.42424)
		)
		(stroke
			(width 0)
			(type solid)
		)
		(fill yes)
		(layer "F.Cu")
		(net "M_A_CPU1_SB_DQ<19>")
	)
	(gr_poly
		(pts
			(xy 78.476856 -279.278334) (xy 78.514194 -279.09139) (xy 78.421738 -279.036018) (xy 78.371954 -279.026112)
			(xy 78.320392 -279.283922) (xy 78.370176 -279.293828)
		)
		(stroke
			(width 0)
			(type solid)
		)
		(fill yes)
		(layer "F.Cu")
		(net "M_A_CPU1_SA_DQ<21>")
	)
	(gr_poly
		(pts
			(xy 78.480412 -276.367748) (xy 78.408022 -276.287992) (xy 78.363064 -276.264116) (xy 78.239112 -276.496018)
			(xy 78.28407 -276.519894) (xy 78.39075 -276.535896)
		)
		(stroke
			(width 0)
			(type solid)
		)
		(fill yes)
		(layer "F.Cu")
		(net "M_A_CPU1_SA_DQ<24>")
	)
	(gr_poly
		(pts
			(xy 78.490064 -227.249736) (xy 78.490064 -227.059236) (xy 78.388464 -227.022914) (xy 78.337664 -227.022914)
			(xy 78.337664 -227.286058) (xy 78.388464 -227.286058)
		)
		(stroke
			(width 0)
			(type solid)
		)
		(fill yes)
		(layer "F.Cu")
		(net "M_A_CPU1_SB_DQ<16>")
	)
	(gr_poly
		(pts
			(xy 78.490064 -226.652836) (xy 78.490064 -226.462336) (xy 78.388464 -226.426014) (xy 78.337664 -226.426014)
			(xy 78.337664 -226.689158) (xy 78.388464 -226.689158)
		)
		(stroke
			(width 0)
			(type solid)
		)
		(fill yes)
		(layer "F.Cu")
		(net "M_A_CPU1_SB_DQ<16>")
	)
	(gr_poly
		(pts
			(xy 78.490064 -226.055936) (xy 78.490064 -225.865436) (xy 78.388464 -225.829114) (xy 78.337664 -225.829114)
			(xy 78.337664 -226.092258) (xy 78.388464 -226.092258)
		)
		(stroke
			(width 0)
			(type solid)
		)
		(fill yes)
		(layer "F.Cu")
		(net "M_A_CPU1_SB_DQ<16>")
	)
	(gr_poly
		(pts
			(xy 78.492858 -275.697696) (xy 78.420468 -275.61794) (xy 78.37551 -275.59381) (xy 78.251558 -275.825712)
			(xy 78.296516 -275.849842) (xy 78.403196 -275.86559)
		)
		(stroke
			(width 0)
			(type solid)
		)
		(fill yes)
		(layer "F.Cu")
		(net "M_A_CPU1_SA_DQ<26>")
	)
	(gr_poly
		(pts
			(xy 78.493112 -286.988504) (xy 78.442312 -286.988504) (xy 78.340712 -287.024826) (xy 78.340712 -287.215326)
			(xy 78.442312 -287.251394) (xy 78.493112 -287.251394)
		)
		(stroke
			(width 0)
			(type solid)
		)
		(fill yes)
		(layer "F.Cu")
		(net "M_A_CPU1_SA_DQ<20>")
	)
	(gr_poly
		(pts
			(xy 78.493112 -286.391604) (xy 78.442312 -286.391604) (xy 78.340712 -286.427926) (xy 78.340712 -286.618426)
			(xy 78.442312 -286.654494) (xy 78.493112 -286.654494)
		)
		(stroke
			(width 0)
			(type solid)
		)
		(fill yes)
		(layer "F.Cu")
		(net "M_A_CPU1_SA_DQ<20>")
	)
	(gr_poly
		(pts
			(xy 78.493112 -285.794704) (xy 78.442312 -285.794704) (xy 78.340712 -285.831026) (xy 78.340712 -286.021526)
			(xy 78.442312 -286.057594) (xy 78.493112 -286.057594)
		)
		(stroke
			(width 0)
			(type solid)
		)
		(fill yes)
		(layer "F.Cu")
		(net "M_A_CPU1_SA_DQ<20>")
	)
	(gr_poly
		(pts
			(xy 78.493112 -285.197804) (xy 78.442312 -285.197804) (xy 78.340712 -285.234126) (xy 78.340712 -285.424626)
			(xy 78.442312 -285.460694) (xy 78.493112 -285.460694)
		)
		(stroke
			(width 0)
			(type solid)
		)
		(fill yes)
		(layer "F.Cu")
		(net "M_A_CPU1_SA_DQ<20>")
	)
	(gr_poly
		(pts
			(xy 78.493112 -284.600904) (xy 78.442312 -284.600904) (xy 78.340712 -284.637226) (xy 78.340712 -284.827726)
			(xy 78.442312 -284.863794) (xy 78.493112 -284.863794)
		)
		(stroke
			(width 0)
			(type solid)
		)
		(fill yes)
		(layer "F.Cu")
		(net "M_A_CPU1_SA_DQ<20>")
	)
	(gr_poly
		(pts
			(xy 78.493112 -284.004004) (xy 78.442312 -284.004004) (xy 78.340712 -284.040326) (xy 78.340712 -284.230826)
			(xy 78.442312 -284.266894) (xy 78.493112 -284.266894)
		)
		(stroke
			(width 0)
			(type solid)
		)
		(fill yes)
		(layer "F.Cu")
		(net "M_A_CPU1_SA_DQ<20>")
	)
	(gr_poly
		(pts
			(xy 78.493112 -283.407104) (xy 78.442312 -283.407104) (xy 78.340712 -283.443426) (xy 78.340712 -283.633926)
			(xy 78.442312 -283.669994) (xy 78.493112 -283.669994)
		)
		(stroke
			(width 0)
			(type solid)
		)
		(fill yes)
		(layer "F.Cu")
		(net "M_A_CPU1_SA_DQ<20>")
	)
	(gr_poly
		(pts
			(xy 78.493112 -282.810204) (xy 78.442312 -282.810204) (xy 78.340712 -282.846526) (xy 78.340712 -283.037026)
			(xy 78.442312 -283.073094) (xy 78.493112 -283.073094)
		)
		(stroke
			(width 0)
			(type solid)
		)
		(fill yes)
		(layer "F.Cu")
		(net "M_A_CPU1_SA_DQ<20>")
	)
	(gr_poly
		(pts
			(xy 78.493112 -282.213304) (xy 78.442312 -282.213304) (xy 78.340712 -282.249626) (xy 78.340712 -282.440126)
			(xy 78.442312 -282.476194) (xy 78.493112 -282.476194)
		)
		(stroke
			(width 0)
			(type solid)
		)
		(fill yes)
		(layer "F.Cu")
		(net "M_A_CPU1_SA_DQ<20>")
	)
	(gr_poly
		(pts
			(xy 78.495906 -279.96388) (xy 78.446122 -279.953974) (xy 78.339188 -279.969468) (xy 78.302104 -280.156412)
			(xy 78.39456 -280.211784) (xy 78.444344 -280.22169)
		)
		(stroke
			(width 0)
			(type solid)
		)
		(fill yes)
		(layer "F.Cu")
		(net "M_A_CPU1_SA_DQ<22>")
	)
	(gr_poly
		(pts
			(xy 78.50378 -276.000718) (xy 78.459076 -275.976842) (xy 78.352396 -275.96084) (xy 78.26248 -276.128988)
			(xy 78.335124 -276.208744) (xy 78.379828 -276.23262)
		)
		(stroke
			(width 0)
			(type solid)
		)
		(fill yes)
		(layer "F.Cu")
		(net "M_A_CPU1_SA_DQ<24>")
	)
	(gr_poly
		(pts
			(xy 78.506828 -264.514838) (xy 78.460346 -264.417302) (xy 78.424532 -264.381488) (xy 78.238604 -264.567416)
			(xy 78.274672 -264.60323) (xy 78.371954 -264.649458)
		)
		(stroke
			(width 0)
			(type solid)
		)
		(fill yes)
		(layer "F.Cu")
		(net "M_A_CPU1_SA_CB<5>")
	)
	(gr_poly
		(pts
			(xy 78.51521 -271.382744) (xy 78.479396 -271.346676) (xy 78.38186 -271.300448) (xy 78.24724 -271.435322)
			(xy 78.293468 -271.532604) (xy 78.329282 -271.568672)
		)
		(stroke
			(width 0)
			(type solid)
		)
		(fill yes)
		(layer "F.Cu")
		(net "M_A_CPU1_SA_DQ<29>")
	)
	(gr_poly
		(pts
			(xy 78.516226 -265.368532) (xy 78.469998 -265.270996) (xy 78.43393 -265.235182) (xy 78.248002 -265.42111)
			(xy 78.28407 -265.456924) (xy 78.381352 -265.503152)
		)
		(stroke
			(width 0)
			(type solid)
		)
		(fill yes)
		(layer "F.Cu")
		(net "M_A_CPU1_SA_CB<4>")
	)
	(gr_poly
		(pts
			(xy 78.51648 -275.330666) (xy 78.471776 -275.30679) (xy 78.365096 -275.290788) (xy 78.27518 -275.458682)
			(xy 78.347824 -275.538692) (xy 78.392528 -275.562568)
		)
		(stroke
			(width 0)
			(type solid)
		)
		(fill yes)
		(layer "F.Cu")
		(net "M_A_CPU1_SA_DQ<26>")
	)
	(gr_poly
		(pts
			(xy 78.517242 -224.73285) (xy 78.56347 -224.635568) (xy 78.42885 -224.500694) (xy 78.331314 -224.546922)
			(xy 78.2955 -224.58299) (xy 78.481428 -224.768918)
		)
		(stroke
			(width 0)
			(type solid)
		)
		(fill yes)
		(layer "F.Cu")
		(net "M_A_CPU1_SB_DQ<17>")
	)
	(gr_poly
		(pts
			(xy 78.521052 -267.951204) (xy 78.474824 -267.853922) (xy 78.43901 -267.817854) (xy 78.253082 -268.003782)
			(xy 78.288896 -268.03985) (xy 78.386432 -268.086078)
		)
		(stroke
			(width 0)
			(type solid)
		)
		(fill yes)
		(layer "F.Cu")
		(net "M_A_CPU1_SA_CB<1>")
	)
	(gr_poly
		(pts
			(xy 78.524862 -272.236438) (xy 78.489048 -272.20037) (xy 78.391512 -272.154142) (xy 78.256892 -272.289016)
			(xy 78.30312 -272.386298) (xy 78.338934 -272.422366)
		)
		(stroke
			(width 0)
			(type solid)
		)
		(fill yes)
		(layer "F.Cu")
		(net "M_A_CPU1_SA_DQ<28>")
	)
	(gr_poly
		(pts
			(xy 78.53045 -268.804898) (xy 78.484222 -268.707362) (xy 78.448154 -268.671548) (xy 78.26248 -268.857222)
			(xy 78.298294 -268.89329) (xy 78.39583 -268.939518)
		)
		(stroke
			(width 0)
			(type solid)
		)
		(fill yes)
		(layer "F.Cu")
		(net "M_A_CPU1_SA_CB<0>")
	)
	(gr_poly
		(pts
			(xy 78.53807 -233.061002) (xy 78.574138 -233.025188) (xy 78.38821 -232.83926) (xy 78.352142 -232.875074)
			(xy 78.305914 -232.97261) (xy 78.440788 -233.10723)
		)
		(stroke
			(width 0)
			(type solid)
		)
		(fill yes)
		(layer "F.Cu")
		(net "M_A_CPU1_SB_DQ<10>")
	)
	(gr_poly
		(pts
			(xy 78.542388 -280.50871) (xy 78.579726 -280.32202) (xy 78.48727 -280.266394) (xy 78.437486 -280.256488)
			(xy 78.385924 -280.514298) (xy 78.435708 -280.524204)
		)
		(stroke
			(width 0)
			(type solid)
		)
		(fill yes)
		(layer "F.Cu")
		(net "M_A_CPU1_SA_DQ<22>")
	)
	(gr_poly
		(pts
			(xy 78.547214 -278.148034) (xy 78.49743 -278.138128) (xy 78.39075 -278.153876) (xy 78.353412 -278.340566)
			(xy 78.445868 -278.395938) (xy 78.495652 -278.405844)
		)
		(stroke
			(width 0)
			(type solid)
		)
		(fill yes)
		(layer "F.Cu")
		(net "M_A_CPU1_SA_DQ<21>")
	)
	(gr_poly
		(pts
			(xy 78.547468 -232.207562) (xy 78.583282 -232.171748) (xy 78.397354 -231.98582) (xy 78.36154 -232.021888)
			(xy 78.315312 -232.11917) (xy 78.449932 -232.254044)
		)
		(stroke
			(width 0)
			(type solid)
		)
		(fill yes)
		(layer "F.Cu")
		(net "M_A_CPU1_SB_DQ<11>")
	)
	(gr_poly
		(pts
			(xy 78.585314 -229.657656) (xy 78.621128 -229.621588) (xy 78.4352 -229.43566) (xy 78.399386 -229.471728)
			(xy 78.353158 -229.56901) (xy 78.487778 -229.703884)
		)
		(stroke
			(width 0)
			(type solid)
		)
		(fill yes)
		(layer "F.Cu")
		(net "M_A_CPU1_SB_DQ<14>")
	)
	(gr_poly
		(pts
			(xy 78.59268 -271.08912) (xy 78.546452 -270.991838) (xy 78.510638 -270.95577) (xy 78.32471 -271.141698)
			(xy 78.360524 -271.177766) (xy 78.45806 -271.223994)
		)
		(stroke
			(width 0)
			(type solid)
		)
		(fill yes)
		(layer "F.Cu")
		(net "M_A_CPU1_SA_DQ<31>")
	)
	(gr_poly
		(pts
			(xy 78.593696 -278.692864) (xy 78.631034 -278.506174) (xy 78.538578 -278.450802) (xy 78.488794 -278.440896)
			(xy 78.437232 -278.698706) (xy 78.487016 -278.708612)
		)
		(stroke
			(width 0)
			(type solid)
		)
		(fill yes)
		(layer "F.Cu")
		(net "M_A_CPU1_SA_DQ<21>")
	)
	(gr_poly
		(pts
			(xy 78.594458 -228.804216) (xy 78.630526 -228.768402) (xy 78.444598 -228.582474) (xy 78.40853 -228.618288)
			(xy 78.362302 -228.715824) (xy 78.497176 -228.850444)
		)
		(stroke
			(width 0)
			(type solid)
		)
		(fill yes)
		(layer "F.Cu")
		(net "M_A_CPU1_SB_DQ<15>")
	)
	(gr_poly
		(pts
			(xy 78.602332 -271.943068) (xy 78.556104 -271.845532) (xy 78.52029 -271.809718) (xy 78.334362 -271.995646)
			(xy 78.37043 -272.03146) (xy 78.467712 -272.077688)
		)
		(stroke
			(width 0)
			(type solid)
		)
		(fill yes)
		(layer "F.Cu")
		(net "M_A_CPU1_SA_DQ<30>")
	)
	(gr_poly
		(pts
			(xy 78.60538 -233.41584) (xy 78.651608 -233.318558) (xy 78.516988 -233.183684) (xy 78.419452 -233.229912)
			(xy 78.383638 -233.26598) (xy 78.569566 -233.451908)
		)
		(stroke
			(width 0)
			(type solid)
		)
		(fill yes)
		(layer "F.Cu")
		(net "M_A_CPU1_SB_DQ<8>")
	)
	(gr_poly
		(pts
			(xy 78.612746 -279.378664) (xy 78.562962 -279.368504) (xy 78.456282 -279.384252) (xy 78.418944 -279.570942)
			(xy 78.5114 -279.626314) (xy 78.561184 -279.636474)
		)
		(stroke
			(width 0)
			(type solid)
		)
		(fill yes)
		(layer "F.Cu")
		(net "M_A_CPU1_SA_DQ<22>")
	)
	(gr_poly
		(pts
			(xy 78.614524 -232.562654) (xy 78.660752 -232.465118) (xy 78.526132 -232.330498) (xy 78.428596 -232.376726)
			(xy 78.392782 -232.41254) (xy 78.57871 -232.598468)
		)
		(stroke
			(width 0)
			(type solid)
		)
		(fill yes)
		(layer "F.Cu")
		(net "M_A_CPU1_SB_DQ<9>")
	)
	(gr_poly
		(pts
			(xy 78.635606 -264.170414) (xy 78.599538 -264.1346) (xy 78.502256 -264.088372) (xy 78.367636 -264.222992)
			(xy 78.413864 -264.320528) (xy 78.449678 -264.356342)
		)
		(stroke
			(width 0)
			(type solid)
		)
		(fill yes)
		(layer "F.Cu")
		(net "M_A_CPU1_SA_CB<5>")
	)
	(gr_poly
		(pts
			(xy 78.642464 -226.724718) (xy 78.591664 -226.724718) (xy 78.490064 -226.760786) (xy 78.490064 -226.951286)
			(xy 78.591664 -226.987354) (xy 78.642464 -226.987354)
		)
		(stroke
			(width 0)
			(type solid)
		)
		(fill yes)
		(layer "F.Cu")
		(net "M_A_CPU1_SB_DQ<18>")
	)
	(gr_poly
		(pts
			(xy 78.642464 -226.127818) (xy 78.591664 -226.127818) (xy 78.490064 -226.163886) (xy 78.490064 -226.354386)
			(xy 78.591664 -226.390454) (xy 78.642464 -226.390454)
		)
		(stroke
			(width 0)
			(type solid)
		)
		(fill yes)
		(layer "F.Cu")
		(net "M_A_CPU1_SB_DQ<18>")
	)
	(gr_poly
		(pts
			(xy 78.642464 -225.530918) (xy 78.591664 -225.530918) (xy 78.490064 -225.566986) (xy 78.490064 -225.757486)
			(xy 78.591664 -225.793554) (xy 78.642464 -225.793554)
		)
		(stroke
			(width 0)
			(type solid)
		)
		(fill yes)
		(layer "F.Cu")
		(net "M_A_CPU1_SB_DQ<18>")
	)
	(gr_poly
		(pts
			(xy 78.645004 -265.024108) (xy 78.60919 -264.98804) (xy 78.511654 -264.941812) (xy 78.377034 -265.076686)
			(xy 78.423262 -265.173968) (xy 78.459076 -265.210036)
		)
		(stroke
			(width 0)
			(type solid)
		)
		(fill yes)
		(layer "F.Cu")
		(net "M_A_CPU1_SA_CB<4>")
	)
	(gr_poly
		(pts
			(xy 78.645512 -287.513522) (xy 78.645512 -287.323022) (xy 78.543912 -287.286954) (xy 78.493112 -287.286954)
			(xy 78.493112 -287.549844) (xy 78.543912 -287.549844)
		)
		(stroke
			(width 0)
			(type solid)
		)
		(fill yes)
		(layer "F.Cu")
		(net "M_A_CPU1_SA_DQ<20>")
	)
	(gr_poly
		(pts
			(xy 78.645512 -286.916622) (xy 78.645512 -286.726122) (xy 78.543912 -286.690054) (xy 78.493112 -286.690054)
			(xy 78.493112 -286.952944) (xy 78.543912 -286.952944)
		)
		(stroke
			(width 0)
			(type solid)
		)
		(fill yes)
		(layer "F.Cu")
		(net "M_A_CPU1_SA_DQ<20>")
	)
	(gr_poly
		(pts
			(xy 78.645512 -286.319722) (xy 78.645512 -286.129222) (xy 78.543912 -286.093154) (xy 78.493112 -286.093154)
			(xy 78.493112 -286.356044) (xy 78.543912 -286.356044)
		)
		(stroke
			(width 0)
			(type solid)
		)
		(fill yes)
		(layer "F.Cu")
		(net "M_A_CPU1_SA_DQ<20>")
	)
	(gr_poly
		(pts
			(xy 78.645512 -285.722822) (xy 78.645512 -285.532322) (xy 78.543912 -285.496254) (xy 78.493112 -285.496254)
			(xy 78.493112 -285.759144) (xy 78.543912 -285.759144)
		)
		(stroke
			(width 0)
			(type solid)
		)
		(fill yes)
		(layer "F.Cu")
		(net "M_A_CPU1_SA_DQ<20>")
	)
	(gr_poly
		(pts
			(xy 78.645512 -285.125922) (xy 78.645512 -284.935422) (xy 78.543912 -284.899354) (xy 78.493112 -284.899354)
			(xy 78.493112 -285.162244) (xy 78.543912 -285.162244)
		)
		(stroke
			(width 0)
			(type solid)
		)
		(fill yes)
		(layer "F.Cu")
		(net "M_A_CPU1_SA_DQ<20>")
	)
	(gr_poly
		(pts
			(xy 78.645512 -284.529022) (xy 78.645512 -284.338522) (xy 78.543912 -284.302454) (xy 78.493112 -284.302454)
			(xy 78.493112 -284.565344) (xy 78.543912 -284.565344)
		)
		(stroke
			(width 0)
			(type solid)
		)
		(fill yes)
		(layer "F.Cu")
		(net "M_A_CPU1_SA_DQ<20>")
	)
	(gr_poly
		(pts
			(xy 78.645512 -283.932122) (xy 78.645512 -283.741622) (xy 78.543912 -283.705554) (xy 78.493112 -283.705554)
			(xy 78.493112 -283.968444) (xy 78.543912 -283.968444)
		)
		(stroke
			(width 0)
			(type solid)
		)
		(fill yes)
		(layer "F.Cu")
		(net "M_A_CPU1_SA_DQ<20>")
	)
	(gr_poly
		(pts
			(xy 78.645512 -283.335222) (xy 78.645512 -283.144722) (xy 78.543912 -283.108654) (xy 78.493112 -283.108654)
			(xy 78.493112 -283.371544) (xy 78.543912 -283.371544)
		)
		(stroke
			(width 0)
			(type solid)
		)
		(fill yes)
		(layer "F.Cu")
		(net "M_A_CPU1_SA_DQ<20>")
	)
	(gr_poly
		(pts
			(xy 78.645512 -282.738322) (xy 78.645512 -282.547822) (xy 78.543912 -282.511754) (xy 78.493112 -282.511754)
			(xy 78.493112 -282.774644) (xy 78.543912 -282.774644)
		)
		(stroke
			(width 0)
			(type solid)
		)
		(fill yes)
		(layer "F.Cu")
		(net "M_A_CPU1_SA_DQ<20>")
	)
	(gr_poly
		(pts
			(xy 78.645512 -282.141422) (xy 78.645512 -281.950922) (xy 78.543912 -281.914854) (xy 78.493112 -281.914854)
			(xy 78.493112 -282.177744) (xy 78.543912 -282.177744)
		)
		(stroke
			(width 0)
			(type solid)
		)
		(fill yes)
		(layer "F.Cu")
		(net "M_A_CPU1_SA_DQ<20>")
	)
	(gr_poly
		(pts
			(xy 78.64983 -274.700746) (xy 78.614016 -274.664678) (xy 78.51648 -274.61845) (xy 78.38186 -274.753324)
			(xy 78.428088 -274.850606) (xy 78.463902 -274.886674)
		)
		(stroke
			(width 0)
			(type solid)
		)
		(fill yes)
		(layer "F.Cu")
		(net "M_A_CPU1_SA_DQ<25>")
	)
	(gr_poly
		(pts
			(xy 78.650084 -267.60678) (xy 78.614016 -267.570966) (xy 78.51648 -267.524738) (xy 78.38186 -267.659358)
			(xy 78.428088 -267.756894) (xy 78.464156 -267.792708)
		)
		(stroke
			(width 0)
			(type solid)
		)
		(fill yes)
		(layer "F.Cu")
		(net "M_A_CPU1_SA_CB<1>")
	)
	(gr_poly
		(pts
			(xy 78.65237 -230.012494) (xy 78.698598 -229.915212) (xy 78.563978 -229.780338) (xy 78.466442 -229.826566)
			(xy 78.430628 -229.862634) (xy 78.616556 -230.048562)
		)
		(stroke
			(width 0)
			(type solid)
		)
		(fill yes)
		(layer "F.Cu")
		(net "M_A_CPU1_SB_DQ<12>")
	)
	(gr_poly
		(pts
			(xy 78.656434 -225.015806) (xy 78.692248 -224.979738) (xy 78.506574 -224.794064) (xy 78.470506 -224.829878)
			(xy 78.424278 -224.927414) (xy 78.558898 -225.062034)
		)
		(stroke
			(width 0)
			(type solid)
		)
		(fill yes)
		(layer "F.Cu")
		(net "M_A_CPU1_SB_DQ<17>")
	)
	(gr_poly
		(pts
			(xy 78.659228 -279.923494) (xy 78.696312 -279.73655) (xy 78.603856 -279.681178) (xy 78.554072 -279.671272)
			(xy 78.50251 -279.929082) (xy 78.552294 -279.938988)
		)
		(stroke
			(width 0)
			(type solid)
		)
		(fill yes)
		(layer "F.Cu")
		(net "M_A_CPU1_SA_DQ<22>")
	)
	(gr_poly
		(pts
			(xy 78.659228 -268.460474) (xy 78.623414 -268.424406) (xy 78.525878 -268.378178) (xy 78.391258 -268.513052)
			(xy 78.437486 -268.610334) (xy 78.4733 -268.646402)
		)
		(stroke
			(width 0)
			(type solid)
		)
		(fill yes)
		(layer "F.Cu")
		(net "M_A_CPU1_SA_CB<0>")
	)
	(gr_poly
		(pts
			(xy 78.65999 -249.371866) (xy 78.65999 -249.321066) (xy 78.3971 -249.321066) (xy 78.3971 -249.371866)
			(xy 78.433168 -249.473466) (xy 78.623668 -249.473466)
		)
		(stroke
			(width 0)
			(type solid)
		)
		(fill yes)
		(layer "F.Cu")
		(net "M_A_CPU1_SB_CA<0>")
	)
	(gr_poly
		(pts
			(xy 78.65999 -249.066812) (xy 78.65999 -249.016012) (xy 78.3971 -249.016012) (xy 78.3971 -249.066812)
			(xy 78.433168 -249.168412) (xy 78.623668 -249.168412)
		)
		(stroke
			(width 0)
			(type solid)
		)
		(fill yes)
		(layer "F.Cu")
		(net "M_A_CPU1_SB_CA<1>")
	)
	(gr_poly
		(pts
			(xy 78.65999 -248.762012) (xy 78.65999 -248.711212) (xy 78.3971 -248.711212) (xy 78.3971 -248.762012)
			(xy 78.433168 -248.863612) (xy 78.623668 -248.863612)
		)
		(stroke
			(width 0)
			(type solid)
		)
		(fill yes)
		(layer "F.Cu")
		(net "M_A_CPU1_SB_CA<2>")
	)
	(gr_poly
		(pts
			(xy 78.65999 -248.457212) (xy 78.65999 -248.406412) (xy 78.3971 -248.406412) (xy 78.3971 -248.457212)
			(xy 78.433168 -248.558812) (xy 78.623668 -248.558812)
		)
		(stroke
			(width 0)
			(type solid)
		)
		(fill yes)
		(layer "F.Cu")
		(net "M_A_CPU1_SB_CA<3>")
	)
	(gr_poly
		(pts
			(xy 78.65999 -248.152412) (xy 78.65999 -248.101612) (xy 78.3971 -248.101612) (xy 78.3971 -248.152412)
			(xy 78.433168 -248.254012) (xy 78.623668 -248.254012)
		)
		(stroke
			(width 0)
			(type solid)
		)
		(fill yes)
		(layer "F.Cu")
		(net "M_A_CPU1_SB_CA<4>")
	)
	(gr_poly
		(pts
			(xy 78.65999 -247.847612) (xy 78.65999 -247.796812) (xy 78.3971 -247.796812) (xy 78.3971 -247.847612)
			(xy 78.433168 -247.949212) (xy 78.623668 -247.949212)
		)
		(stroke
			(width 0)
			(type solid)
		)
		(fill yes)
		(layer "F.Cu")
		(net "M_A_CPU1_SB_CA<5>")
	)
	(gr_poly
		(pts
			(xy 78.65999 -247.542812) (xy 78.65999 -247.492012) (xy 78.3971 -247.492012) (xy 78.3971 -247.542812)
			(xy 78.433168 -247.644412) (xy 78.623668 -247.644412)
		)
		(stroke
			(width 0)
			(type solid)
		)
		(fill yes)
		(layer "F.Cu")
		(net "M_A_CPU1_SB_CA<6>")
	)
	(gr_poly
		(pts
			(xy 78.65999 -247.238012) (xy 78.65999 -247.187212) (xy 78.3971 -247.187212) (xy 78.3971 -247.238012)
			(xy 78.433168 -247.339612) (xy 78.623668 -247.339612)
		)
		(stroke
			(width 0)
			(type solid)
		)
		(fill yes)
		(layer "F.Cu")
		(net "M_A_CPU1_SB_PAR")
	)
	(gr_poly
		(pts
			(xy 78.65999 -246.933212) (xy 78.65999 -246.882412) (xy 78.3971 -246.882412) (xy 78.3971 -246.933212)
			(xy 78.433168 -247.034812) (xy 78.623668 -247.034812)
		)
		(stroke
			(width 0)
			(type solid)
		)
		(fill yes)
		(layer "F.Cu")
		(net "M_A_CPU1_SB_CS_N<2>")
	)
	(gr_poly
		(pts
			(xy 78.65999 -246.628412) (xy 78.65999 -246.577612) (xy 78.3971 -246.577612) (xy 78.3971 -246.628412)
			(xy 78.433168 -246.730012) (xy 78.623668 -246.730012)
		)
		(stroke
			(width 0)
			(type solid)
		)
		(fill yes)
		(layer "F.Cu")
		(net "M_A_CPU1_SB_CS_N<0>")
	)
	(gr_poly
		(pts
			(xy 78.65999 -246.323612) (xy 78.65999 -246.272812) (xy 78.3971 -246.272812) (xy 78.3971 -246.323612)
			(xy 78.433168 -246.425212) (xy 78.623668 -246.425212)
		)
		(stroke
			(width 0)
			(type solid)
		)
		(fill yes)
		(layer "F.Cu")
		(net "M_A_CPU1_SB_CS_N<3>")
	)
	(gr_poly
		(pts
			(xy 78.65999 -246.018812) (xy 78.65999 -245.968012) (xy 78.3971 -245.968012) (xy 78.3971 -246.018812)
			(xy 78.433168 -246.120412) (xy 78.623668 -246.120412)
		)
		(stroke
			(width 0)
			(type solid)
		)
		(fill yes)
		(layer "F.Cu")
		(net "M_A_CPU1_SB_CS_N<1>")
	)
	(gr_poly
		(pts
			(xy 78.661768 -229.159054) (xy 78.707996 -229.061518) (xy 78.573376 -228.926898) (xy 78.47584 -228.973126)
			(xy 78.440026 -229.009194) (xy 78.6257 -229.194868)
		)
		(stroke
			(width 0)
			(type solid)
		)
		(fill yes)
		(layer "F.Cu")
		(net "M_A_CPU1_SB_DQ<13>")
	)
	(gr_poly
		(pts
			(xy 78.671674 -227.889816) (xy 78.717902 -227.79228) (xy 78.583282 -227.65766) (xy 78.485746 -227.703888)
			(xy 78.449932 -227.739702) (xy 78.63586 -227.92563)
		)
		(stroke
			(width 0)
			(type solid)
		)
		(fill yes)
		(layer "F.Cu")
		(net "M_A_CPU1_SB_DQ<16>")
	)
	(gr_poly
		(pts
			(xy 78.678278 -280.608786) (xy 78.628494 -280.59888) (xy 78.52156 -280.614628) (xy 78.484222 -280.801318)
			(xy 78.576932 -280.85669) (xy 78.626716 -280.866596)
		)
		(stroke
			(width 0)
			(type solid)
		)
		(fill yes)
		(layer "F.Cu")
		(net "M_A_CPU1_SA_DQ<20>")
	)
	(gr_poly
		(pts
			(xy 78.692756 -256.570226) (xy 78.656688 -256.468626) (xy 78.466188 -256.468626) (xy 78.429866 -256.570226)
			(xy 78.429866 -256.621026) (xy 78.692756 -256.621026)
		)
		(stroke
			(width 0)
			(type solid)
		)
		(fill yes)
		(layer "F.Cu")
		(net "M_A_CPU1_SA_CA<6>")
	)
	(gr_poly
		(pts
			(xy 78.692756 -256.265426) (xy 78.656688 -256.163826) (xy 78.466188 -256.163826) (xy 78.429866 -256.265426)
			(xy 78.429866 -256.316226) (xy 78.692756 -256.316226)
		)
		(stroke
			(width 0)
			(type solid)
		)
		(fill yes)
		(layer "F.Cu")
		(net "M_A_CPU1_SA_PAR")
	)
	(gr_poly
		(pts
			(xy 78.71079 -278.107648) (xy 78.747874 -277.920704) (xy 78.655418 -277.865332) (xy 78.605634 -277.855426)
			(xy 78.554072 -278.113236) (xy 78.603856 -278.123142)
		)
		(stroke
			(width 0)
			(type solid)
		)
		(fill yes)
		(layer "F.Cu")
		(net "M_A_CPU1_SA_DQ<21>")
	)
	(gr_poly
		(pts
			(xy 78.713076 -263.877044) (xy 78.666848 -263.779508) (xy 78.63078 -263.743694) (xy 78.444852 -263.929622)
			(xy 78.48092 -263.965436) (xy 78.578202 -264.011664)
		)
		(stroke
			(width 0)
			(type solid)
		)
		(fill yes)
		(layer "F.Cu")
		(net "M_A_CPU1_SA_CB<7>")
	)
	(gr_poly
		(pts
			(xy 78.714854 -277.19655) (xy 78.642464 -277.116794) (xy 78.59776 -277.092918) (xy 78.473554 -277.324566)
			(xy 78.518512 -277.348442) (xy 78.624938 -277.364698)
		)
		(stroke
			(width 0)
			(type solid)
		)
		(fill yes)
		(layer "F.Cu")
		(net "M_A_CPU1_SA_DQ<23>")
	)
	(gr_poly
		(pts
			(xy 78.721712 -270.744696) (xy 78.685644 -270.708882) (xy 78.588108 -270.662654) (xy 78.453488 -270.797274)
			(xy 78.499716 -270.89481) (xy 78.535784 -270.930624)
		)
		(stroke
			(width 0)
			(type solid)
		)
		(fill yes)
		(layer "F.Cu")
		(net "M_A_CPU1_SA_DQ<31>")
	)
	(gr_poly
		(pts
			(xy 78.722474 -264.730738) (xy 78.676246 -264.633202) (xy 78.640432 -264.597134) (xy 78.454504 -264.783062)
			(xy 78.490318 -264.81913) (xy 78.587854 -264.865358)
		)
		(stroke
			(width 0)
			(type solid)
		)
		(fill yes)
		(layer "F.Cu")
		(net "M_A_CPU1_SA_CB<6>")
	)
	(gr_poly
		(pts
			(xy 78.7273 -274.407122) (xy 78.680818 -274.309586) (xy 78.645004 -274.273772) (xy 78.459076 -274.4597)
			(xy 78.495144 -274.495514) (xy 78.592426 -274.541742)
		)
		(stroke
			(width 0)
			(type solid)
		)
		(fill yes)
		(layer "F.Cu")
		(net "M_A_CPU1_SA_DQ<27>")
	)
	(gr_poly
		(pts
			(xy 78.727554 -267.313664) (xy 78.681326 -267.216128) (xy 78.645258 -267.180314) (xy 78.459584 -267.365988)
			(xy 78.495398 -267.402056) (xy 78.592934 -267.448284)
		)
		(stroke
			(width 0)
			(type solid)
		)
		(fill yes)
		(layer "F.Cu")
		(net "M_A_CPU1_SA_CB<3>")
	)
	(gr_poly
		(pts
			(xy 78.729586 -278.793194) (xy 78.679802 -278.783288) (xy 78.573122 -278.798782) (xy 78.535784 -278.985726)
			(xy 78.628494 -279.041098) (xy 78.678278 -279.051004)
		)
		(stroke
			(width 0)
			(type solid)
		)
		(fill yes)
		(layer "F.Cu")
		(net "M_A_CPU1_SA_DQ<22>")
	)
	(gr_poly
		(pts
			(xy 78.731364 -271.598644) (xy 78.695296 -271.56283) (xy 78.598014 -271.516602) (xy 78.46314 -271.651222)
			(xy 78.509622 -271.748758) (xy 78.545436 -271.784572)
		)
		(stroke
			(width 0)
			(type solid)
		)
		(fill yes)
		(layer "F.Cu")
		(net "M_A_CPU1_SA_DQ<30>")
	)
	(gr_poly
		(pts
			(xy 78.732888 -224.517204) (xy 78.779116 -224.419922) (xy 78.644496 -224.285048) (xy 78.54696 -224.331276)
			(xy 78.511146 -224.367344) (xy 78.697074 -224.553272)
		)
		(stroke
			(width 0)
			(type solid)
		)
		(fill yes)
		(layer "F.Cu")
		(net "M_A_CPU1_SB_DQ<19>")
	)
	(gr_poly
		(pts
			(xy 78.736952 -268.167104) (xy 78.690724 -268.069568) (xy 78.654656 -268.033754) (xy 78.468728 -268.219682)
			(xy 78.504796 -268.255496) (xy 78.602078 -268.301724)
		)
		(stroke
			(width 0)
			(type solid)
		)
		(fill yes)
		(layer "F.Cu")
		(net "M_A_CPU1_SA_CB<2>")
	)
	(gr_poly
		(pts
			(xy 78.738476 -276.829774) (xy 78.693772 -276.805644) (xy 78.587092 -276.789642) (xy 78.497176 -276.957536)
			(xy 78.569566 -277.037546) (xy 78.614524 -277.061422)
		)
		(stroke
			(width 0)
			(type solid)
		)
		(fill yes)
		(layer "F.Cu")
		(net "M_A_CPU1_SA_DQ<23>")
	)
	(gr_poly
		(pts
			(xy 78.744572 -233.698796) (xy 78.780386 -233.662728) (xy 78.594712 -233.477054) (xy 78.558644 -233.512868)
			(xy 78.512416 -233.610404) (xy 78.647036 -233.745024)
		)
		(stroke
			(width 0)
			(type solid)
		)
		(fill yes)
		(layer "F.Cu")
		(net "M_A_CPU1_SB_DQ<8>")
	)
	(gr_poly
		(pts
			(xy 78.753716 -232.845356) (xy 78.789784 -232.809542) (xy 78.603856 -232.623614) (xy 78.567788 -232.659428)
			(xy 78.52156 -232.756964) (xy 78.656434 -232.891584)
		)
		(stroke
			(width 0)
			(type solid)
		)
		(fill yes)
		(layer "F.Cu")
		(net "M_A_CPU1_SB_DQ<9>")
	)
	(gr_poly
		(pts
			(xy 78.761844 -275.84146) (xy 78.6892 -275.76145) (xy 78.644496 -275.737574) (xy 78.520544 -275.969476)
			(xy 78.565248 -275.993352) (xy 78.671928 -276.009354)
		)
		(stroke
			(width 0)
			(type solid)
		)
		(fill yes)
		(layer "F.Cu")
		(net "M_A_CPU1_SA_DQ<24>")
	)
	(gr_poly
		(pts
			(xy 78.776322 -279.338024) (xy 78.81366 -279.151334) (xy 78.72095 -279.095962) (xy 78.671166 -279.085802)
			(xy 78.619858 -279.343612) (xy 78.669642 -279.353518)
		)
		(stroke
			(width 0)
			(type solid)
		)
		(fill yes)
		(layer "F.Cu")
		(net "M_A_CPU1_SA_DQ<22>")
	)
	(gr_poly
		(pts
			(xy 78.791562 -230.29545) (xy 78.82763 -230.259636) (xy 78.641702 -230.073708) (xy 78.605634 -230.109522)
			(xy 78.559406 -230.207058) (xy 78.694026 -230.341678)
		)
		(stroke
			(width 0)
			(type solid)
		)
		(fill yes)
		(layer "F.Cu")
		(net "M_A_CPU1_SB_DQ<12>")
	)
	(gr_poly
		(pts
			(xy 78.794864 -280.02357) (xy 78.74508 -280.013664) (xy 78.6384 -280.029158) (xy 78.601062 -280.216102)
			(xy 78.693518 -280.271474) (xy 78.743302 -280.28138)
		)
		(stroke
			(width 0)
			(type solid)
		)
		(fill yes)
		(layer "F.Cu")
		(net "M_A_CPU1_SA_DQ<20>")
	)
	(gr_poly
		(pts
			(xy 78.794864 -227.249736) (xy 78.794864 -227.059236) (xy 78.693264 -227.022914) (xy 78.642464 -227.022914)
			(xy 78.642464 -227.286058) (xy 78.693264 -227.286058)
		)
		(stroke
			(width 0)
			(type solid)
		)
		(fill yes)
		(layer "F.Cu")
		(net "M_A_CPU1_SB_DQ<18>")
	)
	(gr_poly
		(pts
			(xy 78.794864 -226.652836) (xy 78.794864 -226.462336) (xy 78.693264 -226.426014) (xy 78.642464 -226.426014)
			(xy 78.642464 -226.689158) (xy 78.693264 -226.689158)
		)
		(stroke
			(width 0)
			(type solid)
		)
		(fill yes)
		(layer "F.Cu")
		(net "M_A_CPU1_SB_DQ<18>")
	)
	(gr_poly
		(pts
			(xy 78.794864 -226.055936) (xy 78.794864 -225.865436) (xy 78.693264 -225.829114) (xy 78.642464 -225.829114)
			(xy 78.642464 -226.092258) (xy 78.693264 -226.092258)
		)
		(stroke
			(width 0)
			(type solid)
		)
		(fill yes)
		(layer "F.Cu")
		(net "M_A_CPU1_SB_DQ<18>")
	)
	(gr_poly
		(pts
			(xy 78.80096 -229.44201) (xy 78.836774 -229.405942) (xy 78.650846 -229.220014) (xy 78.615032 -229.256082)
			(xy 78.568804 -229.353364) (xy 78.703424 -229.488238)
		)
		(stroke
			(width 0)
			(type solid)
		)
		(fill yes)
		(layer "F.Cu")
		(net "M_A_CPU1_SB_DQ<13>")
	)
	(gr_poly
		(pts
			(xy 78.80858 -271.30502) (xy 78.762352 -271.207484) (xy 78.726284 -271.17167) (xy 78.540356 -271.357598)
			(xy 78.576424 -271.393412) (xy 78.673706 -271.43964)
		)
		(stroke
			(width 0)
			(type solid)
		)
		(fill yes)
		(layer "F.Cu")
		(net "M_A_CPU1_SA_DQ<29>")
	)
	(gr_poly
		(pts
			(xy 78.810866 -228.172518) (xy 78.846934 -228.136704) (xy 78.661006 -227.950776) (xy 78.624938 -227.98659)
			(xy 78.57871 -228.084126) (xy 78.713584 -228.218746)
		)
		(stroke
			(width 0)
			(type solid)
		)
		(fill yes)
		(layer "F.Cu")
		(net "M_A_CPU1_SB_DQ<16>")
	)
	(gr_poly
		(pts
			(xy 78.817978 -272.158714) (xy 78.77175 -272.061178) (xy 78.735936 -272.025364) (xy 78.550008 -272.211292)
			(xy 78.586076 -272.247106) (xy 78.683358 -272.293334)
		)
		(stroke
			(width 0)
			(type solid)
		)
		(fill yes)
		(layer "F.Cu")
		(net "M_A_CPU1_SA_DQ<28>")
	)
	(gr_poly
		(pts
			(xy 78.821026 -233.200194) (xy 78.867254 -233.102912) (xy 78.732634 -232.968038) (xy 78.635098 -233.014266)
			(xy 78.599284 -233.050334) (xy 78.785212 -233.236262)
		)
		(stroke
			(width 0)
			(type solid)
		)
		(fill yes)
		(layer "F.Cu")
		(net "M_A_CPU1_SB_DQ<10>")
	)
	(gr_poly
		(pts
			(xy 78.83017 -232.347008) (xy 78.876398 -232.249472) (xy 78.741778 -232.114852) (xy 78.644242 -232.16108)
			(xy 78.608428 -232.196894) (xy 78.794356 -232.382822)
		)
		(stroke
			(width 0)
			(type solid)
		)
		(fill yes)
		(layer "F.Cu")
		(net "M_A_CPU1_SB_DQ<11>")
	)
	(gr_poly
		(pts
			(xy 78.841346 -280.5684) (xy 78.878684 -280.38171) (xy 78.786228 -280.326084) (xy 78.736444 -280.316178)
			(xy 78.684882 -280.573988) (xy 78.734666 -280.583894)
		)
		(stroke
			(width 0)
			(type solid)
		)
		(fill yes)
		(layer "F.Cu")
		(net "M_A_CPU1_SA_DQ<20>")
	)
	(gr_poly
		(pts
			(xy 78.841854 -263.53262) (xy 78.80604 -263.496806) (xy 78.708504 -263.450324) (xy 78.573884 -263.585198)
			(xy 78.620112 -263.68248) (xy 78.655926 -263.718548)
		)
		(stroke
			(width 0)
			(type solid)
		)
		(fill yes)
		(layer "F.Cu")
		(net "M_A_CPU1_SA_CB<7>")
	)
	(gr_poly
		(pts
			(xy 78.84668 -278.207978) (xy 78.796896 -278.197818) (xy 78.690216 -278.213566) (xy 78.652878 -278.400256)
			(xy 78.745334 -278.455628) (xy 78.795118 -278.465788)
		)
		(stroke
			(width 0)
			(type solid)
		)
		(fill yes)
		(layer "F.Cu")
		(net "M_A_CPU1_SA_DQ<22>")
	)
	(gr_poly
		(pts
			(xy 78.851252 -264.386314) (xy 78.815438 -264.350246) (xy 78.717902 -264.304018) (xy 78.583282 -264.438638)
			(xy 78.62951 -264.536174) (xy 78.665578 -264.571988)
		)
		(stroke
			(width 0)
			(type solid)
		)
		(fill yes)
		(layer "F.Cu")
		(net "M_A_CPU1_SA_CB<6>")
	)
	(gr_poly
		(pts
			(xy 78.856078 -274.062698) (xy 78.820264 -274.026884) (xy 78.722728 -273.980656) (xy 78.588108 -274.115276)
			(xy 78.634336 -274.212812) (xy 78.67015 -274.248626)
		)
		(stroke
			(width 0)
			(type solid)
		)
		(fill yes)
		(layer "F.Cu")
		(net "M_A_CPU1_SA_DQ<27>")
	)
	(gr_poly
		(pts
			(xy 78.856332 -266.96924) (xy 78.820518 -266.933172) (xy 78.722982 -266.886944) (xy 78.588362 -267.021818)
			(xy 78.63459 -267.1191) (xy 78.670404 -267.155168)
		)
		(stroke
			(width 0)
			(type solid)
		)
		(fill yes)
		(layer "F.Cu")
		(net "M_A_CPU1_SA_CB<3>")
	)
	(gr_poly
		(pts
			(xy 78.86573 -267.82268) (xy 78.829916 -267.786866) (xy 78.73238 -267.740384) (xy 78.59776 -267.875258)
			(xy 78.643988 -267.97254) (xy 78.679802 -268.008608)
		)
		(stroke
			(width 0)
			(type solid)
		)
		(fill yes)
		(layer "F.Cu")
		(net "M_A_CPU1_SA_CB<2>")
	)
	(gr_poly
		(pts
			(xy 78.86827 -229.796848) (xy 78.914498 -229.699312) (xy 78.779624 -229.564692) (xy 78.682342 -229.61092)
			(xy 78.646274 -229.646734) (xy 78.832202 -229.832662)
		)
		(stroke
			(width 0)
			(type solid)
		)
		(fill yes)
		(layer "F.Cu")
		(net "M_A_CPU1_SB_DQ<14>")
	)
	(gr_poly
		(pts
			(xy 78.87208 -224.80016) (xy 78.907894 -224.764092) (xy 78.72222 -224.578418) (xy 78.686152 -224.614232)
			(xy 78.639924 -224.711768) (xy 78.774544 -224.846388)
		)
		(stroke
			(width 0)
			(type solid)
		)
		(fill yes)
		(layer "F.Cu")
		(net "M_A_CPU1_SB_DQ<19>")
	)
	(gr_poly
		(pts
			(xy 78.877414 -228.943408) (xy 78.923642 -228.845872) (xy 78.789022 -228.711252) (xy 78.691486 -228.75748)
			(xy 78.655672 -228.793548) (xy 78.841346 -228.979222)
		)
		(stroke
			(width 0)
			(type solid)
		)
		(fill yes)
		(layer "F.Cu")
		(net "M_A_CPU1_SB_DQ<15>")
	)
	(gr_poly
		(pts
			(xy 78.893162 -278.752808) (xy 78.9305 -278.565864) (xy 78.838044 -278.510492) (xy 78.78826 -278.500586)
			(xy 78.736698 -278.758396) (xy 78.786482 -278.768302)
		)
		(stroke
			(width 0)
			(type solid)
		)
		(fill yes)
		(layer "F.Cu")
		(net "M_A_CPU1_SA_DQ<22>")
	)
	(gr_poly
		(pts
			(xy 78.911704 -279.438354) (xy 78.86192 -279.428194) (xy 78.75524 -279.443942) (xy 78.717902 -279.630632)
			(xy 78.810358 -279.686004) (xy 78.860396 -279.69591)
		)
		(stroke
			(width 0)
			(type solid)
		)
		(fill yes)
		(layer "F.Cu")
		(net "M_A_CPU1_SA_DQ<20>")
	)
	(gr_poly
		(pts
			(xy 78.928722 -264.09269) (xy 78.882494 -263.995408) (xy 78.84668 -263.95934) (xy 78.660752 -264.145268)
			(xy 78.696566 -264.181336) (xy 78.794102 -264.227564)
		)
		(stroke
			(width 0)
			(type solid)
		)
		(fill yes)
		(layer "F.Cu")
		(net "M_A_CPU1_SA_CB<5>")
	)
	(gr_poly
		(pts
			(xy 78.937358 -270.960596) (xy 78.901544 -270.924782) (xy 78.804008 -270.8783) (xy 78.669388 -271.013174)
			(xy 78.715616 -271.110456) (xy 78.75143 -271.146524)
		)
		(stroke
			(width 0)
			(type solid)
		)
		(fill yes)
		(layer "F.Cu")
		(net "M_A_CPU1_SA_DQ<29>")
	)
	(gr_poly
		(pts
			(xy 78.938374 -264.946384) (xy 78.891892 -264.848848) (xy 78.856078 -264.813034) (xy 78.67015 -264.998962)
			(xy 78.706218 -265.034776) (xy 78.8035 -265.081004)
		)
		(stroke
			(width 0)
			(type solid)
		)
		(fill yes)
		(layer "F.Cu")
		(net "M_A_CPU1_SA_CB<4>")
	)
	(gr_poly
		(pts
			(xy 78.9432 -274.623022) (xy 78.896718 -274.525486) (xy 78.860904 -274.489672) (xy 78.674976 -274.6756)
			(xy 78.711044 -274.711414) (xy 78.808326 -274.757642)
		)
		(stroke
			(width 0)
			(type solid)
		)
		(fill yes)
		(layer "F.Cu")
		(net "M_A_CPU1_SA_DQ<25>")
	)
	(gr_poly
		(pts
			(xy 78.9432 -267.52931) (xy 78.896972 -267.431774) (xy 78.860904 -267.39596) (xy 78.67523 -267.581634)
			(xy 78.711044 -267.617702) (xy 78.80858 -267.66393)
		)
		(stroke
			(width 0)
			(type solid)
		)
		(fill yes)
		(layer "F.Cu")
		(net "M_A_CPU1_SA_CB<1>")
	)
	(gr_poly
		(pts
			(xy 78.94701 -271.81429) (xy 78.910942 -271.778476) (xy 78.81366 -271.732248) (xy 78.678786 -271.866868)
			(xy 78.725268 -271.964404) (xy 78.761082 -272.000218)
		)
		(stroke
			(width 0)
			(type solid)
		)
		(fill yes)
		(layer "F.Cu")
		(net "M_A_CPU1_SA_DQ<28>")
	)
	(gr_poly
		(pts
			(xy 78.947264 -226.724718) (xy 78.896464 -226.724718) (xy 78.794864 -226.760786) (xy 78.794864 -226.951286)
			(xy 78.896464 -226.987354) (xy 78.947264 -226.987354)
		)
		(stroke
			(width 0)
			(type solid)
		)
		(fill yes)
		(layer "F.Cu")
		(net "M_A_CPU1_SB_DQ<17>")
	)
	(gr_poly
		(pts
			(xy 78.947264 -226.127818) (xy 78.896464 -226.127818) (xy 78.794864 -226.163886) (xy 78.794864 -226.354386)
			(xy 78.896464 -226.390454) (xy 78.947264 -226.390454)
		)
		(stroke
			(width 0)
			(type solid)
		)
		(fill yes)
		(layer "F.Cu")
		(net "M_A_CPU1_SB_DQ<17>")
	)
	(gr_poly
		(pts
			(xy 78.947264 -225.530918) (xy 78.896464 -225.530918) (xy 78.794864 -225.566986) (xy 78.794864 -225.757486)
			(xy 78.896464 -225.793554) (xy 78.947264 -225.793554)
		)
		(stroke
			(width 0)
			(type solid)
		)
		(fill yes)
		(layer "F.Cu")
		(net "M_A_CPU1_SB_DQ<17>")
	)
	(gr_poly
		(pts
			(xy 78.952598 -268.38275) (xy 78.90637 -268.285214) (xy 78.870302 -268.2494) (xy 78.684374 -268.435328)
			(xy 78.720442 -268.471142) (xy 78.817724 -268.51737)
		)
		(stroke
			(width 0)
			(type solid)
		)
		(fill yes)
		(layer "F.Cu")
		(net "M_A_CPU1_SA_CB<0>")
	)
	(gr_poly
		(pts
			(xy 78.95844 -279.983184) (xy 78.995778 -279.79624) (xy 78.903068 -279.740868) (xy 78.853284 -279.730962)
			(xy 78.801722 -279.988772) (xy 78.85176 -279.998678)
		)
		(stroke
			(width 0)
			(type solid)
		)
		(fill yes)
		(layer "F.Cu")
		(net "M_A_CPU1_SA_DQ<20>")
	)
	(gr_poly
		(pts
			(xy 78.95844 -249.270266) (xy 78.922372 -249.168666) (xy 78.731872 -249.168666) (xy 78.69555 -249.270266)
			(xy 78.69555 -249.321066) (xy 78.95844 -249.321066)
		)
		(stroke
			(width 0)
			(type solid)
		)
		(fill yes)
		(layer "F.Cu")
		(net "M_A_CPU1_SB_CA<0>")
	)
	(gr_poly
		(pts
			(xy 78.95844 -248.965212) (xy 78.922372 -248.863612) (xy 78.731872 -248.863612) (xy 78.69555 -248.965212)
			(xy 78.69555 -249.016012) (xy 78.95844 -249.016012)
		)
		(stroke
			(width 0)
			(type solid)
		)
		(fill yes)
		(layer "F.Cu")
		(net "M_A_CPU1_SB_CA<1>")
	)
	(gr_poly
		(pts
			(xy 78.95844 -248.660412) (xy 78.922372 -248.558812) (xy 78.731872 -248.558812) (xy 78.69555 -248.660412)
			(xy 78.69555 -248.711212) (xy 78.95844 -248.711212)
		)
		(stroke
			(width 0)
			(type solid)
		)
		(fill yes)
		(layer "F.Cu")
		(net "M_A_CPU1_SB_CA<2>")
	)
	(gr_poly
		(pts
			(xy 78.95844 -248.355612) (xy 78.922372 -248.254012) (xy 78.731872 -248.254012) (xy 78.69555 -248.355612)
			(xy 78.69555 -248.406412) (xy 78.95844 -248.406412)
		)
		(stroke
			(width 0)
			(type solid)
		)
		(fill yes)
		(layer "F.Cu")
		(net "M_A_CPU1_SB_CA<3>")
	)
	(gr_poly
		(pts
			(xy 78.95844 -248.050812) (xy 78.922372 -247.949212) (xy 78.731872 -247.949212) (xy 78.69555 -248.050812)
			(xy 78.69555 -248.101612) (xy 78.95844 -248.101612)
		)
		(stroke
			(width 0)
			(type solid)
		)
		(fill yes)
		(layer "F.Cu")
		(net "M_A_CPU1_SB_CA<4>")
	)
	(gr_poly
		(pts
			(xy 78.95844 -247.746012) (xy 78.922372 -247.644412) (xy 78.731872 -247.644412) (xy 78.69555 -247.746012)
			(xy 78.69555 -247.796812) (xy 78.95844 -247.796812)
		)
		(stroke
			(width 0)
			(type solid)
		)
		(fill yes)
		(layer "F.Cu")
		(net "M_A_CPU1_SB_CA<5>")
	)
	(gr_poly
		(pts
			(xy 78.95844 -247.441212) (xy 78.922372 -247.339612) (xy 78.731872 -247.339612) (xy 78.69555 -247.441212)
			(xy 78.69555 -247.492012) (xy 78.95844 -247.492012)
		)
		(stroke
			(width 0)
			(type solid)
		)
		(fill yes)
		(layer "F.Cu")
		(net "M_A_CPU1_SB_CA<6>")
	)
	(gr_poly
		(pts
			(xy 78.95844 -247.136412) (xy 78.922372 -247.034812) (xy 78.731872 -247.034812) (xy 78.69555 -247.136412)
			(xy 78.69555 -247.187212) (xy 78.95844 -247.187212)
		)
		(stroke
			(width 0)
			(type solid)
		)
		(fill yes)
		(layer "F.Cu")
		(net "M_A_CPU1_SB_PAR")
	)
	(gr_poly
		(pts
			(xy 78.95844 -246.831612) (xy 78.922372 -246.730012) (xy 78.731872 -246.730012) (xy 78.69555 -246.831612)
			(xy 78.69555 -246.882412) (xy 78.95844 -246.882412)
		)
		(stroke
			(width 0)
			(type solid)
		)
		(fill yes)
		(layer "F.Cu")
		(net "M_A_CPU1_SB_CS_N<2>")
	)
	(gr_poly
		(pts
			(xy 78.95844 -246.526812) (xy 78.922372 -246.425212) (xy 78.731872 -246.425212) (xy 78.69555 -246.526812)
			(xy 78.69555 -246.577612) (xy 78.95844 -246.577612)
		)
		(stroke
			(width 0)
			(type solid)
		)
		(fill yes)
		(layer "F.Cu")
		(net "M_A_CPU1_SB_CS_N<0>")
	)
	(gr_poly
		(pts
			(xy 78.95844 -246.222012) (xy 78.922372 -246.120412) (xy 78.731872 -246.120412) (xy 78.69555 -246.222012)
			(xy 78.69555 -246.272812) (xy 78.95844 -246.272812)
		)
		(stroke
			(width 0)
			(type solid)
		)
		(fill yes)
		(layer "F.Cu")
		(net "M_A_CPU1_SB_CS_N<3>")
	)
	(gr_poly
		(pts
			(xy 78.95844 -245.917212) (xy 78.922372 -245.815612) (xy 78.731872 -245.815612) (xy 78.69555 -245.917212)
			(xy 78.69555 -245.968012) (xy 78.95844 -245.968012)
		)
		(stroke
			(width 0)
			(type solid)
		)
		(fill yes)
		(layer "F.Cu")
		(net "M_A_CPU1_SB_CS_N<1>")
	)
	(gr_poly
		(pts
			(xy 78.960218 -233.48315) (xy 78.996032 -233.447082) (xy 78.810358 -233.261408) (xy 78.77429 -233.297222)
			(xy 78.728062 -233.394758) (xy 78.862682 -233.529378)
		)
		(stroke
			(width 0)
			(type solid)
		)
		(fill yes)
		(layer "F.Cu")
		(net "M_A_CPU1_SB_DQ<10>")
	)
	(gr_poly
		(pts
			(xy 78.969362 -232.62971) (xy 79.00543 -232.593896) (xy 78.819502 -232.407968) (xy 78.783434 -232.443782)
			(xy 78.737206 -232.541318) (xy 78.87208 -232.675938)
		)
		(stroke
			(width 0)
			(type solid)
		)
		(fill yes)
		(layer "F.Cu")
		(net "M_A_CPU1_SB_DQ<11>")
	)
	(gr_poly
		(pts
			(xy 78.98384 -277.340568) (xy 78.91145 -277.260812) (xy 78.866746 -277.236682) (xy 78.74254 -277.468584)
			(xy 78.787498 -277.49246) (xy 78.894178 -277.508462)
		)
		(stroke
			(width 0)
			(type solid)
		)
		(fill yes)
		(layer "F.Cu")
		(net "M_A_CPU1_SA_DQ<21>")
	)
	(gr_poly
		(pts
			(xy 78.991206 -257.586226) (xy 78.991206 -257.535426) (xy 78.728316 -257.535426) (xy 78.728316 -257.586226)
			(xy 78.764384 -257.687826) (xy 78.954884 -257.687826)
		)
		(stroke
			(width 0)
			(type solid)
		)
		(fill yes)
		(layer "F.Cu")
		(net "M_A_CPU1_SA_CA<3>")
	)
	(gr_poly
		(pts
			(xy 78.991206 -257.281426) (xy 78.991206 -257.230626) (xy 78.728316 -257.230626) (xy 78.728316 -257.281426)
			(xy 78.764384 -257.383026) (xy 78.954884 -257.383026)
		)
		(stroke
			(width 0)
			(type solid)
		)
		(fill yes)
		(layer "F.Cu")
		(net "M_A_CPU1_SA_CA<4>")
	)
	(gr_poly
		(pts
			(xy 78.991206 -256.976626) (xy 78.991206 -256.925826) (xy 78.728316 -256.925826) (xy 78.728316 -256.976626)
			(xy 78.764384 -257.078226) (xy 78.954884 -257.078226)
		)
		(stroke
			(width 0)
			(type solid)
		)
		(fill yes)
		(layer "F.Cu")
		(net "M_A_CPU1_SA_CA<5>")
	)
	(gr_poly
		(pts
			(xy 78.991206 -256.671826) (xy 78.991206 -256.621026) (xy 78.728316 -256.621026) (xy 78.728316 -256.671826)
			(xy 78.764384 -256.773426) (xy 78.954884 -256.773426)
		)
		(stroke
			(width 0)
			(type solid)
		)
		(fill yes)
		(layer "F.Cu")
		(net "M_A_CPU1_SA_CA<6>")
	)
	(gr_poly
		(pts
			(xy 78.991206 -256.367026) (xy 78.991206 -256.316226) (xy 78.728316 -256.316226) (xy 78.728316 -256.367026)
			(xy 78.764384 -256.468626) (xy 78.954884 -256.468626)
		)
		(stroke
			(width 0)
			(type solid)
		)
		(fill yes)
		(layer "F.Cu")
		(net "M_A_CPU1_SA_PAR")
	)
	(gr_poly
		(pts
			(xy 78.99654 -276.670516) (xy 78.92415 -276.590506) (xy 78.879446 -276.56663) (xy 78.75524 -276.798278)
			(xy 78.800198 -276.822408) (xy 78.906878 -276.83841)
		)
		(stroke
			(width 0)
			(type solid)
		)
		(fill yes)
		(layer "F.Cu")
		(net "M_A_CPU1_SA_DQ<23>")
	)
	(gr_poly
		(pts
			(xy 79.007462 -276.973538) (xy 78.962758 -276.949662) (xy 78.856078 -276.93366) (xy 78.766162 -277.101554)
			(xy 78.838552 -277.18131) (xy 78.88351 -277.20544)
		)
		(stroke
			(width 0)
			(type solid)
		)
		(fill yes)
		(layer "F.Cu")
		(net "M_A_CPU1_SA_DQ<21>")
	)
	(gr_poly
		(pts
			(xy 79.007462 -230.07955) (xy 79.043276 -230.043736) (xy 78.857348 -229.857808) (xy 78.821534 -229.893876)
			(xy 78.775306 -229.991158) (xy 78.909926 -230.126032)
		)
		(stroke
			(width 0)
			(type solid)
		)
		(fill yes)
		(layer "F.Cu")
		(net "M_A_CPU1_SB_DQ<14>")
	)
	(gr_poly
		(pts
			(xy 79.010002 -278.167338) (xy 79.04734 -277.980648) (xy 78.95463 -277.925276) (xy 78.904846 -277.915116)
			(xy 78.853284 -278.172926) (xy 78.903068 -278.183086)
		)
		(stroke
			(width 0)
			(type solid)
		)
		(fill yes)
		(layer "F.Cu")
		(net "M_A_CPU1_SA_DQ<22>")
	)
	(gr_poly
		(pts
			(xy 79.014828 -270.667226) (xy 78.9686 -270.56969) (xy 78.932532 -270.533876) (xy 78.746858 -270.71955)
			(xy 78.782672 -270.755618) (xy 78.880208 -270.801846)
		)
		(stroke
			(width 0)
			(type solid)
		)
		(fill yes)
		(layer "F.Cu")
		(net "M_A_CPU1_SA_DQ<31>")
	)
	(gr_poly
		(pts
			(xy 79.016606 -229.226364) (xy 79.05242 -229.190296) (xy 78.866492 -229.004368) (xy 78.830678 -229.040436)
			(xy 78.78445 -229.137718) (xy 78.91907 -229.272592)
		)
		(stroke
			(width 0)
			(type solid)
		)
		(fill yes)
		(layer "F.Cu")
		(net "M_A_CPU1_SB_DQ<15>")
	)
	(gr_poly
		(pts
			(xy 79.020162 -276.303486) (xy 78.975458 -276.279356) (xy 78.868778 -276.263354) (xy 78.778862 -276.431502)
			(xy 78.851252 -276.511258) (xy 78.89621 -276.535134)
		)
		(stroke
			(width 0)
			(type solid)
		)
		(fill yes)
		(layer "F.Cu")
		(net "M_A_CPU1_SA_DQ<23>")
	)
	(gr_poly
		(pts
			(xy 79.02448 -271.52092) (xy 78.978252 -271.423638) (xy 78.942438 -271.38757) (xy 78.75651 -271.573498)
			(xy 78.792324 -271.609566) (xy 78.88986 -271.655794)
		)
		(stroke
			(width 0)
			(type solid)
		)
		(fill yes)
		(layer "F.Cu")
		(net "M_A_CPU1_SA_DQ<30>")
	)
	(gr_poly
		(pts
			(xy 79.026512 -227.956872) (xy 79.06258 -227.921058) (xy 78.876652 -227.73513) (xy 78.840584 -227.770944)
			(xy 78.794356 -227.86848) (xy 78.92923 -228.0031)
		)
		(stroke
			(width 0)
			(type solid)
		)
		(fill yes)
		(layer "F.Cu")
		(net "M_A_CPU1_SB_DQ<18>")
	)
	(gr_poly
		(pts
			(xy 79.027528 -233.837988) (xy 79.073756 -233.740452) (xy 78.938882 -233.605832) (xy 78.8416 -233.65206)
			(xy 78.805532 -233.687874) (xy 78.99146 -233.873802)
		)
		(stroke
			(width 0)
			(type solid)
		)
		(fill yes)
		(layer "F.Cu")
		(net "M_A_CPU1_SB_DQ<8>")
	)
	(gr_poly
		(pts
			(xy 79.029052 -278.852884) (xy 78.979268 -278.842978) (xy 78.872334 -278.858472) (xy 78.83525 -279.045416)
			(xy 78.927706 -279.100788) (xy 78.97749 -279.110694)
		)
		(stroke
			(width 0)
			(type solid)
		)
		(fill yes)
		(layer "F.Cu")
		(net "M_A_CPU1_SA_DQ<20>")
	)
	(gr_poly
		(pts
			(xy 79.036672 -232.984548) (xy 79.0829 -232.887266) (xy 78.94828 -232.752392) (xy 78.850744 -232.79862)
			(xy 78.81493 -232.834688) (xy 79.000858 -233.020616)
		)
		(stroke
			(width 0)
			(type solid)
		)
		(fill yes)
		(layer "F.Cu")
		(net "M_A_CPU1_SB_DQ<9>")
	)
	(gr_poly
		(pts
			(xy 79.057754 -263.748266) (xy 79.021686 -263.712452) (xy 78.924404 -263.666224) (xy 78.78953 -263.800844)
			(xy 78.835758 -263.89838) (xy 78.871826 -263.934194)
		)
		(stroke
			(width 0)
			(type solid)
		)
		(fill yes)
		(layer "F.Cu")
		(net "M_A_CPU1_SA_CB<5>")
	)
	(gr_poly
		(pts
			(xy 79.067152 -264.60196) (xy 79.031084 -264.566146) (xy 78.933802 -264.519918) (xy 78.799182 -264.654538)
			(xy 78.84541 -264.752074) (xy 78.881224 -264.787888)
		)
		(stroke
			(width 0)
			(type solid)
		)
		(fill yes)
		(layer "F.Cu")
		(net "M_A_CPU1_SA_CB<4>")
	)
	(gr_poly
		(pts
			(xy 79.071978 -274.278598) (xy 79.036164 -274.242784) (xy 78.938628 -274.196556) (xy 78.804008 -274.331176)
			(xy 78.850236 -274.428712) (xy 78.88605 -274.464526)
		)
		(stroke
			(width 0)
			(type solid)
		)
		(fill yes)
		(layer "F.Cu")
		(net "M_A_CPU1_SA_DQ<25>")
	)
	(gr_poly
		(pts
			(xy 79.071978 -267.184886) (xy 79.036164 -267.148818) (xy 78.938628 -267.10259) (xy 78.804008 -267.237464)
			(xy 78.850236 -267.334746) (xy 78.88605 -267.370814)
		)
		(stroke
			(width 0)
			(type solid)
		)
		(fill yes)
		(layer "F.Cu")
		(net "M_A_CPU1_SA_CB<1>")
	)
	(gr_poly
		(pts
			(xy 79.074518 -230.434642) (xy 79.120746 -230.337106) (xy 78.986126 -230.202486) (xy 78.88859 -230.248714)
			(xy 78.852776 -230.284782) (xy 79.03845 -230.470456)
		)
		(stroke
			(width 0)
			(type solid)
		)
		(fill yes)
		(layer "F.Cu")
		(net "M_A_CPU1_SB_DQ<12>")
	)
	(gr_poly
		(pts
			(xy 79.07528 -279.397714) (xy 79.112618 -279.211024) (xy 79.020162 -279.155398) (xy 78.970378 -279.145492)
			(xy 78.918816 -279.403302) (xy 78.9686 -279.413208)
		)
		(stroke
			(width 0)
			(type solid)
		)
		(fill yes)
		(layer "F.Cu")
		(net "M_A_CPU1_SA_DQ<20>")
	)
	(gr_poly
		(pts
			(xy 79.081376 -268.038326) (xy 79.045562 -268.002512) (xy 78.948026 -267.95603) (xy 78.813406 -268.090904)
			(xy 78.859634 -268.188186) (xy 78.895448 -268.224254)
		)
		(stroke
			(width 0)
			(type solid)
		)
		(fill yes)
		(layer "F.Cu")
		(net "M_A_CPU1_SA_CB<0>")
	)
	(gr_poly
		(pts
			(xy 79.083916 -229.581202) (xy 79.130144 -229.483666) (xy 78.99527 -229.349046) (xy 78.897988 -229.395274)
			(xy 78.86192 -229.431088) (xy 79.047848 -229.617016)
		)
		(stroke
			(width 0)
			(type solid)
		)
		(fill yes)
		(layer "F.Cu")
		(net "M_A_CPU1_SB_DQ<13>")
	)
	(gr_poly
		(pts
			(xy 79.093822 -228.31171) (xy 79.14005 -228.214428) (xy 79.00543 -228.079554) (xy 78.907894 -228.125782)
			(xy 78.87208 -228.16185) (xy 79.058008 -228.347778)
		)
		(stroke
			(width 0)
			(type solid)
		)
		(fill yes)
		(layer "F.Cu")
		(net "M_A_CPU1_SB_DQ<16>")
	)
	(gr_poly
		(pts
			(xy 79.099664 -226.652836) (xy 79.099664 -226.462336) (xy 78.998064 -226.426014) (xy 78.947264 -226.426014)
			(xy 78.947264 -226.689158) (xy 78.998064 -226.689158)
		)
		(stroke
			(width 0)
			(type solid)
		)
		(fill yes)
		(layer "F.Cu")
		(net "M_A_CPU1_SB_DQ<17>")
	)
	(gr_poly
		(pts
			(xy 79.099664 -226.055936) (xy 79.099664 -225.865436) (xy 78.998064 -225.829114) (xy 78.947264 -225.829114)
			(xy 78.947264 -226.092258) (xy 78.998064 -226.092258)
		)
		(stroke
			(width 0)
			(type solid)
		)
		(fill yes)
		(layer "F.Cu")
		(net "M_A_CPU1_SB_DQ<17>")
	)
	(gr_poly
		(pts
			(xy 79.13497 -263.454896) (xy 79.088742 -263.35736) (xy 79.052928 -263.321546) (xy 78.867 -263.507474)
			(xy 78.902814 -263.543288) (xy 79.00035 -263.589516)
		)
		(stroke
			(width 0)
			(type solid)
		)
		(fill yes)
		(layer "F.Cu")
		(net "M_A_CPU1_SA_CB<7>")
	)
	(gr_poly
		(pts
			(xy 79.143606 -270.322802) (xy 79.107792 -270.286734) (xy 79.010256 -270.240506) (xy 78.875636 -270.37538)
			(xy 78.921864 -270.472662) (xy 78.957678 -270.50873)
		)
		(stroke
			(width 0)
			(type solid)
		)
		(fill yes)
		(layer "F.Cu")
		(net "M_A_CPU1_SA_DQ<31>")
	)
	(gr_poly
		(pts
			(xy 79.144622 -264.30859) (xy 79.098394 -264.211054) (xy 79.062326 -264.17524) (xy 78.876398 -264.361168)
			(xy 78.912466 -264.396982) (xy 79.009748 -264.44321)
		)
		(stroke
			(width 0)
			(type solid)
		)
		(fill yes)
		(layer "F.Cu")
		(net "M_A_CPU1_SA_CB<6>")
	)
	(gr_poly
		(pts
			(xy 79.145638 -278.267668) (xy 79.095854 -278.257508) (xy 78.989174 -278.273256) (xy 78.951836 -278.459946)
			(xy 79.044292 -278.515318) (xy 79.094076 -278.525478)
		)
		(stroke
			(width 0)
			(type solid)
		)
		(fill yes)
		(layer "F.Cu")
		(net "M_A_CPU1_SA_DQ<20>")
	)
	(gr_poly
		(pts
			(xy 79.149194 -273.984974) (xy 79.102966 -273.887692) (xy 79.067152 -273.851624) (xy 78.881224 -274.037552)
			(xy 78.917038 -274.07362) (xy 79.014574 -274.119848)
		)
		(stroke
			(width 0)
			(type solid)
		)
		(fill yes)
		(layer "F.Cu")
		(net "M_A_CPU1_SA_DQ<27>")
	)
	(gr_poly
		(pts
			(xy 79.149702 -266.891516) (xy 79.10322 -266.79398) (xy 79.067406 -266.758166) (xy 78.881478 -266.944094)
			(xy 78.917546 -266.979908) (xy 79.014828 -267.026136)
		)
		(stroke
			(width 0)
			(type solid)
		)
		(fill yes)
		(layer "F.Cu")
		(net "M_A_CPU1_SA_CB<3>")
	)
	(gr_poly
		(pts
			(xy 79.153512 -271.176496) (xy 79.117444 -271.140682) (xy 79.019908 -271.094454) (xy 78.885288 -271.229074)
			(xy 78.931516 -271.32661) (xy 78.967584 -271.362424)
		)
		(stroke
			(width 0)
			(type solid)
		)
		(fill yes)
		(layer "F.Cu")
		(net "M_A_CPU1_SA_DQ<30>")
	)
	(gr_poly
		(pts
			(xy 79.155036 -224.939352) (xy 79.201264 -224.841816) (xy 79.066644 -224.707196) (xy 78.969108 -224.753424)
			(xy 78.93304 -224.789238) (xy 79.118968 -224.975166)
		)
		(stroke
			(width 0)
			(type solid)
		)
		(fill yes)
		(layer "F.Cu")
		(net "M_A_CPU1_SB_DQ<19>")
	)
	(gr_poly
		(pts
			(xy 79.158846 -274.838668) (xy 79.112364 -274.741132) (xy 79.07655 -274.705318) (xy 78.890622 -274.891246)
			(xy 78.92669 -274.92706) (xy 79.023972 -274.973288)
		)
		(stroke
			(width 0)
			(type solid)
		)
		(fill yes)
		(layer "F.Cu")
		(net "M_A_CPU1_SA_DQ<26>")
	)
	(gr_poly
		(pts
			(xy 79.158846 -267.744956) (xy 79.112618 -267.647674) (xy 79.076804 -267.611606) (xy 78.890876 -267.797534)
			(xy 78.92669 -267.833348) (xy 79.024226 -267.879576)
		)
		(stroke
			(width 0)
			(type solid)
		)
		(fill yes)
		(layer "F.Cu")
		(net "M_A_CPU1_SA_CB<2>")
	)
	(gr_poly
		(pts
			(xy 79.16672 -234.120944) (xy 79.202534 -234.084876) (xy 79.016606 -233.898948) (xy 78.980792 -233.935016)
			(xy 78.934564 -234.032298) (xy 79.069184 -234.167172)
		)
		(stroke
			(width 0)
			(type solid)
		)
		(fill yes)
		(layer "F.Cu")
		(net "M_A_CPU1_SB_DQ<8>")
	)
	(gr_poly
		(pts
			(xy 79.170784 -222.444818) (xy 79.119984 -222.444818) (xy 79.018384 -222.480886) (xy 79.018384 -222.671386)
			(xy 79.119984 -222.707454) (xy 79.170784 -222.707454)
		)
		(stroke
			(width 0)
			(type solid)
		)
		(fill yes)
		(layer "F.Cu")
		(net "M_A_CPU1_SB_DQ<20>")
	)
	(gr_poly
		(pts
			(xy 79.170784 -221.847918) (xy 79.119984 -221.847918) (xy 79.018384 -221.883986) (xy 79.018384 -222.074486)
			(xy 79.119984 -222.110554) (xy 79.170784 -222.110554)
		)
		(stroke
			(width 0)
			(type solid)
		)
		(fill yes)
		(layer "F.Cu")
		(net "M_A_CPU1_SB_DQ<20>")
	)
	(gr_poly
		(pts
			(xy 79.170784 -221.251018) (xy 79.119984 -221.251018) (xy 79.018384 -221.287086) (xy 79.018384 -221.477586)
			(xy 79.119984 -221.513654) (xy 79.170784 -221.513654)
		)
		(stroke
			(width 0)
			(type solid)
		)
		(fill yes)
		(layer "F.Cu")
		(net "M_A_CPU1_SB_DQ<20>")
	)
	(gr_poly
		(pts
			(xy 79.170784 -220.654118) (xy 79.119984 -220.654118) (xy 79.018384 -220.690186) (xy 79.018384 -220.880686)
			(xy 79.119984 -220.916754) (xy 79.170784 -220.916754)
		)
		(stroke
			(width 0)
			(type solid)
		)
		(fill yes)
		(layer "F.Cu")
		(net "M_A_CPU1_SB_DQ<20>")
	)
	(gr_poly
		(pts
			(xy 79.170784 -220.057218) (xy 79.119984 -220.057218) (xy 79.018384 -220.093286) (xy 79.018384 -220.283786)
			(xy 79.119984 -220.319854) (xy 79.170784 -220.319854)
		)
		(stroke
			(width 0)
			(type solid)
		)
		(fill yes)
		(layer "F.Cu")
		(net "M_A_CPU1_SB_DQ<20>")
	)
	(gr_poly
		(pts
			(xy 79.170784 -219.460318) (xy 79.119984 -219.460318) (xy 79.018384 -219.496386) (xy 79.018384 -219.686886)
			(xy 79.119984 -219.722954) (xy 79.170784 -219.722954)
		)
		(stroke
			(width 0)
			(type solid)
		)
		(fill yes)
		(layer "F.Cu")
		(net "M_A_CPU1_SB_DQ<20>")
	)
	(gr_poly
		(pts
			(xy 79.170784 -218.863418) (xy 79.119984 -218.863418) (xy 79.018384 -218.899486) (xy 79.018384 -219.089986)
			(xy 79.119984 -219.126054) (xy 79.170784 -219.126054)
		)
		(stroke
			(width 0)
			(type solid)
		)
		(fill yes)
		(layer "F.Cu")
		(net "M_A_CPU1_SB_DQ<20>")
	)
	(gr_poly
		(pts
			(xy 79.170784 -218.266518) (xy 79.119984 -218.266518) (xy 79.018384 -218.302586) (xy 79.018384 -218.493086)
			(xy 79.119984 -218.529154) (xy 79.170784 -218.529154)
		)
		(stroke
			(width 0)
			(type solid)
		)
		(fill yes)
		(layer "F.Cu")
		(net "M_A_CPU1_SB_DQ<20>")
	)
	(gr_poly
		(pts
			(xy 79.170784 -217.669618) (xy 79.119984 -217.669618) (xy 79.018384 -217.705686) (xy 79.018384 -217.896186)
			(xy 79.119984 -217.932254) (xy 79.170784 -217.932254)
		)
		(stroke
			(width 0)
			(type solid)
		)
		(fill yes)
		(layer "F.Cu")
		(net "M_A_CPU1_SB_DQ<20>")
	)
	(gr_poly
		(pts
			(xy 79.170784 -217.072718) (xy 79.119984 -217.072718) (xy 79.018384 -217.108786) (xy 79.018384 -217.299286)
			(xy 79.119984 -217.335354) (xy 79.170784 -217.335354)
		)
		(stroke
			(width 0)
			(type solid)
		)
		(fill yes)
		(layer "F.Cu")
		(net "M_A_CPU1_SB_DQ<20>")
	)
	(gr_poly
		(pts
			(xy 79.170784 -216.475818) (xy 79.119984 -216.475818) (xy 79.018384 -216.511886) (xy 79.018384 -216.702386)
			(xy 79.119984 -216.738454) (xy 79.170784 -216.738454)
		)
		(stroke
			(width 0)
			(type solid)
		)
		(fill yes)
		(layer "F.Cu")
		(net "M_A_CPU1_SB_DQ<20>")
	)
	(gr_poly
		(pts
			(xy 79.170784 -215.878918) (xy 79.119984 -215.878918) (xy 79.018384 -215.914986) (xy 79.018384 -216.105486)
			(xy 79.119984 -216.141554) (xy 79.170784 -216.141554)
		)
		(stroke
			(width 0)
			(type solid)
		)
		(fill yes)
		(layer "F.Cu")
		(net "M_A_CPU1_SB_DQ<20>")
	)
	(gr_poly
		(pts
			(xy 79.170784 -215.282018) (xy 79.119984 -215.282018) (xy 79.018384 -215.318086) (xy 79.018384 -215.508586)
			(xy 79.119984 -215.544654) (xy 79.170784 -215.544654)
		)
		(stroke
			(width 0)
			(type solid)
		)
		(fill yes)
		(layer "F.Cu")
		(net "M_A_CPU1_SB_DQ<20>")
	)
	(gr_poly
		(pts
			(xy 79.175864 -233.267504) (xy 79.211678 -233.231436) (xy 79.026004 -233.045762) (xy 78.989936 -233.081576)
			(xy 78.943708 -233.179112) (xy 79.078328 -233.313732)
		)
		(stroke
			(width 0)
			(type solid)
		)
		(fill yes)
		(layer "F.Cu")
		(net "M_A_CPU1_SB_DQ<9>")
	)
	(gr_poly
		(pts
			(xy 79.19212 -278.812498) (xy 79.229458 -278.625554) (xy 79.137002 -278.570182) (xy 79.087218 -278.560276)
			(xy 79.035656 -278.818086) (xy 79.08544 -278.827992)
		)
		(stroke
			(width 0)
			(type solid)
		)
		(fill yes)
		(layer "F.Cu")
		(net "M_A_CPU1_SA_DQ<20>")
	)
	(gr_poly
		(pts
			(xy 79.21371 -230.717598) (xy 79.249524 -230.68153) (xy 79.063596 -230.495602) (xy 79.027782 -230.53167)
			(xy 78.981554 -230.628952) (xy 79.116174 -230.763826)
		)
		(stroke
			(width 0)
			(type solid)
		)
		(fill yes)
		(layer "F.Cu")
		(net "M_A_CPU1_SB_DQ<12>")
	)
	(gr_poly
		(pts
			(xy 79.223108 -229.863904) (xy 79.258922 -229.82809) (xy 79.072994 -229.642162) (xy 79.03718 -229.67823)
			(xy 78.990952 -229.775512) (xy 79.125572 -229.910386)
		)
		(stroke
			(width 0)
			(type solid)
		)
		(fill yes)
		(layer "F.Cu")
		(net "M_A_CPU1_SB_DQ<13>")
	)
	(gr_poly
		(pts
			(xy 79.230474 -270.882872) (xy 79.184246 -270.78559) (xy 79.148432 -270.749522) (xy 78.962504 -270.93545)
			(xy 78.998318 -270.971264) (xy 79.095854 -271.017492)
		)
		(stroke
			(width 0)
			(type solid)
		)
		(fill yes)
		(layer "F.Cu")
		(net "M_A_CPU1_SA_DQ<29>")
	)
	(gr_poly
		(pts
			(xy 79.233014 -228.594666) (xy 79.268828 -228.558598) (xy 79.083154 -228.372924) (xy 79.047086 -228.408738)
			(xy 79.000858 -228.506274) (xy 79.135478 -228.640894)
		)
		(stroke
			(width 0)
			(type solid)
		)
		(fill yes)
		(layer "F.Cu")
		(net "M_A_CPU1_SB_DQ<16>")
	)
	(gr_poly
		(pts
			(xy 79.240126 -271.736566) (xy 79.193898 -271.639284) (xy 79.158084 -271.603216) (xy 78.972156 -271.789144)
			(xy 79.00797 -271.825212) (xy 79.105506 -271.87144)
		)
		(stroke
			(width 0)
			(type solid)
		)
		(fill yes)
		(layer "F.Cu")
		(net "M_A_CPU1_SA_DQ<28>")
	)
	(gr_poly
		(pts
			(xy 79.242158 -227.741226) (xy 79.278226 -227.705412) (xy 79.092298 -227.519484) (xy 79.05623 -227.555298)
			(xy 79.010002 -227.652834) (xy 79.144876 -227.787454)
		)
		(stroke
			(width 0)
			(type solid)
		)
		(fill yes)
		(layer "F.Cu")
		(net "M_A_CPU1_SB_DQ<17>")
	)
	(gr_poly
		(pts
			(xy 79.243174 -233.622342) (xy 79.289402 -233.524806) (xy 79.154528 -233.390186) (xy 79.057246 -233.436414)
			(xy 79.021178 -233.472228) (xy 79.207106 -233.658156)
		)
		(stroke
			(width 0)
			(type solid)
		)
		(fill yes)
		(layer "F.Cu")
		(net "M_A_CPU1_SB_DQ<10>")
	)
	(gr_poly
		(pts
			(xy 79.252064 -226.724718) (xy 79.201264 -226.724718) (xy 79.099664 -226.760786) (xy 79.099664 -226.951286)
			(xy 79.201264 -226.987354) (xy 79.252064 -226.987354)
		)
		(stroke
			(width 0)
			(type solid)
		)
		(fill yes)
		(layer "F.Cu")
		(net "M_A_CPU1_SB_DQ<19>")
	)
	(gr_poly
		(pts
			(xy 79.252064 -226.127818) (xy 79.201264 -226.127818) (xy 79.099664 -226.163886) (xy 79.099664 -226.354386)
			(xy 79.201264 -226.390454) (xy 79.252064 -226.390454)
		)
		(stroke
			(width 0)
			(type solid)
		)
		(fill yes)
		(layer "F.Cu")
		(net "M_A_CPU1_SB_DQ<19>")
	)
	(gr_poly
		(pts
			(xy 79.252064 -225.530918) (xy 79.201264 -225.530918) (xy 79.099664 -225.566986) (xy 79.099664 -225.757486)
			(xy 79.201264 -225.793554) (xy 79.252064 -225.793554)
		)
		(stroke
			(width 0)
			(type solid)
		)
		(fill yes)
		(layer "F.Cu")
		(net "M_A_CPU1_SB_DQ<19>")
	)
	(gr_poly
		(pts
			(xy 79.252318 -232.768902) (xy 79.298546 -232.67162) (xy 79.163926 -232.536746) (xy 79.06639 -232.582974)
			(xy 79.030576 -232.619042) (xy 79.216504 -232.80497)
		)
		(stroke
			(width 0)
			(type solid)
		)
		(fill yes)
		(layer "F.Cu")
		(net "M_A_CPU1_SB_DQ<11>")
	)
	(gr_poly
		(pts
			(xy 79.25308 -277.484586) (xy 79.180436 -277.404576) (xy 79.135732 -277.3807) (xy 79.01178 -277.612602)
			(xy 79.056484 -277.636478) (xy 79.163164 -277.65248)
		)
		(stroke
			(width 0)
			(type solid)
		)
		(fill yes)
		(layer "F.Cu")
		(net "M_A_CPU1_SA_DQ<22>")
	)
	(gr_poly
		(pts
			(xy 79.25689 -249.371866) (xy 79.25689 -249.321066) (xy 78.994 -249.321066) (xy 78.994 -249.371866)
			(xy 79.030068 -249.473466) (xy 79.220568 -249.473466)
		)
		(stroke
			(width 0)
			(type solid)
		)
		(fill yes)
		(layer "F.Cu")
		(net "M_A_CPU1_SB_CA<0>")
	)
	(gr_poly
		(pts
			(xy 79.25689 -249.066812) (xy 79.25689 -249.016012) (xy 78.994 -249.016012) (xy 78.994 -249.066812)
			(xy 79.030068 -249.168412) (xy 79.220568 -249.168412)
		)
		(stroke
			(width 0)
			(type solid)
		)
		(fill yes)
		(layer "F.Cu")
		(net "M_A_CPU1_SB_CA<1>")
	)
	(gr_poly
		(pts
			(xy 79.25689 -248.762012) (xy 79.25689 -248.711212) (xy 78.994 -248.711212) (xy 78.994 -248.762012)
			(xy 79.030068 -248.863612) (xy 79.220568 -248.863612)
		)
		(stroke
			(width 0)
			(type solid)
		)
		(fill yes)
		(layer "F.Cu")
		(net "M_A_CPU1_SB_CA<2>")
	)
	(gr_poly
		(pts
			(xy 79.25689 -248.457212) (xy 79.25689 -248.406412) (xy 78.994 -248.406412) (xy 78.994 -248.457212)
			(xy 79.030068 -248.558812) (xy 79.220568 -248.558812)
		)
		(stroke
			(width 0)
			(type solid)
		)
		(fill yes)
		(layer "F.Cu")
		(net "M_A_CPU1_SB_CA<3>")
	)
	(gr_poly
		(pts
			(xy 79.25689 -248.152412) (xy 79.25689 -248.101612) (xy 78.994 -248.101612) (xy 78.994 -248.152412)
			(xy 79.030068 -248.254012) (xy 79.220568 -248.254012)
		)
		(stroke
			(width 0)
			(type solid)
		)
		(fill yes)
		(layer "F.Cu")
		(net "M_A_CPU1_SB_CA<4>")
	)
	(gr_poly
		(pts
			(xy 79.25689 -247.847612) (xy 79.25689 -247.796812) (xy 78.994 -247.796812) (xy 78.994 -247.847612)
			(xy 79.030068 -247.949212) (xy 79.220568 -247.949212)
		)
		(stroke
			(width 0)
			(type solid)
		)
		(fill yes)
		(layer "F.Cu")
		(net "M_A_CPU1_SB_CA<5>")
	)
	(gr_poly
		(pts
			(xy 79.25689 -247.542812) (xy 79.25689 -247.492012) (xy 78.994 -247.492012) (xy 78.994 -247.542812)
			(xy 79.030068 -247.644412) (xy 79.220568 -247.644412)
		)
		(stroke
			(width 0)
			(type solid)
		)
		(fill yes)
		(layer "F.Cu")
		(net "M_A_CPU1_SB_CA<6>")
	)
	(gr_poly
		(pts
			(xy 79.25689 -247.238012) (xy 79.25689 -247.187212) (xy 78.994 -247.187212) (xy 78.994 -247.238012)
			(xy 79.030068 -247.339612) (xy 79.220568 -247.339612)
		)
		(stroke
			(width 0)
			(type solid)
		)
		(fill yes)
		(layer "F.Cu")
		(net "M_A_CPU1_SB_PAR")
	)
	(gr_poly
		(pts
			(xy 79.25689 -246.933212) (xy 79.25689 -246.882412) (xy 78.994 -246.882412) (xy 78.994 -246.933212)
			(xy 79.030068 -247.034812) (xy 79.220568 -247.034812)
		)
		(stroke
			(width 0)
			(type solid)
		)
		(fill yes)
		(layer "F.Cu")
		(net "M_A_CPU1_SB_CS_N<2>")
	)
	(gr_poly
		(pts
			(xy 79.25689 -246.628412) (xy 79.25689 -246.577612) (xy 78.994 -246.577612) (xy 78.994 -246.628412)
			(xy 79.030068 -246.730012) (xy 79.220568 -246.730012)
		)
		(stroke
			(width 0)
			(type solid)
		)
		(fill yes)
		(layer "F.Cu")
		(net "M_A_CPU1_SB_CS_N<0>")
	)
	(gr_poly
		(pts
			(xy 79.25689 -246.323612) (xy 79.25689 -246.272812) (xy 78.994 -246.272812) (xy 78.994 -246.323612)
			(xy 79.030068 -246.425212) (xy 79.220568 -246.425212)
		)
		(stroke
			(width 0)
			(type solid)
		)
		(fill yes)
		(layer "F.Cu")
		(net "M_A_CPU1_SB_CS_N<3>")
	)
	(gr_poly
		(pts
			(xy 79.25689 -246.018812) (xy 79.25689 -245.968012) (xy 78.994 -245.968012) (xy 78.994 -246.018812)
			(xy 79.030068 -246.120412) (xy 79.220568 -246.120412)
		)
		(stroke
			(width 0)
			(type solid)
		)
		(fill yes)
		(layer "F.Cu")
		(net "M_A_CPU1_SB_CS_N<1>")
	)
	(gr_poly
		(pts
			(xy 79.264002 -263.110472) (xy 79.227934 -263.074658) (xy 79.130652 -263.02843) (xy 78.995778 -263.16305)
			(xy 79.04226 -263.260586) (xy 79.078074 -263.2964)
		)
		(stroke
			(width 0)
			(type solid)
		)
		(fill yes)
		(layer "F.Cu")
		(net "M_A_CPU1_SA_CB<7>")
	)
	(gr_poly
		(pts
			(xy 79.265526 -276.81428) (xy 79.193136 -276.734524) (xy 79.148178 -276.710394) (xy 79.024226 -276.942296)
			(xy 79.06893 -276.966172) (xy 79.17561 -276.982174)
		)
		(stroke
			(width 0)
			(type solid)
		)
		(fill yes)
		(layer "F.Cu")
		(net "M_A_CPU1_SA_DQ<21>")
	)
	(gr_poly
		(pts
			(xy 79.2734 -263.964166) (xy 79.237586 -263.928352) (xy 79.14005 -263.88187) (xy 79.00543 -264.016744)
			(xy 79.051658 -264.114026) (xy 79.087472 -264.150094)
		)
		(stroke
			(width 0)
			(type solid)
		)
		(fill yes)
		(layer "F.Cu")
		(net "M_A_CPU1_SA_CB<6>")
	)
	(gr_poly
		(pts
			(xy 79.276448 -277.117556) (xy 79.231744 -277.09368) (xy 79.125064 -277.077424) (xy 79.035148 -277.245572)
			(xy 79.107538 -277.325328) (xy 79.152496 -277.349204)
		)
		(stroke
			(width 0)
			(type solid)
		)
		(fill yes)
		(layer "F.Cu")
		(net "M_A_CPU1_SA_DQ<22>")
	)
	(gr_poly
		(pts
			(xy 79.278226 -276.144228) (xy 79.205836 -276.064218) (xy 79.161132 -276.040342) (xy 79.036926 -276.27199)
			(xy 79.081884 -276.29612) (xy 79.188564 -276.312122)
		)
		(stroke
			(width 0)
			(type solid)
		)
		(fill yes)
		(layer "F.Cu")
		(net "M_A_CPU1_SA_DQ<23>")
	)
	(gr_poly
		(pts
			(xy 79.278226 -273.64055) (xy 79.242158 -273.604736) (xy 79.144876 -273.558508) (xy 79.010002 -273.693128)
			(xy 79.05623 -273.790664) (xy 79.092298 -273.826478)
		)
		(stroke
			(width 0)
			(type solid)
		)
		(fill yes)
		(layer "F.Cu")
		(net "M_A_CPU1_SA_DQ<27>")
	)
	(gr_poly
		(pts
			(xy 79.27848 -266.547092) (xy 79.242666 -266.511278) (xy 79.14513 -266.46505) (xy 79.01051 -266.59967)
			(xy 79.056738 -266.697206) (xy 79.092552 -266.73302)
		)
		(stroke
			(width 0)
			(type solid)
		)
		(fill yes)
		(layer "F.Cu")
		(net "M_A_CPU1_SA_CB<3>")
	)
	(gr_poly
		(pts
			(xy 79.287624 -274.494244) (xy 79.25181 -274.45843) (xy 79.154274 -274.412202) (xy 79.019654 -274.546822)
			(xy 79.065882 -274.644358) (xy 79.101696 -274.680172)
		)
		(stroke
			(width 0)
			(type solid)
		)
		(fill yes)
		(layer "F.Cu")
		(net "M_A_CPU1_SA_DQ<26>")
	)
	(gr_poly
		(pts
			(xy 79.287878 -267.400532) (xy 79.25181 -267.364718) (xy 79.154528 -267.31849) (xy 79.019654 -267.45311)
			(xy 79.065882 -267.550646) (xy 79.10195 -267.58646)
		)
		(stroke
			(width 0)
			(type solid)
		)
		(fill yes)
		(layer "F.Cu")
		(net "M_A_CPU1_SA_CB<2>")
	)
	(gr_poly
		(pts
			(xy 79.289148 -276.44725) (xy 79.244444 -276.423374) (xy 79.137764 -276.407372) (xy 79.047848 -276.575266)
			(xy 79.120238 -276.655022) (xy 79.164942 -276.679152)
		)
		(stroke
			(width 0)
			(type solid)
		)
		(fill yes)
		(layer "F.Cu")
		(net "M_A_CPU1_SA_DQ<21>")
	)
	(gr_poly
		(pts
			(xy 79.289656 -258.094226) (xy 79.253588 -257.992626) (xy 79.063088 -257.992626) (xy 79.026766 -258.094226)
			(xy 79.026766 -258.145026) (xy 79.289656 -258.145026)
		)
		(stroke
			(width 0)
			(type solid)
		)
		(fill yes)
		(layer "F.Cu")
		(net "M_A_CPU1_SA_CA<1>")
	)
	(gr_poly
		(pts
			(xy 79.289656 -257.789426) (xy 79.253588 -257.687826) (xy 79.063088 -257.687826) (xy 79.026766 -257.789426)
			(xy 79.026766 -257.840226) (xy 79.289656 -257.840226)
		)
		(stroke
			(width 0)
			(type solid)
		)
		(fill yes)
		(layer "F.Cu")
		(net "M_A_CPU1_SA_CA<2>")
	)
	(gr_poly
		(pts
			(xy 79.289656 -257.484626) (xy 79.253588 -257.383026) (xy 79.063088 -257.383026) (xy 79.026766 -257.484626)
			(xy 79.026766 -257.535426) (xy 79.289656 -257.535426)
		)
		(stroke
			(width 0)
			(type solid)
		)
		(fill yes)
		(layer "F.Cu")
		(net "M_A_CPU1_SA_CA<3>")
	)
	(gr_poly
		(pts
			(xy 79.289656 -257.179826) (xy 79.253588 -257.078226) (xy 79.063088 -257.078226) (xy 79.026766 -257.179826)
			(xy 79.026766 -257.230626) (xy 79.289656 -257.230626)
		)
		(stroke
			(width 0)
			(type solid)
		)
		(fill yes)
		(layer "F.Cu")
		(net "M_A_CPU1_SA_CA<4>")
	)
	(gr_poly
		(pts
			(xy 79.289656 -256.875026) (xy 79.253588 -256.773426) (xy 79.063088 -256.773426) (xy 79.026766 -256.875026)
			(xy 79.026766 -256.925826) (xy 79.289656 -256.925826)
		)
		(stroke
			(width 0)
			(type solid)
		)
		(fill yes)
		(layer "F.Cu")
		(net "M_A_CPU1_SA_CA<5>")
	)
	(gr_poly
		(pts
			(xy 79.289656 -256.570226) (xy 79.253588 -256.468626) (xy 79.063088 -256.468626) (xy 79.026766 -256.570226)
			(xy 79.026766 -256.621026) (xy 79.289656 -256.621026)
		)
		(stroke
			(width 0)
			(type solid)
		)
		(fill yes)
		(layer "F.Cu")
		(net "M_A_CPU1_SA_CA<6>")
	)
	(gr_poly
		(pts
			(xy 79.289656 -256.265426) (xy 79.253588 -256.163826) (xy 79.063088 -256.163826) (xy 79.026766 -256.265426)
			(xy 79.026766 -256.316226) (xy 79.289656 -256.316226)
		)
		(stroke
			(width 0)
			(type solid)
		)
		(fill yes)
		(layer "F.Cu")
		(net "M_A_CPU1_SA_PAR")
	)
	(gr_poly
		(pts
			(xy 79.290164 -230.218742) (xy 79.336392 -230.12146) (xy 79.201772 -229.98684) (xy 79.104236 -230.033068)
			(xy 79.068422 -230.068882) (xy 79.25435 -230.25481)
		)
		(stroke
			(width 0)
			(type solid)
		)
		(fill yes)
		(layer "F.Cu")
		(net "M_A_CPU1_SB_DQ<14>")
	)
	(gr_poly
		(pts
			(xy 79.299562 -229.365556) (xy 79.34579 -229.26802) (xy 79.210916 -229.1334) (xy 79.113634 -229.179628)
			(xy 79.077566 -229.215442) (xy 79.263494 -229.40137)
		)
		(stroke
			(width 0)
			(type solid)
		)
		(fill yes)
		(layer "F.Cu")
		(net "M_A_CPU1_SB_DQ<15>")
	)
	(gr_poly
		(pts
			(xy 79.309468 -228.096064) (xy 79.355696 -227.998782) (xy 79.221076 -227.863908) (xy 79.12354 -227.910136)
			(xy 79.087726 -227.946204) (xy 79.273654 -228.132132)
		)
		(stroke
			(width 0)
			(type solid)
		)
		(fill yes)
		(layer "F.Cu")
		(net "M_A_CPU1_SB_DQ<18>")
	)
	(gr_poly
		(pts
			(xy 79.323184 -222.372936) (xy 79.323184 -222.182436) (xy 79.221584 -222.146114) (xy 79.170784 -222.146114)
			(xy 79.170784 -222.409258) (xy 79.221584 -222.409258)
		)
		(stroke
			(width 0)
			(type solid)
		)
		(fill yes)
		(layer "F.Cu")
		(net "M_A_CPU1_SB_DQ<20>")
	)
	(gr_poly
		(pts
			(xy 79.323184 -221.776036) (xy 79.323184 -221.585536) (xy 79.221584 -221.549214) (xy 79.170784 -221.549214)
			(xy 79.170784 -221.812358) (xy 79.221584 -221.812358)
		)
		(stroke
			(width 0)
			(type solid)
		)
		(fill yes)
		(layer "F.Cu")
		(net "M_A_CPU1_SB_DQ<20>")
	)
	(gr_poly
		(pts
			(xy 79.323184 -221.179136) (xy 79.323184 -220.988636) (xy 79.221584 -220.952314) (xy 79.170784 -220.952314)
			(xy 79.170784 -221.215458) (xy 79.221584 -221.215458)
		)
		(stroke
			(width 0)
			(type solid)
		)
		(fill yes)
		(layer "F.Cu")
		(net "M_A_CPU1_SB_DQ<20>")
	)
	(gr_poly
		(pts
			(xy 79.323184 -220.582236) (xy 79.323184 -220.391736) (xy 79.221584 -220.355414) (xy 79.170784 -220.355414)
			(xy 79.170784 -220.618558) (xy 79.221584 -220.618558)
		)
		(stroke
			(width 0)
			(type solid)
		)
		(fill yes)
		(layer "F.Cu")
		(net "M_A_CPU1_SB_DQ<20>")
	)
	(gr_poly
		(pts
			(xy 79.323184 -219.985336) (xy 79.323184 -219.794836) (xy 79.221584 -219.758514) (xy 79.170784 -219.758514)
			(xy 79.170784 -220.021658) (xy 79.221584 -220.021658)
		)
		(stroke
			(width 0)
			(type solid)
		)
		(fill yes)
		(layer "F.Cu")
		(net "M_A_CPU1_SB_DQ<20>")
	)
	(gr_poly
		(pts
			(xy 79.323184 -219.388436) (xy 79.323184 -219.197936) (xy 79.221584 -219.161614) (xy 79.170784 -219.161614)
			(xy 79.170784 -219.424758) (xy 79.221584 -219.424758)
		)
		(stroke
			(width 0)
			(type solid)
		)
		(fill yes)
		(layer "F.Cu")
		(net "M_A_CPU1_SB_DQ<20>")
	)
	(gr_poly
		(pts
			(xy 79.323184 -218.791536) (xy 79.323184 -218.601036) (xy 79.221584 -218.564714) (xy 79.170784 -218.564714)
			(xy 79.170784 -218.827858) (xy 79.221584 -218.827858)
		)
		(stroke
			(width 0)
			(type solid)
		)
		(fill yes)
		(layer "F.Cu")
		(net "M_A_CPU1_SB_DQ<20>")
	)
	(gr_poly
		(pts
			(xy 79.323184 -218.194636) (xy 79.323184 -218.004136) (xy 79.221584 -217.967814) (xy 79.170784 -217.967814)
			(xy 79.170784 -218.230958) (xy 79.221584 -218.230958)
		)
		(stroke
			(width 0)
			(type solid)
		)
		(fill yes)
		(layer "F.Cu")
		(net "M_A_CPU1_SB_DQ<20>")
	)
	(gr_poly
		(pts
			(xy 79.323184 -217.597736) (xy 79.323184 -217.407236) (xy 79.221584 -217.370914) (xy 79.170784 -217.370914)
			(xy 79.170784 -217.634058) (xy 79.221584 -217.634058)
		)
		(stroke
			(width 0)
			(type solid)
		)
		(fill yes)
		(layer "F.Cu")
		(net "M_A_CPU1_SB_DQ<20>")
	)
	(gr_poly
		(pts
			(xy 79.323184 -217.000836) (xy 79.323184 -216.810336) (xy 79.221584 -216.774014) (xy 79.170784 -216.774014)
			(xy 79.170784 -217.037158) (xy 79.221584 -217.037158)
		)
		(stroke
			(width 0)
			(type solid)
		)
		(fill yes)
		(layer "F.Cu")
		(net "M_A_CPU1_SB_DQ<20>")
	)
	(gr_poly
		(pts
			(xy 79.323184 -216.403936) (xy 79.323184 -216.213436) (xy 79.221584 -216.177114) (xy 79.170784 -216.177114)
			(xy 79.170784 -216.440258) (xy 79.221584 -216.440258)
		)
		(stroke
			(width 0)
			(type solid)
		)
		(fill yes)
		(layer "F.Cu")
		(net "M_A_CPU1_SB_DQ<20>")
	)
	(gr_poly
		(pts
			(xy 79.323184 -215.807036) (xy 79.323184 -215.616536) (xy 79.221584 -215.580214) (xy 79.170784 -215.580214)
			(xy 79.170784 -215.843358) (xy 79.221584 -215.843358)
		)
		(stroke
			(width 0)
			(type solid)
		)
		(fill yes)
		(layer "F.Cu")
		(net "M_A_CPU1_SB_DQ<20>")
	)
	(gr_poly
		(pts
			(xy 79.35087 -263.670796) (xy 79.304642 -263.57326) (xy 79.268574 -263.537446) (xy 79.0829 -263.72312)
			(xy 79.118714 -263.759188) (xy 79.21625 -263.805416)
		)
		(stroke
			(width 0)
			(type solid)
		)
		(fill yes)
		(layer "F.Cu")
		(net "M_A_CPU1_SA_CB<5>")
	)
	(gr_poly
		(pts
			(xy 79.359506 -270.538448) (xy 79.323438 -270.502634) (xy 79.226156 -270.456406) (xy 79.091282 -270.591026)
			(xy 79.13751 -270.688562) (xy 79.173578 -270.724376)
		)
		(stroke
			(width 0)
			(type solid)
		)
		(fill yes)
		(layer "F.Cu")
		(net "M_A_CPU1_SA_DQ<29>")
	)
	(gr_poly
		(pts
			(xy 79.360268 -264.524236) (xy 79.31404 -264.426954) (xy 79.278226 -264.390886) (xy 79.092298 -264.576814)
			(xy 79.128112 -264.612882) (xy 79.225648 -264.65911)
		)
		(stroke
			(width 0)
			(type solid)
		)
		(fill yes)
		(layer "F.Cu")
		(net "M_A_CPU1_SA_CB<4>")
	)
	(gr_poly
		(pts
			(xy 79.365094 -274.200874) (xy 79.318866 -274.103592) (xy 79.283052 -274.067524) (xy 79.097124 -274.253452)
			(xy 79.132938 -274.28952) (xy 79.230474 -274.335748)
		)
		(stroke
			(width 0)
			(type solid)
		)
		(fill yes)
		(layer "F.Cu")
		(net "M_A_CPU1_SA_DQ<25>")
	)
	(gr_poly
		(pts
			(xy 79.365348 -267.107162) (xy 79.318866 -267.009626) (xy 79.283052 -266.973812) (xy 79.097124 -267.15974)
			(xy 79.133192 -267.195554) (xy 79.230474 -267.241782)
		)
		(stroke
			(width 0)
			(type solid)
		)
		(fill yes)
		(layer "F.Cu")
		(net "M_A_CPU1_SA_CB<1>")
	)
	(gr_poly
		(pts
			(xy 79.369158 -271.392142) (xy 79.33309 -271.356328) (xy 79.235554 -271.3101) (xy 79.100934 -271.44472)
			(xy 79.147162 -271.542256) (xy 79.18323 -271.57807)
		)
		(stroke
			(width 0)
			(type solid)
		)
		(fill yes)
		(layer "F.Cu")
		(net "M_A_CPU1_SA_DQ<28>")
	)
	(gr_poly
		(pts
			(xy 79.374492 -275.054314) (xy 79.32801 -274.956778) (xy 79.292196 -274.920964) (xy 79.106268 -275.106892)
			(xy 79.142336 -275.142706) (xy 79.239618 -275.188934)
		)
		(stroke
			(width 0)
			(type solid)
		)
		(fill yes)
		(layer "F.Cu")
		(net "M_A_CPU1_SA_DQ<24>")
	)
	(gr_poly
		(pts
			(xy 79.374492 -267.960602) (xy 79.328264 -267.86332) (xy 79.29245 -267.827252) (xy 79.106522 -268.01318)
			(xy 79.142336 -268.048994) (xy 79.239872 -268.095222)
		)
		(stroke
			(width 0)
			(type solid)
		)
		(fill yes)
		(layer "F.Cu")
		(net "M_A_CPU1_SA_CB<0>")
	)
	(gr_poly
		(pts
			(xy 79.382366 -233.905298) (xy 79.41818 -233.86923) (xy 79.232252 -233.683302) (xy 79.196438 -233.71937)
			(xy 79.15021 -233.816652) (xy 79.28483 -233.951526)
		)
		(stroke
			(width 0)
			(type solid)
		)
		(fill yes)
		(layer "F.Cu")
		(net "M_A_CPU1_SB_DQ<10>")
	)
	(gr_poly
		(pts
			(xy 79.39151 -233.051858) (xy 79.427324 -233.01579) (xy 79.24165 -232.830116) (xy 79.205582 -232.86593)
			(xy 79.159354 -232.963466) (xy 79.293974 -233.098086)
		)
		(stroke
			(width 0)
			(type solid)
		)
		(fill yes)
		(layer "F.Cu")
		(net "M_A_CPU1_SB_DQ<11>")
	)
	(gr_poly
		(pts
			(xy 79.404464 -226.652836) (xy 79.404464 -226.462336) (xy 79.302864 -226.426014) (xy 79.252064 -226.426014)
			(xy 79.252064 -226.689158) (xy 79.302864 -226.689158)
		)
		(stroke
			(width 0)
			(type solid)
		)
		(fill yes)
		(layer "F.Cu")
		(net "M_A_CPU1_SB_DQ<19>")
	)
	(gr_poly
		(pts
			(xy 79.404464 -226.055936) (xy 79.404464 -225.865436) (xy 79.302864 -225.829114) (xy 79.252064 -225.829114)
			(xy 79.252064 -226.092258) (xy 79.302864 -226.092258)
		)
		(stroke
			(width 0)
			(type solid)
		)
		(fill yes)
		(layer "F.Cu")
		(net "M_A_CPU1_SB_DQ<19>")
	)
	(gr_poly
		(pts
			(xy 79.429356 -230.501698) (xy 79.465424 -230.465884) (xy 79.279496 -230.279956) (xy 79.243428 -230.31577)
			(xy 79.1972 -230.413306) (xy 79.332074 -230.547926)
		)
		(stroke
			(width 0)
			(type solid)
		)
		(fill yes)
		(layer "F.Cu")
		(net "M_A_CPU1_SB_DQ<14>")
	)
	(gr_poly
		(pts
			(xy 79.436976 -270.245078) (xy 79.390494 -270.147542) (xy 79.35468 -270.111728) (xy 79.168752 -270.297656)
			(xy 79.20482 -270.33347) (xy 79.302102 -270.379698)
		)
		(stroke
			(width 0)
			(type solid)
		)
		(fill yes)
		(layer "F.Cu")
		(net "M_A_CPU1_SA_DQ<31>")
	)
	(gr_poly
		(pts
			(xy 79.438754 -229.648258) (xy 79.474568 -229.612444) (xy 79.28864 -229.426516) (xy 79.252826 -229.462584)
			(xy 79.206598 -229.559866) (xy 79.341218 -229.69474)
		)
		(stroke
			(width 0)
			(type solid)
		)
		(fill yes)
		(layer "F.Cu")
		(net "M_A_CPU1_SB_DQ<15>")
	)
	(gr_poly
		(pts
			(xy 79.446628 -271.099026) (xy 79.4004 -271.00149) (xy 79.364332 -270.965676) (xy 79.178658 -271.15135)
			(xy 79.214472 -271.187418) (xy 79.312008 -271.233646)
		)
		(stroke
			(width 0)
			(type solid)
		)
		(fill yes)
		(layer "F.Cu")
		(net "M_A_CPU1_SA_DQ<30>")
	)
	(gr_poly
		(pts
			(xy 79.44866 -228.37902) (xy 79.484474 -228.342952) (xy 79.2988 -228.157278) (xy 79.262732 -228.193092)
			(xy 79.216504 -228.290628) (xy 79.351124 -228.425248)
		)
		(stroke
			(width 0)
			(type solid)
		)
		(fill yes)
		(layer "F.Cu")
		(net "M_A_CPU1_SB_DQ<18>")
	)
	(gr_poly
		(pts
			(xy 79.449422 -234.260136) (xy 79.495904 -234.1626) (xy 79.36103 -234.02798) (xy 79.263748 -234.074208)
			(xy 79.22768 -234.110022) (xy 79.413608 -234.29595)
		)
		(stroke
			(width 0)
			(type solid)
		)
		(fill yes)
		(layer "F.Cu")
		(net "M_A_CPU1_SB_DQ<8>")
	)
	(gr_poly
		(pts
			(xy 79.45882 -233.406696) (xy 79.505048 -233.30916) (xy 79.370174 -233.17454) (xy 79.272892 -233.220768)
			(xy 79.236824 -233.256582) (xy 79.422752 -233.44251)
		)
		(stroke
			(width 0)
			(type solid)
		)
		(fill yes)
		(layer "F.Cu")
		(net "M_A_CPU1_SB_DQ<9>")
	)
	(gr_poly
		(pts
			(xy 79.475584 -221.847918) (xy 79.424784 -221.847918) (xy 79.323184 -221.883986) (xy 79.323184 -222.074486)
			(xy 79.424784 -222.110554) (xy 79.475584 -222.110554)
		)
		(stroke
			(width 0)
			(type solid)
		)
		(fill yes)
		(layer "F.Cu")
		(net "M_A_CPU1_SB_DQ<22>")
	)
	(gr_poly
		(pts
			(xy 79.475584 -221.251018) (xy 79.424784 -221.251018) (xy 79.323184 -221.287086) (xy 79.323184 -221.477586)
			(xy 79.424784 -221.513654) (xy 79.475584 -221.513654)
		)
		(stroke
			(width 0)
			(type solid)
		)
		(fill yes)
		(layer "F.Cu")
		(net "M_A_CPU1_SB_DQ<22>")
	)
	(gr_poly
		(pts
			(xy 79.475584 -220.654118) (xy 79.424784 -220.654118) (xy 79.323184 -220.690186) (xy 79.323184 -220.880686)
			(xy 79.424784 -220.916754) (xy 79.475584 -220.916754)
		)
		(stroke
			(width 0)
			(type solid)
		)
		(fill yes)
		(layer "F.Cu")
		(net "M_A_CPU1_SB_DQ<22>")
	)
	(gr_poly
		(pts
			(xy 79.475584 -220.057218) (xy 79.424784 -220.057218) (xy 79.323184 -220.093286) (xy 79.323184 -220.283786)
			(xy 79.424784 -220.319854) (xy 79.475584 -220.319854)
		)
		(stroke
			(width 0)
			(type solid)
		)
		(fill yes)
		(layer "F.Cu")
		(net "M_A_CPU1_SB_DQ<22>")
	)
	(gr_poly
		(pts
			(xy 79.475584 -219.460318) (xy 79.424784 -219.460318) (xy 79.323184 -219.496386) (xy 79.323184 -219.686886)
			(xy 79.424784 -219.722954) (xy 79.475584 -219.722954)
		)
		(stroke
			(width 0)
			(type solid)
		)
		(fill yes)
		(layer "F.Cu")
		(net "M_A_CPU1_SB_DQ<22>")
	)
	(gr_poly
		(pts
			(xy 79.475584 -218.863418) (xy 79.424784 -218.863418) (xy 79.323184 -218.899486) (xy 79.323184 -219.089986)
			(xy 79.424784 -219.126054) (xy 79.475584 -219.126054)
		)
		(stroke
			(width 0)
			(type solid)
		)
		(fill yes)
		(layer "F.Cu")
		(net "M_A_CPU1_SB_DQ<22>")
	)
	(gr_poly
		(pts
			(xy 79.475584 -218.266518) (xy 79.424784 -218.266518) (xy 79.323184 -218.302586) (xy 79.323184 -218.493086)
			(xy 79.424784 -218.529154) (xy 79.475584 -218.529154)
		)
		(stroke
			(width 0)
			(type solid)
		)
		(fill yes)
		(layer "F.Cu")
		(net "M_A_CPU1_SB_DQ<22>")
	)
	(gr_poly
		(pts
			(xy 79.475584 -217.669618) (xy 79.424784 -217.669618) (xy 79.323184 -217.705686) (xy 79.323184 -217.896186)
			(xy 79.424784 -217.932254) (xy 79.475584 -217.932254)
		)
		(stroke
			(width 0)
			(type solid)
		)
		(fill yes)
		(layer "F.Cu")
		(net "M_A_CPU1_SB_DQ<22>")
	)
	(gr_poly
		(pts
			(xy 79.475584 -217.072718) (xy 79.424784 -217.072718) (xy 79.323184 -217.108786) (xy 79.323184 -217.299286)
			(xy 79.424784 -217.335354) (xy 79.475584 -217.335354)
		)
		(stroke
			(width 0)
			(type solid)
		)
		(fill yes)
		(layer "F.Cu")
		(net "M_A_CPU1_SB_DQ<22>")
	)
	(gr_poly
		(pts
			(xy 79.475584 -216.475818) (xy 79.424784 -216.475818) (xy 79.323184 -216.511886) (xy 79.323184 -216.702386)
			(xy 79.424784 -216.738454) (xy 79.475584 -216.738454)
		)
		(stroke
			(width 0)
			(type solid)
		)
		(fill yes)
		(layer "F.Cu")
		(net "M_A_CPU1_SB_DQ<22>")
	)
	(gr_poly
		(pts
			(xy 79.475584 -215.878918) (xy 79.424784 -215.878918) (xy 79.323184 -215.914986) (xy 79.323184 -216.105486)
			(xy 79.424784 -216.141554) (xy 79.475584 -216.141554)
		)
		(stroke
			(width 0)
			(type solid)
		)
		(fill yes)
		(layer "F.Cu")
		(net "M_A_CPU1_SB_DQ<22>")
	)
	(gr_poly
		(pts
			(xy 79.475584 -215.282018) (xy 79.424784 -215.282018) (xy 79.323184 -215.318086) (xy 79.323184 -215.508586)
			(xy 79.424784 -215.544654) (xy 79.475584 -215.544654)
		)
		(stroke
			(width 0)
			(type solid)
		)
		(fill yes)
		(layer "F.Cu")
		(net "M_A_CPU1_SB_DQ<22>")
	)
	(gr_poly
		(pts
			(xy 79.479648 -263.326372) (xy 79.443834 -263.290304) (xy 79.346298 -263.244076) (xy 79.211678 -263.37895)
			(xy 79.257906 -263.476232) (xy 79.29372 -263.5123)
		)
		(stroke
			(width 0)
			(type solid)
		)
		(fill yes)
		(layer "F.Cu")
		(net "M_A_CPU1_SA_CB<5>")
	)
	(gr_poly
		(pts
			(xy 79.4893 -264.179812) (xy 79.453232 -264.143998) (xy 79.35595 -264.09777) (xy 79.221076 -264.23239)
			(xy 79.267304 -264.329926) (xy 79.303372 -264.36574)
		)
		(stroke
			(width 0)
			(type solid)
		)
		(fill yes)
		(layer "F.Cu")
		(net "M_A_CPU1_SA_CB<4>")
	)
	(gr_poly
		(pts
			(xy 79.494126 -273.85645) (xy 79.458058 -273.820636) (xy 79.360776 -273.774408) (xy 79.225902 -273.909028)
			(xy 79.27213 -274.006564) (xy 79.308198 -274.042378)
		)
		(stroke
			(width 0)
			(type solid)
		)
		(fill yes)
		(layer "F.Cu")
		(net "M_A_CPU1_SA_DQ<25>")
	)
	(gr_poly
		(pts
			(xy 79.494126 -266.762738) (xy 79.458312 -266.726924) (xy 79.360776 -266.680696) (xy 79.226156 -266.815316)
			(xy 79.272384 -266.912852) (xy 79.308198 -266.948666)
		)
		(stroke
			(width 0)
			(type solid)
		)
		(fill yes)
		(layer "F.Cu")
		(net "M_A_CPU1_SA_CB<1>")
	)
	(gr_poly
		(pts
			(xy 79.496412 -230.85679) (xy 79.542894 -230.759254) (xy 79.40802 -230.624634) (xy 79.310738 -230.670862)
			(xy 79.27467 -230.706676) (xy 79.460598 -230.892604)
		)
		(stroke
			(width 0)
			(type solid)
		)
		(fill yes)
		(layer "F.Cu")
		(net "M_A_CPU1_SB_DQ<12>")
	)
	(gr_poly
		(pts
			(xy 79.50327 -274.70989) (xy 79.467456 -274.674076) (xy 79.36992 -274.627848) (xy 79.2353 -274.762468)
			(xy 79.281528 -274.860004) (xy 79.317342 -274.895818)
		)
		(stroke
			(width 0)
			(type solid)
		)
		(fill yes)
		(layer "F.Cu")
		(net "M_A_CPU1_SA_DQ<24>")
	)
	(gr_poly
		(pts
			(xy 79.503524 -267.616178) (xy 79.467456 -267.580364) (xy 79.370174 -267.534136) (xy 79.2353 -267.668756)
			(xy 79.281528 -267.766292) (xy 79.317596 -267.802106)
		)
		(stroke
			(width 0)
			(type solid)
		)
		(fill yes)
		(layer "F.Cu")
		(net "M_A_CPU1_SA_CB<0>")
	)
	(gr_poly
		(pts
			(xy 79.50581 -230.003096) (xy 79.552038 -229.905814) (xy 79.417418 -229.771194) (xy 79.319882 -229.817422)
			(xy 79.284068 -229.853236) (xy 79.469996 -230.039164)
		)
		(stroke
			(width 0)
			(type solid)
		)
		(fill yes)
		(layer "F.Cu")
		(net "M_A_CPU1_SB_DQ<13>")
	)
	(gr_poly
		(pts
			(xy 79.51597 -228.733858) (xy 79.562198 -228.636322) (xy 79.427324 -228.501702) (xy 79.330042 -228.54793)
			(xy 79.293974 -228.583744) (xy 79.479902 -228.769672)
		)
		(stroke
			(width 0)
			(type solid)
		)
		(fill yes)
		(layer "F.Cu")
		(net "M_A_CPU1_SB_DQ<16>")
	)
	(gr_poly
		(pts
			(xy 79.525114 -227.880418) (xy 79.571342 -227.783136) (xy 79.436722 -227.648262) (xy 79.339186 -227.69449)
			(xy 79.303372 -227.730558) (xy 79.4893 -227.916486)
		)
		(stroke
			(width 0)
			(type solid)
		)
		(fill yes)
		(layer "F.Cu")
		(net "M_A_CPU1_SB_DQ<17>")
	)
	(gr_poly
		(pts
			(xy 79.534512 -276.958044) (xy 79.462122 -276.878288) (xy 79.417164 -276.854412) (xy 79.293212 -277.08606)
			(xy 79.337916 -277.11019) (xy 79.444596 -277.126192)
		)
		(stroke
			(width 0)
			(type solid)
		)
		(fill yes)
		(layer "F.Cu")
		(net "M_A_CPU1_SA_DQ<22>")
	)
	(gr_poly
		(pts
			(xy 79.545434 -277.261574) (xy 79.50073 -277.237444) (xy 79.39405 -277.221442) (xy 79.304134 -277.389336)
			(xy 79.376778 -277.469346) (xy 79.421482 -277.493222)
		)
		(stroke
			(width 0)
			(type solid)
		)
		(fill yes)
		(layer "F.Cu")
		(net "M_A_CPU1_SA_DQ<20>")
	)
	(gr_poly
		(pts
			(xy 79.547212 -276.287992) (xy 79.474822 -276.208236) (xy 79.429864 -276.184106) (xy 79.305912 -276.416008)
			(xy 79.350616 -276.439884) (xy 79.457296 -276.455886)
		)
		(stroke
			(width 0)
			(type solid)
		)
		(fill yes)
		(layer "F.Cu")
		(net "M_A_CPU1_SA_DQ<21>")
	)
	(gr_poly
		(pts
			(xy 79.55534 -249.270266) (xy 79.519272 -249.168666) (xy 79.328772 -249.168666) (xy 79.29245 -249.270266)
			(xy 79.29245 -249.321066) (xy 79.55534 -249.321066)
		)
		(stroke
			(width 0)
			(type solid)
		)
		(fill yes)
		(layer "F.Cu")
		(net "M_A_CPU1_SB_CA<0>")
	)
	(gr_poly
		(pts
			(xy 79.55534 -248.965212) (xy 79.519272 -248.863612) (xy 79.328772 -248.863612) (xy 79.29245 -248.965212)
			(xy 79.29245 -249.016012) (xy 79.55534 -249.016012)
		)
		(stroke
			(width 0)
			(type solid)
		)
		(fill yes)
		(layer "F.Cu")
		(net "M_A_CPU1_SB_CA<1>")
	)
	(gr_poly
		(pts
			(xy 79.55534 -248.660412) (xy 79.519272 -248.558812) (xy 79.328772 -248.558812) (xy 79.29245 -248.660412)
			(xy 79.29245 -248.711212) (xy 79.55534 -248.711212)
		)
		(stroke
			(width 0)
			(type solid)
		)
		(fill yes)
		(layer "F.Cu")
		(net "M_A_CPU1_SB_CA<2>")
	)
	(gr_poly
		(pts
			(xy 79.55534 -248.355612) (xy 79.519272 -248.254012) (xy 79.328772 -248.254012) (xy 79.29245 -248.355612)
			(xy 79.29245 -248.406412) (xy 79.55534 -248.406412)
		)
		(stroke
			(width 0)
			(type solid)
		)
		(fill yes)
		(layer "F.Cu")
		(net "M_A_CPU1_SB_CA<3>")
	)
	(gr_poly
		(pts
			(xy 79.55534 -248.050812) (xy 79.519272 -247.949212) (xy 79.328772 -247.949212) (xy 79.29245 -248.050812)
			(xy 79.29245 -248.101612) (xy 79.55534 -248.101612)
		)
		(stroke
			(width 0)
			(type solid)
		)
		(fill yes)
		(layer "F.Cu")
		(net "M_A_CPU1_SB_CA<4>")
	)
	(gr_poly
		(pts
			(xy 79.55534 -247.746012) (xy 79.519272 -247.644412) (xy 79.328772 -247.644412) (xy 79.29245 -247.746012)
			(xy 79.29245 -247.796812) (xy 79.55534 -247.796812)
		)
		(stroke
			(width 0)
			(type solid)
		)
		(fill yes)
		(layer "F.Cu")
		(net "M_A_CPU1_SB_CA<5>")
	)
	(gr_poly
		(pts
			(xy 79.55534 -247.441212) (xy 79.519272 -247.339612) (xy 79.328772 -247.339612) (xy 79.29245 -247.441212)
			(xy 79.29245 -247.492012) (xy 79.55534 -247.492012)
		)
		(stroke
			(width 0)
			(type solid)
		)
		(fill yes)
		(layer "F.Cu")
		(net "M_A_CPU1_SB_CA<6>")
	)
	(gr_poly
		(pts
			(xy 79.55534 -247.136412) (xy 79.519272 -247.034812) (xy 79.328772 -247.034812) (xy 79.29245 -247.136412)
			(xy 79.29245 -247.187212) (xy 79.55534 -247.187212)
		)
		(stroke
			(width 0)
			(type solid)
		)
		(fill yes)
		(layer "F.Cu")
		(net "M_A_CPU1_SB_PAR")
	)
	(gr_poly
		(pts
			(xy 79.55534 -246.831612) (xy 79.519272 -246.730012) (xy 79.328772 -246.730012) (xy 79.29245 -246.831612)
			(xy 79.29245 -246.882412) (xy 79.55534 -246.882412)
		)
		(stroke
			(width 0)
			(type solid)
		)
		(fill yes)
		(layer "F.Cu")
		(net "M_A_CPU1_SB_CS_N<2>")
	)
	(gr_poly
		(pts
			(xy 79.55534 -246.526812) (xy 79.519272 -246.425212) (xy 79.328772 -246.425212) (xy 79.29245 -246.526812)
			(xy 79.29245 -246.577612) (xy 79.55534 -246.577612)
		)
		(stroke
			(width 0)
			(type solid)
		)
		(fill yes)
		(layer "F.Cu")
		(net "M_A_CPU1_SB_CS_N<0>")
	)
	(gr_poly
		(pts
			(xy 79.55534 -246.222012) (xy 79.519272 -246.120412) (xy 79.328772 -246.120412) (xy 79.29245 -246.222012)
			(xy 79.29245 -246.272812) (xy 79.55534 -246.272812)
		)
		(stroke
			(width 0)
			(type solid)
		)
		(fill yes)
		(layer "F.Cu")
		(net "M_A_CPU1_SB_CS_N<3>")
	)
	(gr_poly
		(pts
			(xy 79.55534 -245.917212) (xy 79.519272 -245.815612) (xy 79.328772 -245.815612) (xy 79.29245 -245.917212)
			(xy 79.29245 -245.968012) (xy 79.55534 -245.968012)
		)
		(stroke
			(width 0)
			(type solid)
		)
		(fill yes)
		(layer "F.Cu")
		(net "M_A_CPU1_SB_CS_N<1>")
	)
	(gr_poly
		(pts
			(xy 79.557118 -263.032748) (xy 79.51089 -262.935466) (xy 79.475076 -262.899398) (xy 79.289148 -263.085326)
			(xy 79.324962 -263.121394) (xy 79.422498 -263.167622)
		)
		(stroke
			(width 0)
			(type solid)
		)
		(fill yes)
		(layer "F.Cu")
		(net "M_A_CPU1_SA_CB<7>")
	)
	(gr_poly
		(pts
			(xy 79.558134 -276.591268) (xy 79.513176 -276.567138) (xy 79.406496 -276.551136) (xy 79.31658 -276.719284)
			(xy 79.389224 -276.79904) (xy 79.433928 -276.822916)
		)
		(stroke
			(width 0)
			(type solid)
		)
		(fill yes)
		(layer "F.Cu")
		(net "M_A_CPU1_SA_DQ<22>")
	)
	(gr_poly
		(pts
			(xy 79.565754 -269.900654) (xy 79.52994 -269.86484) (xy 79.432404 -269.818612) (xy 79.297784 -269.953232)
			(xy 79.344012 -270.050768) (xy 79.379826 -270.086582)
		)
		(stroke
			(width 0)
			(type solid)
		)
		(fill yes)
		(layer "F.Cu")
		(net "M_A_CPU1_SA_DQ<31>")
	)
	(gr_poly
		(pts
			(xy 79.566516 -263.886442) (xy 79.520288 -263.788906) (xy 79.484474 -263.753092) (xy 79.298546 -263.93902)
			(xy 79.33436 -263.974834) (xy 79.431896 -264.021062)
		)
		(stroke
			(width 0)
			(type solid)
		)
		(fill yes)
		(layer "F.Cu")
		(net "M_A_CPU1_SA_CB<6>")
	)
	(gr_poly
		(pts
			(xy 79.571342 -273.56308) (xy 79.525114 -273.465544) (xy 79.489046 -273.42973) (xy 79.303372 -273.615404)
			(xy 79.339186 -273.651472) (xy 79.436722 -273.6977)
		)
		(stroke
			(width 0)
			(type solid)
		)
		(fill yes)
		(layer "F.Cu")
		(net "M_A_CPU1_SA_DQ<27>")
	)
	(gr_poly
		(pts
			(xy 79.571596 -266.469368) (xy 79.525368 -266.372086) (xy 79.489554 -266.336018) (xy 79.303626 -266.521946)
			(xy 79.33944 -266.55776) (xy 79.436976 -266.604242)
		)
		(stroke
			(width 0)
			(type solid)
		)
		(fill yes)
		(layer "F.Cu")
		(net "M_A_CPU1_SA_CB<3>")
	)
	(gr_poly
		(pts
			(xy 79.575406 -270.754602) (xy 79.539592 -270.718534) (xy 79.442056 -270.672306) (xy 79.307436 -270.80718)
			(xy 79.353664 -270.904462) (xy 79.389478 -270.94053)
		)
		(stroke
			(width 0)
			(type solid)
		)
		(fill yes)
		(layer "F.Cu")
		(net "M_A_CPU1_SA_DQ<30>")
	)
	(gr_poly
		(pts
			(xy 79.58074 -274.41652) (xy 79.534512 -274.319238) (xy 79.498698 -274.28317) (xy 79.31277 -274.469098)
			(xy 79.348584 -274.505166) (xy 79.44612 -274.551394)
		)
		(stroke
			(width 0)
			(type solid)
		)
		(fill yes)
		(layer "F.Cu")
		(net "M_A_CPU1_SA_DQ<26>")
	)
	(gr_poly
		(pts
			(xy 79.580994 -267.322808) (xy 79.534766 -267.225526) (xy 79.498952 -267.189458) (xy 79.313024 -267.375386)
			(xy 79.348838 -267.411454) (xy 79.446374 -267.457682)
		)
		(stroke
			(width 0)
			(type solid)
		)
		(fill yes)
		(layer "F.Cu")
		(net "M_A_CPU1_SA_CB<2>")
	)
	(gr_poly
		(pts
			(xy 79.588106 -258.805426) (xy 79.588106 -258.754626) (xy 79.325216 -258.754626) (xy 79.325216 -258.805426)
			(xy 79.361284 -258.907026) (xy 79.551784 -258.907026)
		)
		(stroke
			(width 0)
			(type solid)
		)
		(fill yes)
		(layer "F.Cu")
		(net "M_A_CPU1_SA_CS_N<1>")
	)
	(gr_poly
		(pts
			(xy 79.588106 -258.500626) (xy 79.588106 -258.449826) (xy 79.325216 -258.449826) (xy 79.325216 -258.500626)
			(xy 79.361284 -258.602226) (xy 79.551784 -258.602226)
		)
		(stroke
			(width 0)
			(type solid)
		)
		(fill yes)
		(layer "F.Cu")
		(net "M_A_CPU1_SA_CA<0>")
	)
	(gr_poly
		(pts
			(xy 79.588106 -258.195826) (xy 79.588106 -258.145026) (xy 79.325216 -258.145026) (xy 79.325216 -258.195826)
			(xy 79.361284 -258.297426) (xy 79.551784 -258.297426)
		)
		(stroke
			(width 0)
			(type solid)
		)
		(fill yes)
		(layer "F.Cu")
		(net "M_A_CPU1_SA_CA<1>")
	)
	(gr_poly
		(pts
			(xy 79.588106 -257.891026) (xy 79.588106 -257.840226) (xy 79.325216 -257.840226) (xy 79.325216 -257.891026)
			(xy 79.361284 -257.992626) (xy 79.551784 -257.992626)
		)
		(stroke
			(width 0)
			(type solid)
		)
		(fill yes)
		(layer "F.Cu")
		(net "M_A_CPU1_SA_CA<2>")
	)
	(gr_poly
		(pts
			(xy 79.588106 -257.586226) (xy 79.588106 -257.535426) (xy 79.325216 -257.535426) (xy 79.325216 -257.586226)
			(xy 79.361284 -257.687826) (xy 79.551784 -257.687826)
		)
		(stroke
			(width 0)
			(type solid)
		)
		(fill yes)
		(layer "F.Cu")
		(net "M_A_CPU1_SA_CA<3>")
	)
	(gr_poly
		(pts
			(xy 79.588106 -257.281426) (xy 79.588106 -257.230626) (xy 79.325216 -257.230626) (xy 79.325216 -257.281426)
			(xy 79.361284 -257.383026) (xy 79.551784 -257.383026)
		)
		(stroke
			(width 0)
			(type solid)
		)
		(fill yes)
		(layer "F.Cu")
		(net "M_A_CPU1_SA_CA<4>")
	)
	(gr_poly
		(pts
			(xy 79.588106 -256.976626) (xy 79.588106 -256.925826) (xy 79.325216 -256.925826) (xy 79.325216 -256.976626)
			(xy 79.361284 -257.078226) (xy 79.551784 -257.078226)
		)
		(stroke
			(width 0)
			(type solid)
		)
		(fill yes)
		(layer "F.Cu")
		(net "M_A_CPU1_SA_CA<5>")
	)
	(gr_poly
		(pts
			(xy 79.588106 -256.671826) (xy 79.588106 -256.621026) (xy 79.325216 -256.621026) (xy 79.325216 -256.671826)
			(xy 79.361284 -256.773426) (xy 79.551784 -256.773426)
		)
		(stroke
			(width 0)
			(type solid)
		)
		(fill yes)
		(layer "F.Cu")
		(net "M_A_CPU1_SA_CA<6>")
	)
	(gr_poly
		(pts
			(xy 79.588106 -256.367026) (xy 79.588106 -256.316226) (xy 79.325216 -256.316226) (xy 79.325216 -256.367026)
			(xy 79.361284 -256.468626) (xy 79.551784 -256.468626)
		)
		(stroke
			(width 0)
			(type solid)
		)
		(fill yes)
		(layer "F.Cu")
		(net "M_A_CPU1_SA_PAR")
	)
	(gr_poly
		(pts
			(xy 79.588614 -234.542838) (xy 79.624682 -234.507024) (xy 79.438754 -234.321096) (xy 79.40294 -234.35691)
			(xy 79.356712 -234.454446) (xy 79.491332 -234.589066)
		)
		(stroke
			(width 0)
			(type solid)
		)
		(fill yes)
		(layer "F.Cu")
		(net "M_A_CPU1_SB_DQ<8>")
	)
	(gr_poly
		(pts
			(xy 79.598012 -233.689652) (xy 79.633826 -233.653584) (xy 79.447898 -233.467656) (xy 79.412084 -233.503724)
			(xy 79.365856 -233.601006) (xy 79.500476 -233.73588)
		)
		(stroke
			(width 0)
			(type solid)
		)
		(fill yes)
		(layer "F.Cu")
		(net "M_A_CPU1_SB_DQ<9>")
	)
	(gr_poly
		(pts
			(xy 79.627984 -222.372936) (xy 79.627984 -222.182436) (xy 79.526384 -222.146114) (xy 79.475584 -222.146114)
			(xy 79.475584 -222.409258) (xy 79.526384 -222.409258)
		)
		(stroke
			(width 0)
			(type solid)
		)
		(fill yes)
		(layer "F.Cu")
		(net "M_A_CPU1_SB_DQ<22>")
	)
	(gr_poly
		(pts
			(xy 79.627984 -221.776036) (xy 79.627984 -221.585536) (xy 79.526384 -221.549214) (xy 79.475584 -221.549214)
			(xy 79.475584 -221.812358) (xy 79.526384 -221.812358)
		)
		(stroke
			(width 0)
			(type solid)
		)
		(fill yes)
		(layer "F.Cu")
		(net "M_A_CPU1_SB_DQ<22>")
	)
	(gr_poly
		(pts
			(xy 79.627984 -221.179136) (xy 79.627984 -220.988636) (xy 79.526384 -220.952314) (xy 79.475584 -220.952314)
			(xy 79.475584 -221.215458) (xy 79.526384 -221.215458)
		)
		(stroke
			(width 0)
			(type solid)
		)
		(fill yes)
		(layer "F.Cu")
		(net "M_A_CPU1_SB_DQ<22>")
	)
	(gr_poly
		(pts
			(xy 79.627984 -220.582236) (xy 79.627984 -220.391736) (xy 79.526384 -220.355414) (xy 79.475584 -220.355414)
			(xy 79.475584 -220.618558) (xy 79.526384 -220.618558)
		)
		(stroke
			(width 0)
			(type solid)
		)
		(fill yes)
		(layer "F.Cu")
		(net "M_A_CPU1_SB_DQ<22>")
	)
	(gr_poly
		(pts
			(xy 79.627984 -219.985336) (xy 79.627984 -219.794836) (xy 79.526384 -219.758514) (xy 79.475584 -219.758514)
			(xy 79.475584 -220.021658) (xy 79.526384 -220.021658)
		)
		(stroke
			(width 0)
			(type solid)
		)
		(fill yes)
		(layer "F.Cu")
		(net "M_A_CPU1_SB_DQ<22>")
	)
	(gr_poly
		(pts
			(xy 79.627984 -219.388436) (xy 79.627984 -219.197936) (xy 79.526384 -219.161614) (xy 79.475584 -219.161614)
			(xy 79.475584 -219.424758) (xy 79.526384 -219.424758)
		)
		(stroke
			(width 0)
			(type solid)
		)
		(fill yes)
		(layer "F.Cu")
		(net "M_A_CPU1_SB_DQ<22>")
	)
	(gr_poly
		(pts
			(xy 79.627984 -218.791536) (xy 79.627984 -218.601036) (xy 79.526384 -218.564714) (xy 79.475584 -218.564714)
			(xy 79.475584 -218.827858) (xy 79.526384 -218.827858)
		)
		(stroke
			(width 0)
			(type solid)
		)
		(fill yes)
		(layer "F.Cu")
		(net "M_A_CPU1_SB_DQ<22>")
	)
	(gr_poly
		(pts
			(xy 79.627984 -218.194636) (xy 79.627984 -218.004136) (xy 79.526384 -217.967814) (xy 79.475584 -217.967814)
			(xy 79.475584 -218.230958) (xy 79.526384 -218.230958)
		)
		(stroke
			(width 0)
			(type solid)
		)
		(fill yes)
		(layer "F.Cu")
		(net "M_A_CPU1_SB_DQ<22>")
	)
	(gr_poly
		(pts
			(xy 79.627984 -217.597736) (xy 79.627984 -217.407236) (xy 79.526384 -217.370914) (xy 79.475584 -217.370914)
			(xy 79.475584 -217.634058) (xy 79.526384 -217.634058)
		)
		(stroke
			(width 0)
			(type solid)
		)
		(fill yes)
		(layer "F.Cu")
		(net "M_A_CPU1_SB_DQ<22>")
	)
	(gr_poly
		(pts
			(xy 79.627984 -217.000836) (xy 79.627984 -216.810336) (xy 79.526384 -216.774014) (xy 79.475584 -216.774014)
			(xy 79.475584 -217.037158) (xy 79.526384 -217.037158)
		)
		(stroke
			(width 0)
			(type solid)
		)
		(fill yes)
		(layer "F.Cu")
		(net "M_A_CPU1_SB_DQ<22>")
	)
	(gr_poly
		(pts
			(xy 79.627984 -216.403936) (xy 79.627984 -216.213436) (xy 79.526384 -216.177114) (xy 79.475584 -216.177114)
			(xy 79.475584 -216.440258) (xy 79.526384 -216.440258)
		)
		(stroke
			(width 0)
			(type solid)
		)
		(fill yes)
		(layer "F.Cu")
		(net "M_A_CPU1_SB_DQ<22>")
	)
	(gr_poly
		(pts
			(xy 79.627984 -215.807036) (xy 79.627984 -215.616536) (xy 79.526384 -215.580214) (xy 79.475584 -215.580214)
			(xy 79.475584 -215.843358) (xy 79.526384 -215.843358)
		)
		(stroke
			(width 0)
			(type solid)
		)
		(fill yes)
		(layer "F.Cu")
		(net "M_A_CPU1_SB_DQ<22>")
	)
	(gr_poly
		(pts
			(xy 79.627984 -215.210136) (xy 79.627984 -215.019636) (xy 79.526384 -214.983314) (xy 79.475584 -214.983314)
			(xy 79.475584 -215.246458) (xy 79.526384 -215.246458)
		)
		(stroke
			(width 0)
			(type solid)
		)
		(fill yes)
		(layer "F.Cu")
		(net "M_A_CPU1_SB_DQ<22>")
	)
	(gr_poly
		(pts
			(xy 79.635858 -231.139492) (xy 79.671672 -231.103678) (xy 79.485744 -230.91775) (xy 79.44993 -230.953564)
			(xy 79.403702 -231.0511) (xy 79.538322 -231.18572)
		)
		(stroke
			(width 0)
			(type solid)
		)
		(fill yes)
		(layer "F.Cu")
		(net "M_A_CPU1_SB_DQ<12>")
	)
	(gr_poly
		(pts
			(xy 79.645002 -230.286052) (xy 79.68107 -230.250238) (xy 79.495142 -230.06431) (xy 79.459074 -230.100124)
			(xy 79.412846 -230.19766) (xy 79.54772 -230.33228)
		)
		(stroke
			(width 0)
			(type solid)
		)
		(fill yes)
		(layer "F.Cu")
		(net "M_A_CPU1_SB_DQ<13>")
	)
	(gr_poly
		(pts
			(xy 79.64551 -275.454618) (xy 79.609696 -275.41855) (xy 79.51216 -275.372322) (xy 79.37754 -275.507196)
			(xy 79.423768 -275.604478) (xy 79.459836 -275.640546)
		)
		(stroke
			(width 0)
			(type solid)
		)
		(fill yes)
		(layer "F.Cu")
		(net "M_A_CPU1_SA_DQ<23>")
	)
	(gr_poly
		(pts
			(xy 79.652622 -270.460724) (xy 79.606394 -270.363442) (xy 79.57058 -270.327374) (xy 79.384652 -270.513302)
			(xy 79.420466 -270.54937) (xy 79.518002 -270.595598)
		)
		(stroke
			(width 0)
			(type solid)
		)
		(fill yes)
		(layer "F.Cu")
		(net "M_A_CPU1_SA_DQ<29>")
	)
	(gr_poly
		(pts
			(xy 79.655162 -229.016814) (xy 79.690976 -228.980746) (xy 79.505048 -228.794818) (xy 79.469234 -228.830886)
			(xy 79.423006 -228.928168) (xy 79.557626 -229.063042)
		)
		(stroke
			(width 0)
			(type solid)
		)
		(fill yes)
		(layer "F.Cu")
		(net "M_A_CPU1_SB_DQ<16>")
	)
	(gr_poly
		(pts
			(xy 79.662274 -271.314672) (xy 79.616046 -271.217136) (xy 79.579978 -271.181322) (xy 79.394304 -271.366996)
			(xy 79.430118 -271.403064) (xy 79.527654 -271.449292)
		)
		(stroke
			(width 0)
			(type solid)
		)
		(fill yes)
		(layer "F.Cu")
		(net "M_A_CPU1_SA_DQ<28>")
	)
	(gr_poly
		(pts
			(xy 79.664306 -228.163374) (xy 79.70012 -228.127306) (xy 79.514446 -227.941632) (xy 79.478378 -227.977446)
			(xy 79.43215 -228.074982) (xy 79.56677 -228.209602)
		)
		(stroke
			(width 0)
			(type solid)
		)
		(fill yes)
		(layer "F.Cu")
		(net "M_A_CPU1_SB_DQ<17>")
	)
	(gr_poly
		(pts
			(xy 79.665068 -234.04449) (xy 79.71155 -233.946954) (xy 79.576676 -233.812334) (xy 79.479394 -233.858562)
			(xy 79.443326 -233.894376) (xy 79.629254 -234.080304)
		)
		(stroke
			(width 0)
			(type solid)
		)
		(fill yes)
		(layer "F.Cu")
		(net "M_A_CPU1_SB_DQ<10>")
	)
	(gr_poly
		(pts
			(xy 79.674466 -233.19105) (xy 79.720694 -233.093514) (xy 79.58582 -232.958894) (xy 79.488538 -233.005122)
			(xy 79.45247 -233.040936) (xy 79.638398 -233.226864)
		)
		(stroke
			(width 0)
			(type solid)
		)
		(fill yes)
		(layer "F.Cu")
		(net "M_A_CPU1_SB_DQ<11>")
	)
	(gr_poly
		(pts
			(xy 79.680308 -223.308672) (xy 79.726536 -223.211136) (xy 79.591662 -223.076516) (xy 79.49438 -223.122744)
			(xy 79.458312 -223.158558) (xy 79.64424 -223.344486)
		)
		(stroke
			(width 0)
			(type solid)
		)
		(fill yes)
		(layer "F.Cu")
		(net "M_A_CPU1_SB_DQ<20>")
	)
	(gr_poly
		(pts
			(xy 79.685896 -262.688578) (xy 79.650082 -262.65251) (xy 79.552546 -262.606282) (xy 79.417926 -262.740902)
			(xy 79.464154 -262.838438) (xy 79.500222 -262.874252)
		)
		(stroke
			(width 0)
			(type solid)
		)
		(fill yes)
		(layer "F.Cu")
		(net "M_A_CPU1_SA_CB<7>")
	)
	(gr_poly
		(pts
			(xy 79.695548 -263.542018) (xy 79.65948 -263.506204) (xy 79.562198 -263.459976) (xy 79.427324 -263.594596)
			(xy 79.473806 -263.692132) (xy 79.50962 -263.727946)
		)
		(stroke
			(width 0)
			(type solid)
		)
		(fill yes)
		(layer "F.Cu")
		(net "M_A_CPU1_SA_CB<6>")
	)
	(gr_poly
		(pts
			(xy 79.70012 -273.218656) (xy 79.664306 -273.182588) (xy 79.56677 -273.13636) (xy 79.43215 -273.271234)
			(xy 79.478378 -273.368516) (xy 79.514192 -273.404584)
		)
		(stroke
			(width 0)
			(type solid)
		)
		(fill yes)
		(layer "F.Cu")
		(net "M_A_CPU1_SA_DQ<27>")
	)
	(gr_poly
		(pts
			(xy 79.700628 -266.124944) (xy 79.66456 -266.08913) (xy 79.567278 -266.042902) (xy 79.432404 -266.177522)
			(xy 79.478632 -266.275058) (xy 79.5147 -266.310872)
		)
		(stroke
			(width 0)
			(type solid)
		)
		(fill yes)
		(layer "F.Cu")
		(net "M_A_CPU1_SA_CB<3>")
	)
	(gr_poly
		(pts
			(xy 79.709772 -274.072096) (xy 79.673704 -274.036282) (xy 79.576422 -273.990054) (xy 79.441548 -274.124674)
			(xy 79.487776 -274.22221) (xy 79.523844 -274.258024)
		)
		(stroke
			(width 0)
			(type solid)
		)
		(fill yes)
		(layer "F.Cu")
		(net "M_A_CPU1_SA_DQ<26>")
	)
	(gr_poly
		(pts
			(xy 79.709772 -266.978638) (xy 79.673958 -266.94257) (xy 79.576422 -266.896342) (xy 79.441802 -267.030962)
			(xy 79.48803 -267.128498) (xy 79.524098 -267.164312)
		)
		(stroke
			(width 0)
			(type solid)
		)
		(fill yes)
		(layer "F.Cu")
		(net "M_A_CPU1_SA_CB<2>")
	)
	(gr_poly
		(pts
			(xy 79.712312 -230.64089) (xy 79.75854 -230.543608) (xy 79.62392 -230.408734) (xy 79.526384 -230.454962)
			(xy 79.49057 -230.49103) (xy 79.676498 -230.676958)
		)
		(stroke
			(width 0)
			(type solid)
		)
		(fill yes)
		(layer "F.Cu")
		(net "M_A_CPU1_SB_DQ<14>")
	)
	(gr_poly
		(pts
			(xy 79.721456 -229.78745) (xy 79.767684 -229.690168) (xy 79.633064 -229.555548) (xy 79.535528 -229.601776)
			(xy 79.499714 -229.63759) (xy 79.685642 -229.823518)
		)
		(stroke
			(width 0)
			(type solid)
		)
		(fill yes)
		(layer "F.Cu")
		(net "M_A_CPU1_SB_DQ<15>")
	)
	(gr_poly
		(pts
			(xy 79.731616 -228.518212) (xy 79.777844 -228.420676) (xy 79.64297 -228.286056) (xy 79.545688 -228.332284)
			(xy 79.50962 -228.368098) (xy 79.695548 -228.554026)
		)
		(stroke
			(width 0)
			(type solid)
		)
		(fill yes)
		(layer "F.Cu")
		(net "M_A_CPU1_SB_DQ<18>")
	)
	(gr_poly
		(pts
			(xy 79.74076 -227.664772) (xy 79.786988 -227.56749) (xy 79.652368 -227.432616) (xy 79.554832 -227.478844)
			(xy 79.519018 -227.514912) (xy 79.704946 -227.70084)
		)
		(stroke
			(width 0)
			(type solid)
		)
		(fill yes)
		(layer "F.Cu")
		(net "M_A_CPU1_SB_DQ<19>")
	)
	(gr_poly
		(pts
			(xy 79.773018 -263.248648) (xy 79.72679 -263.151112) (xy 79.690722 -263.115298) (xy 79.504794 -263.301226)
			(xy 79.540862 -263.33704) (xy 79.638144 -263.383268)
		)
		(stroke
			(width 0)
			(type solid)
		)
		(fill yes)
		(layer "F.Cu")
		(net "M_A_CPU1_SA_CB<5>")
	)
	(gr_poly
		(pts
			(xy 79.780384 -221.847918) (xy 79.729584 -221.847918) (xy 79.627984 -221.883986) (xy 79.627984 -222.074486)
			(xy 79.729584 -222.110554) (xy 79.780384 -222.110554)
		)
		(stroke
			(width 0)
			(type solid)
		)
		(fill yes)
		(layer "F.Cu")
		(net "M_A_CPU1_SB_DQ<21>")
	)
	(gr_poly
		(pts
			(xy 79.780384 -221.251018) (xy 79.729584 -221.251018) (xy 79.627984 -221.287086) (xy 79.627984 -221.477586)
			(xy 79.729584 -221.513654) (xy 79.780384 -221.513654)
		)
		(stroke
			(width 0)
			(type solid)
		)
		(fill yes)
		(layer "F.Cu")
		(net "M_A_CPU1_SB_DQ<21>")
	)
	(gr_poly
		(pts
			(xy 79.780384 -220.654118) (xy 79.729584 -220.654118) (xy 79.627984 -220.690186) (xy 79.627984 -220.880686)
			(xy 79.729584 -220.916754) (xy 79.780384 -220.916754)
		)
		(stroke
			(width 0)
			(type solid)
		)
		(fill yes)
		(layer "F.Cu")
		(net "M_A_CPU1_SB_DQ<21>")
	)
	(gr_poly
		(pts
			(xy 79.780384 -220.057218) (xy 79.729584 -220.057218) (xy 79.627984 -220.093286) (xy 79.627984 -220.283786)
			(xy 79.729584 -220.319854) (xy 79.780384 -220.319854)
		)
		(stroke
			(width 0)
			(type solid)
		)
		(fill yes)
		(layer "F.Cu")
		(net "M_A_CPU1_SB_DQ<21>")
	)
	(gr_poly
		(pts
			(xy 79.780384 -219.460318) (xy 79.729584 -219.460318) (xy 79.627984 -219.496386) (xy 79.627984 -219.686886)
			(xy 79.729584 -219.722954) (xy 79.780384 -219.722954)
		)
		(stroke
			(width 0)
			(type solid)
		)
		(fill yes)
		(layer "F.Cu")
		(net "M_A_CPU1_SB_DQ<21>")
	)
	(gr_poly
		(pts
			(xy 79.780384 -218.863418) (xy 79.729584 -218.863418) (xy 79.627984 -218.899486) (xy 79.627984 -219.089986)
			(xy 79.729584 -219.126054) (xy 79.780384 -219.126054)
		)
		(stroke
			(width 0)
			(type solid)
		)
		(fill yes)
		(layer "F.Cu")
		(net "M_A_CPU1_SB_DQ<21>")
	)
	(gr_poly
		(pts
			(xy 79.780384 -218.266518) (xy 79.729584 -218.266518) (xy 79.627984 -218.302586) (xy 79.627984 -218.493086)
			(xy 79.729584 -218.529154) (xy 79.780384 -218.529154)
		)
		(stroke
			(width 0)
			(type solid)
		)
		(fill yes)
		(layer "F.Cu")
		(net "M_A_CPU1_SB_DQ<21>")
	)
	(gr_poly
		(pts
			(xy 79.780384 -217.669618) (xy 79.729584 -217.669618) (xy 79.627984 -217.705686) (xy 79.627984 -217.896186)
			(xy 79.729584 -217.932254) (xy 79.780384 -217.932254)
		)
		(stroke
			(width 0)
			(type solid)
		)
		(fill yes)
		(layer "F.Cu")
		(net "M_A_CPU1_SB_DQ<21>")
	)
	(gr_poly
		(pts
			(xy 79.780384 -217.072718) (xy 79.729584 -217.072718) (xy 79.627984 -217.108786) (xy 79.627984 -217.299286)
			(xy 79.729584 -217.335354) (xy 79.780384 -217.335354)
		)
		(stroke
			(width 0)
			(type solid)
		)
		(fill yes)
		(layer "F.Cu")
		(net "M_A_CPU1_SB_DQ<21>")
	)
	(gr_poly
		(pts
			(xy 79.780384 -216.475818) (xy 79.729584 -216.475818) (xy 79.627984 -216.511886) (xy 79.627984 -216.702386)
			(xy 79.729584 -216.738454) (xy 79.780384 -216.738454)
		)
		(stroke
			(width 0)
			(type solid)
		)
		(fill yes)
		(layer "F.Cu")
		(net "M_A_CPU1_SB_DQ<21>")
	)
	(gr_poly
		(pts
			(xy 79.780384 -215.878918) (xy 79.729584 -215.878918) (xy 79.627984 -215.914986) (xy 79.627984 -216.105486)
			(xy 79.729584 -216.141554) (xy 79.780384 -216.141554)
		)
		(stroke
			(width 0)
			(type solid)
		)
		(fill yes)
		(layer "F.Cu")
		(net "M_A_CPU1_SB_DQ<21>")
	)
	(gr_poly
		(pts
			(xy 79.780384 -215.282018) (xy 79.729584 -215.282018) (xy 79.627984 -215.318086) (xy 79.627984 -215.508586)
			(xy 79.729584 -215.544654) (xy 79.780384 -215.544654)
		)
		(stroke
			(width 0)
			(type solid)
		)
		(fill yes)
		(layer "F.Cu")
		(net "M_A_CPU1_SB_DQ<21>")
	)
	(gr_poly
		(pts
			(xy 79.7814 -270.116554) (xy 79.745586 -270.080486) (xy 79.64805 -270.034258) (xy 79.51343 -270.168878)
			(xy 79.559658 -270.266414) (xy 79.595726 -270.302228)
		)
		(stroke
			(width 0)
			(type solid)
		)
		(fill yes)
		(layer "F.Cu")
		(net "M_A_CPU1_SA_DQ<29>")
	)
	(gr_poly
		(pts
			(xy 79.782416 -264.102342) (xy 79.736188 -264.004806) (xy 79.70012 -263.968992) (xy 79.514446 -264.154666)
			(xy 79.55026 -264.190734) (xy 79.647796 -264.236962)
		)
		(stroke
			(width 0)
			(type solid)
		)
		(fill yes)
		(layer "F.Cu")
		(net "M_A_CPU1_SA_CB<4>")
	)
	(gr_poly
		(pts
			(xy 79.787242 -273.77898) (xy 79.741014 -273.681444) (xy 79.704946 -273.64563) (xy 79.519272 -273.831304)
			(xy 79.555086 -273.867372) (xy 79.652622 -273.9136)
		)
		(stroke
			(width 0)
			(type solid)
		)
		(fill yes)
		(layer "F.Cu")
		(net "M_A_CPU1_SA_DQ<25>")
	)
	(gr_poly
		(pts
			(xy 79.787242 -266.685014) (xy 79.741014 -266.587732) (xy 79.7052 -266.551664) (xy 79.519272 -266.737592)
			(xy 79.555086 -266.773406) (xy 79.652622 -266.819888)
		)
		(stroke
			(width 0)
			(type solid)
		)
		(fill yes)
		(layer "F.Cu")
		(net "M_A_CPU1_SA_CB<1>")
	)
	(gr_poly
		(pts
			(xy 79.791052 -270.970248) (xy 79.755238 -270.93418) (xy 79.657702 -270.887952) (xy 79.523082 -271.022826)
			(xy 79.56931 -271.120108) (xy 79.605124 -271.156176)
		)
		(stroke
			(width 0)
			(type solid)
		)
		(fill yes)
		(layer "F.Cu")
		(net "M_A_CPU1_SA_DQ<28>")
	)
	(gr_poly
		(pts
			(xy 79.796386 -274.632166) (xy 79.750158 -274.534884) (xy 79.714344 -274.498816) (xy 79.528416 -274.684744)
			(xy 79.56423 -274.720812) (xy 79.661766 -274.76704)
		)
		(stroke
			(width 0)
			(type solid)
		)
		(fill yes)
		(layer "F.Cu")
		(net "M_A_CPU1_SA_DQ<24>")
	)
	(gr_poly
		(pts
			(xy 79.79664 -267.538454) (xy 79.750412 -267.441172) (xy 79.714598 -267.405104) (xy 79.52867 -267.591032)
			(xy 79.564484 -267.6271) (xy 79.66202 -267.673328)
		)
		(stroke
			(width 0)
			(type solid)
		)
		(fill yes)
		(layer "F.Cu")
		(net "M_A_CPU1_SA_CB<0>")
	)
	(gr_poly
		(pts
			(xy 79.803498 -277.102062) (xy 79.731108 -277.022306) (xy 79.68615 -276.99843) (xy 79.562198 -277.230078)
			(xy 79.607156 -277.253954) (xy 79.713582 -277.27021)
		)
		(stroke
			(width 0)
			(type solid)
		)
		(fill yes)
		(layer "F.Cu")
		(net "M_A_CPU1_SA_DQ<20>")
	)
	(gr_poly
		(pts
			(xy 79.80426 -234.327192) (xy 79.840328 -234.291378) (xy 79.6544 -234.10545) (xy 79.618586 -234.141264)
			(xy 79.572358 -234.2388) (xy 79.706978 -234.37342)
		)
		(stroke
			(width 0)
			(type solid)
		)
		(fill yes)
		(layer "F.Cu")
		(net "M_A_CPU1_SB_DQ<10>")
	)
	(gr_poly
		(pts
			(xy 79.813658 -233.474006) (xy 79.849472 -233.437938) (xy 79.663544 -233.25201) (xy 79.62773 -233.288078)
			(xy 79.581502 -233.38536) (xy 79.716122 -233.520234)
		)
		(stroke
			(width 0)
			(type solid)
		)
		(fill yes)
		(layer "F.Cu")
		(net "M_A_CPU1_SB_DQ<11>")
	)
	(gr_poly
		(pts
			(xy 79.816198 -276.431756) (xy 79.743554 -276.352) (xy 79.69885 -276.328124) (xy 79.574898 -276.559772)
			(xy 79.619602 -276.583902) (xy 79.726282 -276.599904)
		)
		(stroke
			(width 0)
			(type solid)
		)
		(fill yes)
		(layer "F.Cu")
		(net "M_A_CPU1_SA_DQ<22>")
	)
	(gr_poly
		(pts
			(xy 79.8195 -223.591374) (xy 79.855314 -223.55556) (xy 79.669386 -223.369632) (xy 79.633572 -223.4057)
			(xy 79.587344 -223.502982) (xy 79.721964 -223.637856)
		)
		(stroke
			(width 0)
			(type solid)
		)
		(fill yes)
		(layer "F.Cu")
		(net "M_A_CPU1_SB_DQ<20>")
	)
	(gr_poly
		(pts
			(xy 79.82712 -276.735286) (xy 79.782162 -276.711156) (xy 79.675482 -276.695154) (xy 79.58582 -276.863048)
			(xy 79.65821 -276.943058) (xy 79.703168 -276.966934)
		)
		(stroke
			(width 0)
			(type solid)
		)
		(fill yes)
		(layer "F.Cu")
		(net "M_A_CPU1_SA_DQ<20>")
	)
	(gr_poly
		(pts
			(xy 79.851504 -230.923846) (xy 79.887318 -230.887778) (xy 79.701644 -230.702104) (xy 79.665576 -230.737918)
			(xy 79.619348 -230.835454) (xy 79.753968 -230.970074)
		)
		(stroke
			(width 0)
			(type solid)
		)
		(fill yes)
		(layer "F.Cu")
		(net "M_A_CPU1_SB_DQ<14>")
	)
	(gr_poly
		(pts
			(xy 79.85379 -249.371866) (xy 79.85379 -249.321066) (xy 79.5909 -249.321066) (xy 79.5909 -249.371866)
			(xy 79.626968 -249.473466) (xy 79.817468 -249.473466)
		)
		(stroke
			(width 0)
			(type solid)
		)
		(fill yes)
		(layer "F.Cu")
		(net "M_A_CPU1_SB_CA<0>")
	)
	(gr_poly
		(pts
			(xy 79.85379 -249.066812) (xy 79.85379 -249.016012) (xy 79.5909 -249.016012) (xy 79.5909 -249.066812)
			(xy 79.626968 -249.168412) (xy 79.817468 -249.168412)
		)
		(stroke
			(width 0)
			(type solid)
		)
		(fill yes)
		(layer "F.Cu")
		(net "M_A_CPU1_SB_CA<1>")
	)
	(gr_poly
		(pts
			(xy 79.85379 -248.762012) (xy 79.85379 -248.711212) (xy 79.5909 -248.711212) (xy 79.5909 -248.762012)
			(xy 79.626968 -248.863612) (xy 79.817468 -248.863612)
		)
		(stroke
			(width 0)
			(type solid)
		)
		(fill yes)
		(layer "F.Cu")
		(net "M_A_CPU1_SB_CA<2>")
	)
	(gr_poly
		(pts
			(xy 79.85379 -248.457212) (xy 79.85379 -248.406412) (xy 79.5909 -248.406412) (xy 79.5909 -248.457212)
			(xy 79.626968 -248.558812) (xy 79.817468 -248.558812)
		)
		(stroke
			(width 0)
			(type solid)
		)
		(fill yes)
		(layer "F.Cu")
		(net "M_A_CPU1_SB_CA<3>")
	)
	(gr_poly
		(pts
			(xy 79.85379 -248.152412) (xy 79.85379 -248.101612) (xy 79.5909 -248.101612) (xy 79.5909 -248.152412)
			(xy 79.626968 -248.254012) (xy 79.817468 -248.254012)
		)
		(stroke
			(width 0)
			(type solid)
		)
		(fill yes)
		(layer "F.Cu")
		(net "M_A_CPU1_SB_CA<4>")
	)
	(gr_poly
		(pts
			(xy 79.85379 -247.847612) (xy 79.85379 -247.796812) (xy 79.5909 -247.796812) (xy 79.5909 -247.847612)
			(xy 79.626968 -247.949212) (xy 79.817468 -247.949212)
		)
		(stroke
			(width 0)
			(type solid)
		)
		(fill yes)
		(layer "F.Cu")
		(net "M_A_CPU1_SB_CA<5>")
	)
	(gr_poly
		(pts
			(xy 79.85379 -247.542812) (xy 79.85379 -247.492012) (xy 79.5909 -247.492012) (xy 79.5909 -247.542812)
			(xy 79.626968 -247.644412) (xy 79.817468 -247.644412)
		)
		(stroke
			(width 0)
			(type solid)
		)
		(fill yes)
		(layer "F.Cu")
		(net "M_A_CPU1_SB_CA<6>")
	)
	(gr_poly
		(pts
			(xy 79.85379 -247.238012) (xy 79.85379 -247.187212) (xy 79.5909 -247.187212) (xy 79.5909 -247.238012)
			(xy 79.626968 -247.339612) (xy 79.817468 -247.339612)
		)
		(stroke
			(width 0)
			(type solid)
		)
		(fill yes)
		(layer "F.Cu")
		(net "M_A_CPU1_SB_PAR")
	)
	(gr_poly
		(pts
			(xy 79.85379 -246.933212) (xy 79.85379 -246.882412) (xy 79.5909 -246.882412) (xy 79.5909 -246.933212)
			(xy 79.626968 -247.034812) (xy 79.817468 -247.034812)
		)
		(stroke
			(width 0)
			(type solid)
		)
		(fill yes)
		(layer "F.Cu")
		(net "M_A_CPU1_SB_CS_N<2>")
	)
	(gr_poly
		(pts
			(xy 79.85379 -246.628412) (xy 79.85379 -246.577612) (xy 79.5909 -246.577612) (xy 79.5909 -246.628412)
			(xy 79.626968 -246.730012) (xy 79.817468 -246.730012)
		)
		(stroke
			(width 0)
			(type solid)
		)
		(fill yes)
		(layer "F.Cu")
		(net "M_A_CPU1_SB_CS_N<0>")
	)
	(gr_poly
		(pts
			(xy 79.85379 -246.323612) (xy 79.85379 -246.272812) (xy 79.5909 -246.272812) (xy 79.5909 -246.323612)
			(xy 79.626968 -246.425212) (xy 79.817468 -246.425212)
		)
		(stroke
			(width 0)
			(type solid)
		)
		(fill yes)
		(layer "F.Cu")
		(net "M_A_CPU1_SB_CS_N<3>")
	)
	(gr_poly
		(pts
			(xy 79.85379 -246.018812) (xy 79.85379 -245.968012) (xy 79.5909 -245.968012) (xy 79.5909 -246.018812)
			(xy 79.626968 -246.120412) (xy 79.817468 -246.120412)
		)
		(stroke
			(width 0)
			(type solid)
		)
		(fill yes)
		(layer "F.Cu")
		(net "M_A_CPU1_SB_CS_N<1>")
	)
	(gr_poly
		(pts
			(xy 79.85887 -269.82293) (xy 79.812642 -269.725648) (xy 79.776828 -269.68958) (xy 79.5909 -269.875508)
			(xy 79.626714 -269.911322) (xy 79.72425 -269.957804)
		)
		(stroke
			(width 0)
			(type solid)
		)
		(fill yes)
		(layer "F.Cu")
		(net "M_A_CPU1_SA_DQ<31>")
	)
	(gr_poly
		(pts
			(xy 79.860648 -230.070406) (xy 79.896716 -230.034592) (xy 79.710788 -229.848664) (xy 79.67472 -229.884478)
			(xy 79.628492 -229.982014) (xy 79.763366 -230.116634)
		)
		(stroke
			(width 0)
			(type solid)
		)
		(fill yes)
		(layer "F.Cu")
		(net "M_A_CPU1_SB_DQ<15>")
	)
	(gr_poly
		(pts
			(xy 79.861156 -275.670264) (xy 79.825342 -275.634196) (xy 79.727806 -275.587968) (xy 79.593186 -275.722842)
			(xy 79.639414 -275.820124) (xy 79.675228 -275.856192)
		)
		(stroke
			(width 0)
			(type solid)
		)
		(fill yes)
		(layer "F.Cu")
		(net "M_A_CPU1_SA_DQ<21>")
	)
	(gr_poly
		(pts
			(xy 79.868776 -270.676878) (xy 79.822294 -270.579342) (xy 79.78648 -270.543528) (xy 79.600552 -270.729456)
			(xy 79.63662 -270.76527) (xy 79.733902 -270.811498)
		)
		(stroke
			(width 0)
			(type solid)
		)
		(fill yes)
		(layer "F.Cu")
		(net "M_A_CPU1_SA_DQ<30>")
	)
	(gr_poly
		(pts
			(xy 79.870808 -228.801168) (xy 79.906622 -228.7651) (xy 79.720694 -228.579172) (xy 79.68488 -228.61524)
			(xy 79.638652 -228.712522) (xy 79.773272 -228.847396)
		)
		(stroke
			(width 0)
			(type solid)
		)
		(fill yes)
		(layer "F.Cu")
		(net "M_A_CPU1_SB_DQ<18>")
	)
	(gr_poly
		(pts
			(xy 79.87157 -234.68203) (xy 79.917798 -234.584748) (xy 79.783178 -234.449874) (xy 79.685642 -234.496102)
			(xy 79.649828 -234.53217) (xy 79.835756 -234.718098)
		)
		(stroke
			(width 0)
			(type solid)
		)
		(fill yes)
		(layer "F.Cu")
		(net "M_A_CPU1_SB_DQ<8>")
	)
	(gr_poly
		(pts
			(xy 79.879952 -227.947728) (xy 79.915766 -227.91166) (xy 79.730092 -227.725986) (xy 79.694024 -227.7618)
			(xy 79.647796 -227.859336) (xy 79.782416 -227.993956)
		)
		(stroke
			(width 0)
			(type solid)
		)
		(fill yes)
		(layer "F.Cu")
		(net "M_A_CPU1_SB_DQ<19>")
	)
	(gr_poly
		(pts
			(xy 79.880714 -233.828844) (xy 79.927196 -233.731308) (xy 79.792322 -233.596688) (xy 79.69504 -233.642916)
			(xy 79.658972 -233.67873) (xy 79.8449 -233.864658)
		)
		(stroke
			(width 0)
			(type solid)
		)
		(fill yes)
		(layer "F.Cu")
		(net "M_A_CPU1_SB_DQ<9>")
	)
	(gr_poly
		(pts
			(xy 79.886556 -259.008626) (xy 79.850488 -258.907026) (xy 79.659988 -258.907026) (xy 79.623666 -259.008626)
			(xy 79.623666 -259.059426) (xy 79.886556 -259.059426)
		)
		(stroke
			(width 0)
			(type solid)
		)
		(fill yes)
		(layer "F.Cu")
		(net "M_A_CPU1_SA_CS_N<3>")
	)
	(gr_poly
		(pts
			(xy 79.886556 -258.703826) (xy 79.850488 -258.602226) (xy 79.659988 -258.602226) (xy 79.623666 -258.703826)
			(xy 79.623666 -258.754626) (xy 79.886556 -258.754626)
		)
		(stroke
			(width 0)
			(type solid)
		)
		(fill yes)
		(layer "F.Cu")
		(net "M_A_CPU1_SA_CS_N<1>")
	)
	(gr_poly
		(pts
			(xy 79.886556 -258.399026) (xy 79.850488 -258.297426) (xy 79.659988 -258.297426) (xy 79.623666 -258.399026)
			(xy 79.623666 -258.449826) (xy 79.886556 -258.449826)
		)
		(stroke
			(width 0)
			(type solid)
		)
		(fill yes)
		(layer "F.Cu")
		(net "M_A_CPU1_SA_CA<0>")
	)
	(gr_poly
		(pts
			(xy 79.886556 -258.094226) (xy 79.850488 -257.992626) (xy 79.659988 -257.992626) (xy 79.623666 -258.094226)
			(xy 79.623666 -258.145026) (xy 79.886556 -258.145026)
		)
		(stroke
			(width 0)
			(type solid)
		)
		(fill yes)
		(layer "F.Cu")
		(net "M_A_CPU1_SA_CA<1>")
	)
	(gr_poly
		(pts
			(xy 79.886556 -257.789426) (xy 79.850488 -257.687826) (xy 79.659988 -257.687826) (xy 79.623666 -257.789426)
			(xy 79.623666 -257.840226) (xy 79.886556 -257.840226)
		)
		(stroke
			(width 0)
			(type solid)
		)
		(fill yes)
		(layer "F.Cu")
		(net "M_A_CPU1_SA_CA<2>")
	)
	(gr_poly
		(pts
			(xy 79.886556 -257.484626) (xy 79.850488 -257.383026) (xy 79.659988 -257.383026) (xy 79.623666 -257.484626)
			(xy 79.623666 -257.535426) (xy 79.886556 -257.535426)
		)
		(stroke
			(width 0)
			(type solid)
		)
		(fill yes)
		(layer "F.Cu")
		(net "M_A_CPU1_SA_CA<3>")
	)
	(gr_poly
		(pts
			(xy 79.886556 -257.179826) (xy 79.850488 -257.078226) (xy 79.659988 -257.078226) (xy 79.623666 -257.179826)
			(xy 79.623666 -257.230626) (xy 79.886556 -257.230626)
		)
		(stroke
			(width 0)
			(type solid)
		)
		(fill yes)
		(layer "F.Cu")
		(net "M_A_CPU1_SA_CA<4>")
	)
	(gr_poly
		(pts
			(xy 79.886556 -256.875026) (xy 79.850488 -256.773426) (xy 79.659988 -256.773426) (xy 79.623666 -256.875026)
			(xy 79.623666 -256.925826) (xy 79.886556 -256.925826)
		)
		(stroke
			(width 0)
			(type solid)
		)
		(fill yes)
		(layer "F.Cu")
		(net "M_A_CPU1_SA_CA<5>")
	)
	(gr_poly
		(pts
			(xy 79.886556 -256.570226) (xy 79.850488 -256.468626) (xy 79.659988 -256.468626) (xy 79.623666 -256.570226)
			(xy 79.623666 -256.621026) (xy 79.886556 -256.621026)
		)
		(stroke
			(width 0)
			(type solid)
		)
		(fill yes)
		(layer "F.Cu")
		(net "M_A_CPU1_SA_CA<6>")
	)
	(gr_poly
		(pts
			(xy 79.886556 -256.265426) (xy 79.850488 -256.163826) (xy 79.659988 -256.163826) (xy 79.623666 -256.265426)
			(xy 79.623666 -256.316226) (xy 79.886556 -256.316226)
		)
		(stroke
			(width 0)
			(type solid)
		)
		(fill yes)
		(layer "F.Cu")
		(net "M_A_CPU1_SA_PAR")
	)
	(gr_poly
		(pts
			(xy 79.895954 -223.093026) (xy 79.942182 -222.99549) (xy 79.807308 -222.86087) (xy 79.710026 -222.907098)
			(xy 79.673958 -222.942912) (xy 79.859886 -223.12884)
		)
		(stroke
			(width 0)
			(type solid)
		)
		(fill yes)
		(layer "F.Cu")
		(net "M_A_CPU1_SB_DQ<22>")
	)
	(gr_poly
		(pts
			(xy 79.901796 -262.904224) (xy 79.865982 -262.86841) (xy 79.768446 -262.822182) (xy 79.633826 -262.956802)
			(xy 79.680054 -263.054084) (xy 79.715868 -263.090152)
		)
		(stroke
			(width 0)
			(type solid)
		)
		(fill yes)
		(layer "F.Cu")
		(net "M_A_CPU1_SA_CB<5>")
	)
	(gr_poly
		(pts
			(xy 79.911194 -263.757918) (xy 79.87538 -263.72185) (xy 79.777844 -263.675622) (xy 79.643224 -263.810496)
			(xy 79.689452 -263.907778) (xy 79.725266 -263.943846)
		)
		(stroke
			(width 0)
			(type solid)
		)
		(fill yes)
		(layer "F.Cu")
		(net "M_A_CPU1_SA_CB<4>")
	)
	(gr_poly
		(pts
			(xy 79.91602 -273.434556) (xy 79.880206 -273.398488) (xy 79.78267 -273.35226) (xy 79.64805 -273.487134)
			(xy 79.694278 -273.584416) (xy 79.730092 -273.620484)
		)
		(stroke
			(width 0)
			(type solid)
		)
		(fill yes)
		(layer "F.Cu")
		(net "M_A_CPU1_SA_DQ<25>")
	)
	(gr_poly
		(pts
			(xy 79.916274 -266.34059) (xy 79.880206 -266.304776) (xy 79.782924 -266.258548) (xy 79.64805 -266.393168)
			(xy 79.694278 -266.490704) (xy 79.730346 -266.526518)
		)
		(stroke
			(width 0)
			(type solid)
		)
		(fill yes)
		(layer "F.Cu")
		(net "M_A_CPU1_SA_CB<1>")
	)
	(gr_poly
		(pts
			(xy 79.91856 -231.278684) (xy 79.964788 -231.181402) (xy 79.830168 -231.046528) (xy 79.732632 -231.09301)
			(xy 79.696818 -231.128824) (xy 79.882746 -231.314752)
		)
		(stroke
			(width 0)
			(type solid)
		)
		(fill yes)
		(layer "F.Cu")
		(net "M_A_CPU1_SB_DQ<12>")
	)
	(gr_poly
		(pts
			(xy 79.925418 -274.287742) (xy 79.88935 -274.251928) (xy 79.792068 -274.2057) (xy 79.657194 -274.34032)
			(xy 79.703422 -274.437856) (xy 79.73949 -274.47367)
		)
		(stroke
			(width 0)
			(type solid)
		)
		(fill yes)
		(layer "F.Cu")
		(net "M_A_CPU1_SA_DQ<24>")
	)
	(gr_poly
		(pts
			(xy 79.925418 -267.194284) (xy 79.889604 -267.158216) (xy 79.792068 -267.111988) (xy 79.657448 -267.246608)
			(xy 79.703676 -267.344144) (xy 79.739744 -267.379958)
		)
		(stroke
			(width 0)
			(type solid)
		)
		(fill yes)
		(layer "F.Cu")
		(net "M_A_CPU1_SA_CB<0>")
	)
	(gr_poly
		(pts
			(xy 79.927958 -230.425244) (xy 79.974186 -230.327962) (xy 79.839566 -230.193088) (xy 79.74203 -230.239316)
			(xy 79.706216 -230.275384) (xy 79.892144 -230.461312)
		)
		(stroke
			(width 0)
			(type solid)
		)
		(fill yes)
		(layer "F.Cu")
		(net "M_A_CPU1_SB_DQ<13>")
	)
	(gr_poly
		(pts
			(xy 79.932784 -222.372936) (xy 79.932784 -222.182436) (xy 79.831184 -222.146114) (xy 79.780384 -222.146114)
			(xy 79.780384 -222.409258) (xy 79.831184 -222.409258)
		)
		(stroke
			(width 0)
			(type solid)
		)
		(fill yes)
		(layer "F.Cu")
		(net "M_A_CPU1_SB_DQ<21>")
	)
	(gr_poly
		(pts
			(xy 79.932784 -221.776036) (xy 79.932784 -221.585536) (xy 79.831184 -221.549214) (xy 79.780384 -221.549214)
			(xy 79.780384 -221.812358) (xy 79.831184 -221.812358)
		)
		(stroke
			(width 0)
			(type solid)
		)
		(fill yes)
		(layer "F.Cu")
		(net "M_A_CPU1_SB_DQ<21>")
	)
	(gr_poly
		(pts
			(xy 79.932784 -221.179136) (xy 79.932784 -220.988636) (xy 79.831184 -220.952314) (xy 79.780384 -220.952314)
			(xy 79.780384 -221.215458) (xy 79.831184 -221.215458)
		)
		(stroke
			(width 0)
			(type solid)
		)
		(fill yes)
		(layer "F.Cu")
		(net "M_A_CPU1_SB_DQ<21>")
	)
	(gr_poly
		(pts
			(xy 79.932784 -220.582236) (xy 79.932784 -220.391736) (xy 79.831184 -220.355414) (xy 79.780384 -220.355414)
			(xy 79.780384 -220.618558) (xy 79.831184 -220.618558)
		)
		(stroke
			(width 0)
			(type solid)
		)
		(fill yes)
		(layer "F.Cu")
		(net "M_A_CPU1_SB_DQ<21>")
	)
	(gr_poly
		(pts
			(xy 79.932784 -219.985336) (xy 79.932784 -219.794836) (xy 79.831184 -219.758514) (xy 79.780384 -219.758514)
			(xy 79.780384 -220.021658) (xy 79.831184 -220.021658)
		)
		(stroke
			(width 0)
			(type solid)
		)
		(fill yes)
		(layer "F.Cu")
		(net "M_A_CPU1_SB_DQ<21>")
	)
	(gr_poly
		(pts
			(xy 79.932784 -219.388436) (xy 79.932784 -219.197936) (xy 79.831184 -219.161614) (xy 79.780384 -219.161614)
			(xy 79.780384 -219.424758) (xy 79.831184 -219.424758)
		)
		(stroke
			(width 0)
			(type solid)
		)
		(fill yes)
		(layer "F.Cu")
		(net "M_A_CPU1_SB_DQ<21>")
	)
	(gr_poly
		(pts
			(xy 79.932784 -218.791536) (xy 79.932784 -218.601036) (xy 79.831184 -218.564714) (xy 79.780384 -218.564714)
			(xy 79.780384 -218.827858) (xy 79.831184 -218.827858)
		)
		(stroke
			(width 0)
			(type solid)
		)
		(fill yes)
		(layer "F.Cu")
		(net "M_A_CPU1_SB_DQ<21>")
	)
	(gr_poly
		(pts
			(xy 79.932784 -218.194636) (xy 79.932784 -218.004136) (xy 79.831184 -217.967814) (xy 79.780384 -217.967814)
			(xy 79.780384 -218.230958) (xy 79.831184 -218.230958)
		)
		(stroke
			(width 0)
			(type solid)
		)
		(fill yes)
		(layer "F.Cu")
		(net "M_A_CPU1_SB_DQ<21>")
	)
	(gr_poly
		(pts
			(xy 79.932784 -217.597736) (xy 79.932784 -217.407236) (xy 79.831184 -217.370914) (xy 79.780384 -217.370914)
			(xy 79.780384 -217.634058) (xy 79.831184 -217.634058)
		)
		(stroke
			(width 0)
			(type solid)
		)
		(fill yes)
		(layer "F.Cu")
		(net "M_A_CPU1_SB_DQ<21>")
	)
	(gr_poly
		(pts
			(xy 79.932784 -217.000836) (xy 79.932784 -216.810336) (xy 79.831184 -216.774014) (xy 79.780384 -216.774014)
			(xy 79.780384 -217.037158) (xy 79.831184 -217.037158)
		)
		(stroke
			(width 0)
			(type solid)
		)
		(fill yes)
		(layer "F.Cu")
		(net "M_A_CPU1_SB_DQ<21>")
	)
	(gr_poly
		(pts
			(xy 79.932784 -216.403936) (xy 79.932784 -216.213436) (xy 79.831184 -216.177114) (xy 79.780384 -216.177114)
			(xy 79.780384 -216.440258) (xy 79.831184 -216.440258)
		)
		(stroke
			(width 0)
			(type solid)
		)
		(fill yes)
		(layer "F.Cu")
		(net "M_A_CPU1_SB_DQ<21>")
	)
	(gr_poly
		(pts
			(xy 79.932784 -215.807036) (xy 79.932784 -215.616536) (xy 79.831184 -215.580214) (xy 79.780384 -215.580214)
			(xy 79.780384 -215.843358) (xy 79.831184 -215.843358)
		)
		(stroke
			(width 0)
			(type solid)
		)
		(fill yes)
		(layer "F.Cu")
		(net "M_A_CPU1_SB_DQ<21>")
	)
	(gr_poly
		(pts
			(xy 79.932784 -215.210136) (xy 79.932784 -215.019636) (xy 79.831184 -214.983314) (xy 79.780384 -214.983314)
			(xy 79.780384 -215.246458) (xy 79.831184 -215.246458)
		)
		(stroke
			(width 0)
			(type solid)
		)
		(fill yes)
		(layer "F.Cu")
		(net "M_A_CPU1_SB_DQ<21>")
	)
	(gr_poly
		(pts
			(xy 79.937864 -229.156006) (xy 79.984346 -229.05847) (xy 79.849472 -228.92385) (xy 79.75219 -228.970078)
			(xy 79.716122 -229.005892) (xy 79.90205 -229.19182)
		)
		(stroke
			(width 0)
			(type solid)
		)
		(fill yes)
		(layer "F.Cu")
		(net "M_A_CPU1_SB_DQ<16>")
	)
	(gr_poly
		(pts
			(xy 79.93888 -275.376894) (xy 79.892652 -275.279358) (xy 79.856584 -275.243544) (xy 79.670656 -275.429472)
			(xy 79.706724 -275.465286) (xy 79.804006 -275.511514)
		)
		(stroke
			(width 0)
			(type solid)
		)
		(fill yes)
		(layer "F.Cu")
		(net "M_A_CPU1_SA_DQ<23>")
	)
	(gr_poly
		(pts
			(xy 79.947262 -228.302566) (xy 79.99349 -228.20503) (xy 79.858616 -228.07041) (xy 79.761334 -228.116638)
			(xy 79.725266 -228.152452) (xy 79.911194 -228.33838)
		)
		(stroke
			(width 0)
			(type solid)
		)
		(fill yes)
		(layer "F.Cu")
		(net "M_A_CPU1_SB_DQ<17>")
	)
	(gr_poly
		(pts
			(xy 79.979266 -262.610854) (xy 79.933038 -262.513318) (xy 79.89697 -262.477504) (xy 79.711042 -262.663432)
			(xy 79.74711 -262.699246) (xy 79.844646 -262.745474)
		)
		(stroke
			(width 0)
			(type solid)
		)
		(fill yes)
		(layer "F.Cu")
		(net "M_A_CPU1_SA_CB<7>")
	)
	(gr_poly
		(pts
			(xy 79.987902 -269.478506) (xy 79.951834 -269.442692) (xy 79.854552 -269.396464) (xy 79.719678 -269.531084)
			(xy 79.765906 -269.62862) (xy 79.801974 -269.664434)
		)
		(stroke
			(width 0)
			(type solid)
		)
		(fill yes)
		(layer "F.Cu")
		(net "M_A_CPU1_SA_DQ<31>")
	)
	(gr_poly
		(pts
			(xy 79.988664 -263.464294) (xy 79.942436 -263.367012) (xy 79.906622 -263.330944) (xy 79.720694 -263.516872)
			(xy 79.756508 -263.55294) (xy 79.854044 -263.599168)
		)
		(stroke
			(width 0)
			(type solid)
		)
		(fill yes)
		(layer "F.Cu")
		(net "M_A_CPU1_SA_CB<6>")
	)
	(gr_poly
		(pts
			(xy 79.99349 -273.140932) (xy 79.947262 -273.043396) (xy 79.911194 -273.007582) (xy 79.725266 -273.19351)
			(xy 79.761334 -273.229324) (xy 79.858616 -273.275552)
		)
		(stroke
			(width 0)
			(type solid)
		)
		(fill yes)
		(layer "F.Cu")
		(net "M_A_CPU1_SA_DQ<27>")
	)
	(gr_poly
		(pts
			(xy 79.993744 -266.047474) (xy 79.947516 -265.949938) (xy 79.911448 -265.914124) (xy 79.725774 -266.099798)
			(xy 79.761588 -266.135866) (xy 79.859124 -266.182094)
		)
		(stroke
			(width 0)
			(type solid)
		)
		(fill yes)
		(layer "F.Cu")
		(net "M_A_CPU1_SA_CB<3>")
	)
	(gr_poly
		(pts
			(xy 79.997554 -270.332454) (xy 79.96174 -270.29664) (xy 79.864204 -270.250412) (xy 79.729584 -270.385032)
			(xy 79.775812 -270.482568) (xy 79.811626 -270.518382)
		)
		(stroke
			(width 0)
			(type solid)
		)
		(fill yes)
		(layer "F.Cu")
		(net "M_A_CPU1_SA_DQ<30>")
	)
	(gr_poly
		(pts
			(xy 80.002888 -273.994626) (xy 79.95666 -273.89709) (xy 79.920592 -273.861276) (xy 79.734918 -274.04695)
			(xy 79.770732 -274.083018) (xy 79.868268 -274.129246)
		)
		(stroke
			(width 0)
			(type solid)
		)
		(fill yes)
		(layer "F.Cu")
		(net "M_A_CPU1_SA_DQ<26>")
	)
	(gr_poly
		(pts
			(xy 80.003142 -266.900914) (xy 79.956914 -266.803378) (xy 79.920846 -266.767564) (xy 79.734918 -266.953492)
			(xy 79.770986 -266.989306) (xy 79.868268 -267.035534)
		)
		(stroke
			(width 0)
			(type solid)
		)
		(fill yes)
		(layer "F.Cu")
		(net "M_A_CPU1_SA_CB<2>")
	)
	(gr_poly
		(pts
			(xy 80.010762 -234.964986) (xy 80.04683 -234.929172) (xy 79.860902 -234.743244) (xy 79.824834 -234.779058)
			(xy 79.778606 -234.876594) (xy 79.91348 -235.011214)
		)
		(stroke
			(width 0)
			(type solid)
		)
		(fill yes)
		(layer "F.Cu")
		(net "M_A_CPU1_SB_DQ<8>")
	)
	(gr_poly
		(pts
			(xy 80.017112 -288.65576) (xy 79.966312 -288.65576) (xy 79.864712 -288.692082) (xy 79.864712 -288.882582)
			(xy 79.966312 -288.91865) (xy 80.017112 -288.91865)
		)
		(stroke
			(width 0)
			(type solid)
		)
		(fill yes)
		(layer "F.Cu")
		(net "M_A_CPU1_SA_DQ<19>")
	)
	(gr_poly
		(pts
			(xy 80.017112 -288.05886) (xy 79.966312 -288.05886) (xy 79.864712 -288.095182) (xy 79.864712 -288.285682)
			(xy 79.966312 -288.32175) (xy 80.017112 -288.32175)
		)
		(stroke
			(width 0)
			(type solid)
		)
		(fill yes)
		(layer "F.Cu")
		(net "M_A_CPU1_SA_DQ<19>")
	)
	(gr_poly
		(pts
			(xy 80.017112 -287.46196) (xy 79.966312 -287.46196) (xy 79.864712 -287.498282) (xy 79.864712 -287.688782)
			(xy 79.966312 -287.72485) (xy 80.017112 -287.72485)
		)
		(stroke
			(width 0)
			(type solid)
		)
		(fill yes)
		(layer "F.Cu")
		(net "M_A_CPU1_SA_DQ<19>")
	)
	(gr_poly
		(pts
			(xy 80.017112 -286.86506) (xy 79.966312 -286.86506) (xy 79.864712 -286.901382) (xy 79.864712 -287.091882)
			(xy 79.966312 -287.12795) (xy 80.017112 -287.12795)
		)
		(stroke
			(width 0)
			(type solid)
		)
		(fill yes)
		(layer "F.Cu")
		(net "M_A_CPU1_SA_DQ<19>")
	)
	(gr_poly
		(pts
			(xy 80.017112 -286.26816) (xy 79.966312 -286.26816) (xy 79.864712 -286.304482) (xy 79.864712 -286.494982)
			(xy 79.966312 -286.53105) (xy 80.017112 -286.53105)
		)
		(stroke
			(width 0)
			(type solid)
		)
		(fill yes)
		(layer "F.Cu")
		(net "M_A_CPU1_SA_DQ<19>")
	)
	(gr_poly
		(pts
			(xy 80.017112 -285.67126) (xy 79.966312 -285.67126) (xy 79.864712 -285.707582) (xy 79.864712 -285.898082)
			(xy 79.966312 -285.93415) (xy 80.017112 -285.93415)
		)
		(stroke
			(width 0)
			(type solid)
		)
		(fill yes)
		(layer "F.Cu")
		(net "M_A_CPU1_SA_DQ<19>")
	)
	(gr_poly
		(pts
			(xy 80.017112 -285.07436) (xy 79.966312 -285.07436) (xy 79.864712 -285.110682) (xy 79.864712 -285.301182)
			(xy 79.966312 -285.33725) (xy 80.017112 -285.33725)
		)
		(stroke
			(width 0)
			(type solid)
		)
		(fill yes)
		(layer "F.Cu")
		(net "M_A_CPU1_SA_DQ<19>")
	)
	(gr_poly
		(pts
			(xy 80.017112 -284.47746) (xy 79.966312 -284.47746) (xy 79.864712 -284.513782) (xy 79.864712 -284.704282)
			(xy 79.966312 -284.74035) (xy 80.017112 -284.74035)
		)
		(stroke
			(width 0)
			(type solid)
		)
		(fill yes)
		(layer "F.Cu")
		(net "M_A_CPU1_SA_DQ<19>")
	)
	(gr_poly
		(pts
			(xy 80.017112 -283.88056) (xy 79.966312 -283.88056) (xy 79.864712 -283.916882) (xy 79.864712 -284.107382)
			(xy 79.966312 -284.14345) (xy 80.017112 -284.14345)
		)
		(stroke
			(width 0)
			(type solid)
		)
		(fill yes)
		(layer "F.Cu")
		(net "M_A_CPU1_SA_DQ<19>")
	)
	(gr_poly
		(pts
			(xy 80.017112 -283.28366) (xy 79.966312 -283.28366) (xy 79.864712 -283.319982) (xy 79.864712 -283.510482)
			(xy 79.966312 -283.54655) (xy 80.017112 -283.54655)
		)
		(stroke
			(width 0)
			(type solid)
		)
		(fill yes)
		(layer "F.Cu")
		(net "M_A_CPU1_SA_DQ<19>")
	)
	(gr_poly
		(pts
			(xy 80.017112 -282.68676) (xy 79.966312 -282.68676) (xy 79.864712 -282.723082) (xy 79.864712 -282.913582)
			(xy 79.966312 -282.94965) (xy 80.017112 -282.94965)
		)
		(stroke
			(width 0)
			(type solid)
		)
		(fill yes)
		(layer "F.Cu")
		(net "M_A_CPU1_SA_DQ<19>")
	)
	(gr_poly
		(pts
			(xy 80.017112 -282.08986) (xy 79.966312 -282.08986) (xy 79.864712 -282.126182) (xy 79.864712 -282.316682)
			(xy 79.966312 -282.35275) (xy 80.017112 -282.35275)
		)
		(stroke
			(width 0)
			(type solid)
		)
		(fill yes)
		(layer "F.Cu")
		(net "M_A_CPU1_SA_DQ<19>")
	)
	(gr_poly
		(pts
			(xy 80.019906 -234.111546) (xy 80.055974 -234.075732) (xy 79.870046 -233.889804) (xy 79.834232 -233.925618)
			(xy 79.788004 -234.023154) (xy 79.922624 -234.157774)
		)
		(stroke
			(width 0)
			(type solid)
		)
		(fill yes)
		(layer "F.Cu")
		(net "M_A_CPU1_SB_DQ<9>")
	)
	(gr_poly
		(pts
			(xy 80.035146 -223.375728) (xy 80.07096 -223.339914) (xy 79.885032 -223.153986) (xy 79.849218 -223.190054)
			(xy 79.80299 -223.287336) (xy 79.93761 -223.42221)
		)
		(stroke
			(width 0)
			(type solid)
		)
		(fill yes)
		(layer "F.Cu")
		(net "M_A_CPU1_SB_DQ<22>")
	)
	(gr_poly
		(pts
			(xy 80.057752 -231.56164) (xy 80.09382 -231.525826) (xy 79.907892 -231.339898) (xy 79.871824 -231.375712)
			(xy 79.825596 -231.473248) (xy 79.96047 -231.607868)
		)
		(stroke
			(width 0)
			(type solid)
		)
		(fill yes)
		(layer "F.Cu")
		(net "M_A_CPU1_SB_DQ<12>")
	)
	(gr_poly
		(pts
			(xy 80.06715 -230.7082) (xy 80.102964 -230.672132) (xy 79.91729 -230.486458) (xy 79.881222 -230.522272)
			(xy 79.834994 -230.619808) (xy 79.969614 -230.754428)
		)
		(stroke
			(width 0)
			(type solid)
		)
		(fill yes)
		(layer "F.Cu")
		(net "M_A_CPU1_SB_DQ<13>")
	)
	(gr_poly
		(pts
			(xy 80.067658 -275.03247) (xy 80.031844 -274.996656) (xy 79.934308 -274.950428) (xy 79.799688 -275.085048)
			(xy 79.845916 -275.182584) (xy 79.88173 -275.218398)
		)
		(stroke
			(width 0)
			(type solid)
		)
		(fill yes)
		(layer "F.Cu")
		(net "M_A_CPU1_SA_DQ<23>")
	)
	(gr_poly
		(pts
			(xy 80.07477 -270.03883) (xy 80.028542 -269.941294) (xy 79.992474 -269.90548) (xy 79.806546 -270.091408)
			(xy 79.842614 -270.127222) (xy 79.939896 -270.17345)
		)
		(stroke
			(width 0)
			(type solid)
		)
		(fill yes)
		(layer "F.Cu")
		(net "M_A_CPU1_SA_DQ<29>")
	)
	(gr_poly
		(pts
			(xy 80.077056 -275.886164) (xy 80.040988 -275.850096) (xy 79.943706 -275.803868) (xy 79.808832 -275.938488)
			(xy 79.85506 -276.036024) (xy 79.891128 -276.071838)
		)
		(stroke
			(width 0)
			(type solid)
		)
		(fill yes)
		(layer "F.Cu")
		(net "M_A_CPU1_SA_DQ<22>")
	)
	(gr_poly
		(pts
			(xy 80.077056 -229.438708) (xy 80.113124 -229.402894) (xy 79.927196 -229.216966) (xy 79.891382 -229.25278)
			(xy 79.845154 -229.350316) (xy 79.979774 -229.484936)
		)
		(stroke
			(width 0)
			(type solid)
		)
		(fill yes)
		(layer "F.Cu")
		(net "M_A_CPU1_SB_DQ<16>")
	)
	(gr_poly
		(pts
			(xy 80.084422 -270.892524) (xy 80.03794 -270.794988) (xy 80.002126 -270.759174) (xy 79.816198 -270.945102)
			(xy 79.852266 -270.980916) (xy 79.949548 -271.027144)
		)
		(stroke
			(width 0)
			(type solid)
		)
		(fill yes)
		(layer "F.Cu")
		(net "M_A_CPU1_SA_DQ<28>")
	)
	(gr_poly
		(pts
			(xy 80.085184 -221.847918) (xy 80.034384 -221.847918) (xy 79.932784 -221.883986) (xy 79.932784 -222.074486)
			(xy 80.034384 -222.110554) (xy 80.085184 -222.110554)
		)
		(stroke
			(width 0)
			(type solid)
		)
		(fill yes)
		(layer "F.Cu")
		(net "M_A_CPU1_SB_DQ<23>")
	)
	(gr_poly
		(pts
			(xy 80.085184 -221.251018) (xy 80.034384 -221.251018) (xy 79.932784 -221.287086) (xy 79.932784 -221.477586)
			(xy 80.034384 -221.513654) (xy 80.085184 -221.513654)
		)
		(stroke
			(width 0)
			(type solid)
		)
		(fill yes)
		(layer "F.Cu")
		(net "M_A_CPU1_SB_DQ<23>")
	)
	(gr_poly
		(pts
			(xy 80.085184 -220.654118) (xy 80.034384 -220.654118) (xy 79.932784 -220.690186) (xy 79.932784 -220.880686)
			(xy 80.034384 -220.916754) (xy 80.085184 -220.916754)
		)
		(stroke
			(width 0)
			(type solid)
		)
		(fill yes)
		(layer "F.Cu")
		(net "M_A_CPU1_SB_DQ<23>")
	)
	(gr_poly
		(pts
			(xy 80.085184 -220.057218) (xy 80.034384 -220.057218) (xy 79.932784 -220.093286) (xy 79.932784 -220.283786)
			(xy 80.034384 -220.319854) (xy 80.085184 -220.319854)
		)
		(stroke
			(width 0)
			(type solid)
		)
		(fill yes)
		(layer "F.Cu")
		(net "M_A_CPU1_SB_DQ<23>")
	)
	(gr_poly
		(pts
			(xy 80.085184 -219.460318) (xy 80.034384 -219.460318) (xy 79.932784 -219.496386) (xy 79.932784 -219.686886)
			(xy 80.034384 -219.722954) (xy 80.085184 -219.722954)
		)
		(stroke
			(width 0)
			(type solid)
		)
		(fill yes)
		(layer "F.Cu")
		(net "M_A_CPU1_SB_DQ<23>")
	)
	(gr_poly
		(pts
			(xy 80.085184 -218.863418) (xy 80.034384 -218.863418) (xy 79.932784 -218.899486) (xy 79.932784 -219.089986)
			(xy 80.034384 -219.126054) (xy 80.085184 -219.126054)
		)
		(stroke
			(width 0)
			(type solid)
		)
		(fill yes)
		(layer "F.Cu")
		(net "M_A_CPU1_SB_DQ<23>")
	)
	(gr_poly
		(pts
			(xy 80.085184 -218.266518) (xy 80.034384 -218.266518) (xy 79.932784 -218.302586) (xy 79.932784 -218.493086)
			(xy 80.034384 -218.529154) (xy 80.085184 -218.529154)
		)
		(stroke
			(width 0)
			(type solid)
		)
		(fill yes)
		(layer "F.Cu")
		(net "M_A_CPU1_SB_DQ<23>")
	)
	(gr_poly
		(pts
			(xy 80.085184 -217.669618) (xy 80.034384 -217.669618) (xy 79.932784 -217.705686) (xy 79.932784 -217.896186)
			(xy 80.034384 -217.932254) (xy 80.085184 -217.932254)
		)
		(stroke
			(width 0)
			(type solid)
		)
		(fill yes)
		(layer "F.Cu")
		(net "M_A_CPU1_SB_DQ<23>")
	)
	(gr_poly
		(pts
			(xy 80.085184 -217.072718) (xy 80.034384 -217.072718) (xy 79.932784 -217.108786) (xy 79.932784 -217.299286)
			(xy 80.034384 -217.335354) (xy 80.085184 -217.335354)
		)
		(stroke
			(width 0)
			(type solid)
		)
		(fill yes)
		(layer "F.Cu")
		(net "M_A_CPU1_SB_DQ<23>")
	)
	(gr_poly
		(pts
			(xy 80.085184 -216.475818) (xy 80.034384 -216.475818) (xy 79.932784 -216.511886) (xy 79.932784 -216.702386)
			(xy 80.034384 -216.738454) (xy 80.085184 -216.738454)
		)
		(stroke
			(width 0)
			(type solid)
		)
		(fill yes)
		(layer "F.Cu")
		(net "M_A_CPU1_SB_DQ<23>")
	)
	(gr_poly
		(pts
			(xy 80.085184 -215.878918) (xy 80.034384 -215.878918) (xy 79.932784 -215.914986) (xy 79.932784 -216.105486)
			(xy 80.034384 -216.141554) (xy 80.085184 -216.141554)
		)
		(stroke
			(width 0)
			(type solid)
		)
		(fill yes)
		(layer "F.Cu")
		(net "M_A_CPU1_SB_DQ<23>")
	)
	(gr_poly
		(pts
			(xy 80.085184 -215.282018) (xy 80.034384 -215.282018) (xy 79.932784 -215.318086) (xy 79.932784 -215.508586)
			(xy 80.034384 -215.544654) (xy 80.085184 -215.544654)
		)
		(stroke
			(width 0)
			(type solid)
		)
		(fill yes)
		(layer "F.Cu")
		(net "M_A_CPU1_SB_DQ<23>")
	)
	(gr_poly
		(pts
			(xy 80.085184 -214.685118) (xy 80.034384 -214.685118) (xy 79.932784 -214.721186) (xy 79.932784 -214.911686)
			(xy 80.034384 -214.947754) (xy 80.085184 -214.947754)
		)
		(stroke
			(width 0)
			(type solid)
		)
		(fill yes)
		(layer "F.Cu")
		(net "M_A_CPU1_SB_DQ<23>")
	)
	(gr_poly
		(pts
			(xy 80.086454 -228.585522) (xy 80.122268 -228.549454) (xy 79.93634 -228.363526) (xy 79.900526 -228.399594)
			(xy 79.854298 -228.496876) (xy 79.988918 -228.63175)
		)
		(stroke
			(width 0)
			(type solid)
		)
		(fill yes)
		(layer "F.Cu")
		(net "M_A_CPU1_SB_DQ<17>")
	)
	(gr_poly
		(pts
			(xy 80.087216 -234.466384) (xy 80.133444 -234.369102) (xy 79.998824 -234.234228) (xy 79.901288 -234.280456)
			(xy 79.865474 -234.316524) (xy 80.051402 -234.502452)
		)
		(stroke
			(width 0)
			(type solid)
		)
		(fill yes)
		(layer "F.Cu")
		(net "M_A_CPU1_SB_DQ<10>")
	)
	(gr_poly
		(pts
			(xy 80.09636 -233.613198) (xy 80.142842 -233.515662) (xy 80.007968 -233.381042) (xy 79.910686 -233.42727)
			(xy 79.874618 -233.463084) (xy 80.060546 -233.649012)
		)
		(stroke
			(width 0)
			(type solid)
		)
		(fill yes)
		(layer "F.Cu")
		(net "M_A_CPU1_SB_DQ<11>")
	)
	(gr_poly
		(pts
			(xy 80.102202 -223.73082) (xy 80.14843 -223.633284) (xy 80.01381 -223.498664) (xy 79.916274 -223.544892)
			(xy 79.88046 -223.580706) (xy 80.066388 -223.766634)
		)
		(stroke
			(width 0)
			(type solid)
		)
		(fill yes)
		(layer "F.Cu")
		(net "M_A_CPU1_SB_DQ<20>")
	)
	(gr_poly
		(pts
			(xy 80.108044 -262.26643) (xy 80.07223 -262.230362) (xy 79.974694 -262.184134) (xy 79.840074 -262.319008)
			(xy 79.886302 -262.41629) (xy 79.922116 -262.452358)
		)
		(stroke
			(width 0)
			(type solid)
		)
		(fill yes)
		(layer "F.Cu")
		(net "M_A_CPU1_SA_CB<7>")
	)
	(gr_poly
		(pts
			(xy 80.1116 -222.87738) (xy 80.157828 -222.779844) (xy 80.022954 -222.645224) (xy 79.925672 -222.691452)
			(xy 79.889604 -222.727266) (xy 80.075532 -222.913194)
		)
		(stroke
			(width 0)
			(type solid)
		)
		(fill yes)
		(layer "F.Cu")
		(net "M_A_CPU1_SB_DQ<21>")
	)
	(gr_poly
		(pts
			(xy 80.117442 -263.120124) (xy 80.081628 -263.084056) (xy 79.984092 -263.037828) (xy 79.849472 -263.172448)
			(xy 79.8957 -263.269984) (xy 79.931768 -263.305798)
		)
		(stroke
			(width 0)
			(type solid)
		)
		(fill yes)
		(layer "F.Cu")
		(net "M_A_CPU1_SA_CB<6>")
	)
	(gr_poly
		(pts
			(xy 80.122268 -272.796508) (xy 80.086454 -272.760694) (xy 79.988918 -272.714212) (xy 79.854298 -272.849086)
			(xy 79.900526 -272.946368) (xy 79.93634 -272.982436)
		)
		(stroke
			(width 0)
			(type solid)
		)
		(fill yes)
		(layer "F.Cu")
		(net "M_A_CPU1_SA_DQ<27>")
	)
	(gr_poly
		(pts
			(xy 80.122522 -265.70305) (xy 80.086708 -265.666982) (xy 79.989172 -265.620754) (xy 79.854552 -265.755374)
			(xy 79.90078 -265.85291) (xy 79.936594 -265.888978)
		)
		(stroke
			(width 0)
			(type solid)
		)
		(fill yes)
		(layer "F.Cu")
		(net "M_A_CPU1_SA_CB<3>")
	)
	(gr_poly
		(pts
			(xy 80.131666 -273.650202) (xy 80.095852 -273.614134) (xy 79.998316 -273.567906) (xy 79.863696 -273.70278)
			(xy 79.909924 -273.800062) (xy 79.945738 -273.83613)
		)
		(stroke
			(width 0)
			(type solid)
		)
		(fill yes)
		(layer "F.Cu")
		(net "M_A_CPU1_SA_DQ<26>")
	)
	(gr_poly
		(pts
			(xy 80.13192 -266.55649) (xy 80.096106 -266.520422) (xy 79.99857 -266.474194) (xy 79.86395 -266.609068)
			(xy 79.910178 -266.70635) (xy 79.945992 -266.742418)
		)
		(stroke
			(width 0)
			(type solid)
		)
		(fill yes)
		(layer "F.Cu")
		(net "M_A_CPU1_SA_CB<2>")
	)
	(gr_poly
		(pts
			(xy 80.13446 -231.063038) (xy 80.180688 -230.965502) (xy 80.045814 -230.830882) (xy 79.948532 -230.87711)
			(xy 79.912464 -230.912924) (xy 80.098392 -231.098852)
		)
		(stroke
			(width 0)
			(type solid)
		)
		(fill yes)
		(layer "F.Cu")
		(net "M_A_CPU1_SB_DQ<14>")
	)
	(gr_poly
		(pts
			(xy 80.143604 -230.209598) (xy 80.189832 -230.112316) (xy 80.055212 -229.977442) (xy 79.957676 -230.02367)
			(xy 79.921862 -230.059738) (xy 80.10779 -230.245666)
		)
		(stroke
			(width 0)
			(type solid)
		)
		(fill yes)
		(layer "F.Cu")
		(net "M_A_CPU1_SB_DQ<15>")
	)
	(gr_poly
		(pts
			(xy 80.15224 -249.270266) (xy 80.116172 -249.168666) (xy 79.925672 -249.168666) (xy 79.88935 -249.270266)
			(xy 79.88935 -249.321066) (xy 80.15224 -249.321066)
		)
		(stroke
			(width 0)
			(type solid)
		)
		(fill yes)
		(layer "F.Cu")
		(net "M_A_CPU1_SB_CA<0>")
	)
	(gr_poly
		(pts
			(xy 80.15224 -248.965212) (xy 80.116172 -248.863612) (xy 79.925672 -248.863612) (xy 79.88935 -248.965212)
			(xy 79.88935 -249.016012) (xy 80.15224 -249.016012)
		)
		(stroke
			(width 0)
			(type solid)
		)
		(fill yes)
		(layer "F.Cu")
		(net "M_A_CPU1_SB_CA<1>")
	)
	(gr_poly
		(pts
			(xy 80.15224 -248.660412) (xy 80.116172 -248.558812) (xy 79.925672 -248.558812) (xy 79.88935 -248.660412)
			(xy 79.88935 -248.711212) (xy 80.15224 -248.711212)
		)
		(stroke
			(width 0)
			(type solid)
		)
		(fill yes)
		(layer "F.Cu")
		(net "M_A_CPU1_SB_CA<2>")
	)
	(gr_poly
		(pts
			(xy 80.15224 -248.355612) (xy 80.116172 -248.254012) (xy 79.925672 -248.254012) (xy 79.88935 -248.355612)
			(xy 79.88935 -248.406412) (xy 80.15224 -248.406412)
		)
		(stroke
			(width 0)
			(type solid)
		)
		(fill yes)
		(layer "F.Cu")
		(net "M_A_CPU1_SB_CA<3>")
	)
	(gr_poly
		(pts
			(xy 80.15224 -248.050812) (xy 80.116172 -247.949212) (xy 79.925672 -247.949212) (xy 79.88935 -248.050812)
			(xy 79.88935 -248.101612) (xy 80.15224 -248.101612)
		)
		(stroke
			(width 0)
			(type solid)
		)
		(fill yes)
		(layer "F.Cu")
		(net "M_A_CPU1_SB_CA<4>")
	)
	(gr_poly
		(pts
			(xy 80.15224 -247.746012) (xy 80.116172 -247.644412) (xy 79.925672 -247.644412) (xy 79.88935 -247.746012)
			(xy 79.88935 -247.796812) (xy 80.15224 -247.796812)
		)
		(stroke
			(width 0)
			(type solid)
		)
		(fill yes)
		(layer "F.Cu")
		(net "M_A_CPU1_SB_CA<5>")
	)
	(gr_poly
		(pts
			(xy 80.15224 -247.441212) (xy 80.116172 -247.339612) (xy 79.925672 -247.339612) (xy 79.88935 -247.441212)
			(xy 79.88935 -247.492012) (xy 80.15224 -247.492012)
		)
		(stroke
			(width 0)
			(type solid)
		)
		(fill yes)
		(layer "F.Cu")
		(net "M_A_CPU1_SB_CA<6>")
	)
	(gr_poly
		(pts
			(xy 80.15224 -247.136412) (xy 80.116172 -247.034812) (xy 79.925672 -247.034812) (xy 79.88935 -247.136412)
			(xy 79.88935 -247.187212) (xy 80.15224 -247.187212)
		)
		(stroke
			(width 0)
			(type solid)
		)
		(fill yes)
		(layer "F.Cu")
		(net "M_A_CPU1_SB_PAR")
	)
	(gr_poly
		(pts
			(xy 80.15224 -246.831612) (xy 80.116172 -246.730012) (xy 79.925672 -246.730012) (xy 79.88935 -246.831612)
			(xy 79.88935 -246.882412) (xy 80.15224 -246.882412)
		)
		(stroke
			(width 0)
			(type solid)
		)
		(fill yes)
		(layer "F.Cu")
		(net "M_A_CPU1_SB_CS_N<2>")
	)
	(gr_poly
		(pts
			(xy 80.15224 -246.526812) (xy 80.116172 -246.425212) (xy 79.925672 -246.425212) (xy 79.88935 -246.526812)
			(xy 79.88935 -246.577612) (xy 80.15224 -246.577612)
		)
		(stroke
			(width 0)
			(type solid)
		)
		(fill yes)
		(layer "F.Cu")
		(net "M_A_CPU1_SB_CS_N<0>")
	)
	(gr_poly
		(pts
			(xy 80.15224 -246.222012) (xy 80.116172 -246.120412) (xy 79.925672 -246.120412) (xy 79.88935 -246.222012)
			(xy 79.88935 -246.272812) (xy 80.15224 -246.272812)
		)
		(stroke
			(width 0)
			(type solid)
		)
		(fill yes)
		(layer "F.Cu")
		(net "M_A_CPU1_SB_CS_N<3>")
	)
	(gr_poly
		(pts
			(xy 80.15224 -245.917212) (xy 80.116172 -245.815612) (xy 79.925672 -245.815612) (xy 79.88935 -245.917212)
			(xy 79.88935 -245.968012) (xy 80.15224 -245.968012)
		)
		(stroke
			(width 0)
			(type solid)
		)
		(fill yes)
		(layer "F.Cu")
		(net "M_A_CPU1_SB_CS_N<1>")
	)
	(gr_poly
		(pts
			(xy 80.15351 -228.94036) (xy 80.199992 -228.842824) (xy 80.065118 -228.708204) (xy 79.967836 -228.754432)
			(xy 79.931768 -228.790246) (xy 80.117696 -228.976174)
		)
		(stroke
			(width 0)
			(type solid)
		)
		(fill yes)
		(layer "F.Cu")
		(net "M_A_CPU1_SB_DQ<18>")
	)
	(gr_poly
		(pts
			(xy 80.154526 -275.59254) (xy 80.108298 -275.495258) (xy 80.07223 -275.45919) (xy 79.886302 -275.645118)
			(xy 79.92237 -275.680932) (xy 80.019652 -275.727414)
		)
		(stroke
			(width 0)
			(type solid)
		)
		(fill yes)
		(layer "F.Cu")
		(net "M_A_CPU1_SA_DQ<21>")
	)
	(gr_poly
		(pts
			(xy 80.162908 -228.08692) (xy 80.209136 -227.989384) (xy 80.074262 -227.854764) (xy 79.97698 -227.900992)
			(xy 79.940912 -227.936806) (xy 80.12684 -228.122734)
		)
		(stroke
			(width 0)
			(type solid)
		)
		(fill yes)
		(layer "F.Cu")
		(net "M_A_CPU1_SB_DQ<19>")
	)
	(gr_poly
		(pts
			(xy 80.169512 -288.584132) (xy 80.169512 -288.393632) (xy 80.067912 -288.35731) (xy 80.017112 -288.35731)
			(xy 80.017112 -288.6202) (xy 80.067912 -288.6202)
		)
		(stroke
			(width 0)
			(type solid)
		)
		(fill yes)
		(layer "F.Cu")
		(net "M_A_CPU1_SA_DQ<19>")
	)
	(gr_poly
		(pts
			(xy 80.169512 -287.987232) (xy 80.169512 -287.796732) (xy 80.067912 -287.76041) (xy 80.017112 -287.76041)
			(xy 80.017112 -288.0233) (xy 80.067912 -288.0233)
		)
		(stroke
			(width 0)
			(type solid)
		)
		(fill yes)
		(layer "F.Cu")
		(net "M_A_CPU1_SA_DQ<19>")
	)
	(gr_poly
		(pts
			(xy 80.169512 -287.390332) (xy 80.169512 -287.199832) (xy 80.067912 -287.16351) (xy 80.017112 -287.16351)
			(xy 80.017112 -287.4264) (xy 80.067912 -287.4264)
		)
		(stroke
			(width 0)
			(type solid)
		)
		(fill yes)
		(layer "F.Cu")
		(net "M_A_CPU1_SA_DQ<19>")
	)
	(gr_poly
		(pts
			(xy 80.169512 -286.793432) (xy 80.169512 -286.602932) (xy 80.067912 -286.56661) (xy 80.017112 -286.56661)
			(xy 80.017112 -286.8295) (xy 80.067912 -286.8295)
		)
		(stroke
			(width 0)
			(type solid)
		)
		(fill yes)
		(layer "F.Cu")
		(net "M_A_CPU1_SA_DQ<19>")
	)
	(gr_poly
		(pts
			(xy 80.169512 -286.196532) (xy 80.169512 -286.006032) (xy 80.067912 -285.96971) (xy 80.017112 -285.96971)
			(xy 80.017112 -286.2326) (xy 80.067912 -286.2326)
		)
		(stroke
			(width 0)
			(type solid)
		)
		(fill yes)
		(layer "F.Cu")
		(net "M_A_CPU1_SA_DQ<19>")
	)
	(gr_poly
		(pts
			(xy 80.169512 -285.599632) (xy 80.169512 -285.409132) (xy 80.067912 -285.37281) (xy 80.017112 -285.37281)
			(xy 80.017112 -285.6357) (xy 80.067912 -285.6357)
		)
		(stroke
			(width 0)
			(type solid)
		)
		(fill yes)
		(layer "F.Cu")
		(net "M_A_CPU1_SA_DQ<19>")
	)
	(gr_poly
		(pts
			(xy 80.169512 -285.002732) (xy 80.169512 -284.812232) (xy 80.067912 -284.77591) (xy 80.017112 -284.77591)
			(xy 80.017112 -285.0388) (xy 80.067912 -285.0388)
		)
		(stroke
			(width 0)
			(type solid)
		)
		(fill yes)
		(layer "F.Cu")
		(net "M_A_CPU1_SA_DQ<19>")
	)
	(gr_poly
		(pts
			(xy 80.169512 -284.405832) (xy 80.169512 -284.215332) (xy 80.067912 -284.17901) (xy 80.017112 -284.17901)
			(xy 80.017112 -284.4419) (xy 80.067912 -284.4419)
		)
		(stroke
			(width 0)
			(type solid)
		)
		(fill yes)
		(layer "F.Cu")
		(net "M_A_CPU1_SA_DQ<19>")
	)
	(gr_poly
		(pts
			(xy 80.169512 -283.808932) (xy 80.169512 -283.618432) (xy 80.067912 -283.58211) (xy 80.017112 -283.58211)
			(xy 80.017112 -283.845) (xy 80.067912 -283.845)
		)
		(stroke
			(width 0)
			(type solid)
		)
		(fill yes)
		(layer "F.Cu")
		(net "M_A_CPU1_SA_DQ<19>")
	)
	(gr_poly
		(pts
			(xy 80.169512 -283.212032) (xy 80.169512 -283.021532) (xy 80.067912 -282.98521) (xy 80.017112 -282.98521)
			(xy 80.017112 -283.2481) (xy 80.067912 -283.2481)
		)
		(stroke
			(width 0)
			(type solid)
		)
		(fill yes)
		(layer "F.Cu")
		(net "M_A_CPU1_SA_DQ<19>")
	)
	(gr_poly
		(pts
			(xy 80.169512 -282.615132) (xy 80.169512 -282.424632) (xy 80.067912 -282.38831) (xy 80.017112 -282.38831)
			(xy 80.017112 -282.6512) (xy 80.067912 -282.6512)
		)
		(stroke
			(width 0)
			(type solid)
		)
		(fill yes)
		(layer "F.Cu")
		(net "M_A_CPU1_SA_DQ<19>")
	)
	(gr_poly
		(pts
			(xy 80.185006 -259.110226) (xy 80.185006 -259.059426) (xy 79.922116 -259.059426) (xy 79.922116 -259.110226)
			(xy 79.958184 -259.211826) (xy 80.148684 -259.211826)
		)
		(stroke
			(width 0)
			(type solid)
		)
		(fill yes)
		(layer "F.Cu")
		(net "M_A_CPU1_SA_CS_N<3>")
	)
	(gr_poly
		(pts
			(xy 80.185006 -258.805426) (xy 80.185006 -258.754626) (xy 79.922116 -258.754626) (xy 79.922116 -258.805426)
			(xy 79.958184 -258.907026) (xy 80.148684 -258.907026)
		)
		(stroke
			(width 0)
			(type solid)
		)
		(fill yes)
		(layer "F.Cu")
		(net "M_A_CPU1_SA_CS_N<1>")
	)
	(gr_poly
		(pts
			(xy 80.185006 -258.500626) (xy 80.185006 -258.449826) (xy 79.922116 -258.449826) (xy 79.922116 -258.500626)
			(xy 79.958184 -258.602226) (xy 80.148684 -258.602226)
		)
		(stroke
			(width 0)
			(type solid)
		)
		(fill yes)
		(layer "F.Cu")
		(net "M_A_CPU1_SA_CA<0>")
	)
	(gr_poly
		(pts
			(xy 80.185006 -258.195826) (xy 80.185006 -258.145026) (xy 79.922116 -258.145026) (xy 79.922116 -258.195826)
			(xy 79.958184 -258.297426) (xy 80.148684 -258.297426)
		)
		(stroke
			(width 0)
			(type solid)
		)
		(fill yes)
		(layer "F.Cu")
		(net "M_A_CPU1_SA_CA<1>")
	)
	(gr_poly
		(pts
			(xy 80.185006 -257.891026) (xy 80.185006 -257.840226) (xy 79.922116 -257.840226) (xy 79.922116 -257.891026)
			(xy 79.958184 -257.992626) (xy 80.148684 -257.992626)
		)
		(stroke
			(width 0)
			(type solid)
		)
		(fill yes)
		(layer "F.Cu")
		(net "M_A_CPU1_SA_CA<2>")
	)
	(gr_poly
		(pts
			(xy 80.185006 -257.586226) (xy 80.185006 -257.535426) (xy 79.922116 -257.535426) (xy 79.922116 -257.586226)
			(xy 79.958184 -257.687826) (xy 80.148684 -257.687826)
		)
		(stroke
			(width 0)
			(type solid)
		)
		(fill yes)
		(layer "F.Cu")
		(net "M_A_CPU1_SA_CA<3>")
	)
	(gr_poly
		(pts
			(xy 80.185006 -257.281426) (xy 80.185006 -257.230626) (xy 79.922116 -257.230626) (xy 79.922116 -257.281426)
			(xy 79.958184 -257.383026) (xy 80.148684 -257.383026)
		)
		(stroke
			(width 0)
			(type solid)
		)
		(fill yes)
		(layer "F.Cu")
		(net "M_A_CPU1_SA_CA<4>")
	)
	(gr_poly
		(pts
			(xy 80.185006 -256.976626) (xy 80.185006 -256.925826) (xy 79.922116 -256.925826) (xy 79.922116 -256.976626)
			(xy 79.958184 -257.078226) (xy 80.148684 -257.078226)
		)
		(stroke
			(width 0)
			(type solid)
		)
		(fill yes)
		(layer "F.Cu")
		(net "M_A_CPU1_SA_CA<5>")
	)
	(gr_poly
		(pts
			(xy 80.185006 -256.671826) (xy 80.185006 -256.621026) (xy 79.922116 -256.621026) (xy 79.922116 -256.671826)
			(xy 79.958184 -256.773426) (xy 80.148684 -256.773426)
		)
		(stroke
			(width 0)
			(type solid)
		)
		(fill yes)
		(layer "F.Cu")
		(net "M_A_CPU1_SA_CA<6>")
	)
	(gr_poly
		(pts
			(xy 80.185006 -256.367026) (xy 80.185006 -256.316226) (xy 79.922116 -256.316226) (xy 79.922116 -256.367026)
			(xy 79.958184 -256.468626) (xy 80.148684 -256.468626)
		)
		(stroke
			(width 0)
			(type solid)
		)
		(fill yes)
		(layer "F.Cu")
		(net "M_A_CPU1_SA_PAR")
	)
	(gr_poly
		(pts
			(xy 80.194912 -262.8265) (xy 80.148684 -262.729218) (xy 80.11287 -262.69315) (xy 79.926942 -262.879078)
			(xy 79.962756 -262.914892) (xy 80.060292 -262.961374)
		)
		(stroke
			(width 0)
			(type solid)
		)
		(fill yes)
		(layer "F.Cu")
		(net "M_A_CPU1_SA_CB<5>")
	)
	(gr_poly
		(pts
			(xy 80.203548 -269.694406) (xy 80.167734 -269.658338) (xy 80.070198 -269.61211) (xy 79.935578 -269.746984)
			(xy 79.981806 -269.844266) (xy 80.01762 -269.880334)
		)
		(stroke
			(width 0)
			(type solid)
		)
		(fill yes)
		(layer "F.Cu")
		(net "M_A_CPU1_SA_DQ<29>")
	)
	(gr_poly
		(pts
			(xy 80.204564 -263.680194) (xy 80.158336 -263.582658) (xy 80.122268 -263.546844) (xy 79.93634 -263.732772)
			(xy 79.972408 -263.768586) (xy 80.06969 -263.814814)
		)
		(stroke
			(width 0)
			(type solid)
		)
		(fill yes)
		(layer "F.Cu")
		(net "M_A_CPU1_SA_CB<4>")
	)
	(gr_poly
		(pts
			(xy 80.20939 -273.356832) (xy 80.163162 -273.259296) (xy 80.127094 -273.223482) (xy 79.941166 -273.40941)
			(xy 79.977234 -273.445224) (xy 80.074516 -273.491452)
		)
		(stroke
			(width 0)
			(type solid)
		)
		(fill yes)
		(layer "F.Cu")
		(net "M_A_CPU1_SA_DQ<25>")
	)
	(gr_poly
		(pts
			(xy 80.20939 -266.26312) (xy 80.163162 -266.165584) (xy 80.127094 -266.12977) (xy 79.94142 -266.315444)
			(xy 79.977234 -266.351512) (xy 80.07477 -266.39774)
		)
		(stroke
			(width 0)
			(type solid)
		)
		(fill yes)
		(layer "F.Cu")
		(net "M_A_CPU1_SA_CB<1>")
	)
	(gr_poly
		(pts
			(xy 80.2132 -270.5481) (xy 80.177386 -270.512286) (xy 80.07985 -270.466058) (xy 79.94523 -270.600678)
			(xy 79.991458 -270.698214) (xy 80.027272 -270.734028)
		)
		(stroke
			(width 0)
			(type solid)
		)
		(fill yes)
		(layer "F.Cu")
		(net "M_A_CPU1_SA_DQ<28>")
	)
	(gr_poly
		(pts
			(xy 80.218534 -274.210272) (xy 80.172306 -274.112736) (xy 80.136238 -274.076922) (xy 79.950564 -274.262596)
			(xy 79.986378 -274.298664) (xy 80.083914 -274.344892)
		)
		(stroke
			(width 0)
			(type solid)
		)
		(fill yes)
		(layer "F.Cu")
		(net "M_A_CPU1_SA_DQ<24>")
	)
	(gr_poly
		(pts
			(xy 80.218788 -267.11656) (xy 80.17256 -267.019024) (xy 80.136492 -266.98321) (xy 79.950564 -267.169138)
			(xy 79.986632 -267.204952) (xy 80.083914 -267.25118)
		)
		(stroke
			(width 0)
			(type solid)
		)
		(fill yes)
		(layer "F.Cu")
		(net "M_A_CPU1_SA_CB<0>")
	)
	(gr_poly
		(pts
			(xy 80.224122 -280.656792) (xy 80.174338 -280.646886) (xy 80.067658 -280.66238) (xy 80.03032 -280.849324)
			(xy 80.12303 -280.904696) (xy 80.172814 -280.914602)
		)
		(stroke
			(width 0)
			(type solid)
		)
		(fill yes)
		(layer "F.Cu")
		(net "M_A_CPU1_SA_DQ<19>")
	)
	(gr_poly
		(pts
			(xy 80.226408 -234.74934) (xy 80.262476 -234.713526) (xy 80.076548 -234.527598) (xy 80.04048 -234.563412)
			(xy 79.994252 -234.660948) (xy 80.129126 -234.795568)
		)
		(stroke
			(width 0)
			(type solid)
		)
		(fill yes)
		(layer "F.Cu")
		(net "M_A_CPU1_SB_DQ<10>")
	)
	(gr_poly
		(pts
			(xy 80.235552 -233.8959) (xy 80.27162 -233.860086) (xy 80.085692 -233.674158) (xy 80.049878 -233.709972)
			(xy 80.00365 -233.807508) (xy 80.13827 -233.942128)
		)
		(stroke
			(width 0)
			(type solid)
		)
		(fill yes)
		(layer "F.Cu")
		(net "M_A_CPU1_SB_DQ<11>")
	)
	(gr_poly
		(pts
			(xy 80.237584 -221.776036) (xy 80.237584 -221.585536) (xy 80.135984 -221.549214) (xy 80.085184 -221.549214)
			(xy 80.085184 -221.812358) (xy 80.135984 -221.812358)
		)
		(stroke
			(width 0)
			(type solid)
		)
		(fill yes)
		(layer "F.Cu")
		(net "M_A_CPU1_SB_DQ<23>")
	)
	(gr_poly
		(pts
			(xy 80.237584 -221.179136) (xy 80.237584 -220.988636) (xy 80.135984 -220.952314) (xy 80.085184 -220.952314)
			(xy 80.085184 -221.215458) (xy 80.135984 -221.215458)
		)
		(stroke
			(width 0)
			(type solid)
		)
		(fill yes)
		(layer "F.Cu")
		(net "M_A_CPU1_SB_DQ<23>")
	)
	(gr_poly
		(pts
			(xy 80.237584 -220.582236) (xy 80.237584 -220.391736) (xy 80.135984 -220.355414) (xy 80.085184 -220.355414)
			(xy 80.085184 -220.618558) (xy 80.135984 -220.618558)
		)
		(stroke
			(width 0)
			(type solid)
		)
		(fill yes)
		(layer "F.Cu")
		(net "M_A_CPU1_SB_DQ<23>")
	)
	(gr_poly
		(pts
			(xy 80.237584 -219.985336) (xy 80.237584 -219.794836) (xy 80.135984 -219.758514) (xy 80.085184 -219.758514)
			(xy 80.085184 -220.021658) (xy 80.135984 -220.021658)
		)
		(stroke
			(width 0)
			(type solid)
		)
		(fill yes)
		(layer "F.Cu")
		(net "M_A_CPU1_SB_DQ<23>")
	)
	(gr_poly
		(pts
			(xy 80.237584 -219.388436) (xy 80.237584 -219.197936) (xy 80.135984 -219.161614) (xy 80.085184 -219.161614)
			(xy 80.085184 -219.424758) (xy 80.135984 -219.424758)
		)
		(stroke
			(width 0)
			(type solid)
		)
		(fill yes)
		(layer "F.Cu")
		(net "M_A_CPU1_SB_DQ<23>")
	)
	(gr_poly
		(pts
			(xy 80.237584 -218.791536) (xy 80.237584 -218.601036) (xy 80.135984 -218.564714) (xy 80.085184 -218.564714)
			(xy 80.085184 -218.827858) (xy 80.135984 -218.827858)
		)
		(stroke
			(width 0)
			(type solid)
		)
		(fill yes)
		(layer "F.Cu")
		(net "M_A_CPU1_SB_DQ<23>")
	)
	(gr_poly
		(pts
			(xy 80.237584 -218.194636) (xy 80.237584 -218.004136) (xy 80.135984 -217.967814) (xy 80.085184 -217.967814)
			(xy 80.085184 -218.230958) (xy 80.135984 -218.230958)
		)
		(stroke
			(width 0)
			(type solid)
		)
		(fill yes)
		(layer "F.Cu")
		(net "M_A_CPU1_SB_DQ<23>")
	)
	(gr_poly
		(pts
			(xy 80.237584 -217.597736) (xy 80.237584 -217.407236) (xy 80.135984 -217.370914) (xy 80.085184 -217.370914)
			(xy 80.085184 -217.634058) (xy 80.135984 -217.634058)
		)
		(stroke
			(width 0)
			(type solid)
		)
		(fill yes)
		(layer "F.Cu")
		(net "M_A_CPU1_SB_DQ<23>")
	)
	(gr_poly
		(pts
			(xy 80.237584 -217.000836) (xy 80.237584 -216.810336) (xy 80.135984 -216.774014) (xy 80.085184 -216.774014)
			(xy 80.085184 -217.037158) (xy 80.135984 -217.037158)
		)
		(stroke
			(width 0)
			(type solid)
		)
		(fill yes)
		(layer "F.Cu")
		(net "M_A_CPU1_SB_DQ<23>")
	)
	(gr_poly
		(pts
			(xy 80.237584 -216.403936) (xy 80.237584 -216.213436) (xy 80.135984 -216.177114) (xy 80.085184 -216.177114)
			(xy 80.085184 -216.440258) (xy 80.135984 -216.440258)
		)
		(stroke
			(width 0)
			(type solid)
		)
		(fill yes)
		(layer "F.Cu")
		(net "M_A_CPU1_SB_DQ<23>")
	)
	(gr_poly
		(pts
			(xy 80.237584 -215.807036) (xy 80.237584 -215.616536) (xy 80.135984 -215.580214) (xy 80.085184 -215.580214)
			(xy 80.085184 -215.843358) (xy 80.135984 -215.843358)
		)
		(stroke
			(width 0)
			(type solid)
		)
		(fill yes)
		(layer "F.Cu")
		(net "M_A_CPU1_SB_DQ<23>")
	)
	(gr_poly
		(pts
			(xy 80.237584 -215.210136) (xy 80.237584 -215.019636) (xy 80.135984 -214.983314) (xy 80.085184 -214.983314)
			(xy 80.085184 -215.246458) (xy 80.135984 -215.246458)
		)
		(stroke
			(width 0)
			(type solid)
		)
		(fill yes)
		(layer "F.Cu")
		(net "M_A_CPU1_SB_DQ<23>")
	)
	(gr_poly
		(pts
			(xy 80.241394 -224.013522) (xy 80.277462 -223.977708) (xy 80.091534 -223.79178) (xy 80.05572 -223.827594)
			(xy 80.009238 -223.92513) (xy 80.144112 -224.05975)
		)
		(stroke
			(width 0)
			(type solid)
		)
		(fill yes)
		(layer "F.Cu")
		(net "M_A_CPU1_SB_DQ<20>")
	)
	(gr_poly
		(pts
			(xy 80.250792 -223.160082) (xy 80.286606 -223.124268) (xy 80.100678 -222.93834) (xy 80.064864 -222.974408)
			(xy 80.018636 -223.07169) (xy 80.153256 -223.206564)
		)
		(stroke
			(width 0)
			(type solid)
		)
		(fill yes)
		(layer "F.Cu")
		(net "M_A_CPU1_SB_DQ<21>")
	)
	(gr_poly
		(pts
			(xy 80.270858 -281.201622) (xy 80.308196 -281.014932) (xy 80.215486 -280.95956) (xy 80.165702 -280.9494)
			(xy 80.11414 -281.20721) (xy 80.164178 -281.21737)
		)
		(stroke
			(width 0)
			(type solid)
		)
		(fill yes)
		(layer "F.Cu")
		(net "M_A_CPU1_SA_DQ<19>")
	)
	(gr_poly
		(pts
			(xy 80.273652 -231.345994) (xy 80.309466 -231.309926) (xy 80.123538 -231.123998) (xy 80.087724 -231.160066)
			(xy 80.041496 -231.257348) (xy 80.176116 -231.392222)
		)
		(stroke
			(width 0)
			(type solid)
		)
		(fill yes)
		(layer "F.Cu")
		(net "M_A_CPU1_SB_DQ<14>")
	)
	(gr_poly
		(pts
			(xy 80.281018 -269.401036) (xy 80.23479 -269.3035) (xy 80.198722 -269.267686) (xy 80.013048 -269.45336)
			(xy 80.048862 -269.489428) (xy 80.146398 -269.535656)
		)
		(stroke
			(width 0)
			(type solid)
		)
		(fill yes)
		(layer "F.Cu")
		(net "M_A_CPU1_SA_DQ<31>")
	)
	(gr_poly
		(pts
			(xy 80.282796 -230.492554) (xy 80.31861 -230.456486) (xy 80.132936 -230.270812) (xy 80.096868 -230.306626)
			(xy 80.05064 -230.404162) (xy 80.18526 -230.538782)
		)
		(stroke
			(width 0)
			(type solid)
		)
		(fill yes)
		(layer "F.Cu")
		(net "M_A_CPU1_SB_DQ<15>")
	)
	(gr_poly
		(pts
			(xy 80.283304 -275.248116) (xy 80.24749 -275.212302) (xy 80.149954 -275.166074) (xy 80.015334 -275.300694)
			(xy 80.061562 -275.39823) (xy 80.097376 -275.434044)
		)
		(stroke
			(width 0)
			(type solid)
		)
		(fill yes)
		(layer "F.Cu")
		(net "M_A_CPU1_SA_DQ<21>")
	)
	(gr_poly
		(pts
			(xy 80.29067 -270.25473) (xy 80.244442 -270.157448) (xy 80.208628 -270.12138) (xy 80.0227 -270.307308)
			(xy 80.058514 -270.343122) (xy 80.15605 -270.389604)
		)
		(stroke
			(width 0)
			(type solid)
		)
		(fill yes)
		(layer "F.Cu")
		(net "M_A_CPU1_SA_DQ<30>")
	)
	(gr_poly
		(pts
			(xy 80.292702 -229.223062) (xy 80.32877 -229.187248) (xy 80.142842 -229.00132) (xy 80.107028 -229.037134)
			(xy 80.0608 -229.13467) (xy 80.19542 -229.26929)
		)
		(stroke
			(width 0)
			(type solid)
		)
		(fill yes)
		(layer "F.Cu")
		(net "M_A_CPU1_SB_DQ<18>")
	)
	(gr_poly
		(pts
			(xy 80.293718 -235.104178) (xy 80.339946 -235.006642) (xy 80.205326 -234.872022) (xy 80.10779 -234.91825)
			(xy 80.071976 -234.954318) (xy 80.25765 -235.139992)
		)
		(stroke
			(width 0)
			(type solid)
		)
		(fill yes)
		(layer "F.Cu")
		(net "M_A_CPU1_SB_DQ<8>")
	)
	(gr_poly
		(pts
			(xy 80.3021 -228.369876) (xy 80.337914 -228.333808) (xy 80.151986 -228.14788) (xy 80.116172 -228.183948)
			(xy 80.069944 -228.28123) (xy 80.204564 -228.416104)
		)
		(stroke
			(width 0)
			(type solid)
		)
		(fill yes)
		(layer "F.Cu")
		(net "M_A_CPU1_SB_DQ<19>")
	)
	(gr_poly
		(pts
			(xy 80.302862 -234.250738) (xy 80.34909 -234.153456) (xy 80.21447 -234.018582) (xy 80.116934 -234.06481)
			(xy 80.08112 -234.100878) (xy 80.267048 -234.286806)
		)
		(stroke
			(width 0)
			(type solid)
		)
		(fill yes)
		(layer "F.Cu")
		(net "M_A_CPU1_SB_DQ<9>")
	)
	(gr_poly
		(pts
			(xy 80.317848 -223.515174) (xy 80.364076 -223.417638) (xy 80.229456 -223.283018) (xy 80.13192 -223.329246)
			(xy 80.096106 -223.36506) (xy 80.282034 -223.550988)
		)
		(stroke
			(width 0)
			(type solid)
		)
		(fill yes)
		(layer "F.Cu")
		(net "M_A_CPU1_SB_DQ<22>")
	)
	(gr_poly
		(pts
			(xy 80.321912 -289.25266) (xy 80.271112 -289.25266) (xy 80.169512 -289.288982) (xy 80.169512 -289.479482)
			(xy 80.271112 -289.51555) (xy 80.321912 -289.51555)
		)
		(stroke
			(width 0)
			(type solid)
		)
		(fill yes)
		(layer "F.Cu")
		(net "M_A_CPU1_SA_DQ<17>")
	)
	(gr_poly
		(pts
			(xy 80.321912 -288.65576) (xy 80.271112 -288.65576) (xy 80.169512 -288.692082) (xy 80.169512 -288.882582)
			(xy 80.271112 -288.91865) (xy 80.321912 -288.91865)
		)
		(stroke
			(width 0)
			(type solid)
		)
		(fill yes)
		(layer "F.Cu")
		(net "M_A_CPU1_SA_DQ<17>")
	)
	(gr_poly
		(pts
			(xy 80.321912 -288.05886) (xy 80.271112 -288.05886) (xy 80.169512 -288.095182) (xy 80.169512 -288.285682)
			(xy 80.271112 -288.32175) (xy 80.321912 -288.32175)
		)
		(stroke
			(width 0)
			(type solid)
		)
		(fill yes)
		(layer "F.Cu")
		(net "M_A_CPU1_SA_DQ<17>")
	)
	(gr_poly
		(pts
			(xy 80.321912 -287.46196) (xy 80.271112 -287.46196) (xy 80.169512 -287.498282) (xy 80.169512 -287.688782)
			(xy 80.271112 -287.72485) (xy 80.321912 -287.72485)
		)
		(stroke
			(width 0)
			(type solid)
		)
		(fill yes)
		(layer "F.Cu")
		(net "M_A_CPU1_SA_DQ<17>")
	)
	(gr_poly
		(pts
			(xy 80.321912 -286.86506) (xy 80.271112 -286.86506) (xy 80.169512 -286.901382) (xy 80.169512 -287.091882)
			(xy 80.271112 -287.12795) (xy 80.321912 -287.12795)
		)
		(stroke
			(width 0)
			(type solid)
		)
		(fill yes)
		(layer "F.Cu")
		(net "M_A_CPU1_SA_DQ<17>")
	)
	(gr_poly
		(pts
			(xy 80.321912 -286.26816) (xy 80.271112 -286.26816) (xy 80.169512 -286.304482) (xy 80.169512 -286.494982)
			(xy 80.271112 -286.53105) (xy 80.321912 -286.53105)
		)
		(stroke
			(width 0)
			(type solid)
		)
		(fill yes)
		(layer "F.Cu")
		(net "M_A_CPU1_SA_DQ<17>")
	)
	(gr_poly
		(pts
			(xy 80.321912 -285.67126) (xy 80.271112 -285.67126) (xy 80.169512 -285.707582) (xy 80.169512 -285.898082)
			(xy 80.271112 -285.93415) (xy 80.321912 -285.93415)
		)
		(stroke
			(width 0)
			(type solid)
		)
		(fill yes)
		(layer "F.Cu")
		(net "M_A_CPU1_SA_DQ<17>")
	)
	(gr_poly
		(pts
			(xy 80.321912 -285.07436) (xy 80.271112 -285.07436) (xy 80.169512 -285.110682) (xy 80.169512 -285.301182)
			(xy 80.271112 -285.33725) (xy 80.321912 -285.33725)
		)
		(stroke
			(width 0)
			(type solid)
		)
		(fill yes)
		(layer "F.Cu")
		(net "M_A_CPU1_SA_DQ<17>")
	)
	(gr_poly
		(pts
			(xy 80.321912 -284.47746) (xy 80.271112 -284.47746) (xy 80.169512 -284.513782) (xy 80.169512 -284.704282)
			(xy 80.271112 -284.74035) (xy 80.321912 -284.74035)
		)
		(stroke
			(width 0)
			(type solid)
		)
		(fill yes)
		(layer "F.Cu")
		(net "M_A_CPU1_SA_DQ<17>")
	)
	(gr_poly
		(pts
			(xy 80.321912 -283.88056) (xy 80.271112 -283.88056) (xy 80.169512 -283.916882) (xy 80.169512 -284.107382)
			(xy 80.271112 -284.14345) (xy 80.321912 -284.14345)
		)
		(stroke
			(width 0)
			(type solid)
		)
		(fill yes)
		(layer "F.Cu")
		(net "M_A_CPU1_SA_DQ<17>")
	)
	(gr_poly
		(pts
			(xy 80.321912 -283.28366) (xy 80.271112 -283.28366) (xy 80.169512 -283.319982) (xy 80.169512 -283.510482)
			(xy 80.271112 -283.54655) (xy 80.321912 -283.54655)
		)
		(stroke
			(width 0)
			(type solid)
		)
		(fill yes)
		(layer "F.Cu")
		(net "M_A_CPU1_SA_DQ<17>")
	)
	(gr_poly
		(pts
			(xy 80.321912 -282.68676) (xy 80.271112 -282.68676) (xy 80.169512 -282.723082) (xy 80.169512 -282.913582)
			(xy 80.271112 -282.94965) (xy 80.321912 -282.94965)
		)
		(stroke
			(width 0)
			(type solid)
		)
		(fill yes)
		(layer "F.Cu")
		(net "M_A_CPU1_SA_DQ<17>")
	)
	(gr_poly
		(pts
			(xy 80.321912 -282.08986) (xy 80.271112 -282.08986) (xy 80.169512 -282.126182) (xy 80.169512 -282.316682)
			(xy 80.271112 -282.35275) (xy 80.321912 -282.35275)
		)
		(stroke
			(width 0)
			(type solid)
		)
		(fill yes)
		(layer "F.Cu")
		(net "M_A_CPU1_SA_DQ<17>")
	)
	(gr_poly
		(pts
			(xy 80.323944 -262.482076) (xy 80.287876 -262.446262) (xy 80.190594 -262.400034) (xy 80.05572 -262.534654)
			(xy 80.101948 -262.63219) (xy 80.138016 -262.668004)
		)
		(stroke
			(width 0)
			(type solid)
		)
		(fill yes)
		(layer "F.Cu")
		(net "M_A_CPU1_SA_CB<5>")
	)
	(gr_poly
		(pts
			(xy 80.333342 -263.33577) (xy 80.297528 -263.299956) (xy 80.199992 -263.253728) (xy 80.065372 -263.388348)
			(xy 80.1116 -263.48563) (xy 80.147414 -263.521698)
		)
		(stroke
			(width 0)
			(type solid)
		)
		(fill yes)
		(layer "F.Cu")
		(net "M_A_CPU1_SA_CB<4>")
	)
	(gr_poly
		(pts
			(xy 80.338168 -273.012408) (xy 80.302354 -272.976594) (xy 80.204818 -272.930112) (xy 80.070198 -273.064986)
			(xy 80.116426 -273.162268) (xy 80.15224 -273.198336)
		)
		(stroke
			(width 0)
			(type solid)
		)
		(fill yes)
		(layer "F.Cu")
		(net "M_A_CPU1_SA_DQ<25>")
	)
	(gr_poly
		(pts
			(xy 80.338168 -265.918696) (xy 80.302354 -265.882628) (xy 80.204818 -265.8364) (xy 80.070198 -265.97102)
			(xy 80.116426 -266.068556) (xy 80.15224 -266.104624)
		)
		(stroke
			(width 0)
			(type solid)
		)
		(fill yes)
		(layer "F.Cu")
		(net "M_A_CPU1_SA_CB<1>")
	)
	(gr_poly
		(pts
			(xy 80.340708 -231.700832) (xy 80.386936 -231.603296) (xy 80.252316 -231.468676) (xy 80.15478 -231.514904)
			(xy 80.118966 -231.550972) (xy 80.30464 -231.736646)
		)
		(stroke
			(width 0)
			(type solid)
		)
		(fill yes)
		(layer "F.Cu")
		(net "M_A_CPU1_SB_DQ<12>")
	)
	(gr_poly
		(pts
			(xy 80.341216 -280.071576) (xy 80.291432 -280.06167) (xy 80.184498 -280.077164) (xy 80.147414 -280.263854)
			(xy 80.23987 -280.31948) (xy 80.289654 -280.329386)
		)
		(stroke
			(width 0)
			(type solid)
		)
		(fill yes)
		(layer "F.Cu")
		(net "M_A_CPU1_SA_DQ<19>")
	)
	(gr_poly
		(pts
			(xy 80.347312 -273.865848) (xy 80.311498 -273.82978) (xy 80.213962 -273.783552) (xy 80.079342 -273.918426)
			(xy 80.12557 -274.015708) (xy 80.161384 -274.051776)
		)
		(stroke
			(width 0)
			(type solid)
		)
		(fill yes)
		(layer "F.Cu")
		(net "M_A_CPU1_SA_DQ<24>")
	)
	(gr_poly
		(pts
			(xy 80.347566 -266.772136) (xy 80.311752 -266.736068) (xy 80.214216 -266.68984) (xy 80.079596 -266.824714)
			(xy 80.125824 -266.921996) (xy 80.161638 -266.958064)
		)
		(stroke
			(width 0)
			(type solid)
		)
		(fill yes)
		(layer "F.Cu")
		(net "M_A_CPU1_SA_CB<0>")
	)
	(gr_poly
		(pts
			(xy 80.350106 -230.847392) (xy 80.396334 -230.749856) (xy 80.26146 -230.615236) (xy 80.164178 -230.661464)
			(xy 80.12811 -230.697278) (xy 80.314038 -230.883206)
		)
		(stroke
			(width 0)
			(type solid)
		)
		(fill yes)
		(layer "F.Cu")
		(net "M_A_CPU1_SB_DQ<13>")
	)
	(gr_poly
		(pts
			(xy 80.360012 -229.5779) (xy 80.40624 -229.480618) (xy 80.27162 -229.345744) (xy 80.174084 -229.391972)
			(xy 80.13827 -229.42804) (xy 80.324198 -229.613968)
		)
		(stroke
			(width 0)
			(type solid)
		)
		(fill yes)
		(layer "F.Cu")
		(net "M_A_CPU1_SB_DQ<16>")
	)
	(gr_poly
		(pts
			(xy 80.361028 -274.954746) (xy 80.3148 -274.857464) (xy 80.278732 -274.821396) (xy 80.092804 -275.007324)
			(xy 80.128872 -275.043392) (xy 80.226154 -275.08962)
		)
		(stroke
			(width 0)
			(type solid)
		)
		(fill yes)
		(layer "F.Cu")
		(net "M_A_CPU1_SA_DQ<23>")
	)
	(gr_poly
		(pts
			(xy 80.369156 -228.724714) (xy 80.415638 -228.627178) (xy 80.280764 -228.492558) (xy 80.183482 -228.538786)
			(xy 80.147414 -228.5746) (xy 80.333342 -228.760528)
		)
		(stroke
			(width 0)
			(type solid)
		)
		(fill yes)
		(layer "F.Cu")
		(net "M_A_CPU1_SB_DQ<17>")
	)
	(gr_poly
		(pts
			(xy 80.370172 -275.80844) (xy 80.323944 -275.710904) (xy 80.28813 -275.67509) (xy 80.102202 -275.861018)
			(xy 80.138016 -275.896832) (xy 80.235552 -275.94306)
		)
		(stroke
			(width 0)
			(type solid)
		)
		(fill yes)
		(layer "F.Cu")
		(net "M_A_CPU1_SA_DQ<22>")
	)
	(gr_poly
		(pts
			(xy 80.387698 -280.616406) (xy 80.425036 -280.429462) (xy 80.33258 -280.37409) (xy 80.282796 -280.364184)
			(xy 80.231234 -280.621994) (xy 80.281018 -280.6319)
		)
		(stroke
			(width 0)
			(type solid)
		)
		(fill yes)
		(layer "F.Cu")
		(net "M_A_CPU1_SA_DQ<19>")
	)
	(gr_poly
		(pts
			(xy 80.401414 -262.188706) (xy 80.354932 -262.09117) (xy 80.319118 -262.055356) (xy 80.13319 -262.241284)
			(xy 80.169258 -262.277098) (xy 80.26654 -262.323326)
		)
		(stroke
			(width 0)
			(type solid)
		)
		(fill yes)
		(layer "F.Cu")
		(net "M_A_CPU1_SA_CB<7>")
	)
	(gr_poly
		(pts
			(xy 80.409796 -269.056612) (xy 80.373982 -269.020544) (xy 80.276446 -268.974316) (xy 80.141826 -269.108936)
			(xy 80.188054 -269.206472) (xy 80.223868 -269.24254)
		)
		(stroke
			(width 0)
			(type solid)
		)
		(fill yes)
		(layer "F.Cu")
		(net "M_A_CPU1_SA_DQ<31>")
	)
	(gr_poly
		(pts
			(xy 80.410812 -263.0424) (xy 80.364584 -262.944864) (xy 80.328516 -262.90905) (xy 80.142588 -263.094978)
			(xy 80.178656 -263.130792) (xy 80.276192 -263.17702)
		)
		(stroke
			(width 0)
			(type solid)
		)
		(fill yes)
		(layer "F.Cu")
		(net "M_A_CPU1_SA_CB<6>")
	)
	(gr_poly
		(pts
			(xy 80.415384 -272.718784) (xy 80.369156 -272.621502) (xy 80.333342 -272.585434) (xy 80.147414 -272.771362)
			(xy 80.183228 -272.807176) (xy 80.280764 -272.853404)
		)
		(stroke
			(width 0)
			(type solid)
		)
		(fill yes)
		(layer "F.Cu")
		(net "M_A_CPU1_SA_DQ<27>")
	)
	(gr_poly
		(pts
			(xy 80.415892 -265.625326) (xy 80.369664 -265.52779) (xy 80.333596 -265.491976) (xy 80.147668 -265.677904)
			(xy 80.183736 -265.713718) (xy 80.281018 -265.759946)
		)
		(stroke
			(width 0)
			(type solid)
		)
		(fill yes)
		(layer "F.Cu")
		(net "M_A_CPU1_SA_CB<3>")
	)
	(gr_poly
		(pts
			(xy 80.419702 -269.910306) (xy 80.383634 -269.874492) (xy 80.286352 -269.828264) (xy 80.151478 -269.962884)
			(xy 80.197706 -270.06042) (xy 80.233774 -270.096234)
		)
		(stroke
			(width 0)
			(type solid)
		)
		(fill yes)
		(layer "F.Cu")
		(net "M_A_CPU1_SA_DQ<30>")
	)
	(gr_poly
		(pts
			(xy 80.425036 -273.572478) (xy 80.378808 -273.474942) (xy 80.34274 -273.439128) (xy 80.156812 -273.625056)
			(xy 80.19288 -273.66087) (xy 80.290162 -273.707098)
		)
		(stroke
			(width 0)
			(type solid)
		)
		(fill yes)
		(layer "F.Cu")
		(net "M_A_CPU1_SA_DQ<26>")
	)
	(gr_poly
		(pts
			(xy 80.425036 -266.478766) (xy 80.378808 -266.38123) (xy 80.342994 -266.345416) (xy 80.157066 -266.531344)
			(xy 80.193134 -266.567158) (xy 80.290416 -266.613386)
		)
		(stroke
			(width 0)
			(type solid)
		)
		(fill yes)
		(layer "F.Cu")
		(net "M_A_CPU1_SA_CB<2>")
	)
	(gr_poly
		(pts
			(xy 80.43291 -235.387134) (xy 80.468724 -235.351066) (xy 80.282796 -235.165138) (xy 80.246982 -235.201206)
			(xy 80.200754 -235.298488) (xy 80.335374 -235.433362)
		)
		(stroke
			(width 0)
			(type solid)
		)
		(fill yes)
		(layer "F.Cu")
		(net "M_A_CPU1_SB_DQ<8>")
	)
	(gr_poly
		(pts
			(xy 80.442054 -234.533694) (xy 80.478122 -234.49788) (xy 80.292194 -234.311952) (xy 80.256126 -234.347766)
			(xy 80.209898 -234.445302) (xy 80.344772 -234.579922)
		)
		(stroke
			(width 0)
			(type solid)
		)
		(fill yes)
		(layer "F.Cu")
		(net "M_A_CPU1_SB_DQ<9>")
	)
	(gr_poly
		(pts
			(xy 80.45069 -249.371866) (xy 80.45069 -249.321066) (xy 80.1878 -249.321066) (xy 80.1878 -249.371866)
			(xy 80.223868 -249.473466) (xy 80.414368 -249.473466)
		)
		(stroke
			(width 0)
			(type solid)
		)
		(fill yes)
		(layer "F.Cu")
		(net "M_A_CPU1_SB_CA<0>")
	)
	(gr_poly
		(pts
			(xy 80.45069 -249.066812) (xy 80.45069 -249.016012) (xy 80.1878 -249.016012) (xy 80.1878 -249.066812)
			(xy 80.223868 -249.168412) (xy 80.414368 -249.168412)
		)
		(stroke
			(width 0)
			(type solid)
		)
		(fill yes)
		(layer "F.Cu")
		(net "M_A_CPU1_SB_CA<1>")
	)
	(gr_poly
		(pts
			(xy 80.45069 -248.762012) (xy 80.45069 -248.711212) (xy 80.1878 -248.711212) (xy 80.1878 -248.762012)
			(xy 80.223868 -248.863612) (xy 80.414368 -248.863612)
		)
		(stroke
			(width 0)
			(type solid)
		)
		(fill yes)
		(layer "F.Cu")
		(net "M_A_CPU1_SB_CA<2>")
	)
	(gr_poly
		(pts
			(xy 80.45069 -248.457212) (xy 80.45069 -248.406412) (xy 80.1878 -248.406412) (xy 80.1878 -248.457212)
			(xy 80.223868 -248.558812) (xy 80.414368 -248.558812)
		)
		(stroke
			(width 0)
			(type solid)
		)
		(fill yes)
		(layer "F.Cu")
		(net "M_A_CPU1_SB_CA<3>")
	)
	(gr_poly
		(pts
			(xy 80.45069 -248.152412) (xy 80.45069 -248.101612) (xy 80.1878 -248.101612) (xy 80.1878 -248.152412)
			(xy 80.223868 -248.254012) (xy 80.414368 -248.254012)
		)
		(stroke
			(width 0)
			(type solid)
		)
		(fill yes)
		(layer "F.Cu")
		(net "M_A_CPU1_SB_CA<4>")
	)
	(gr_poly
		(pts
			(xy 80.45069 -247.847612) (xy 80.45069 -247.796812) (xy 80.1878 -247.796812) (xy 80.1878 -247.847612)
			(xy 80.223868 -247.949212) (xy 80.414368 -247.949212)
		)
		(stroke
			(width 0)
			(type solid)
		)
		(fill yes)
		(layer "F.Cu")
		(net "M_A_CPU1_SB_CA<5>")
	)
	(gr_poly
		(pts
			(xy 80.45069 -247.542812) (xy 80.45069 -247.492012) (xy 80.1878 -247.492012) (xy 80.1878 -247.542812)
			(xy 80.223868 -247.644412) (xy 80.414368 -247.644412)
		)
		(stroke
			(width 0)
			(type solid)
		)
		(fill yes)
		(layer "F.Cu")
		(net "M_A_CPU1_SB_CA<6>")
	)
	(gr_poly
		(pts
			(xy 80.45069 -247.238012) (xy 80.45069 -247.187212) (xy 80.1878 -247.187212) (xy 80.1878 -247.238012)
			(xy 80.223868 -247.339612) (xy 80.414368 -247.339612)
		)
		(stroke
			(width 0)
			(type solid)
		)
		(fill yes)
		(layer "F.Cu")
		(net "M_A_CPU1_SB_PAR")
	)
	(gr_poly
		(pts
			(xy 80.45069 -246.933212) (xy 80.45069 -246.882412) (xy 80.1878 -246.882412) (xy 80.1878 -246.933212)
			(xy 80.223868 -247.034812) (xy 80.414368 -247.034812)
		)
		(stroke
			(width 0)
			(type solid)
		)
		(fill yes)
		(layer "F.Cu")
		(net "M_A_CPU1_SB_CS_N<2>")
	)
	(gr_poly
		(pts
			(xy 80.45069 -246.628412) (xy 80.45069 -246.577612) (xy 80.1878 -246.577612) (xy 80.1878 -246.628412)
			(xy 80.223868 -246.730012) (xy 80.414368 -246.730012)
		)
		(stroke
			(width 0)
			(type solid)
		)
		(fill yes)
		(layer "F.Cu")
		(net "M_A_CPU1_SB_CS_N<0>")
	)
	(gr_poly
		(pts
			(xy 80.45069 -246.323612) (xy 80.45069 -246.272812) (xy 80.1878 -246.272812) (xy 80.1878 -246.323612)
			(xy 80.223868 -246.425212) (xy 80.414368 -246.425212)
		)
		(stroke
			(width 0)
			(type solid)
		)
		(fill yes)
		(layer "F.Cu")
		(net "M_A_CPU1_SB_CS_N<3>")
	)
	(gr_poly
		(pts
			(xy 80.45069 -246.018812) (xy 80.45069 -245.968012) (xy 80.1878 -245.968012) (xy 80.1878 -246.018812)
			(xy 80.223868 -246.120412) (xy 80.414368 -246.120412)
		)
		(stroke
			(width 0)
			(type solid)
		)
		(fill yes)
		(layer "F.Cu")
		(net "M_A_CPU1_SB_CS_N<1>")
	)
	(gr_poly
		(pts
			(xy 80.45704 -223.797876) (xy 80.493108 -223.762062) (xy 80.30718 -223.576134) (xy 80.271366 -223.611948)
			(xy 80.224884 -223.709484) (xy 80.359758 -223.844104)
		)
		(stroke
			(width 0)
			(type solid)
		)
		(fill yes)
		(layer "F.Cu")
		(net "M_A_CPU1_SB_DQ<22>")
	)
	(gr_poly
		(pts
			(xy 80.458056 -279.486106) (xy 80.408272 -279.4762) (xy 80.301592 -279.491948) (xy 80.264254 -279.678638)
			(xy 80.35671 -279.73401) (xy 80.406494 -279.743916)
		)
		(stroke
			(width 0)
			(type solid)
		)
		(fill yes)
		(layer "F.Cu")
		(net "M_A_CPU1_SA_DQ<19>")
	)
	(gr_poly
		(pts
			(xy 80.466438 -222.944436) (xy 80.502252 -222.908622) (xy 80.316324 -222.722694) (xy 80.28051 -222.758762)
			(xy 80.234282 -222.856044) (xy 80.368902 -222.990918)
		)
		(stroke
			(width 0)
			(type solid)
		)
		(fill yes)
		(layer "F.Cu")
		(net "M_A_CPU1_SB_DQ<23>")
	)
	(gr_poly
		(pts
			(xy 80.474312 -289.181032) (xy 80.474312 -288.990532) (xy 80.372712 -288.95421) (xy 80.321912 -288.95421)
			(xy 80.321912 -289.2171) (xy 80.372712 -289.2171)
		)
		(stroke
			(width 0)
			(type solid)
		)
		(fill yes)
		(layer "F.Cu")
		(net "M_A_CPU1_SA_DQ<17>")
	)
	(gr_poly
		(pts
			(xy 80.474312 -288.584132) (xy 80.474312 -288.393632) (xy 80.372712 -288.35731) (xy 80.321912 -288.35731)
			(xy 80.321912 -288.6202) (xy 80.372712 -288.6202)
		)
		(stroke
			(width 0)
			(type solid)
		)
		(fill yes)
		(layer "F.Cu")
		(net "M_A_CPU1_SA_DQ<17>")
	)
	(gr_poly
		(pts
			(xy 80.474312 -287.987232) (xy 80.474312 -287.796732) (xy 80.372712 -287.76041) (xy 80.321912 -287.76041)
			(xy 80.321912 -288.0233) (xy 80.372712 -288.0233)
		)
		(stroke
			(width 0)
			(type solid)
		)
		(fill yes)
		(layer "F.Cu")
		(net "M_A_CPU1_SA_DQ<17>")
	)
	(gr_poly
		(pts
			(xy 80.474312 -287.390332) (xy 80.474312 -287.199832) (xy 80.372712 -287.16351) (xy 80.321912 -287.16351)
			(xy 80.321912 -287.4264) (xy 80.372712 -287.4264)
		)
		(stroke
			(width 0)
			(type solid)
		)
		(fill yes)
		(layer "F.Cu")
		(net "M_A_CPU1_SA_DQ<17>")
	)
	(gr_poly
		(pts
			(xy 80.474312 -286.793432) (xy 80.474312 -286.602932) (xy 80.372712 -286.56661) (xy 80.321912 -286.56661)
			(xy 80.321912 -286.8295) (xy 80.372712 -286.8295)
		)
		(stroke
			(width 0)
			(type solid)
		)
		(fill yes)
		(layer "F.Cu")
		(net "M_A_CPU1_SA_DQ<17>")
	)
	(gr_poly
		(pts
			(xy 80.474312 -286.196532) (xy 80.474312 -286.006032) (xy 80.372712 -285.96971) (xy 80.321912 -285.96971)
			(xy 80.321912 -286.2326) (xy 80.372712 -286.2326)
		)
		(stroke
			(width 0)
			(type solid)
		)
		(fill yes)
		(layer "F.Cu")
		(net "M_A_CPU1_SA_DQ<17>")
	)
	(gr_poly
		(pts
			(xy 80.474312 -285.599632) (xy 80.474312 -285.409132) (xy 80.372712 -285.37281) (xy 80.321912 -285.37281)
			(xy 80.321912 -285.6357) (xy 80.372712 -285.6357)
		)
		(stroke
			(width 0)
			(type solid)
		)
		(fill yes)
		(layer "F.Cu")
		(net "M_A_CPU1_SA_DQ<17>")
	)
	(gr_poly
		(pts
			(xy 80.474312 -285.002732) (xy 80.474312 -284.812232) (xy 80.372712 -284.77591) (xy 80.321912 -284.77591)
			(xy 80.321912 -285.0388) (xy 80.372712 -285.0388)
		)
		(stroke
			(width 0)
			(type solid)
		)
		(fill yes)
		(layer "F.Cu")
		(net "M_A_CPU1_SA_DQ<17>")
	)
	(gr_poly
		(pts
			(xy 80.474312 -284.405832) (xy 80.474312 -284.215332) (xy 80.372712 -284.17901) (xy 80.321912 -284.17901)
			(xy 80.321912 -284.4419) (xy 80.372712 -284.4419)
		)
		(stroke
			(width 0)
			(type solid)
		)
		(fill yes)
		(layer "F.Cu")
		(net "M_A_CPU1_SA_DQ<17>")
	)
	(gr_poly
		(pts
			(xy 80.474312 -283.808932) (xy 80.474312 -283.618432) (xy 80.372712 -283.58211) (xy 80.321912 -283.58211)
			(xy 80.321912 -283.845) (xy 80.372712 -283.845)
		)
		(stroke
			(width 0)
			(type solid)
		)
		(fill yes)
		(layer "F.Cu")
		(net "M_A_CPU1_SA_DQ<17>")
	)
	(gr_poly
		(pts
			(xy 80.474312 -283.212032) (xy 80.474312 -283.021532) (xy 80.372712 -282.98521) (xy 80.321912 -282.98521)
			(xy 80.321912 -283.2481) (xy 80.372712 -283.2481)
		)
		(stroke
			(width 0)
			(type solid)
		)
		(fill yes)
		(layer "F.Cu")
		(net "M_A_CPU1_SA_DQ<17>")
	)
	(gr_poly
		(pts
			(xy 80.474312 -282.615132) (xy 80.474312 -282.424632) (xy 80.372712 -282.38831) (xy 80.321912 -282.38831)
			(xy 80.321912 -282.6512) (xy 80.372712 -282.6512)
		)
		(stroke
			(width 0)
			(type solid)
		)
		(fill yes)
		(layer "F.Cu")
		(net "M_A_CPU1_SA_DQ<17>")
	)
	(gr_poly
		(pts
			(xy 80.4799 -231.983788) (xy 80.515714 -231.94772) (xy 80.329786 -231.761792) (xy 80.293972 -231.79786)
			(xy 80.247744 -231.895396) (xy 80.382364 -232.030016)
		)
		(stroke
			(width 0)
			(type solid)
		)
		(fill yes)
		(layer "F.Cu")
		(net "M_A_CPU1_SB_DQ<12>")
	)
	(gr_poly
		(pts
			(xy 80.483456 -259.313426) (xy 80.447388 -259.211826) (xy 80.256888 -259.211826) (xy 80.220566 -259.313426)
			(xy 80.220566 -259.364226) (xy 80.483456 -259.364226)
		)
		(stroke
			(width 0)
			(type solid)
		)
		(fill yes)
		(layer "F.Cu")
		(net "M_A_CPU1_SA_CS_N<2>")
	)
	(gr_poly
		(pts
			(xy 80.483456 -259.008626) (xy 80.447388 -258.907026) (xy 80.256888 -258.907026) (xy 80.220566 -259.008626)
			(xy 80.220566 -259.059426) (xy 80.483456 -259.059426)
		)
		(stroke
			(width 0)
			(type solid)
		)
		(fill yes)
		(layer "F.Cu")
		(net "M_A_CPU1_SA_CS_N<3>")
	)
	(gr_poly
		(pts
			(xy 80.483456 -258.703826) (xy 80.447388 -258.602226) (xy 80.256888 -258.602226) (xy 80.220566 -258.703826)
			(xy 80.220566 -258.754626) (xy 80.483456 -258.754626)
		)
		(stroke
			(width 0)
			(type solid)
		)
		(fill yes)
		(layer "F.Cu")
		(net "M_A_CPU1_SA_CS_N<1>")
	)
	(gr_poly
		(pts
			(xy 80.483456 -258.399026) (xy 80.447388 -258.297426) (xy 80.256888 -258.297426) (xy 80.220566 -258.399026)
			(xy 80.220566 -258.449826) (xy 80.483456 -258.449826)
		)
		(stroke
			(width 0)
			(type solid)
		)
		(fill yes)
		(layer "F.Cu")
		(net "M_A_CPU1_SA_CA<0>")
	)
	(gr_poly
		(pts
			(xy 80.483456 -258.094226) (xy 80.447388 -257.992626) (xy 80.256888 -257.992626) (xy 80.220566 -258.094226)
			(xy 80.220566 -258.145026) (xy 80.483456 -258.145026)
		)
		(stroke
			(width 0)
			(type solid)
		)
		(fill yes)
		(layer "F.Cu")
		(net "M_A_CPU1_SA_CA<1>")
	)
	(gr_poly
		(pts
			(xy 80.483456 -257.789426) (xy 80.447388 -257.687826) (xy 80.256888 -257.687826) (xy 80.220566 -257.789426)
			(xy 80.220566 -257.840226) (xy 80.483456 -257.840226)
		)
		(stroke
			(width 0)
			(type solid)
		)
		(fill yes)
		(layer "F.Cu")
		(net "M_A_CPU1_SA_CA<2>")
	)
	(gr_poly
		(pts
			(xy 80.483456 -257.484626) (xy 80.447388 -257.383026) (xy 80.256888 -257.383026) (xy 80.220566 -257.484626)
			(xy 80.220566 -257.535426) (xy 80.483456 -257.535426)
		)
		(stroke
			(width 0)
			(type solid)
		)
		(fill yes)
		(layer "F.Cu")
		(net "M_A_CPU1_SA_CA<3>")
	)
	(gr_poly
		(pts
			(xy 80.483456 -257.179826) (xy 80.447388 -257.078226) (xy 80.256888 -257.078226) (xy 80.220566 -257.179826)
			(xy 80.220566 -257.230626) (xy 80.483456 -257.230626)
		)
		(stroke
			(width 0)
			(type solid)
		)
		(fill yes)
		(layer "F.Cu")
		(net "M_A_CPU1_SA_CA<4>")
	)
	(gr_poly
		(pts
			(xy 80.483456 -256.875026) (xy 80.447388 -256.773426) (xy 80.256888 -256.773426) (xy 80.220566 -256.875026)
			(xy 80.220566 -256.925826) (xy 80.483456 -256.925826)
		)
		(stroke
			(width 0)
			(type solid)
		)
		(fill yes)
		(layer "F.Cu")
		(net "M_A_CPU1_SA_CA<5>")
	)
	(gr_poly
		(pts
			(xy 80.483456 -256.570226) (xy 80.447388 -256.468626) (xy 80.256888 -256.468626) (xy 80.220566 -256.570226)
			(xy 80.220566 -256.621026) (xy 80.483456 -256.621026)
		)
		(stroke
			(width 0)
			(type solid)
		)
		(fill yes)
		(layer "F.Cu")
		(net "M_A_CPU1_SA_CA<6>")
	)
	(gr_poly
		(pts
			(xy 80.483456 -256.265426) (xy 80.447388 -256.163826) (xy 80.256888 -256.163826) (xy 80.220566 -256.265426)
			(xy 80.220566 -256.316226) (xy 80.483456 -256.316226)
		)
		(stroke
			(width 0)
			(type solid)
		)
		(fill yes)
		(layer "F.Cu")
		(net "M_A_CPU1_SA_PAR")
	)
	(gr_poly
		(pts
			(xy 80.489298 -231.130348) (xy 80.525112 -231.09428) (xy 80.339184 -230.908352) (xy 80.30337 -230.94442)
			(xy 80.257142 -231.041702) (xy 80.391762 -231.176576)
		)
		(stroke
			(width 0)
			(type solid)
		)
		(fill yes)
		(layer "F.Cu")
		(net "M_A_CPU1_SB_DQ<13>")
	)
	(gr_poly
		(pts
			(xy 80.489806 -274.610576) (xy 80.453992 -274.574508) (xy 80.356456 -274.52828) (xy 80.221836 -274.6629)
			(xy 80.268064 -274.760436) (xy 80.303878 -274.79625)
		)
		(stroke
			(width 0)
			(type solid)
		)
		(fill yes)
		(layer "F.Cu")
		(net "M_A_CPU1_SA_DQ<23>")
	)
	(gr_poly
		(pts
			(xy 80.496664 -269.616682) (xy 80.450436 -269.519146) (xy 80.414622 -269.483332) (xy 80.228694 -269.66926)
			(xy 80.264762 -269.705074) (xy 80.362044 -269.751302)
		)
		(stroke
			(width 0)
			(type solid)
		)
		(fill yes)
		(layer "F.Cu")
		(net "M_A_CPU1_SA_DQ<29>")
	)
	(gr_poly
		(pts
			(xy 80.499204 -275.464016) (xy 80.463136 -275.428202) (xy 80.365854 -275.38172) (xy 80.23098 -275.516594)
			(xy 80.277208 -275.613876) (xy 80.313276 -275.649944)
		)
		(stroke
			(width 0)
			(type solid)
		)
		(fill yes)
		(layer "F.Cu")
		(net "M_A_CPU1_SA_DQ<22>")
	)
	(gr_poly
		(pts
			(xy 80.499204 -229.860856) (xy 80.535272 -229.825042) (xy 80.349344 -229.639114) (xy 80.313276 -229.674928)
			(xy 80.267048 -229.772464) (xy 80.401922 -229.907084)
		)
		(stroke
			(width 0)
			(type solid)
		)
		(fill yes)
		(layer "F.Cu")
		(net "M_A_CPU1_SB_DQ<16>")
	)
	(gr_poly
		(pts
			(xy 80.504538 -280.030936) (xy 80.541876 -279.844246) (xy 80.44942 -279.788874) (xy 80.399636 -279.778968)
			(xy 80.348074 -280.036524) (xy 80.397858 -280.046684)
		)
		(stroke
			(width 0)
			(type solid)
		)
		(fill yes)
		(layer "F.Cu")
		(net "M_A_CPU1_SA_DQ<19>")
	)
	(gr_poly
		(pts
			(xy 80.506316 -270.470376) (xy 80.460088 -270.373094) (xy 80.424274 -270.337026) (xy 80.238346 -270.522954)
			(xy 80.27416 -270.558768) (xy 80.371696 -270.60525)
		)
		(stroke
			(width 0)
			(type solid)
		)
		(fill yes)
		(layer "F.Cu")
		(net "M_A_CPU1_SA_DQ<28>")
	)
	(gr_poly
		(pts
			(xy 80.508348 -229.007416) (xy 80.544416 -228.971602) (xy 80.358488 -228.785674) (xy 80.322674 -228.821488)
			(xy 80.276446 -228.919024) (xy 80.411066 -229.053644)
		)
		(stroke
			(width 0)
			(type solid)
		)
		(fill yes)
		(layer "F.Cu")
		(net "M_A_CPU1_SB_DQ<17>")
	)
	(gr_poly
		(pts
			(xy 80.509364 -234.888532) (xy 80.555592 -234.790996) (xy 80.420972 -234.656376) (xy 80.323436 -234.702604)
			(xy 80.287622 -234.738672) (xy 80.473296 -234.924346)
		)
		(stroke
			(width 0)
			(type solid)
		)
		(fill yes)
		(layer "F.Cu")
		(net "M_A_CPU1_SB_DQ<10>")
	)
	(gr_poly
		(pts
			(xy 80.518508 -234.035092) (xy 80.564736 -233.93781) (xy 80.430116 -233.802936) (xy 80.33258 -233.849164)
			(xy 80.296766 -233.885232) (xy 80.482694 -234.07116)
		)
		(stroke
			(width 0)
			(type solid)
		)
		(fill yes)
		(layer "F.Cu")
		(net "M_A_CPU1_SB_DQ<11>")
	)
	(gr_poly
		(pts
			(xy 80.523588 -280.716736) (xy 80.473804 -280.70683) (xy 80.367124 -280.722324) (xy 80.329786 -280.909268)
			(xy 80.422242 -280.96464) (xy 80.472026 -280.974546)
		)
		(stroke
			(width 0)
			(type solid)
		)
		(fill yes)
		(layer "F.Cu")
		(net "M_A_CPU1_SA_DQ<17>")
	)
	(gr_poly
		(pts
			(xy 80.52435 -224.152714) (xy 80.570578 -224.055432) (xy 80.435958 -223.920558) (xy 80.338422 -223.966786)
			(xy 80.302608 -224.002854) (xy 80.488536 -224.188782)
		)
		(stroke
			(width 0)
			(type solid)
		)
		(fill yes)
		(layer "F.Cu")
		(net "M_A_CPU1_SB_DQ<20>")
	)
	(gr_poly
		(pts
			(xy 80.530192 -261.844282) (xy 80.494124 -261.808468) (xy 80.396842 -261.76224) (xy 80.262222 -261.89686)
			(xy 80.30845 -261.994396) (xy 80.344264 -262.03021)
		)
		(stroke
			(width 0)
			(type solid)
		)
		(fill yes)
		(layer "F.Cu")
		(net "M_A_CPU1_SA_CB<7>")
	)
	(gr_poly
		(pts
			(xy 80.533494 -223.299528) (xy 80.579722 -223.201992) (xy 80.445102 -223.067372) (xy 80.347566 -223.1136)
			(xy 80.311752 -223.149414) (xy 80.49768 -223.335342)
		)
		(stroke
			(width 0)
			(type solid)
		)
		(fill yes)
		(layer "F.Cu")
		(net "M_A_CPU1_SB_DQ<21>")
	)
	(gr_poly
		(pts
			(xy 80.53959 -262.697976) (xy 80.503776 -262.661908) (xy 80.40624 -262.61568) (xy 80.27162 -262.750554)
			(xy 80.317848 -262.847836) (xy 80.353662 -262.883904)
		)
		(stroke
			(width 0)
			(type solid)
		)
		(fill yes)
		(layer "F.Cu")
		(net "M_A_CPU1_SA_CB<6>")
	)
	(gr_poly
		(pts
			(xy 80.544416 -272.37436) (xy 80.508348 -272.338546) (xy 80.411066 -272.292318) (xy 80.276192 -272.426938)
			(xy 80.32242 -272.524474) (xy 80.358488 -272.560288)
		)
		(stroke
			(width 0)
			(type solid)
		)
		(fill yes)
		(layer "F.Cu")
		(net "M_A_CPU1_SA_DQ<27>")
	)
	(gr_poly
		(pts
			(xy 80.54467 -265.280902) (xy 80.508856 -265.245088) (xy 80.41132 -265.198606) (xy 80.2767 -265.33348)
			(xy 80.322928 -265.430762) (xy 80.358742 -265.46683)
		)
		(stroke
			(width 0)
			(type solid)
		)
		(fill yes)
		(layer "F.Cu")
		(net "M_A_CPU1_SA_CB<3>")
	)
	(gr_poly
		(pts
			(xy 80.553814 -273.228054) (xy 80.518 -273.19224) (xy 80.420464 -273.145758) (xy 80.285844 -273.280632)
			(xy 80.332072 -273.377914) (xy 80.367886 -273.413982)
		)
		(stroke
			(width 0)
			(type solid)
		)
		(fill yes)
		(layer "F.Cu")
		(net "M_A_CPU1_SA_DQ<26>")
	)
	(gr_poly
		(pts
			(xy 80.554068 -266.134342) (xy 80.518 -266.098528) (xy 80.420718 -266.0523) (xy 80.285844 -266.18692)
			(xy 80.332326 -266.284456) (xy 80.36814 -266.32027)
		)
		(stroke
			(width 0)
			(type solid)
		)
		(fill yes)
		(layer "F.Cu")
		(net "M_A_CPU1_SA_CB<2>")
	)
	(gr_poly
		(pts
			(xy 80.556354 -231.485186) (xy 80.602582 -231.38765) (xy 80.467962 -231.25303) (xy 80.37068 -231.299258)
			(xy 80.334612 -231.335072) (xy 80.52054 -231.521)
		)
		(stroke
			(width 0)
			(type solid)
		)
		(fill yes)
		(layer "F.Cu")
		(net "M_A_CPU1_SB_DQ<14>")
	)
	(gr_poly
		(pts
			(xy 80.565752 -230.631746) (xy 80.61198 -230.53421) (xy 80.477106 -230.39959) (xy 80.379824 -230.445818)
			(xy 80.343756 -230.481632) (xy 80.529684 -230.66756)
		)
		(stroke
			(width 0)
			(type solid)
		)
		(fill yes)
		(layer "F.Cu")
		(net "M_A_CPU1_SB_DQ<15>")
	)
	(gr_poly
		(pts
			(xy 80.57007 -281.261566) (xy 80.607408 -281.074622) (xy 80.514952 -281.01925) (xy 80.465168 -281.009344)
			(xy 80.413606 -281.267154) (xy 80.46339 -281.27706)
		)
		(stroke
			(width 0)
			(type solid)
		)
		(fill yes)
		(layer "F.Cu")
		(net "M_A_CPU1_SA_DQ<17>")
	)
	(gr_poly
		(pts
			(xy 80.574896 -278.90089) (xy 80.525112 -278.890984) (xy 80.418432 -278.906478) (xy 80.381094 -279.093168)
			(xy 80.47355 -279.148794) (xy 80.523588 -279.1587)
		)
		(stroke
			(width 0)
			(type solid)
		)
		(fill yes)
		(layer "F.Cu")
		(net "M_A_CPU1_SA_DQ<19>")
	)
	(gr_poly
		(pts
			(xy 80.575658 -229.362254) (xy 80.621886 -229.264972) (xy 80.487266 -229.130098) (xy 80.38973 -229.176326)
			(xy 80.353916 -229.212394) (xy 80.539844 -229.398322)
		)
		(stroke
			(width 0)
			(type solid)
		)
		(fill yes)
		(layer "F.Cu")
		(net "M_A_CPU1_SB_DQ<18>")
	)
	(gr_poly
		(pts
			(xy 80.576674 -275.170646) (xy 80.530446 -275.07311) (xy 80.494378 -275.037296) (xy 80.30845 -275.22297)
			(xy 80.344518 -275.259038) (xy 80.4418 -275.305266)
		)
		(stroke
			(width 0)
			(type solid)
		)
		(fill yes)
		(layer "F.Cu")
		(net "M_A_CPU1_SA_DQ<21>")
	)
	(gr_poly
		(pts
			(xy 80.584802 -228.509068) (xy 80.631284 -228.411532) (xy 80.49641 -228.276912) (xy 80.399128 -228.32314)
			(xy 80.36306 -228.358954) (xy 80.548988 -228.544882)
		)
		(stroke
			(width 0)
			(type solid)
		)
		(fill yes)
		(layer "F.Cu")
		(net "M_A_CPU1_SB_DQ<19>")
	)
	(gr_poly
		(pts
			(xy 80.58658 -276.024848) (xy 80.540352 -275.927312) (xy 80.504538 -275.891498) (xy 80.31861 -276.077426)
			(xy 80.354424 -276.11324) (xy 80.45196 -276.159468)
		)
		(stroke
			(width 0)
			(type solid)
		)
		(fill yes)
		(layer "F.Cu")
		(net "M_A_CPU1_SA_DQ<20>")
	)
	(gr_poly
		(pts
			(xy 80.61706 -262.404352) (xy 80.570832 -262.30707) (xy 80.535018 -262.271002) (xy 80.34909 -262.45693)
			(xy 80.384904 -262.492998) (xy 80.48244 -262.539226)
		)
		(stroke
			(width 0)
			(type solid)
		)
		(fill yes)
		(layer "F.Cu")
		(net "M_A_CPU1_SA_CB<5>")
	)
	(gr_poly
		(pts
			(xy 80.621632 -279.44572) (xy 80.65897 -279.258776) (xy 80.56626 -279.203404) (xy 80.516476 -279.193498)
			(xy 80.464914 -279.451308) (xy 80.514952 -279.461214)
		)
		(stroke
			(width 0)
			(type solid)
		)
		(fill yes)
		(layer "F.Cu")
		(net "M_A_CPU1_SA_DQ<19>")
	)
	(gr_poly
		(pts
			(xy 80.625696 -269.272258) (xy 80.589628 -269.236444) (xy 80.492346 -269.190216) (xy 80.357472 -269.324836)
			(xy 80.403954 -269.422372) (xy 80.439768 -269.458186)
		)
		(stroke
			(width 0)
			(type solid)
		)
		(fill yes)
		(layer "F.Cu")
		(net "M_A_CPU1_SA_DQ<29>")
	)
	(gr_poly
		(pts
			(xy 80.626458 -263.258046) (xy 80.58023 -263.160764) (xy 80.544416 -263.124696) (xy 80.358488 -263.310624)
			(xy 80.394302 -263.346438) (xy 80.491838 -263.39292)
		)
		(stroke
			(width 0)
			(type solid)
		)
		(fill yes)
		(layer "F.Cu")
		(net "M_A_CPU1_SA_CB<4>")
	)
	(gr_poly
		(pts
			(xy 80.626712 -289.25266) (xy 80.575912 -289.25266) (xy 80.474312 -289.288982) (xy 80.474312 -289.479482)
			(xy 80.575912 -289.51555) (xy 80.626712 -289.51555)
		)
		(stroke
			(width 0)
			(type solid)
		)
		(fill yes)
		(layer "F.Cu")
		(net "M_A_CPU1_SA_DQ<18>")
	)
	(gr_poly
		(pts
			(xy 80.626712 -288.65576) (xy 80.575912 -288.65576) (xy 80.474312 -288.692082) (xy 80.474312 -288.882582)
			(xy 80.575912 -288.91865) (xy 80.626712 -288.91865)
		)
		(stroke
			(width 0)
			(type solid)
		)
		(fill yes)
		(layer "F.Cu")
		(net "M_A_CPU1_SA_DQ<18>")
	)
	(gr_poly
		(pts
			(xy 80.626712 -288.05886) (xy 80.575912 -288.05886) (xy 80.474312 -288.095182) (xy 80.474312 -288.285682)
			(xy 80.575912 -288.32175) (xy 80.626712 -288.32175)
		)
		(stroke
			(width 0)
			(type solid)
		)
		(fill yes)
		(layer "F.Cu")
		(net "M_A_CPU1_SA_DQ<18>")
	)
	(gr_poly
		(pts
			(xy 80.626712 -287.46196) (xy 80.575912 -287.46196) (xy 80.474312 -287.498282) (xy 80.474312 -287.688782)
			(xy 80.575912 -287.72485) (xy 80.626712 -287.72485)
		)
		(stroke
			(width 0)
			(type solid)
		)
		(fill yes)
		(layer "F.Cu")
		(net "M_A_CPU1_SA_DQ<18>")
	)
	(gr_poly
		(pts
			(xy 80.626712 -286.86506) (xy 80.575912 -286.86506) (xy 80.474312 -286.901382) (xy 80.474312 -287.091882)
			(xy 80.575912 -287.12795) (xy 80.626712 -287.12795)
		)
		(stroke
			(width 0)
			(type solid)
		)
		(fill yes)
		(layer "F.Cu")
		(net "M_A_CPU1_SA_DQ<18>")
	)
	(gr_poly
		(pts
			(xy 80.626712 -286.26816) (xy 80.575912 -286.26816) (xy 80.474312 -286.304482) (xy 80.474312 -286.494982)
			(xy 80.575912 -286.53105) (xy 80.626712 -286.53105)
		)
		(stroke
			(width 0)
			(type solid)
		)
		(fill yes)
		(layer "F.Cu")
		(net "M_A_CPU1_SA_DQ<18>")
	)
	(gr_poly
		(pts
			(xy 80.626712 -285.67126) (xy 80.575912 -285.67126) (xy 80.474312 -285.707582) (xy 80.474312 -285.898082)
			(xy 80.575912 -285.93415) (xy 80.626712 -285.93415)
		)
		(stroke
			(width 0)
			(type solid)
		)
		(fill yes)
		(layer "F.Cu")
		(net "M_A_CPU1_SA_DQ<18>")
	)
	(gr_poly
		(pts
			(xy 80.626712 -285.07436) (xy 80.575912 -285.07436) (xy 80.474312 -285.110682) (xy 80.474312 -285.301182)
			(xy 80.575912 -285.33725) (xy 80.626712 -285.33725)
		)
		(stroke
			(width 0)
			(type solid)
		)
		(fill yes)
		(layer "F.Cu")
		(net "M_A_CPU1_SA_DQ<18>")
	)
	(gr_poly
		(pts
			(xy 80.626712 -284.47746) (xy 80.575912 -284.47746) (xy 80.474312 -284.513782) (xy 80.474312 -284.704282)
			(xy 80.575912 -284.74035) (xy 80.626712 -284.74035)
		)
		(stroke
			(width 0)
			(type solid)
		)
		(fill yes)
		(layer "F.Cu")
		(net "M_A_CPU1_SA_DQ<18>")
	)
	(gr_poly
		(pts
			(xy 80.626712 -283.88056) (xy 80.575912 -283.88056) (xy 80.474312 -283.916882) (xy 80.474312 -284.107382)
			(xy 80.575912 -284.14345) (xy 80.626712 -284.14345)
		)
		(stroke
			(width 0)
			(type solid)
		)
		(fill yes)
		(layer "F.Cu")
		(net "M_A_CPU1_SA_DQ<18>")
	)
	(gr_poly
		(pts
			(xy 80.626712 -283.28366) (xy 80.575912 -283.28366) (xy 80.474312 -283.319982) (xy 80.474312 -283.510482)
			(xy 80.575912 -283.54655) (xy 80.626712 -283.54655)
		)
		(stroke
			(width 0)
			(type solid)
		)
		(fill yes)
		(layer "F.Cu")
		(net "M_A_CPU1_SA_DQ<18>")
	)
	(gr_poly
		(pts
			(xy 80.626712 -282.68676) (xy 80.575912 -282.68676) (xy 80.474312 -282.723082) (xy 80.474312 -282.913582)
			(xy 80.575912 -282.94965) (xy 80.626712 -282.94965)
		)
		(stroke
			(width 0)
			(type solid)
		)
		(fill yes)
		(layer "F.Cu")
		(net "M_A_CPU1_SA_DQ<18>")
	)
	(gr_poly
		(pts
			(xy 80.626712 -282.08986) (xy 80.575912 -282.08986) (xy 80.474312 -282.126182) (xy 80.474312 -282.316682)
			(xy 80.575912 -282.35275) (xy 80.626712 -282.35275)
		)
		(stroke
			(width 0)
			(type solid)
		)
		(fill yes)
		(layer "F.Cu")
		(net "M_A_CPU1_SA_DQ<18>")
	)
	(gr_poly
		(pts
			(xy 80.631284 -272.934684) (xy 80.585056 -272.837402) (xy 80.549242 -272.801334) (xy 80.363314 -272.987262)
			(xy 80.399128 -273.023076) (xy 80.496664 -273.069304)
		)
		(stroke
			(width 0)
			(type solid)
		)
		(fill yes)
		(layer "F.Cu")
		(net "M_A_CPU1_SA_DQ<25>")
	)
	(gr_poly
		(pts
			(xy 80.631538 -265.840972) (xy 80.58531 -265.743436) (xy 80.549242 -265.707622) (xy 80.363314 -265.89355)
			(xy 80.399382 -265.929364) (xy 80.496664 -265.975592)
		)
		(stroke
			(width 0)
			(type solid)
		)
		(fill yes)
		(layer "F.Cu")
		(net "M_A_CPU1_SA_CB<1>")
	)
	(gr_poly
		(pts
			(xy 80.635348 -270.125952) (xy 80.59928 -270.090138) (xy 80.501998 -270.04391) (xy 80.367124 -270.17853)
			(xy 80.413352 -270.276066) (xy 80.44942 -270.31188)
		)
		(stroke
			(width 0)
			(type solid)
		)
		(fill yes)
		(layer "F.Cu")
		(net "M_A_CPU1_SA_DQ<28>")
	)
	(gr_poly
		(pts
			(xy 80.640682 -280.13152) (xy 80.590898 -280.12136) (xy 80.484218 -280.137108) (xy 80.44688 -280.323798)
			(xy 80.539336 -280.37917) (xy 80.58912 -280.389076)
		)
		(stroke
			(width 0)
			(type solid)
		)
		(fill yes)
		(layer "F.Cu")
		(net "M_A_CPU1_SA_DQ<17>")
	)
	(gr_poly
		(pts
			(xy 80.640682 -273.788124) (xy 80.594454 -273.690588) (xy 80.558386 -273.654774) (xy 80.372458 -273.840702)
			(xy 80.408526 -273.876516) (xy 80.505808 -273.922744)
		)
		(stroke
			(width 0)
			(type solid)
		)
		(fill yes)
		(layer "F.Cu")
		(net "M_A_CPU1_SA_DQ<24>")
	)
	(gr_poly
		(pts
			(xy 80.640682 -266.694412) (xy 80.594454 -266.596876) (xy 80.55864 -266.561062) (xy 80.372712 -266.74699)
			(xy 80.40878 -266.782804) (xy 80.506062 -266.829032)
		)
		(stroke
			(width 0)
			(type solid)
		)
		(fill yes)
		(layer "F.Cu")
		(net "M_A_CPU1_SA_CB<0>")
	)
	(gr_poly
		(pts
			(xy 80.648556 -235.171488) (xy 80.68437 -235.13542) (xy 80.498442 -234.949492) (xy 80.462628 -234.98556)
			(xy 80.4164 -235.082842) (xy 80.55102 -235.217716)
		)
		(stroke
			(width 0)
			(type solid)
		)
		(fill yes)
		(layer "F.Cu")
		(net "M_A_CPU1_SB_DQ<10>")
	)
	(gr_poly
		(pts
			(xy 80.6577 -234.318048) (xy 80.693768 -234.282234) (xy 80.50784 -234.096306) (xy 80.471772 -234.13212)
			(xy 80.425544 -234.229656) (xy 80.560418 -234.364276)
		)
		(stroke
			(width 0)
			(type solid)
		)
		(fill yes)
		(layer "F.Cu")
		(net "M_A_CPU1_SB_DQ<11>")
	)
	(gr_poly
		(pts
			(xy 80.672686 -223.58223) (xy 80.708754 -223.546416) (xy 80.522826 -223.360488) (xy 80.487012 -223.396302)
			(xy 80.44053 -223.493838) (xy 80.575404 -223.628458)
		)
		(stroke
			(width 0)
			(type solid)
		)
		(fill yes)
		(layer "F.Cu")
		(net "M_A_CPU1_SB_DQ<21>")
	)
	(gr_poly
		(pts
			(xy 80.687164 -280.67635) (xy 80.724502 -280.489406) (xy 80.632046 -280.434034) (xy 80.582262 -280.424128)
			(xy 80.5307 -280.681938) (xy 80.580484 -280.691844)
		)
		(stroke
			(width 0)
			(type solid)
		)
		(fill yes)
		(layer "F.Cu")
		(net "M_A_CPU1_SA_DQ<17>")
	)
	(gr_poly
		(pts
			(xy 80.695546 -231.767888) (xy 80.731614 -231.732074) (xy 80.545686 -231.546146) (xy 80.509872 -231.58196)
			(xy 80.46339 -231.679496) (xy 80.598264 -231.814116)
		)
		(stroke
			(width 0)
			(type solid)
		)
		(fill yes)
		(layer "F.Cu")
		(net "M_A_CPU1_SB_DQ<14>")
	)
	(gr_poly
		(pts
			(xy 80.703166 -268.978888) (xy 80.656938 -268.881352) (xy 80.62087 -268.845538) (xy 80.434942 -269.031466)
			(xy 80.47101 -269.06728) (xy 80.568292 -269.113508)
		)
		(stroke
			(width 0)
			(type solid)
		)
		(fill yes)
		(layer "F.Cu")
		(net "M_A_CPU1_SA_DQ<31>")
	)
	(gr_poly
		(pts
			(xy 80.704944 -230.914702) (xy 80.740758 -230.878634) (xy 80.55483 -230.692706) (xy 80.519016 -230.728774)
			(xy 80.472788 -230.826056) (xy 80.607408 -230.96093)
		)
		(stroke
			(width 0)
			(type solid)
		)
		(fill yes)
		(layer "F.Cu")
		(net "M_A_CPU1_SB_DQ<15>")
	)
	(gr_poly
		(pts
			(xy 80.705452 -274.826222) (xy 80.669638 -274.790154) (xy 80.572102 -274.743926) (xy 80.437482 -274.8788)
			(xy 80.48371 -274.976082) (xy 80.519524 -275.01215)
		)
		(stroke
			(width 0)
			(type solid)
		)
		(fill yes)
		(layer "F.Cu")
		(net "M_A_CPU1_SA_DQ<21>")
	)
	(gr_poly
		(pts
			(xy 80.712818 -269.832836) (xy 80.66659 -269.7353) (xy 80.630522 -269.699486) (xy 80.444848 -269.88516)
			(xy 80.480662 -269.921228) (xy 80.578198 -269.967456)
		)
		(stroke
			(width 0)
			(type solid)
		)
		(fill yes)
		(layer "F.Cu")
		(net "M_A_CPU1_SA_DQ<30>")
	)
	(gr_poly
		(pts
			(xy 80.71485 -229.64521) (xy 80.750918 -229.609396) (xy 80.56499 -229.423468) (xy 80.528922 -229.459282)
			(xy 80.482694 -229.556818) (xy 80.617568 -229.691438)
		)
		(stroke
			(width 0)
			(type solid)
		)
		(fill yes)
		(layer "F.Cu")
		(net "M_A_CPU1_SB_DQ<18>")
	)
	(gr_poly
		(pts
			(xy 80.715612 -275.680424) (xy 80.679544 -275.64461) (xy 80.582262 -275.598382) (xy 80.447388 -275.733002)
			(xy 80.493616 -275.830284) (xy 80.529684 -275.866352)
		)
		(stroke
			(width 0)
			(type solid)
		)
		(fill yes)
		(layer "F.Cu")
		(net "M_A_CPU1_SA_DQ<20>")
	)
	(gr_poly
		(pts
			(xy 80.715866 -235.526326) (xy 80.762094 -235.42879) (xy 80.62722 -235.29417) (xy 80.529938 -235.340398)
			(xy 80.49387 -235.376212) (xy 80.679798 -235.56214)
		)
		(stroke
			(width 0)
			(type solid)
		)
		(fill yes)
		(layer "F.Cu")
		(net "M_A_CPU1_SB_DQ<8>")
	)
	(gr_poly
		(pts
			(xy 80.723994 -228.79177) (xy 80.760062 -228.755956) (xy 80.574134 -228.570028) (xy 80.53832 -228.605842)
			(xy 80.492092 -228.703378) (xy 80.626712 -228.837998)
		)
		(stroke
			(width 0)
			(type solid)
		)
		(fill yes)
		(layer "F.Cu")
		(net "M_A_CPU1_SB_DQ<19>")
	)
	(gr_poly
		(pts
			(xy 80.72501 -234.672886) (xy 80.771238 -234.57535) (xy 80.636618 -234.44073) (xy 80.539082 -234.486958)
			(xy 80.503268 -234.523026) (xy 80.688942 -234.7087)
		)
		(stroke
			(width 0)
			(type solid)
		)
		(fill yes)
		(layer "F.Cu")
		(net "M_A_CPU1_SB_DQ<9>")
	)
	(gr_poly
		(pts
			(xy 80.738472 -278.86025) (xy 80.77581 -278.67356) (xy 80.683354 -278.618188) (xy 80.63357 -278.608282)
			(xy 80.582008 -278.866092) (xy 80.631792 -278.875998)
		)
		(stroke
			(width 0)
			(type solid)
		)
		(fill yes)
		(layer "F.Cu")
		(net "M_A_CPU1_SA_DQ<19>")
	)
	(gr_poly
		(pts
			(xy 80.739996 -223.937068) (xy 80.786224 -223.839786) (xy 80.651604 -223.704912) (xy 80.554068 -223.75114)
			(xy 80.518254 -223.787208) (xy 80.704182 -223.973136)
		)
		(stroke
			(width 0)
			(type solid)
		)
		(fill yes)
		(layer "F.Cu")
		(net "M_A_CPU1_SB_DQ<22>")
	)
	(gr_poly
		(pts
			(xy 80.745838 -262.060182) (xy 80.710024 -262.024114) (xy 80.612488 -261.977886) (xy 80.477868 -262.112506)
			(xy 80.524096 -262.210042) (xy 80.560164 -262.245856)
		)
		(stroke
			(width 0)
			(type solid)
		)
		(fill yes)
		(layer "F.Cu")
		(net "M_A_CPU1_SA_CB<5>")
	)
	(gr_poly
		(pts
			(xy 80.74914 -249.270266) (xy 80.713072 -249.168666) (xy 80.522572 -249.168666) (xy 80.48625 -249.270266)
			(xy 80.48625 -249.321066) (xy 80.74914 -249.321066)
		)
		(stroke
			(width 0)
			(type solid)
		)
		(fill yes)
		(layer "F.Cu")
		(net "M_A_CPU1_SB_CA<0>")
	)
	(gr_poly
		(pts
			(xy 80.74914 -248.965212) (xy 80.713072 -248.863612) (xy 80.522572 -248.863612) (xy 80.48625 -248.965212)
			(xy 80.48625 -249.016012) (xy 80.74914 -249.016012)
		)
		(stroke
			(width 0)
			(type solid)
		)
		(fill yes)
		(layer "F.Cu")
		(net "M_A_CPU1_SB_CA<1>")
	)
	(gr_poly
		(pts
			(xy 80.74914 -248.660412) (xy 80.713072 -248.558812) (xy 80.522572 -248.558812) (xy 80.48625 -248.660412)
			(xy 80.48625 -248.711212) (xy 80.74914 -248.711212)
		)
		(stroke
			(width 0)
			(type solid)
		)
		(fill yes)
		(layer "F.Cu")
		(net "M_A_CPU1_SB_CA<2>")
	)
	(gr_poly
		(pts
			(xy 80.74914 -248.355612) (xy 80.713072 -248.254012) (xy 80.522572 -248.254012) (xy 80.48625 -248.355612)
			(xy 80.48625 -248.406412) (xy 80.74914 -248.406412)
		)
		(stroke
			(width 0)
			(type solid)
		)
		(fill yes)
		(layer "F.Cu")
		(net "M_A_CPU1_SB_CA<3>")
	)
	(gr_poly
		(pts
			(xy 80.74914 -248.050812) (xy 80.713072 -247.949212) (xy 80.522572 -247.949212) (xy 80.48625 -248.050812)
			(xy 80.48625 -248.101612) (xy 80.74914 -248.101612)
		)
		(stroke
			(width 0)
			(type solid)
		)
		(fill yes)
		(layer "F.Cu")
		(net "M_A_CPU1_SB_CA<4>")
	)
	(gr_poly
		(pts
			(xy 80.74914 -247.746012) (xy 80.713072 -247.644412) (xy 80.522572 -247.644412) (xy 80.48625 -247.746012)
			(xy 80.48625 -247.796812) (xy 80.74914 -247.796812)
		)
		(stroke
			(width 0)
			(type solid)
		)
		(fill yes)
		(layer "F.Cu")
		(net "M_A_CPU1_SB_CA<5>")
	)
	(gr_poly
		(pts
			(xy 80.74914 -247.441212) (xy 80.713072 -247.339612) (xy 80.522572 -247.339612) (xy 80.48625 -247.441212)
			(xy 80.48625 -247.492012) (xy 80.74914 -247.492012)
		)
		(stroke
			(width 0)
			(type solid)
		)
		(fill yes)
		(layer "F.Cu")
		(net "M_A_CPU1_SB_CA<6>")
	)
	(gr_poly
		(pts
			(xy 80.74914 -247.136412) (xy 80.713072 -247.034812) (xy 80.522572 -247.034812) (xy 80.48625 -247.136412)
			(xy 80.48625 -247.187212) (xy 80.74914 -247.187212)
		)
		(stroke
			(width 0)
			(type solid)
		)
		(fill yes)
		(layer "F.Cu")
		(net "M_A_CPU1_SB_PAR")
	)
	(gr_poly
		(pts
			(xy 80.74914 -246.831612) (xy 80.713072 -246.730012) (xy 80.522572 -246.730012) (xy 80.48625 -246.831612)
			(xy 80.48625 -246.882412) (xy 80.74914 -246.882412)
		)
		(stroke
			(width 0)
			(type solid)
		)
		(fill yes)
		(layer "F.Cu")
		(net "M_A_CPU1_SB_CS_N<2>")
	)
	(gr_poly
		(pts
			(xy 80.74914 -246.526812) (xy 80.713072 -246.425212) (xy 80.522572 -246.425212) (xy 80.48625 -246.526812)
			(xy 80.48625 -246.577612) (xy 80.74914 -246.577612)
		)
		(stroke
			(width 0)
			(type solid)
		)
		(fill yes)
		(layer "F.Cu")
		(net "M_A_CPU1_SB_CS_N<0>")
	)
	(gr_poly
		(pts
			(xy 80.74914 -223.083882) (xy 80.795368 -222.986346) (xy 80.660748 -222.851726) (xy 80.563212 -222.897954)
			(xy 80.527398 -222.933768) (xy 80.713326 -223.119696)
		)
		(stroke
			(width 0)
			(type solid)
		)
		(fill yes)
		(layer "F.Cu")
		(net "M_A_CPU1_SB_DQ<23>")
	)
	(gr_poly
		(pts
			(xy 80.75549 -262.913622) (xy 80.719422 -262.877808) (xy 80.62214 -262.83158) (xy 80.487266 -262.9662)
			(xy 80.533494 -263.063736) (xy 80.569562 -263.09955)
		)
		(stroke
			(width 0)
			(type solid)
		)
		(fill yes)
		(layer "F.Cu")
		(net "M_A_CPU1_SA_CB<4>")
	)
	(gr_poly
		(pts
			(xy 80.757522 -279.54605) (xy 80.707738 -279.536144) (xy 80.601058 -279.551638) (xy 80.56372 -279.738582)
			(xy 80.65643 -279.793954) (xy 80.706214 -279.80386)
		)
		(stroke
			(width 0)
			(type solid)
		)
		(fill yes)
		(layer "F.Cu")
		(net "M_A_CPU1_SA_DQ<17>")
	)
	(gr_poly
		(pts
			(xy 80.760316 -272.59026) (xy 80.724248 -272.554446) (xy 80.626966 -272.508218) (xy 80.492092 -272.642838)
			(xy 80.53832 -272.740374) (xy 80.574388 -272.776188)
		)
		(stroke
			(width 0)
			(type solid)
		)
		(fill yes)
		(layer "F.Cu")
		(net "M_A_CPU1_SA_DQ<25>")
	)
	(gr_poly
		(pts
			(xy 80.760316 -265.496548) (xy 80.724502 -265.460734) (xy 80.626966 -265.414252) (xy 80.492346 -265.549126)
			(xy 80.538574 -265.646408) (xy 80.574388 -265.682476)
		)
		(stroke
			(width 0)
			(type solid)
		)
		(fill yes)
		(layer "F.Cu")
		(net "M_A_CPU1_SA_CB<1>")
	)
	(gr_poly
		(pts
			(xy 80.762856 -232.12298) (xy 80.809084 -232.025444) (xy 80.67421 -231.890824) (xy 80.576928 -231.937052)
			(xy 80.54086 -231.972866) (xy 80.726788 -232.158794)
		)
		(stroke
			(width 0)
			(type solid)
		)
		(fill yes)
		(layer "F.Cu")
		(net "M_A_CPU1_SB_DQ<12>")
	)
	(gr_poly
		(pts
			(xy 80.76946 -273.4437) (xy 80.733646 -273.407886) (xy 80.63611 -273.361404) (xy 80.50149 -273.496278)
			(xy 80.547718 -273.59356) (xy 80.583532 -273.629628)
		)
		(stroke
			(width 0)
			(type solid)
		)
		(fill yes)
		(layer "F.Cu")
		(net "M_A_CPU1_SA_DQ<24>")
	)
	(gr_poly
		(pts
			(xy 80.769714 -266.349988) (xy 80.733646 -266.314174) (xy 80.636364 -266.267946) (xy 80.50149 -266.402566)
			(xy 80.547972 -266.500102) (xy 80.583786 -266.535916)
		)
		(stroke
			(width 0)
			(type solid)
		)
		(fill yes)
		(layer "F.Cu")
		(net "M_A_CPU1_SA_CB<0>")
	)
	(gr_poly
		(pts
			(xy 80.772 -231.26954) (xy 80.818228 -231.172004) (xy 80.683608 -231.037384) (xy 80.586326 -231.083612)
			(xy 80.550258 -231.119426) (xy 80.736186 -231.305354)
		)
		(stroke
			(width 0)
			(type solid)
		)
		(fill yes)
		(layer "F.Cu")
		(net "M_A_CPU1_SB_DQ<13>")
	)
	(gr_poly
		(pts
			(xy 80.776064 -225.712782) (xy 80.725264 -225.712782) (xy 80.623664 -225.749104) (xy 80.623664 -225.939604)
			(xy 80.725264 -225.975926) (xy 80.776064 -225.975926)
		)
		(stroke
			(width 0)
			(type solid)
		)
		(fill yes)
		(layer "F.Cu")
		(net "M_A_CPU1_SB_DQ<20>")
	)
	(gr_poly
		(pts
			(xy 80.776064 -225.115882) (xy 80.725264 -225.115882) (xy 80.623664 -225.152204) (xy 80.623664 -225.342704)
			(xy 80.725264 -225.379026) (xy 80.776064 -225.379026)
		)
		(stroke
			(width 0)
			(type solid)
		)
		(fill yes)
		(layer "F.Cu")
		(net "M_A_CPU1_SB_DQ<20>")
	)
	(gr_poly
		(pts
			(xy 80.779112 -289.181032) (xy 80.779112 -288.990532) (xy 80.677512 -288.95421) (xy 80.626712 -288.95421)
			(xy 80.626712 -289.2171) (xy 80.677512 -289.2171)
		)
		(stroke
			(width 0)
			(type solid)
		)
		(fill yes)
		(layer "F.Cu")
		(net "M_A_CPU1_SA_DQ<18>")
	)
	(gr_poly
		(pts
			(xy 80.779112 -288.584132) (xy 80.779112 -288.393632) (xy 80.677512 -288.35731) (xy 80.626712 -288.35731)
			(xy 80.626712 -288.6202) (xy 80.677512 -288.6202)
		)
		(stroke
			(width 0)
			(type solid)
		)
		(fill yes)
		(layer "F.Cu")
		(net "M_A_CPU1_SA_DQ<18>")
	)
	(gr_poly
		(pts
			(xy 80.779112 -287.987232) (xy 80.779112 -287.796732) (xy 80.677512 -287.76041) (xy 80.626712 -287.76041)
			(xy 80.626712 -288.0233) (xy 80.677512 -288.0233)
		)
		(stroke
			(width 0)
			(type solid)
		)
		(fill yes)
		(layer "F.Cu")
		(net "M_A_CPU1_SA_DQ<18>")
	)
	(gr_poly
		(pts
			(xy 80.779112 -287.390332) (xy 80.779112 -287.199832) (xy 80.677512 -287.16351) (xy 80.626712 -287.16351)
			(xy 80.626712 -287.4264) (xy 80.677512 -287.4264)
		)
		(stroke
			(width 0)
			(type solid)
		)
		(fill yes)
		(layer "F.Cu")
		(net "M_A_CPU1_SA_DQ<18>")
	)
	(gr_poly
		(pts
			(xy 80.779112 -286.793432) (xy 80.779112 -286.602932) (xy 80.677512 -286.56661) (xy 80.626712 -286.56661)
			(xy 80.626712 -286.8295) (xy 80.677512 -286.8295)
		)
		(stroke
			(width 0)
			(type solid)
		)
		(fill yes)
		(layer "F.Cu")
		(net "M_A_CPU1_SA_DQ<18>")
	)
	(gr_poly
		(pts
			(xy 80.779112 -286.196532) (xy 80.779112 -286.006032) (xy 80.677512 -285.96971) (xy 80.626712 -285.96971)
			(xy 80.626712 -286.2326) (xy 80.677512 -286.2326)
		)
		(stroke
			(width 0)
			(type solid)
		)
		(fill yes)
		(layer "F.Cu")
		(net "M_A_CPU1_SA_DQ<18>")
	)
	(gr_poly
		(pts
			(xy 80.779112 -285.599632) (xy 80.779112 -285.409132) (xy 80.677512 -285.37281) (xy 80.626712 -285.37281)
			(xy 80.626712 -285.6357) (xy 80.677512 -285.6357)
		)
		(stroke
			(width 0)
			(type solid)
		)
		(fill yes)
		(layer "F.Cu")
		(net "M_A_CPU1_SA_DQ<18>")
	)
	(gr_poly
		(pts
			(xy 80.779112 -285.002732) (xy 80.779112 -284.812232) (xy 80.677512 -284.77591) (xy 80.626712 -284.77591)
			(xy 80.626712 -285.0388) (xy 80.677512 -285.0388)
		)
		(stroke
			(width 0)
			(type solid)
		)
		(fill yes)
		(layer "F.Cu")
		(net "M_A_CPU1_SA_DQ<18>")
	)
	(gr_poly
		(pts
			(xy 80.779112 -284.405832) (xy 80.779112 -284.215332) (xy 80.677512 -284.17901) (xy 80.626712 -284.17901)
			(xy 80.626712 -284.4419) (xy 80.677512 -284.4419)
		)
		(stroke
			(width 0)
			(type solid)
		)
		(fill yes)
		(layer "F.Cu")
		(net "M_A_CPU1_SA_DQ<18>")
	)
	(gr_poly
		(pts
			(xy 80.779112 -283.808932) (xy 80.779112 -283.618432) (xy 80.677512 -283.58211) (xy 80.626712 -283.58211)
			(xy 80.626712 -283.845) (xy 80.677512 -283.845)
		)
		(stroke
			(width 0)
			(type solid)
		)
		(fill yes)
		(layer "F.Cu")
		(net "M_A_CPU1_SA_DQ<18>")
	)
	(gr_poly
		(pts
			(xy 80.779112 -283.212032) (xy 80.779112 -283.021532) (xy 80.677512 -282.98521) (xy 80.626712 -282.98521)
			(xy 80.626712 -283.2481) (xy 80.677512 -283.2481)
		)
		(stroke
			(width 0)
			(type solid)
		)
		(fill yes)
		(layer "F.Cu")
		(net "M_A_CPU1_SA_DQ<18>")
	)
	(gr_poly
		(pts
			(xy 80.779112 -282.615132) (xy 80.779112 -282.424632) (xy 80.677512 -282.38831) (xy 80.626712 -282.38831)
			(xy 80.626712 -282.6512) (xy 80.677512 -282.6512)
		)
		(stroke
			(width 0)
			(type solid)
		)
		(fill yes)
		(layer "F.Cu")
		(net "M_A_CPU1_SA_DQ<18>")
	)
	(gr_poly
		(pts
			(xy 80.781906 -259.415026) (xy 80.781906 -259.364226) (xy 80.519016 -259.364226) (xy 80.519016 -259.415026)
			(xy 80.555084 -259.516626) (xy 80.745584 -259.516626)
		)
		(stroke
			(width 0)
			(type solid)
		)
		(fill yes)
		(layer "F.Cu")
		(net "M_A_CPU1_SA_CS_N<2>")
	)
	(gr_poly
		(pts
			(xy 80.781906 -259.110226) (xy 80.781906 -259.059426) (xy 80.519016 -259.059426) (xy 80.519016 -259.110226)
			(xy 80.555084 -259.211826) (xy 80.745584 -259.211826)
		)
		(stroke
			(width 0)
			(type solid)
		)
		(fill yes)
		(layer "F.Cu")
		(net "M_A_CPU1_SA_CS_N<3>")
	)
	(gr_poly
		(pts
			(xy 80.781906 -258.805426) (xy 80.781906 -258.754626) (xy 80.519016 -258.754626) (xy 80.519016 -258.805426)
			(xy 80.555084 -258.907026) (xy 80.745584 -258.907026)
		)
		(stroke
			(width 0)
			(type solid)
		)
		(fill yes)
		(layer "F.Cu")
		(net "M_A_CPU1_SA_CS_N<1>")
	)
	(gr_poly
		(pts
			(xy 80.781906 -258.500626) (xy 80.781906 -258.449826) (xy 80.519016 -258.449826) (xy 80.519016 -258.500626)
			(xy 80.555084 -258.602226) (xy 80.745584 -258.602226)
		)
		(stroke
			(width 0)
			(type solid)
		)
		(fill yes)
		(layer "F.Cu")
		(net "M_A_CPU1_SA_CA<0>")
	)
	(gr_poly
		(pts
			(xy 80.781906 -258.195826) (xy 80.781906 -258.145026) (xy 80.519016 -258.145026) (xy 80.519016 -258.195826)
			(xy 80.555084 -258.297426) (xy 80.745584 -258.297426)
		)
		(stroke
			(width 0)
			(type solid)
		)
		(fill yes)
		(layer "F.Cu")
		(net "M_A_CPU1_SA_CA<1>")
	)
	(gr_poly
		(pts
			(xy 80.781906 -257.891026) (xy 80.781906 -257.840226) (xy 80.519016 -257.840226) (xy 80.519016 -257.891026)
			(xy 80.555084 -257.992626) (xy 80.745584 -257.992626)
		)
		(stroke
			(width 0)
			(type solid)
		)
		(fill yes)
		(layer "F.Cu")
		(net "M_A_CPU1_SA_CA<2>")
	)
	(gr_poly
		(pts
			(xy 80.781906 -257.586226) (xy 80.781906 -257.535426) (xy 80.519016 -257.535426) (xy 80.519016 -257.586226)
			(xy 80.555084 -257.687826) (xy 80.745584 -257.687826)
		)
		(stroke
			(width 0)
			(type solid)
		)
		(fill yes)
		(layer "F.Cu")
		(net "M_A_CPU1_SA_CA<3>")
	)
	(gr_poly
		(pts
			(xy 80.781906 -257.281426) (xy 80.781906 -257.230626) (xy 80.519016 -257.230626) (xy 80.519016 -257.281426)
			(xy 80.555084 -257.383026) (xy 80.745584 -257.383026)
		)
		(stroke
			(width 0)
			(type solid)
		)
		(fill yes)
		(layer "F.Cu")
		(net "M_A_CPU1_SA_CA<4>")
	)
	(gr_poly
		(pts
			(xy 80.781906 -256.976626) (xy 80.781906 -256.925826) (xy 80.519016 -256.925826) (xy 80.519016 -256.976626)
			(xy 80.555084 -257.078226) (xy 80.745584 -257.078226)
		)
		(stroke
			(width 0)
			(type solid)
		)
		(fill yes)
		(layer "F.Cu")
		(net "M_A_CPU1_SA_CA<5>")
	)
	(gr_poly
		(pts
			(xy 80.781906 -256.671826) (xy 80.781906 -256.621026) (xy 80.519016 -256.621026) (xy 80.519016 -256.671826)
			(xy 80.555084 -256.773426) (xy 80.745584 -256.773426)
		)
		(stroke
			(width 0)
			(type solid)
		)
		(fill yes)
		(layer "F.Cu")
		(net "M_A_CPU1_SA_CA<6>")
	)
	(gr_poly
		(pts
			(xy 80.781906 -256.367026) (xy 80.781906 -256.316226) (xy 80.519016 -256.316226) (xy 80.519016 -256.367026)
			(xy 80.555084 -256.468626) (xy 80.745584 -256.468626)
		)
		(stroke
			(width 0)
			(type solid)
		)
		(fill yes)
		(layer "F.Cu")
		(net "M_A_CPU1_SA_PAR")
	)
	(gr_poly
		(pts
			(xy 80.78216 -230.000048) (xy 80.828388 -229.902512) (xy 80.693768 -229.767892) (xy 80.596232 -229.81412)
			(xy 80.560418 -229.850188) (xy 80.746092 -230.035862)
		)
		(stroke
			(width 0)
			(type solid)
		)
		(fill yes)
		(layer "F.Cu")
		(net "M_A_CPU1_SB_DQ<16>")
	)
	(gr_poly
		(pts
			(xy 80.782922 -274.532852) (xy 80.736694 -274.435316) (xy 80.70088 -274.399502) (xy 80.514952 -274.58543)
			(xy 80.550766 -274.621244) (xy 80.648302 -274.667472)
		)
		(stroke
			(width 0)
			(type solid)
		)
		(fill yes)
		(layer "F.Cu")
		(net "M_A_CPU1_SA_DQ<23>")
	)
	(gr_poly
		(pts
			(xy 80.791304 -229.146608) (xy 80.837532 -229.049326) (xy 80.702912 -228.914452) (xy 80.605376 -228.96068)
			(xy 80.569562 -228.996748) (xy 80.75549 -229.182676)
		)
		(stroke
			(width 0)
			(type solid)
		)
		(fill yes)
		(layer "F.Cu")
		(net "M_A_CPU1_SB_DQ<17>")
	)
	(gr_poly
		(pts
			(xy 80.79232 -275.386292) (xy 80.746092 -275.28901) (xy 80.710278 -275.252942) (xy 80.52435 -275.43887)
			(xy 80.560164 -275.474684) (xy 80.6577 -275.521166)
		)
		(stroke
			(width 0)
			(type solid)
		)
		(fill yes)
		(layer "F.Cu")
		(net "M_A_CPU1_SA_DQ<22>")
	)
	(gr_poly
		(pts
			(xy 80.804258 -280.09088) (xy 80.841596 -279.90419) (xy 80.748886 -279.848818) (xy 80.699102 -279.838658)
			(xy 80.64754 -280.096468) (xy 80.697324 -280.106374)
		)
		(stroke
			(width 0)
			(type solid)
		)
		(fill yes)
		(layer "F.Cu")
		(net "M_A_CPU1_SA_DQ<17>")
	)
	(gr_poly
		(pts
			(xy 80.822546 -280.776426) (xy 80.772762 -280.76652) (xy 80.666082 -280.782014) (xy 80.628744 -280.968958)
			(xy 80.7212 -281.02433) (xy 80.770984 -281.034236)
		)
		(stroke
			(width 0)
			(type solid)
		)
		(fill yes)
		(layer "F.Cu")
		(net "M_A_CPU1_SA_DQ<18>")
	)
	(gr_poly
		(pts
			(xy 80.823308 -261.766558) (xy 80.77708 -261.669276) (xy 80.741266 -261.633208) (xy 80.555338 -261.819136)
			(xy 80.591152 -261.855204) (xy 80.688688 -261.901432)
		)
		(stroke
			(width 0)
			(type solid)
		)
		(fill yes)
		(layer "F.Cu")
		(net "M_A_CPU1_SA_CB<7>")
	)
	(gr_poly
		(pts
			(xy 80.831944 -268.634464) (xy 80.79613 -268.59865) (xy 80.698594 -268.552168) (xy 80.563974 -268.687042)
			(xy 80.610202 -268.784324) (xy 80.646016 -268.820392)
		)
		(stroke
			(width 0)
			(type solid)
		)
		(fill yes)
		(layer "F.Cu")
		(net "M_A_CPU1_SA_DQ<31>")
	)
	(gr_poly
		(pts
			(xy 80.83296 -262.620252) (xy 80.786478 -262.522716) (xy 80.750664 -262.486902) (xy 80.564736 -262.67283)
			(xy 80.600804 -262.708644) (xy 80.698086 -262.754872)
		)
		(stroke
			(width 0)
			(type solid)
		)
		(fill yes)
		(layer "F.Cu")
		(net "M_A_CPU1_SA_CB<6>")
	)
	(gr_poly
		(pts
			(xy 80.837532 -272.296636) (xy 80.791304 -272.199354) (xy 80.75549 -272.163286) (xy 80.569562 -272.349214)
			(xy 80.605376 -272.385282) (xy 80.702912 -272.43151)
		)
		(stroke
			(width 0)
			(type solid)
		)
		(fill yes)
		(layer "F.Cu")
		(net "M_A_CPU1_SA_DQ<27>")
	)
	(gr_poly
		(pts
			(xy 80.837786 -265.203178) (xy 80.791558 -265.105896) (xy 80.755744 -265.069828) (xy 80.569816 -265.255756)
			(xy 80.60563 -265.29157) (xy 80.703166 -265.337798)
		)
		(stroke
			(width 0)
			(type solid)
		)
		(fill yes)
		(layer "F.Cu")
		(net "M_A_CPU1_SA_CB<3>")
	)
	(gr_poly
		(pts
			(xy 80.841596 -269.488412) (xy 80.805782 -269.452344) (xy 80.708246 -269.406116) (xy 80.573626 -269.540736)
			(xy 80.619854 -269.638272) (xy 80.655668 -269.67434)
		)
		(stroke
			(width 0)
			(type solid)
		)
		(fill yes)
		(layer "F.Cu")
		(net "M_A_CPU1_SA_DQ<30>")
	)
	(gr_poly
		(pts
			(xy 80.84693 -273.15033) (xy 80.800702 -273.053048) (xy 80.764888 -273.01698) (xy 80.57896 -273.202908)
			(xy 80.614774 -273.238722) (xy 80.71231 -273.28495)
		)
		(stroke
			(width 0)
			(type solid)
		)
		(fill yes)
		(layer "F.Cu")
		(net "M_A_CPU1_SA_DQ<26>")
	)
	(gr_poly
		(pts
			(xy 80.847184 -266.056618) (xy 80.800956 -265.959336) (xy 80.765142 -265.923268) (xy 80.579214 -266.109196)
			(xy 80.615028 -266.145264) (xy 80.712564 -266.191492)
		)
		(stroke
			(width 0)
			(type solid)
		)
		(fill yes)
		(layer "F.Cu")
		(net "M_A_CPU1_SA_CB<2>")
	)
	(gr_poly
		(pts
			(xy 80.855058 -235.809028) (xy 80.890872 -235.773214) (xy 80.704944 -235.587286) (xy 80.66913 -235.623354)
			(xy 80.622902 -235.720636) (xy 80.757522 -235.855256)
		)
		(stroke
			(width 0)
			(type solid)
		)
		(fill yes)
		(layer "F.Cu")
		(net "M_A_CPU1_SB_DQ<8>")
	)
	(gr_poly
		(pts
			(xy 80.864202 -234.955842) (xy 80.900016 -234.919774) (xy 80.714088 -234.733846) (xy 80.678274 -234.769914)
			(xy 80.632046 -234.867196) (xy 80.766666 -235.00207)
		)
		(stroke
			(width 0)
			(type solid)
		)
		(fill yes)
		(layer "F.Cu")
		(net "M_A_CPU1_SB_DQ<9>")
	)
	(gr_poly
		(pts
			(xy 80.869028 -281.321256) (xy 80.906366 -281.134566) (xy 80.81391 -281.079194) (xy 80.764126 -281.069288)
			(xy 80.712564 -281.326844) (xy 80.762348 -281.337004)
		)
		(stroke
			(width 0)
			(type solid)
		)
		(fill yes)
		(layer "F.Cu")
		(net "M_A_CPU1_SA_DQ<18>")
	)
	(gr_poly
		(pts
			(xy 80.874616 -278.960834) (xy 80.824832 -278.950928) (xy 80.718152 -278.966422) (xy 80.680814 -279.153112)
			(xy 80.77327 -279.208484) (xy 80.823054 -279.218644)
		)
		(stroke
			(width 0)
			(type solid)
		)
		(fill yes)
		(layer "F.Cu")
		(net "M_A_CPU1_SA_DQ<17>")
	)
	(gr_poly
		(pts
			(xy 80.879188 -224.220024) (xy 80.915002 -224.183956) (xy 80.729328 -223.998282) (xy 80.69326 -224.034096)
			(xy 80.647032 -224.131632) (xy 80.781652 -224.266252)
		)
		(stroke
			(width 0)
			(type solid)
		)
		(fill yes)
		(layer "F.Cu")
		(net "M_A_CPU1_SB_DQ<22>")
	)
	(gr_poly
		(pts
			(xy 80.888332 -223.366584) (xy 80.9244 -223.33077) (xy 80.738472 -223.144842) (xy 80.702658 -223.180656)
			(xy 80.656176 -223.278192) (xy 80.79105 -223.412812)
		)
		(stroke
			(width 0)
			(type solid)
		)
		(fill yes)
		(layer "F.Cu")
		(net "M_A_CPU1_SB_DQ<23>")
	)
	(gr_poly
		(pts
			(xy 80.890618 -277.982426) (xy 80.845914 -277.95855) (xy 80.739234 -277.942294) (xy 80.649318 -278.110442)
			(xy 80.721708 -278.190198) (xy 80.766412 -278.214074)
		)
		(stroke
			(width 0)
			(type solid)
		)
		(fill yes)
		(layer "F.Cu")
		(net "M_A_CPU1_SA_DQ<19>")
	)
	(gr_poly
		(pts
			(xy 80.902048 -232.405682) (xy 80.937862 -232.369868) (xy 80.751934 -232.18394) (xy 80.71612 -232.220008)
			(xy 80.669892 -232.31729) (xy 80.804512 -232.452164)
		)
		(stroke
			(width 0)
			(type solid)
		)
		(fill yes)
		(layer "F.Cu")
		(net "M_A_CPU1_SB_DQ<12>")
	)
	(gr_poly
		(pts
			(xy 80.911192 -231.552242) (xy 80.94726 -231.516428) (xy 80.761332 -231.3305) (xy 80.725518 -231.366314)
			(xy 80.679036 -231.46385) (xy 80.81391 -231.59847)
		)
		(stroke
			(width 0)
			(type solid)
		)
		(fill yes)
		(layer "F.Cu")
		(net "M_A_CPU1_SB_DQ<13>")
	)
	(gr_poly
		(pts
			(xy 80.911954 -274.188428) (xy 80.875886 -274.152614) (xy 80.778604 -274.106386) (xy 80.643984 -274.241006)
			(xy 80.690212 -274.338288) (xy 80.726026 -274.374356)
		)
		(stroke
			(width 0)
			(type solid)
		)
		(fill yes)
		(layer "F.Cu")
		(net "M_A_CPU1_SA_DQ<23>")
	)
	(gr_poly
		(pts
			(xy 80.918812 -269.194534) (xy 80.872584 -269.097252) (xy 80.83677 -269.061184) (xy 80.650842 -269.247112)
			(xy 80.686656 -269.28318) (xy 80.784192 -269.329408)
		)
		(stroke
			(width 0)
			(type solid)
		)
		(fill yes)
		(layer "F.Cu")
		(net "M_A_CPU1_SA_DQ<29>")
	)
	(gr_poly
		(pts
			(xy 80.921098 -279.505664) (xy 80.958436 -279.31872) (xy 80.86598 -279.263348) (xy 80.816196 -279.253442)
			(xy 80.764634 -279.511252) (xy 80.814418 -279.521158)
		)
		(stroke
			(width 0)
			(type solid)
		)
		(fill yes)
		(layer "F.Cu")
		(net "M_A_CPU1_SA_DQ<17>")
	)
	(gr_poly
		(pts
			(xy 80.921352 -275.041868) (xy 80.885284 -275.006054) (xy 80.788002 -274.959826) (xy 80.653128 -275.094446)
			(xy 80.699356 -275.191982) (xy 80.735424 -275.227796)
		)
		(stroke
			(width 0)
			(type solid)
		)
		(fill yes)
		(layer "F.Cu")
		(net "M_A_CPU1_SA_DQ<22>")
	)
	(gr_poly
		(pts
			(xy 80.921352 -230.283004) (xy 80.957166 -230.246936) (xy 80.771238 -230.061008) (xy 80.735424 -230.097076)
			(xy 80.689196 -230.194358) (xy 80.823816 -230.329232)
		)
		(stroke
			(width 0)
			(type solid)
		)
		(fill yes)
		(layer "F.Cu")
		(net "M_A_CPU1_SB_DQ<16>")
	)
	(gr_poly
		(pts
			(xy 80.928464 -270.048482) (xy 80.882236 -269.950946) (xy 80.846168 -269.915132) (xy 80.660494 -270.100806)
			(xy 80.696308 -270.136874) (xy 80.793844 -270.183102)
		)
		(stroke
			(width 0)
			(type solid)
		)
		(fill yes)
		(layer "F.Cu")
		(net "M_A_CPU1_SA_DQ<28>")
	)
	(gr_poly
		(pts
			(xy 80.928464 -226.238054) (xy 80.928464 -226.047554) (xy 80.826864 -226.011486) (xy 80.776064 -226.011486)
			(xy 80.776064 -226.274122) (xy 80.826864 -226.274122)
		)
		(stroke
			(width 0)
			(type solid)
		)
		(fill yes)
		(layer "F.Cu")
		(net "M_A_CPU1_SB_DQ<20>")
	)
	(gr_poly
		(pts
			(xy 80.928464 -225.641154) (xy 80.928464 -225.450654) (xy 80.826864 -225.414586) (xy 80.776064 -225.414586)
			(xy 80.776064 -225.677222) (xy 80.826864 -225.677222)
		)
		(stroke
			(width 0)
			(type solid)
		)
		(fill yes)
		(layer "F.Cu")
		(net "M_A_CPU1_SB_DQ<20>")
	)
	(gr_poly
		(pts
			(xy 80.928464 -225.044254) (xy 80.928464 -224.853754) (xy 80.826864 -224.817686) (xy 80.776064 -224.817686)
			(xy 80.776064 -225.080322) (xy 80.826864 -225.080322)
		)
		(stroke
			(width 0)
			(type solid)
		)
		(fill yes)
		(layer "F.Cu")
		(net "M_A_CPU1_SB_DQ<20>")
	)
	(gr_poly
		(pts
			(xy 80.930496 -229.429564) (xy 80.966564 -229.39375) (xy 80.780636 -229.207822) (xy 80.744568 -229.243636)
			(xy 80.69834 -229.341172) (xy 80.833214 -229.475792)
		)
		(stroke
			(width 0)
			(type solid)
		)
		(fill yes)
		(layer "F.Cu")
		(net "M_A_CPU1_SB_DQ<17>")
	)
	(gr_poly
		(pts
			(xy 80.931512 -289.25266) (xy 80.880712 -289.25266) (xy 80.779112 -289.288982) (xy 80.779112 -289.479482)
			(xy 80.880712 -289.51555) (xy 80.931512 -289.51555)
		)
		(stroke
			(width 0)
			(type solid)
		)
		(fill yes)
		(layer "F.Cu")
		(net "M_A_CPU1_SA_DQ<16>")
	)
	(gr_poly
		(pts
			(xy 80.931512 -288.65576) (xy 80.880712 -288.65576) (xy 80.779112 -288.692082) (xy 80.779112 -288.882582)
			(xy 80.880712 -288.91865) (xy 80.931512 -288.91865)
		)
		(stroke
			(width 0)
			(type solid)
		)
		(fill yes)
		(layer "F.Cu")
		(net "M_A_CPU1_SA_DQ<16>")
	)
	(gr_poly
		(pts
			(xy 80.931512 -288.05886) (xy 80.880712 -288.05886) (xy 80.779112 -288.095182) (xy 80.779112 -288.285682)
			(xy 80.880712 -288.32175) (xy 80.931512 -288.32175)
		)
		(stroke
			(width 0)
			(type solid)
		)
		(fill yes)
		(layer "F.Cu")
		(net "M_A_CPU1_SA_DQ<16>")
	)
	(gr_poly
		(pts
			(xy 80.931512 -287.46196) (xy 80.880712 -287.46196) (xy 80.779112 -287.498282) (xy 80.779112 -287.688782)
			(xy 80.880712 -287.72485) (xy 80.931512 -287.72485)
		)
		(stroke
			(width 0)
			(type solid)
		)
		(fill yes)
		(layer "F.Cu")
		(net "M_A_CPU1_SA_DQ<16>")
	)
	(gr_poly
		(pts
			(xy 80.931512 -286.86506) (xy 80.880712 -286.86506) (xy 80.779112 -286.901382) (xy 80.779112 -287.091882)
			(xy 80.880712 -287.12795) (xy 80.931512 -287.12795)
		)
		(stroke
			(width 0)
			(type solid)
		)
		(fill yes)
		(layer "F.Cu")
		(net "M_A_CPU1_SA_DQ<16>")
	)
	(gr_poly
		(pts
			(xy 80.931512 -286.26816) (xy 80.880712 -286.26816) (xy 80.779112 -286.304482) (xy 80.779112 -286.494982)
			(xy 80.880712 -286.53105) (xy 80.931512 -286.53105)
		)
		(stroke
			(width 0)
			(type solid)
		)
		(fill yes)
		(layer "F.Cu")
		(net "M_A_CPU1_SA_DQ<16>")
	)
	(gr_poly
		(pts
			(xy 80.931512 -285.67126) (xy 80.880712 -285.67126) (xy 80.779112 -285.707582) (xy 80.779112 -285.898082)
			(xy 80.880712 -285.93415) (xy 80.931512 -285.93415)
		)
		(stroke
			(width 0)
			(type solid)
		)
		(fill yes)
		(layer "F.Cu")
		(net "M_A_CPU1_SA_DQ<16>")
	)
	(gr_poly
		(pts
			(xy 80.931512 -285.07436) (xy 80.880712 -285.07436) (xy 80.779112 -285.110682) (xy 80.779112 -285.301182)
			(xy 80.880712 -285.33725) (xy 80.931512 -285.33725)
		)
		(stroke
			(width 0)
			(type solid)
		)
		(fill yes)
		(layer "F.Cu")
		(net "M_A_CPU1_SA_DQ<16>")
	)
	(gr_poly
		(pts
			(xy 80.931512 -284.47746) (xy 80.880712 -284.47746) (xy 80.779112 -284.513782) (xy 80.779112 -284.704282)
			(xy 80.880712 -284.74035) (xy 80.931512 -284.74035)
		)
		(stroke
			(width 0)
			(type solid)
		)
		(fill yes)
		(layer "F.Cu")
		(net "M_A_CPU1_SA_DQ<16>")
	)
	(gr_poly
		(pts
			(xy 80.931512 -283.88056) (xy 80.880712 -283.88056) (xy 80.779112 -283.916882) (xy 80.779112 -284.107382)
			(xy 80.880712 -284.14345) (xy 80.931512 -284.14345)
		)
		(stroke
			(width 0)
			(type solid)
		)
		(fill yes)
		(layer "F.Cu")
		(net "M_A_CPU1_SA_DQ<16>")
	)
	(gr_poly
		(pts
			(xy 80.931512 -283.28366) (xy 80.880712 -283.28366) (xy 80.779112 -283.319982) (xy 80.779112 -283.510482)
			(xy 80.880712 -283.54655) (xy 80.931512 -283.54655)
		)
		(stroke
			(width 0)
			(type solid)
		)
		(fill yes)
		(layer "F.Cu")
		(net "M_A_CPU1_SA_DQ<16>")
	)
	(gr_poly
		(pts
			(xy 80.931512 -282.68676) (xy 80.880712 -282.68676) (xy 80.779112 -282.723082) (xy 80.779112 -282.913582)
			(xy 80.880712 -282.94965) (xy 80.931512 -282.94965)
		)
		(stroke
			(width 0)
			(type solid)
		)
		(fill yes)
		(layer "F.Cu")
		(net "M_A_CPU1_SA_DQ<16>")
	)
	(gr_poly
		(pts
			(xy 80.931512 -282.08986) (xy 80.880712 -282.08986) (xy 80.779112 -282.126182) (xy 80.779112 -282.316682)
			(xy 80.880712 -282.35275) (xy 80.931512 -282.35275)
		)
		(stroke
			(width 0)
			(type solid)
		)
		(fill yes)
		(layer "F.Cu")
		(net "M_A_CPU1_SA_DQ<16>")
	)
	(gr_poly
		(pts
			(xy 80.931512 -235.31068) (xy 80.97774 -235.213144) (xy 80.842866 -235.078524) (xy 80.745584 -235.124752)
			(xy 80.709516 -235.160566) (xy 80.895444 -235.346494)
		)
		(stroke
			(width 0)
			(type solid)
		)
		(fill yes)
		(layer "F.Cu")
		(net "M_A_CPU1_SB_DQ<10>")
	)
	(gr_poly
		(pts
			(xy 80.93964 -280.19121) (xy 80.889856 -280.181304) (xy 80.783176 -280.196798) (xy 80.745838 -280.383742)
			(xy 80.838294 -280.439114) (xy 80.888078 -280.44902)
		)
		(stroke
			(width 0)
			(type solid)
		)
		(fill yes)
		(layer "F.Cu")
		(net "M_A_CPU1_SA_DQ<18>")
	)
	(gr_poly
		(pts
			(xy 80.940656 -234.45724) (xy 80.986884 -234.359704) (xy 80.852264 -234.225084) (xy 80.754728 -234.271312)
			(xy 80.718914 -234.30738) (xy 80.904588 -234.493054)
		)
		(stroke
			(width 0)
			(type solid)
		)
		(fill yes)
		(layer "F.Cu")
		(net "M_A_CPU1_SB_DQ<11>")
	)
	(gr_poly
		(pts
			(xy 80.95234 -261.422134) (xy 80.916272 -261.38632) (xy 80.81899 -261.340092) (xy 80.684116 -261.474712)
			(xy 80.730344 -261.572248) (xy 80.766412 -261.608062)
		)
		(stroke
			(width 0)
			(type solid)
		)
		(fill yes)
		(layer "F.Cu")
		(net "M_A_CPU1_SA_CB<7>")
	)
	(gr_poly
		(pts
			(xy 80.955642 -223.721422) (xy 81.00187 -223.62414) (xy 80.86725 -223.489266) (xy 80.769714 -223.535494)
			(xy 80.7339 -223.571562) (xy 80.919828 -223.75749)
		)
		(stroke
			(width 0)
			(type solid)
		)
		(fill yes)
		(layer "F.Cu")
		(net "M_A_CPU1_SB_DQ<21>")
	)
	(gr_poly
		(pts
			(xy 80.961738 -262.275828) (xy 80.92567 -262.240014) (xy 80.828388 -262.193786) (xy 80.693768 -262.328406)
			(xy 80.739996 -262.425942) (xy 80.77581 -262.461756)
		)
		(stroke
			(width 0)
			(type solid)
		)
		(fill yes)
		(layer "F.Cu")
		(net "M_A_CPU1_SA_CB<6>")
	)
	(gr_poly
		(pts
			(xy 80.96631 -271.952466) (xy 80.930496 -271.916398) (xy 80.83296 -271.87017) (xy 80.69834 -272.00479)
			(xy 80.744568 -272.102326) (xy 80.780636 -272.13814)
		)
		(stroke
			(width 0)
			(type solid)
		)
		(fill yes)
		(layer "F.Cu")
		(net "M_A_CPU1_SA_DQ<27>")
	)
	(gr_poly
		(pts
			(xy 80.966818 -264.858754) (xy 80.93075 -264.82294) (xy 80.833468 -264.776712) (xy 80.698594 -264.911332)
			(xy 80.744822 -265.008868) (xy 80.78089 -265.044682)
		)
		(stroke
			(width 0)
			(type solid)
		)
		(fill yes)
		(layer "F.Cu")
		(net "M_A_CPU1_SA_CB<3>")
	)
	(gr_poly
		(pts
			(xy 80.975962 -272.805906) (xy 80.939894 -272.770092) (xy 80.842612 -272.723864) (xy 80.707738 -272.858484)
			(xy 80.753966 -272.95602) (xy 80.790034 -272.991834)
		)
		(stroke
			(width 0)
			(type solid)
		)
		(fill yes)
		(layer "F.Cu")
		(net "M_A_CPU1_SA_DQ<26>")
	)
	(gr_poly
		(pts
			(xy 80.976216 -265.712194) (xy 80.940148 -265.67638) (xy 80.842866 -265.630152) (xy 80.707992 -265.764772)
			(xy 80.75422 -265.862308) (xy 80.790288 -265.898122)
		)
		(stroke
			(width 0)
			(type solid)
		)
		(fill yes)
		(layer "F.Cu")
		(net "M_A_CPU1_SA_CB<2>")
	)
	(gr_poly
		(pts
			(xy 80.978502 -231.90708) (xy 81.02473 -231.809798) (xy 80.89011 -231.674924) (xy 80.792574 -231.721152)
			(xy 80.75676 -231.75722) (xy 80.942688 -231.943148)
		)
		(stroke
			(width 0)
			(type solid)
		)
		(fill yes)
		(layer "F.Cu")
		(net "M_A_CPU1_SB_DQ<14>")
	)
	(gr_poly
		(pts
			(xy 80.986122 -280.73604) (xy 81.02346 -280.549096) (xy 80.931004 -280.493724) (xy 80.88122 -280.483818)
			(xy 80.829658 -280.741628) (xy 80.879442 -280.751534)
		)
		(stroke
			(width 0)
			(type solid)
		)
		(fill yes)
		(layer "F.Cu")
		(net "M_A_CPU1_SA_DQ<18>")
	)
	(gr_poly
		(pts
			(xy 80.987646 -231.053894) (xy 81.033874 -230.956358) (xy 80.899254 -230.821738) (xy 80.801972 -230.867966)
			(xy 80.765904 -230.90378) (xy 80.951832 -231.089708)
		)
		(stroke
			(width 0)
			(type solid)
		)
		(fill yes)
		(layer "F.Cu")
		(net "M_A_CPU1_SB_DQ<15>")
	)
	(gr_poly
		(pts
			(xy 80.997806 -229.784402) (xy 81.044034 -229.686866) (xy 80.909414 -229.552246) (xy 80.811878 -229.598474)
			(xy 80.776064 -229.634542) (xy 80.961738 -229.820216)
		)
		(stroke
			(width 0)
			(type solid)
		)
		(fill yes)
		(layer "F.Cu")
		(net "M_A_CPU1_SB_DQ<18>")
	)
	(gr_poly
		(pts
			(xy 80.998822 -274.748498) (xy 80.952594 -274.651216) (xy 80.916526 -274.615148) (xy 80.730598 -274.801076)
			(xy 80.766666 -274.83689) (xy 80.863948 -274.883372)
		)
		(stroke
			(width 0)
			(type solid)
		)
		(fill yes)
		(layer "F.Cu")
		(net "M_A_CPU1_SA_DQ<21>")
	)
	(gr_poly
		(pts
			(xy 81.00695 -228.930962) (xy 81.053178 -228.83368) (xy 80.918558 -228.698806) (xy 80.821022 -228.745034)
			(xy 80.785208 -228.781102) (xy 80.971136 -228.96703)
		)
		(stroke
			(width 0)
			(type solid)
		)
		(fill yes)
		(layer "F.Cu")
		(net "M_A_CPU1_SB_DQ<19>")
	)
	(gr_poly
		(pts
			(xy 81.008728 -275.6027) (xy 80.9625 -275.505418) (xy 80.926432 -275.46935) (xy 80.740758 -275.655278)
			(xy 80.776572 -275.691346) (xy 80.874108 -275.737574)
		)
		(stroke
			(width 0)
			(type solid)
		)
		(fill yes)
		(layer "F.Cu")
		(net "M_A_CPU1_SA_DQ<20>")
	)
	(gr_poly
		(pts
			(xy 81.038192 -278.920194) (xy 81.07553 -278.733504) (xy 80.983074 -278.678132) (xy 80.933036 -278.667972)
			(xy 80.881728 -278.925782) (xy 80.931512 -278.935942)
		)
		(stroke
			(width 0)
			(type solid)
		)
		(fill yes)
		(layer "F.Cu")
		(net "M_A_CPU1_SA_DQ<17>")
	)
	(gr_poly
		(pts
			(xy 81.039208 -261.982458) (xy 80.99298 -261.884922) (xy 80.956912 -261.849108) (xy 80.770984 -262.035036)
			(xy 80.807052 -262.07085) (xy 80.904334 -262.117078)
		)
		(stroke
			(width 0)
			(type solid)
		)
		(fill yes)
		(layer "F.Cu")
		(net "M_A_CPU1_SA_CB<5>")
	)
	(gr_poly
		(pts
			(xy 81.04759 -249.371866) (xy 81.04759 -249.321066) (xy 80.7847 -249.321066) (xy 80.7847 -249.371866)
			(xy 80.820768 -249.473466) (xy 81.011268 -249.473466)
		)
		(stroke
			(width 0)
			(type solid)
		)
		(fill yes)
		(layer "F.Cu")
		(net "M_A_CPU1_SB_CA<0>")
	)
	(gr_poly
		(pts
			(xy 81.04759 -249.066812) (xy 81.04759 -249.016012) (xy 80.7847 -249.016012) (xy 80.7847 -249.066812)
			(xy 80.820768 -249.168412) (xy 81.011268 -249.168412)
		)
		(stroke
			(width 0)
			(type solid)
		)
		(fill yes)
		(layer "F.Cu")
		(net "M_A_CPU1_SB_CA<1>")
	)
	(gr_poly
		(pts
			(xy 81.04759 -248.762012) (xy 81.04759 -248.711212) (xy 80.7847 -248.711212) (xy 80.7847 -248.762012)
			(xy 80.820768 -248.863612) (xy 81.011268 -248.863612)
		)
		(stroke
			(width 0)
			(type solid)
		)
		(fill yes)
		(layer "F.Cu")
		(net "M_A_CPU1_SB_CA<2>")
	)
	(gr_poly
		(pts
			(xy 81.04759 -248.457212) (xy 81.04759 -248.406412) (xy 80.7847 -248.406412) (xy 80.7847 -248.457212)
			(xy 80.820768 -248.558812) (xy 81.011268 -248.558812)
		)
		(stroke
			(width 0)
			(type solid)
		)
		(fill yes)
		(layer "F.Cu")
		(net "M_A_CPU1_SB_CA<3>")
	)
	(gr_poly
		(pts
			(xy 81.04759 -248.152412) (xy 81.04759 -248.101612) (xy 80.7847 -248.101612) (xy 80.7847 -248.152412)
			(xy 80.820768 -248.254012) (xy 81.011268 -248.254012)
		)
		(stroke
			(width 0)
			(type solid)
		)
		(fill yes)
		(layer "F.Cu")
		(net "M_A_CPU1_SB_CA<4>")
	)
	(gr_poly
		(pts
			(xy 81.04759 -247.847612) (xy 81.04759 -247.796812) (xy 80.7847 -247.796812) (xy 80.7847 -247.847612)
			(xy 80.820768 -247.949212) (xy 81.011268 -247.949212)
		)
		(stroke
			(width 0)
			(type solid)
		)
		(fill yes)
		(layer "F.Cu")
		(net "M_A_CPU1_SB_CA<5>")
	)
	(gr_poly
		(pts
			(xy 81.04759 -247.542812) (xy 81.04759 -247.492012) (xy 80.7847 -247.492012) (xy 80.7847 -247.542812)
			(xy 80.820768 -247.644412) (xy 81.011268 -247.644412)
		)
		(stroke
			(width 0)
			(type solid)
		)
		(fill yes)
		(layer "F.Cu")
		(net "M_A_CPU1_SB_CA<6>")
	)
	(gr_poly
		(pts
			(xy 81.04759 -247.238012) (xy 81.04759 -247.187212) (xy 80.7847 -247.187212) (xy 80.7847 -247.238012)
			(xy 80.820768 -247.339612) (xy 81.011268 -247.339612)
		)
		(stroke
			(width 0)
			(type solid)
		)
		(fill yes)
		(layer "F.Cu")
		(net "M_A_CPU1_SB_PAR")
	)
	(gr_poly
		(pts
			(xy 81.047844 -268.85011) (xy 81.011776 -268.814296) (xy 80.914494 -268.768068) (xy 80.77962 -268.902688)
			(xy 80.825848 -269.000224) (xy 80.861916 -269.036038)
		)
		(stroke
			(width 0)
			(type solid)
		)
		(fill yes)
		(layer "F.Cu")
		(net "M_A_CPU1_SA_DQ<29>")
	)
	(gr_poly
		(pts
			(xy 81.048606 -262.835898) (xy 81.002378 -262.738616) (xy 80.966564 -262.702548) (xy 80.780636 -262.888476)
			(xy 80.81645 -262.924544) (xy 80.913986 -262.970772)
		)
		(stroke
			(width 0)
			(type solid)
		)
		(fill yes)
		(layer "F.Cu")
		(net "M_A_CPU1_SA_CB<4>")
	)
	(gr_poly
		(pts
			(xy 81.053432 -272.512536) (xy 81.007204 -272.415254) (xy 80.97139 -272.379186) (xy 80.785462 -272.565114)
			(xy 80.821276 -272.601182) (xy 80.918812 -272.64741)
		)
		(stroke
			(width 0)
			(type solid)
		)
		(fill yes)
		(layer "F.Cu")
		(net "M_A_CPU1_SA_DQ<25>")
	)
	(gr_poly
		(pts
			(xy 81.053432 -265.418824) (xy 81.007204 -265.321542) (xy 80.97139 -265.285474) (xy 80.785462 -265.471402)
			(xy 80.821276 -265.507216) (xy 80.918812 -265.553444)
		)
		(stroke
			(width 0)
			(type solid)
		)
		(fill yes)
		(layer "F.Cu")
		(net "M_A_CPU1_SA_CB<1>")
	)
	(gr_poly
		(pts
			(xy 81.056734 -279.605994) (xy 81.00695 -279.595834) (xy 80.90027 -279.611582) (xy 80.862932 -279.798272)
			(xy 80.955388 -279.853644) (xy 81.005172 -279.86355)
		)
		(stroke
			(width 0)
			(type solid)
		)
		(fill yes)
		(layer "F.Cu")
		(net "M_A_CPU1_SA_DQ<18>")
	)
	(gr_poly
		(pts
			(xy 81.057242 -269.704058) (xy 81.021428 -269.66799) (xy 80.923892 -269.621762) (xy 80.789272 -269.756382)
			(xy 80.8355 -269.853918) (xy 80.871314 -269.889986)
		)
		(stroke
			(width 0)
			(type solid)
		)
		(fill yes)
		(layer "F.Cu")
		(net "M_A_CPU1_SA_DQ<28>")
	)
	(gr_poly
		(pts
			(xy 81.062576 -273.365976) (xy 81.016348 -273.268694) (xy 80.980534 -273.232626) (xy 80.794606 -273.418554)
			(xy 80.83042 -273.454368) (xy 80.927956 -273.500596)
		)
		(stroke
			(width 0)
			(type solid)
		)
		(fill yes)
		(layer "F.Cu")
		(net "M_A_CPU1_SA_DQ<24>")
	)
	(gr_poly
		(pts
			(xy 81.06283 -266.272264) (xy 81.016602 -266.174982) (xy 80.980788 -266.138914) (xy 80.79486 -266.324842)
			(xy 80.830674 -266.36091) (xy 80.92821 -266.407138)
		)
		(stroke
			(width 0)
			(type solid)
		)
		(fill yes)
		(layer "F.Cu")
		(net "M_A_CPU1_SA_CB<0>")
	)
	(gr_poly
		(pts
			(xy 81.070704 -235.593382) (xy 81.106518 -235.557568) (xy 80.92059 -235.37164) (xy 80.884776 -235.407708)
			(xy 80.838548 -235.50499) (xy 80.973168 -235.63961)
		)
		(stroke
			(width 0)
			(type solid)
		)
		(fill yes)
		(layer "F.Cu")
		(net "M_A_CPU1_SB_DQ<10>")
	)
	(gr_poly
		(pts
			(xy 81.079848 -234.740196) (xy 81.115662 -234.704128) (xy 80.929734 -234.5182) (xy 80.89392 -234.554268)
			(xy 80.847692 -234.65155) (xy 80.982312 -234.786424)
		)
		(stroke
			(width 0)
			(type solid)
		)
		(fill yes)
		(layer "F.Cu")
		(net "M_A_CPU1_SB_DQ<11>")
	)
	(gr_poly
		(pts
			(xy 81.080356 -259.618226) (xy 81.044288 -259.516626) (xy 80.853788 -259.516626) (xy 80.817466 -259.618226)
			(xy 80.817466 -259.669026) (xy 81.080356 -259.669026)
		)
		(stroke
			(width 0)
			(type solid)
		)
		(fill yes)
		(layer "F.Cu")
		(net "M_A_CPU1_SA_CS_N<0>")
	)
	(gr_poly
		(pts
			(xy 81.080356 -259.313426) (xy 81.044288 -259.211826) (xy 80.853788 -259.211826) (xy 80.817466 -259.313426)
			(xy 80.817466 -259.364226) (xy 81.080356 -259.364226)
		)
		(stroke
			(width 0)
			(type solid)
		)
		(fill yes)
		(layer "F.Cu")
		(net "M_A_CPU1_SA_CS_N<2>")
	)
	(gr_poly
		(pts
			(xy 81.080356 -259.008626) (xy 81.044288 -258.907026) (xy 80.853788 -258.907026) (xy 80.817466 -259.008626)
			(xy 80.817466 -259.059426) (xy 81.080356 -259.059426)
		)
		(stroke
			(width 0)
			(type solid)
		)
		(fill yes)
		(layer "F.Cu")
		(net "M_A_CPU1_SA_CS_N<3>")
	)
	(gr_poly
		(pts
			(xy 81.080356 -258.703826) (xy 81.044288 -258.602226) (xy 80.853788 -258.602226) (xy 80.817466 -258.703826)
			(xy 80.817466 -258.754626) (xy 81.080356 -258.754626)
		)
		(stroke
			(width 0)
			(type solid)
		)
		(fill yes)
		(layer "F.Cu")
		(net "M_A_CPU1_SA_CS_N<1>")
	)
	(gr_poly
		(pts
			(xy 81.080356 -258.399026) (xy 81.044288 -258.297426) (xy 80.853788 -258.297426) (xy 80.817466 -258.399026)
			(xy 80.817466 -258.449826) (xy 81.080356 -258.449826)
		)
		(stroke
			(width 0)
			(type solid)
		)
		(fill yes)
		(layer "F.Cu")
		(net "M_A_CPU1_SA_CA<0>")
	)
	(gr_poly
		(pts
			(xy 81.080356 -258.094226) (xy 81.044288 -257.992626) (xy 80.853788 -257.992626) (xy 80.817466 -258.094226)
			(xy 80.817466 -258.145026) (xy 81.080356 -258.145026)
		)
		(stroke
			(width 0)
			(type solid)
		)
		(fill yes)
		(layer "F.Cu")
		(net "M_A_CPU1_SA_CA<1>")
	)
	(gr_poly
		(pts
			(xy 81.080356 -257.789426) (xy 81.044288 -257.687826) (xy 80.853788 -257.687826) (xy 80.817466 -257.789426)
			(xy 80.817466 -257.840226) (xy 81.080356 -257.840226)
		)
		(stroke
			(width 0)
			(type solid)
		)
		(fill yes)
		(layer "F.Cu")
		(net "M_A_CPU1_SA_CA<2>")
	)
	(gr_poly
		(pts
			(xy 81.080356 -257.484626) (xy 81.044288 -257.383026) (xy 80.853788 -257.383026) (xy 80.817466 -257.484626)
			(xy 80.817466 -257.535426) (xy 81.080356 -257.535426)
		)
		(stroke
			(width 0)
			(type solid)
		)
		(fill yes)
		(layer "F.Cu")
		(net "M_A_CPU1_SA_CA<3>")
	)
	(gr_poly
		(pts
			(xy 81.080356 -257.179826) (xy 81.044288 -257.078226) (xy 80.853788 -257.078226) (xy 80.817466 -257.179826)
			(xy 80.817466 -257.230626) (xy 81.080356 -257.230626)
		)
		(stroke
			(width 0)
			(type solid)
		)
		(fill yes)
		(layer "F.Cu")
		(net "M_A_CPU1_SA_CA<4>")
	)
	(gr_poly
		(pts
			(xy 81.080356 -256.875026) (xy 81.044288 -256.773426) (xy 80.853788 -256.773426) (xy 80.817466 -256.875026)
			(xy 80.817466 -256.925826) (xy 81.080356 -256.925826)
		)
		(stroke
			(width 0)
			(type solid)
		)
		(fill yes)
		(layer "F.Cu")
		(net "M_A_CPU1_SA_CA<5>")
	)
	(gr_poly
		(pts
			(xy 81.080356 -256.570226) (xy 81.044288 -256.468626) (xy 80.853788 -256.468626) (xy 80.817466 -256.570226)
			(xy 80.817466 -256.621026) (xy 81.080356 -256.621026)
		)
		(stroke
			(width 0)
			(type solid)
		)
		(fill yes)
		(layer "F.Cu")
		(net "M_A_CPU1_SA_CA<6>")
	)
	(gr_poly
		(pts
			(xy 81.080356 -256.265426) (xy 81.044288 -256.163826) (xy 80.853788 -256.163826) (xy 80.817466 -256.265426)
			(xy 80.817466 -256.316226) (xy 81.080356 -256.316226)
		)
		(stroke
			(width 0)
			(type solid)
		)
		(fill yes)
		(layer "F.Cu")
		(net "M_A_CPU1_SA_PAR")
	)
	(gr_poly
		(pts
			(xy 81.080864 -225.712782) (xy 81.030064 -225.712782) (xy 80.928464 -225.749104) (xy 80.928464 -225.939604)
			(xy 81.030064 -225.975926) (xy 81.080864 -225.975926)
		)
		(stroke
			(width 0)
			(type solid)
		)
		(fill yes)
		(layer "F.Cu")
		(net "M_A_CPU1_SB_DQ<22>")
	)
	(gr_poly
		(pts
			(xy 81.080864 -225.115882) (xy 81.030064 -225.115882) (xy 80.928464 -225.152204) (xy 80.928464 -225.342704)
			(xy 81.030064 -225.379026) (xy 81.080864 -225.379026)
		)
		(stroke
			(width 0)
			(type solid)
		)
		(fill yes)
		(layer "F.Cu")
		(net "M_A_CPU1_SB_DQ<22>")
	)
	(gr_poly
		(pts
			(xy 81.080864 -224.518982) (xy 81.030064 -224.518982) (xy 80.928464 -224.555304) (xy 80.928464 -224.745804)
			(xy 81.030064 -224.782126) (xy 81.080864 -224.782126)
		)
		(stroke
			(width 0)
			(type solid)
		)
		(fill yes)
		(layer "F.Cu")
		(net "M_A_CPU1_SB_DQ<22>")
	)
	(gr_poly
		(pts
			(xy 81.083912 -289.181032) (xy 81.083912 -288.990532) (xy 80.982312 -288.95421) (xy 80.931512 -288.95421)
			(xy 80.931512 -289.2171) (xy 80.982312 -289.2171)
		)
		(stroke
			(width 0)
			(type solid)
		)
		(fill yes)
		(layer "F.Cu")
		(net "M_A_CPU1_SA_DQ<16>")
	)
	(gr_poly
		(pts
			(xy 81.083912 -288.584132) (xy 81.083912 -288.393632) (xy 80.982312 -288.35731) (xy 80.931512 -288.35731)
			(xy 80.931512 -288.6202) (xy 80.982312 -288.6202)
		)
		(stroke
			(width 0)
			(type solid)
		)
		(fill yes)
		(layer "F.Cu")
		(net "M_A_CPU1_SA_DQ<16>")
	)
	(gr_poly
		(pts
			(xy 81.083912 -287.987232) (xy 81.083912 -287.796732) (xy 80.982312 -287.76041) (xy 80.931512 -287.76041)
			(xy 80.931512 -288.0233) (xy 80.982312 -288.0233)
		)
		(stroke
			(width 0)
			(type solid)
		)
		(fill yes)
		(layer "F.Cu")
		(net "M_A_CPU1_SA_DQ<16>")
	)
	(gr_poly
		(pts
			(xy 81.083912 -287.390332) (xy 81.083912 -287.199832) (xy 80.982312 -287.16351) (xy 80.931512 -287.16351)
			(xy 80.931512 -287.4264) (xy 80.982312 -287.4264)
		)
		(stroke
			(width 0)
			(type solid)
		)
		(fill yes)
		(layer "F.Cu")
		(net "M_A_CPU1_SA_DQ<16>")
	)
	(gr_poly
		(pts
			(xy 81.083912 -286.793432) (xy 81.083912 -286.602932) (xy 80.982312 -286.56661) (xy 80.931512 -286.56661)
			(xy 80.931512 -286.8295) (xy 80.982312 -286.8295)
		)
		(stroke
			(width 0)
			(type solid)
		)
		(fill yes)
		(layer "F.Cu")
		(net "M_A_CPU1_SA_DQ<16>")
	)
	(gr_poly
		(pts
			(xy 81.083912 -286.196532) (xy 81.083912 -286.006032) (xy 80.982312 -285.96971) (xy 80.931512 -285.96971)
			(xy 80.931512 -286.2326) (xy 80.982312 -286.2326)
		)
		(stroke
			(width 0)
			(type solid)
		)
		(fill yes)
		(layer "F.Cu")
		(net "M_A_CPU1_SA_DQ<16>")
	)
	(gr_poly
		(pts
			(xy 81.083912 -285.599632) (xy 81.083912 -285.409132) (xy 80.982312 -285.37281) (xy 80.931512 -285.37281)
			(xy 80.931512 -285.6357) (xy 80.982312 -285.6357)
		)
		(stroke
			(width 0)
			(type solid)
		)
		(fill yes)
		(layer "F.Cu")
		(net "M_A_CPU1_SA_DQ<16>")
	)
	(gr_poly
		(pts
			(xy 81.083912 -285.002732) (xy 81.083912 -284.812232) (xy 80.982312 -284.77591) (xy 80.931512 -284.77591)
			(xy 80.931512 -285.0388) (xy 80.982312 -285.0388)
		)
		(stroke
			(width 0)
			(type solid)
		)
		(fill yes)
		(layer "F.Cu")
		(net "M_A_CPU1_SA_DQ<16>")
	)
	(gr_poly
		(pts
			(xy 81.083912 -284.405832) (xy 81.083912 -284.215332) (xy 80.982312 -284.17901) (xy 80.931512 -284.17901)
			(xy 80.931512 -284.4419) (xy 80.982312 -284.4419)
		)
		(stroke
			(width 0)
			(type solid)
		)
		(fill yes)
		(layer "F.Cu")
		(net "M_A_CPU1_SA_DQ<16>")
	)
	(gr_poly
		(pts
			(xy 81.083912 -283.808932) (xy 81.083912 -283.618432) (xy 80.982312 -283.58211) (xy 80.931512 -283.58211)
			(xy 80.931512 -283.845) (xy 80.982312 -283.845)
		)
		(stroke
			(width 0)
			(type solid)
		)
		(fill yes)
		(layer "F.Cu")
		(net "M_A_CPU1_SA_DQ<16>")
	)
	(gr_poly
		(pts
			(xy 81.083912 -283.212032) (xy 81.083912 -283.021532) (xy 80.982312 -282.98521) (xy 80.931512 -282.98521)
			(xy 80.931512 -283.2481) (xy 80.982312 -283.2481)
		)
		(stroke
			(width 0)
			(type solid)
		)
		(fill yes)
		(layer "F.Cu")
		(net "M_A_CPU1_SA_DQ<16>")
	)
	(gr_poly
		(pts
			(xy 81.083912 -282.615132) (xy 81.083912 -282.424632) (xy 80.982312 -282.38831) (xy 80.931512 -282.38831)
			(xy 80.931512 -282.6512) (xy 80.982312 -282.6512)
		)
		(stroke
			(width 0)
			(type solid)
		)
		(fill yes)
		(layer "F.Cu")
		(net "M_A_CPU1_SA_DQ<16>")
	)
	(gr_poly
		(pts
			(xy 81.094834 -224.004378) (xy 81.130648 -223.96831) (xy 80.944974 -223.782636) (xy 80.908906 -223.81845)
			(xy 80.862678 -223.915986) (xy 80.997298 -224.050606)
		)
		(stroke
			(width 0)
			(type solid)
		)
		(fill yes)
		(layer "F.Cu")
		(net "M_A_CPU1_SB_DQ<21>")
	)
	(gr_poly
		(pts
			(xy 81.103216 -280.150824) (xy 81.140554 -279.96388) (xy 81.048098 -279.908508) (xy 80.998314 -279.898602)
			(xy 80.946752 -280.156412) (xy 80.996536 -280.166318)
		)
		(stroke
			(width 0)
			(type solid)
		)
		(fill yes)
		(layer "F.Cu")
		(net "M_A_CPU1_SA_DQ<18>")
	)
	(gr_poly
		(pts
			(xy 81.117694 -232.190036) (xy 81.153762 -232.154222) (xy 80.967834 -231.968294) (xy 80.931766 -232.004108)
			(xy 80.885538 -232.101644) (xy 81.020412 -232.236264)
		)
		(stroke
			(width 0)
			(type solid)
		)
		(fill yes)
		(layer "F.Cu")
		(net "M_A_CPU1_SB_DQ<14>")
	)
	(gr_poly
		(pts
			(xy 81.121758 -280.83637) (xy 81.071974 -280.826464) (xy 80.965294 -280.841958) (xy 80.927956 -281.028648)
			(xy 81.020412 -281.08402) (xy 81.070196 -281.09418)
		)
		(stroke
			(width 0)
			(type solid)
		)
		(fill yes)
		(layer "F.Cu")
		(net "M_A_CPU1_SA_DQ<16>")
	)
	(gr_poly
		(pts
			(xy 81.12506 -268.55674) (xy 81.078832 -268.459458) (xy 81.043018 -268.42339) (xy 80.85709 -268.609318)
			(xy 80.892904 -268.645132) (xy 80.99044 -268.69136)
		)
		(stroke
			(width 0)
			(type solid)
		)
		(fill yes)
		(layer "F.Cu")
		(net "M_A_CPU1_SA_DQ<31>")
	)
	(gr_poly
		(pts
			(xy 81.126838 -231.336596) (xy 81.162906 -231.300782) (xy 80.976978 -231.114854) (xy 80.941164 -231.150668)
			(xy 80.894682 -231.248204) (xy 81.029556 -231.382824)
		)
		(stroke
			(width 0)
			(type solid)
		)
		(fill yes)
		(layer "F.Cu")
		(net "M_A_CPU1_SB_DQ<15>")
	)
	(gr_poly
		(pts
			(xy 81.1276 -274.404074) (xy 81.091786 -274.36826) (xy 80.99425 -274.322032) (xy 80.85963 -274.456652)
			(xy 80.905858 -274.554188) (xy 80.941672 -274.590002)
		)
		(stroke
			(width 0)
			(type solid)
		)
		(fill yes)
		(layer "F.Cu")
		(net "M_A_CPU1_SA_DQ<21>")
	)
	(gr_poly
		(pts
			(xy 81.134966 -269.410688) (xy 81.088738 -269.313152) (xy 81.05267 -269.277338) (xy 80.866742 -269.463266)
			(xy 80.90281 -269.49908) (xy 81.000092 -269.545308)
		)
		(stroke
			(width 0)
			(type solid)
		)
		(fill yes)
		(layer "F.Cu")
		(net "M_A_CPU1_SA_DQ<30>")
	)
	(gr_poly
		(pts
			(xy 81.136998 -230.067358) (xy 81.172812 -230.03129) (xy 80.986884 -229.845362) (xy 80.95107 -229.88143)
			(xy 80.904842 -229.978712) (xy 81.039462 -230.113586)
		)
		(stroke
			(width 0)
			(type solid)
		)
		(fill yes)
		(layer "F.Cu")
		(net "M_A_CPU1_SB_DQ<18>")
	)
	(gr_poly
		(pts
			(xy 81.137506 -275.25853) (xy 81.101692 -275.222462) (xy 81.004156 -275.176234) (xy 80.869536 -275.310854)
			(xy 80.915764 -275.40839) (xy 80.951832 -275.444204)
		)
		(stroke
			(width 0)
			(type solid)
		)
		(fill yes)
		(layer "F.Cu")
		(net "M_A_CPU1_SA_DQ<20>")
	)
	(gr_poly
		(pts
			(xy 81.13776 -235.94822) (xy 81.183988 -235.850938) (xy 81.049368 -235.716064) (xy 80.951832 -235.762546)
			(xy 80.916018 -235.79836) (xy 81.101946 -235.984288)
		)
		(stroke
			(width 0)
			(type solid)
		)
		(fill yes)
		(layer "F.Cu")
		(net "M_A_CPU1_SB_DQ<8>")
	)
	(gr_poly
		(pts
			(xy 81.146142 -229.213918) (xy 81.18221 -229.178104) (xy 80.996282 -228.992176) (xy 80.960214 -229.02799)
			(xy 80.913986 -229.125526) (xy 81.04886 -229.260146)
		)
		(stroke
			(width 0)
			(type solid)
		)
		(fill yes)
		(layer "F.Cu")
		(net "M_A_CPU1_SB_DQ<19>")
	)
	(gr_poly
		(pts
			(xy 81.147158 -235.095034) (xy 81.193386 -234.997498) (xy 81.058512 -234.862878) (xy 80.96123 -234.909106)
			(xy 80.925162 -234.94492) (xy 81.11109 -235.130848)
		)
		(stroke
			(width 0)
			(type solid)
		)
		(fill yes)
		(layer "F.Cu")
		(net "M_A_CPU1_SB_DQ<9>")
	)
	(gr_poly
		(pts
			(xy 81.148682 -277.823168) (xy 81.076292 -277.743412) (xy 81.031588 -277.719282) (xy 80.907382 -277.951184)
			(xy 80.952086 -277.97506) (xy 81.058766 -277.991062)
		)
		(stroke
			(width 0)
			(type solid)
		)
		(fill yes)
		(layer "F.Cu")
		(net "M_A_CPU1_SA_DQ<19>")
	)
	(gr_poly
		(pts
			(xy 81.151984 -227.0633) (xy 81.188052 -227.027486) (xy 81.002124 -226.841558) (xy 80.966056 -226.877372)
			(xy 80.919828 -226.974908) (xy 81.054702 -227.109528)
		)
		(stroke
			(width 0)
			(type solid)
		)
		(fill yes)
		(layer "F.Cu")
		(net "M_A_CPU1_SB_DQ<20>")
	)
	(gr_poly
		(pts
			(xy 81.167986 -261.638034) (xy 81.132172 -261.601966) (xy 81.034636 -261.555738) (xy 80.900016 -261.690612)
			(xy 80.946244 -261.787894) (xy 80.982058 -261.823962)
		)
		(stroke
			(width 0)
			(type solid)
		)
		(fill yes)
		(layer "F.Cu")
		(net "M_A_CPU1_SA_CB<5>")
	)
	(gr_poly
		(pts
			(xy 81.16824 -281.3812) (xy 81.205578 -281.194256) (xy 81.113122 -281.138884) (xy 81.063338 -281.128978)
			(xy 81.011776 -281.386788) (xy 81.06156 -281.396694)
		)
		(stroke
			(width 0)
			(type solid)
		)
		(fill yes)
		(layer "F.Cu")
		(net "M_A_CPU1_SA_DQ<16>")
	)
	(gr_poly
		(pts
			(xy 81.171288 -223.505776) (xy 81.217516 -223.408494) (xy 81.082896 -223.27362) (xy 80.98536 -223.319848)
			(xy 80.949546 -223.355916) (xy 81.135474 -223.541844)
		)
		(stroke
			(width 0)
			(type solid)
		)
		(fill yes)
		(layer "F.Cu")
		(net "M_A_CPU1_SB_DQ<23>")
	)
	(gr_poly
		(pts
			(xy 81.172558 -277.456392) (xy 81.1276 -277.432262) (xy 81.02092 -277.41626) (xy 80.931004 -277.584154)
			(xy 81.003648 -277.66391) (xy 81.048352 -277.68804)
		)
		(stroke
			(width 0)
			(type solid)
		)
		(fill yes)
		(layer "F.Cu")
		(net "M_A_CPU1_SA_DQ<19>")
	)
	(gr_poly
		(pts
			(xy 81.173828 -279.020524) (xy 81.124044 -279.010618) (xy 81.01711 -279.026112) (xy 80.979772 -279.213056)
			(xy 81.072482 -279.268428) (xy 81.122266 -279.278334)
		)
		(stroke
			(width 0)
			(type solid)
		)
		(fill yes)
		(layer "F.Cu")
		(net "M_A_CPU1_SA_DQ<18>")
	)
	(gr_poly
		(pts
			(xy 81.177384 -262.491728) (xy 81.14157 -262.45566) (xy 81.044034 -262.409432) (xy 80.909414 -262.544052)
			(xy 80.955642 -262.641588) (xy 80.99171 -262.677402)
		)
		(stroke
			(width 0)
			(type solid)
		)
		(fill yes)
		(layer "F.Cu")
		(net "M_A_CPU1_SA_CB<4>")
	)
	(gr_poly
		(pts
			(xy 81.18221 -272.168366) (xy 81.146396 -272.132298) (xy 81.04886 -272.08607) (xy 80.91424 -272.22069)
			(xy 80.960468 -272.318226) (xy 80.996536 -272.35404)
		)
		(stroke
			(width 0)
			(type solid)
		)
		(fill yes)
		(layer "F.Cu")
		(net "M_A_CPU1_SA_DQ<25>")
	)
	(gr_poly
		(pts
			(xy 81.182464 -265.0744) (xy 81.146396 -265.038586) (xy 81.049114 -264.992358) (xy 80.91424 -265.126978)
			(xy 80.960468 -265.224514) (xy 80.996536 -265.260328)
		)
		(stroke
			(width 0)
			(type solid)
		)
		(fill yes)
		(layer "F.Cu")
		(net "M_A_CPU1_SA_CB<1>")
	)
	(gr_poly
		(pts
			(xy 81.18475 -232.544874) (xy 81.230978 -232.447592) (xy 81.096358 -232.312972) (xy 80.998822 -232.3592)
			(xy 80.963008 -232.395014) (xy 81.148936 -232.580942)
		)
		(stroke
			(width 0)
			(type solid)
		)
		(fill yes)
		(layer "F.Cu")
		(net "M_A_CPU1_SB_DQ<12>")
	)
	(gr_poly
		(pts
			(xy 81.191608 -273.021552) (xy 81.15554 -272.985738) (xy 81.058258 -272.93951) (xy 80.923384 -273.07413)
			(xy 80.969612 -273.171666) (xy 81.00568 -273.20748)
		)
		(stroke
			(width 0)
			(type solid)
		)
		(fill yes)
		(layer "F.Cu")
		(net "M_A_CPU1_SA_DQ<24>")
	)
	(gr_poly
		(pts
			(xy 81.191862 -265.92784) (xy 81.155794 -265.892026) (xy 81.058512 -265.845798) (xy 80.923638 -265.980418)
			(xy 80.969866 -266.077954) (xy 81.005934 -266.113768)
		)
		(stroke
			(width 0)
			(type solid)
		)
		(fill yes)
		(layer "F.Cu")
		(net "M_A_CPU1_SA_CB<0>")
	)
	(gr_poly
		(pts
			(xy 81.194148 -231.691434) (xy 81.240376 -231.594152) (xy 81.105756 -231.459278) (xy 81.00822 -231.505506)
			(xy 80.972406 -231.541574) (xy 81.158334 -231.727502)
		)
		(stroke
			(width 0)
			(type solid)
		)
		(fill yes)
		(layer "F.Cu")
		(net "M_A_CPU1_SB_DQ<13>")
	)
	(gr_poly
		(pts
			(xy 81.204308 -230.422196) (xy 81.250536 -230.32466) (xy 81.115662 -230.19004) (xy 81.01838 -230.236268)
			(xy 80.982312 -230.272082) (xy 81.16824 -230.45801)
		)
		(stroke
			(width 0)
			(type solid)
		)
		(fill yes)
		(layer "F.Cu")
		(net "M_A_CPU1_SB_DQ<16>")
	)
	(gr_poly
		(pts
			(xy 81.20507 -274.110704) (xy 81.158842 -274.013422) (xy 81.123028 -273.977354) (xy 80.9371 -274.163282)
			(xy 80.972914 -274.199096) (xy 81.07045 -274.245578)
		)
		(stroke
			(width 0)
			(type solid)
		)
		(fill yes)
		(layer "F.Cu")
		(net "M_A_CPU1_SA_DQ<23>")
	)
	(gr_poly
		(pts
			(xy 81.213452 -229.568756) (xy 81.25968 -229.47122) (xy 81.12506 -229.3366) (xy 81.027524 -229.382828)
			(xy 80.99171 -229.418896) (xy 81.177384 -229.60457)
		)
		(stroke
			(width 0)
			(type solid)
		)
		(fill yes)
		(layer "F.Cu")
		(net "M_A_CPU1_SB_DQ<17>")
	)
	(gr_poly
		(pts
			(xy 81.214468 -274.964398) (xy 81.16824 -274.866862) (xy 81.132172 -274.831048) (xy 80.946498 -275.016722)
			(xy 80.982312 -275.05279) (xy 81.079848 -275.099018)
		)
		(stroke
			(width 0)
			(type solid)
		)
		(fill yes)
		(layer "F.Cu")
		(net "M_A_CPU1_SA_DQ<22>")
	)
	(gr_poly
		(pts
			(xy 81.22031 -279.565354) (xy 81.257648 -279.378664) (xy 81.164938 -279.323292) (xy 81.115154 -279.313132)
			(xy 81.063592 -279.570942) (xy 81.113376 -279.580848)
		)
		(stroke
			(width 0)
			(type solid)
		)
		(fill yes)
		(layer "F.Cu")
		(net "M_A_CPU1_SA_DQ<18>")
	)
	(gr_poly
		(pts
			(xy 81.233264 -226.238054) (xy 81.233264 -226.047554) (xy 81.131664 -226.011486) (xy 81.080864 -226.011486)
			(xy 81.080864 -226.274122) (xy 81.131664 -226.274122)
		)
		(stroke
			(width 0)
			(type solid)
		)
		(fill yes)
		(layer "F.Cu")
		(net "M_A_CPU1_SB_DQ<22>")
	)
	(gr_poly
		(pts
			(xy 81.233264 -225.641154) (xy 81.233264 -225.450654) (xy 81.131664 -225.414586) (xy 81.080864 -225.414586)
			(xy 81.080864 -225.677222) (xy 81.131664 -225.677222)
		)
		(stroke
			(width 0)
			(type solid)
		)
		(fill yes)
		(layer "F.Cu")
		(net "M_A_CPU1_SB_DQ<22>")
	)
	(gr_poly
		(pts
			(xy 81.233264 -225.044254) (xy 81.233264 -224.853754) (xy 81.131664 -224.817686) (xy 81.080864 -224.817686)
			(xy 81.080864 -225.080322) (xy 81.131664 -225.080322)
		)
		(stroke
			(width 0)
			(type solid)
		)
		(fill yes)
		(layer "F.Cu")
		(net "M_A_CPU1_SB_DQ<22>")
	)
	(gr_poly
		(pts
			(xy 81.238852 -280.2509) (xy 81.189068 -280.240994) (xy 81.082388 -280.256488) (xy 81.04505 -280.443432)
			(xy 81.137506 -280.498804) (xy 81.18729 -280.50871)
		)
		(stroke
			(width 0)
			(type solid)
		)
		(fill yes)
		(layer "F.Cu")
		(net "M_A_CPU1_SA_DQ<16>")
	)
	(gr_poly
		(pts
			(xy 81.245456 -261.344664) (xy 81.199228 -261.247128) (xy 81.16316 -261.211314) (xy 80.977486 -261.396988)
			(xy 81.0133 -261.433056) (xy 81.110836 -261.479284)
		)
		(stroke
			(width 0)
			(type solid)
		)
		(fill yes)
		(layer "F.Cu")
		(net "M_A_CPU1_SA_CB<7>")
	)
	(gr_poly
		(pts
			(xy 81.254092 -268.212316) (xy 81.218024 -268.176502) (xy 81.120742 -268.130274) (xy 80.985868 -268.264894)
			(xy 81.032096 -268.36243) (xy 81.068164 -268.398244)
		)
		(stroke
			(width 0)
			(type solid)
		)
		(fill yes)
		(layer "F.Cu")
		(net "M_A_CPU1_SA_DQ<31>")
	)
	(gr_poly
		(pts
			(xy 81.254854 -262.198104) (xy 81.208626 -262.100822) (xy 81.172812 -262.064754) (xy 80.986884 -262.250682)
			(xy 81.022698 -262.28675) (xy 81.120234 -262.332978)
		)
		(stroke
			(width 0)
			(type solid)
		)
		(fill yes)
		(layer "F.Cu")
		(net "M_A_CPU1_SA_CB<6>")
	)
	(gr_poly
		(pts
			(xy 81.25968 -271.874742) (xy 81.213452 -271.777206) (xy 81.177384 -271.741392) (xy 80.991456 -271.92732)
			(xy 81.027524 -271.963134) (xy 81.124806 -272.009362)
		)
		(stroke
			(width 0)
			(type solid)
		)
		(fill yes)
		(layer "F.Cu")
		(net "M_A_CPU1_SA_DQ<27>")
	)
	(gr_poly
		(pts
			(xy 81.259934 -264.78103) (xy 81.213706 -264.683748) (xy 81.177892 -264.64768) (xy 80.991964 -264.833608)
			(xy 81.027778 -264.869676) (xy 81.125314 -264.915904)
		)
		(stroke
			(width 0)
			(type solid)
		)
		(fill yes)
		(layer "F.Cu")
		(net "M_A_CPU1_SA_CB<3>")
	)
	(gr_poly
		(pts
			(xy 81.263744 -269.066264) (xy 81.22793 -269.03045) (xy 81.130394 -268.983968) (xy 80.995774 -269.118842)
			(xy 81.042002 -269.216124) (xy 81.077816 -269.252192)
		)
		(stroke
			(width 0)
			(type solid)
		)
		(fill yes)
		(layer "F.Cu")
		(net "M_A_CPU1_SA_DQ<30>")
	)
	(gr_poly
		(pts
			(xy 81.269078 -272.728182) (xy 81.22285 -272.6309) (xy 81.187036 -272.594832) (xy 81.001108 -272.78076)
			(xy 81.036922 -272.816828) (xy 81.134458 -272.863056)
		)
		(stroke
			(width 0)
			(type solid)
		)
		(fill yes)
		(layer "F.Cu")
		(net "M_A_CPU1_SA_DQ<26>")
	)
	(gr_poly
		(pts
			(xy 81.269332 -265.634724) (xy 81.223104 -265.537188) (xy 81.187036 -265.501374) (xy 81.001362 -265.687048)
			(xy 81.037176 -265.723116) (xy 81.134712 -265.769344)
		)
		(stroke
			(width 0)
			(type solid)
		)
		(fill yes)
		(layer "F.Cu")
		(net "M_A_CPU1_SA_CB<2>")
	)
	(gr_poly
		(pts
			(xy 81.276952 -236.231176) (xy 81.31302 -236.195362) (xy 81.127092 -236.009434) (xy 81.091024 -236.045248)
			(xy 81.044796 -236.142784) (xy 81.17967 -236.277404)
		)
		(stroke
			(width 0)
			(type solid)
		)
		(fill yes)
		(layer "F.Cu")
		(net "M_A_CPU1_SB_DQ<8>")
	)
	(gr_poly
		(pts
			(xy 81.285334 -280.79573) (xy 81.322672 -280.60904) (xy 81.230216 -280.553668) (xy 81.180178 -280.543762)
			(xy 81.12887 -280.801572) (xy 81.178654 -280.811478)
		)
		(stroke
			(width 0)
			(type solid)
		)
		(fill yes)
		(layer "F.Cu")
		(net "M_A_CPU1_SA_DQ<16>")
	)
	(gr_poly
		(pts
			(xy 81.28635 -235.377736) (xy 81.322164 -235.341922) (xy 81.136236 -235.155994) (xy 81.100422 -235.192062)
			(xy 81.054194 -235.289344) (xy 81.188814 -235.423964)
		)
		(stroke
			(width 0)
			(type solid)
		)
		(fill yes)
		(layer "F.Cu")
		(net "M_A_CPU1_SB_DQ<9>")
	)
	(gr_poly
		(pts
			(xy 81.31048 -223.788732) (xy 81.346294 -223.752664) (xy 81.16062 -223.56699) (xy 81.124552 -223.602804)
			(xy 81.078324 -223.70034) (xy 81.212944 -223.83496)
		)
		(stroke
			(width 0)
			(type solid)
		)
		(fill yes)
		(layer "F.Cu")
		(net "M_A_CPU1_SB_DQ<23>")
	)
	(gr_poly
		(pts
			(xy 81.323942 -232.82783) (xy 81.36001 -232.792016) (xy 81.174082 -232.606088) (xy 81.138014 -232.641902)
			(xy 81.091786 -232.739438) (xy 81.22666 -232.874058)
		)
		(stroke
			(width 0)
			(type solid)
		)
		(fill yes)
		(layer "F.Cu")
		(net "M_A_CPU1_SB_DQ<12>")
	)
	(gr_poly
		(pts
			(xy 81.33334 -231.97439) (xy 81.369408 -231.938576) (xy 81.18348 -231.752648) (xy 81.147412 -231.788462)
			(xy 81.101184 -231.885998) (xy 81.236058 -232.020618)
		)
		(stroke
			(width 0)
			(type solid)
		)
		(fill yes)
		(layer "F.Cu")
		(net "M_A_CPU1_SB_DQ<13>")
	)
	(gr_poly
		(pts
			(xy 81.334102 -273.76628) (xy 81.298034 -273.730466) (xy 81.200752 -273.684238) (xy 81.065878 -273.818858)
			(xy 81.112106 -273.916394) (xy 81.148174 -273.952208)
		)
		(stroke
			(width 0)
			(type solid)
		)
		(fill yes)
		(layer "F.Cu")
		(net "M_A_CPU1_SA_DQ<23>")
	)
	(gr_poly
		(pts
			(xy 81.33715 -278.980138) (xy 81.374488 -278.793194) (xy 81.282032 -278.737822) (xy 81.232248 -278.727916)
			(xy 81.180686 -278.985726) (xy 81.23047 -278.995632)
		)
		(stroke
			(width 0)
			(type solid)
		)
		(fill yes)
		(layer "F.Cu")
		(net "M_A_CPU1_SA_DQ<18>")
	)
	(gr_poly
		(pts
			(xy 81.34096 -268.77264) (xy 81.294732 -268.675104) (xy 81.258664 -268.63929) (xy 81.07299 -268.824964)
			(xy 81.108804 -268.861032) (xy 81.20634 -268.90726)
		)
		(stroke
			(width 0)
			(type solid)
		)
		(fill yes)
		(layer "F.Cu")
		(net "M_A_CPU1_SA_DQ<29>")
	)
	(gr_poly
		(pts
			(xy 81.343246 -274.619974) (xy 81.307432 -274.58416) (xy 81.209896 -274.537678) (xy 81.075276 -274.672552)
			(xy 81.121504 -274.769834) (xy 81.157318 -274.805902)
		)
		(stroke
			(width 0)
			(type solid)
		)
		(fill yes)
		(layer "F.Cu")
		(net "M_A_CPU1_SA_DQ<22>")
	)
	(gr_poly
		(pts
			(xy 81.3435 -230.704898) (xy 81.379314 -230.669084) (xy 81.193386 -230.483156) (xy 81.157572 -230.519224)
			(xy 81.111344 -230.616506) (xy 81.245964 -230.751126)
		)
		(stroke
			(width 0)
			(type solid)
		)
		(fill yes)
		(layer "F.Cu")
		(net "M_A_CPU1_SB_DQ<16>")
	)
	(gr_poly
		(pts
			(xy 81.34604 -249.270266) (xy 81.309972 -249.168666) (xy 81.119472 -249.168666) (xy 81.08315 -249.270266)
			(xy 81.08315 -249.321066) (xy 81.34604 -249.321066)
		)
		(stroke
			(width 0)
			(type solid)
		)
		(fill yes)
		(layer "F.Cu")
		(net "M_A_CPU1_SB_CA<0>")
	)
	(gr_poly
		(pts
			(xy 81.34604 -248.660412) (xy 81.309972 -248.558812) (xy 81.119472 -248.558812) (xy 81.08315 -248.660412)
			(xy 81.08315 -248.711212) (xy 81.34604 -248.711212)
		)
		(stroke
			(width 0)
			(type solid)
		)
		(fill yes)
		(layer "F.Cu")
		(net "M_A_CPU1_SB_CA<2>")
	)
	(gr_poly
		(pts
			(xy 81.34604 -248.355612) (xy 81.309972 -248.254012) (xy 81.119472 -248.254012) (xy 81.08315 -248.355612)
			(xy 81.08315 -248.406412) (xy 81.34604 -248.406412)
		)
		(stroke
			(width 0)
			(type solid)
		)
		(fill yes)
		(layer "F.Cu")
		(net "M_A_CPU1_SB_CA<3>")
	)
	(gr_poly
		(pts
			(xy 81.34604 -248.050812) (xy 81.309972 -247.949212) (xy 81.119472 -247.949212) (xy 81.08315 -248.050812)
			(xy 81.08315 -248.101612) (xy 81.34604 -248.101612)
		)
		(stroke
			(width 0)
			(type solid)
		)
		(fill yes)
		(layer "F.Cu")
		(net "M_A_CPU1_SB_CA<4>")
	)
	(gr_poly
		(pts
			(xy 81.34604 -247.746012) (xy 81.309972 -247.644412) (xy 81.119472 -247.644412) (xy 81.08315 -247.746012)
			(xy 81.08315 -247.796812) (xy 81.34604 -247.796812)
		)
		(stroke
			(width 0)
			(type solid)
		)
		(fill yes)
		(layer "F.Cu")
		(net "M_A_CPU1_SB_CA<5>")
	)
	(gr_poly
		(pts
			(xy 81.350612 -269.626334) (xy 81.304384 -269.528798) (xy 81.268316 -269.492984) (xy 81.082388 -269.678912)
			(xy 81.118456 -269.714726) (xy 81.215738 -269.760954)
		)
		(stroke
			(width 0)
			(type solid)
		)
		(fill yes)
		(layer "F.Cu")
		(net "M_A_CPU1_SA_DQ<28>")
	)
	(gr_poly
		(pts
			(xy 81.352644 -229.851712) (xy 81.388458 -229.815644) (xy 81.20253 -229.629716) (xy 81.166716 -229.665784)
			(xy 81.120488 -229.763066) (xy 81.255108 -229.89794)
		)
		(stroke
			(width 0)
			(type solid)
		)
		(fill yes)
		(layer "F.Cu")
		(net "M_A_CPU1_SB_DQ<17>")
	)
	(gr_poly
		(pts
			(xy 81.353406 -235.732574) (xy 81.399634 -235.635292) (xy 81.265014 -235.500418) (xy 81.167478 -235.5469)
			(xy 81.131664 -235.582714) (xy 81.317592 -235.768642)
		)
		(stroke
			(width 0)
			(type solid)
		)
		(fill yes)
		(layer "F.Cu")
		(net "M_A_CPU1_SB_DQ<10>")
	)
	(gr_poly
		(pts
			(xy 81.355946 -279.665684) (xy 81.305908 -279.655778) (xy 81.199228 -279.671272) (xy 81.16189 -279.858216)
			(xy 81.2546 -279.913588) (xy 81.304384 -279.923494)
		)
		(stroke
			(width 0)
			(type solid)
		)
		(fill yes)
		(layer "F.Cu")
		(net "M_A_CPU1_SA_DQ<16>")
	)
	(gr_poly
		(pts
			(xy 81.362804 -234.879388) (xy 81.409032 -234.781852) (xy 81.274158 -234.647232) (xy 81.176876 -234.69346)
			(xy 81.140808 -234.729274) (xy 81.326736 -234.915202)
		)
		(stroke
			(width 0)
			(type solid)
		)
		(fill yes)
		(layer "F.Cu")
		(net "M_A_CPU1_SB_DQ<11>")
	)
	(gr_poly
		(pts
			(xy 81.367884 -226.847654) (xy 81.403698 -226.811586) (xy 81.21777 -226.625658) (xy 81.181956 -226.661726)
			(xy 81.135728 -226.759008) (xy 81.270348 -226.893882)
		)
		(stroke
			(width 0)
			(type solid)
		)
		(fill yes)
		(layer "F.Cu")
		(net "M_A_CPU1_SB_DQ<22>")
	)
	(gr_poly
		(pts
			(xy 81.374234 -261.00024) (xy 81.33842 -260.964172) (xy 81.240884 -260.917944) (xy 81.106264 -261.052818)
			(xy 81.152492 -261.1501) (xy 81.188306 -261.186168)
		)
		(stroke
			(width 0)
			(type solid)
		)
		(fill yes)
		(layer "F.Cu")
		(net "M_A_CPU1_SA_CB<7>")
	)
	(gr_poly
		(pts
			(xy 81.378806 -259.719826) (xy 81.378806 -259.669026) (xy 81.115916 -259.669026) (xy 81.115916 -259.719826)
			(xy 81.151984 -259.821426) (xy 81.342484 -259.821426)
		)
		(stroke
			(width 0)
			(type solid)
		)
		(fill yes)
		(layer "F.Cu")
		(net "M_A_CPU1_SA_CS_N<0>")
	)
	(gr_poly
		(pts
			(xy 81.378806 -259.415026) (xy 81.378806 -259.364226) (xy 81.115916 -259.364226) (xy 81.115916 -259.415026)
			(xy 81.151984 -259.516626) (xy 81.342484 -259.516626)
		)
		(stroke
			(width 0)
			(type solid)
		)
		(fill yes)
		(layer "F.Cu")
		(net "M_A_CPU1_SA_CS_N<2>")
	)
	(gr_poly
		(pts
			(xy 81.378806 -259.110226) (xy 81.378806 -259.059426) (xy 81.115916 -259.059426) (xy 81.115916 -259.110226)
			(xy 81.151984 -259.211826) (xy 81.342484 -259.211826)
		)
		(stroke
			(width 0)
			(type solid)
		)
		(fill yes)
		(layer "F.Cu")
		(net "M_A_CPU1_SA_CS_N<3>")
	)
	(gr_poly
		(pts
			(xy 81.378806 -258.805426) (xy 81.378806 -258.754626) (xy 81.115916 -258.754626) (xy 81.115916 -258.805426)
			(xy 81.151984 -258.907026) (xy 81.342484 -258.907026)
		)
		(stroke
			(width 0)
			(type solid)
		)
		(fill yes)
		(layer "F.Cu")
		(net "M_A_CPU1_SA_CS_N<1>")
	)
	(gr_poly
		(pts
			(xy 81.378806 -258.500626) (xy 81.378806 -258.449826) (xy 81.115916 -258.449826) (xy 81.115916 -258.500626)
			(xy 81.151984 -258.602226) (xy 81.342484 -258.602226)
		)
		(stroke
			(width 0)
			(type solid)
		)
		(fill yes)
		(layer "F.Cu")
		(net "M_A_CPU1_SA_CA<0>")
	)
	(gr_poly
		(pts
			(xy 81.378806 -258.195826) (xy 81.378806 -258.145026) (xy 81.115916 -258.145026) (xy 81.115916 -258.195826)
			(xy 81.151984 -258.297426) (xy 81.342484 -258.297426)
		)
		(stroke
			(width 0)
			(type solid)
		)
		(fill yes)
		(layer "F.Cu")
		(net "M_A_CPU1_SA_CA<1>")
	)
	(gr_poly
		(pts
			(xy 81.378806 -257.891026) (xy 81.378806 -257.840226) (xy 81.115916 -257.840226) (xy 81.115916 -257.891026)
			(xy 81.151984 -257.992626) (xy 81.342484 -257.992626)
		)
		(stroke
			(width 0)
			(type solid)
		)
		(fill yes)
		(layer "F.Cu")
		(net "M_A_CPU1_SA_CA<2>")
	)
	(gr_poly
		(pts
			(xy 81.378806 -257.586226) (xy 81.378806 -257.535426) (xy 81.115916 -257.535426) (xy 81.115916 -257.586226)
			(xy 81.151984 -257.687826) (xy 81.342484 -257.687826)
		)
		(stroke
			(width 0)
			(type solid)
		)
		(fill yes)
		(layer "F.Cu")
		(net "M_A_CPU1_SA_CA<3>")
	)
	(gr_poly
		(pts
			(xy 81.378806 -257.281426) (xy 81.378806 -257.230626) (xy 81.115916 -257.230626) (xy 81.115916 -257.281426)
			(xy 81.151984 -257.383026) (xy 81.342484 -257.383026)
		)
		(stroke
			(width 0)
			(type solid)
		)
		(fill yes)
		(layer "F.Cu")
		(net "M_A_CPU1_SA_CA<4>")
	)
	(gr_poly
		(pts
			(xy 81.378806 -256.976626) (xy 81.378806 -256.925826) (xy 81.115916 -256.925826) (xy 81.115916 -256.976626)
			(xy 81.151984 -257.078226) (xy 81.342484 -257.078226)
		)
		(stroke
			(width 0)
			(type solid)
		)
		(fill yes)
		(layer "F.Cu")
		(net "M_A_CPU1_SA_CA<5>")
	)
	(gr_poly
		(pts
			(xy 81.378806 -256.671826) (xy 81.378806 -256.621026) (xy 81.115916 -256.621026) (xy 81.115916 -256.671826)
			(xy 81.151984 -256.773426) (xy 81.342484 -256.773426)
		)
		(stroke
			(width 0)
			(type solid)
		)
		(fill yes)
		(layer "F.Cu")
		(net "M_A_CPU1_SA_CA<6>")
	)
	(gr_poly
		(pts
			(xy 81.378806 -256.367026) (xy 81.378806 -256.316226) (xy 81.115916 -256.316226) (xy 81.115916 -256.367026)
			(xy 81.151984 -256.468626) (xy 81.342484 -256.468626)
		)
		(stroke
			(width 0)
			(type solid)
		)
		(fill yes)
		(layer "F.Cu")
		(net "M_A_CPU1_SA_PAR")
	)
	(gr_poly
		(pts
			(xy 81.383886 -261.85368) (xy 81.347818 -261.817866) (xy 81.250536 -261.771638) (xy 81.115662 -261.906258)
			(xy 81.16189 -262.003794) (xy 81.197958 -262.039608)
		)
		(stroke
			(width 0)
			(type solid)
		)
		(fill yes)
		(layer "F.Cu")
		(net "M_A_CPU1_SA_CB<6>")
	)
	(gr_poly
		(pts
			(xy 81.385664 -225.712782) (xy 81.334864 -225.712782) (xy 81.233264 -225.749104) (xy 81.233264 -225.939604)
			(xy 81.334864 -225.975926) (xy 81.385664 -225.975926)
		)
		(stroke
			(width 0)
			(type solid)
		)
		(fill yes)
		(layer "F.Cu")
		(net "M_A_CPU1_SB_DQ<21>")
	)
	(gr_poly
		(pts
			(xy 81.385664 -225.115882) (xy 81.334864 -225.115882) (xy 81.233264 -225.152204) (xy 81.233264 -225.342704)
			(xy 81.334864 -225.379026) (xy 81.385664 -225.379026)
		)
		(stroke
			(width 0)
			(type solid)
		)
		(fill yes)
		(layer "F.Cu")
		(net "M_A_CPU1_SB_DQ<21>")
	)
	(gr_poly
		(pts
			(xy 81.385664 -224.518982) (xy 81.334864 -224.518982) (xy 81.233264 -224.555304) (xy 81.233264 -224.745804)
			(xy 81.334864 -224.782126) (xy 81.385664 -224.782126)
		)
		(stroke
			(width 0)
			(type solid)
		)
		(fill yes)
		(layer "F.Cu")
		(net "M_A_CPU1_SB_DQ<21>")
	)
	(gr_poly
		(pts
			(xy 81.388458 -271.530318) (xy 81.352644 -271.49425) (xy 81.255108 -271.448022) (xy 81.120488 -271.582896)
			(xy 81.166716 -271.680178) (xy 81.20253 -271.716246)
		)
		(stroke
			(width 0)
			(type solid)
		)
		(fill yes)
		(layer "F.Cu")
		(net "M_A_CPU1_SA_DQ<27>")
	)
	(gr_poly
		(pts
			(xy 81.388712 -264.43686) (xy 81.352898 -264.400792) (xy 81.255362 -264.354564) (xy 81.120742 -264.489184)
			(xy 81.16697 -264.58672) (xy 81.203038 -264.622534)
		)
		(stroke
			(width 0)
			(type solid)
		)
		(fill yes)
		(layer "F.Cu")
		(net "M_A_CPU1_SA_CB<3>")
	)
	(gr_poly
		(pts
			(xy 81.397856 -272.384012) (xy 81.362042 -272.347944) (xy 81.264506 -272.301716) (xy 81.129886 -272.436336)
			(xy 81.176114 -272.533872) (xy 81.212182 -272.569686)
		)
		(stroke
			(width 0)
			(type solid)
		)
		(fill yes)
		(layer "F.Cu")
		(net "M_A_CPU1_SA_DQ<26>")
	)
	(gr_poly
		(pts
			(xy 81.39811 -265.2903) (xy 81.362296 -265.254232) (xy 81.26476 -265.208004) (xy 81.13014 -265.342878)
			(xy 81.176368 -265.44016) (xy 81.212182 -265.476228)
		)
		(stroke
			(width 0)
			(type solid)
		)
		(fill yes)
		(layer "F.Cu")
		(net "M_A_CPU1_SA_CB<2>")
	)
	(gr_poly
		(pts
			(xy 81.40065 -232.329228) (xy 81.446878 -232.231692) (xy 81.312258 -232.097072) (xy 81.214722 -232.1433)
			(xy 81.178908 -232.179368) (xy 81.364582 -232.365042)
		)
		(stroke
			(width 0)
			(type solid)
		)
		(fill yes)
		(layer "F.Cu")
		(net "M_A_CPU1_SB_DQ<14>")
	)
	(gr_poly
		(pts
			(xy 81.400904 -217.801698) (xy 81.350104 -217.801698) (xy 81.248504 -217.837766) (xy 81.248504 -218.028266)
			(xy 81.350104 -218.064334) (xy 81.400904 -218.064334)
		)
		(stroke
			(width 0)
			(type solid)
		)
		(fill yes)
		(layer "F.Cu")
		(net "M_A_CPU1_SB_DQ<24>")
	)
	(gr_poly
		(pts
			(xy 81.400904 -217.204798) (xy 81.350104 -217.204798) (xy 81.248504 -217.240866) (xy 81.248504 -217.431366)
			(xy 81.350104 -217.467434) (xy 81.400904 -217.467434)
		)
		(stroke
			(width 0)
			(type solid)
		)
		(fill yes)
		(layer "F.Cu")
		(net "M_A_CPU1_SB_DQ<24>")
	)
	(gr_poly
		(pts
			(xy 81.400904 -216.607898) (xy 81.350104 -216.607898) (xy 81.248504 -216.643966) (xy 81.248504 -216.834466)
			(xy 81.350104 -216.870534) (xy 81.400904 -216.870534)
		)
		(stroke
			(width 0)
			(type solid)
		)
		(fill yes)
		(layer "F.Cu")
		(net "M_A_CPU1_SB_DQ<24>")
	)
	(gr_poly
		(pts
			(xy 81.402428 -280.210514) (xy 81.439766 -280.023824) (xy 81.347056 -279.968198) (xy 81.297272 -279.958292)
			(xy 81.24571 -280.216102) (xy 81.295494 -280.226008)
		)
		(stroke
			(width 0)
			(type solid)
		)
		(fill yes)
		(layer "F.Cu")
		(net "M_A_CPU1_SA_DQ<16>")
	)
	(gr_poly
		(pts
			(xy 81.409794 -231.475788) (xy 81.456022 -231.378506) (xy 81.321402 -231.243632) (xy 81.223866 -231.28986)
			(xy 81.188052 -231.325928) (xy 81.37398 -231.511856)
		)
		(stroke
			(width 0)
			(type solid)
		)
		(fill yes)
		(layer "F.Cu")
		(net "M_A_CPU1_SB_DQ<15>")
	)
	(gr_poly
		(pts
			(xy 81.417922 -277.96744) (xy 81.345278 -277.887684) (xy 81.300574 -277.863554) (xy 81.176368 -278.095202)
			(xy 81.221072 -278.119332) (xy 81.327752 -278.135334)
		)
		(stroke
			(width 0)
			(type solid)
		)
		(fill yes)
		(layer "F.Cu")
		(net "M_A_CPU1_SA_DQ<17>")
	)
	(gr_poly
		(pts
			(xy 81.419954 -230.20655) (xy 81.466182 -230.109014) (xy 81.331308 -229.974394) (xy 81.234026 -230.020622)
			(xy 81.197958 -230.056436) (xy 81.383886 -230.242364)
		)
		(stroke
			(width 0)
			(type solid)
		)
		(fill yes)
		(layer "F.Cu")
		(net "M_A_CPU1_SB_DQ<18>")
	)
	(gr_poly
		(pts
			(xy 81.420716 -274.326604) (xy 81.374488 -274.229068) (xy 81.338674 -274.193254) (xy 81.152746 -274.378928)
			(xy 81.188814 -274.414996) (xy 81.286096 -274.461224)
		)
		(stroke
			(width 0)
			(type solid)
		)
		(fill yes)
		(layer "F.Cu")
		(net "M_A_CPU1_SA_DQ<21>")
	)
	(gr_poly
		(pts
			(xy 81.429098 -229.35311) (xy 81.475326 -229.255574) (xy 81.340706 -229.120954) (xy 81.24317 -229.167182)
			(xy 81.207356 -229.20325) (xy 81.39303 -229.388924)
		)
		(stroke
			(width 0)
			(type solid)
		)
		(fill yes)
		(layer "F.Cu")
		(net "M_A_CPU1_SB_DQ<19>")
	)
	(gr_poly
		(pts
			(xy 81.430876 -275.180806) (xy 81.384648 -275.08327) (xy 81.34858 -275.047456) (xy 81.162652 -275.233384)
			(xy 81.19872 -275.269198) (xy 81.296002 -275.315426)
		)
		(stroke
			(width 0)
			(type solid)
		)
		(fill yes)
		(layer "F.Cu")
		(net "M_A_CPU1_SA_DQ<20>")
	)
	(gr_poly
		(pts
			(xy 81.43494 -227.202492) (xy 81.481168 -227.104956) (xy 81.346548 -226.970336) (xy 81.249012 -227.016564)
			(xy 81.213198 -227.052632) (xy 81.399126 -227.23856)
		)
		(stroke
			(width 0)
			(type solid)
		)
		(fill yes)
		(layer "F.Cu")
		(net "M_A_CPU1_SB_DQ<20>")
	)
	(gr_poly
		(pts
			(xy 81.461102 -261.56031) (xy 81.414874 -261.462774) (xy 81.37906 -261.42696) (xy 81.193132 -261.612888)
			(xy 81.228946 -261.648702) (xy 81.326482 -261.69493)
		)
		(stroke
			(width 0)
			(type solid)
		)
		(fill yes)
		(layer "F.Cu")
		(net "M_A_CPU1_SA_CB<5>")
	)
	(gr_poly
		(pts
			(xy 81.469738 -268.428216) (xy 81.433924 -268.392148) (xy 81.336388 -268.34592) (xy 81.201768 -268.480794)
			(xy 81.247996 -268.578076) (xy 81.28381 -268.614144)
		)
		(stroke
			(width 0)
			(type solid)
		)
		(fill yes)
		(layer "F.Cu")
		(net "M_A_CPU1_SA_DQ<29>")
	)
	(gr_poly
		(pts
			(xy 81.470754 -262.414004) (xy 81.424526 -262.316468) (xy 81.388458 -262.280654) (xy 81.20253 -262.466582)
			(xy 81.238598 -262.502396) (xy 81.33588 -262.548624)
		)
		(stroke
			(width 0)
			(type solid)
		)
		(fill yes)
		(layer "F.Cu")
		(net "M_A_CPU1_SA_CB<4>")
	)
	(gr_poly
		(pts
			(xy 81.472786 -279.080468) (xy 81.423002 -279.070308) (xy 81.316322 -279.086056) (xy 81.278984 -279.272746)
			(xy 81.37144 -279.328118) (xy 81.421224 -279.338278)
		)
		(stroke
			(width 0)
			(type solid)
		)
		(fill yes)
		(layer "F.Cu")
		(net "M_A_CPU1_SA_DQ<16>")
	)
	(gr_poly
		(pts
			(xy 81.47558 -272.090642) (xy 81.429352 -271.993106) (xy 81.393284 -271.957292) (xy 81.207356 -272.14322)
			(xy 81.243424 -272.179034) (xy 81.340706 -272.225262)
		)
		(stroke
			(width 0)
			(type solid)
		)
		(fill yes)
		(layer "F.Cu")
		(net "M_A_CPU1_SA_DQ<25>")
	)
	(gr_poly
		(pts
			(xy 81.47558 -264.996676) (xy 81.429352 -264.899394) (xy 81.393538 -264.863326) (xy 81.20761 -265.049254)
			(xy 81.243424 -265.085322) (xy 81.34096 -265.13155)
		)
		(stroke
			(width 0)
			(type solid)
		)
		(fill yes)
		(layer "F.Cu")
		(net "M_A_CPU1_SA_CB<1>")
	)
	(gr_poly
		(pts
			(xy 81.47939 -269.28191) (xy 81.443576 -269.246096) (xy 81.34604 -269.199614) (xy 81.21142 -269.334488)
			(xy 81.257648 -269.43177) (xy 81.293462 -269.467838)
		)
		(stroke
			(width 0)
			(type solid)
		)
		(fill yes)
		(layer "F.Cu")
		(net "M_A_CPU1_SA_DQ<28>")
	)
	(gr_poly
		(pts
			(xy 81.484724 -272.943828) (xy 81.438496 -272.846546) (xy 81.402682 -272.810478) (xy 81.216754 -272.996406)
			(xy 81.252568 -273.032474) (xy 81.350104 -273.078702)
		)
		(stroke
			(width 0)
			(type solid)
		)
		(fill yes)
		(layer "F.Cu")
		(net "M_A_CPU1_SA_DQ<24>")
	)
	(gr_poly
		(pts
			(xy 81.484978 -265.85037) (xy 81.43875 -265.752834) (xy 81.402682 -265.71702) (xy 81.217008 -265.902694)
			(xy 81.252822 -265.938762) (xy 81.350358 -265.98499)
		)
		(stroke
			(width 0)
			(type solid)
		)
		(fill yes)
		(layer "F.Cu")
		(net "M_A_CPU1_SA_CB<0>")
	)
	(gr_poly
		(pts
			(xy 81.490312 -293.57955) (xy 81.439512 -293.57955) (xy 81.337912 -293.615872) (xy 81.337912 -293.806372)
			(xy 81.439512 -293.84244) (xy 81.490312 -293.84244)
		)
		(stroke
			(width 0)
			(type solid)
		)
		(fill yes)
		(layer "F.Cu")
		(net "M_A_CPU1_SA_DQ<7>")
	)
	(gr_poly
		(pts
			(xy 81.490312 -292.98265) (xy 81.439512 -292.98265) (xy 81.337912 -293.018972) (xy 81.337912 -293.209472)
			(xy 81.439512 -293.24554) (xy 81.490312 -293.24554)
		)
		(stroke
			(width 0)
			(type solid)
		)
		(fill yes)
		(layer "F.Cu")
		(net "M_A_CPU1_SA_DQ<7>")
	)
	(gr_poly
		(pts
			(xy 81.490312 -292.38575) (xy 81.439512 -292.38575) (xy 81.337912 -292.422072) (xy 81.337912 -292.612572)
			(xy 81.439512 -292.64864) (xy 81.490312 -292.64864)
		)
		(stroke
			(width 0)
			(type solid)
		)
		(fill yes)
		(layer "F.Cu")
		(net "M_A_CPU1_SA_DQ<7>")
	)
	(gr_poly
		(pts
			(xy 81.490312 -291.78885) (xy 81.439512 -291.78885) (xy 81.337912 -291.825172) (xy 81.337912 -292.015672)
			(xy 81.439512 -292.05174) (xy 81.490312 -292.05174)
		)
		(stroke
			(width 0)
			(type solid)
		)
		(fill yes)
		(layer "F.Cu")
		(net "M_A_CPU1_SA_DQ<7>")
	)
	(gr_poly
		(pts
			(xy 81.490312 -291.19195) (xy 81.439512 -291.19195) (xy 81.337912 -291.228272) (xy 81.337912 -291.418772)
			(xy 81.439512 -291.45484) (xy 81.490312 -291.45484)
		)
		(stroke
			(width 0)
			(type solid)
		)
		(fill yes)
		(layer "F.Cu")
		(net "M_A_CPU1_SA_DQ<7>")
	)
	(gr_poly
		(pts
			(xy 81.490312 -290.59505) (xy 81.439512 -290.59505) (xy 81.337912 -290.631372) (xy 81.337912 -290.821872)
			(xy 81.439512 -290.85794) (xy 81.490312 -290.85794)
		)
		(stroke
			(width 0)
			(type solid)
		)
		(fill yes)
		(layer "F.Cu")
		(net "M_A_CPU1_SA_DQ<7>")
	)
	(gr_poly
		(pts
			(xy 81.490312 -289.99815) (xy 81.439512 -289.99815) (xy 81.337912 -290.034472) (xy 81.337912 -290.224972)
			(xy 81.439512 -290.26104) (xy 81.490312 -290.26104)
		)
		(stroke
			(width 0)
			(type solid)
		)
		(fill yes)
		(layer "F.Cu")
		(net "M_A_CPU1_SA_DQ<7>")
	)
	(gr_poly
		(pts
			(xy 81.490312 -289.40125) (xy 81.439512 -289.40125) (xy 81.337912 -289.437572) (xy 81.337912 -289.628072)
			(xy 81.439512 -289.66414) (xy 81.490312 -289.66414)
		)
		(stroke
			(width 0)
			(type solid)
		)
		(fill yes)
		(layer "F.Cu")
		(net "M_A_CPU1_SA_DQ<7>")
	)
	(gr_poly
		(pts
			(xy 81.490312 -288.80435) (xy 81.439512 -288.80435) (xy 81.337912 -288.840672) (xy 81.337912 -289.031172)
			(xy 81.439512 -289.06724) (xy 81.490312 -289.06724)
		)
		(stroke
			(width 0)
			(type solid)
		)
		(fill yes)
		(layer "F.Cu")
		(net "M_A_CPU1_SA_DQ<7>")
	)
	(gr_poly
		(pts
			(xy 81.490312 -288.20745) (xy 81.439512 -288.20745) (xy 81.337912 -288.243772) (xy 81.337912 -288.434272)
			(xy 81.439512 -288.47034) (xy 81.490312 -288.47034)
		)
		(stroke
			(width 0)
			(type solid)
		)
		(fill yes)
		(layer "F.Cu")
		(net "M_A_CPU1_SA_DQ<7>")
	)
	(gr_poly
		(pts
			(xy 81.490312 -287.61055) (xy 81.439512 -287.61055) (xy 81.337912 -287.646872) (xy 81.337912 -287.837372)
			(xy 81.439512 -287.87344) (xy 81.490312 -287.87344)
		)
		(stroke
			(width 0)
			(type solid)
		)
		(fill yes)
		(layer "F.Cu")
		(net "M_A_CPU1_SA_DQ<7>")
	)
	(gr_poly
		(pts
			(xy 81.490312 -287.01365) (xy 81.439512 -287.01365) (xy 81.337912 -287.049972) (xy 81.337912 -287.240472)
			(xy 81.439512 -287.27654) (xy 81.490312 -287.27654)
		)
		(stroke
			(width 0)
			(type solid)
		)
		(fill yes)
		(layer "F.Cu")
		(net "M_A_CPU1_SA_DQ<7>")
	)
	(gr_poly
		(pts
			(xy 81.490312 -286.41675) (xy 81.439512 -286.41675) (xy 81.337912 -286.453072) (xy 81.337912 -286.643572)
			(xy 81.439512 -286.67964) (xy 81.490312 -286.67964)
		)
		(stroke
			(width 0)
			(type solid)
		)
		(fill yes)
		(layer "F.Cu")
		(net "M_A_CPU1_SA_DQ<7>")
	)
	(gr_poly
		(pts
			(xy 81.490312 -285.81985) (xy 81.439512 -285.81985) (xy 81.337912 -285.856172) (xy 81.337912 -286.046672)
			(xy 81.439512 -286.08274) (xy 81.490312 -286.08274)
		)
		(stroke
			(width 0)
			(type solid)
		)
		(fill yes)
		(layer "F.Cu")
		(net "M_A_CPU1_SA_DQ<7>")
	)
	(gr_poly
		(pts
			(xy 81.490312 -285.22295) (xy 81.439512 -285.22295) (xy 81.337912 -285.259272) (xy 81.337912 -285.449772)
			(xy 81.439512 -285.48584) (xy 81.490312 -285.48584)
		)
		(stroke
			(width 0)
			(type solid)
		)
		(fill yes)
		(layer "F.Cu")
		(net "M_A_CPU1_SA_DQ<7>")
	)
	(gr_poly
		(pts
			(xy 81.490312 -284.62605) (xy 81.439512 -284.62605) (xy 81.337912 -284.662372) (xy 81.337912 -284.852872)
			(xy 81.439512 -284.88894) (xy 81.490312 -284.88894)
		)
		(stroke
			(width 0)
			(type solid)
		)
		(fill yes)
		(layer "F.Cu")
		(net "M_A_CPU1_SA_DQ<7>")
	)
	(gr_poly
		(pts
			(xy 81.490312 -284.02915) (xy 81.439512 -284.02915) (xy 81.337912 -284.065472) (xy 81.337912 -284.255972)
			(xy 81.439512 -284.29204) (xy 81.490312 -284.29204)
		)
		(stroke
			(width 0)
			(type solid)
		)
		(fill yes)
		(layer "F.Cu")
		(net "M_A_CPU1_SA_DQ<7>")
	)
	(gr_poly
		(pts
			(xy 81.490312 -283.43225) (xy 81.439512 -283.43225) (xy 81.337912 -283.468572) (xy 81.337912 -283.659072)
			(xy 81.439512 -283.69514) (xy 81.490312 -283.69514)
		)
		(stroke
			(width 0)
			(type solid)
		)
		(fill yes)
		(layer "F.Cu")
		(net "M_A_CPU1_SA_DQ<7>")
	)
	(gr_poly
		(pts
			(xy 81.490312 -282.83535) (xy 81.439512 -282.83535) (xy 81.337912 -282.871672) (xy 81.337912 -283.062172)
			(xy 81.439512 -283.09824) (xy 81.490312 -283.09824)
		)
		(stroke
			(width 0)
			(type solid)
		)
		(fill yes)
		(layer "F.Cu")
		(net "M_A_CPU1_SA_DQ<7>")
	)
	(gr_poly
		(pts
			(xy 81.492598 -236.01553) (xy 81.528666 -235.979716) (xy 81.342738 -235.793788) (xy 81.30667 -235.829602)
			(xy 81.260442 -235.927138) (xy 81.395316 -236.061758)
		)
		(stroke
			(width 0)
			(type solid)
		)
		(fill yes)
		(layer "F.Cu")
		(net "M_A_CPU1_SB_DQ<10>")
	)
	(gr_poly
		(pts
			(xy 81.501996 -235.16209) (xy 81.53781 -235.126276) (xy 81.351882 -234.940348) (xy 81.316068 -234.976416)
			(xy 81.26984 -235.073698) (xy 81.40446 -235.208318)
		)
		(stroke
			(width 0)
			(type solid)
		)
		(fill yes)
		(layer "F.Cu")
		(net "M_A_CPU1_SB_DQ<11>")
	)
	(gr_poly
		(pts
			(xy 81.519268 -279.625298) (xy 81.556606 -279.438354) (xy 81.46415 -279.382982) (xy 81.414366 -279.373076)
			(xy 81.362804 -279.630886) (xy 81.412588 -279.640792)
		)
		(stroke
			(width 0)
			(type solid)
		)
		(fill yes)
		(layer "F.Cu")
		(net "M_A_CPU1_SA_DQ<16>")
	)
	(gr_poly
		(pts
			(xy 81.538064 -225.641154) (xy 81.538064 -225.450654) (xy 81.436464 -225.414586) (xy 81.385664 -225.414586)
			(xy 81.385664 -225.677222) (xy 81.436464 -225.677222)
		)
		(stroke
			(width 0)
			(type solid)
		)
		(fill yes)
		(layer "F.Cu")
		(net "M_A_CPU1_SB_DQ<21>")
	)
	(gr_poly
		(pts
			(xy 81.538064 -225.044254) (xy 81.538064 -224.853754) (xy 81.436464 -224.817686) (xy 81.385664 -224.817686)
			(xy 81.385664 -225.080322) (xy 81.436464 -225.080322)
		)
		(stroke
			(width 0)
			(type solid)
		)
		(fill yes)
		(layer "F.Cu")
		(net "M_A_CPU1_SB_DQ<21>")
	)
	(gr_poly
		(pts
			(xy 81.539842 -232.612184) (xy 81.575656 -232.576116) (xy 81.389728 -232.390188) (xy 81.353914 -232.426256)
			(xy 81.307686 -232.523538) (xy 81.442306 -232.658412)
		)
		(stroke
			(width 0)
			(type solid)
		)
		(fill yes)
		(layer "F.Cu")
		(net "M_A_CPU1_SB_DQ<14>")
	)
	(gr_poly
		(pts
			(xy 81.547208 -268.134592) (xy 81.50098 -268.03731) (xy 81.465166 -268.001242) (xy 81.279238 -268.18717)
			(xy 81.315052 -268.223238) (xy 81.412588 -268.269466)
		)
		(stroke
			(width 0)
			(type solid)
		)
		(fill yes)
		(layer "F.Cu")
		(net "M_A_CPU1_SA_DQ<31>")
	)
	(gr_poly
		(pts
			(xy 81.548986 -231.758744) (xy 81.585054 -231.72293) (xy 81.399126 -231.537002) (xy 81.363058 -231.572816)
			(xy 81.31683 -231.670352) (xy 81.451704 -231.804972)
		)
		(stroke
			(width 0)
			(type solid)
		)
		(fill yes)
		(layer "F.Cu")
		(net "M_A_CPU1_SB_DQ<15>")
	)
	(gr_poly
		(pts
			(xy 81.549748 -273.98218) (xy 81.513934 -273.946366) (xy 81.416398 -273.899884) (xy 81.281778 -274.034758)
			(xy 81.328006 -274.13204) (xy 81.36382 -274.168108)
		)
		(stroke
			(width 0)
			(type solid)
		)
		(fill yes)
		(layer "F.Cu")
		(net "M_A_CPU1_SA_DQ<21>")
	)
	(gr_poly
		(pts
			(xy 81.553304 -218.326716) (xy 81.553304 -218.136216) (xy 81.451704 -218.099894) (xy 81.400904 -218.099894)
			(xy 81.400904 -218.363038) (xy 81.451704 -218.363038)
		)
		(stroke
			(width 0)
			(type solid)
		)
		(fill yes)
		(layer "F.Cu")
		(net "M_A_CPU1_SB_DQ<24>")
	)
	(gr_poly
		(pts
			(xy 81.553304 -217.729816) (xy 81.553304 -217.539316) (xy 81.451704 -217.502994) (xy 81.400904 -217.502994)
			(xy 81.400904 -217.766138) (xy 81.451704 -217.766138)
		)
		(stroke
			(width 0)
			(type solid)
		)
		(fill yes)
		(layer "F.Cu")
		(net "M_A_CPU1_SB_DQ<24>")
	)
	(gr_poly
		(pts
			(xy 81.553304 -217.132916) (xy 81.553304 -216.942416) (xy 81.451704 -216.906094) (xy 81.400904 -216.906094)
			(xy 81.400904 -217.169238) (xy 81.451704 -217.169238)
		)
		(stroke
			(width 0)
			(type solid)
		)
		(fill yes)
		(layer "F.Cu")
		(net "M_A_CPU1_SB_DQ<24>")
	)
	(gr_poly
		(pts
			(xy 81.553304 -216.536016) (xy 81.553304 -216.345516) (xy 81.451704 -216.309194) (xy 81.400904 -216.309194)
			(xy 81.400904 -216.572338) (xy 81.451704 -216.572338)
		)
		(stroke
			(width 0)
			(type solid)
		)
		(fill yes)
		(layer "F.Cu")
		(net "M_A_CPU1_SB_DQ<24>")
	)
	(gr_poly
		(pts
			(xy 81.55686 -268.98854) (xy 81.510632 -268.891258) (xy 81.474818 -268.85519) (xy 81.28889 -269.041118)
			(xy 81.324704 -269.076932) (xy 81.42224 -269.12316)
		)
		(stroke
			(width 0)
			(type solid)
		)
		(fill yes)
		(layer "F.Cu")
		(net "M_A_CPU1_SA_DQ<30>")
	)
	(gr_poly
		(pts
			(xy 81.559146 -230.489252) (xy 81.59496 -230.453438) (xy 81.409032 -230.26751) (xy 81.373218 -230.303578)
			(xy 81.32699 -230.40086) (xy 81.46161 -230.53548)
		)
		(stroke
			(width 0)
			(type solid)
		)
		(fill yes)
		(layer "F.Cu")
		(net "M_A_CPU1_SB_DQ<18>")
	)
	(gr_poly
		(pts
			(xy 81.559654 -274.836382) (xy 81.52384 -274.800568) (xy 81.426304 -274.75434) (xy 81.291684 -274.88896)
			(xy 81.337912 -274.986242) (xy 81.373726 -275.02231)
		)
		(stroke
			(width 0)
			(type solid)
		)
		(fill yes)
		(layer "F.Cu")
		(net "M_A_CPU1_SA_DQ<20>")
	)
	(gr_poly
		(pts
			(xy 81.559908 -236.370368) (xy 81.606136 -236.273086) (xy 81.471516 -236.138212) (xy 81.37398 -236.18444)
			(xy 81.338166 -236.220508) (xy 81.524094 -236.406436)
		)
		(stroke
			(width 0)
			(type solid)
		)
		(fill yes)
		(layer "F.Cu")
		(net "M_A_CPU1_SB_DQ<8>")
	)
	(gr_poly
		(pts
			(xy 81.56829 -229.636066) (xy 81.604104 -229.599998) (xy 81.418176 -229.41407) (xy 81.382362 -229.450138)
			(xy 81.336134 -229.54742) (xy 81.470754 -229.682294)
		)
		(stroke
			(width 0)
			(type solid)
		)
		(fill yes)
		(layer "F.Cu")
		(net "M_A_CPU1_SB_DQ<19>")
	)
	(gr_poly
		(pts
			(xy 81.569052 -235.516928) (xy 81.61528 -235.419646) (xy 81.48066 -235.284772) (xy 81.383124 -235.331254)
			(xy 81.34731 -235.367068) (xy 81.533238 -235.552996)
		)
		(stroke
			(width 0)
			(type solid)
		)
		(fill yes)
		(layer "F.Cu")
		(net "M_A_CPU1_SB_DQ<9>")
	)
	(gr_poly
		(pts
			(xy 81.573116 -281.532584) (xy 81.523332 -281.522678) (xy 81.416652 -281.538172) (xy 81.379314 -281.725116)
			(xy 81.472024 -281.780488) (xy 81.521808 -281.790394)
		)
		(stroke
			(width 0)
			(type solid)
		)
		(fill yes)
		(layer "F.Cu")
		(net "M_A_CPU1_SA_DQ<7>")
	)
	(gr_poly
		(pts
			(xy 81.574132 -227.485448) (xy 81.609946 -227.44938) (xy 81.424272 -227.263706) (xy 81.388204 -227.29952)
			(xy 81.341976 -227.397056) (xy 81.476596 -227.531676)
		)
		(stroke
			(width 0)
			(type solid)
		)
		(fill yes)
		(layer "F.Cu")
		(net "M_A_CPU1_SB_DQ<20>")
	)
	(gr_poly
		(pts
			(xy 81.590134 -261.215886) (xy 81.554066 -261.180072) (xy 81.456784 -261.133844) (xy 81.32191 -261.268464)
			(xy 81.368392 -261.366) (xy 81.404206 -261.401814)
		)
		(stroke
			(width 0)
			(type solid)
		)
		(fill yes)
		(layer "F.Cu")
		(net "M_A_CPU1_SA_CB<5>")
	)
	(gr_poly
		(pts
			(xy 81.593436 -223.927924) (xy 81.639664 -223.830388) (xy 81.505044 -223.695768) (xy 81.407508 -223.741996)
			(xy 81.37144 -223.77781) (xy 81.557368 -223.963738)
		)
		(stroke
			(width 0)
			(type solid)
		)
		(fill yes)
		(layer "F.Cu")
		(net "M_A_CPU1_SB_DQ<23>")
	)
	(gr_poly
		(pts
			(xy 81.599532 -262.06958) (xy 81.563718 -262.033512) (xy 81.466182 -261.987284) (xy 81.331562 -262.122158)
			(xy 81.37779 -262.21944) (xy 81.413604 -262.255508)
		)
		(stroke
			(width 0)
			(type solid)
		)
		(fill yes)
		(layer "F.Cu")
		(net "M_A_CPU1_SA_CB<4>")
	)
	(gr_poly
		(pts
			(xy 81.604358 -271.746218) (xy 81.568544 -271.71015) (xy 81.471008 -271.663922) (xy 81.336388 -271.798796)
			(xy 81.382616 -271.896078) (xy 81.41843 -271.932146)
		)
		(stroke
			(width 0)
			(type solid)
		)
		(fill yes)
		(layer "F.Cu")
		(net "M_A_CPU1_SA_DQ<25>")
	)
	(gr_poly
		(pts
			(xy 81.604358 -264.652506) (xy 81.568544 -264.616438) (xy 81.471008 -264.57021) (xy 81.336388 -264.70483)
			(xy 81.382616 -264.802366) (xy 81.418684 -264.83818)
		)
		(stroke
			(width 0)
			(type solid)
		)
		(fill yes)
		(layer "F.Cu")
		(net "M_A_CPU1_SA_CB<1>")
	)
	(gr_poly
		(pts
			(xy 81.606898 -232.967022) (xy 81.653126 -232.86974) (xy 81.518506 -232.734866) (xy 81.42097 -232.781094)
			(xy 81.385156 -232.817162) (xy 81.571084 -233.00309)
		)
		(stroke
			(width 0)
			(type solid)
		)
		(fill yes)
		(layer "F.Cu")
		(net "M_A_CPU1_SB_DQ<12>")
	)
	(gr_poly
		(pts
			(xy 81.613502 -272.599658) (xy 81.577688 -272.56359) (xy 81.480152 -272.517362) (xy 81.345532 -272.651982)
			(xy 81.39176 -272.749518) (xy 81.427828 -272.785332)
		)
		(stroke
			(width 0)
			(type solid)
		)
		(fill yes)
		(layer "F.Cu")
		(net "M_A_CPU1_SA_DQ<24>")
	)
	(gr_poly
		(pts
			(xy 81.613756 -265.505946) (xy 81.577942 -265.469878) (xy 81.480406 -265.42365) (xy 81.345786 -265.558524)
			(xy 81.392014 -265.655806) (xy 81.427828 -265.691874)
		)
		(stroke
			(width 0)
			(type solid)
		)
		(fill yes)
		(layer "F.Cu")
		(net "M_A_CPU1_SA_CB<0>")
	)
	(gr_poly
		(pts
			(xy 81.616296 -232.113582) (xy 81.662524 -232.016046) (xy 81.527904 -231.881426) (xy 81.430368 -231.927654)
			(xy 81.394554 -231.963722) (xy 81.580228 -232.149396)
		)
		(stroke
			(width 0)
			(type solid)
		)
		(fill yes)
		(layer "F.Cu")
		(net "M_A_CPU1_SB_DQ<13>")
	)
	(gr_poly
		(pts
			(xy 81.626202 -230.84409) (xy 81.67243 -230.746808) (xy 81.53781 -230.611934) (xy 81.440274 -230.658416)
			(xy 81.40446 -230.69423) (xy 81.590388 -230.880158)
		)
		(stroke
			(width 0)
			(type solid)
		)
		(fill yes)
		(layer "F.Cu")
		(net "M_A_CPU1_SB_DQ<16>")
	)
	(gr_poly
		(pts
			(xy 81.627218 -273.68881) (xy 81.58099 -273.591274) (xy 81.545176 -273.55546) (xy 81.359248 -273.741134)
			(xy 81.395062 -273.777202) (xy 81.492598 -273.82343)
		)
		(stroke
			(width 0)
			(type solid)
		)
		(fill yes)
		(layer "F.Cu")
		(net "M_A_CPU1_SA_DQ<23>")
	)
	(gr_poly
		(pts
			(xy 81.6356 -229.990904) (xy 81.681828 -229.893368) (xy 81.546954 -229.758748) (xy 81.449672 -229.804976)
			(xy 81.413604 -229.84079) (xy 81.599532 -230.026718)
		)
		(stroke
			(width 0)
			(type solid)
		)
		(fill yes)
		(layer "F.Cu")
		(net "M_A_CPU1_SB_DQ<17>")
	)
	(gr_poly
		(pts
			(xy 81.636616 -274.54225) (xy 81.590388 -274.444968) (xy 81.55432 -274.4089) (xy 81.368392 -274.594828)
			(xy 81.40446 -274.630642) (xy 81.501742 -274.677124)
		)
		(stroke
			(width 0)
			(type solid)
		)
		(fill yes)
		(layer "F.Cu")
		(net "M_A_CPU1_SA_DQ<22>")
	)
	(gr_poly
		(pts
			(xy 81.642712 -293.507922) (xy 81.642712 -293.317422) (xy 81.541112 -293.2811) (xy 81.490312 -293.2811)
			(xy 81.490312 -293.54399) (xy 81.541112 -293.54399)
		)
		(stroke
			(width 0)
			(type solid)
		)
		(fill yes)
		(layer "F.Cu")
		(net "M_A_CPU1_SA_DQ<7>")
	)
	(gr_poly
		(pts
			(xy 81.642712 -292.911022) (xy 81.642712 -292.720522) (xy 81.541112 -292.6842) (xy 81.490312 -292.6842)
			(xy 81.490312 -292.94709) (xy 81.541112 -292.94709)
		)
		(stroke
			(width 0)
			(type solid)
		)
		(fill yes)
		(layer "F.Cu")
		(net "M_A_CPU1_SA_DQ<7>")
	)
	(gr_poly
		(pts
			(xy 81.642712 -292.314122) (xy 81.642712 -292.123622) (xy 81.541112 -292.0873) (xy 81.490312 -292.0873)
			(xy 81.490312 -292.35019) (xy 81.541112 -292.35019)
		)
		(stroke
			(width 0)
			(type solid)
		)
		(fill yes)
		(layer "F.Cu")
		(net "M_A_CPU1_SA_DQ<7>")
	)
	(gr_poly
		(pts
			(xy 81.642712 -291.717222) (xy 81.642712 -291.526722) (xy 81.541112 -291.4904) (xy 81.490312 -291.4904)
			(xy 81.490312 -291.75329) (xy 81.541112 -291.75329)
		)
		(stroke
			(width 0)
			(type solid)
		)
		(fill yes)
		(layer "F.Cu")
		(net "M_A_CPU1_SA_DQ<7>")
	)
	(gr_poly
		(pts
			(xy 81.642712 -291.120322) (xy 81.642712 -290.929822) (xy 81.541112 -290.8935) (xy 81.490312 -290.8935)
			(xy 81.490312 -291.15639) (xy 81.541112 -291.15639)
		)
		(stroke
			(width 0)
			(type solid)
		)
		(fill yes)
		(layer "F.Cu")
		(net "M_A_CPU1_SA_DQ<7>")
	)
	(gr_poly
		(pts
			(xy 81.642712 -290.523422) (xy 81.642712 -290.332922) (xy 81.541112 -290.2966) (xy 81.490312 -290.2966)
			(xy 81.490312 -290.55949) (xy 81.541112 -290.55949)
		)
		(stroke
			(width 0)
			(type solid)
		)
		(fill yes)
		(layer "F.Cu")
		(net "M_A_CPU1_SA_DQ<7>")
	)
	(gr_poly
		(pts
			(xy 81.642712 -289.926522) (xy 81.642712 -289.736022) (xy 81.541112 -289.6997) (xy 81.490312 -289.6997)
			(xy 81.490312 -289.96259) (xy 81.541112 -289.96259)
		)
		(stroke
			(width 0)
			(type solid)
		)
		(fill yes)
		(layer "F.Cu")
		(net "M_A_CPU1_SA_DQ<7>")
	)
	(gr_poly
		(pts
			(xy 81.642712 -289.329622) (xy 81.642712 -289.139122) (xy 81.541112 -289.1028) (xy 81.490312 -289.1028)
			(xy 81.490312 -289.36569) (xy 81.541112 -289.36569)
		)
		(stroke
			(width 0)
			(type solid)
		)
		(fill yes)
		(layer "F.Cu")
		(net "M_A_CPU1_SA_DQ<7>")
	)
	(gr_poly
		(pts
			(xy 81.642712 -288.732722) (xy 81.642712 -288.542222) (xy 81.541112 -288.5059) (xy 81.490312 -288.5059)
			(xy 81.490312 -288.76879) (xy 81.541112 -288.76879)
		)
		(stroke
			(width 0)
			(type solid)
		)
		(fill yes)
		(layer "F.Cu")
		(net "M_A_CPU1_SA_DQ<7>")
	)
	(gr_poly
		(pts
			(xy 81.642712 -288.135822) (xy 81.642712 -287.945322) (xy 81.541112 -287.909) (xy 81.490312 -287.909)
			(xy 81.490312 -288.17189) (xy 81.541112 -288.17189)
		)
		(stroke
			(width 0)
			(type solid)
		)
		(fill yes)
		(layer "F.Cu")
		(net "M_A_CPU1_SA_DQ<7>")
	)
	(gr_poly
		(pts
			(xy 81.642712 -287.538922) (xy 81.642712 -287.348422) (xy 81.541112 -287.3121) (xy 81.490312 -287.3121)
			(xy 81.490312 -287.57499) (xy 81.541112 -287.57499)
		)
		(stroke
			(width 0)
			(type solid)
		)
		(fill yes)
		(layer "F.Cu")
		(net "M_A_CPU1_SA_DQ<7>")
	)
	(gr_poly
		(pts
			(xy 81.642712 -286.942022) (xy 81.642712 -286.751522) (xy 81.541112 -286.7152) (xy 81.490312 -286.7152)
			(xy 81.490312 -286.97809) (xy 81.541112 -286.97809)
		)
		(stroke
			(width 0)
			(type solid)
		)
		(fill yes)
		(layer "F.Cu")
		(net "M_A_CPU1_SA_DQ<7>")
	)
	(gr_poly
		(pts
			(xy 81.642712 -286.345122) (xy 81.642712 -286.154622) (xy 81.541112 -286.1183) (xy 81.490312 -286.1183)
			(xy 81.490312 -286.38119) (xy 81.541112 -286.38119)
		)
		(stroke
			(width 0)
			(type solid)
		)
		(fill yes)
		(layer "F.Cu")
		(net "M_A_CPU1_SA_DQ<7>")
	)
	(gr_poly
		(pts
			(xy 81.642712 -285.748222) (xy 81.642712 -285.557722) (xy 81.541112 -285.5214) (xy 81.490312 -285.5214)
			(xy 81.490312 -285.78429) (xy 81.541112 -285.78429)
		)
		(stroke
			(width 0)
			(type solid)
		)
		(fill yes)
		(layer "F.Cu")
		(net "M_A_CPU1_SA_DQ<7>")
	)
	(gr_poly
		(pts
			(xy 81.642712 -285.151322) (xy 81.642712 -284.960822) (xy 81.541112 -284.9245) (xy 81.490312 -284.9245)
			(xy 81.490312 -285.18739) (xy 81.541112 -285.18739)
		)
		(stroke
			(width 0)
			(type solid)
		)
		(fill yes)
		(layer "F.Cu")
		(net "M_A_CPU1_SA_DQ<7>")
	)
	(gr_poly
		(pts
			(xy 81.642712 -284.554422) (xy 81.642712 -284.363922) (xy 81.541112 -284.3276) (xy 81.490312 -284.3276)
			(xy 81.490312 -284.59049) (xy 81.541112 -284.59049)
		)
		(stroke
			(width 0)
			(type solid)
		)
		(fill yes)
		(layer "F.Cu")
		(net "M_A_CPU1_SA_DQ<7>")
	)
	(gr_poly
		(pts
			(xy 81.642712 -283.957522) (xy 81.642712 -283.767022) (xy 81.541112 -283.7307) (xy 81.490312 -283.7307)
			(xy 81.490312 -283.99359) (xy 81.541112 -283.99359)
		)
		(stroke
			(width 0)
			(type solid)
		)
		(fill yes)
		(layer "F.Cu")
		(net "M_A_CPU1_SA_DQ<7>")
	)
	(gr_poly
		(pts
			(xy 81.642712 -283.360622) (xy 81.642712 -283.170122) (xy 81.541112 -283.1338) (xy 81.490312 -283.1338)
			(xy 81.490312 -283.39669) (xy 81.541112 -283.39669)
		)
		(stroke
			(width 0)
			(type solid)
		)
		(fill yes)
		(layer "F.Cu")
		(net "M_A_CPU1_SA_DQ<7>")
	)
	(gr_poly
		(pts
			(xy 81.642712 -282.763722) (xy 81.642712 -282.573222) (xy 81.541112 -282.5369) (xy 81.490312 -282.5369)
			(xy 81.490312 -282.79979) (xy 81.541112 -282.79979)
		)
		(stroke
			(width 0)
			(type solid)
		)
		(fill yes)
		(layer "F.Cu")
		(net "M_A_CPU1_SA_DQ<7>")
	)
	(gr_poly
		(pts
			(xy 81.650586 -226.986846) (xy 81.697068 -226.88931) (xy 81.562194 -226.75469) (xy 81.464912 -226.800918)
			(xy 81.428844 -226.836732) (xy 81.614772 -227.02266)
		)
		(stroke
			(width 0)
			(type solid)
		)
		(fill yes)
		(layer "F.Cu")
		(net "M_A_CPU1_SB_DQ<22>")
	)
	(gr_poly
		(pts
			(xy 81.651094 -276.902418) (xy 81.61528 -276.86635) (xy 81.517744 -276.820122) (xy 81.383124 -276.954996)
			(xy 81.429352 -277.052278) (xy 81.465166 -277.088346)
		)
		(stroke
			(width 0)
			(type solid)
		)
		(fill yes)
		(layer "F.Cu")
		(net "M_A_CPU1_SA_DQ<19>")
	)
	(gr_poly
		(pts
			(xy 81.667604 -260.922516) (xy 81.621376 -260.82498) (xy 81.585308 -260.789166) (xy 81.39938 -260.975094)
			(xy 81.435448 -261.010908) (xy 81.53273 -261.057136)
		)
		(stroke
			(width 0)
			(type solid)
		)
		(fill yes)
		(layer "F.Cu")
		(net "M_A_CPU1_SA_CB<7>")
	)
	(gr_poly
		(pts
			(xy 81.675986 -267.790422) (xy 81.640172 -267.754354) (xy 81.542636 -267.708126) (xy 81.408016 -267.842746)
			(xy 81.454244 -267.940282) (xy 81.490312 -267.976096)
		)
		(stroke
			(width 0)
			(type solid)
		)
		(fill yes)
		(layer "F.Cu")
		(net "M_A_CPU1_SA_DQ<31>")
	)
	(gr_poly
		(pts
			(xy 81.677002 -261.77621) (xy 81.630774 -261.678674) (xy 81.594706 -261.64286) (xy 81.409032 -261.828534)
			(xy 81.444846 -261.864602) (xy 81.542382 -261.91083)
		)
		(stroke
			(width 0)
			(type solid)
		)
		(fill yes)
		(layer "F.Cu")
		(net "M_A_CPU1_SA_CB<6>")
	)
	(gr_poly
		(pts
			(xy 81.677256 -259.618226) (xy 81.641188 -259.516626) (xy 81.450688 -259.516626) (xy 81.414366 -259.618226)
			(xy 81.414366 -259.669026) (xy 81.677256 -259.669026)
		)
		(stroke
			(width 0)
			(type solid)
		)
		(fill yes)
		(layer "F.Cu")
		(net "M_A_CPU1_SA_CS_N<0>")
	)
	(gr_poly
		(pts
			(xy 81.677256 -259.313426) (xy 81.641188 -259.211826) (xy 81.450688 -259.211826) (xy 81.414366 -259.313426)
			(xy 81.414366 -259.364226) (xy 81.677256 -259.364226)
		)
		(stroke
			(width 0)
			(type solid)
		)
		(fill yes)
		(layer "F.Cu")
		(net "M_A_CPU1_SA_CS_N<2>")
	)
	(gr_poly
		(pts
			(xy 81.677256 -259.008626) (xy 81.641188 -258.907026) (xy 81.450688 -258.907026) (xy 81.414366 -259.008626)
			(xy 81.414366 -259.059426) (xy 81.677256 -259.059426)
		)
		(stroke
			(width 0)
			(type solid)
		)
		(fill yes)
		(layer "F.Cu")
		(net "M_A_CPU1_SA_CS_N<3>")
	)
	(gr_poly
		(pts
			(xy 81.677256 -258.703826) (xy 81.641188 -258.602226) (xy 81.450688 -258.602226) (xy 81.414366 -258.703826)
			(xy 81.414366 -258.754626) (xy 81.677256 -258.754626)
		)
		(stroke
			(width 0)
			(type solid)
		)
		(fill yes)
		(layer "F.Cu")
		(net "M_A_CPU1_SA_CS_N<1>")
	)
	(gr_poly
		(pts
			(xy 81.677256 -258.399026) (xy 81.641188 -258.297426) (xy 81.450688 -258.297426) (xy 81.414366 -258.399026)
			(xy 81.414366 -258.449826) (xy 81.677256 -258.449826)
		)
		(stroke
			(width 0)
			(type solid)
		)
		(fill yes)
		(layer "F.Cu")
		(net "M_A_CPU1_SA_CA<0>")
	)
	(gr_poly
		(pts
			(xy 81.677256 -258.094226) (xy 81.641188 -257.992626) (xy 81.450688 -257.992626) (xy 81.414366 -258.094226)
			(xy 81.414366 -258.145026) (xy 81.677256 -258.145026)
		)
		(stroke
			(width 0)
			(type solid)
		)
		(fill yes)
		(layer "F.Cu")
		(net "M_A_CPU1_SA_CA<1>")
	)
	(gr_poly
		(pts
			(xy 81.677256 -257.789426) (xy 81.641188 -257.687826) (xy 81.450688 -257.687826) (xy 81.414366 -257.789426)
			(xy 81.414366 -257.840226) (xy 81.677256 -257.840226)
		)
		(stroke
			(width 0)
			(type solid)
		)
		(fill yes)
		(layer "F.Cu")
		(net "M_A_CPU1_SA_CA<2>")
	)
	(gr_poly
		(pts
			(xy 81.677256 -257.484626) (xy 81.641188 -257.383026) (xy 81.450688 -257.383026) (xy 81.414366 -257.484626)
			(xy 81.414366 -257.535426) (xy 81.677256 -257.535426)
		)
		(stroke
			(width 0)
			(type solid)
		)
		(fill yes)
		(layer "F.Cu")
		(net "M_A_CPU1_SA_CA<3>")
	)
	(gr_poly
		(pts
			(xy 81.677256 -257.179826) (xy 81.641188 -257.078226) (xy 81.450688 -257.078226) (xy 81.414366 -257.179826)
			(xy 81.414366 -257.230626) (xy 81.677256 -257.230626)
		)
		(stroke
			(width 0)
			(type solid)
		)
		(fill yes)
		(layer "F.Cu")
		(net "M_A_CPU1_SA_CA<4>")
	)
	(gr_poly
		(pts
			(xy 81.677256 -256.875026) (xy 81.641188 -256.773426) (xy 81.450688 -256.773426) (xy 81.414366 -256.875026)
			(xy 81.414366 -256.925826) (xy 81.677256 -256.925826)
		)
		(stroke
			(width 0)
			(type solid)
		)
		(fill yes)
		(layer "F.Cu")
		(net "M_A_CPU1_SA_CA<5>")
	)
	(gr_poly
		(pts
			(xy 81.677256 -256.570226) (xy 81.641188 -256.468626) (xy 81.450688 -256.468626) (xy 81.414366 -256.570226)
			(xy 81.414366 -256.621026) (xy 81.677256 -256.621026)
		)
		(stroke
			(width 0)
			(type solid)
		)
		(fill yes)
		(layer "F.Cu")
		(net "M_A_CPU1_SA_CA<6>")
	)
	(gr_poly
		(pts
			(xy 81.677256 -256.265426) (xy 81.641188 -256.163826) (xy 81.450688 -256.163826) (xy 81.414366 -256.265426)
			(xy 81.414366 -256.316226) (xy 81.677256 -256.316226)
		)
		(stroke
			(width 0)
			(type solid)
		)
		(fill yes)
		(layer "F.Cu")
		(net "M_A_CPU1_SA_PAR")
	)
	(gr_poly
		(pts
			(xy 81.681574 -271.452594) (xy 81.635346 -271.355058) (xy 81.599532 -271.319244) (xy 81.413604 -271.505172)
			(xy 81.449672 -271.540986) (xy 81.546954 -271.587214)
		)
		(stroke
			(width 0)
			(type solid)
		)
		(fill yes)
		(layer "F.Cu")
		(net "M_A_CPU1_SA_DQ<27>")
	)
	(gr_poly
		(pts
			(xy 81.682082 -264.359136) (xy 81.635854 -264.2616) (xy 81.599786 -264.225786) (xy 81.413858 -264.411714)
			(xy 81.449926 -264.447528) (xy 81.547208 -264.493756)
		)
		(stroke
			(width 0)
			(type solid)
		)
		(fill yes)
		(layer "F.Cu")
		(net "M_A_CPU1_SA_CB<3>")
	)
	(gr_poly
		(pts
			(xy 81.685638 -278.113998) (xy 81.613248 -278.033988) (xy 81.568544 -278.010112) (xy 81.444338 -278.24176)
			(xy 81.489296 -278.26589) (xy 81.595722 -278.281892)
		)
		(stroke
			(width 0)
			(type solid)
		)
		(fill yes)
		(layer "F.Cu")
		(net "M_A_CPU1_SA_DQ<18>")
	)
	(gr_poly
		(pts
			(xy 81.685892 -268.644116) (xy 81.649824 -268.608302) (xy 81.552542 -268.562074) (xy 81.417668 -268.696694)
			(xy 81.463896 -268.79423) (xy 81.499964 -268.830044)
		)
		(stroke
			(width 0)
			(type solid)
		)
		(fill yes)
		(layer "F.Cu")
		(net "M_A_CPU1_SA_DQ<30>")
	)
	(gr_poly
		(pts
			(xy 81.69021 -280.947368) (xy 81.640426 -280.937462) (xy 81.533492 -280.952956) (xy 81.496408 -281.139646)
			(xy 81.588864 -281.195018) (xy 81.638648 -281.205178)
		)
		(stroke
			(width 0)
			(type solid)
		)
		(fill yes)
		(layer "F.Cu")
		(net "M_A_CPU1_SA_DQ<7>")
	)
	(gr_poly
		(pts
			(xy 81.690464 -225.712782) (xy 81.639664 -225.712782) (xy 81.538064 -225.749104) (xy 81.538064 -225.939604)
			(xy 81.639664 -225.975926) (xy 81.690464 -225.975926)
		)
		(stroke
			(width 0)
			(type solid)
		)
		(fill yes)
		(layer "F.Cu")
		(net "M_A_CPU1_SB_DQ<23>")
	)
	(gr_poly
		(pts
			(xy 81.690464 -225.115882) (xy 81.639664 -225.115882) (xy 81.538064 -225.152204) (xy 81.538064 -225.342704)
			(xy 81.639664 -225.379026) (xy 81.690464 -225.379026)
		)
		(stroke
			(width 0)
			(type solid)
		)
		(fill yes)
		(layer "F.Cu")
		(net "M_A_CPU1_SB_DQ<23>")
	)
	(gr_poly
		(pts
			(xy 81.690464 -224.518982) (xy 81.639664 -224.518982) (xy 81.538064 -224.555304) (xy 81.538064 -224.745804)
			(xy 81.639664 -224.782126) (xy 81.690464 -224.782126)
		)
		(stroke
			(width 0)
			(type solid)
		)
		(fill yes)
		(layer "F.Cu")
		(net "M_A_CPU1_SB_DQ<23>")
	)
	(gr_poly
		(pts
			(xy 81.691226 -272.306288) (xy 81.644998 -272.208752) (xy 81.60893 -272.172938) (xy 81.423002 -272.358866)
			(xy 81.45907 -272.39468) (xy 81.556352 -272.440908)
		)
		(stroke
			(width 0)
			(type solid)
		)
		(fill yes)
		(layer "F.Cu")
		(net "M_A_CPU1_SA_DQ<26>")
	)
	(gr_poly
		(pts
			(xy 81.69148 -265.212576) (xy 81.645252 -265.11504) (xy 81.609184 -265.079226) (xy 81.423256 -265.265154)
			(xy 81.459324 -265.300968) (xy 81.556606 -265.347196)
		)
		(stroke
			(width 0)
			(type solid)
		)
		(fill yes)
		(layer "F.Cu")
		(net "M_A_CPU1_SA_CB<2>")
	)
	(gr_poly
		(pts
			(xy 81.6991 -236.653324) (xy 81.734914 -236.617256) (xy 81.54924 -236.431582) (xy 81.513172 -236.467396)
			(xy 81.466944 -236.564932) (xy 81.601564 -236.699552)
		)
		(stroke
			(width 0)
			(type solid)
		)
		(fill yes)
		(layer "F.Cu")
		(net "M_A_CPU1_SB_DQ<8>")
	)
	(gr_poly
		(pts
			(xy 81.705704 -217.801698) (xy 81.654904 -217.801698) (xy 81.553304 -217.837766) (xy 81.553304 -218.028266)
			(xy 81.654904 -218.064334) (xy 81.705704 -218.064334)
		)
		(stroke
			(width 0)
			(type solid)
		)
		(fill yes)
		(layer "F.Cu")
		(net "M_A_CPU1_SB_DQ<26>")
	)
	(gr_poly
		(pts
			(xy 81.705704 -217.204798) (xy 81.654904 -217.204798) (xy 81.553304 -217.240866) (xy 81.553304 -217.431366)
			(xy 81.654904 -217.467434) (xy 81.705704 -217.467434)
		)
		(stroke
			(width 0)
			(type solid)
		)
		(fill yes)
		(layer "F.Cu")
		(net "M_A_CPU1_SB_DQ<26>")
	)
	(gr_poly
		(pts
			(xy 81.705704 -216.607898) (xy 81.654904 -216.607898) (xy 81.553304 -216.643966) (xy 81.553304 -216.834466)
			(xy 81.654904 -216.870534) (xy 81.705704 -216.870534)
		)
		(stroke
			(width 0)
			(type solid)
		)
		(fill yes)
		(layer "F.Cu")
		(net "M_A_CPU1_SB_DQ<26>")
	)
	(gr_poly
		(pts
			(xy 81.708244 -235.799884) (xy 81.744312 -235.76407) (xy 81.558384 -235.578142) (xy 81.522316 -235.613956)
			(xy 81.476088 -235.711492) (xy 81.610962 -235.846112)
		)
		(stroke
			(width 0)
			(type solid)
		)
		(fill yes)
		(layer "F.Cu")
		(net "M_A_CPU1_SB_DQ<9>")
	)
	(gr_poly
		(pts
			(xy 81.736692 -281.492198) (xy 81.77403 -281.305254) (xy 81.681574 -281.249882) (xy 81.63179 -281.239976)
			(xy 81.580228 -281.497786) (xy 81.630012 -281.507692)
		)
		(stroke
			(width 0)
			(type solid)
		)
		(fill yes)
		(layer "F.Cu")
		(net "M_A_CPU1_SA_DQ<7>")
	)
	(gr_poly
		(pts
			(xy 81.74609 -233.249978) (xy 81.781904 -233.21391) (xy 81.59623 -233.028236) (xy 81.560162 -233.06405)
			(xy 81.513934 -233.161586) (xy 81.648554 -233.296206)
		)
		(stroke
			(width 0)
			(type solid)
		)
		(fill yes)
		(layer "F.Cu")
		(net "M_A_CPU1_SB_DQ<12>")
	)
	(gr_poly
		(pts
			(xy 81.755488 -232.396538) (xy 81.791302 -232.36047) (xy 81.605374 -232.174542) (xy 81.56956 -232.21061)
			(xy 81.523332 -232.307892) (xy 81.657952 -232.442766)
		)
		(stroke
			(width 0)
			(type solid)
		)
		(fill yes)
		(layer "F.Cu")
		(net "M_A_CPU1_SB_DQ<13>")
	)
	(gr_poly
		(pts
			(xy 81.75625 -273.344386) (xy 81.720182 -273.308318) (xy 81.6229 -273.26209) (xy 81.488026 -273.396964)
			(xy 81.534254 -273.494246) (xy 81.570322 -273.530314)
		)
		(stroke
			(width 0)
			(type solid)
		)
		(fill yes)
		(layer "F.Cu")
		(net "M_A_CPU1_SA_DQ<23>")
	)
	(gr_poly
		(pts
			(xy 81.763108 -268.350492) (xy 81.71688 -268.252956) (xy 81.680812 -268.217142) (xy 81.494884 -268.40307)
			(xy 81.530952 -268.438884) (xy 81.628234 -268.485112)
		)
		(stroke
			(width 0)
			(type solid)
		)
		(fill yes)
		(layer "F.Cu")
		(net "M_A_CPU1_SA_DQ<29>")
	)
	(gr_poly
		(pts
			(xy 81.765394 -274.197826) (xy 81.72958 -274.162012) (xy 81.632044 -274.115784) (xy 81.497424 -274.250404)
			(xy 81.543652 -274.34794) (xy 81.579466 -274.383754)
		)
		(stroke
			(width 0)
			(type solid)
		)
		(fill yes)
		(layer "F.Cu")
		(net "M_A_CPU1_SA_DQ<22>")
	)
	(gr_poly
		(pts
			(xy 81.765394 -231.127046) (xy 81.801462 -231.091232) (xy 81.615534 -230.905304) (xy 81.579466 -230.941118)
			(xy 81.533238 -231.038654) (xy 81.668112 -231.173274)
		)
		(stroke
			(width 0)
			(type solid)
		)
		(fill yes)
		(layer "F.Cu")
		(net "M_A_CPU1_SB_DQ<16>")
	)
	(gr_poly
		(pts
			(xy 81.772506 -269.204186) (xy 81.726278 -269.106904) (xy 81.690464 -269.070836) (xy 81.504536 -269.256764)
			(xy 81.54035 -269.292578) (xy 81.637886 -269.338806)
		)
		(stroke
			(width 0)
			(type solid)
		)
		(fill yes)
		(layer "F.Cu")
		(net "M_A_CPU1_SA_DQ<28>")
	)
	(gr_poly
		(pts
			(xy 81.774792 -230.273606) (xy 81.810606 -230.237792) (xy 81.624678 -230.051864) (xy 81.588864 -230.087932)
			(xy 81.542636 -230.185214) (xy 81.677256 -230.319834)
		)
		(stroke
			(width 0)
			(type solid)
		)
		(fill yes)
		(layer "F.Cu")
		(net "M_A_CPU1_SB_DQ<17>")
	)
	(gr_poly
		(pts
			(xy 81.775554 -236.154722) (xy 81.821782 -236.05744) (xy 81.687162 -235.922566) (xy 81.589626 -235.968794)
			(xy 81.553812 -236.004862) (xy 81.73974 -236.19079)
		)
		(stroke
			(width 0)
			(type solid)
		)
		(fill yes)
		(layer "F.Cu")
		(net "M_A_CPU1_SB_DQ<10>")
	)
	(gr_poly
		(pts
			(xy 81.784698 -235.301282) (xy 81.830926 -235.204) (xy 81.696306 -235.069126) (xy 81.59877 -235.115608)
			(xy 81.562956 -235.151422) (xy 81.748884 -235.33735)
		)
		(stroke
			(width 0)
			(type solid)
		)
		(fill yes)
		(layer "F.Cu")
		(net "M_A_CPU1_SB_DQ<11>")
	)
	(gr_poly
		(pts
			(xy 81.789778 -227.269548) (xy 81.825846 -227.233734) (xy 81.639918 -227.047806) (xy 81.604104 -227.08362)
			(xy 81.557876 -227.181156) (xy 81.692496 -227.315776)
		)
		(stroke
			(width 0)
			(type solid)
		)
		(fill yes)
		(layer "F.Cu")
		(net "M_A_CPU1_SB_DQ<22>")
	)
	(gr_poly
		(pts
			(xy 81.795112 -293.57955) (xy 81.744312 -293.57955) (xy 81.642712 -293.615872) (xy 81.642712 -293.806372)
			(xy 81.744312 -293.84244) (xy 81.795112 -293.84244)
		)
		(stroke
			(width 0)
			(type solid)
		)
		(fill yes)
		(layer "F.Cu")
		(net "M_A_CPU1_SA_DQ<5>")
	)
	(gr_poly
		(pts
			(xy 81.795112 -292.98265) (xy 81.744312 -292.98265) (xy 81.642712 -293.018972) (xy 81.642712 -293.209472)
			(xy 81.744312 -293.24554) (xy 81.795112 -293.24554)
		)
		(stroke
			(width 0)
			(type solid)
		)
		(fill yes)
		(layer "F.Cu")
		(net "M_A_CPU1_SA_DQ<5>")
	)
	(gr_poly
		(pts
			(xy 81.795112 -292.38575) (xy 81.744312 -292.38575) (xy 81.642712 -292.422072) (xy 81.642712 -292.612572)
			(xy 81.744312 -292.64864) (xy 81.795112 -292.64864)
		)
		(stroke
			(width 0)
			(type solid)
		)
		(fill yes)
		(layer "F.Cu")
		(net "M_A_CPU1_SA_DQ<5>")
	)
	(gr_poly
		(pts
			(xy 81.795112 -291.78885) (xy 81.744312 -291.78885) (xy 81.642712 -291.825172) (xy 81.642712 -292.015672)
			(xy 81.744312 -292.05174) (xy 81.795112 -292.05174)
		)
		(stroke
			(width 0)
			(type solid)
		)
		(fill yes)
		(layer "F.Cu")
		(net "M_A_CPU1_SA_DQ<5>")
	)
	(gr_poly
		(pts
			(xy 81.795112 -291.19195) (xy 81.744312 -291.19195) (xy 81.642712 -291.228272) (xy 81.642712 -291.418772)
			(xy 81.744312 -291.45484) (xy 81.795112 -291.45484)
		)
		(stroke
			(width 0)
			(type solid)
		)
		(fill yes)
		(layer "F.Cu")
		(net "M_A_CPU1_SA_DQ<5>")
	)
	(gr_poly
		(pts
			(xy 81.795112 -290.59505) (xy 81.744312 -290.59505) (xy 81.642712 -290.631372) (xy 81.642712 -290.821872)
			(xy 81.744312 -290.85794) (xy 81.795112 -290.85794)
		)
		(stroke
			(width 0)
			(type solid)
		)
		(fill yes)
		(layer "F.Cu")
		(net "M_A_CPU1_SA_DQ<5>")
	)
	(gr_poly
		(pts
			(xy 81.795112 -289.99815) (xy 81.744312 -289.99815) (xy 81.642712 -290.034472) (xy 81.642712 -290.224972)
			(xy 81.744312 -290.26104) (xy 81.795112 -290.26104)
		)
		(stroke
			(width 0)
			(type solid)
		)
		(fill yes)
		(layer "F.Cu")
		(net "M_A_CPU1_SA_DQ<5>")
	)
	(gr_poly
		(pts
			(xy 81.795112 -289.40125) (xy 81.744312 -289.40125) (xy 81.642712 -289.437572) (xy 81.642712 -289.628072)
			(xy 81.744312 -289.66414) (xy 81.795112 -289.66414)
		)
		(stroke
			(width 0)
			(type solid)
		)
		(fill yes)
		(layer "F.Cu")
		(net "M_A_CPU1_SA_DQ<5>")
	)
	(gr_poly
		(pts
			(xy 81.795112 -288.80435) (xy 81.744312 -288.80435) (xy 81.642712 -288.840672) (xy 81.642712 -289.031172)
			(xy 81.744312 -289.06724) (xy 81.795112 -289.06724)
		)
		(stroke
			(width 0)
			(type solid)
		)
		(fill yes)
		(layer "F.Cu")
		(net "M_A_CPU1_SA_DQ<5>")
	)
	(gr_poly
		(pts
			(xy 81.795112 -288.20745) (xy 81.744312 -288.20745) (xy 81.642712 -288.243772) (xy 81.642712 -288.434272)
			(xy 81.744312 -288.47034) (xy 81.795112 -288.47034)
		)
		(stroke
			(width 0)
			(type solid)
		)
		(fill yes)
		(layer "F.Cu")
		(net "M_A_CPU1_SA_DQ<5>")
	)
	(gr_poly
		(pts
			(xy 81.795112 -287.61055) (xy 81.744312 -287.61055) (xy 81.642712 -287.646872) (xy 81.642712 -287.837372)
			(xy 81.744312 -287.87344) (xy 81.795112 -287.87344)
		)
		(stroke
			(width 0)
			(type solid)
		)
		(fill yes)
		(layer "F.Cu")
		(net "M_A_CPU1_SA_DQ<5>")
	)
	(gr_poly
		(pts
			(xy 81.795112 -287.01365) (xy 81.744312 -287.01365) (xy 81.642712 -287.049972) (xy 81.642712 -287.240472)
			(xy 81.744312 -287.27654) (xy 81.795112 -287.27654)
		)
		(stroke
			(width 0)
			(type solid)
		)
		(fill yes)
		(layer "F.Cu")
		(net "M_A_CPU1_SA_DQ<5>")
	)
	(gr_poly
		(pts
			(xy 81.795112 -286.41675) (xy 81.744312 -286.41675) (xy 81.642712 -286.453072) (xy 81.642712 -286.643572)
			(xy 81.744312 -286.67964) (xy 81.795112 -286.67964)
		)
		(stroke
			(width 0)
			(type solid)
		)
		(fill yes)
		(layer "F.Cu")
		(net "M_A_CPU1_SA_DQ<5>")
	)
	(gr_poly
		(pts
			(xy 81.795112 -285.81985) (xy 81.744312 -285.81985) (xy 81.642712 -285.856172) (xy 81.642712 -286.046672)
			(xy 81.744312 -286.08274) (xy 81.795112 -286.08274)
		)
		(stroke
			(width 0)
			(type solid)
		)
		(fill yes)
		(layer "F.Cu")
		(net "M_A_CPU1_SA_DQ<5>")
	)
	(gr_poly
		(pts
			(xy 81.795112 -285.22295) (xy 81.744312 -285.22295) (xy 81.642712 -285.259272) (xy 81.642712 -285.449772)
			(xy 81.744312 -285.48584) (xy 81.795112 -285.48584)
		)
		(stroke
			(width 0)
			(type solid)
		)
		(fill yes)
		(layer "F.Cu")
		(net "M_A_CPU1_SA_DQ<5>")
	)
	(gr_poly
		(pts
			(xy 81.795112 -284.62605) (xy 81.744312 -284.62605) (xy 81.642712 -284.662372) (xy 81.642712 -284.852872)
			(xy 81.744312 -284.88894) (xy 81.795112 -284.88894)
		)
		(stroke
			(width 0)
			(type solid)
		)
		(fill yes)
		(layer "F.Cu")
		(net "M_A_CPU1_SA_DQ<5>")
	)
	(gr_poly
		(pts
			(xy 81.795112 -284.02915) (xy 81.744312 -284.02915) (xy 81.642712 -284.065472) (xy 81.642712 -284.255972)
			(xy 81.744312 -284.29204) (xy 81.795112 -284.29204)
		)
		(stroke
			(width 0)
			(type solid)
		)
		(fill yes)
		(layer "F.Cu")
		(net "M_A_CPU1_SA_DQ<5>")
	)
	(gr_poly
		(pts
			(xy 81.795112 -283.43225) (xy 81.744312 -283.43225) (xy 81.642712 -283.468572) (xy 81.642712 -283.659072)
			(xy 81.744312 -283.69514) (xy 81.795112 -283.69514)
		)
		(stroke
			(width 0)
			(type solid)
		)
		(fill yes)
		(layer "F.Cu")
		(net "M_A_CPU1_SA_DQ<5>")
	)
	(gr_poly
		(pts
			(xy 81.795112 -282.83535) (xy 81.744312 -282.83535) (xy 81.642712 -282.871672) (xy 81.642712 -283.062172)
			(xy 81.744312 -283.09824) (xy 81.795112 -283.09824)
		)
		(stroke
			(width 0)
			(type solid)
		)
		(fill yes)
		(layer "F.Cu")
		(net "M_A_CPU1_SA_DQ<5>")
	)
	(gr_poly
		(pts
			(xy 81.80578 -261.431786) (xy 81.769966 -261.395718) (xy 81.67243 -261.34949) (xy 81.53781 -261.484364)
			(xy 81.584038 -261.581646) (xy 81.619852 -261.617714)
		)
		(stroke
			(width 0)
			(type solid)
		)
		(fill yes)
		(layer "F.Cu")
		(net "M_A_CPU1_SA_CB<6>")
	)
	(gr_poly
		(pts
			(xy 81.80705 -280.361898) (xy 81.757266 -280.351992) (xy 81.650586 -280.367486) (xy 81.613248 -280.55443)
			(xy 81.705704 -280.609802) (xy 81.755488 -280.619708)
		)
		(stroke
			(width 0)
			(type solid)
		)
		(fill yes)
		(layer "F.Cu")
		(net "M_A_CPU1_SA_DQ<7>")
	)
	(gr_poly
		(pts
			(xy 81.810606 -271.10817) (xy 81.774538 -271.072356) (xy 81.677256 -271.026128) (xy 81.542382 -271.160748)
			(xy 81.588864 -271.258284) (xy 81.624678 -271.294098)
		)
		(stroke
			(width 0)
			(type solid)
		)
		(fill yes)
		(layer "F.Cu")
		(net "M_A_CPU1_SA_DQ<27>")
	)
	(gr_poly
		(pts
			(xy 81.81086 -264.014712) (xy 81.775046 -263.978644) (xy 81.67751 -263.932416) (xy 81.54289 -264.06729)
			(xy 81.589118 -264.164572) (xy 81.624932 -264.20064)
		)
		(stroke
			(width 0)
			(type solid)
		)
		(fill yes)
		(layer "F.Cu")
		(net "M_A_CPU1_SA_CB<3>")
	)
	(gr_poly
		(pts
			(xy 81.820004 -271.961864) (xy 81.78419 -271.925796) (xy 81.686654 -271.879568) (xy 81.552034 -272.014442)
			(xy 81.598262 -272.111724) (xy 81.634076 -272.147792)
		)
		(stroke
			(width 0)
			(type solid)
		)
		(fill yes)
		(layer "F.Cu")
		(net "M_A_CPU1_SA_DQ<26>")
	)
	(gr_poly
		(pts
			(xy 81.820258 -264.868152) (xy 81.784444 -264.832338) (xy 81.686908 -264.78611) (xy 81.552288 -264.92073)
			(xy 81.598516 -265.018266) (xy 81.63433 -265.05408)
		)
		(stroke
			(width 0)
			(type solid)
		)
		(fill yes)
		(layer "F.Cu")
		(net "M_A_CPU1_SA_CB<2>")
	)
	(gr_poly
		(pts
			(xy 81.822798 -232.751376) (xy 81.869026 -232.65384) (xy 81.734152 -232.51922) (xy 81.63687 -232.565448)
			(xy 81.600802 -232.601262) (xy 81.78673 -232.78719)
		)
		(stroke
			(width 0)
			(type solid)
		)
		(fill yes)
		(layer "F.Cu")
		(net "M_A_CPU1_SB_DQ<14>")
	)
	(gr_poly
		(pts
			(xy 81.831942 -231.897936) (xy 81.87817 -231.8004) (xy 81.74355 -231.66578) (xy 81.646014 -231.712008)
			(xy 81.6102 -231.748076) (xy 81.795874 -231.93375)
		)
		(stroke
			(width 0)
			(type solid)
		)
		(fill yes)
		(layer "F.Cu")
		(net "M_A_CPU1_SB_DQ<15>")
	)
	(gr_poly
		(pts
			(xy 81.841848 -230.628444) (xy 81.888076 -230.531162) (xy 81.753456 -230.396288) (xy 81.65592 -230.44277)
			(xy 81.620106 -230.478584) (xy 81.806034 -230.664512)
		)
		(stroke
			(width 0)
			(type solid)
		)
		(fill yes)
		(layer "F.Cu")
		(net "M_A_CPU1_SB_DQ<18>")
	)
	(gr_poly
		(pts
			(xy 81.842864 -273.904456) (xy 81.796636 -273.807174) (xy 81.760822 -273.771106) (xy 81.574894 -273.957034)
			(xy 81.610708 -273.992848) (xy 81.708244 -274.03933)
		)
		(stroke
			(width 0)
			(type solid)
		)
		(fill yes)
		(layer "F.Cu")
		(net "M_A_CPU1_SA_DQ<21>")
	)
	(gr_poly
		(pts
			(xy 81.842864 -225.641154) (xy 81.842864 -225.450654) (xy 81.741264 -225.414586) (xy 81.690464 -225.414586)
			(xy 81.690464 -225.677222) (xy 81.741264 -225.677222)
		)
		(stroke
			(width 0)
			(type solid)
		)
		(fill yes)
		(layer "F.Cu")
		(net "M_A_CPU1_SB_DQ<23>")
	)
	(gr_poly
		(pts
			(xy 81.842864 -225.044254) (xy 81.842864 -224.853754) (xy 81.741264 -224.817686) (xy 81.690464 -224.817686)
			(xy 81.690464 -225.080322) (xy 81.741264 -225.080322)
		)
		(stroke
			(width 0)
			(type solid)
		)
		(fill yes)
		(layer "F.Cu")
		(net "M_A_CPU1_SB_DQ<23>")
	)
	(gr_poly
		(pts
			(xy 81.851246 -229.775258) (xy 81.897474 -229.677722) (xy 81.7626 -229.543102) (xy 81.665318 -229.58933)
			(xy 81.62925 -229.625144) (xy 81.815178 -229.811072)
		)
		(stroke
			(width 0)
			(type solid)
		)
		(fill yes)
		(layer "F.Cu")
		(net "M_A_CPU1_SB_DQ<19>")
	)
	(gr_poly
		(pts
			(xy 81.853024 -274.758658) (xy 81.806796 -274.661376) (xy 81.770728 -274.625308) (xy 81.5848 -274.811236)
			(xy 81.620868 -274.847304) (xy 81.71815 -274.893532)
		)
		(stroke
			(width 0)
			(type solid)
		)
		(fill yes)
		(layer "F.Cu")
		(net "M_A_CPU1_SA_DQ<20>")
	)
	(gr_poly
		(pts
			(xy 81.853532 -280.906728) (xy 81.89087 -280.720038) (xy 81.798414 -280.664666) (xy 81.74863 -280.654506)
			(xy 81.697068 -280.912316) (xy 81.746852 -280.922476)
		)
		(stroke
			(width 0)
			(type solid)
		)
		(fill yes)
		(layer "F.Cu")
		(net "M_A_CPU1_SA_DQ<7>")
	)
	(gr_poly
		(pts
			(xy 81.857088 -227.62464) (xy 81.903316 -227.527104) (xy 81.768442 -227.392484) (xy 81.67116 -227.438712)
			(xy 81.635092 -227.474526) (xy 81.82102 -227.660454)
		)
		(stroke
			(width 0)
			(type solid)
		)
		(fill yes)
		(layer "F.Cu")
		(net "M_A_CPU1_SB_DQ<20>")
	)
	(gr_poly
		(pts
			(xy 81.858104 -218.326716) (xy 81.858104 -218.136216) (xy 81.756504 -218.099894) (xy 81.705704 -218.099894)
			(xy 81.705704 -218.363038) (xy 81.756504 -218.363038)
		)
		(stroke
			(width 0)
			(type solid)
		)
		(fill yes)
		(layer "F.Cu")
		(net "M_A_CPU1_SB_DQ<26>")
	)
	(gr_poly
		(pts
			(xy 81.858104 -217.729816) (xy 81.858104 -217.539316) (xy 81.756504 -217.502994) (xy 81.705704 -217.502994)
			(xy 81.705704 -217.766138) (xy 81.756504 -217.766138)
		)
		(stroke
			(width 0)
			(type solid)
		)
		(fill yes)
		(layer "F.Cu")
		(net "M_A_CPU1_SB_DQ<26>")
	)
	(gr_poly
		(pts
			(xy 81.858104 -217.132916) (xy 81.858104 -216.942416) (xy 81.756504 -216.906094) (xy 81.705704 -216.906094)
			(xy 81.705704 -217.169238) (xy 81.756504 -217.169238)
		)
		(stroke
			(width 0)
			(type solid)
		)
		(fill yes)
		(layer "F.Cu")
		(net "M_A_CPU1_SB_DQ<26>")
	)
	(gr_poly
		(pts
			(xy 81.858104 -216.536016) (xy 81.858104 -216.345516) (xy 81.756504 -216.309194) (xy 81.705704 -216.309194)
			(xy 81.705704 -216.572338) (xy 81.756504 -216.572338)
		)
		(stroke
			(width 0)
			(type solid)
		)
		(fill yes)
		(layer "F.Cu")
		(net "M_A_CPU1_SB_DQ<26>")
	)
	(gr_poly
		(pts
			(xy 81.866232 -226.7712) (xy 81.912714 -226.673664) (xy 81.77784 -226.539044) (xy 81.680558 -226.585272)
			(xy 81.64449 -226.621086) (xy 81.830418 -226.807014)
		)
		(stroke
			(width 0)
			(type solid)
		)
		(fill yes)
		(layer "F.Cu")
		(net "M_A_CPU1_SB_DQ<21>")
	)
	(gr_poly
		(pts
			(xy 81.868518 -277.119588) (xy 81.83245 -277.083774) (xy 81.735168 -277.037546) (xy 81.600294 -277.172166)
			(xy 81.646522 -277.269702) (xy 81.68259 -277.305516)
		)
		(stroke
			(width 0)
			(type solid)
		)
		(fill yes)
		(layer "F.Cu")
		(net "M_A_CPU1_SA_DQ<17>")
	)
	(gr_poly
		(pts
			(xy 81.872328 -281.592274) (xy 81.822544 -281.582368) (xy 81.715864 -281.598116) (xy 81.678526 -281.784806)
			(xy 81.771236 -281.840178) (xy 81.82102 -281.850084)
		)
		(stroke
			(width 0)
			(type solid)
		)
		(fill yes)
		(layer "F.Cu")
		(net "M_A_CPU1_SA_DQ<5>")
	)
	(gr_poly
		(pts
			(xy 81.891886 -268.006068) (xy 81.856072 -267.970254) (xy 81.758536 -267.924026) (xy 81.623916 -268.058646)
			(xy 81.670144 -268.156182) (xy 81.705958 -268.191996)
		)
		(stroke
			(width 0)
			(type solid)
		)
		(fill yes)
		(layer "F.Cu")
		(net "M_A_CPU1_SA_DQ<29>")
	)
	(gr_poly
		(pts
			(xy 81.892648 -261.991856) (xy 81.84642 -261.89432) (xy 81.810606 -261.858506) (xy 81.624678 -262.044434)
			(xy 81.660492 -262.080248) (xy 81.758028 -262.126476)
		)
		(stroke
			(width 0)
			(type solid)
		)
		(fill yes)
		(layer "F.Cu")
		(net "M_A_CPU1_SA_CB<4>")
	)
	(gr_poly
		(pts
			(xy 81.897474 -271.668494) (xy 81.851246 -271.570958) (xy 81.815432 -271.535144) (xy 81.629504 -271.721072)
			(xy 81.665572 -271.756886) (xy 81.762854 -271.803114)
		)
		(stroke
			(width 0)
			(type solid)
		)
		(fill yes)
		(layer "F.Cu")
		(net "M_A_CPU1_SA_DQ<25>")
	)
	(gr_poly
		(pts
			(xy 81.897728 -264.574782) (xy 81.8515 -264.477246) (xy 81.815432 -264.441432) (xy 81.629504 -264.62736)
			(xy 81.665572 -264.663174) (xy 81.762854 -264.709402)
		)
		(stroke
			(width 0)
			(type solid)
		)
		(fill yes)
		(layer "F.Cu")
		(net "M_A_CPU1_SA_CB<1>")
	)
	(gr_poly
		(pts
			(xy 81.901538 -268.859762) (xy 81.86547 -268.823948) (xy 81.768188 -268.77772) (xy 81.633314 -268.91234)
			(xy 81.679542 -269.009876) (xy 81.71561 -269.04569)
		)
		(stroke
			(width 0)
			(type solid)
		)
		(fill yes)
		(layer "F.Cu")
		(net "M_A_CPU1_SA_DQ<28>")
	)
	(gr_poly
		(pts
			(xy 81.906872 -272.521934) (xy 81.860644 -272.424398) (xy 81.824576 -272.388584) (xy 81.638648 -272.574512)
			(xy 81.674716 -272.610326) (xy 81.771998 -272.656554)
		)
		(stroke
			(width 0)
			(type solid)
		)
		(fill yes)
		(layer "F.Cu")
		(net "M_A_CPU1_SA_DQ<24>")
	)
	(gr_poly
		(pts
			(xy 81.907126 -265.428222) (xy 81.860898 -265.330686) (xy 81.82483 -265.294872) (xy 81.638902 -265.4808)
			(xy 81.67497 -265.516614) (xy 81.772252 -265.562842)
		)
		(stroke
			(width 0)
			(type solid)
		)
		(fill yes)
		(layer "F.Cu")
		(net "M_A_CPU1_SA_CB<0>")
	)
	(gr_poly
		(pts
			(xy 81.914746 -236.437678) (xy 81.95056 -236.40161) (xy 81.764886 -236.215936) (xy 81.728818 -236.25175)
			(xy 81.68259 -236.349286) (xy 81.81721 -236.483906)
		)
		(stroke
			(width 0)
			(type solid)
		)
		(fill yes)
		(layer "F.Cu")
		(net "M_A_CPU1_SB_DQ<10>")
	)
	(gr_poly
		(pts
			(xy 81.92389 -279.776682) (xy 81.874106 -279.766776) (xy 81.767426 -279.78227) (xy 81.730088 -279.96896)
			(xy 81.822798 -280.024586) (xy 81.872582 -280.034492)
		)
		(stroke
			(width 0)
			(type solid)
		)
		(fill yes)
		(layer "F.Cu")
		(net "M_A_CPU1_SA_DQ<7>")
	)
	(gr_poly
		(pts
			(xy 81.92389 -235.584238) (xy 81.959958 -235.548424) (xy 81.77403 -235.362496) (xy 81.737962 -235.39831)
			(xy 81.691734 -235.495846) (xy 81.826608 -235.630466)
		)
		(stroke
			(width 0)
			(type solid)
		)
		(fill yes)
		(layer "F.Cu")
		(net "M_A_CPU1_SB_DQ<11>")
	)
	(gr_poly
		(pts
			(xy 81.944464 -276.824694) (xy 81.897982 -276.727158) (xy 81.862168 -276.691344) (xy 81.67624 -276.877272)
			(xy 81.712308 -276.913086) (xy 81.80959 -276.959314)
		)
		(stroke
			(width 0)
			(type solid)
		)
		(fill yes)
		(layer "F.Cu")
		(net "M_A_CPU1_SA_DQ<19>")
	)
	(gr_poly
		(pts
			(xy 81.947512 -294.104822) (xy 81.947512 -293.914322) (xy 81.845912 -293.878) (xy 81.795112 -293.878)
			(xy 81.795112 -294.14089) (xy 81.845912 -294.14089)
		)
		(stroke
			(width 0)
			(type solid)
		)
		(fill yes)
		(layer "F.Cu")
		(net "M_A_CPU1_SA_DQ<5>")
	)
	(gr_poly
		(pts
			(xy 81.947512 -293.507922) (xy 81.947512 -293.317422) (xy 81.845912 -293.2811) (xy 81.795112 -293.2811)
			(xy 81.795112 -293.54399) (xy 81.845912 -293.54399)
		)
		(stroke
			(width 0)
			(type solid)
		)
		(fill yes)
		(layer "F.Cu")
		(net "M_A_CPU1_SA_DQ<5>")
	)
	(gr_poly
		(pts
			(xy 81.947512 -292.911022) (xy 81.947512 -292.720522) (xy 81.845912 -292.6842) (xy 81.795112 -292.6842)
			(xy 81.795112 -292.94709) (xy 81.845912 -292.94709)
		)
		(stroke
			(width 0)
			(type solid)
		)
		(fill yes)
		(layer "F.Cu")
		(net "M_A_CPU1_SA_DQ<5>")
	)
	(gr_poly
		(pts
			(xy 81.947512 -292.314122) (xy 81.947512 -292.123622) (xy 81.845912 -292.0873) (xy 81.795112 -292.0873)
			(xy 81.795112 -292.35019) (xy 81.845912 -292.35019)
		)
		(stroke
			(width 0)
			(type solid)
		)
		(fill yes)
		(layer "F.Cu")
		(net "M_A_CPU1_SA_DQ<5>")
	)
	(gr_poly
		(pts
			(xy 81.947512 -291.717222) (xy 81.947512 -291.526722) (xy 81.845912 -291.4904) (xy 81.795112 -291.4904)
			(xy 81.795112 -291.75329) (xy 81.845912 -291.75329)
		)
		(stroke
			(width 0)
			(type solid)
		)
		(fill yes)
		(layer "F.Cu")
		(net "M_A_CPU1_SA_DQ<5>")
	)
	(gr_poly
		(pts
			(xy 81.947512 -291.120322) (xy 81.947512 -290.929822) (xy 81.845912 -290.8935) (xy 81.795112 -290.8935)
			(xy 81.795112 -291.15639) (xy 81.845912 -291.15639)
		)
		(stroke
			(width 0)
			(type solid)
		)
		(fill yes)
		(layer "F.Cu")
		(net "M_A_CPU1_SA_DQ<5>")
	)
	(gr_poly
		(pts
			(xy 81.947512 -290.523422) (xy 81.947512 -290.332922) (xy 81.845912 -290.2966) (xy 81.795112 -290.2966)
			(xy 81.795112 -290.55949) (xy 81.845912 -290.55949)
		)
		(stroke
			(width 0)
			(type solid)
		)
		(fill yes)
		(layer "F.Cu")
		(net "M_A_CPU1_SA_DQ<5>")
	)
	(gr_poly
		(pts
			(xy 81.947512 -289.926522) (xy 81.947512 -289.736022) (xy 81.845912 -289.6997) (xy 81.795112 -289.6997)
			(xy 81.795112 -289.96259) (xy 81.845912 -289.96259)
		)
		(stroke
			(width 0)
			(type solid)
		)
		(fill yes)
		(layer "F.Cu")
		(net "M_A_CPU1_SA_DQ<5>")
	)
	(gr_poly
		(pts
			(xy 81.947512 -289.329622) (xy 81.947512 -289.139122) (xy 81.845912 -289.1028) (xy 81.795112 -289.1028)
			(xy 81.795112 -289.36569) (xy 81.845912 -289.36569)
		)
		(stroke
			(width 0)
			(type solid)
		)
		(fill yes)
		(layer "F.Cu")
		(net "M_A_CPU1_SA_DQ<5>")
	)
	(gr_poly
		(pts
			(xy 81.947512 -288.732722) (xy 81.947512 -288.542222) (xy 81.845912 -288.5059) (xy 81.795112 -288.5059)
			(xy 81.795112 -288.76879) (xy 81.845912 -288.76879)
		)
		(stroke
			(width 0)
			(type solid)
		)
		(fill yes)
		(layer "F.Cu")
		(net "M_A_CPU1_SA_DQ<5>")
	)
	(gr_poly
		(pts
			(xy 81.947512 -288.135822) (xy 81.947512 -287.945322) (xy 81.845912 -287.909) (xy 81.795112 -287.909)
			(xy 81.795112 -288.17189) (xy 81.845912 -288.17189)
		)
		(stroke
			(width 0)
			(type solid)
		)
		(fill yes)
		(layer "F.Cu")
		(net "M_A_CPU1_SA_DQ<5>")
	)
	(gr_poly
		(pts
			(xy 81.947512 -287.538922) (xy 81.947512 -287.348422) (xy 81.845912 -287.3121) (xy 81.795112 -287.3121)
			(xy 81.795112 -287.57499) (xy 81.845912 -287.57499)
		)
		(stroke
			(width 0)
			(type solid)
		)
		(fill yes)
		(layer "F.Cu")
		(net "M_A_CPU1_SA_DQ<5>")
	)
	(gr_poly
		(pts
			(xy 81.947512 -286.942022) (xy 81.947512 -286.751522) (xy 81.845912 -286.7152) (xy 81.795112 -286.7152)
			(xy 81.795112 -286.97809) (xy 81.845912 -286.97809)
		)
		(stroke
			(width 0)
			(type solid)
		)
		(fill yes)
		(layer "F.Cu")
		(net "M_A_CPU1_SA_DQ<5>")
	)
	(gr_poly
		(pts
			(xy 81.947512 -286.345122) (xy 81.947512 -286.154622) (xy 81.845912 -286.1183) (xy 81.795112 -286.1183)
			(xy 81.795112 -286.38119) (xy 81.845912 -286.38119)
		)
		(stroke
			(width 0)
			(type solid)
		)
		(fill yes)
		(layer "F.Cu")
		(net "M_A_CPU1_SA_DQ<5>")
	)
	(gr_poly
		(pts
			(xy 81.947512 -285.748222) (xy 81.947512 -285.557722) (xy 81.845912 -285.5214) (xy 81.795112 -285.5214)
			(xy 81.795112 -285.78429) (xy 81.845912 -285.78429)
		)
		(stroke
			(width 0)
			(type solid)
		)
		(fill yes)
		(layer "F.Cu")
		(net "M_A_CPU1_SA_DQ<5>")
	)
	(gr_poly
		(pts
			(xy 81.947512 -285.151322) (xy 81.947512 -284.960822) (xy 81.845912 -284.9245) (xy 81.795112 -284.9245)
			(xy 81.795112 -285.18739) (xy 81.845912 -285.18739)
		)
		(stroke
			(width 0)
			(type solid)
		)
		(fill yes)
		(layer "F.Cu")
		(net "M_A_CPU1_SA_DQ<5>")
	)
	(gr_poly
		(pts
			(xy 81.947512 -284.554422) (xy 81.947512 -284.363922) (xy 81.845912 -284.3276) (xy 81.795112 -284.3276)
			(xy 81.795112 -284.59049) (xy 81.845912 -284.59049)
		)
		(stroke
			(width 0)
			(type solid)
		)
		(fill yes)
		(layer "F.Cu")
		(net "M_A_CPU1_SA_DQ<5>")
	)
	(gr_poly
		(pts
			(xy 81.947512 -283.957522) (xy 81.947512 -283.767022) (xy 81.845912 -283.7307) (xy 81.795112 -283.7307)
			(xy 81.795112 -283.99359) (xy 81.845912 -283.99359)
		)
		(stroke
			(width 0)
			(type solid)
		)
		(fill yes)
		(layer "F.Cu")
		(net "M_A_CPU1_SA_DQ<5>")
	)
	(gr_poly
		(pts
			(xy 81.947512 -283.360622) (xy 81.947512 -283.170122) (xy 81.845912 -283.1338) (xy 81.795112 -283.1338)
			(xy 81.795112 -283.39669) (xy 81.845912 -283.39669)
		)
		(stroke
			(width 0)
			(type solid)
		)
		(fill yes)
		(layer "F.Cu")
		(net "M_A_CPU1_SA_DQ<5>")
	)
	(gr_poly
		(pts
			(xy 81.947512 -282.763722) (xy 81.947512 -282.573222) (xy 81.845912 -282.5369) (xy 81.795112 -282.5369)
			(xy 81.795112 -282.79979) (xy 81.845912 -282.79979)
		)
		(stroke
			(width 0)
			(type solid)
		)
		(fill yes)
		(layer "F.Cu")
		(net "M_A_CPU1_SA_DQ<5>")
	)
	(gr_poly
		(pts
			(xy 81.954624 -278.258016) (xy 81.882234 -278.17826) (xy 81.83753 -278.154384) (xy 81.713324 -278.386032)
			(xy 81.758282 -278.409908) (xy 81.864708 -278.426164)
		)
		(stroke
			(width 0)
			(type solid)
		)
		(fill yes)
		(layer "F.Cu")
		(net "M_A_CPU1_SA_DQ<16>")
	)
	(gr_poly
		(pts
			(xy 81.96199 -233.034078) (xy 81.997804 -232.998264) (xy 81.811876 -232.812336) (xy 81.776062 -232.84815)
			(xy 81.729834 -232.945686) (xy 81.864454 -233.080306)
		)
		(stroke
			(width 0)
			(type solid)
		)
		(fill yes)
		(layer "F.Cu")
		(net "M_A_CPU1_SB_DQ<14>")
	)
	(gr_poly
		(pts
			(xy 81.969356 -267.712698) (xy 81.923128 -267.615162) (xy 81.88706 -267.579348) (xy 81.701132 -267.765276)
			(xy 81.7372 -267.80109) (xy 81.834482 -267.847318)
		)
		(stroke
			(width 0)
			(type solid)
		)
		(fill yes)
		(layer "F.Cu")
		(net "M_A_CPU1_SA_DQ<31>")
	)
	(gr_poly
		(pts
			(xy 81.970626 -280.321512) (xy 82.007964 -280.134568) (xy 81.915254 -280.079196) (xy 81.86547 -280.06929)
			(xy 81.813908 -280.3271) (xy 81.863946 -280.337006)
		)
		(stroke
			(width 0)
			(type solid)
		)
		(fill yes)
		(layer "F.Cu")
		(net "M_A_CPU1_SA_DQ<7>")
	)
	(gr_poly
		(pts
			(xy 81.971134 -232.180892) (xy 82.006948 -232.144824) (xy 81.82102 -231.958896) (xy 81.785206 -231.994964)
			(xy 81.738978 -232.092246) (xy 81.873598 -232.22712)
		)
		(stroke
			(width 0)
			(type solid)
		)
		(fill yes)
		(layer "F.Cu")
		(net "M_A_CPU1_SB_DQ<15>")
	)
	(gr_poly
		(pts
			(xy 81.971896 -273.560032) (xy 81.935828 -273.524218) (xy 81.838546 -273.47799) (xy 81.703926 -273.61261)
			(xy 81.750154 -273.710146) (xy 81.785968 -273.74596)
		)
		(stroke
			(width 0)
			(type solid)
		)
		(fill yes)
		(layer "F.Cu")
		(net "M_A_CPU1_SA_DQ<21>")
	)
	(gr_poly
		(pts
			(xy 81.975706 -259.719826) (xy 81.975706 -259.669026) (xy 81.712816 -259.669026) (xy 81.712816 -259.719826)
			(xy 81.748884 -259.821426) (xy 81.939384 -259.821426)
		)
		(stroke
			(width 0)
			(type solid)
		)
		(fill yes)
		(layer "F.Cu")
		(net "M_A_CPU1_SA_CS_N<0>")
	)
	(gr_poly
		(pts
			(xy 81.975706 -259.415026) (xy 81.975706 -259.364226) (xy 81.712816 -259.364226) (xy 81.712816 -259.415026)
			(xy 81.748884 -259.516626) (xy 81.939384 -259.516626)
		)
		(stroke
			(width 0)
			(type solid)
		)
		(fill yes)
		(layer "F.Cu")
		(net "M_A_CPU1_SA_CS_N<2>")
	)
	(gr_poly
		(pts
			(xy 81.975706 -259.110226) (xy 81.975706 -259.059426) (xy 81.712816 -259.059426) (xy 81.712816 -259.110226)
			(xy 81.748884 -259.211826) (xy 81.939384 -259.211826)
		)
		(stroke
			(width 0)
			(type solid)
		)
		(fill yes)
		(layer "F.Cu")
		(net "M_A_CPU1_SA_CS_N<3>")
	)
	(gr_poly
		(pts
			(xy 81.975706 -258.805426) (xy 81.975706 -258.754626) (xy 81.712816 -258.754626) (xy 81.712816 -258.805426)
			(xy 81.748884 -258.907026) (xy 81.939384 -258.907026)
		)
		(stroke
			(width 0)
			(type solid)
		)
		(fill yes)
		(layer "F.Cu")
		(net "M_A_CPU1_SA_CS_N<1>")
	)
	(gr_poly
		(pts
			(xy 81.975706 -258.500626) (xy 81.975706 -258.449826) (xy 81.712816 -258.449826) (xy 81.712816 -258.500626)
			(xy 81.748884 -258.602226) (xy 81.939384 -258.602226)
		)
		(stroke
			(width 0)
			(type solid)
		)
		(fill yes)
		(layer "F.Cu")
		(net "M_A_CPU1_SA_CA<0>")
	)
	(gr_poly
		(pts
			(xy 81.975706 -258.195826) (xy 81.975706 -258.145026) (xy 81.712816 -258.145026) (xy 81.712816 -258.195826)
			(xy 81.748884 -258.297426) (xy 81.939384 -258.297426)
		)
		(stroke
			(width 0)
			(type solid)
		)
		(fill yes)
		(layer "F.Cu")
		(net "M_A_CPU1_SA_CA<1>")
	)
	(gr_poly
		(pts
			(xy 81.975706 -257.891026) (xy 81.975706 -257.840226) (xy 81.712816 -257.840226) (xy 81.712816 -257.891026)
			(xy 81.748884 -257.992626) (xy 81.939384 -257.992626)
		)
		(stroke
			(width 0)
			(type solid)
		)
		(fill yes)
		(layer "F.Cu")
		(net "M_A_CPU1_SA_CA<2>")
	)
	(gr_poly
		(pts
			(xy 81.975706 -257.586226) (xy 81.975706 -257.535426) (xy 81.712816 -257.535426) (xy 81.712816 -257.586226)
			(xy 81.748884 -257.687826) (xy 81.939384 -257.687826)
		)
		(stroke
			(width 0)
			(type solid)
		)
		(fill yes)
		(layer "F.Cu")
		(net "M_A_CPU1_SA_CA<3>")
	)
	(gr_poly
		(pts
			(xy 81.975706 -257.281426) (xy 81.975706 -257.230626) (xy 81.712816 -257.230626) (xy 81.712816 -257.281426)
			(xy 81.748884 -257.383026) (xy 81.939384 -257.383026)
		)
		(stroke
			(width 0)
			(type solid)
		)
		(fill yes)
		(layer "F.Cu")
		(net "M_A_CPU1_SA_CA<4>")
	)
	(gr_poly
		(pts
			(xy 81.975706 -256.976626) (xy 81.975706 -256.925826) (xy 81.712816 -256.925826) (xy 81.712816 -256.976626)
			(xy 81.748884 -257.078226) (xy 81.939384 -257.078226)
		)
		(stroke
			(width 0)
			(type solid)
		)
		(fill yes)
		(layer "F.Cu")
		(net "M_A_CPU1_SA_CA<5>")
	)
	(gr_poly
		(pts
			(xy 81.979008 -268.566392) (xy 81.93278 -268.46911) (xy 81.896966 -268.433042) (xy 81.711038 -268.61897)
			(xy 81.746852 -268.655038) (xy 81.844388 -268.701266)
		)
		(stroke
			(width 0)
			(type solid)
		)
		(fill yes)
		(layer "F.Cu")
		(net "M_A_CPU1_SA_DQ<30>")
	)
	(gr_poly
		(pts
			(xy 81.98104 -230.9114) (xy 82.017108 -230.875586) (xy 81.83118 -230.689658) (xy 81.795112 -230.725472)
			(xy 81.748884 -230.823008) (xy 81.883758 -230.957628)
		)
		(stroke
			(width 0)
			(type solid)
		)
		(fill yes)
		(layer "F.Cu")
		(net "M_A_CPU1_SB_DQ<18>")
	)
	(gr_poly
		(pts
			(xy 81.981802 -274.414488) (xy 81.945988 -274.37842) (xy 81.848452 -274.332192) (xy 81.713832 -274.466812)
			(xy 81.76006 -274.564348) (xy 81.795874 -274.600162)
		)
		(stroke
			(width 0)
			(type solid)
		)
		(fill yes)
		(layer "F.Cu")
		(net "M_A_CPU1_SA_DQ<20>")
	)
	(gr_poly
		(pts
			(xy 81.982056 -236.792516) (xy 82.028284 -236.69498) (xy 81.89341 -236.56036) (xy 81.796128 -236.606588)
			(xy 81.76006 -236.642402) (xy 81.945988 -236.82833)
		)
		(stroke
			(width 0)
			(type solid)
		)
		(fill yes)
		(layer "F.Cu")
		(net "M_A_CPU1_SB_DQ<8>")
	)
	(gr_poly
		(pts
			(xy 81.989676 -281.007058) (xy 81.939892 -280.997152) (xy 81.833212 -281.012646) (xy 81.795874 -281.19959)
			(xy 81.88833 -281.254962) (xy 81.938114 -281.264868)
		)
		(stroke
			(width 0)
			(type solid)
		)
		(fill yes)
		(layer "F.Cu")
		(net "M_A_CPU1_SA_DQ<5>")
	)
	(gr_poly
		(pts
			(xy 81.990438 -230.05796) (xy 82.026252 -230.022146) (xy 81.840324 -229.836218) (xy 81.80451 -229.872286)
			(xy 81.758282 -229.969568) (xy 81.892902 -230.104188)
		)
		(stroke
			(width 0)
			(type solid)
		)
		(fill yes)
		(layer "F.Cu")
		(net "M_A_CPU1_SB_DQ<19>")
	)
	(gr_poly
		(pts
			(xy 81.9912 -235.939076) (xy 82.037428 -235.841794) (xy 81.902808 -235.70692) (xy 81.805272 -235.753148)
			(xy 81.769458 -235.789216) (xy 81.955386 -235.975144)
		)
		(stroke
			(width 0)
			(type solid)
		)
		(fill yes)
		(layer "F.Cu")
		(net "M_A_CPU1_SB_DQ<9>")
	)
	(gr_poly
		(pts
			(xy 81.99628 -227.907342) (xy 82.032094 -227.871528) (xy 81.846166 -227.6856) (xy 81.810352 -227.721668)
			(xy 81.764124 -227.81895) (xy 81.898744 -227.953824)
		)
		(stroke
			(width 0)
			(type solid)
		)
		(fill yes)
		(layer "F.Cu")
		(net "M_A_CPU1_SB_DQ<20>")
	)
	(gr_poly
		(pts
			(xy 82.005424 -227.053902) (xy 82.041492 -227.018088) (xy 81.855564 -226.83216) (xy 81.81975 -226.867974)
			(xy 81.773522 -226.96551) (xy 81.908142 -227.10013)
		)
		(stroke
			(width 0)
			(type solid)
		)
		(fill yes)
		(layer "F.Cu")
		(net "M_A_CPU1_SB_DQ<21>")
	)
	(gr_poly
		(pts
			(xy 82.010504 -217.801698) (xy 81.959704 -217.801698) (xy 81.858104 -217.837766) (xy 81.858104 -218.028266)
			(xy 81.959704 -218.064334) (xy 82.010504 -218.064334)
		)
		(stroke
			(width 0)
			(type solid)
		)
		(fill yes)
		(layer "F.Cu")
		(net "M_A_CPU1_SB_DQ<25>")
	)
	(gr_poly
		(pts
			(xy 82.010504 -217.204798) (xy 81.959704 -217.204798) (xy 81.858104 -217.240866) (xy 81.858104 -217.431366)
			(xy 81.959704 -217.467434) (xy 82.010504 -217.467434)
		)
		(stroke
			(width 0)
			(type solid)
		)
		(fill yes)
		(layer "F.Cu")
		(net "M_A_CPU1_SB_DQ<25>")
	)
	(gr_poly
		(pts
			(xy 82.010504 -216.607898) (xy 81.959704 -216.607898) (xy 81.858104 -216.643966) (xy 81.858104 -216.834466)
			(xy 81.959704 -216.870534) (xy 82.010504 -216.870534)
		)
		(stroke
			(width 0)
			(type solid)
		)
		(fill yes)
		(layer "F.Cu")
		(net "M_A_CPU1_SB_DQ<25>")
	)
	(gr_poly
		(pts
			(xy 82.026506 -271.32407) (xy 81.990438 -271.288256) (xy 81.893156 -271.242028) (xy 81.758282 -271.376648)
			(xy 81.804764 -271.474184) (xy 81.840578 -271.509998)
		)
		(stroke
			(width 0)
			(type solid)
		)
		(fill yes)
		(layer "F.Cu")
		(net "M_A_CPU1_SA_DQ<25>")
	)
	(gr_poly
		(pts
			(xy 82.026506 -264.230358) (xy 81.990692 -264.19429) (xy 81.893156 -264.148062) (xy 81.758536 -264.282936)
			(xy 81.804764 -264.380218) (xy 81.840578 -264.416286)
		)
		(stroke
			(width 0)
			(type solid)
		)
		(fill yes)
		(layer "F.Cu")
		(net "M_A_CPU1_SA_CB<1>")
	)
	(gr_poly
		(pts
			(xy 82.029046 -233.38917) (xy 82.075274 -233.291634) (xy 81.9404 -233.157014) (xy 81.843118 -233.203242)
			(xy 81.80705 -233.239056) (xy 81.992978 -233.424984)
		)
		(stroke
			(width 0)
			(type solid)
		)
		(fill yes)
		(layer "F.Cu")
		(net "M_A_CPU1_SB_DQ<12>")
	)
	(gr_poly
		(pts
			(xy 82.03565 -272.17751) (xy 81.999836 -272.141442) (xy 81.9023 -272.095214) (xy 81.76768 -272.230088)
			(xy 81.813908 -272.32737) (xy 81.849722 -272.363438)
		)
		(stroke
			(width 0)
			(type solid)
		)
		(fill yes)
		(layer "F.Cu")
		(net "M_A_CPU1_SA_DQ<24>")
	)
	(gr_poly
		(pts
			(xy 82.035904 -281.551888) (xy 82.073496 -281.365198) (xy 81.980786 -281.309826) (xy 81.931002 -281.299666)
			(xy 81.87944 -281.557476) (xy 81.929224 -281.567636)
		)
		(stroke
			(width 0)
			(type solid)
		)
		(fill yes)
		(layer "F.Cu")
		(net "M_A_CPU1_SA_DQ<5>")
	)
	(gr_poly
		(pts
			(xy 82.035904 -265.083798) (xy 82.00009 -265.047984) (xy 81.902554 -265.001756) (xy 81.767934 -265.136376)
			(xy 81.814162 -265.233912) (xy 81.849976 -265.269726)
		)
		(stroke
			(width 0)
			(type solid)
		)
		(fill yes)
		(layer "F.Cu")
		(net "M_A_CPU1_SA_CB<0>")
	)
	(gr_poly
		(pts
			(xy 82.038444 -232.53573) (xy 82.084672 -232.438194) (xy 81.949798 -232.303574) (xy 81.852516 -232.349802)
			(xy 81.816448 -232.385616) (xy 82.002376 -232.571544)
		)
		(stroke
			(width 0)
			(type solid)
		)
		(fill yes)
		(layer "F.Cu")
		(net "M_A_CPU1_SB_DQ<13>")
	)
	(gr_poly
		(pts
			(xy 82.040984 -279.191212) (xy 81.9912 -279.181306) (xy 81.884266 -279.1968) (xy 81.846928 -279.383744)
			(xy 81.939638 -279.439116) (xy 81.989422 -279.449022)
		)
		(stroke
			(width 0)
			(type solid)
		)
		(fill yes)
		(layer "F.Cu")
		(net "M_A_CPU1_SA_DQ<7>")
	)
	(gr_poly
		(pts
			(xy 82.04835 -231.266238) (xy 82.094578 -231.168956) (xy 81.959958 -231.034082) (xy 81.862422 -231.08031)
			(xy 81.826608 -231.116378) (xy 82.012536 -231.302306)
		)
		(stroke
			(width 0)
			(type solid)
		)
		(fill yes)
		(layer "F.Cu")
		(net "M_A_CPU1_SB_DQ<16>")
	)
	(gr_poly
		(pts
			(xy 82.049366 -273.266662) (xy 82.003138 -273.16938) (xy 81.96707 -273.133312) (xy 81.781396 -273.31924)
			(xy 81.81721 -273.355054) (xy 81.914746 -273.401282)
		)
		(stroke
			(width 0)
			(type solid)
		)
		(fill yes)
		(layer "F.Cu")
		(net "M_A_CPU1_SA_DQ<23>")
	)
	(gr_poly
		(pts
			(xy 82.057494 -230.412798) (xy 82.103722 -230.315516) (xy 81.969102 -230.180642) (xy 81.871566 -230.227124)
			(xy 81.835752 -230.262938) (xy 82.02168 -230.448866)
		)
		(stroke
			(width 0)
			(type solid)
		)
		(fill yes)
		(layer "F.Cu")
		(net "M_A_CPU1_SB_DQ<17>")
	)
	(gr_poly
		(pts
			(xy 82.058764 -274.120356) (xy 82.012536 -274.02282) (xy 81.976468 -273.987006) (xy 81.79054 -274.17268)
			(xy 81.826608 -274.208748) (xy 81.92389 -274.254976)
		)
		(stroke
			(width 0)
			(type solid)
		)
		(fill yes)
		(layer "F.Cu")
		(net "M_A_CPU1_SA_DQ<22>")
	)
	(gr_poly
		(pts
			(xy 82.072734 -227.40874) (xy 82.118962 -227.311458) (xy 81.984342 -227.176584) (xy 81.886806 -227.222812)
			(xy 81.850992 -227.25888) (xy 82.03692 -227.444808)
		)
		(stroke
			(width 0)
			(type solid)
		)
		(fill yes)
		(layer "F.Cu")
		(net "M_A_CPU1_SB_DQ<22>")
	)
	(gr_poly
		(pts
			(xy 82.073242 -276.48027) (xy 82.037174 -276.444456) (xy 81.939892 -276.398228) (xy 81.805272 -276.532848)
			(xy 81.8515 -276.630384) (xy 81.887314 -276.666198)
		)
		(stroke
			(width 0)
			(type solid)
		)
		(fill yes)
		(layer "F.Cu")
		(net "M_A_CPU1_SA_DQ<19>")
	)
	(gr_poly
		(pts
			(xy 82.081878 -226.555554) (xy 82.12836 -226.458018) (xy 81.993486 -226.323398) (xy 81.896204 -226.369626)
			(xy 81.860136 -226.40544) (xy 82.046064 -226.591368)
		)
		(stroke
			(width 0)
			(type solid)
		)
		(fill yes)
		(layer "F.Cu")
		(net "M_A_CPU1_SB_DQ<23>")
	)
	(gr_poly
		(pts
			(xy 82.084164 -277.335234) (xy 82.048096 -277.29942) (xy 81.950814 -277.253192) (xy 81.81594 -277.387812)
			(xy 81.862168 -277.485348) (xy 81.898236 -277.521162)
		)
		(stroke
			(width 0)
			(type solid)
		)
		(fill yes)
		(layer "F.Cu")
		(net "M_A_CPU1_SA_DQ<18>")
	)
	(gr_poly
		(pts
			(xy 82.087466 -279.736042) (xy 82.124804 -279.549352) (xy 82.032348 -279.49398) (xy 81.982564 -279.484074)
			(xy 81.931002 -279.74163) (xy 81.980786 -279.75179)
		)
		(stroke
			(width 0)
			(type solid)
		)
		(fill yes)
		(layer "F.Cu")
		(net "M_A_CPU1_SA_DQ<7>")
	)
	(gr_poly
		(pts
			(xy 82.098134 -267.368274) (xy 82.06232 -267.332206) (xy 81.964784 -267.285978) (xy 81.830164 -267.420852)
			(xy 81.876392 -267.518134) (xy 81.912206 -267.554202)
		)
		(stroke
			(width 0)
			(type solid)
		)
		(fill yes)
		(layer "F.Cu")
		(net "M_A_CPU1_SA_DQ<31>")
	)
	(gr_poly
		(pts
			(xy 82.099912 -294.17645) (xy 82.049112 -294.17645) (xy 81.947512 -294.212772) (xy 81.947512 -294.403272)
			(xy 82.049112 -294.43934) (xy 82.099912 -294.43934)
		)
		(stroke
			(width 0)
			(type solid)
		)
		(fill yes)
		(layer "F.Cu")
		(net "M_A_CPU1_SA_DQ<6>")
	)
	(gr_poly
		(pts
			(xy 82.099912 -293.57955) (xy 82.049112 -293.57955) (xy 81.947512 -293.615872) (xy 81.947512 -293.806372)
			(xy 82.049112 -293.84244) (xy 82.099912 -293.84244)
		)
		(stroke
			(width 0)
			(type solid)
		)
		(fill yes)
		(layer "F.Cu")
		(net "M_A_CPU1_SA_DQ<6>")
	)
	(gr_poly
		(pts
			(xy 82.099912 -292.98265) (xy 82.049112 -292.98265) (xy 81.947512 -293.018972) (xy 81.947512 -293.209472)
			(xy 82.049112 -293.24554) (xy 82.099912 -293.24554)
		)
		(stroke
			(width 0)
			(type solid)
		)
		(fill yes)
		(layer "F.Cu")
		(net "M_A_CPU1_SA_DQ<6>")
	)
	(gr_poly
		(pts
			(xy 82.099912 -292.38575) (xy 82.049112 -292.38575) (xy 81.947512 -292.422072) (xy 81.947512 -292.612572)
			(xy 82.049112 -292.64864) (xy 82.099912 -292.64864)
		)
		(stroke
			(width 0)
			(type solid)
		)
		(fill yes)
		(layer "F.Cu")
		(net "M_A_CPU1_SA_DQ<6>")
	)
	(gr_poly
		(pts
			(xy 82.099912 -291.78885) (xy 82.049112 -291.78885) (xy 81.947512 -291.825172) (xy 81.947512 -292.015672)
			(xy 82.049112 -292.05174) (xy 82.099912 -292.05174)
		)
		(stroke
			(width 0)
			(type solid)
		)
		(fill yes)
		(layer "F.Cu")
		(net "M_A_CPU1_SA_DQ<6>")
	)
	(gr_poly
		(pts
			(xy 82.099912 -291.19195) (xy 82.049112 -291.19195) (xy 81.947512 -291.228272) (xy 81.947512 -291.418772)
			(xy 82.049112 -291.45484) (xy 82.099912 -291.45484)
		)
		(stroke
			(width 0)
			(type solid)
		)
		(fill yes)
		(layer "F.Cu")
		(net "M_A_CPU1_SA_DQ<6>")
	)
	(gr_poly
		(pts
			(xy 82.099912 -290.59505) (xy 82.049112 -290.59505) (xy 81.947512 -290.631372) (xy 81.947512 -290.821872)
			(xy 82.049112 -290.85794) (xy 82.099912 -290.85794)
		)
		(stroke
			(width 0)
			(type solid)
		)
		(fill yes)
		(layer "F.Cu")
		(net "M_A_CPU1_SA_DQ<6>")
	)
	(gr_poly
		(pts
			(xy 82.099912 -289.99815) (xy 82.049112 -289.99815) (xy 81.947512 -290.034472) (xy 81.947512 -290.224972)
			(xy 82.049112 -290.26104) (xy 82.099912 -290.26104)
		)
		(stroke
			(width 0)
			(type solid)
		)
		(fill yes)
		(layer "F.Cu")
		(net "M_A_CPU1_SA_DQ<6>")
	)
	(gr_poly
		(pts
			(xy 82.099912 -289.40125) (xy 82.049112 -289.40125) (xy 81.947512 -289.437572) (xy 81.947512 -289.628072)
			(xy 82.049112 -289.66414) (xy 82.099912 -289.66414)
		)
		(stroke
			(width 0)
			(type solid)
		)
		(fill yes)
		(layer "F.Cu")
		(net "M_A_CPU1_SA_DQ<6>")
	)
	(gr_poly
		(pts
			(xy 82.099912 -288.80435) (xy 82.049112 -288.80435) (xy 81.947512 -288.840672) (xy 81.947512 -289.031172)
			(xy 82.049112 -289.06724) (xy 82.099912 -289.06724)
		)
		(stroke
			(width 0)
			(type solid)
		)
		(fill yes)
		(layer "F.Cu")
		(net "M_A_CPU1_SA_DQ<6>")
	)
	(gr_poly
		(pts
			(xy 82.099912 -288.20745) (xy 82.049112 -288.20745) (xy 81.947512 -288.243772) (xy 81.947512 -288.434272)
			(xy 82.049112 -288.47034) (xy 82.099912 -288.47034)
		)
		(stroke
			(width 0)
			(type solid)
		)
		(fill yes)
		(layer "F.Cu")
		(net "M_A_CPU1_SA_DQ<6>")
	)
	(gr_poly
		(pts
			(xy 82.099912 -287.61055) (xy 82.049112 -287.61055) (xy 81.947512 -287.646872) (xy 81.947512 -287.837372)
			(xy 82.049112 -287.87344) (xy 82.099912 -287.87344)
		)
		(stroke
			(width 0)
			(type solid)
		)
		(fill yes)
		(layer "F.Cu")
		(net "M_A_CPU1_SA_DQ<6>")
	)
	(gr_poly
		(pts
			(xy 82.099912 -287.01365) (xy 82.049112 -287.01365) (xy 81.947512 -287.049972) (xy 81.947512 -287.240472)
			(xy 82.049112 -287.27654) (xy 82.099912 -287.27654)
		)
		(stroke
			(width 0)
			(type solid)
		)
		(fill yes)
		(layer "F.Cu")
		(net "M_A_CPU1_SA_DQ<6>")
	)
	(gr_poly
		(pts
			(xy 82.099912 -286.41675) (xy 82.049112 -286.41675) (xy 81.947512 -286.453072) (xy 81.947512 -286.643572)
			(xy 82.049112 -286.67964) (xy 82.099912 -286.67964)
		)
		(stroke
			(width 0)
			(type solid)
		)
		(fill yes)
		(layer "F.Cu")
		(net "M_A_CPU1_SA_DQ<6>")
	)
	(gr_poly
		(pts
			(xy 82.099912 -285.81985) (xy 82.049112 -285.81985) (xy 81.947512 -285.856172) (xy 81.947512 -286.046672)
			(xy 82.049112 -286.08274) (xy 82.099912 -286.08274)
		)
		(stroke
			(width 0)
			(type solid)
		)
		(fill yes)
		(layer "F.Cu")
		(net "M_A_CPU1_SA_DQ<6>")
	)
	(gr_poly
		(pts
			(xy 82.099912 -285.22295) (xy 82.049112 -285.22295) (xy 81.947512 -285.259272) (xy 81.947512 -285.449772)
			(xy 82.049112 -285.48584) (xy 82.099912 -285.48584)
		)
		(stroke
			(width 0)
			(type solid)
		)
		(fill yes)
		(layer "F.Cu")
		(net "M_A_CPU1_SA_DQ<6>")
	)
	(gr_poly
		(pts
			(xy 82.099912 -284.62605) (xy 82.049112 -284.62605) (xy 81.947512 -284.662372) (xy 81.947512 -284.852872)
			(xy 82.049112 -284.88894) (xy 82.099912 -284.88894)
		)
		(stroke
			(width 0)
			(type solid)
		)
		(fill yes)
		(layer "F.Cu")
		(net "M_A_CPU1_SA_DQ<6>")
	)
	(gr_poly
		(pts
			(xy 82.099912 -284.02915) (xy 82.049112 -284.02915) (xy 81.947512 -284.065472) (xy 81.947512 -284.255972)
			(xy 82.049112 -284.29204) (xy 82.099912 -284.29204)
		)
		(stroke
			(width 0)
			(type solid)
		)
		(fill yes)
		(layer "F.Cu")
		(net "M_A_CPU1_SA_DQ<6>")
	)
	(gr_poly
		(pts
			(xy 82.099912 -283.43225) (xy 82.049112 -283.43225) (xy 81.947512 -283.468572) (xy 81.947512 -283.659072)
			(xy 82.049112 -283.69514) (xy 82.099912 -283.69514)
		)
		(stroke
			(width 0)
			(type solid)
		)
		(fill yes)
		(layer "F.Cu")
		(net "M_A_CPU1_SA_DQ<6>")
	)
	(gr_poly
		(pts
			(xy 82.099912 -282.83535) (xy 82.049112 -282.83535) (xy 81.947512 -282.871672) (xy 81.947512 -283.062172)
			(xy 82.049112 -283.09824) (xy 82.099912 -283.09824)
		)
		(stroke
			(width 0)
			(type solid)
		)
		(fill yes)
		(layer "F.Cu")
		(net "M_A_CPU1_SA_DQ<6>")
	)
	(gr_poly
		(pts
			(xy 82.103722 -271.030446) (xy 82.057494 -270.933164) (xy 82.02168 -270.897096) (xy 81.835752 -271.083024)
			(xy 81.871566 -271.119092) (xy 81.969102 -271.16532)
		)
		(stroke
			(width 0)
			(type solid)
		)
		(fill yes)
		(layer "F.Cu")
		(net "M_A_CPU1_SA_DQ<27>")
	)
	(gr_poly
		(pts
			(xy 82.103976 -263.936988) (xy 82.057748 -263.839452) (xy 82.021934 -263.803638) (xy 81.836006 -263.989566)
			(xy 81.872074 -264.02538) (xy 81.969356 -264.071608)
		)
		(stroke
			(width 0)
			(type solid)
		)
		(fill yes)
		(layer "F.Cu")
		(net "M_A_CPU1_SA_CB<3>")
	)
	(gr_poly
		(pts
			(xy 82.10677 -280.421842) (xy 82.056986 -280.411936) (xy 81.950306 -280.42743) (xy 81.912968 -280.614374)
			(xy 82.005424 -280.669746) (xy 82.055462 -280.679652)
		)
		(stroke
			(width 0)
			(type solid)
		)
		(fill yes)
		(layer "F.Cu")
		(net "M_A_CPU1_SA_DQ<5>")
	)
	(gr_poly
		(pts
			(xy 82.107786 -268.222222) (xy 82.071972 -268.186154) (xy 81.974436 -268.139926) (xy 81.839816 -268.274546)
			(xy 81.886044 -268.372082) (xy 81.922112 -268.407896)
		)
		(stroke
			(width 0)
			(type solid)
		)
		(fill yes)
		(layer "F.Cu")
		(net "M_A_CPU1_SA_DQ<30>")
	)
	(gr_poly
		(pts
			(xy 82.11312 -271.88414) (xy 82.066892 -271.786604) (xy 82.031078 -271.75079) (xy 81.84515 -271.936718)
			(xy 81.881218 -271.972532) (xy 81.9785 -272.01876)
		)
		(stroke
			(width 0)
			(type solid)
		)
		(fill yes)
		(layer "F.Cu")
		(net "M_A_CPU1_SA_DQ<26>")
	)
	(gr_poly
		(pts
			(xy 82.113374 -264.790428) (xy 82.067146 -264.693146) (xy 82.031332 -264.657078) (xy 81.845404 -264.843006)
			(xy 81.881218 -264.87882) (xy 81.978754 -264.925302)
		)
		(stroke
			(width 0)
			(type solid)
		)
		(fill yes)
		(layer "F.Cu")
		(net "M_A_CPU1_SA_CB<2>")
	)
	(gr_poly
		(pts
			(xy 82.153252 -280.966672) (xy 82.19059 -280.779982) (xy 82.098134 -280.724356) (xy 82.04835 -280.71445)
			(xy 81.996788 -280.97226) (xy 82.046572 -280.982166)
		)
		(stroke
			(width 0)
			(type solid)
		)
		(fill yes)
		(layer "F.Cu")
		(net "M_A_CPU1_SA_DQ<5>")
	)
	(gr_poly
		(pts
			(xy 82.161634 -277.042118) (xy 82.115406 -276.944582) (xy 82.079592 -276.908514) (xy 81.893664 -277.094442)
			(xy 81.929478 -277.13051) (xy 82.027014 -277.176738)
		)
		(stroke
			(width 0)
			(type solid)
		)
		(fill yes)
		(layer "F.Cu")
		(net "M_A_CPU1_SA_DQ<17>")
	)
	(gr_poly
		(pts
			(xy 82.162904 -218.326716) (xy 82.162904 -218.136216) (xy 82.061304 -218.099894) (xy 82.010504 -218.099894)
			(xy 82.010504 -218.363038) (xy 82.061304 -218.363038)
		)
		(stroke
			(width 0)
			(type solid)
		)
		(fill yes)
		(layer "F.Cu")
		(net "M_A_CPU1_SB_DQ<25>")
	)
	(gr_poly
		(pts
			(xy 82.162904 -217.729816) (xy 82.162904 -217.539316) (xy 82.061304 -217.502994) (xy 82.010504 -217.502994)
			(xy 82.010504 -217.766138) (xy 82.061304 -217.766138)
		)
		(stroke
			(width 0)
			(type solid)
		)
		(fill yes)
		(layer "F.Cu")
		(net "M_A_CPU1_SB_DQ<25>")
	)
	(gr_poly
		(pts
			(xy 82.162904 -217.132916) (xy 82.162904 -216.942416) (xy 82.061304 -216.906094) (xy 82.010504 -216.906094)
			(xy 82.010504 -217.169238) (xy 82.061304 -217.169238)
		)
		(stroke
			(width 0)
			(type solid)
		)
		(fill yes)
		(layer "F.Cu")
		(net "M_A_CPU1_SB_DQ<25>")
	)
	(gr_poly
		(pts
			(xy 82.162904 -216.536016) (xy 82.162904 -216.345516) (xy 82.061304 -216.309194) (xy 82.010504 -216.309194)
			(xy 82.010504 -216.572338) (xy 82.061304 -216.572338)
		)
		(stroke
			(width 0)
			(type solid)
		)
		(fill yes)
		(layer "F.Cu")
		(net "M_A_CPU1_SB_DQ<25>")
	)
	(gr_poly
		(pts
			(xy 82.17154 -281.652218) (xy 82.121756 -281.642058) (xy 82.015076 -281.657806) (xy 81.977738 -281.844496)
			(xy 82.070194 -281.899868) (xy 82.119978 -281.910028)
		)
		(stroke
			(width 0)
			(type solid)
		)
		(fill yes)
		(layer "F.Cu")
		(net "M_A_CPU1_SA_DQ<6>")
	)
	(gr_poly
		(pts
			(xy 82.177636 -232.818432) (xy 82.21345 -232.782618) (xy 82.027522 -232.59669) (xy 81.991708 -232.632504)
			(xy 81.94548 -232.73004) (xy 82.0801 -232.86466)
		)
		(stroke
			(width 0)
			(type solid)
		)
		(fill yes)
		(layer "F.Cu")
		(net "M_A_CPU1_SB_DQ<13>")
	)
	(gr_poly
		(pts
			(xy 82.178144 -272.922238) (xy 82.14233 -272.886424) (xy 82.044794 -272.840196) (xy 81.910174 -272.974816)
			(xy 81.956402 -273.072352) (xy 81.992216 -273.108166)
		)
		(stroke
			(width 0)
			(type solid)
		)
		(fill yes)
		(layer "F.Cu")
		(net "M_A_CPU1_SA_DQ<23>")
	)
	(gr_poly
		(pts
			(xy 82.180684 -238.761016) (xy 82.180684 -238.710216) (xy 81.918048 -238.710216) (xy 81.918048 -238.761016)
			(xy 81.954116 -238.862616) (xy 82.144616 -238.862616)
		)
		(stroke
			(width 0)
			(type solid)
		)
		(fill yes)
		(layer "F.Cu")
		(net "M_A_CPU1_SB_CB<0>")
	)
	(gr_poly
		(pts
			(xy 82.180684 -238.456216) (xy 82.180684 -238.405416) (xy 81.918048 -238.405416) (xy 81.918048 -238.456216)
			(xy 81.954116 -238.557816) (xy 82.144616 -238.557816)
		)
		(stroke
			(width 0)
			(type solid)
		)
		(fill yes)
		(layer "F.Cu")
		(net "M_A_CPU1_SB_CB<2>")
	)
	(gr_poly
		(pts
			(xy 82.180684 -238.151416) (xy 82.180684 -238.100616) (xy 81.918048 -238.100616) (xy 81.918048 -238.151416)
			(xy 81.954116 -238.253016) (xy 82.144616 -238.253016)
		)
		(stroke
			(width 0)
			(type solid)
		)
		(fill yes)
		(layer "F.Cu")
		(net "M_A_CPU1_SB_CB<1>")
	)
	(gr_poly
		(pts
			(xy 82.185002 -267.928344) (xy 82.138774 -267.831062) (xy 82.10296 -267.794994) (xy 81.917032 -267.980922)
			(xy 81.952846 -268.016736) (xy 82.050382 -268.063218)
		)
		(stroke
			(width 0)
			(type solid)
		)
		(fill yes)
		(layer "F.Cu")
		(net "M_A_CPU1_SA_DQ<29>")
	)
	(gr_poly
		(pts
			(xy 82.187542 -273.775932) (xy 82.151728 -273.739864) (xy 82.054192 -273.693636) (xy 81.919572 -273.82851)
			(xy 81.9658 -273.925792) (xy 82.001614 -273.96186)
		)
		(stroke
			(width 0)
			(type solid)
		)
		(fill yes)
		(layer "F.Cu")
		(net "M_A_CPU1_SA_DQ<22>")
	)
	(gr_poly
		(pts
			(xy 82.187542 -231.549194) (xy 82.223356 -231.513126) (xy 82.037682 -231.327452) (xy 82.001614 -231.363266)
			(xy 81.955386 -231.460802) (xy 82.090006 -231.595422)
		)
		(stroke
			(width 0)
			(type solid)
		)
		(fill yes)
		(layer "F.Cu")
		(net "M_A_CPU1_SB_DQ<16>")
	)
	(gr_poly
		(pts
			(xy 82.194654 -268.782038) (xy 82.148426 -268.684756) (xy 82.112612 -268.648688) (xy 81.926684 -268.834616)
			(xy 81.962498 -268.870684) (xy 82.060034 -268.916912)
		)
		(stroke
			(width 0)
			(type solid)
		)
		(fill yes)
		(layer "F.Cu")
		(net "M_A_CPU1_SA_DQ<28>")
	)
	(gr_poly
		(pts
			(xy 82.196686 -230.695754) (xy 82.232754 -230.65994) (xy 82.046826 -230.474012) (xy 82.010758 -230.509826)
			(xy 81.96453 -230.607362) (xy 82.099404 -230.741982)
		)
		(stroke
			(width 0)
			(type solid)
		)
		(fill yes)
		(layer "F.Cu")
		(net "M_A_CPU1_SB_DQ<17>")
	)
	(gr_poly
		(pts
			(xy 82.204306 -279.150826) (xy 82.241644 -278.963882) (xy 82.149188 -278.90851) (xy 82.099404 -278.898604)
			(xy 82.047842 -279.156414) (xy 82.097626 -279.16632)
		)
		(stroke
			(width 0)
			(type solid)
		)
		(fill yes)
		(layer "F.Cu")
		(net "M_A_CPU1_SA_DQ<7>")
	)
	(gr_poly
		(pts
			(xy 82.206846 -235.72343) (xy 82.253074 -235.626148) (xy 82.118454 -235.491274) (xy 82.020918 -235.537502)
			(xy 81.985104 -235.57357) (xy 82.171032 -235.759498)
		)
		(stroke
			(width 0)
			(type solid)
		)
		(fill yes)
		(layer "F.Cu")
		(net "M_A_CPU1_SB_DQ<11>")
	)
	(gr_poly
		(pts
			(xy 82.211926 -227.691696) (xy 82.247994 -227.655882) (xy 82.062066 -227.469954) (xy 82.025998 -227.505768)
			(xy 81.97977 -227.603304) (xy 82.114644 -227.737924)
		)
		(stroke
			(width 0)
			(type solid)
		)
		(fill yes)
		(layer "F.Cu")
		(net "M_A_CPU1_SB_DQ<22>")
	)
	(gr_poly
		(pts
			(xy 82.22107 -226.838256) (xy 82.257138 -226.802442) (xy 82.07121 -226.616514) (xy 82.035396 -226.652328)
			(xy 81.989168 -226.749864) (xy 82.123788 -226.884484)
		)
		(stroke
			(width 0)
			(type solid)
		)
		(fill yes)
		(layer "F.Cu")
		(net "M_A_CPU1_SB_DQ<23>")
	)
	(gr_poly
		(pts
			(xy 82.224118 -279.836626) (xy 82.174334 -279.82672) (xy 82.0674 -279.842214) (xy 82.030316 -280.028904)
			(xy 82.122772 -280.08453) (xy 82.172556 -280.094436)
		)
		(stroke
			(width 0)
			(type solid)
		)
		(fill yes)
		(layer "F.Cu")
		(net "M_A_CPU1_SA_DQ<5>")
	)
	(gr_poly
		(pts
			(xy 82.232754 -270.686022) (xy 82.196686 -270.650208) (xy 82.099404 -270.60398) (xy 81.96453 -270.7386)
			(xy 82.010758 -270.836136) (xy 82.046826 -270.87195)
		)
		(stroke
			(width 0)
			(type solid)
		)
		(fill yes)
		(layer "F.Cu")
		(net "M_A_CPU1_SA_DQ<27>")
	)
	(gr_poly
		(pts
			(xy 82.233008 -263.592564) (xy 82.19694 -263.55675) (xy 82.099658 -263.510522) (xy 81.964784 -263.645142)
			(xy 82.011266 -263.742678) (xy 82.04708 -263.778492)
		)
		(stroke
			(width 0)
			(type solid)
		)
		(fill yes)
		(layer "F.Cu")
		(net "M_A_CPU1_SA_CB<3>")
	)
	(gr_poly
		(pts
			(xy 82.242152 -271.539716) (xy 82.206084 -271.503902) (xy 82.108802 -271.457674) (xy 81.973928 -271.592294)
			(xy 82.02041 -271.68983) (xy 82.056224 -271.725644)
		)
		(stroke
			(width 0)
			(type solid)
		)
		(fill yes)
		(layer "F.Cu")
		(net "M_A_CPU1_SA_DQ<26>")
	)
	(gr_poly
		(pts
			(xy 82.242406 -264.446004) (xy 82.206338 -264.41019) (xy 82.109056 -264.363962) (xy 81.974182 -264.498582)
			(xy 82.02041 -264.596118) (xy 82.056478 -264.631932)
		)
		(stroke
			(width 0)
			(type solid)
		)
		(fill yes)
		(layer "F.Cu")
		(net "M_A_CPU1_SA_CB<2>")
	)
	(gr_poly
		(pts
			(xy 82.244692 -233.17327) (xy 82.29092 -233.075988) (xy 82.1563 -232.941114) (xy 82.058764 -232.987596)
			(xy 82.02295 -233.02341) (xy 82.208878 -233.209338)
		)
		(stroke
			(width 0)
			(type solid)
		)
		(fill yes)
		(layer "F.Cu")
		(net "M_A_CPU1_SB_DQ<14>")
	)
	(gr_poly
		(pts
			(xy 82.252312 -294.701722) (xy 82.252312 -294.511222) (xy 82.150712 -294.4749) (xy 82.099912 -294.4749)
			(xy 82.099912 -294.73779) (xy 82.150712 -294.73779)
		)
		(stroke
			(width 0)
			(type solid)
		)
		(fill yes)
		(layer "F.Cu")
		(net "M_A_CPU1_SA_DQ<6>")
	)
	(gr_poly
		(pts
			(xy 82.252312 -294.104822) (xy 82.252312 -293.914322) (xy 82.150712 -293.878) (xy 82.099912 -293.878)
			(xy 82.099912 -294.14089) (xy 82.150712 -294.14089)
		)
		(stroke
			(width 0)
			(type solid)
		)
		(fill yes)
		(layer "F.Cu")
		(net "M_A_CPU1_SA_DQ<6>")
	)
	(gr_poly
		(pts
			(xy 82.252312 -293.507922) (xy 82.252312 -293.317422) (xy 82.150712 -293.2811) (xy 82.099912 -293.2811)
			(xy 82.099912 -293.54399) (xy 82.150712 -293.54399)
		)
		(stroke
			(width 0)
			(type solid)
		)
		(fill yes)
		(layer "F.Cu")
		(net "M_A_CPU1_SA_DQ<6>")
	)
	(gr_poly
		(pts
			(xy 82.252312 -292.911022) (xy 82.252312 -292.720522) (xy 82.150712 -292.6842) (xy 82.099912 -292.6842)
			(xy 82.099912 -292.94709) (xy 82.150712 -292.94709)
		)
		(stroke
			(width 0)
			(type solid)
		)
		(fill yes)
		(layer "F.Cu")
		(net "M_A_CPU1_SA_DQ<6>")
	)
	(gr_poly
		(pts
			(xy 82.252312 -292.314122) (xy 82.252312 -292.123622) (xy 82.150712 -292.0873) (xy 82.099912 -292.0873)
			(xy 82.099912 -292.35019) (xy 82.150712 -292.35019)
		)
		(stroke
			(width 0)
			(type solid)
		)
		(fill yes)
		(layer "F.Cu")
		(net "M_A_CPU1_SA_DQ<6>")
	)
	(gr_poly
		(pts
			(xy 82.252312 -291.717222) (xy 82.252312 -291.526722) (xy 82.150712 -291.4904) (xy 82.099912 -291.4904)
			(xy 82.099912 -291.75329) (xy 82.150712 -291.75329)
		)
		(stroke
			(width 0)
			(type solid)
		)
		(fill yes)
		(layer "F.Cu")
		(net "M_A_CPU1_SA_DQ<6>")
	)
	(gr_poly
		(pts
			(xy 82.252312 -291.120322) (xy 82.252312 -290.929822) (xy 82.150712 -290.8935) (xy 82.099912 -290.8935)
			(xy 82.099912 -291.15639) (xy 82.150712 -291.15639)
		)
		(stroke
			(width 0)
			(type solid)
		)
		(fill yes)
		(layer "F.Cu")
		(net "M_A_CPU1_SA_DQ<6>")
	)
	(gr_poly
		(pts
			(xy 82.252312 -290.523422) (xy 82.252312 -290.332922) (xy 82.150712 -290.2966) (xy 82.099912 -290.2966)
			(xy 82.099912 -290.55949) (xy 82.150712 -290.55949)
		)
		(stroke
			(width 0)
			(type solid)
		)
		(fill yes)
		(layer "F.Cu")
		(net "M_A_CPU1_SA_DQ<6>")
	)
	(gr_poly
		(pts
			(xy 82.252312 -289.926522) (xy 82.252312 -289.736022) (xy 82.150712 -289.6997) (xy 82.099912 -289.6997)
			(xy 82.099912 -289.96259) (xy 82.150712 -289.96259)
		)
		(stroke
			(width 0)
			(type solid)
		)
		(fill yes)
		(layer "F.Cu")
		(net "M_A_CPU1_SA_DQ<6>")
	)
	(gr_poly
		(pts
			(xy 82.252312 -289.329622) (xy 82.252312 -289.139122) (xy 82.150712 -289.1028) (xy 82.099912 -289.1028)
			(xy 82.099912 -289.36569) (xy 82.150712 -289.36569)
		)
		(stroke
			(width 0)
			(type solid)
		)
		(fill yes)
		(layer "F.Cu")
		(net "M_A_CPU1_SA_DQ<6>")
	)
	(gr_poly
		(pts
			(xy 82.252312 -288.732722) (xy 82.252312 -288.542222) (xy 82.150712 -288.5059) (xy 82.099912 -288.5059)
			(xy 82.099912 -288.76879) (xy 82.150712 -288.76879)
		)
		(stroke
			(width 0)
			(type solid)
		)
		(fill yes)
		(layer "F.Cu")
		(net "M_A_CPU1_SA_DQ<6>")
	)
	(gr_poly
		(pts
			(xy 82.252312 -288.135822) (xy 82.252312 -287.945322) (xy 82.150712 -287.909) (xy 82.099912 -287.909)
			(xy 82.099912 -288.17189) (xy 82.150712 -288.17189)
		)
		(stroke
			(width 0)
			(type solid)
		)
		(fill yes)
		(layer "F.Cu")
		(net "M_A_CPU1_SA_DQ<6>")
	)
	(gr_poly
		(pts
			(xy 82.252312 -287.538922) (xy 82.252312 -287.348422) (xy 82.150712 -287.3121) (xy 82.099912 -287.3121)
			(xy 82.099912 -287.57499) (xy 82.150712 -287.57499)
		)
		(stroke
			(width 0)
			(type solid)
		)
		(fill yes)
		(layer "F.Cu")
		(net "M_A_CPU1_SA_DQ<6>")
	)
	(gr_poly
		(pts
			(xy 82.252312 -286.942022) (xy 82.252312 -286.751522) (xy 82.150712 -286.7152) (xy 82.099912 -286.7152)
			(xy 82.099912 -286.97809) (xy 82.150712 -286.97809)
		)
		(stroke
			(width 0)
			(type solid)
		)
		(fill yes)
		(layer "F.Cu")
		(net "M_A_CPU1_SA_DQ<6>")
	)
	(gr_poly
		(pts
			(xy 82.252312 -286.345122) (xy 82.252312 -286.154622) (xy 82.150712 -286.1183) (xy 82.099912 -286.1183)
			(xy 82.099912 -286.38119) (xy 82.150712 -286.38119)
		)
		(stroke
			(width 0)
			(type solid)
		)
		(fill yes)
		(layer "F.Cu")
		(net "M_A_CPU1_SA_DQ<6>")
	)
	(gr_poly
		(pts
			(xy 82.252312 -285.748222) (xy 82.252312 -285.557722) (xy 82.150712 -285.5214) (xy 82.099912 -285.5214)
			(xy 82.099912 -285.78429) (xy 82.150712 -285.78429)
		)
		(stroke
			(width 0)
			(type solid)
		)
		(fill yes)
		(layer "F.Cu")
		(net "M_A_CPU1_SA_DQ<6>")
	)
	(gr_poly
		(pts
			(xy 82.252312 -285.151322) (xy 82.252312 -284.960822) (xy 82.150712 -284.9245) (xy 82.099912 -284.9245)
			(xy 82.099912 -285.18739) (xy 82.150712 -285.18739)
		)
		(stroke
			(width 0)
			(type solid)
		)
		(fill yes)
		(layer "F.Cu")
		(net "M_A_CPU1_SA_DQ<6>")
	)
	(gr_poly
		(pts
			(xy 82.252312 -284.554422) (xy 82.252312 -284.363922) (xy 82.150712 -284.3276) (xy 82.099912 -284.3276)
			(xy 82.099912 -284.59049) (xy 82.150712 -284.59049)
		)
		(stroke
			(width 0)
			(type solid)
		)
		(fill yes)
		(layer "F.Cu")
		(net "M_A_CPU1_SA_DQ<6>")
	)
	(gr_poly
		(pts
			(xy 82.252312 -283.957522) (xy 82.252312 -283.767022) (xy 82.150712 -283.7307) (xy 82.099912 -283.7307)
			(xy 82.099912 -283.99359) (xy 82.150712 -283.99359)
		)
		(stroke
			(width 0)
			(type solid)
		)
		(fill yes)
		(layer "F.Cu")
		(net "M_A_CPU1_SA_DQ<6>")
	)
	(gr_poly
		(pts
			(xy 82.252312 -283.360622) (xy 82.252312 -283.170122) (xy 82.150712 -283.1338) (xy 82.099912 -283.1338)
			(xy 82.099912 -283.39669) (xy 82.150712 -283.39669)
		)
		(stroke
			(width 0)
			(type solid)
		)
		(fill yes)
		(layer "F.Cu")
		(net "M_A_CPU1_SA_DQ<6>")
	)
	(gr_poly
		(pts
			(xy 82.252312 -282.763722) (xy 82.252312 -282.573222) (xy 82.150712 -282.5369) (xy 82.099912 -282.5369)
			(xy 82.099912 -282.79979) (xy 82.150712 -282.79979)
		)
		(stroke
			(width 0)
			(type solid)
		)
		(fill yes)
		(layer "F.Cu")
		(net "M_A_CPU1_SA_DQ<6>")
	)
	(gr_poly
		(pts
			(xy 82.25409 -232.320084) (xy 82.300318 -232.222548) (xy 82.165444 -232.087928) (xy 82.068162 -232.134156)
			(xy 82.032094 -232.16997) (xy 82.218022 -232.355898)
		)
		(stroke
			(width 0)
			(type solid)
		)
		(fill yes)
		(layer "F.Cu")
		(net "M_A_CPU1_SB_DQ<15>")
	)
	(gr_poly
		(pts
			(xy 82.263996 -231.050592) (xy 82.310224 -230.95331) (xy 82.175604 -230.818436) (xy 82.078068 -230.864664)
			(xy 82.042254 -230.900732) (xy 82.228182 -231.08666)
		)
		(stroke
			(width 0)
			(type solid)
		)
		(fill yes)
		(layer "F.Cu")
		(net "M_A_CPU1_SB_DQ<18>")
	)
	(gr_poly
		(pts
			(xy 82.265012 -273.482562) (xy 82.218784 -273.385026) (xy 82.18297 -273.349212) (xy 81.997042 -273.534886)
			(xy 82.032856 -273.570954) (xy 82.130392 -273.617182)
		)
		(stroke
			(width 0)
			(type solid)
		)
		(fill yes)
		(layer "F.Cu")
		(net "M_A_CPU1_SA_DQ<21>")
	)
	(gr_poly
		(pts
			(xy 82.270346 -280.381456) (xy 82.307938 -280.194512) (xy 82.215228 -280.13914) (xy 82.165444 -280.129234)
			(xy 82.113882 -280.387044) (xy 82.163666 -280.39695)
		)
		(stroke
			(width 0)
			(type solid)
		)
		(fill yes)
		(layer "F.Cu")
		(net "M_A_CPU1_SA_DQ<5>")
	)
	(gr_poly
		(pts
			(xy 82.27314 -230.197152) (xy 82.319368 -230.09987) (xy 82.184748 -229.964996) (xy 82.087212 -230.011478)
			(xy 82.051398 -230.047292) (xy 82.237326 -230.23322)
		)
		(stroke
			(width 0)
			(type solid)
		)
		(fill yes)
		(layer "F.Cu")
		(net "M_A_CPU1_SB_DQ<19>")
	)
	(gr_poly
		(pts
			(xy 82.274156 -259.618226) (xy 82.238088 -259.516626) (xy 82.047588 -259.516626) (xy 82.011266 -259.618226)
			(xy 82.011266 -259.669026) (xy 82.274156 -259.669026)
		)
		(stroke
			(width 0)
			(type solid)
		)
		(fill yes)
		(layer "F.Cu")
		(net "M_A_CPU1_SA_CS_N<0>")
	)
	(gr_poly
		(pts
			(xy 82.274156 -259.313426) (xy 82.238088 -259.211826) (xy 82.047588 -259.211826) (xy 82.011266 -259.313426)
			(xy 82.011266 -259.364226) (xy 82.274156 -259.364226)
		)
		(stroke
			(width 0)
			(type solid)
		)
		(fill yes)
		(layer "F.Cu")
		(net "M_A_CPU1_SA_CS_N<2>")
	)
	(gr_poly
		(pts
			(xy 82.274156 -259.008626) (xy 82.238088 -258.907026) (xy 82.047588 -258.907026) (xy 82.011266 -259.008626)
			(xy 82.011266 -259.059426) (xy 82.274156 -259.059426)
		)
		(stroke
			(width 0)
			(type solid)
		)
		(fill yes)
		(layer "F.Cu")
		(net "M_A_CPU1_SA_CS_N<3>")
	)
	(gr_poly
		(pts
			(xy 82.274156 -258.703826) (xy 82.238088 -258.602226) (xy 82.047588 -258.602226) (xy 82.011266 -258.703826)
			(xy 82.011266 -258.754626) (xy 82.274156 -258.754626)
		)
		(stroke
			(width 0)
			(type solid)
		)
		(fill yes)
		(layer "F.Cu")
		(net "M_A_CPU1_SA_CS_N<1>")
	)
	(gr_poly
		(pts
			(xy 82.274156 -258.399026) (xy 82.238088 -258.297426) (xy 82.047588 -258.297426) (xy 82.011266 -258.399026)
			(xy 82.011266 -258.449826) (xy 82.274156 -258.449826)
		)
		(stroke
			(width 0)
			(type solid)
		)
		(fill yes)
		(layer "F.Cu")
		(net "M_A_CPU1_SA_CA<0>")
	)
	(gr_poly
		(pts
			(xy 82.274156 -258.094226) (xy 82.238088 -257.992626) (xy 82.047588 -257.992626) (xy 82.011266 -258.094226)
			(xy 82.011266 -258.145026) (xy 82.274156 -258.145026)
		)
		(stroke
			(width 0)
			(type solid)
		)
		(fill yes)
		(layer "F.Cu")
		(net "M_A_CPU1_SA_CA<1>")
	)
	(gr_poly
		(pts
			(xy 82.274156 -257.789426) (xy 82.238088 -257.687826) (xy 82.047588 -257.687826) (xy 82.011266 -257.789426)
			(xy 82.011266 -257.840226) (xy 82.274156 -257.840226)
		)
		(stroke
			(width 0)
			(type solid)
		)
		(fill yes)
		(layer "F.Cu")
		(net "M_A_CPU1_SA_CA<2>")
	)
	(gr_poly
		(pts
			(xy 82.275172 -274.336764) (xy 82.228944 -274.239228) (xy 82.192876 -274.203414) (xy 82.006948 -274.389342)
			(xy 82.043016 -274.425156) (xy 82.140298 -274.471384)
		)
		(stroke
			(width 0)
			(type solid)
		)
		(fill yes)
		(layer "F.Cu")
		(net "M_A_CPU1_SA_DQ<20>")
	)
	(gr_poly
		(pts
			(xy 82.278982 -228.046788) (xy 82.32521 -227.949252) (xy 82.19059 -227.814632) (xy 82.093054 -227.86086)
			(xy 82.05724 -227.896674) (xy 82.243168 -228.082602)
		)
		(stroke
			(width 0)
			(type solid)
		)
		(fill yes)
		(layer "F.Cu")
		(net "M_A_CPU1_SB_DQ<20>")
	)
	(gr_poly
		(pts
			(xy 82.28838 -227.193094) (xy 82.334608 -227.095812) (xy 82.199988 -226.960938) (xy 82.102452 -227.007166)
			(xy 82.066638 -227.043234) (xy 82.252566 -227.229162)
		)
		(stroke
			(width 0)
			(type solid)
		)
		(fill yes)
		(layer "F.Cu")
		(net "M_A_CPU1_SB_DQ<21>")
	)
	(gr_poly
		(pts
			(xy 82.288888 -281.067002) (xy 82.239104 -281.056842) (xy 82.13217 -281.072336) (xy 82.094832 -281.25928)
			(xy 82.187288 -281.314652) (xy 82.237072 -281.324558)
		)
		(stroke
			(width 0)
			(type solid)
		)
		(fill yes)
		(layer "F.Cu")
		(net "M_A_CPU1_SA_DQ<6>")
	)
	(gr_poly
		(pts
			(xy 82.290412 -276.697694) (xy 82.254598 -276.661626) (xy 82.157062 -276.615398) (xy 82.022442 -276.750018)
			(xy 82.06867 -276.847554) (xy 82.104738 -276.883368)
		)
		(stroke
			(width 0)
			(type solid)
		)
		(fill yes)
		(layer "F.Cu")
		(net "M_A_CPU1_SA_DQ<17>")
	)
	(gr_poly
		(pts
			(xy 82.29981 -277.551134) (xy 82.263996 -277.515066) (xy 82.16646 -277.468838) (xy 82.03184 -277.603712)
			(xy 82.078068 -277.700994) (xy 82.113882 -277.737062)
		)
		(stroke
			(width 0)
			(type solid)
		)
		(fill yes)
		(layer "F.Cu")
		(net "M_A_CPU1_SA_DQ<16>")
	)
	(gr_poly
		(pts
			(xy 82.314034 -267.58392) (xy 82.277966 -267.548106) (xy 82.180684 -267.501878) (xy 82.04581 -267.636498)
			(xy 82.092038 -267.734034) (xy 82.128106 -267.769848)
		)
		(stroke
			(width 0)
			(type solid)
		)
		(fill yes)
		(layer "F.Cu")
		(net "M_A_CPU1_SA_DQ<29>")
	)
	(gr_poly
		(pts
			(xy 82.315304 -217.801698) (xy 82.264504 -217.801698) (xy 82.162904 -217.837766) (xy 82.162904 -218.028266)
			(xy 82.264504 -218.064334) (xy 82.315304 -218.064334)
		)
		(stroke
			(width 0)
			(type solid)
		)
		(fill yes)
		(layer "F.Cu")
		(net "M_A_CPU1_SB_DQ<27>")
	)
	(gr_poly
		(pts
			(xy 82.315304 -217.204798) (xy 82.264504 -217.204798) (xy 82.162904 -217.240866) (xy 82.162904 -217.431366)
			(xy 82.264504 -217.467434) (xy 82.315304 -217.467434)
		)
		(stroke
			(width 0)
			(type solid)
		)
		(fill yes)
		(layer "F.Cu")
		(net "M_A_CPU1_SB_DQ<27>")
	)
	(gr_poly
		(pts
			(xy 82.315304 -216.607898) (xy 82.264504 -216.607898) (xy 82.162904 -216.643966) (xy 82.162904 -216.834466)
			(xy 82.264504 -216.870534) (xy 82.315304 -216.870534)
		)
		(stroke
			(width 0)
			(type solid)
		)
		(fill yes)
		(layer "F.Cu")
		(net "M_A_CPU1_SB_DQ<27>")
	)
	(gr_poly
		(pts
			(xy 82.319622 -271.246346) (xy 82.273394 -271.149064) (xy 82.23758 -271.112996) (xy 82.051652 -271.298924)
			(xy 82.087466 -271.334992) (xy 82.185002 -271.38122)
		)
		(stroke
			(width 0)
			(type solid)
		)
		(fill yes)
		(layer "F.Cu")
		(net "M_A_CPU1_SA_DQ<25>")
	)
	(gr_poly
		(pts
			(xy 82.319622 -264.152634) (xy 82.273394 -264.055098) (xy 82.23758 -264.019284) (xy 82.051652 -264.205212)
			(xy 82.08772 -264.241026) (xy 82.185002 -264.287254)
		)
		(stroke
			(width 0)
			(type solid)
		)
		(fill yes)
		(layer "F.Cu")
		(net "M_A_CPU1_SA_CB<1>")
	)
	(gr_poly
		(pts
			(xy 82.323432 -268.437868) (xy 82.287618 -268.4018) (xy 82.190082 -268.355572) (xy 82.055462 -268.490192)
			(xy 82.10169 -268.587728) (xy 82.137758 -268.623542)
		)
		(stroke
			(width 0)
			(type solid)
		)
		(fill yes)
		(layer "F.Cu")
		(net "M_A_CPU1_SA_DQ<28>")
	)
	(gr_poly
		(pts
			(xy 82.328766 -272.099786) (xy 82.282538 -272.00225) (xy 82.246724 -271.966436) (xy 82.060796 -272.152364)
			(xy 82.096864 -272.188178) (xy 82.194146 -272.234406)
		)
		(stroke
			(width 0)
			(type solid)
		)
		(fill yes)
		(layer "F.Cu")
		(net "M_A_CPU1_SA_DQ<24>")
	)
	(gr_poly
		(pts
			(xy 82.32902 -265.006074) (xy 82.282792 -264.908792) (xy 82.246978 -264.872724) (xy 82.06105 -265.058652)
			(xy 82.096864 -265.094466) (xy 82.1944 -265.140948)
		)
		(stroke
			(width 0)
			(type solid)
		)
		(fill yes)
		(layer "F.Cu")
		(net "M_A_CPU1_SA_CB<0>")
	)
	(gr_poly
		(pts
			(xy 82.335116 -281.611832) (xy 82.372454 -281.424888) (xy 82.279998 -281.369516) (xy 82.230214 -281.35961)
			(xy 82.178652 -281.617166) (xy 82.228436 -281.627326)
		)
		(stroke
			(width 0)
			(type solid)
		)
		(fill yes)
		(layer "F.Cu")
		(net "M_A_CPU1_SA_DQ<6>")
	)
	(gr_poly
		(pts
			(xy 82.341212 -279.251156) (xy 82.291428 -279.24125) (xy 82.184748 -279.256998) (xy 82.14741 -279.443688)
			(xy 82.239866 -279.49906) (xy 82.28965 -279.508966)
		)
		(stroke
			(width 0)
			(type solid)
		)
		(fill yes)
		(layer "F.Cu")
		(net "M_A_CPU1_SA_DQ<5>")
	)
	(gr_poly
		(pts
			(xy 82.366358 -276.402546) (xy 82.32013 -276.305264) (xy 82.284316 -276.269196) (xy 82.098388 -276.455124)
			(xy 82.134202 -276.491192) (xy 82.231738 -276.53742)
		)
		(stroke
			(width 0)
			(type solid)
		)
		(fill yes)
		(layer "F.Cu")
		(net "M_A_CPU1_SA_DQ<19>")
	)
	(gr_poly
		(pts
			(xy 82.37728 -277.257764) (xy 82.331052 -277.160228) (xy 82.295238 -277.12416) (xy 82.10931 -277.310088)
			(xy 82.145124 -277.346156) (xy 82.24266 -277.392384)
		)
		(stroke
			(width 0)
			(type solid)
		)
		(fill yes)
		(layer "F.Cu")
		(net "M_A_CPU1_SA_DQ<18>")
	)
	(gr_poly
		(pts
			(xy 82.387694 -279.79624) (xy 82.425032 -279.609296) (xy 82.332576 -279.553924) (xy 82.282792 -279.544018)
			(xy 82.230976 -279.801828) (xy 82.281014 -279.811734)
		)
		(stroke
			(width 0)
			(type solid)
		)
		(fill yes)
		(layer "F.Cu")
		(net "M_A_CPU1_SA_DQ<5>")
	)
	(gr_poly
		(pts
			(xy 82.39125 -267.29055) (xy 82.345022 -267.193014) (xy 82.309208 -267.1572) (xy 82.12328 -267.343128)
			(xy 82.159348 -267.378942) (xy 82.25663 -267.42517)
		)
		(stroke
			(width 0)
			(type solid)
		)
		(fill yes)
		(layer "F.Cu")
		(net "M_A_CPU1_SA_DQ<31>")
	)
	(gr_poly
		(pts
			(xy 82.393282 -232.602786) (xy 82.429096 -232.566972) (xy 82.243168 -232.381044) (xy 82.207354 -232.416858)
			(xy 82.161126 -232.514394) (xy 82.295746 -232.649014)
		)
		(stroke
			(width 0)
			(type solid)
		)
		(fill yes)
		(layer "F.Cu")
		(net "M_A_CPU1_SB_DQ<15>")
	)
	(gr_poly
		(pts
			(xy 82.394044 -273.138138) (xy 82.357976 -273.102324) (xy 82.260694 -273.055842) (xy 82.12582 -273.190716)
			(xy 82.172048 -273.287998) (xy 82.208116 -273.324066)
		)
		(stroke
			(width 0)
			(type solid)
		)
		(fill yes)
		(layer "F.Cu")
		(net "M_A_CPU1_SA_DQ<21>")
	)
	(gr_poly
		(pts
			(xy 82.401156 -268.144498) (xy 82.354928 -268.046962) (xy 82.31886 -268.011148) (xy 82.132932 -268.197076)
			(xy 82.169 -268.23289) (xy 82.266282 -268.279118)
		)
		(stroke
			(width 0)
			(type solid)
		)
		(fill yes)
		(layer "F.Cu")
		(net "M_A_CPU1_SA_DQ<30>")
	)
	(gr_poly
		(pts
			(xy 82.403188 -231.333548) (xy 82.439002 -231.29748) (xy 82.253328 -231.111806) (xy 82.21726 -231.14762)
			(xy 82.171032 -231.245156) (xy 82.305652 -231.379776)
		)
		(stroke
			(width 0)
			(type solid)
		)
		(fill yes)
		(layer "F.Cu")
		(net "M_A_CPU1_SB_DQ<18>")
	)
	(gr_poly
		(pts
			(xy 82.40395 -273.99234) (xy 82.368136 -273.956526) (xy 82.2706 -273.910044) (xy 82.13598 -274.044918)
			(xy 82.182208 -274.1422) (xy 82.218022 -274.178268)
		)
		(stroke
			(width 0)
			(type solid)
		)
		(fill yes)
		(layer "F.Cu")
		(net "M_A_CPU1_SA_DQ<20>")
	)
	(gr_poly
		(pts
			(xy 82.404712 -294.77335) (xy 82.353912 -294.77335) (xy 82.252312 -294.809672) (xy 82.252312 -295.000172)
			(xy 82.353912 -295.03624) (xy 82.404712 -295.03624)
		)
		(stroke
			(width 0)
			(type solid)
		)
		(fill yes)
		(layer "F.Cu")
		(net "M_A_CPU1_SA_DQ<4>")
	)
	(gr_poly
		(pts
			(xy 82.404712 -294.17645) (xy 82.353912 -294.17645) (xy 82.252312 -294.212772) (xy 82.252312 -294.403272)
			(xy 82.353912 -294.43934) (xy 82.404712 -294.43934)
		)
		(stroke
			(width 0)
			(type solid)
		)
		(fill yes)
		(layer "F.Cu")
		(net "M_A_CPU1_SA_DQ<4>")
	)
	(gr_poly
		(pts
			(xy 82.404712 -293.57955) (xy 82.353912 -293.57955) (xy 82.252312 -293.615872) (xy 82.252312 -293.806372)
			(xy 82.353912 -293.84244) (xy 82.404712 -293.84244)
		)
		(stroke
			(width 0)
			(type solid)
		)
		(fill yes)
		(layer "F.Cu")
		(net "M_A_CPU1_SA_DQ<4>")
	)
	(gr_poly
		(pts
			(xy 82.404712 -292.98265) (xy 82.353912 -292.98265) (xy 82.252312 -293.018972) (xy 82.252312 -293.209472)
			(xy 82.353912 -293.24554) (xy 82.404712 -293.24554)
		)
		(stroke
			(width 0)
			(type solid)
		)
		(fill yes)
		(layer "F.Cu")
		(net "M_A_CPU1_SA_DQ<4>")
	)
	(gr_poly
		(pts
			(xy 82.404712 -292.38575) (xy 82.353912 -292.38575) (xy 82.252312 -292.422072) (xy 82.252312 -292.612572)
			(xy 82.353912 -292.64864) (xy 82.404712 -292.64864)
		)
		(stroke
			(width 0)
			(type solid)
		)
		(fill yes)
		(layer "F.Cu")
		(net "M_A_CPU1_SA_DQ<4>")
	)
	(gr_poly
		(pts
			(xy 82.404712 -291.78885) (xy 82.353912 -291.78885) (xy 82.252312 -291.825172) (xy 82.252312 -292.015672)
			(xy 82.353912 -292.05174) (xy 82.404712 -292.05174)
		)
		(stroke
			(width 0)
			(type solid)
		)
		(fill yes)
		(layer "F.Cu")
		(net "M_A_CPU1_SA_DQ<4>")
	)
	(gr_poly
		(pts
			(xy 82.404712 -291.19195) (xy 82.353912 -291.19195) (xy 82.252312 -291.228272) (xy 82.252312 -291.418772)
			(xy 82.353912 -291.45484) (xy 82.404712 -291.45484)
		)
		(stroke
			(width 0)
			(type solid)
		)
		(fill yes)
		(layer "F.Cu")
		(net "M_A_CPU1_SA_DQ<4>")
	)
	(gr_poly
		(pts
			(xy 82.404712 -290.59505) (xy 82.353912 -290.59505) (xy 82.252312 -290.631372) (xy 82.252312 -290.821872)
			(xy 82.353912 -290.85794) (xy 82.404712 -290.85794)
		)
		(stroke
			(width 0)
			(type solid)
		)
		(fill yes)
		(layer "F.Cu")
		(net "M_A_CPU1_SA_DQ<4>")
	)
	(gr_poly
		(pts
			(xy 82.404712 -289.99815) (xy 82.353912 -289.99815) (xy 82.252312 -290.034472) (xy 82.252312 -290.224972)
			(xy 82.353912 -290.26104) (xy 82.404712 -290.26104)
		)
		(stroke
			(width 0)
			(type solid)
		)
		(fill yes)
		(layer "F.Cu")
		(net "M_A_CPU1_SA_DQ<4>")
	)
	(gr_poly
		(pts
			(xy 82.404712 -289.40125) (xy 82.353912 -289.40125) (xy 82.252312 -289.437572) (xy 82.252312 -289.628072)
			(xy 82.353912 -289.66414) (xy 82.404712 -289.66414)
		)
		(stroke
			(width 0)
			(type solid)
		)
		(fill yes)
		(layer "F.Cu")
		(net "M_A_CPU1_SA_DQ<4>")
	)
	(gr_poly
		(pts
			(xy 82.404712 -288.80435) (xy 82.353912 -288.80435) (xy 82.252312 -288.840672) (xy 82.252312 -289.031172)
			(xy 82.353912 -289.06724) (xy 82.404712 -289.06724)
		)
		(stroke
			(width 0)
			(type solid)
		)
		(fill yes)
		(layer "F.Cu")
		(net "M_A_CPU1_SA_DQ<4>")
	)
	(gr_poly
		(pts
			(xy 82.404712 -288.20745) (xy 82.353912 -288.20745) (xy 82.252312 -288.243772) (xy 82.252312 -288.434272)
			(xy 82.353912 -288.47034) (xy 82.404712 -288.47034)
		)
		(stroke
			(width 0)
			(type solid)
		)
		(fill yes)
		(layer "F.Cu")
		(net "M_A_CPU1_SA_DQ<4>")
	)
	(gr_poly
		(pts
			(xy 82.404712 -287.61055) (xy 82.353912 -287.61055) (xy 82.252312 -287.646872) (xy 82.252312 -287.837372)
			(xy 82.353912 -287.87344) (xy 82.404712 -287.87344)
		)
		(stroke
			(width 0)
			(type solid)
		)
		(fill yes)
		(layer "F.Cu")
		(net "M_A_CPU1_SA_DQ<4>")
	)
	(gr_poly
		(pts
			(xy 82.404712 -287.01365) (xy 82.353912 -287.01365) (xy 82.252312 -287.049972) (xy 82.252312 -287.240472)
			(xy 82.353912 -287.27654) (xy 82.404712 -287.27654)
		)
		(stroke
			(width 0)
			(type solid)
		)
		(fill yes)
		(layer "F.Cu")
		(net "M_A_CPU1_SA_DQ<4>")
	)
	(gr_poly
		(pts
			(xy 82.404712 -286.41675) (xy 82.353912 -286.41675) (xy 82.252312 -286.453072) (xy 82.252312 -286.643572)
			(xy 82.353912 -286.67964) (xy 82.404712 -286.67964)
		)
		(stroke
			(width 0)
			(type solid)
		)
		(fill yes)
		(layer "F.Cu")
		(net "M_A_CPU1_SA_DQ<4>")
	)
	(gr_poly
		(pts
			(xy 82.404712 -285.81985) (xy 82.353912 -285.81985) (xy 82.252312 -285.856172) (xy 82.252312 -286.046672)
			(xy 82.353912 -286.08274) (xy 82.404712 -286.08274)
		)
		(stroke
			(width 0)
			(type solid)
		)
		(fill yes)
		(layer "F.Cu")
		(net "M_A_CPU1_SA_DQ<4>")
	)
	(gr_poly
		(pts
			(xy 82.404712 -285.22295) (xy 82.353912 -285.22295) (xy 82.252312 -285.259272) (xy 82.252312 -285.449772)
			(xy 82.353912 -285.48584) (xy 82.404712 -285.48584)
		)
		(stroke
			(width 0)
			(type solid)
		)
		(fill yes)
		(layer "F.Cu")
		(net "M_A_CPU1_SA_DQ<4>")
	)
	(gr_poly
		(pts
			(xy 82.404712 -284.62605) (xy 82.353912 -284.62605) (xy 82.252312 -284.662372) (xy 82.252312 -284.852872)
			(xy 82.353912 -284.88894) (xy 82.404712 -284.88894)
		)
		(stroke
			(width 0)
			(type solid)
		)
		(fill yes)
		(layer "F.Cu")
		(net "M_A_CPU1_SA_DQ<4>")
	)
	(gr_poly
		(pts
			(xy 82.404712 -284.02915) (xy 82.353912 -284.02915) (xy 82.252312 -284.065472) (xy 82.252312 -284.255972)
			(xy 82.353912 -284.29204) (xy 82.404712 -284.29204)
		)
		(stroke
			(width 0)
			(type solid)
		)
		(fill yes)
		(layer "F.Cu")
		(net "M_A_CPU1_SA_DQ<4>")
	)
	(gr_poly
		(pts
			(xy 82.404712 -283.43225) (xy 82.353912 -283.43225) (xy 82.252312 -283.468572) (xy 82.252312 -283.659072)
			(xy 82.353912 -283.69514) (xy 82.404712 -283.69514)
		)
		(stroke
			(width 0)
			(type solid)
		)
		(fill yes)
		(layer "F.Cu")
		(net "M_A_CPU1_SA_DQ<4>")
	)
	(gr_poly
		(pts
			(xy 82.404712 -282.83535) (xy 82.353912 -282.83535) (xy 82.252312 -282.871672) (xy 82.252312 -283.062172)
			(xy 82.353912 -283.09824) (xy 82.404712 -283.09824)
		)
		(stroke
			(width 0)
			(type solid)
		)
		(fill yes)
		(layer "F.Cu")
		(net "M_A_CPU1_SA_DQ<4>")
	)
	(gr_poly
		(pts
			(xy 82.405982 -280.481532) (xy 82.356198 -280.471626) (xy 82.249518 -280.48712) (xy 82.21218 -280.674064)
			(xy 82.304636 -280.729436) (xy 82.35442 -280.739342)
		)
		(stroke
			(width 0)
			(type solid)
		)
		(fill yes)
		(layer "F.Cu")
		(net "M_A_CPU1_SA_DQ<6>")
	)
	(gr_poly
		(pts
			(xy 82.412332 -230.480108) (xy 82.4484 -230.444294) (xy 82.262472 -230.258366) (xy 82.226404 -230.29418)
			(xy 82.180176 -230.391716) (xy 82.31505 -230.526336)
		)
		(stroke
			(width 0)
			(type solid)
		)
		(fill yes)
		(layer "F.Cu")
		(net "M_A_CPU1_SB_DQ<19>")
	)
	(gr_poly
		(pts
			(xy 82.418174 -228.32949) (xy 82.454242 -228.293676) (xy 82.268314 -228.107748) (xy 82.2325 -228.143562)
			(xy 82.186018 -228.241098) (xy 82.320892 -228.375718)
		)
		(stroke
			(width 0)
			(type solid)
		)
		(fill yes)
		(layer "F.Cu")
		(net "M_A_CPU1_SB_DQ<20>")
	)
	(gr_poly
		(pts
			(xy 82.427572 -227.47605) (xy 82.46364 -227.440236) (xy 82.277712 -227.254308) (xy 82.241644 -227.290122)
			(xy 82.195416 -227.387658) (xy 82.33029 -227.522278)
		)
		(stroke
			(width 0)
			(type solid)
		)
		(fill yes)
		(layer "F.Cu")
		(net "M_A_CPU1_SB_DQ<21>")
	)
	(gr_poly
		(pts
			(xy 82.448654 -270.901922) (xy 82.412586 -270.866108) (xy 82.315304 -270.81988) (xy 82.18043 -270.9545)
			(xy 82.226658 -271.052036) (xy 82.262726 -271.08785)
		)
		(stroke
			(width 0)
			(type solid)
		)
		(fill yes)
		(layer "F.Cu")
		(net "M_A_CPU1_SA_DQ<25>")
	)
	(gr_poly
		(pts
			(xy 82.448654 -263.80821) (xy 82.412586 -263.772396) (xy 82.315304 -263.726168) (xy 82.18043 -263.860788)
			(xy 82.226912 -263.958324) (xy 82.262726 -263.994138)
		)
		(stroke
			(width 0)
			(type solid)
		)
		(fill yes)
		(layer "F.Cu")
		(net "M_A_CPU1_SA_CB<1>")
	)
	(gr_poly
		(pts
			(xy 82.45221 -281.026362) (xy 82.489802 -280.839672) (xy 82.397346 -280.7843) (xy 82.347308 -280.77414)
			(xy 82.295746 -281.03195) (xy 82.34553 -281.04211)
		)
		(stroke
			(width 0)
			(type solid)
		)
		(fill yes)
		(layer "F.Cu")
		(net "M_A_CPU1_SA_DQ<6>")
	)
	(gr_poly
		(pts
			(xy 82.457798 -271.755362) (xy 82.42173 -271.719548) (xy 82.324448 -271.67332) (xy 82.189574 -271.80794)
			(xy 82.236056 -271.905476) (xy 82.27187 -271.94129)
		)
		(stroke
			(width 0)
			(type solid)
		)
		(fill yes)
		(layer "F.Cu")
		(net "M_A_CPU1_SA_DQ<24>")
	)
	(gr_poly
		(pts
			(xy 82.458052 -264.66165) (xy 82.421984 -264.625836) (xy 82.324702 -264.579608) (xy 82.189828 -264.714228)
			(xy 82.236056 -264.811764) (xy 82.272124 -264.847578)
		)
		(stroke
			(width 0)
			(type solid)
		)
		(fill yes)
		(layer "F.Cu")
		(net "M_A_CPU1_SA_CB<0>")
	)
	(gr_poly
		(pts
			(xy 82.460338 -232.957624) (xy 82.506566 -232.860342) (xy 82.371946 -232.725468) (xy 82.27441 -232.77195)
			(xy 82.238596 -232.807764) (xy 82.424524 -232.993692)
		)
		(stroke
			(width 0)
			(type solid)
		)
		(fill yes)
		(layer "F.Cu")
		(net "M_A_CPU1_SB_DQ<13>")
	)
	(gr_poly
		(pts
			(xy 82.467704 -218.326716) (xy 82.467704 -218.136216) (xy 82.366104 -218.099894) (xy 82.315304 -218.099894)
			(xy 82.315304 -218.363038) (xy 82.366104 -218.363038)
		)
		(stroke
			(width 0)
			(type solid)
		)
		(fill yes)
		(layer "F.Cu")
		(net "M_A_CPU1_SB_DQ<27>")
	)
	(gr_poly
		(pts
			(xy 82.467704 -217.729816) (xy 82.467704 -217.539316) (xy 82.366104 -217.502994) (xy 82.315304 -217.502994)
			(xy 82.315304 -217.766138) (xy 82.366104 -217.766138)
		)
		(stroke
			(width 0)
			(type solid)
		)
		(fill yes)
		(layer "F.Cu")
		(net "M_A_CPU1_SB_DQ<27>")
	)
	(gr_poly
		(pts
			(xy 82.467704 -217.132916) (xy 82.467704 -216.942416) (xy 82.366104 -216.906094) (xy 82.315304 -216.906094)
			(xy 82.315304 -217.169238) (xy 82.366104 -217.169238)
		)
		(stroke
			(width 0)
			(type solid)
		)
		(fill yes)
		(layer "F.Cu")
		(net "M_A_CPU1_SB_DQ<27>")
	)
	(gr_poly
		(pts
			(xy 82.467704 -216.536016) (xy 82.467704 -216.345516) (xy 82.366104 -216.309194) (xy 82.315304 -216.309194)
			(xy 82.315304 -216.572338) (xy 82.366104 -216.572338)
		)
		(stroke
			(width 0)
			(type solid)
		)
		(fill yes)
		(layer "F.Cu")
		(net "M_A_CPU1_SB_DQ<27>")
	)
	(gr_poly
		(pts
			(xy 82.470498 -231.688386) (xy 82.516726 -231.59085) (xy 82.381852 -231.45623) (xy 82.28457 -231.502458)
			(xy 82.248502 -231.538272) (xy 82.43443 -231.7242)
		)
		(stroke
			(width 0)
			(type solid)
		)
		(fill yes)
		(layer "F.Cu")
		(net "M_A_CPU1_SB_DQ<16>")
	)
	(gr_poly
		(pts
			(xy 82.471006 -281.711908) (xy 82.420968 -281.702002) (xy 82.314288 -281.717496) (xy 82.27695 -281.904186)
			(xy 82.369406 -281.959812) (xy 82.41919 -281.969718)
		)
		(stroke
			(width 0)
			(type solid)
		)
		(fill yes)
		(layer "F.Cu")
		(net "M_A_CPU1_SA_DQ<4>")
	)
	(gr_poly
		(pts
			(xy 82.471514 -272.844768) (xy 82.425286 -272.747232) (xy 82.389218 -272.711418) (xy 82.20329 -272.897092)
			(xy 82.239358 -272.93316) (xy 82.33664 -272.979388)
		)
		(stroke
			(width 0)
			(type solid)
		)
		(fill yes)
		(layer "F.Cu")
		(net "M_A_CPU1_SA_DQ<23>")
	)
	(gr_poly
		(pts
			(xy 82.479388 -238.659416) (xy 82.443066 -238.557816) (xy 82.252566 -238.557816) (xy 82.216244 -238.659416)
			(xy 82.216244 -238.710216) (xy 82.479388 -238.710216)
		)
		(stroke
			(width 0)
			(type solid)
		)
		(fill yes)
		(layer "F.Cu")
		(net "M_A_CPU1_SB_CB<0>")
	)
	(gr_poly
		(pts
			(xy 82.479388 -238.354616) (xy 82.443066 -238.253016) (xy 82.252566 -238.253016) (xy 82.216244 -238.354616)
			(xy 82.216244 -238.405416) (xy 82.479388 -238.405416)
		)
		(stroke
			(width 0)
			(type solid)
		)
		(fill yes)
		(layer "F.Cu")
		(net "M_A_CPU1_SB_CB<2>")
	)
	(gr_poly
		(pts
			(xy 82.479388 -238.049816) (xy 82.443066 -237.948216) (xy 82.252566 -237.948216) (xy 82.216244 -238.049816)
			(xy 82.216244 -238.100616) (xy 82.479388 -238.100616)
		)
		(stroke
			(width 0)
			(type solid)
		)
		(fill yes)
		(layer "F.Cu")
		(net "M_A_CPU1_SB_CB<1>")
	)
	(gr_poly
		(pts
			(xy 82.479388 -237.745016) (xy 82.443066 -237.643416) (xy 82.252566 -237.643416) (xy 82.216244 -237.745016)
			(xy 82.216244 -237.795816) (xy 82.479388 -237.795816)
		)
		(stroke
			(width 0)
			(type solid)
		)
		(fill yes)
		(layer "F.Cu")
		(net "M_A_CPU1_SB_CB<3>")
	)
	(gr_poly
		(pts
			(xy 82.479642 -230.834946) (xy 82.52587 -230.737664) (xy 82.39125 -230.60279) (xy 82.293714 -230.649018)
			(xy 82.2579 -230.685086) (xy 82.443828 -230.871014)
		)
		(stroke
			(width 0)
			(type solid)
		)
		(fill yes)
		(layer "F.Cu")
		(net "M_A_CPU1_SB_DQ<17>")
	)
	(gr_poly
		(pts
			(xy 82.480912 -273.698208) (xy 82.434684 -273.600926) (xy 82.398616 -273.564858) (xy 82.212688 -273.750786)
			(xy 82.248756 -273.7866) (xy 82.346038 -273.832828)
		)
		(stroke
			(width 0)
			(type solid)
		)
		(fill yes)
		(layer "F.Cu")
		(net "M_A_CPU1_SA_DQ<22>")
	)
	(gr_poly
		(pts
			(xy 82.494882 -227.830888) (xy 82.54111 -227.733352) (xy 82.40649 -227.598732) (xy 82.308954 -227.64496)
			(xy 82.27314 -227.681028) (xy 82.458814 -227.866702)
		)
		(stroke
			(width 0)
			(type solid)
		)
		(fill yes)
		(layer "F.Cu")
		(net "M_A_CPU1_SB_DQ<22>")
	)
	(gr_poly
		(pts
			(xy 82.49539 -276.058122) (xy 82.459322 -276.022308) (xy 82.36204 -275.97608) (xy 82.227166 -276.1107)
			(xy 82.273394 -276.208236) (xy 82.309462 -276.24405)
		)
		(stroke
			(width 0)
			(type solid)
		)
		(fill yes)
		(layer "F.Cu")
		(net "M_A_CPU1_SA_DQ<19>")
	)
	(gr_poly
		(pts
			(xy 82.504026 -226.977448) (xy 82.550254 -226.880166) (xy 82.415634 -226.745292) (xy 82.318098 -226.79152)
			(xy 82.282284 -226.827588) (xy 82.468212 -227.013516)
		)
		(stroke
			(width 0)
			(type solid)
		)
		(fill yes)
		(layer "F.Cu")
		(net "M_A_CPU1_SB_DQ<23>")
	)
	(gr_poly
		(pts
			(xy 82.504788 -279.21077) (xy 82.542126 -279.02408) (xy 82.44967 -278.968708) (xy 82.399886 -278.958548)
			(xy 82.348324 -279.216358) (xy 82.398108 -279.226518)
		)
		(stroke
			(width 0)
			(type solid)
		)
		(fill yes)
		(layer "F.Cu")
		(net "M_A_CPU1_SA_DQ<5>")
	)
	(gr_poly
		(pts
			(xy 82.506058 -276.91334) (xy 82.470244 -276.877272) (xy 82.372708 -276.831044) (xy 82.238088 -276.965664)
			(xy 82.284316 -277.0632) (xy 82.320384 -277.099014)
		)
		(stroke
			(width 0)
			(type solid)
		)
		(fill yes)
		(layer "F.Cu")
		(net "M_A_CPU1_SA_DQ<18>")
	)
	(gr_poly
		(pts
			(xy 82.520282 -266.946126) (xy 82.484214 -266.910312) (xy 82.386932 -266.864084) (xy 82.252058 -266.998704)
			(xy 82.29854 -267.09624) (xy 82.334354 -267.132054)
		)
		(stroke
			(width 0)
			(type solid)
		)
		(fill yes)
		(layer "F.Cu")
		(net "M_A_CPU1_SA_DQ<31>")
	)
	(gr_poly
		(pts
			(xy 82.52333 -279.896316) (xy 82.473292 -279.88641) (xy 82.366612 -279.901904) (xy 82.329274 -280.088594)
			(xy 82.42173 -280.14422) (xy 82.471514 -280.154126)
		)
		(stroke
			(width 0)
			(type solid)
		)
		(fill yes)
		(layer "F.Cu")
		(net "M_A_CPU1_SA_DQ<6>")
	)
	(gr_poly
		(pts
			(xy 82.52587 -270.608552) (xy 82.479642 -270.511016) (xy 82.443574 -270.475202) (xy 82.2579 -270.660876)
			(xy 82.293714 -270.696944) (xy 82.39125 -270.743172)
		)
		(stroke
			(width 0)
			(type solid)
		)
		(fill yes)
		(layer "F.Cu")
		(net "M_A_CPU1_SA_DQ<27>")
	)
	(gr_poly
		(pts
			(xy 82.529934 -267.800074) (xy 82.49412 -267.764006) (xy 82.396584 -267.717778) (xy 82.261964 -267.852652)
			(xy 82.308192 -267.949934) (xy 82.344006 -267.986002)
		)
		(stroke
			(width 0)
			(type solid)
		)
		(fill yes)
		(layer "F.Cu")
		(net "M_A_CPU1_SA_DQ<30>")
	)
	(gr_poly
		(pts
			(xy 82.535268 -271.461992) (xy 82.48904 -271.36471) (xy 82.453226 -271.328642) (xy 82.267298 -271.51457)
			(xy 82.303112 -271.550638) (xy 82.400648 -271.596866)
		)
		(stroke
			(width 0)
			(type solid)
		)
		(fill yes)
		(layer "F.Cu")
		(net "M_A_CPU1_SA_DQ<26>")
	)
	(gr_poly
		(pts
			(xy 82.535522 -264.368534) (xy 82.489294 -264.270998) (xy 82.453226 -264.235184) (xy 82.267552 -264.420858)
			(xy 82.303366 -264.456926) (xy 82.400902 -264.503154)
		)
		(stroke
			(width 0)
			(type solid)
		)
		(fill yes)
		(layer "F.Cu")
		(net "M_A_CPU1_SA_CB<2>")
	)
	(gr_poly
		(pts
			(xy 82.557112 -295.298622) (xy 82.557112 -295.108122) (xy 82.455512 -295.0718) (xy 82.404712 -295.0718)
			(xy 82.404712 -295.33469) (xy 82.455512 -295.33469)
		)
		(stroke
			(width 0)
			(type solid)
		)
		(fill yes)
		(layer "F.Cu")
		(net "M_A_CPU1_SA_DQ<4>")
	)
	(gr_poly
		(pts
			(xy 82.557112 -294.701722) (xy 82.557112 -294.511222) (xy 82.455512 -294.4749) (xy 82.404712 -294.4749)
			(xy 82.404712 -294.73779) (xy 82.455512 -294.73779)
		)
		(stroke
			(width 0)
			(type solid)
		)
		(fill yes)
		(layer "F.Cu")
		(net "M_A_CPU1_SA_DQ<4>")
	)
	(gr_poly
		(pts
			(xy 82.557112 -294.104822) (xy 82.557112 -293.914322) (xy 82.455512 -293.878) (xy 82.404712 -293.878)
			(xy 82.404712 -294.14089) (xy 82.455512 -294.14089)
		)
		(stroke
			(width 0)
			(type solid)
		)
		(fill yes)
		(layer "F.Cu")
		(net "M_A_CPU1_SA_DQ<4>")
	)
	(gr_poly
		(pts
			(xy 82.557112 -293.507922) (xy 82.557112 -293.317422) (xy 82.455512 -293.2811) (xy 82.404712 -293.2811)
			(xy 82.404712 -293.54399) (xy 82.455512 -293.54399)
		)
		(stroke
			(width 0)
			(type solid)
		)
		(fill yes)
		(layer "F.Cu")
		(net "M_A_CPU1_SA_DQ<4>")
	)
	(gr_poly
		(pts
			(xy 82.557112 -292.911022) (xy 82.557112 -292.720522) (xy 82.455512 -292.6842) (xy 82.404712 -292.6842)
			(xy 82.404712 -292.94709) (xy 82.455512 -292.94709)
		)
		(stroke
			(width 0)
			(type solid)
		)
		(fill yes)
		(layer "F.Cu")
		(net "M_A_CPU1_SA_DQ<4>")
	)
	(gr_poly
		(pts
			(xy 82.557112 -292.314122) (xy 82.557112 -292.123622) (xy 82.455512 -292.0873) (xy 82.404712 -292.0873)
			(xy 82.404712 -292.35019) (xy 82.455512 -292.35019)
		)
		(stroke
			(width 0)
			(type solid)
		)
		(fill yes)
		(layer "F.Cu")
		(net "M_A_CPU1_SA_DQ<4>")
	)
	(gr_poly
		(pts
			(xy 82.557112 -291.717222) (xy 82.557112 -291.526722) (xy 82.455512 -291.4904) (xy 82.404712 -291.4904)
			(xy 82.404712 -291.75329) (xy 82.455512 -291.75329)
		)
		(stroke
			(width 0)
			(type solid)
		)
		(fill yes)
		(layer "F.Cu")
		(net "M_A_CPU1_SA_DQ<4>")
	)
	(gr_poly
		(pts
			(xy 82.557112 -291.120322) (xy 82.557112 -290.929822) (xy 82.455512 -290.8935) (xy 82.404712 -290.8935)
			(xy 82.404712 -291.15639) (xy 82.455512 -291.15639)
		)
		(stroke
			(width 0)
			(type solid)
		)
		(fill yes)
		(layer "F.Cu")
		(net "M_A_CPU1_SA_DQ<4>")
	)
	(gr_poly
		(pts
			(xy 82.557112 -290.523422) (xy 82.557112 -290.332922) (xy 82.455512 -290.2966) (xy 82.404712 -290.2966)
			(xy 82.404712 -290.55949) (xy 82.455512 -290.55949)
		)
		(stroke
			(width 0)
			(type solid)
		)
		(fill yes)
		(layer "F.Cu")
		(net "M_A_CPU1_SA_DQ<4>")
	)
	(gr_poly
		(pts
			(xy 82.557112 -289.926522) (xy 82.557112 -289.736022) (xy 82.455512 -289.6997) (xy 82.404712 -289.6997)
			(xy 82.404712 -289.96259) (xy 82.455512 -289.96259)
		)
		(stroke
			(width 0)
			(type solid)
		)
		(fill yes)
		(layer "F.Cu")
		(net "M_A_CPU1_SA_DQ<4>")
	)
	(gr_poly
		(pts
			(xy 82.557112 -289.329622) (xy 82.557112 -289.139122) (xy 82.455512 -289.1028) (xy 82.404712 -289.1028)
			(xy 82.404712 -289.36569) (xy 82.455512 -289.36569)
		)
		(stroke
			(width 0)
			(type solid)
		)
		(fill yes)
		(layer "F.Cu")
		(net "M_A_CPU1_SA_DQ<4>")
	)
	(gr_poly
		(pts
			(xy 82.557112 -288.732722) (xy 82.557112 -288.542222) (xy 82.455512 -288.5059) (xy 82.404712 -288.5059)
			(xy 82.404712 -288.76879) (xy 82.455512 -288.76879)
		)
		(stroke
			(width 0)
			(type solid)
		)
		(fill yes)
		(layer "F.Cu")
		(net "M_A_CPU1_SA_DQ<4>")
	)
	(gr_poly
		(pts
			(xy 82.557112 -288.135822) (xy 82.557112 -287.945322) (xy 82.455512 -287.909) (xy 82.404712 -287.909)
			(xy 82.404712 -288.17189) (xy 82.455512 -288.17189)
		)
		(stroke
			(width 0)
			(type solid)
		)
		(fill yes)
		(layer "F.Cu")
		(net "M_A_CPU1_SA_DQ<4>")
	)
	(gr_poly
		(pts
			(xy 82.557112 -287.538922) (xy 82.557112 -287.348422) (xy 82.455512 -287.3121) (xy 82.404712 -287.3121)
			(xy 82.404712 -287.57499) (xy 82.455512 -287.57499)
		)
		(stroke
			(width 0)
			(type solid)
		)
		(fill yes)
		(layer "F.Cu")
		(net "M_A_CPU1_SA_DQ<4>")
	)
	(gr_poly
		(pts
			(xy 82.557112 -286.942022) (xy 82.557112 -286.751522) (xy 82.455512 -286.7152) (xy 82.404712 -286.7152)
			(xy 82.404712 -286.97809) (xy 82.455512 -286.97809)
		)
		(stroke
			(width 0)
			(type solid)
		)
		(fill yes)
		(layer "F.Cu")
		(net "M_A_CPU1_SA_DQ<4>")
	)
	(gr_poly
		(pts
			(xy 82.557112 -286.345122) (xy 82.557112 -286.154622) (xy 82.455512 -286.1183) (xy 82.404712 -286.1183)
			(xy 82.404712 -286.38119) (xy 82.455512 -286.38119)
		)
		(stroke
			(width 0)
			(type solid)
		)
		(fill yes)
		(layer "F.Cu")
		(net "M_A_CPU1_SA_DQ<4>")
	)
	(gr_poly
		(pts
			(xy 82.557112 -285.748222) (xy 82.557112 -285.557722) (xy 82.455512 -285.5214) (xy 82.404712 -285.5214)
			(xy 82.404712 -285.78429) (xy 82.455512 -285.78429)
		)
		(stroke
			(width 0)
			(type solid)
		)
		(fill yes)
		(layer "F.Cu")
		(net "M_A_CPU1_SA_DQ<4>")
	)
	(gr_poly
		(pts
			(xy 82.557112 -285.151322) (xy 82.557112 -284.960822) (xy 82.455512 -284.9245) (xy 82.404712 -284.9245)
			(xy 82.404712 -285.18739) (xy 82.455512 -285.18739)
		)
		(stroke
			(width 0)
			(type solid)
		)
		(fill yes)
		(layer "F.Cu")
		(net "M_A_CPU1_SA_DQ<4>")
	)
	(gr_poly
		(pts
			(xy 82.557112 -284.554422) (xy 82.557112 -284.363922) (xy 82.455512 -284.3276) (xy 82.404712 -284.3276)
			(xy 82.404712 -284.59049) (xy 82.455512 -284.59049)
		)
		(stroke
			(width 0)
			(type solid)
		)
		(fill yes)
		(layer "F.Cu")
		(net "M_A_CPU1_SA_DQ<4>")
	)
	(gr_poly
		(pts
			(xy 82.557112 -283.957522) (xy 82.557112 -283.767022) (xy 82.455512 -283.7307) (xy 82.404712 -283.7307)
			(xy 82.404712 -283.99359) (xy 82.455512 -283.99359)
		)
		(stroke
			(width 0)
			(type solid)
		)
		(fill yes)
		(layer "F.Cu")
		(net "M_A_CPU1_SA_DQ<4>")
	)
	(gr_poly
		(pts
			(xy 82.557112 -283.360622) (xy 82.557112 -283.170122) (xy 82.455512 -283.1338) (xy 82.404712 -283.1338)
			(xy 82.404712 -283.39669) (xy 82.455512 -283.39669)
		)
		(stroke
			(width 0)
			(type solid)
		)
		(fill yes)
		(layer "F.Cu")
		(net "M_A_CPU1_SA_DQ<4>")
	)
	(gr_poly
		(pts
			(xy 82.557112 -282.763722) (xy 82.557112 -282.573222) (xy 82.455512 -282.5369) (xy 82.404712 -282.5369)
			(xy 82.404712 -282.79979) (xy 82.455512 -282.79979)
		)
		(stroke
			(width 0)
			(type solid)
		)
		(fill yes)
		(layer "F.Cu")
		(net "M_A_CPU1_SA_DQ<4>")
	)
	(gr_poly
		(pts
			(xy 82.569558 -280.441146) (xy 82.606896 -280.254456) (xy 82.51444 -280.19883) (xy 82.464656 -280.188924)
			(xy 82.413094 -280.446734) (xy 82.462878 -280.45664)
		)
		(stroke
			(width 0)
			(type solid)
		)
		(fill yes)
		(layer "F.Cu")
		(net "M_A_CPU1_SA_DQ<6>")
	)
	(gr_poly
		(pts
			(xy 82.572606 -259.719826) (xy 82.572606 -259.669026) (xy 82.309716 -259.669026) (xy 82.309716 -259.719826)
			(xy 82.345784 -259.821426) (xy 82.536284 -259.821426)
		)
		(stroke
			(width 0)
			(type solid)
		)
		(fill yes)
		(layer "F.Cu")
		(net "M_A_CPU1_SA_CS_N<0>")
	)
	(gr_poly
		(pts
			(xy 82.572606 -259.415026) (xy 82.572606 -259.364226) (xy 82.309716 -259.364226) (xy 82.309716 -259.415026)
			(xy 82.345784 -259.516626) (xy 82.536284 -259.516626)
		)
		(stroke
			(width 0)
			(type solid)
		)
		(fill yes)
		(layer "F.Cu")
		(net "M_A_CPU1_SA_CS_N<2>")
	)
	(gr_poly
		(pts
			(xy 82.572606 -259.110226) (xy 82.572606 -259.059426) (xy 82.309716 -259.059426) (xy 82.309716 -259.110226)
			(xy 82.345784 -259.211826) (xy 82.536284 -259.211826)
		)
		(stroke
			(width 0)
			(type solid)
		)
		(fill yes)
		(layer "F.Cu")
		(net "M_A_CPU1_SA_CS_N<3>")
	)
	(gr_poly
		(pts
			(xy 82.572606 -258.805426) (xy 82.572606 -258.754626) (xy 82.309716 -258.754626) (xy 82.309716 -258.805426)
			(xy 82.345784 -258.907026) (xy 82.536284 -258.907026)
		)
		(stroke
			(width 0)
			(type solid)
		)
		(fill yes)
		(layer "F.Cu")
		(net "M_A_CPU1_SA_CS_N<1>")
	)
	(gr_poly
		(pts
			(xy 82.572606 -258.500626) (xy 82.572606 -258.449826) (xy 82.309716 -258.449826) (xy 82.309716 -258.500626)
			(xy 82.345784 -258.602226) (xy 82.536284 -258.602226)
		)
		(stroke
			(width 0)
			(type solid)
		)
		(fill yes)
		(layer "F.Cu")
		(net "M_A_CPU1_SA_CA<0>")
	)
	(gr_poly
		(pts
			(xy 82.583782 -276.61997) (xy 82.537554 -276.522434) (xy 82.501486 -276.48662) (xy 82.315558 -276.672548)
			(xy 82.351626 -276.708362) (xy 82.448908 -276.75459)
		)
		(stroke
			(width 0)
			(type solid)
		)
		(fill yes)
		(layer "F.Cu")
		(net "M_A_CPU1_SA_DQ<17>")
	)
	(gr_poly
		(pts
			(xy 82.5881 -281.126692) (xy 82.538316 -281.116786) (xy 82.431636 -281.13228) (xy 82.394044 -281.31897)
			(xy 82.486754 -281.374342) (xy 82.536538 -281.384502)
		)
		(stroke
			(width 0)
			(type solid)
		)
		(fill yes)
		(layer "F.Cu")
		(net "M_A_CPU1_SA_DQ<4>")
	)
	(gr_poly
		(pts
			(xy 82.59318 -277.47341) (xy 82.546698 -277.375874) (xy 82.510884 -277.34006) (xy 82.324956 -277.525988)
			(xy 82.361024 -277.561802) (xy 82.458306 -277.60803)
		)
		(stroke
			(width 0)
			(type solid)
		)
		(fill yes)
		(layer "F.Cu")
		(net "M_A_CPU1_SA_DQ<16>")
	)
	(gr_poly
		(pts
			(xy 82.600292 -272.500344) (xy 82.564478 -272.464276) (xy 82.466942 -272.418048) (xy 82.332322 -272.552668)
			(xy 82.37855 -272.650204) (xy 82.414364 -272.686272)
		)
		(stroke
			(width 0)
			(type solid)
		)
		(fill yes)
		(layer "F.Cu")
		(net "M_A_CPU1_SA_DQ<23>")
	)
	(gr_poly
		(pts
			(xy 82.60715 -267.50645) (xy 82.560922 -267.408914) (xy 82.524854 -267.3731) (xy 82.33918 -267.558774)
			(xy 82.374994 -267.594842) (xy 82.47253 -267.64107)
		)
		(stroke
			(width 0)
			(type solid)
		)
		(fill yes)
		(layer "F.Cu")
		(net "M_A_CPU1_SA_DQ<29>")
	)
	(gr_poly
		(pts
			(xy 82.60969 -273.353784) (xy 82.573876 -273.31797) (xy 82.47634 -273.271742) (xy 82.34172 -273.406362)
			(xy 82.387948 -273.503898) (xy 82.423762 -273.539712)
		)
		(stroke
			(width 0)
			(type solid)
		)
		(fill yes)
		(layer "F.Cu")
		(net "M_A_CPU1_SA_DQ<22>")
	)
	(gr_poly
		(pts
			(xy 82.60969 -231.971342) (xy 82.645504 -231.935274) (xy 82.459576 -231.749346) (xy 82.423762 -231.785414)
			(xy 82.377534 -231.882696) (xy 82.512154 -232.01757)
		)
		(stroke
			(width 0)
			(type solid)
		)
		(fill yes)
		(layer "F.Cu")
		(net "M_A_CPU1_SB_DQ<16>")
	)
	(gr_poly
		(pts
			(xy 82.615532 -242.211098) (xy 82.579718 -242.17503) (xy 82.482182 -242.128802) (xy 82.347562 -242.263422)
			(xy 82.39379 -242.360958) (xy 82.429858 -242.396772)
		)
		(stroke
			(width 0)
			(type solid)
		)
		(fill yes)
		(layer "F.Cu")
		(net "M_A_CPU1_SB_CB<6>")
	)
	(gr_poly
		(pts
			(xy 82.616802 -268.360144) (xy 82.570574 -268.262608) (xy 82.534506 -268.226794) (xy 82.348578 -268.412722)
			(xy 82.384646 -268.448536) (xy 82.481928 -268.494764)
		)
		(stroke
			(width 0)
			(type solid)
		)
		(fill yes)
		(layer "F.Cu")
		(net "M_A_CPU1_SA_DQ<28>")
	)
	(gr_poly
		(pts
			(xy 82.618834 -231.117902) (xy 82.654648 -231.081834) (xy 82.468974 -230.89616) (xy 82.432906 -230.931974)
			(xy 82.386678 -231.02951) (xy 82.521298 -231.16413)
		)
		(stroke
			(width 0)
			(type solid)
		)
		(fill yes)
		(layer "F.Cu")
		(net "M_A_CPU1_SB_DQ<17>")
	)
	(gr_poly
		(pts
			(xy 82.634074 -228.113844) (xy 82.669888 -228.077776) (xy 82.48396 -227.891848) (xy 82.448146 -227.927916)
			(xy 82.401918 -228.025198) (xy 82.536538 -228.160072)
		)
		(stroke
			(width 0)
			(type solid)
		)
		(fill yes)
		(layer "F.Cu")
		(net "M_A_CPU1_SB_DQ<22>")
	)
	(gr_poly
		(pts
			(xy 82.634328 -281.671522) (xy 82.67192 -281.484832) (xy 82.57921 -281.429206) (xy 82.529426 -281.4193)
			(xy 82.477864 -281.67711) (xy 82.527648 -281.687016)
		)
		(stroke
			(width 0)
			(type solid)
		)
		(fill yes)
		(layer "F.Cu")
		(net "M_A_CPU1_SA_DQ<4>")
	)
	(gr_poly
		(pts
			(xy 82.640424 -279.3111) (xy 82.59064 -279.301194) (xy 82.48396 -279.316688) (xy 82.446368 -279.503378)
			(xy 82.539078 -279.55875) (xy 82.588862 -279.56891)
		)
		(stroke
			(width 0)
			(type solid)
		)
		(fill yes)
		(layer "F.Cu")
		(net "M_A_CPU1_SA_DQ<6>")
	)
	(gr_poly
		(pts
			(xy 82.643218 -227.260404) (xy 82.679286 -227.22459) (xy 82.493358 -227.038662) (xy 82.45729 -227.074476)
			(xy 82.411062 -227.172012) (xy 82.545936 -227.306632)
		)
		(stroke
			(width 0)
			(type solid)
		)
		(fill yes)
		(layer "F.Cu")
		(net "M_A_CPU1_SB_DQ<23>")
	)
	(gr_poly
		(pts
			(xy 82.654648 -270.264128) (xy 82.618834 -270.22806) (xy 82.521298 -270.181832) (xy 82.386678 -270.316706)
			(xy 82.432906 -270.413988) (xy 82.46872 -270.450056)
		)
		(stroke
			(width 0)
			(type solid)
		)
		(fill yes)
		(layer "F.Cu")
		(net "M_A_CPU1_SA_DQ<27>")
	)
	(gr_poly
		(pts
			(xy 82.6643 -271.117568) (xy 82.628232 -271.081754) (xy 82.53095 -271.035526) (xy 82.396076 -271.170146)
			(xy 82.442304 -271.267682) (xy 82.478372 -271.303496)
		)
		(stroke
			(width 0)
			(type solid)
		)
		(fill yes)
		(layer "F.Cu")
		(net "M_A_CPU1_SA_DQ<26>")
	)
	(gr_poly
		(pts
			(xy 82.686144 -231.47274) (xy 82.732372 -231.375204) (xy 82.597498 -231.240584) (xy 82.500216 -231.286812)
			(xy 82.464148 -231.322626) (xy 82.650076 -231.508554)
		)
		(stroke
			(width 0)
			(type solid)
		)
		(fill yes)
		(layer "F.Cu")
		(net "M_A_CPU1_SB_DQ<18>")
	)
	(gr_poly
		(pts
			(xy 82.686652 -279.85593) (xy 82.724244 -279.668986) (xy 82.631534 -279.613614) (xy 82.58175 -279.603708)
			(xy 82.530188 -279.861518) (xy 82.579972 -279.871424)
		)
		(stroke
			(width 0)
			(type solid)
		)
		(fill yes)
		(layer "F.Cu")
		(net "M_A_CPU1_SA_DQ<6>")
	)
	(gr_poly
		(pts
			(xy 82.68716 -273.060414) (xy 82.640932 -272.963132) (xy 82.605118 -272.927064) (xy 82.41919 -273.112992)
			(xy 82.455004 -273.148806) (xy 82.55254 -273.195288)
		)
		(stroke
			(width 0)
			(type solid)
		)
		(fill yes)
		(layer "F.Cu")
		(net "M_A_CPU1_SA_DQ<21>")
	)
	(gr_poly
		(pts
			(xy 82.693256 -241.917728) (xy 82.647028 -241.820192) (xy 82.61096 -241.784124) (xy 82.425032 -241.970052)
			(xy 82.4611 -242.00612) (xy 82.558382 -242.052348)
		)
		(stroke
			(width 0)
			(type solid)
		)
		(fill yes)
		(layer "F.Cu")
		(net "M_A_CPU1_SB_CB<5>")
	)
	(gr_poly
		(pts
			(xy 82.695288 -230.6193) (xy 82.741516 -230.522018) (xy 82.606896 -230.387144) (xy 82.50936 -230.433372)
			(xy 82.473546 -230.46944) (xy 82.659474 -230.655368)
		)
		(stroke
			(width 0)
			(type solid)
		)
		(fill yes)
		(layer "F.Cu")
		(net "M_A_CPU1_SB_DQ<19>")
	)
	(gr_poly
		(pts
			(xy 82.69732 -273.914616) (xy 82.650838 -273.817334) (xy 82.615024 -273.781266) (xy 82.429096 -273.967194)
			(xy 82.465164 -274.003262) (xy 82.562446 -274.04949)
		)
		(stroke
			(width 0)
			(type solid)
		)
		(fill yes)
		(layer "F.Cu")
		(net "M_A_CPU1_SA_DQ<20>")
	)
	(gr_poly
		(pts
			(xy 82.70113 -228.468682) (xy 82.747358 -228.3714) (xy 82.612738 -228.236526) (xy 82.515202 -228.282754)
			(xy 82.479388 -228.318822) (xy 82.665316 -228.50475)
		)
		(stroke
			(width 0)
			(type solid)
		)
		(fill yes)
		(layer "F.Cu")
		(net "M_A_CPU1_SB_DQ<20>")
	)
	(gr_poly
		(pts
			(xy 82.705194 -280.541476) (xy 82.65541 -280.531316) (xy 82.54873 -280.54681) (xy 82.511392 -280.733754)
			(xy 82.603848 -280.789126) (xy 82.653632 -280.799032)
		)
		(stroke
			(width 0)
			(type solid)
		)
		(fill yes)
		(layer "F.Cu")
		(net "M_A_CPU1_SA_DQ<4>")
	)
	(gr_poly
		(pts
			(xy 82.710528 -227.615242) (xy 82.756756 -227.517706) (xy 82.622136 -227.383086) (xy 82.5246 -227.429314)
			(xy 82.488786 -227.465382) (xy 82.67446 -227.651056)
		)
		(stroke
			(width 0)
			(type solid)
		)
		(fill yes)
		(layer "F.Cu")
		(net "M_A_CPU1_SB_DQ<21>")
	)
	(gr_poly
		(pts
			(xy 82.71256 -276.275546) (xy 82.676746 -276.239732) (xy 82.57921 -276.19325) (xy 82.44459 -276.328124)
			(xy 82.490818 -276.425406) (xy 82.526632 -276.461474)
		)
		(stroke
			(width 0)
			(type solid)
		)
		(fill yes)
		(layer "F.Cu")
		(net "M_A_CPU1_SA_DQ<17>")
	)
	(gr_poly
		(pts
			(xy 82.721958 -277.128986) (xy 82.68589 -277.093172) (xy 82.588608 -277.046944) (xy 82.453988 -277.181564)
			(xy 82.500216 -277.2791) (xy 82.53603 -277.314914)
		)
		(stroke
			(width 0)
			(type solid)
		)
		(fill yes)
		(layer "F.Cu")
		(net "M_A_CPU1_SA_DQ<16>")
	)
	(gr_poly
		(pts
			(xy 82.735928 -267.162026) (xy 82.700114 -267.125958) (xy 82.602578 -267.07973) (xy 82.467958 -267.21435)
			(xy 82.514186 -267.311886) (xy 82.55 -267.347954)
		)
		(stroke
			(width 0)
			(type solid)
		)
		(fill yes)
		(layer "F.Cu")
		(net "M_A_CPU1_SA_DQ<29>")
	)
	(gr_poly
		(pts
			(xy 82.74177 -270.824452) (xy 82.695542 -270.726916) (xy 82.659474 -270.691102) (xy 82.4738 -270.876776)
			(xy 82.509614 -270.912844) (xy 82.60715 -270.959072)
		)
		(stroke
			(width 0)
			(type solid)
		)
		(fill yes)
		(layer "F.Cu")
		(net "M_A_CPU1_SA_DQ<25>")
	)
	(gr_poly
		(pts
			(xy 82.74558 -268.01572) (xy 82.709766 -267.979652) (xy 82.61223 -267.933424) (xy 82.47761 -268.068298)
			(xy 82.523838 -268.16558) (xy 82.559652 -268.201648)
		)
		(stroke
			(width 0)
			(type solid)
		)
		(fill yes)
		(layer "F.Cu")
		(net "M_A_CPU1_SA_DQ<28>")
	)
	(gr_poly
		(pts
			(xy 82.750914 -271.677638) (xy 82.704686 -271.580356) (xy 82.668872 -271.544288) (xy 82.482944 -271.730216)
			(xy 82.518758 -271.766284) (xy 82.616294 -271.812512)
		)
		(stroke
			(width 0)
			(type solid)
		)
		(fill yes)
		(layer "F.Cu")
		(net "M_A_CPU1_SA_DQ<24>")
	)
	(gr_poly
		(pts
			(xy 82.751676 -281.086306) (xy 82.789014 -280.899362) (xy 82.696558 -280.84399) (xy 82.64652 -280.834084)
			(xy 82.594958 -281.091894) (xy 82.644742 -281.1018)
		)
		(stroke
			(width 0)
			(type solid)
		)
		(fill yes)
		(layer "F.Cu")
		(net "M_A_CPU1_SA_DQ<4>")
	)
	(gr_poly
		(pts
			(xy 82.777584 -238.761016) (xy 82.777584 -238.710216) (xy 82.514948 -238.710216) (xy 82.514948 -238.761016)
			(xy 82.551016 -238.862616) (xy 82.741516 -238.862616)
		)
		(stroke
			(width 0)
			(type solid)
		)
		(fill yes)
		(layer "F.Cu")
		(net "M_A_CPU1_SB_CB<0>")
	)
	(gr_poly
		(pts
			(xy 82.777584 -238.456216) (xy 82.777584 -238.405416) (xy 82.514948 -238.405416) (xy 82.514948 -238.456216)
			(xy 82.551016 -238.557816) (xy 82.741516 -238.557816)
		)
		(stroke
			(width 0)
			(type solid)
		)
		(fill yes)
		(layer "F.Cu")
		(net "M_A_CPU1_SB_CB<2>")
	)
	(gr_poly
		(pts
			(xy 82.777584 -238.151416) (xy 82.777584 -238.100616) (xy 82.514948 -238.100616) (xy 82.514948 -238.151416)
			(xy 82.551016 -238.253016) (xy 82.741516 -238.253016)
		)
		(stroke
			(width 0)
			(type solid)
		)
		(fill yes)
		(layer "F.Cu")
		(net "M_A_CPU1_SB_CB<1>")
	)
	(gr_poly
		(pts
			(xy 82.777584 -237.846616) (xy 82.777584 -237.795816) (xy 82.514948 -237.795816) (xy 82.514948 -237.846616)
			(xy 82.551016 -237.948216) (xy 82.741516 -237.948216)
		)
		(stroke
			(width 0)
			(type solid)
		)
		(fill yes)
		(layer "F.Cu")
		(net "M_A_CPU1_SB_CB<3>")
	)
	(gr_poly
		(pts
			(xy 82.788506 -275.980652) (xy 82.742278 -275.883116) (xy 82.70621 -275.847302) (xy 82.520536 -276.032976)
			(xy 82.55635 -276.069044) (xy 82.653886 -276.115272)
		)
		(stroke
			(width 0)
			(type solid)
		)
		(fill yes)
		(layer "F.Cu")
		(net "M_A_CPU1_SA_DQ<19>")
	)
	(gr_poly
		(pts
			(xy 82.799428 -276.835616) (xy 82.7532 -276.73808) (xy 82.717132 -276.702266) (xy 82.531204 -276.888194)
			(xy 82.567272 -276.924008) (xy 82.664554 -276.970236)
		)
		(stroke
			(width 0)
			(type solid)
		)
		(fill yes)
		(layer "F.Cu")
		(net "M_A_CPU1_SA_DQ<18>")
	)
	(gr_poly
		(pts
			(xy 82.816192 -272.71599) (xy 82.780124 -272.680176) (xy 82.682842 -272.633948) (xy 82.547968 -272.768568)
			(xy 82.594196 -272.866104) (xy 82.630264 -272.901918)
		)
		(stroke
			(width 0)
			(type solid)
		)
		(fill yes)
		(layer "F.Cu")
		(net "M_A_CPU1_SA_DQ<21>")
	)
	(gr_poly
		(pts
			(xy 82.822034 -241.57305) (xy 82.785966 -241.537236) (xy 82.68843 -241.491008) (xy 82.55381 -241.625628)
			(xy 82.600038 -241.723164) (xy 82.636106 -241.758978)
		)
		(stroke
			(width 0)
			(type solid)
		)
		(fill yes)
		(layer "F.Cu")
		(net "M_A_CPU1_SB_CB<5>")
	)
	(gr_poly
		(pts
			(xy 82.822288 -279.956006) (xy 82.772504 -279.9461) (xy 82.665824 -279.961594) (xy 82.628486 -280.148538)
			(xy 82.720942 -280.20391) (xy 82.770726 -280.213816)
		)
		(stroke
			(width 0)
			(type solid)
		)
		(fill yes)
		(layer "F.Cu")
		(net "M_A_CPU1_SA_DQ<4>")
	)
	(gr_poly
		(pts
			(xy 82.82305 -267.72235) (xy 82.776822 -267.624814) (xy 82.741008 -267.589) (xy 82.55508 -267.774928)
			(xy 82.591148 -267.810742) (xy 82.68843 -267.85697)
		)
		(stroke
			(width 0)
			(type solid)
		)
		(fill yes)
		(layer "F.Cu")
		(net "M_A_CPU1_SA_DQ<30>")
	)
	(gr_poly
		(pts
			(xy 82.825336 -231.755696) (xy 82.86115 -231.719628) (xy 82.675222 -231.5337) (xy 82.639408 -231.569768)
			(xy 82.59318 -231.66705) (xy 82.7278 -231.801924)
		)
		(stroke
			(width 0)
			(type solid)
		)
		(fill yes)
		(layer "F.Cu")
		(net "M_A_CPU1_SB_DQ<18>")
	)
	(gr_poly
		(pts
			(xy 82.826098 -273.570446) (xy 82.790284 -273.534378) (xy 82.692748 -273.48815) (xy 82.558128 -273.62277)
			(xy 82.604356 -273.720306) (xy 82.64017 -273.75612)
		)
		(stroke
			(width 0)
			(type solid)
		)
		(fill yes)
		(layer "F.Cu")
		(net "M_A_CPU1_SA_DQ<20>")
	)
	(gr_poly
		(pts
			(xy 82.831432 -242.426744) (xy 82.795364 -242.39093) (xy 82.698082 -242.344702) (xy 82.563462 -242.479322)
			(xy 82.60969 -242.576858) (xy 82.645504 -242.612672)
		)
		(stroke
			(width 0)
			(type solid)
		)
		(fill yes)
		(layer "F.Cu")
		(net "M_A_CPU1_SB_CB<4>")
	)
	(gr_poly
		(pts
			(xy 82.83448 -230.902256) (xy 82.870294 -230.866188) (xy 82.68462 -230.680514) (xy 82.648552 -230.716328)
			(xy 82.602324 -230.813864) (xy 82.736944 -230.948484)
		)
		(stroke
			(width 0)
			(type solid)
		)
		(fill yes)
		(layer "F.Cu")
		(net "M_A_CPU1_SB_DQ<19>")
	)
	(gr_poly
		(pts
			(xy 82.840322 -228.751638) (xy 82.876136 -228.71557) (xy 82.690462 -228.529896) (xy 82.654394 -228.56571)
			(xy 82.608166 -228.663246) (xy 82.742786 -228.797866)
		)
		(stroke
			(width 0)
			(type solid)
		)
		(fill yes)
		(layer "F.Cu")
		(net "M_A_CPU1_SB_DQ<20>")
	)
	(gr_poly
		(pts
			(xy 82.84972 -227.898198) (xy 82.885534 -227.86213) (xy 82.699606 -227.676202) (xy 82.663792 -227.71227)
			(xy 82.617564 -227.809552) (xy 82.752184 -227.944426)
		)
		(stroke
			(width 0)
			(type solid)
		)
		(fill yes)
		(layer "F.Cu")
		(net "M_A_CPU1_SB_DQ<21>")
	)
	(gr_poly
		(pts
			(xy 82.86877 -280.500836) (xy 82.906108 -280.314146) (xy 82.813652 -280.258774) (xy 82.763868 -280.248614)
			(xy 82.712306 -280.506424) (xy 82.76209 -280.516584)
		)
		(stroke
			(width 0)
			(type solid)
		)
		(fill yes)
		(layer "F.Cu")
		(net "M_A_CPU1_SA_DQ<4>")
	)
	(gr_poly
		(pts
			(xy 82.870548 -270.480028) (xy 82.834734 -270.44396) (xy 82.737198 -270.397732) (xy 82.602578 -270.532606)
			(xy 82.648806 -270.629888) (xy 82.68462 -270.665956)
		)
		(stroke
			(width 0)
			(type solid)
		)
		(fill yes)
		(layer "F.Cu")
		(net "M_A_CPU1_SA_DQ<25>")
	)
	(gr_poly
		(pts
			(xy 82.871056 -259.618226) (xy 82.834988 -259.516626) (xy 82.644488 -259.516626) (xy 82.608166 -259.618226)
			(xy 82.608166 -259.669026) (xy 82.871056 -259.669026)
		)
		(stroke
			(width 0)
			(type solid)
		)
		(fill yes)
		(layer "F.Cu")
		(net "M_A_CPU1_SA_CS_N<0>")
	)
	(gr_poly
		(pts
			(xy 82.871056 -259.313426) (xy 82.834988 -259.211826) (xy 82.644488 -259.211826) (xy 82.608166 -259.313426)
			(xy 82.608166 -259.364226) (xy 82.871056 -259.364226)
		)
		(stroke
			(width 0)
			(type solid)
		)
		(fill yes)
		(layer "F.Cu")
		(net "M_A_CPU1_SA_CS_N<2>")
	)
	(gr_poly
		(pts
			(xy 82.871056 -259.008626) (xy 82.834988 -258.907026) (xy 82.644488 -258.907026) (xy 82.608166 -259.008626)
			(xy 82.608166 -259.059426) (xy 82.871056 -259.059426)
		)
		(stroke
			(width 0)
			(type solid)
		)
		(fill yes)
		(layer "F.Cu")
		(net "M_A_CPU1_SA_CS_N<3>")
	)
	(gr_poly
		(pts
			(xy 82.879946 -271.333214) (xy 82.843878 -271.2974) (xy 82.746596 -271.251172) (xy 82.611722 -271.385792)
			(xy 82.65795 -271.483328) (xy 82.694018 -271.519142)
		)
		(stroke
			(width 0)
			(type solid)
		)
		(fill yes)
		(layer "F.Cu")
		(net "M_A_CPU1_SA_DQ<24>")
	)
	(gr_poly
		(pts
			(xy 82.892392 -232.110534) (xy 82.93862 -232.012998) (xy 82.804 -231.878378) (xy 82.706464 -231.924606)
			(xy 82.67065 -231.96042) (xy 82.856578 -232.146348)
		)
		(stroke
			(width 0)
			(type solid)
		)
		(fill yes)
		(layer "F.Cu")
		(net "M_A_CPU1_SB_DQ<16>")
	)
	(gr_poly
		(pts
			(xy 82.893662 -272.42262) (xy 82.847434 -272.325084) (xy 82.811366 -272.28927) (xy 82.625438 -272.475198)
			(xy 82.661506 -272.511012) (xy 82.758788 -272.55724)
		)
		(stroke
			(width 0)
			(type solid)
		)
		(fill yes)
		(layer "F.Cu")
		(net "M_A_CPU1_SA_DQ<23>")
	)
	(gr_poly
		(pts
			(xy 82.899504 -241.27968) (xy 82.853276 -241.182144) (xy 82.817208 -241.14633) (xy 82.631534 -241.332004)
			(xy 82.667348 -241.368072) (xy 82.764884 -241.4143)
		)
		(stroke
			(width 0)
			(type solid)
		)
		(fill yes)
		(layer "F.Cu")
		(net "M_A_CPU1_SB_CB<7>")
	)
	(gr_poly
		(pts
			(xy 82.90179 -231.257094) (xy 82.948018 -231.159558) (xy 82.813144 -231.024938) (xy 82.715862 -231.071166)
			(xy 82.679794 -231.10698) (xy 82.865722 -231.292908)
		)
		(stroke
			(width 0)
			(type solid)
		)
		(fill yes)
		(layer "F.Cu")
		(net "M_A_CPU1_SB_DQ<17>")
	)
	(gr_poly
		(pts
			(xy 82.902806 -273.276314) (xy 82.856578 -273.178778) (xy 82.820764 -273.142964) (xy 82.634836 -273.328638)
			(xy 82.67065 -273.364706) (xy 82.768186 -273.410934)
		)
		(stroke
			(width 0)
			(type solid)
		)
		(fill yes)
		(layer "F.Cu")
		(net "M_A_CPU1_SA_DQ<22>")
	)
	(gr_poly
		(pts
			(xy 82.908902 -242.133374) (xy 82.862674 -242.035838) (xy 82.826606 -242.000024) (xy 82.640678 -242.185952)
			(xy 82.676746 -242.221766) (xy 82.774028 -242.267994)
		)
		(stroke
			(width 0)
			(type solid)
		)
		(fill yes)
		(layer "F.Cu")
		(net "M_A_CPU1_SB_CB<6>")
	)
	(gr_poly
		(pts
			(xy 82.917284 -275.636228) (xy 82.88147 -275.60016) (xy 82.783934 -275.553932) (xy 82.649314 -275.688806)
			(xy 82.695542 -275.786088) (xy 82.731356 -275.822156)
		)
		(stroke
			(width 0)
			(type solid)
		)
		(fill yes)
		(layer "F.Cu")
		(net "M_A_CPU1_SA_DQ<19>")
	)
	(gr_poly
		(pts
			(xy 82.926174 -227.399596) (xy 82.972402 -227.30206) (xy 82.837782 -227.16744) (xy 82.740246 -227.213668)
			(xy 82.704432 -227.249736) (xy 82.890106 -227.43541)
		)
		(stroke
			(width 0)
			(type solid)
		)
		(fill yes)
		(layer "F.Cu")
		(net "M_A_CPU1_SB_DQ<23>")
	)
	(gr_poly
		(pts
			(xy 82.928206 -276.491192) (xy 82.892392 -276.455378) (xy 82.794856 -276.408896) (xy 82.660236 -276.54377)
			(xy 82.706464 -276.641052) (xy 82.742278 -276.67712)
		)
		(stroke
			(width 0)
			(type solid)
		)
		(fill yes)
		(layer "F.Cu")
		(net "M_A_CPU1_SA_DQ<18>")
	)
	(gr_poly
		(pts
			(xy 82.948018 -270.186404) (xy 82.90179 -270.088868) (xy 82.865722 -270.053054) (xy 82.679794 -270.238982)
			(xy 82.715862 -270.274796) (xy 82.813144 -270.321024)
		)
		(stroke
			(width 0)
			(type solid)
		)
		(fill yes)
		(layer "F.Cu")
		(net "M_A_CPU1_SA_DQ<27>")
	)
	(gr_poly
		(pts
			(xy 82.952082 -267.377926) (xy 82.916014 -267.342112) (xy 82.818732 -267.295884) (xy 82.683858 -267.430504)
			(xy 82.73034 -267.52804) (xy 82.766154 -267.563854)
		)
		(stroke
			(width 0)
			(type solid)
		)
		(fill yes)
		(layer "F.Cu")
		(net "M_A_CPU1_SA_DQ<30>")
	)
	(gr_poly
		(pts
			(xy 82.957416 -271.040098) (xy 82.911188 -270.942562) (xy 82.87512 -270.906748) (xy 82.689446 -271.092422)
			(xy 82.72526 -271.12849) (xy 82.822796 -271.174718)
		)
		(stroke
			(width 0)
			(type solid)
		)
		(fill yes)
		(layer "F.Cu")
		(net "M_A_CPU1_SA_DQ<26>")
	)
	(gr_poly
		(pts
			(xy 83.005676 -276.197822) (xy 82.959448 -276.100286) (xy 82.923634 -276.064472) (xy 82.737706 -276.2504)
			(xy 82.77352 -276.286214) (xy 82.871056 -276.332442)
		)
		(stroke
			(width 0)
			(type solid)
		)
		(fill yes)
		(layer "F.Cu")
		(net "M_A_CPU1_SA_DQ<17>")
	)
	(gr_poly
		(pts
			(xy 83.015074 -277.051262) (xy 82.968846 -276.95398) (xy 82.933032 -276.917912) (xy 82.747104 -277.10384)
			(xy 82.782918 -277.139908) (xy 82.880454 -277.186136)
		)
		(stroke
			(width 0)
			(type solid)
		)
		(fill yes)
		(layer "F.Cu")
		(net "M_A_CPU1_SA_DQ<16>")
	)
	(gr_poly
		(pts
			(xy 83.02244 -272.078196) (xy 82.986626 -272.042382) (xy 82.88909 -271.996154) (xy 82.75447 -272.130774)
			(xy 82.800698 -272.22831) (xy 82.836512 -272.264124)
		)
		(stroke
			(width 0)
			(type solid)
		)
		(fill yes)
		(layer "F.Cu")
		(net "M_A_CPU1_SA_DQ<23>")
	)
	(gr_poly
		(pts
			(xy 83.03768 -241.78895) (xy 83.001866 -241.753136) (xy 82.90433 -241.706654) (xy 82.76971 -241.841528)
			(xy 82.815938 -241.93881) (xy 82.851752 -241.974878)
		)
		(stroke
			(width 0)
			(type solid)
		)
		(fill yes)
		(layer "F.Cu")
		(net "M_A_CPU1_SB_CB<6>")
	)
	(gr_poly
		(pts
			(xy 83.038696 -267.937996) (xy 82.992468 -267.84046) (xy 82.956654 -267.804646) (xy 82.770726 -267.990574)
			(xy 82.806794 -268.026388) (xy 82.904076 -268.072616)
		)
		(stroke
			(width 0)
			(type solid)
		)
		(fill yes)
		(layer "F.Cu")
		(net "M_A_CPU1_SA_DQ<28>")
	)
	(gr_poly
		(pts
			(xy 83.040982 -231.54005) (xy 83.076796 -231.503982) (xy 82.890868 -231.318054) (xy 82.855054 -231.354122)
			(xy 82.808826 -231.451404) (xy 82.943446 -231.586278)
		)
		(stroke
			(width 0)
			(type solid)
		)
		(fill yes)
		(layer "F.Cu")
		(net "M_A_CPU1_SB_DQ<17>")
	)
	(gr_poly
		(pts
			(xy 83.065366 -227.682552) (xy 83.10118 -227.646484) (xy 82.915252 -227.460556) (xy 82.879438 -227.496624)
			(xy 82.83321 -227.593906) (xy 82.96783 -227.72878)
		)
		(stroke
			(width 0)
			(type solid)
		)
		(fill yes)
		(layer "F.Cu")
		(net "M_A_CPU1_SB_DQ<23>")
	)
	(gr_poly
		(pts
			(xy 83.076288 -237.745016) (xy 83.039966 -237.643416) (xy 82.849466 -237.643416) (xy 82.813144 -237.745016)
			(xy 82.813144 -237.795816) (xy 83.076288 -237.795816)
		)
		(stroke
			(width 0)
			(type solid)
		)
		(fill yes)
		(layer "F.Cu")
		(net "M_A_CPU1_SB_CB<3>")
	)
	(gr_poly
		(pts
			(xy 83.086194 -270.695674) (xy 83.05038 -270.659606) (xy 82.952844 -270.613378) (xy 82.818224 -270.748252)
			(xy 82.864452 -270.845534) (xy 82.900266 -270.881602)
		)
		(stroke
			(width 0)
			(type solid)
		)
		(fill yes)
		(layer "F.Cu")
		(net "M_A_CPU1_SA_DQ<26>")
	)
	(gr_poly
		(pts
			(xy 83.109308 -272.63852) (xy 83.06308 -272.540984) (xy 83.027266 -272.50517) (xy 82.841338 -272.690844)
			(xy 82.877152 -272.726912) (xy 82.974688 -272.77314)
		)
		(stroke
			(width 0)
			(type solid)
		)
		(fill yes)
		(layer "F.Cu")
		(net "M_A_CPU1_SA_DQ<21>")
	)
	(gr_poly
		(pts
			(xy 83.11515 -241.49558) (xy 83.068922 -241.398044) (xy 83.032854 -241.36223) (xy 82.84718 -241.547904)
			(xy 82.882994 -241.583972) (xy 82.98053 -241.6302)
		)
		(stroke
			(width 0)
			(type solid)
		)
		(fill yes)
		(layer "F.Cu")
		(net "M_A_CPU1_SB_CB<5>")
	)
	(gr_poly
		(pts
			(xy 83.117436 -231.041448) (xy 83.163664 -230.943912) (xy 83.02879 -230.809292) (xy 82.931508 -230.85552)
			(xy 82.89544 -230.891334) (xy 83.081368 -231.077262)
		)
		(stroke
			(width 0)
			(type solid)
		)
		(fill yes)
		(layer "F.Cu")
		(net "M_A_CPU1_SB_DQ<19>")
	)
	(gr_poly
		(pts
			(xy 83.119214 -273.492722) (xy 83.072986 -273.395186) (xy 83.037172 -273.359372) (xy 82.851244 -273.5453)
			(xy 82.887058 -273.581114) (xy 82.984594 -273.627342)
		)
		(stroke
			(width 0)
			(type solid)
		)
		(fill yes)
		(layer "F.Cu")
		(net "M_A_CPU1_SA_DQ<20>")
	)
	(gr_poly
		(pts
			(xy 83.124548 -242.34902) (xy 83.07832 -242.251738) (xy 83.042506 -242.21567) (xy 82.856578 -242.401598)
			(xy 82.892392 -242.437666) (xy 82.989928 -242.483894)
		)
		(stroke
			(width 0)
			(type solid)
		)
		(fill yes)
		(layer "F.Cu")
		(net "M_A_CPU1_SB_CB<4>")
	)
	(gr_poly
		(pts
			(xy 83.132676 -228.03739) (xy 83.178904 -227.939854) (xy 83.04403 -227.805234) (xy 82.946748 -227.851462)
			(xy 82.91068 -227.887276) (xy 83.096608 -228.073204)
		)
		(stroke
			(width 0)
			(type solid)
		)
		(fill yes)
		(layer "F.Cu")
		(net "M_A_CPU1_SB_DQ<21>")
	)
	(gr_poly
		(pts
			(xy 83.134708 -275.853398) (xy 83.09864 -275.817584) (xy 83.001358 -275.771356) (xy 82.866484 -275.905976)
			(xy 82.912966 -276.003512) (xy 82.94878 -276.039326)
		)
		(stroke
			(width 0)
			(type solid)
		)
		(fill yes)
		(layer "F.Cu")
		(net "M_A_CPU1_SA_DQ<17>")
	)
	(gr_poly
		(pts
			(xy 83.144106 -276.706838) (xy 83.108038 -276.671024) (xy 83.010756 -276.624796) (xy 82.875882 -276.759416)
			(xy 82.92211 -276.856952) (xy 82.958178 -276.892766)
		)
		(stroke
			(width 0)
			(type solid)
		)
		(fill yes)
		(layer "F.Cu")
		(net "M_A_CPU1_SA_DQ<16>")
	)
	(gr_poly
		(pts
			(xy 83.163918 -270.402304) (xy 83.11769 -270.304768) (xy 83.081622 -270.268954) (xy 82.895694 -270.454882)
			(xy 82.931762 -270.490696) (xy 83.029044 -270.536924)
		)
		(stroke
			(width 0)
			(type solid)
		)
		(fill yes)
		(layer "F.Cu")
		(net "M_A_CPU1_SA_DQ<25>")
	)
	(gr_poly
		(pts
			(xy 83.167728 -267.593572) (xy 83.13166 -267.557758) (xy 83.034378 -267.51153) (xy 82.899504 -267.64615)
			(xy 82.945986 -267.743686) (xy 82.9818 -267.7795)
		)
		(stroke
			(width 0)
			(type solid)
		)
		(fill yes)
		(layer "F.Cu")
		(net "M_A_CPU1_SA_DQ<28>")
	)
	(gr_poly
		(pts
			(xy 83.169506 -259.719826) (xy 83.169506 -259.669026) (xy 82.906616 -259.669026) (xy 82.906616 -259.719826)
			(xy 82.942684 -259.821426) (xy 83.133184 -259.821426)
		)
		(stroke
			(width 0)
			(type solid)
		)
		(fill yes)
		(layer "F.Cu")
		(net "M_A_CPU1_SA_CS_N<0>")
	)
	(gr_poly
		(pts
			(xy 83.173062 -271.255744) (xy 83.126834 -271.158208) (xy 83.090766 -271.122394) (xy 82.905092 -271.308068)
			(xy 82.940906 -271.344136) (xy 83.038442 -271.390364)
		)
		(stroke
			(width 0)
			(type solid)
		)
		(fill yes)
		(layer "F.Cu")
		(net "M_A_CPU1_SA_DQ<24>")
	)
	(gr_poly
		(pts
			(xy 83.210654 -275.558504) (xy 83.164426 -275.460968) (xy 83.128358 -275.425154) (xy 82.94243 -275.611082)
			(xy 82.978498 -275.646896) (xy 83.07578 -275.693124)
		)
		(stroke
			(width 0)
			(type solid)
		)
		(fill yes)
		(layer "F.Cu")
		(net "M_A_CPU1_SA_DQ<19>")
	)
	(gr_poly
		(pts
			(xy 83.221322 -276.413468) (xy 83.175094 -276.315932) (xy 83.13928 -276.280118) (xy 82.953352 -276.466046)
			(xy 82.989166 -276.50186) (xy 83.086702 -276.548088)
		)
		(stroke
			(width 0)
			(type solid)
		)
		(fill yes)
		(layer "F.Cu")
		(net "M_A_CPU1_SA_DQ<18>")
	)
	(gr_poly
		(pts
			(xy 83.23834 -272.294096) (xy 83.202272 -272.258282) (xy 83.10499 -272.2118) (xy 82.970116 -272.346674)
			(xy 83.016344 -272.443956) (xy 83.052412 -272.480024)
		)
		(stroke
			(width 0)
			(type solid)
		)
		(fill yes)
		(layer "F.Cu")
		(net "M_A_CPU1_SA_DQ<21>")
	)
	(gr_poly
		(pts
			(xy 83.25358 -242.004596) (xy 83.217512 -241.968782) (xy 83.12023 -241.922554) (xy 82.985356 -242.057174)
			(xy 83.031584 -242.15471) (xy 83.067652 -242.190524)
		)
		(stroke
			(width 0)
			(type solid)
		)
		(fill yes)
		(layer "F.Cu")
		(net "M_A_CPU1_SB_CB<4>")
	)
	(gr_poly
		(pts
			(xy 83.271868 -228.320092) (xy 83.307682 -228.284278) (xy 83.121754 -228.09835) (xy 83.08594 -228.134418)
			(xy 83.039712 -228.2317) (xy 83.174332 -228.36632)
		)
		(stroke
			(width 0)
			(type solid)
		)
		(fill yes)
		(layer "F.Cu")
		(net "M_A_CPU1_SB_DQ<21>")
	)
	(gr_poly
		(pts
			(xy 83.292696 -270.05788) (xy 83.256882 -270.022066) (xy 83.159346 -269.975838) (xy 83.024726 -270.110458)
			(xy 83.070954 -270.207994) (xy 83.106768 -270.243808)
		)
		(stroke
			(width 0)
			(type solid)
		)
		(fill yes)
		(layer "F.Cu")
		(net "M_A_CPU1_SA_DQ<25>")
	)
	(gr_poly
		(pts
			(xy 83.30184 -270.91132) (xy 83.266026 -270.875252) (xy 83.16849 -270.829024) (xy 83.03387 -270.963898)
			(xy 83.080098 -271.06118) (xy 83.115912 -271.097248)
		)
		(stroke
			(width 0)
			(type solid)
		)
		(fill yes)
		(layer "F.Cu")
		(net "M_A_CPU1_SA_DQ<24>")
	)
	(gr_poly
		(pts
			(xy 83.339432 -275.21408) (xy 83.303618 -275.178266) (xy 83.206082 -275.132038) (xy 83.071462 -275.266658)
			(xy 83.11769 -275.36394) (xy 83.153504 -275.400008)
		)
		(stroke
			(width 0)
			(type solid)
		)
		(fill yes)
		(layer "F.Cu")
		(net "M_A_CPU1_SA_DQ<19>")
	)
	(gr_poly
		(pts
			(xy 83.348322 -227.821744) (xy 83.39455 -227.724208) (xy 83.259676 -227.589588) (xy 83.162394 -227.635816)
			(xy 83.126326 -227.67163) (xy 83.312254 -227.857558)
		)
		(stroke
			(width 0)
			(type solid)
		)
		(fill yes)
		(layer "F.Cu")
		(net "M_A_CPU1_SB_DQ<23>")
	)
	(gr_poly
		(pts
			(xy 83.350354 -276.069044) (xy 83.314286 -276.03323) (xy 83.217004 -275.987002) (xy 83.08213 -276.121622)
			(xy 83.128612 -276.219158) (xy 83.164426 -276.254972)
		)
		(stroke
			(width 0)
			(type solid)
		)
		(fill yes)
		(layer "F.Cu")
		(net "M_A_CPU1_SA_DQ<18>")
	)
	(gr_poly
		(pts
			(xy 83.379564 -270.61795) (xy 83.333336 -270.520414) (xy 83.297268 -270.4846) (xy 83.11134 -270.670528)
			(xy 83.147408 -270.706342) (xy 83.24469 -270.75257)
		)
		(stroke
			(width 0)
			(type solid)
		)
		(fill yes)
		(layer "F.Cu")
		(net "M_A_CPU1_SA_DQ<26>")
	)
	(gr_poly
		(pts
			(xy 83.427824 -275.775674) (xy 83.381596 -275.678392) (xy 83.345782 -275.642324) (xy 83.159854 -275.828252)
			(xy 83.195668 -275.86432) (xy 83.293204 -275.910548)
		)
		(stroke
			(width 0)
			(type solid)
		)
		(fill yes)
		(layer "F.Cu")
		(net "M_A_CPU1_SA_DQ<17>")
	)
	(gr_poly
		(pts
			(xy 83.437222 -276.629368) (xy 83.390994 -276.531832) (xy 83.354926 -276.496018) (xy 83.169252 -276.681692)
			(xy 83.205066 -276.71776) (xy 83.302602 -276.763988)
		)
		(stroke
			(width 0)
			(type solid)
		)
		(fill yes)
		(layer "F.Cu")
		(net "M_A_CPU1_SA_DQ<16>")
	)
	(gr_poly
		(pts
			(xy 83.467956 -259.618226) (xy 83.431888 -259.516626) (xy 83.241388 -259.516626) (xy 83.205066 -259.618226)
			(xy 83.205066 -259.669026) (xy 83.467956 -259.669026)
		)
		(stroke
			(width 0)
			(type solid)
		)
		(fill yes)
		(layer "F.Cu")
		(net "M_A_CPU1_SA_CS_N<0>")
	)
	(gr_poly
		(pts
			(xy 83.487514 -228.104446) (xy 83.523328 -228.068632) (xy 83.3374 -227.882704) (xy 83.301586 -227.918772)
			(xy 83.255358 -228.016054) (xy 83.389978 -228.150674)
		)
		(stroke
			(width 0)
			(type solid)
		)
		(fill yes)
		(layer "F.Cu")
		(net "M_A_CPU1_SB_DQ<23>")
	)
	(gr_poly
		(pts
			(xy 83.508342 -270.273526) (xy 83.472528 -270.237712) (xy 83.374992 -270.191484) (xy 83.240372 -270.326104)
			(xy 83.2866 -270.42364) (xy 83.322414 -270.459454)
		)
		(stroke
			(width 0)
			(type solid)
		)
		(fill yes)
		(layer "F.Cu")
		(net "M_A_CPU1_SA_DQ<26>")
	)
	(gr_poly
		(pts
			(xy 83.556602 -275.431504) (xy 83.520788 -275.395436) (xy 83.423252 -275.349208) (xy 83.288632 -275.483828)
			(xy 83.33486 -275.581364) (xy 83.370928 -275.617178)
		)
		(stroke
			(width 0)
			(type solid)
		)
		(fill yes)
		(layer "F.Cu")
		(net "M_A_CPU1_SA_DQ<17>")
	)
	(gr_poly
		(pts
			(xy 83.566 -276.284944) (xy 83.530186 -276.248876) (xy 83.43265 -276.202648) (xy 83.29803 -276.337522)
			(xy 83.344258 -276.434804) (xy 83.380072 -276.470872)
		)
		(stroke
			(width 0)
			(type solid)
		)
		(fill yes)
		(layer "F.Cu")
		(net "M_A_CPU1_SA_DQ<16>")
	)
	(gr_poly
		(pts
			(xy 83.585812 -269.980156) (xy 83.539584 -269.882874) (xy 83.50377 -269.846806) (xy 83.317842 -270.032734)
			(xy 83.353656 -270.068548) (xy 83.451192 -270.11503)
		)
		(stroke
			(width 0)
			(type solid)
		)
		(fill yes)
		(layer "F.Cu")
		(net "M_A_CPU1_SA_DQ<25>")
	)
	(gr_poly
		(pts
			(xy 83.59521 -270.833596) (xy 83.548982 -270.73606) (xy 83.512914 -270.700246) (xy 83.326986 -270.886174)
			(xy 83.363054 -270.921988) (xy 83.460336 -270.968216)
		)
		(stroke
			(width 0)
			(type solid)
		)
		(fill yes)
		(layer "F.Cu")
		(net "M_A_CPU1_SA_DQ<24>")
	)
	(gr_poly
		(pts
			(xy 83.632548 -275.136356) (xy 83.58632 -275.039074) (xy 83.550506 -275.003006) (xy 83.364578 -275.188934)
			(xy 83.400392 -275.224748) (xy 83.497928 -275.27123)
		)
		(stroke
			(width 0)
			(type solid)
		)
		(fill yes)
		(layer "F.Cu")
		(net "M_A_CPU1_SA_DQ<19>")
	)
	(gr_poly
		(pts
			(xy 83.64347 -275.99132) (xy 83.597242 -275.894038) (xy 83.561428 -275.85797) (xy 83.3755 -276.043898)
			(xy 83.411314 -276.079966) (xy 83.50885 -276.126194)
		)
		(stroke
			(width 0)
			(type solid)
		)
		(fill yes)
		(layer "F.Cu")
		(net "M_A_CPU1_SA_DQ<18>")
	)
	(gr_poly
		(pts
			(xy 83.723988 -270.489172) (xy 83.688174 -270.453358) (xy 83.590638 -270.40713) (xy 83.456018 -270.54175)
			(xy 83.502246 -270.639286) (xy 83.53806 -270.6751)
		)
		(stroke
			(width 0)
			(type solid)
		)
		(fill yes)
		(layer "F.Cu")
		(net "M_A_CPU1_SA_DQ<24>")
	)
	(gr_poly
		(pts
			(xy 83.76158 -274.791932) (xy 83.725512 -274.756118) (xy 83.62823 -274.70989) (xy 83.493356 -274.84451)
			(xy 83.539584 -274.942046) (xy 83.575652 -274.97786)
		)
		(stroke
			(width 0)
			(type solid)
		)
		(fill yes)
		(layer "F.Cu")
		(net "M_A_CPU1_SA_DQ<19>")
	)
	(gr_poly
		(pts
			(xy 83.766406 -259.719826) (xy 83.766406 -259.669026) (xy 83.503516 -259.669026) (xy 83.503516 -259.719826)
			(xy 83.539584 -259.821426) (xy 83.730084 -259.821426)
		)
		(stroke
			(width 0)
			(type solid)
		)
		(fill yes)
		(layer "F.Cu")
		(net "M_A_CPU1_SA_CS_N<0>")
	)
	(gr_poly
		(pts
			(xy 83.772248 -275.64715) (xy 83.736434 -275.611082) (xy 83.638898 -275.564854) (xy 83.504278 -275.699474)
			(xy 83.550506 -275.79701) (xy 83.586574 -275.832824)
		)
		(stroke
			(width 0)
			(type solid)
		)
		(fill yes)
		(layer "F.Cu")
		(net "M_A_CPU1_SA_DQ<18>")
	)
	(gr_poly
		(pts
			(xy 83.801458 -270.195802) (xy 83.75523 -270.09852) (xy 83.719416 -270.062452) (xy 83.533488 -270.24838)
			(xy 83.569302 -270.284194) (xy 83.666838 -270.330676)
		)
		(stroke
			(width 0)
			(type solid)
		)
		(fill yes)
		(layer "F.Cu")
		(net "M_A_CPU1_SA_DQ<26>")
	)
	(gr_poly
		(pts
			(xy 83.839304 -217.80119) (xy 83.788504 -217.80119) (xy 83.686904 -217.837258) (xy 83.686904 -218.027758)
			(xy 83.788504 -218.063826) (xy 83.839304 -218.063826)
		)
		(stroke
			(width 0)
			(type solid)
		)
		(fill yes)
		(layer "F.Cu")
		(net "M_A_CPU1_SB_DQ<28>")
	)
	(gr_poly
		(pts
			(xy 83.839304 -217.20429) (xy 83.788504 -217.20429) (xy 83.686904 -217.240358) (xy 83.686904 -217.430858)
			(xy 83.788504 -217.466926) (xy 83.839304 -217.466926)
		)
		(stroke
			(width 0)
			(type solid)
		)
		(fill yes)
		(layer "F.Cu")
		(net "M_A_CPU1_SB_DQ<28>")
	)
	(gr_poly
		(pts
			(xy 83.839304 -216.60739) (xy 83.788504 -216.60739) (xy 83.686904 -216.643458) (xy 83.686904 -216.833958)
			(xy 83.788504 -216.870026) (xy 83.839304 -216.870026)
		)
		(stroke
			(width 0)
			(type solid)
		)
		(fill yes)
		(layer "F.Cu")
		(net "M_A_CPU1_SB_DQ<28>")
	)
	(gr_poly
		(pts
			(xy 83.849972 -275.35378) (xy 83.803744 -275.256244) (xy 83.767676 -275.22043) (xy 83.581748 -275.406358)
			(xy 83.617816 -275.442172) (xy 83.715352 -275.4884)
		)
		(stroke
			(width 0)
			(type solid)
		)
		(fill yes)
		(layer "F.Cu")
		(net "M_A_CPU1_SA_DQ<17>")
	)
	(gr_poly
		(pts
			(xy 83.85937 -276.20722) (xy 83.813142 -276.109684) (xy 83.777074 -276.07387) (xy 83.591146 -276.259798)
			(xy 83.627214 -276.295612) (xy 83.724496 -276.34184)
		)
		(stroke
			(width 0)
			(type solid)
		)
		(fill yes)
		(layer "F.Cu")
		(net "M_A_CPU1_SA_DQ<16>")
	)
	(gr_poly
		(pts
			(xy 83.928712 -296.54246) (xy 83.877912 -296.54246) (xy 83.776312 -296.578782) (xy 83.776312 -296.769282)
			(xy 83.877912 -296.80535) (xy 83.928712 -296.80535)
		)
		(stroke
			(width 0)
			(type solid)
		)
		(fill yes)
		(layer "F.Cu")
		(net "M_A_CPU1_SA_DQ<3>")
	)
	(gr_poly
		(pts
			(xy 83.928712 -295.94556) (xy 83.877912 -295.94556) (xy 83.776312 -295.981882) (xy 83.776312 -296.172382)
			(xy 83.877912 -296.20845) (xy 83.928712 -296.20845)
		)
		(stroke
			(width 0)
			(type solid)
		)
		(fill yes)
		(layer "F.Cu")
		(net "M_A_CPU1_SA_DQ<3>")
	)
	(gr_poly
		(pts
			(xy 83.928712 -295.34866) (xy 83.877912 -295.34866) (xy 83.776312 -295.384982) (xy 83.776312 -295.575482)
			(xy 83.877912 -295.61155) (xy 83.928712 -295.61155)
		)
		(stroke
			(width 0)
			(type solid)
		)
		(fill yes)
		(layer "F.Cu")
		(net "M_A_CPU1_SA_DQ<3>")
	)
	(gr_poly
		(pts
			(xy 83.928712 -294.75176) (xy 83.877912 -294.75176) (xy 83.776312 -294.788082) (xy 83.776312 -294.978582)
			(xy 83.877912 -295.01465) (xy 83.928712 -295.01465)
		)
		(stroke
			(width 0)
			(type solid)
		)
		(fill yes)
		(layer "F.Cu")
		(net "M_A_CPU1_SA_DQ<3>")
	)
	(gr_poly
		(pts
			(xy 83.928712 -294.15486) (xy 83.877912 -294.15486) (xy 83.776312 -294.191182) (xy 83.776312 -294.381682)
			(xy 83.877912 -294.41775) (xy 83.928712 -294.41775)
		)
		(stroke
			(width 0)
			(type solid)
		)
		(fill yes)
		(layer "F.Cu")
		(net "M_A_CPU1_SA_DQ<3>")
	)
	(gr_poly
		(pts
			(xy 83.928712 -293.55796) (xy 83.877912 -293.55796) (xy 83.776312 -293.594282) (xy 83.776312 -293.784782)
			(xy 83.877912 -293.82085) (xy 83.928712 -293.82085)
		)
		(stroke
			(width 0)
			(type solid)
		)
		(fill yes)
		(layer "F.Cu")
		(net "M_A_CPU1_SA_DQ<3>")
	)
	(gr_poly
		(pts
			(xy 83.928712 -292.96106) (xy 83.877912 -292.96106) (xy 83.776312 -292.997382) (xy 83.776312 -293.187882)
			(xy 83.877912 -293.22395) (xy 83.928712 -293.22395)
		)
		(stroke
			(width 0)
			(type solid)
		)
		(fill yes)
		(layer "F.Cu")
		(net "M_A_CPU1_SA_DQ<3>")
	)
	(gr_poly
		(pts
			(xy 83.928712 -292.36416) (xy 83.877912 -292.36416) (xy 83.776312 -292.400482) (xy 83.776312 -292.590982)
			(xy 83.877912 -292.62705) (xy 83.928712 -292.62705)
		)
		(stroke
			(width 0)
			(type solid)
		)
		(fill yes)
		(layer "F.Cu")
		(net "M_A_CPU1_SA_DQ<3>")
	)
	(gr_poly
		(pts
			(xy 83.928712 -291.76726) (xy 83.877912 -291.76726) (xy 83.776312 -291.803582) (xy 83.776312 -291.994082)
			(xy 83.877912 -292.03015) (xy 83.928712 -292.03015)
		)
		(stroke
			(width 0)
			(type solid)
		)
		(fill yes)
		(layer "F.Cu")
		(net "M_A_CPU1_SA_DQ<3>")
	)
	(gr_poly
		(pts
			(xy 83.928712 -291.17036) (xy 83.877912 -291.17036) (xy 83.776312 -291.206682) (xy 83.776312 -291.397182)
			(xy 83.877912 -291.43325) (xy 83.928712 -291.43325)
		)
		(stroke
			(width 0)
			(type solid)
		)
		(fill yes)
		(layer "F.Cu")
		(net "M_A_CPU1_SA_DQ<3>")
	)
	(gr_poly
		(pts
			(xy 83.928712 -290.57346) (xy 83.877912 -290.57346) (xy 83.776312 -290.609782) (xy 83.776312 -290.800282)
			(xy 83.877912 -290.83635) (xy 83.928712 -290.83635)
		)
		(stroke
			(width 0)
			(type solid)
		)
		(fill yes)
		(layer "F.Cu")
		(net "M_A_CPU1_SA_DQ<3>")
	)
	(gr_poly
		(pts
			(xy 83.928712 -289.97656) (xy 83.877912 -289.97656) (xy 83.776312 -290.012882) (xy 83.776312 -290.203382)
			(xy 83.877912 -290.23945) (xy 83.928712 -290.23945)
		)
		(stroke
			(width 0)
			(type solid)
		)
		(fill yes)
		(layer "F.Cu")
		(net "M_A_CPU1_SA_DQ<3>")
	)
	(gr_poly
		(pts
			(xy 83.928712 -289.37966) (xy 83.877912 -289.37966) (xy 83.776312 -289.415982) (xy 83.776312 -289.606482)
			(xy 83.877912 -289.64255) (xy 83.928712 -289.64255)
		)
		(stroke
			(width 0)
			(type solid)
		)
		(fill yes)
		(layer "F.Cu")
		(net "M_A_CPU1_SA_DQ<3>")
	)
	(gr_poly
		(pts
			(xy 83.928712 -288.78276) (xy 83.877912 -288.78276) (xy 83.776312 -288.819082) (xy 83.776312 -289.009582)
			(xy 83.877912 -289.04565) (xy 83.928712 -289.04565)
		)
		(stroke
			(width 0)
			(type solid)
		)
		(fill yes)
		(layer "F.Cu")
		(net "M_A_CPU1_SA_DQ<3>")
	)
	(gr_poly
		(pts
			(xy 83.928712 -288.18586) (xy 83.877912 -288.18586) (xy 83.776312 -288.222182) (xy 83.776312 -288.412682)
			(xy 83.877912 -288.44875) (xy 83.928712 -288.44875)
		)
		(stroke
			(width 0)
			(type solid)
		)
		(fill yes)
		(layer "F.Cu")
		(net "M_A_CPU1_SA_DQ<3>")
	)
	(gr_poly
		(pts
			(xy 83.928712 -287.58896) (xy 83.877912 -287.58896) (xy 83.776312 -287.625282) (xy 83.776312 -287.815782)
			(xy 83.877912 -287.85185) (xy 83.928712 -287.85185)
		)
		(stroke
			(width 0)
			(type solid)
		)
		(fill yes)
		(layer "F.Cu")
		(net "M_A_CPU1_SA_DQ<3>")
	)
	(gr_poly
		(pts
			(xy 83.928712 -286.99206) (xy 83.877912 -286.99206) (xy 83.776312 -287.028382) (xy 83.776312 -287.218882)
			(xy 83.877912 -287.25495) (xy 83.928712 -287.25495)
		)
		(stroke
			(width 0)
			(type solid)
		)
		(fill yes)
		(layer "F.Cu")
		(net "M_A_CPU1_SA_DQ<3>")
	)
	(gr_poly
		(pts
			(xy 83.928712 -286.39516) (xy 83.877912 -286.39516) (xy 83.776312 -286.431482) (xy 83.776312 -286.621982)
			(xy 83.877912 -286.65805) (xy 83.928712 -286.65805)
		)
		(stroke
			(width 0)
			(type solid)
		)
		(fill yes)
		(layer "F.Cu")
		(net "M_A_CPU1_SA_DQ<3>")
	)
	(gr_poly
		(pts
			(xy 83.928712 -285.79826) (xy 83.877912 -285.79826) (xy 83.776312 -285.834582) (xy 83.776312 -286.025082)
			(xy 83.877912 -286.06115) (xy 83.928712 -286.06115)
		)
		(stroke
			(width 0)
			(type solid)
		)
		(fill yes)
		(layer "F.Cu")
		(net "M_A_CPU1_SA_DQ<3>")
	)
	(gr_poly
		(pts
			(xy 83.928712 -285.20136) (xy 83.877912 -285.20136) (xy 83.776312 -285.237682) (xy 83.776312 -285.428182)
			(xy 83.877912 -285.46425) (xy 83.928712 -285.46425)
		)
		(stroke
			(width 0)
			(type solid)
		)
		(fill yes)
		(layer "F.Cu")
		(net "M_A_CPU1_SA_DQ<3>")
	)
	(gr_poly
		(pts
			(xy 83.928712 -284.60446) (xy 83.877912 -284.60446) (xy 83.776312 -284.640782) (xy 83.776312 -284.831282)
			(xy 83.877912 -284.86735) (xy 83.928712 -284.86735)
		)
		(stroke
			(width 0)
			(type solid)
		)
		(fill yes)
		(layer "F.Cu")
		(net "M_A_CPU1_SA_DQ<3>")
	)
	(gr_poly
		(pts
			(xy 83.928712 -284.00756) (xy 83.877912 -284.00756) (xy 83.776312 -284.043882) (xy 83.776312 -284.234382)
			(xy 83.877912 -284.27045) (xy 83.928712 -284.27045)
		)
		(stroke
			(width 0)
			(type solid)
		)
		(fill yes)
		(layer "F.Cu")
		(net "M_A_CPU1_SA_DQ<3>")
	)
	(gr_poly
		(pts
			(xy 83.928712 -283.41066) (xy 83.877912 -283.41066) (xy 83.776312 -283.446982) (xy 83.776312 -283.637482)
			(xy 83.877912 -283.67355) (xy 83.928712 -283.67355)
		)
		(stroke
			(width 0)
			(type solid)
		)
		(fill yes)
		(layer "F.Cu")
		(net "M_A_CPU1_SA_DQ<3>")
	)
	(gr_poly
		(pts
			(xy 83.928712 -282.81376) (xy 83.877912 -282.81376) (xy 83.776312 -282.850082) (xy 83.776312 -283.040582)
			(xy 83.877912 -283.07665) (xy 83.928712 -283.07665)
		)
		(stroke
			(width 0)
			(type solid)
		)
		(fill yes)
		(layer "F.Cu")
		(net "M_A_CPU1_SA_DQ<3>")
	)
	(gr_poly
		(pts
			(xy 83.97875 -275.009356) (xy 83.942936 -274.973288) (xy 83.8454 -274.92706) (xy 83.71078 -275.061934)
			(xy 83.757008 -275.159216) (xy 83.792822 -275.195284)
		)
		(stroke
			(width 0)
			(type solid)
		)
		(fill yes)
		(layer "F.Cu")
		(net "M_A_CPU1_SA_DQ<17>")
	)
	(gr_poly
		(pts
			(xy 83.988148 -275.862796) (xy 83.952334 -275.826982) (xy 83.854798 -275.780754) (xy 83.720178 -275.915374)
			(xy 83.766406 -276.012656) (xy 83.80222 -276.048724)
		)
		(stroke
			(width 0)
			(type solid)
		)
		(fill yes)
		(layer "F.Cu")
		(net "M_A_CPU1_SA_DQ<16>")
	)
	(gr_poly
		(pts
			(xy 83.991704 -218.326208) (xy 83.991704 -218.135708) (xy 83.890104 -218.099386) (xy 83.839304 -218.099386)
			(xy 83.839304 -218.36253) (xy 83.890104 -218.36253)
		)
		(stroke
			(width 0)
			(type solid)
		)
		(fill yes)
		(layer "F.Cu")
		(net "M_A_CPU1_SB_DQ<28>")
	)
	(gr_poly
		(pts
			(xy 83.991704 -217.729308) (xy 83.991704 -217.538808) (xy 83.890104 -217.502486) (xy 83.839304 -217.502486)
			(xy 83.839304 -217.76563) (xy 83.890104 -217.76563)
		)
		(stroke
			(width 0)
			(type solid)
		)
		(fill yes)
		(layer "F.Cu")
		(net "M_A_CPU1_SB_DQ<28>")
	)
	(gr_poly
		(pts
			(xy 83.991704 -217.132408) (xy 83.991704 -216.941908) (xy 83.890104 -216.905586) (xy 83.839304 -216.905586)
			(xy 83.839304 -217.16873) (xy 83.890104 -217.16873)
		)
		(stroke
			(width 0)
			(type solid)
		)
		(fill yes)
		(layer "F.Cu")
		(net "M_A_CPU1_SB_DQ<28>")
	)
	(gr_poly
		(pts
			(xy 83.991704 -216.535508) (xy 83.991704 -216.345008) (xy 83.890104 -216.308686) (xy 83.839304 -216.308686)
			(xy 83.839304 -216.57183) (xy 83.890104 -216.57183)
		)
		(stroke
			(width 0)
			(type solid)
		)
		(fill yes)
		(layer "F.Cu")
		(net "M_A_CPU1_SB_DQ<28>")
	)
	(gr_poly
		(pts
			(xy 84.017104 -270.411448) (xy 83.970876 -270.314166) (xy 83.935062 -270.278098) (xy 83.749134 -270.464026)
			(xy 83.784948 -270.49984) (xy 83.882484 -270.546322)
		)
		(stroke
			(width 0)
			(type solid)
		)
		(fill yes)
		(layer "F.Cu")
		(net "M_A_CPU1_SA_DQ<24>")
	)
	(gr_poly
		(pts
			(xy 84.065618 -275.569426) (xy 84.01939 -275.47189) (xy 83.983322 -275.436076) (xy 83.797394 -275.622004)
			(xy 83.833462 -275.657818) (xy 83.930998 -275.704046)
		)
		(stroke
			(width 0)
			(type solid)
		)
		(fill yes)
		(layer "F.Cu")
		(net "M_A_CPU1_SA_DQ<18>")
	)
	(gr_poly
		(pts
			(xy 84.081112 -296.470832) (xy 84.081112 -296.280332) (xy 83.979512 -296.24401) (xy 83.928712 -296.24401)
			(xy 83.928712 -296.5069) (xy 83.979512 -296.5069)
		)
		(stroke
			(width 0)
			(type solid)
		)
		(fill yes)
		(layer "F.Cu")
		(net "M_A_CPU1_SA_DQ<3>")
	)
	(gr_poly
		(pts
			(xy 84.081112 -295.873932) (xy 84.081112 -295.683432) (xy 83.979512 -295.64711) (xy 83.928712 -295.64711)
			(xy 83.928712 -295.91) (xy 83.979512 -295.91)
		)
		(stroke
			(width 0)
			(type solid)
		)
		(fill yes)
		(layer "F.Cu")
		(net "M_A_CPU1_SA_DQ<3>")
	)
	(gr_poly
		(pts
			(xy 84.081112 -295.277032) (xy 84.081112 -295.086532) (xy 83.979512 -295.05021) (xy 83.928712 -295.05021)
			(xy 83.928712 -295.3131) (xy 83.979512 -295.3131)
		)
		(stroke
			(width 0)
			(type solid)
		)
		(fill yes)
		(layer "F.Cu")
		(net "M_A_CPU1_SA_DQ<3>")
	)
	(gr_poly
		(pts
			(xy 84.081112 -294.680132) (xy 84.081112 -294.489632) (xy 83.979512 -294.45331) (xy 83.928712 -294.45331)
			(xy 83.928712 -294.7162) (xy 83.979512 -294.7162)
		)
		(stroke
			(width 0)
			(type solid)
		)
		(fill yes)
		(layer "F.Cu")
		(net "M_A_CPU1_SA_DQ<3>")
	)
	(gr_poly
		(pts
			(xy 84.081112 -294.083232) (xy 84.081112 -293.892732) (xy 83.979512 -293.85641) (xy 83.928712 -293.85641)
			(xy 83.928712 -294.1193) (xy 83.979512 -294.1193)
		)
		(stroke
			(width 0)
			(type solid)
		)
		(fill yes)
		(layer "F.Cu")
		(net "M_A_CPU1_SA_DQ<3>")
	)
	(gr_poly
		(pts
			(xy 84.081112 -293.486332) (xy 84.081112 -293.295832) (xy 83.979512 -293.25951) (xy 83.928712 -293.25951)
			(xy 83.928712 -293.5224) (xy 83.979512 -293.5224)
		)
		(stroke
			(width 0)
			(type solid)
		)
		(fill yes)
		(layer "F.Cu")
		(net "M_A_CPU1_SA_DQ<3>")
	)
	(gr_poly
		(pts
			(xy 84.081112 -292.889432) (xy 84.081112 -292.698932) (xy 83.979512 -292.66261) (xy 83.928712 -292.66261)
			(xy 83.928712 -292.9255) (xy 83.979512 -292.9255)
		)
		(stroke
			(width 0)
			(type solid)
		)
		(fill yes)
		(layer "F.Cu")
		(net "M_A_CPU1_SA_DQ<3>")
	)
	(gr_poly
		(pts
			(xy 84.081112 -292.292532) (xy 84.081112 -292.102032) (xy 83.979512 -292.06571) (xy 83.928712 -292.06571)
			(xy 83.928712 -292.3286) (xy 83.979512 -292.3286)
		)
		(stroke
			(width 0)
			(type solid)
		)
		(fill yes)
		(layer "F.Cu")
		(net "M_A_CPU1_SA_DQ<3>")
	)
	(gr_poly
		(pts
			(xy 84.081112 -291.695632) (xy 84.081112 -291.505132) (xy 83.979512 -291.46881) (xy 83.928712 -291.46881)
			(xy 83.928712 -291.7317) (xy 83.979512 -291.7317)
		)
		(stroke
			(width 0)
			(type solid)
		)
		(fill yes)
		(layer "F.Cu")
		(net "M_A_CPU1_SA_DQ<3>")
	)
	(gr_poly
		(pts
			(xy 84.081112 -291.098732) (xy 84.081112 -290.908232) (xy 83.979512 -290.87191) (xy 83.928712 -290.87191)
			(xy 83.928712 -291.1348) (xy 83.979512 -291.1348)
		)
		(stroke
			(width 0)
			(type solid)
		)
		(fill yes)
		(layer "F.Cu")
		(net "M_A_CPU1_SA_DQ<3>")
	)
	(gr_poly
		(pts
			(xy 84.081112 -290.501832) (xy 84.081112 -290.311332) (xy 83.979512 -290.27501) (xy 83.928712 -290.27501)
			(xy 83.928712 -290.5379) (xy 83.979512 -290.5379)
		)
		(stroke
			(width 0)
			(type solid)
		)
		(fill yes)
		(layer "F.Cu")
		(net "M_A_CPU1_SA_DQ<3>")
	)
	(gr_poly
		(pts
			(xy 84.081112 -289.904932) (xy 84.081112 -289.714432) (xy 83.979512 -289.67811) (xy 83.928712 -289.67811)
			(xy 83.928712 -289.941) (xy 83.979512 -289.941)
		)
		(stroke
			(width 0)
			(type solid)
		)
		(fill yes)
		(layer "F.Cu")
		(net "M_A_CPU1_SA_DQ<3>")
	)
	(gr_poly
		(pts
			(xy 84.081112 -289.308032) (xy 84.081112 -289.117532) (xy 83.979512 -289.08121) (xy 83.928712 -289.08121)
			(xy 83.928712 -289.3441) (xy 83.979512 -289.3441)
		)
		(stroke
			(width 0)
			(type solid)
		)
		(fill yes)
		(layer "F.Cu")
		(net "M_A_CPU1_SA_DQ<3>")
	)
	(gr_poly
		(pts
			(xy 84.081112 -288.711132) (xy 84.081112 -288.520632) (xy 83.979512 -288.48431) (xy 83.928712 -288.48431)
			(xy 83.928712 -288.7472) (xy 83.979512 -288.7472)
		)
		(stroke
			(width 0)
			(type solid)
		)
		(fill yes)
		(layer "F.Cu")
		(net "M_A_CPU1_SA_DQ<3>")
	)
	(gr_poly
		(pts
			(xy 84.081112 -288.114232) (xy 84.081112 -287.923732) (xy 83.979512 -287.88741) (xy 83.928712 -287.88741)
			(xy 83.928712 -288.1503) (xy 83.979512 -288.1503)
		)
		(stroke
			(width 0)
			(type solid)
		)
		(fill yes)
		(layer "F.Cu")
		(net "M_A_CPU1_SA_DQ<3>")
	)
	(gr_poly
		(pts
			(xy 84.081112 -287.517332) (xy 84.081112 -287.326832) (xy 83.979512 -287.29051) (xy 83.928712 -287.29051)
			(xy 83.928712 -287.5534) (xy 83.979512 -287.5534)
		)
		(stroke
			(width 0)
			(type solid)
		)
		(fill yes)
		(layer "F.Cu")
		(net "M_A_CPU1_SA_DQ<3>")
	)
	(gr_poly
		(pts
			(xy 84.081112 -286.920432) (xy 84.081112 -286.729932) (xy 83.979512 -286.69361) (xy 83.928712 -286.69361)
			(xy 83.928712 -286.9565) (xy 83.979512 -286.9565)
		)
		(stroke
			(width 0)
			(type solid)
		)
		(fill yes)
		(layer "F.Cu")
		(net "M_A_CPU1_SA_DQ<3>")
	)
	(gr_poly
		(pts
			(xy 84.081112 -286.323532) (xy 84.081112 -286.133032) (xy 83.979512 -286.09671) (xy 83.928712 -286.09671)
			(xy 83.928712 -286.3596) (xy 83.979512 -286.3596)
		)
		(stroke
			(width 0)
			(type solid)
		)
		(fill yes)
		(layer "F.Cu")
		(net "M_A_CPU1_SA_DQ<3>")
	)
	(gr_poly
		(pts
			(xy 84.081112 -285.726632) (xy 84.081112 -285.536132) (xy 83.979512 -285.49981) (xy 83.928712 -285.49981)
			(xy 83.928712 -285.7627) (xy 83.979512 -285.7627)
		)
		(stroke
			(width 0)
			(type solid)
		)
		(fill yes)
		(layer "F.Cu")
		(net "M_A_CPU1_SA_DQ<3>")
	)
	(gr_poly
		(pts
			(xy 84.081112 -285.129732) (xy 84.081112 -284.939232) (xy 83.979512 -284.90291) (xy 83.928712 -284.90291)
			(xy 83.928712 -285.1658) (xy 83.979512 -285.1658)
		)
		(stroke
			(width 0)
			(type solid)
		)
		(fill yes)
		(layer "F.Cu")
		(net "M_A_CPU1_SA_DQ<3>")
	)
	(gr_poly
		(pts
			(xy 84.081112 -284.532832) (xy 84.081112 -284.342332) (xy 83.979512 -284.30601) (xy 83.928712 -284.30601)
			(xy 83.928712 -284.5689) (xy 83.979512 -284.5689)
		)
		(stroke
			(width 0)
			(type solid)
		)
		(fill yes)
		(layer "F.Cu")
		(net "M_A_CPU1_SA_DQ<3>")
	)
	(gr_poly
		(pts
			(xy 84.081112 -283.935932) (xy 84.081112 -283.745432) (xy 83.979512 -283.70911) (xy 83.928712 -283.70911)
			(xy 83.928712 -283.972) (xy 83.979512 -283.972)
		)
		(stroke
			(width 0)
			(type solid)
		)
		(fill yes)
		(layer "F.Cu")
		(net "M_A_CPU1_SA_DQ<3>")
	)
	(gr_poly
		(pts
			(xy 84.081112 -283.339032) (xy 84.081112 -283.148532) (xy 83.979512 -283.11221) (xy 83.928712 -283.11221)
			(xy 83.928712 -283.3751) (xy 83.979512 -283.3751)
		)
		(stroke
			(width 0)
			(type solid)
		)
		(fill yes)
		(layer "F.Cu")
		(net "M_A_CPU1_SA_DQ<3>")
	)
	(gr_poly
		(pts
			(xy 84.081112 -281.692096) (xy 84.031328 -281.68219) (xy 83.924648 -281.697684) (xy 83.887056 -281.884374)
			(xy 83.979766 -281.94) (xy 84.02955 -281.949906)
		)
		(stroke
			(width 0)
			(type solid)
		)
		(fill yes)
		(layer "F.Cu")
		(net "M_A_CPU1_SA_DQ<3>")
	)
	(gr_poly
		(pts
			(xy 84.127594 -282.236926) (xy 84.164932 -282.050236) (xy 84.072222 -281.99461) (xy 84.022438 -281.984704)
			(xy 83.970876 -282.242514) (xy 84.02066 -282.25242)
		)
		(stroke
			(width 0)
			(type solid)
		)
		(fill yes)
		(layer "F.Cu")
		(net "M_A_CPU1_SA_DQ<3>")
	)
	(gr_poly
		(pts
			(xy 84.144104 -217.80119) (xy 84.093304 -217.80119) (xy 83.991704 -217.837258) (xy 83.991704 -218.027758)
			(xy 84.093304 -218.063826) (xy 84.144104 -218.063826)
		)
		(stroke
			(width 0)
			(type solid)
		)
		(fill yes)
		(layer "F.Cu")
		(net "M_A_CPU1_SB_DQ<30>")
	)
	(gr_poly
		(pts
			(xy 84.144104 -217.20429) (xy 84.093304 -217.20429) (xy 83.991704 -217.240358) (xy 83.991704 -217.430858)
			(xy 84.093304 -217.466926) (xy 84.144104 -217.466926)
		)
		(stroke
			(width 0)
			(type solid)
		)
		(fill yes)
		(layer "F.Cu")
		(net "M_A_CPU1_SB_DQ<30>")
	)
	(gr_poly
		(pts
			(xy 84.144104 -216.60739) (xy 84.093304 -216.60739) (xy 83.991704 -216.643458) (xy 83.991704 -216.833958)
			(xy 84.093304 -216.870026) (xy 84.144104 -216.870026)
		)
		(stroke
			(width 0)
			(type solid)
		)
		(fill yes)
		(layer "F.Cu")
		(net "M_A_CPU1_SB_DQ<30>")
	)
	(gr_poly
		(pts
			(xy 84.194396 -275.225002) (xy 84.158582 -275.188934) (xy 84.061046 -275.142706) (xy 83.926426 -275.27758)
			(xy 83.972654 -275.374862) (xy 84.008468 -275.41093)
		)
		(stroke
			(width 0)
			(type solid)
		)
		(fill yes)
		(layer "F.Cu")
		(net "M_A_CPU1_SA_DQ<18>")
	)
	(gr_poly
		(pts
			(xy 84.233512 -296.54246) (xy 84.182712 -296.54246) (xy 84.081112 -296.578782) (xy 84.081112 -296.769282)
			(xy 84.182712 -296.80535) (xy 84.233512 -296.80535)
		)
		(stroke
			(width 0)
			(type solid)
		)
		(fill yes)
		(layer "F.Cu")
		(net "M_A_CPU1_SA_DQ<1>")
	)
	(gr_poly
		(pts
			(xy 84.233512 -295.94556) (xy 84.182712 -295.94556) (xy 84.081112 -295.981882) (xy 84.081112 -296.172382)
			(xy 84.182712 -296.20845) (xy 84.233512 -296.20845)
		)
		(stroke
			(width 0)
			(type solid)
		)
		(fill yes)
		(layer "F.Cu")
		(net "M_A_CPU1_SA_DQ<1>")
	)
	(gr_poly
		(pts
			(xy 84.233512 -295.34866) (xy 84.182712 -295.34866) (xy 84.081112 -295.384982) (xy 84.081112 -295.575482)
			(xy 84.182712 -295.61155) (xy 84.233512 -295.61155)
		)
		(stroke
			(width 0)
			(type solid)
		)
		(fill yes)
		(layer "F.Cu")
		(net "M_A_CPU1_SA_DQ<1>")
	)
	(gr_poly
		(pts
			(xy 84.233512 -294.75176) (xy 84.182712 -294.75176) (xy 84.081112 -294.788082) (xy 84.081112 -294.978582)
			(xy 84.182712 -295.01465) (xy 84.233512 -295.01465)
		)
		(stroke
			(width 0)
			(type solid)
		)
		(fill yes)
		(layer "F.Cu")
		(net "M_A_CPU1_SA_DQ<1>")
	)
	(gr_poly
		(pts
			(xy 84.233512 -294.15486) (xy 84.182712 -294.15486) (xy 84.081112 -294.191182) (xy 84.081112 -294.381682)
			(xy 84.182712 -294.41775) (xy 84.233512 -294.41775)
		)
		(stroke
			(width 0)
			(type solid)
		)
		(fill yes)
		(layer "F.Cu")
		(net "M_A_CPU1_SA_DQ<1>")
	)
	(gr_poly
		(pts
			(xy 84.233512 -293.55796) (xy 84.182712 -293.55796) (xy 84.081112 -293.594282) (xy 84.081112 -293.784782)
			(xy 84.182712 -293.82085) (xy 84.233512 -293.82085)
		)
		(stroke
			(width 0)
			(type solid)
		)
		(fill yes)
		(layer "F.Cu")
		(net "M_A_CPU1_SA_DQ<1>")
	)
	(gr_poly
		(pts
			(xy 84.233512 -292.96106) (xy 84.182712 -292.96106) (xy 84.081112 -292.997382) (xy 84.081112 -293.187882)
			(xy 84.182712 -293.22395) (xy 84.233512 -293.22395)
		)
		(stroke
			(width 0)
			(type solid)
		)
		(fill yes)
		(layer "F.Cu")
		(net "M_A_CPU1_SA_DQ<1>")
	)
	(gr_poly
		(pts
			(xy 84.233512 -292.36416) (xy 84.182712 -292.36416) (xy 84.081112 -292.400482) (xy 84.081112 -292.590982)
			(xy 84.182712 -292.62705) (xy 84.233512 -292.62705)
		)
		(stroke
			(width 0)
			(type solid)
		)
		(fill yes)
		(layer "F.Cu")
		(net "M_A_CPU1_SA_DQ<1>")
	)
	(gr_poly
		(pts
			(xy 84.233512 -291.76726) (xy 84.182712 -291.76726) (xy 84.081112 -291.803582) (xy 84.081112 -291.994082)
			(xy 84.182712 -292.03015) (xy 84.233512 -292.03015)
		)
		(stroke
			(width 0)
			(type solid)
		)
		(fill yes)
		(layer "F.Cu")
		(net "M_A_CPU1_SA_DQ<1>")
	)
	(gr_poly
		(pts
			(xy 84.233512 -291.17036) (xy 84.182712 -291.17036) (xy 84.081112 -291.206682) (xy 84.081112 -291.397182)
			(xy 84.182712 -291.43325) (xy 84.233512 -291.43325)
		)
		(stroke
			(width 0)
			(type solid)
		)
		(fill yes)
		(layer "F.Cu")
		(net "M_A_CPU1_SA_DQ<1>")
	)
	(gr_poly
		(pts
			(xy 84.233512 -290.57346) (xy 84.182712 -290.57346) (xy 84.081112 -290.609782) (xy 84.081112 -290.800282)
			(xy 84.182712 -290.83635) (xy 84.233512 -290.83635)
		)
		(stroke
			(width 0)
			(type solid)
		)
		(fill yes)
		(layer "F.Cu")
		(net "M_A_CPU1_SA_DQ<1>")
	)
	(gr_poly
		(pts
			(xy 84.233512 -289.97656) (xy 84.182712 -289.97656) (xy 84.081112 -290.012882) (xy 84.081112 -290.203382)
			(xy 84.182712 -290.23945) (xy 84.233512 -290.23945)
		)
		(stroke
			(width 0)
			(type solid)
		)
		(fill yes)
		(layer "F.Cu")
		(net "M_A_CPU1_SA_DQ<1>")
	)
	(gr_poly
		(pts
			(xy 84.233512 -289.37966) (xy 84.182712 -289.37966) (xy 84.081112 -289.415982) (xy 84.081112 -289.606482)
			(xy 84.182712 -289.64255) (xy 84.233512 -289.64255)
		)
		(stroke
			(width 0)
			(type solid)
		)
		(fill yes)
		(layer "F.Cu")
		(net "M_A_CPU1_SA_DQ<1>")
	)
	(gr_poly
		(pts
			(xy 84.233512 -288.78276) (xy 84.182712 -288.78276) (xy 84.081112 -288.819082) (xy 84.081112 -289.009582)
			(xy 84.182712 -289.04565) (xy 84.233512 -289.04565)
		)
		(stroke
			(width 0)
			(type solid)
		)
		(fill yes)
		(layer "F.Cu")
		(net "M_A_CPU1_SA_DQ<1>")
	)
	(gr_poly
		(pts
			(xy 84.233512 -288.18586) (xy 84.182712 -288.18586) (xy 84.081112 -288.222182) (xy 84.081112 -288.412682)
			(xy 84.182712 -288.44875) (xy 84.233512 -288.44875)
		)
		(stroke
			(width 0)
			(type solid)
		)
		(fill yes)
		(layer "F.Cu")
		(net "M_A_CPU1_SA_DQ<1>")
	)
	(gr_poly
		(pts
			(xy 84.233512 -287.58896) (xy 84.182712 -287.58896) (xy 84.081112 -287.625282) (xy 84.081112 -287.815782)
			(xy 84.182712 -287.85185) (xy 84.233512 -287.85185)
		)
		(stroke
			(width 0)
			(type solid)
		)
		(fill yes)
		(layer "F.Cu")
		(net "M_A_CPU1_SA_DQ<1>")
	)
	(gr_poly
		(pts
			(xy 84.233512 -286.99206) (xy 84.182712 -286.99206) (xy 84.081112 -287.028382) (xy 84.081112 -287.218882)
			(xy 84.182712 -287.25495) (xy 84.233512 -287.25495)
		)
		(stroke
			(width 0)
			(type solid)
		)
		(fill yes)
		(layer "F.Cu")
		(net "M_A_CPU1_SA_DQ<1>")
	)
	(gr_poly
		(pts
			(xy 84.233512 -286.39516) (xy 84.182712 -286.39516) (xy 84.081112 -286.431482) (xy 84.081112 -286.621982)
			(xy 84.182712 -286.65805) (xy 84.233512 -286.65805)
		)
		(stroke
			(width 0)
			(type solid)
		)
		(fill yes)
		(layer "F.Cu")
		(net "M_A_CPU1_SA_DQ<1>")
	)
	(gr_poly
		(pts
			(xy 84.233512 -285.79826) (xy 84.182712 -285.79826) (xy 84.081112 -285.834582) (xy 84.081112 -286.025082)
			(xy 84.182712 -286.06115) (xy 84.233512 -286.06115)
		)
		(stroke
			(width 0)
			(type solid)
		)
		(fill yes)
		(layer "F.Cu")
		(net "M_A_CPU1_SA_DQ<1>")
	)
	(gr_poly
		(pts
			(xy 84.233512 -285.20136) (xy 84.182712 -285.20136) (xy 84.081112 -285.237682) (xy 84.081112 -285.428182)
			(xy 84.182712 -285.46425) (xy 84.233512 -285.46425)
		)
		(stroke
			(width 0)
			(type solid)
		)
		(fill yes)
		(layer "F.Cu")
		(net "M_A_CPU1_SA_DQ<1>")
	)
	(gr_poly
		(pts
			(xy 84.233512 -284.60446) (xy 84.182712 -284.60446) (xy 84.081112 -284.640782) (xy 84.081112 -284.831282)
			(xy 84.182712 -284.86735) (xy 84.233512 -284.86735)
		)
		(stroke
			(width 0)
			(type solid)
		)
		(fill yes)
		(layer "F.Cu")
		(net "M_A_CPU1_SA_DQ<1>")
	)
	(gr_poly
		(pts
			(xy 84.233512 -284.00756) (xy 84.182712 -284.00756) (xy 84.081112 -284.043882) (xy 84.081112 -284.234382)
			(xy 84.182712 -284.27045) (xy 84.233512 -284.27045)
		)
		(stroke
			(width 0)
			(type solid)
		)
		(fill yes)
		(layer "F.Cu")
		(net "M_A_CPU1_SA_DQ<1>")
	)
	(gr_poly
		(pts
			(xy 84.233512 -283.41066) (xy 84.182712 -283.41066) (xy 84.081112 -283.446982) (xy 84.081112 -283.637482)
			(xy 84.182712 -283.67355) (xy 84.233512 -283.67355)
		)
		(stroke
			(width 0)
			(type solid)
		)
		(fill yes)
		(layer "F.Cu")
		(net "M_A_CPU1_SA_DQ<1>")
	)
	(gr_poly
		(pts
			(xy 84.233512 -282.81376) (xy 84.182712 -282.81376) (xy 84.081112 -282.850082) (xy 84.081112 -283.040582)
			(xy 84.182712 -283.07665) (xy 84.233512 -283.07665)
		)
		(stroke
			(width 0)
			(type solid)
		)
		(fill yes)
		(layer "F.Cu")
		(net "M_A_CPU1_SA_DQ<1>")
	)
	(gr_poly
		(pts
			(xy 84.244688 -281.65171) (xy 84.282026 -281.464766) (xy 84.189316 -281.409394) (xy 84.139532 -281.399488)
			(xy 84.08797 -281.657298) (xy 84.137754 -281.667204)
		)
		(stroke
			(width 0)
			(type solid)
		)
		(fill yes)
		(layer "F.Cu")
		(net "M_A_CPU1_SA_DQ<3>")
	)
	(gr_poly
		(pts
			(xy 84.281264 -275.785072) (xy 84.235036 -275.68779) (xy 84.199222 -275.651722) (xy 84.013294 -275.83765)
			(xy 84.049108 -275.873464) (xy 84.146644 -275.919946)
		)
		(stroke
			(width 0)
			(type solid)
		)
		(fill yes)
		(layer "F.Cu")
		(net "M_A_CPU1_SA_DQ<16>")
	)
	(gr_poly
		(pts
			(xy 84.296504 -218.326208) (xy 84.296504 -218.135708) (xy 84.194904 -218.099386) (xy 84.144104 -218.099386)
			(xy 84.144104 -218.36253) (xy 84.194904 -218.36253)
		)
		(stroke
			(width 0)
			(type solid)
		)
		(fill yes)
		(layer "F.Cu")
		(net "M_A_CPU1_SB_DQ<30>")
	)
	(gr_poly
		(pts
			(xy 84.296504 -217.729308) (xy 84.296504 -217.538808) (xy 84.194904 -217.502486) (xy 84.144104 -217.502486)
			(xy 84.144104 -217.76563) (xy 84.194904 -217.76563)
		)
		(stroke
			(width 0)
			(type solid)
		)
		(fill yes)
		(layer "F.Cu")
		(net "M_A_CPU1_SB_DQ<30>")
	)
	(gr_poly
		(pts
			(xy 84.296504 -217.132408) (xy 84.296504 -216.941908) (xy 84.194904 -216.905586) (xy 84.144104 -216.905586)
			(xy 84.144104 -217.16873) (xy 84.194904 -217.16873)
		)
		(stroke
			(width 0)
			(type solid)
		)
		(fill yes)
		(layer "F.Cu")
		(net "M_A_CPU1_SB_DQ<30>")
	)
	(gr_poly
		(pts
			(xy 84.296504 -216.535508) (xy 84.296504 -216.345008) (xy 84.194904 -216.308686) (xy 84.144104 -216.308686)
			(xy 84.144104 -216.57183) (xy 84.194904 -216.57183)
		)
		(stroke
			(width 0)
			(type solid)
		)
		(fill yes)
		(layer "F.Cu")
		(net "M_A_CPU1_SB_DQ<30>")
	)
	(gr_poly
		(pts
			(xy 84.380324 -281.75204) (xy 84.33054 -281.742134) (xy 84.22386 -281.757628) (xy 84.186522 -281.944318)
			(xy 84.278978 -281.99969) (xy 84.328762 -282.00985)
		)
		(stroke
			(width 0)
			(type solid)
		)
		(fill yes)
		(layer "F.Cu")
		(net "M_A_CPU1_SA_DQ<1>")
	)
	(gr_poly
		(pts
			(xy 84.385912 -296.470832) (xy 84.385912 -296.280332) (xy 84.284312 -296.24401) (xy 84.233512 -296.24401)
			(xy 84.233512 -296.5069) (xy 84.284312 -296.5069)
		)
		(stroke
			(width 0)
			(type solid)
		)
		(fill yes)
		(layer "F.Cu")
		(net "M_A_CPU1_SA_DQ<1>")
	)
	(gr_poly
		(pts
			(xy 84.385912 -295.873932) (xy 84.385912 -295.683432) (xy 84.284312 -295.64711) (xy 84.233512 -295.64711)
			(xy 84.233512 -295.91) (xy 84.284312 -295.91)
		)
		(stroke
			(width 0)
			(type solid)
		)
		(fill yes)
		(layer "F.Cu")
		(net "M_A_CPU1_SA_DQ<1>")
	)
	(gr_poly
		(pts
			(xy 84.385912 -295.277032) (xy 84.385912 -295.086532) (xy 84.284312 -295.05021) (xy 84.233512 -295.05021)
			(xy 84.233512 -295.3131) (xy 84.284312 -295.3131)
		)
		(stroke
			(width 0)
			(type solid)
		)
		(fill yes)
		(layer "F.Cu")
		(net "M_A_CPU1_SA_DQ<1>")
	)
	(gr_poly
		(pts
			(xy 84.385912 -294.680132) (xy 84.385912 -294.489632) (xy 84.284312 -294.45331) (xy 84.233512 -294.45331)
			(xy 84.233512 -294.7162) (xy 84.284312 -294.7162)
		)
		(stroke
			(width 0)
			(type solid)
		)
		(fill yes)
		(layer "F.Cu")
		(net "M_A_CPU1_SA_DQ<1>")
	)
	(gr_poly
		(pts
			(xy 84.385912 -294.083232) (xy 84.385912 -293.892732) (xy 84.284312 -293.85641) (xy 84.233512 -293.85641)
			(xy 84.233512 -294.1193) (xy 84.284312 -294.1193)
		)
		(stroke
			(width 0)
			(type solid)
		)
		(fill yes)
		(layer "F.Cu")
		(net "M_A_CPU1_SA_DQ<1>")
	)
	(gr_poly
		(pts
			(xy 84.385912 -293.486332) (xy 84.385912 -293.295832) (xy 84.284312 -293.25951) (xy 84.233512 -293.25951)
			(xy 84.233512 -293.5224) (xy 84.284312 -293.5224)
		)
		(stroke
			(width 0)
			(type solid)
		)
		(fill yes)
		(layer "F.Cu")
		(net "M_A_CPU1_SA_DQ<1>")
	)
	(gr_poly
		(pts
			(xy 84.385912 -292.889432) (xy 84.385912 -292.698932) (xy 84.284312 -292.66261) (xy 84.233512 -292.66261)
			(xy 84.233512 -292.9255) (xy 84.284312 -292.9255)
		)
		(stroke
			(width 0)
			(type solid)
		)
		(fill yes)
		(layer "F.Cu")
		(net "M_A_CPU1_SA_DQ<1>")
	)
	(gr_poly
		(pts
			(xy 84.385912 -292.292532) (xy 84.385912 -292.102032) (xy 84.284312 -292.06571) (xy 84.233512 -292.06571)
			(xy 84.233512 -292.3286) (xy 84.284312 -292.3286)
		)
		(stroke
			(width 0)
			(type solid)
		)
		(fill yes)
		(layer "F.Cu")
		(net "M_A_CPU1_SA_DQ<1>")
	)
	(gr_poly
		(pts
			(xy 84.385912 -291.695632) (xy 84.385912 -291.505132) (xy 84.284312 -291.46881) (xy 84.233512 -291.46881)
			(xy 84.233512 -291.7317) (xy 84.284312 -291.7317)
		)
		(stroke
			(width 0)
			(type solid)
		)
		(fill yes)
		(layer "F.Cu")
		(net "M_A_CPU1_SA_DQ<1>")
	)
	(gr_poly
		(pts
			(xy 84.385912 -291.098732) (xy 84.385912 -290.908232) (xy 84.284312 -290.87191) (xy 84.233512 -290.87191)
			(xy 84.233512 -291.1348) (xy 84.284312 -291.1348)
		)
		(stroke
			(width 0)
			(type solid)
		)
		(fill yes)
		(layer "F.Cu")
		(net "M_A_CPU1_SA_DQ<1>")
	)
	(gr_poly
		(pts
			(xy 84.385912 -290.501832) (xy 84.385912 -290.311332) (xy 84.284312 -290.27501) (xy 84.233512 -290.27501)
			(xy 84.233512 -290.5379) (xy 84.284312 -290.5379)
		)
		(stroke
			(width 0)
			(type solid)
		)
		(fill yes)
		(layer "F.Cu")
		(net "M_A_CPU1_SA_DQ<1>")
	)
	(gr_poly
		(pts
			(xy 84.385912 -289.904932) (xy 84.385912 -289.714432) (xy 84.284312 -289.67811) (xy 84.233512 -289.67811)
			(xy 84.233512 -289.941) (xy 84.284312 -289.941)
		)
		(stroke
			(width 0)
			(type solid)
		)
		(fill yes)
		(layer "F.Cu")
		(net "M_A_CPU1_SA_DQ<1>")
	)
	(gr_poly
		(pts
			(xy 84.385912 -289.308032) (xy 84.385912 -289.117532) (xy 84.284312 -289.08121) (xy 84.233512 -289.08121)
			(xy 84.233512 -289.3441) (xy 84.284312 -289.3441)
		)
		(stroke
			(width 0)
			(type solid)
		)
		(fill yes)
		(layer "F.Cu")
		(net "M_A_CPU1_SA_DQ<1>")
	)
	(gr_poly
		(pts
			(xy 84.385912 -288.711132) (xy 84.385912 -288.520632) (xy 84.284312 -288.48431) (xy 84.233512 -288.48431)
			(xy 84.233512 -288.7472) (xy 84.284312 -288.7472)
		)
		(stroke
			(width 0)
			(type solid)
		)
		(fill yes)
		(layer "F.Cu")
		(net "M_A_CPU1_SA_DQ<1>")
	)
	(gr_poly
		(pts
			(xy 84.385912 -288.114232) (xy 84.385912 -287.923732) (xy 84.284312 -287.88741) (xy 84.233512 -287.88741)
			(xy 84.233512 -288.1503) (xy 84.284312 -288.1503)
		)
		(stroke
			(width 0)
			(type solid)
		)
		(fill yes)
		(layer "F.Cu")
		(net "M_A_CPU1_SA_DQ<1>")
	)
	(gr_poly
		(pts
			(xy 84.385912 -287.517332) (xy 84.385912 -287.326832) (xy 84.284312 -287.29051) (xy 84.233512 -287.29051)
			(xy 84.233512 -287.5534) (xy 84.284312 -287.5534)
		)
		(stroke
			(width 0)
			(type solid)
		)
		(fill yes)
		(layer "F.Cu")
		(net "M_A_CPU1_SA_DQ<1>")
	)
	(gr_poly
		(pts
			(xy 84.385912 -286.920432) (xy 84.385912 -286.729932) (xy 84.284312 -286.69361) (xy 84.233512 -286.69361)
			(xy 84.233512 -286.9565) (xy 84.284312 -286.9565)
		)
		(stroke
			(width 0)
			(type solid)
		)
		(fill yes)
		(layer "F.Cu")
		(net "M_A_CPU1_SA_DQ<1>")
	)
	(gr_poly
		(pts
			(xy 84.385912 -286.323532) (xy 84.385912 -286.133032) (xy 84.284312 -286.09671) (xy 84.233512 -286.09671)
			(xy 84.233512 -286.3596) (xy 84.284312 -286.3596)
		)
		(stroke
			(width 0)
			(type solid)
		)
		(fill yes)
		(layer "F.Cu")
		(net "M_A_CPU1_SA_DQ<1>")
	)
	(gr_poly
		(pts
			(xy 84.385912 -285.726632) (xy 84.385912 -285.536132) (xy 84.284312 -285.49981) (xy 84.233512 -285.49981)
			(xy 84.233512 -285.7627) (xy 84.284312 -285.7627)
		)
		(stroke
			(width 0)
			(type solid)
		)
		(fill yes)
		(layer "F.Cu")
		(net "M_A_CPU1_SA_DQ<1>")
	)
	(gr_poly
		(pts
			(xy 84.385912 -285.129732) (xy 84.385912 -284.939232) (xy 84.284312 -284.90291) (xy 84.233512 -284.90291)
			(xy 84.233512 -285.1658) (xy 84.284312 -285.1658)
		)
		(stroke
			(width 0)
			(type solid)
		)
		(fill yes)
		(layer "F.Cu")
		(net "M_A_CPU1_SA_DQ<1>")
	)
	(gr_poly
		(pts
			(xy 84.385912 -284.532832) (xy 84.385912 -284.342332) (xy 84.284312 -284.30601) (xy 84.233512 -284.30601)
			(xy 84.233512 -284.5689) (xy 84.284312 -284.5689)
		)
		(stroke
			(width 0)
			(type solid)
		)
		(fill yes)
		(layer "F.Cu")
		(net "M_A_CPU1_SA_DQ<1>")
	)
	(gr_poly
		(pts
			(xy 84.385912 -283.935932) (xy 84.385912 -283.745432) (xy 84.284312 -283.70911) (xy 84.233512 -283.70911)
			(xy 84.233512 -283.972) (xy 84.284312 -283.972)
		)
		(stroke
			(width 0)
			(type solid)
		)
		(fill yes)
		(layer "F.Cu")
		(net "M_A_CPU1_SA_DQ<1>")
	)
	(gr_poly
		(pts
			(xy 84.385912 -283.339032) (xy 84.385912 -283.148532) (xy 84.284312 -283.11221) (xy 84.233512 -283.11221)
			(xy 84.233512 -283.3751) (xy 84.284312 -283.3751)
		)
		(stroke
			(width 0)
			(type solid)
		)
		(fill yes)
		(layer "F.Cu")
		(net "M_A_CPU1_SA_DQ<1>")
	)
	(gr_poly
		(pts
			(xy 84.410296 -275.440648) (xy 84.374228 -275.404834) (xy 84.276946 -275.358606) (xy 84.142072 -275.493226)
			(xy 84.1883 -275.590762) (xy 84.224368 -275.626576)
		)
		(stroke
			(width 0)
			(type solid)
		)
		(fill yes)
		(layer "F.Cu")
		(net "M_A_CPU1_SA_DQ<16>")
	)
	(gr_poly
		(pts
			(xy 84.426806 -282.29687) (xy 84.464144 -282.109926) (xy 84.371688 -282.054554) (xy 84.321904 -282.044648)
			(xy 84.270342 -282.302458) (xy 84.320126 -282.312364)
		)
		(stroke
			(width 0)
			(type solid)
		)
		(fill yes)
		(layer "F.Cu")
		(net "M_A_CPU1_SA_DQ<1>")
	)
	(gr_poly
		(pts
			(xy 84.448904 -217.80119) (xy 84.398104 -217.80119) (xy 84.296504 -217.837258) (xy 84.296504 -218.027758)
			(xy 84.398104 -218.063826) (xy 84.448904 -218.063826)
		)
		(stroke
			(width 0)
			(type solid)
		)
		(fill yes)
		(layer "F.Cu")
		(net "M_A_CPU1_SB_DQ<29>")
	)
	(gr_poly
		(pts
			(xy 84.448904 -217.20429) (xy 84.398104 -217.20429) (xy 84.296504 -217.240358) (xy 84.296504 -217.430858)
			(xy 84.398104 -217.466926) (xy 84.448904 -217.466926)
		)
		(stroke
			(width 0)
			(type solid)
		)
		(fill yes)
		(layer "F.Cu")
		(net "M_A_CPU1_SB_DQ<29>")
	)
	(gr_poly
		(pts
			(xy 84.448904 -216.60739) (xy 84.398104 -216.60739) (xy 84.296504 -216.643458) (xy 84.296504 -216.833958)
			(xy 84.398104 -216.870026) (xy 84.448904 -216.870026)
		)
		(stroke
			(width 0)
			(type solid)
		)
		(fill yes)
		(layer "F.Cu")
		(net "M_A_CPU1_SB_DQ<29>")
	)
	(gr_poly
		(pts
			(xy 84.538312 -296.54246) (xy 84.487512 -296.54246) (xy 84.385912 -296.578782) (xy 84.385912 -296.769282)
			(xy 84.487512 -296.80535) (xy 84.538312 -296.80535)
		)
		(stroke
			(width 0)
			(type solid)
		)
		(fill yes)
		(layer "F.Cu")
		(net "M_A_CPU1_SA_DQ<2>")
	)
	(gr_poly
		(pts
			(xy 84.538312 -295.94556) (xy 84.487512 -295.94556) (xy 84.385912 -295.981882) (xy 84.385912 -296.172382)
			(xy 84.487512 -296.20845) (xy 84.538312 -296.20845)
		)
		(stroke
			(width 0)
			(type solid)
		)
		(fill yes)
		(layer "F.Cu")
		(net "M_A_CPU1_SA_DQ<2>")
	)
	(gr_poly
		(pts
			(xy 84.538312 -295.34866) (xy 84.487512 -295.34866) (xy 84.385912 -295.384982) (xy 84.385912 -295.575482)
			(xy 84.487512 -295.61155) (xy 84.538312 -295.61155)
		)
		(stroke
			(width 0)
			(type solid)
		)
		(fill yes)
		(layer "F.Cu")
		(net "M_A_CPU1_SA_DQ<2>")
	)
	(gr_poly
		(pts
			(xy 84.538312 -294.75176) (xy 84.487512 -294.75176) (xy 84.385912 -294.788082) (xy 84.385912 -294.978582)
			(xy 84.487512 -295.01465) (xy 84.538312 -295.01465)
		)
		(stroke
			(width 0)
			(type solid)
		)
		(fill yes)
		(layer "F.Cu")
		(net "M_A_CPU1_SA_DQ<2>")
	)
	(gr_poly
		(pts
			(xy 84.538312 -294.15486) (xy 84.487512 -294.15486) (xy 84.385912 -294.191182) (xy 84.385912 -294.381682)
			(xy 84.487512 -294.41775) (xy 84.538312 -294.41775)
		)
		(stroke
			(width 0)
			(type solid)
		)
		(fill yes)
		(layer "F.Cu")
		(net "M_A_CPU1_SA_DQ<2>")
	)
	(gr_poly
		(pts
			(xy 84.538312 -293.55796) (xy 84.487512 -293.55796) (xy 84.385912 -293.594282) (xy 84.385912 -293.784782)
			(xy 84.487512 -293.82085) (xy 84.538312 -293.82085)
		)
		(stroke
			(width 0)
			(type solid)
		)
		(fill yes)
		(layer "F.Cu")
		(net "M_A_CPU1_SA_DQ<2>")
	)
	(gr_poly
		(pts
			(xy 84.538312 -292.96106) (xy 84.487512 -292.96106) (xy 84.385912 -292.997382) (xy 84.385912 -293.187882)
			(xy 84.487512 -293.22395) (xy 84.538312 -293.22395)
		)
		(stroke
			(width 0)
			(type solid)
		)
		(fill yes)
		(layer "F.Cu")
		(net "M_A_CPU1_SA_DQ<2>")
	)
	(gr_poly
		(pts
			(xy 84.538312 -292.36416) (xy 84.487512 -292.36416) (xy 84.385912 -292.400482) (xy 84.385912 -292.590982)
			(xy 84.487512 -292.62705) (xy 84.538312 -292.62705)
		)
		(stroke
			(width 0)
			(type solid)
		)
		(fill yes)
		(layer "F.Cu")
		(net "M_A_CPU1_SA_DQ<2>")
	)
	(gr_poly
		(pts
			(xy 84.538312 -291.76726) (xy 84.487512 -291.76726) (xy 84.385912 -291.803582) (xy 84.385912 -291.994082)
			(xy 84.487512 -292.03015) (xy 84.538312 -292.03015)
		)
		(stroke
			(width 0)
			(type solid)
		)
		(fill yes)
		(layer "F.Cu")
		(net "M_A_CPU1_SA_DQ<2>")
	)
	(gr_poly
		(pts
			(xy 84.538312 -291.17036) (xy 84.487512 -291.17036) (xy 84.385912 -291.206682) (xy 84.385912 -291.397182)
			(xy 84.487512 -291.43325) (xy 84.538312 -291.43325)
		)
		(stroke
			(width 0)
			(type solid)
		)
		(fill yes)
		(layer "F.Cu")
		(net "M_A_CPU1_SA_DQ<2>")
	)
	(gr_poly
		(pts
			(xy 84.538312 -290.57346) (xy 84.487512 -290.57346) (xy 84.385912 -290.609782) (xy 84.385912 -290.800282)
			(xy 84.487512 -290.83635) (xy 84.538312 -290.83635)
		)
		(stroke
			(width 0)
			(type solid)
		)
		(fill yes)
		(layer "F.Cu")
		(net "M_A_CPU1_SA_DQ<2>")
	)
	(gr_poly
		(pts
			(xy 84.538312 -289.97656) (xy 84.487512 -289.97656) (xy 84.385912 -290.012882) (xy 84.385912 -290.203382)
			(xy 84.487512 -290.23945) (xy 84.538312 -290.23945)
		)
		(stroke
			(width 0)
			(type solid)
		)
		(fill yes)
		(layer "F.Cu")
		(net "M_A_CPU1_SA_DQ<2>")
	)
	(gr_poly
		(pts
			(xy 84.538312 -289.37966) (xy 84.487512 -289.37966) (xy 84.385912 -289.415982) (xy 84.385912 -289.606482)
			(xy 84.487512 -289.64255) (xy 84.538312 -289.64255)
		)
		(stroke
			(width 0)
			(type solid)
		)
		(fill yes)
		(layer "F.Cu")
		(net "M_A_CPU1_SA_DQ<2>")
	)
	(gr_poly
		(pts
			(xy 84.538312 -288.78276) (xy 84.487512 -288.78276) (xy 84.385912 -288.819082) (xy 84.385912 -289.009582)
			(xy 84.487512 -289.04565) (xy 84.538312 -289.04565)
		)
		(stroke
			(width 0)
			(type solid)
		)
		(fill yes)
		(layer "F.Cu")
		(net "M_A_CPU1_SA_DQ<2>")
	)
	(gr_poly
		(pts
			(xy 84.538312 -288.18586) (xy 84.487512 -288.18586) (xy 84.385912 -288.222182) (xy 84.385912 -288.412682)
			(xy 84.487512 -288.44875) (xy 84.538312 -288.44875)
		)
		(stroke
			(width 0)
			(type solid)
		)
		(fill yes)
		(layer "F.Cu")
		(net "M_A_CPU1_SA_DQ<2>")
	)
	(gr_poly
		(pts
			(xy 84.538312 -287.58896) (xy 84.487512 -287.58896) (xy 84.385912 -287.625282) (xy 84.385912 -287.815782)
			(xy 84.487512 -287.85185) (xy 84.538312 -287.85185)
		)
		(stroke
			(width 0)
			(type solid)
		)
		(fill yes)
		(layer "F.Cu")
		(net "M_A_CPU1_SA_DQ<2>")
	)
	(gr_poly
		(pts
			(xy 84.538312 -286.99206) (xy 84.487512 -286.99206) (xy 84.385912 -287.028382) (xy 84.385912 -287.218882)
			(xy 84.487512 -287.25495) (xy 84.538312 -287.25495)
		)
		(stroke
			(width 0)
			(type solid)
		)
		(fill yes)
		(layer "F.Cu")
		(net "M_A_CPU1_SA_DQ<2>")
	)
	(gr_poly
		(pts
			(xy 84.538312 -286.39516) (xy 84.487512 -286.39516) (xy 84.385912 -286.431482) (xy 84.385912 -286.621982)
			(xy 84.487512 -286.65805) (xy 84.538312 -286.65805)
		)
		(stroke
			(width 0)
			(type solid)
		)
		(fill yes)
		(layer "F.Cu")
		(net "M_A_CPU1_SA_DQ<2>")
	)
	(gr_poly
		(pts
			(xy 84.538312 -285.79826) (xy 84.487512 -285.79826) (xy 84.385912 -285.834582) (xy 84.385912 -286.025082)
			(xy 84.487512 -286.06115) (xy 84.538312 -286.06115)
		)
		(stroke
			(width 0)
			(type solid)
		)
		(fill yes)
		(layer "F.Cu")
		(net "M_A_CPU1_SA_DQ<2>")
	)
	(gr_poly
		(pts
			(xy 84.538312 -285.20136) (xy 84.487512 -285.20136) (xy 84.385912 -285.237682) (xy 84.385912 -285.428182)
			(xy 84.487512 -285.46425) (xy 84.538312 -285.46425)
		)
		(stroke
			(width 0)
			(type solid)
		)
		(fill yes)
		(layer "F.Cu")
		(net "M_A_CPU1_SA_DQ<2>")
	)
	(gr_poly
		(pts
			(xy 84.538312 -284.60446) (xy 84.487512 -284.60446) (xy 84.385912 -284.640782) (xy 84.385912 -284.831282)
			(xy 84.487512 -284.86735) (xy 84.538312 -284.86735)
		)
		(stroke
			(width 0)
			(type solid)
		)
		(fill yes)
		(layer "F.Cu")
		(net "M_A_CPU1_SA_DQ<2>")
	)
	(gr_poly
		(pts
			(xy 84.538312 -284.00756) (xy 84.487512 -284.00756) (xy 84.385912 -284.043882) (xy 84.385912 -284.234382)
			(xy 84.487512 -284.27045) (xy 84.538312 -284.27045)
		)
		(stroke
			(width 0)
			(type solid)
		)
		(fill yes)
		(layer "F.Cu")
		(net "M_A_CPU1_SA_DQ<2>")
	)
	(gr_poly
		(pts
			(xy 84.538312 -283.41066) (xy 84.487512 -283.41066) (xy 84.385912 -283.446982) (xy 84.385912 -283.637482)
			(xy 84.487512 -283.67355) (xy 84.538312 -283.67355)
		)
		(stroke
			(width 0)
			(type solid)
		)
		(fill yes)
		(layer "F.Cu")
		(net "M_A_CPU1_SA_DQ<2>")
	)
	(gr_poly
		(pts
			(xy 84.538312 -282.81376) (xy 84.487512 -282.81376) (xy 84.385912 -282.850082) (xy 84.385912 -283.040582)
			(xy 84.487512 -283.07665) (xy 84.538312 -283.07665)
		)
		(stroke
			(width 0)
			(type solid)
		)
		(fill yes)
		(layer "F.Cu")
		(net "M_A_CPU1_SA_DQ<2>")
	)
	(gr_poly
		(pts
			(xy 84.5439 -281.7114) (xy 84.581238 -281.52471) (xy 84.488782 -281.469338) (xy 84.438744 -281.459432)
			(xy 84.387436 -281.716988) (xy 84.43722 -281.727148)
		)
		(stroke
			(width 0)
			(type solid)
		)
		(fill yes)
		(layer "F.Cu")
		(net "M_A_CPU1_SA_DQ<1>")
	)
	(gr_poly
		(pts
			(xy 84.601304 -218.326208) (xy 84.601304 -218.135708) (xy 84.499704 -218.099386) (xy 84.448904 -218.099386)
			(xy 84.448904 -218.36253) (xy 84.499704 -218.36253)
		)
		(stroke
			(width 0)
			(type solid)
		)
		(fill yes)
		(layer "F.Cu")
		(net "M_A_CPU1_SB_DQ<29>")
	)
	(gr_poly
		(pts
			(xy 84.601304 -217.729308) (xy 84.601304 -217.538808) (xy 84.499704 -217.502486) (xy 84.448904 -217.502486)
			(xy 84.448904 -217.76563) (xy 84.499704 -217.76563)
		)
		(stroke
			(width 0)
			(type solid)
		)
		(fill yes)
		(layer "F.Cu")
		(net "M_A_CPU1_SB_DQ<29>")
	)
	(gr_poly
		(pts
			(xy 84.601304 -217.132408) (xy 84.601304 -216.941908) (xy 84.499704 -216.905586) (xy 84.448904 -216.905586)
			(xy 84.448904 -217.16873) (xy 84.499704 -217.16873)
		)
		(stroke
			(width 0)
			(type solid)
		)
		(fill yes)
		(layer "F.Cu")
		(net "M_A_CPU1_SB_DQ<29>")
	)
	(gr_poly
		(pts
			(xy 84.601304 -216.535508) (xy 84.601304 -216.345008) (xy 84.499704 -216.308686) (xy 84.448904 -216.308686)
			(xy 84.448904 -216.57183) (xy 84.499704 -216.57183)
		)
		(stroke
			(width 0)
			(type solid)
		)
		(fill yes)
		(layer "F.Cu")
		(net "M_A_CPU1_SB_DQ<29>")
	)
	(gr_poly
		(pts
			(xy 84.681822 -281.812238) (xy 84.632038 -281.802332) (xy 84.525358 -281.817826) (xy 84.48802 -282.00477)
			(xy 84.580476 -282.060142) (xy 84.63026 -282.070048)
		)
		(stroke
			(width 0)
			(type solid)
		)
		(fill yes)
		(layer "F.Cu")
		(net "M_A_CPU1_SA_DQ<2>")
	)
	(gr_poly
		(pts
			(xy 84.690712 -296.470832) (xy 84.690712 -296.280332) (xy 84.589112 -296.24401) (xy 84.538312 -296.24401)
			(xy 84.538312 -296.5069) (xy 84.589112 -296.5069)
		)
		(stroke
			(width 0)
			(type solid)
		)
		(fill yes)
		(layer "F.Cu")
		(net "M_A_CPU1_SA_DQ<2>")
	)
	(gr_poly
		(pts
			(xy 84.690712 -295.873932) (xy 84.690712 -295.683432) (xy 84.589112 -295.64711) (xy 84.538312 -295.64711)
			(xy 84.538312 -295.91) (xy 84.589112 -295.91)
		)
		(stroke
			(width 0)
			(type solid)
		)
		(fill yes)
		(layer "F.Cu")
		(net "M_A_CPU1_SA_DQ<2>")
	)
	(gr_poly
		(pts
			(xy 84.690712 -295.277032) (xy 84.690712 -295.086532) (xy 84.589112 -295.05021) (xy 84.538312 -295.05021)
			(xy 84.538312 -295.3131) (xy 84.589112 -295.3131)
		)
		(stroke
			(width 0)
			(type solid)
		)
		(fill yes)
		(layer "F.Cu")
		(net "M_A_CPU1_SA_DQ<2>")
	)
	(gr_poly
		(pts
			(xy 84.690712 -294.680132) (xy 84.690712 -294.489632) (xy 84.589112 -294.45331) (xy 84.538312 -294.45331)
			(xy 84.538312 -294.7162) (xy 84.589112 -294.7162)
		)
		(stroke
			(width 0)
			(type solid)
		)
		(fill yes)
		(layer "F.Cu")
		(net "M_A_CPU1_SA_DQ<2>")
	)
	(gr_poly
		(pts
			(xy 84.690712 -294.083232) (xy 84.690712 -293.892732) (xy 84.589112 -293.85641) (xy 84.538312 -293.85641)
			(xy 84.538312 -294.1193) (xy 84.589112 -294.1193)
		)
		(stroke
			(width 0)
			(type solid)
		)
		(fill yes)
		(layer "F.Cu")
		(net "M_A_CPU1_SA_DQ<2>")
	)
	(gr_poly
		(pts
			(xy 84.690712 -293.486332) (xy 84.690712 -293.295832) (xy 84.589112 -293.25951) (xy 84.538312 -293.25951)
			(xy 84.538312 -293.5224) (xy 84.589112 -293.5224)
		)
		(stroke
			(width 0)
			(type solid)
		)
		(fill yes)
		(layer "F.Cu")
		(net "M_A_CPU1_SA_DQ<2>")
	)
	(gr_poly
		(pts
			(xy 84.690712 -292.889432) (xy 84.690712 -292.698932) (xy 84.589112 -292.66261) (xy 84.538312 -292.66261)
			(xy 84.538312 -292.9255) (xy 84.589112 -292.9255)
		)
		(stroke
			(width 0)
			(type solid)
		)
		(fill yes)
		(layer "F.Cu")
		(net "M_A_CPU1_SA_DQ<2>")
	)
	(gr_poly
		(pts
			(xy 84.690712 -292.292532) (xy 84.690712 -292.102032) (xy 84.589112 -292.06571) (xy 84.538312 -292.06571)
			(xy 84.538312 -292.3286) (xy 84.589112 -292.3286)
		)
		(stroke
			(width 0)
			(type solid)
		)
		(fill yes)
		(layer "F.Cu")
		(net "M_A_CPU1_SA_DQ<2>")
	)
	(gr_poly
		(pts
			(xy 84.690712 -291.695632) (xy 84.690712 -291.505132) (xy 84.589112 -291.46881) (xy 84.538312 -291.46881)
			(xy 84.538312 -291.7317) (xy 84.589112 -291.7317)
		)
		(stroke
			(width 0)
			(type solid)
		)
		(fill yes)
		(layer "F.Cu")
		(net "M_A_CPU1_SA_DQ<2>")
	)
	(gr_poly
		(pts
			(xy 84.690712 -291.098732) (xy 84.690712 -290.908232) (xy 84.589112 -290.87191) (xy 84.538312 -290.87191)
			(xy 84.538312 -291.1348) (xy 84.589112 -291.1348)
		)
		(stroke
			(width 0)
			(type solid)
		)
		(fill yes)
		(layer "F.Cu")
		(net "M_A_CPU1_SA_DQ<2>")
	)
	(gr_poly
		(pts
			(xy 84.690712 -290.501832) (xy 84.690712 -290.311332) (xy 84.589112 -290.27501) (xy 84.538312 -290.27501)
			(xy 84.538312 -290.5379) (xy 84.589112 -290.5379)
		)
		(stroke
			(width 0)
			(type solid)
		)
		(fill yes)
		(layer "F.Cu")
		(net "M_A_CPU1_SA_DQ<2>")
	)
	(gr_poly
		(pts
			(xy 84.690712 -289.904932) (xy 84.690712 -289.714432) (xy 84.589112 -289.67811) (xy 84.538312 -289.67811)
			(xy 84.538312 -289.941) (xy 84.589112 -289.941)
		)
		(stroke
			(width 0)
			(type solid)
		)
		(fill yes)
		(layer "F.Cu")
		(net "M_A_CPU1_SA_DQ<2>")
	)
	(gr_poly
		(pts
			(xy 84.690712 -289.308032) (xy 84.690712 -289.117532) (xy 84.589112 -289.08121) (xy 84.538312 -289.08121)
			(xy 84.538312 -289.3441) (xy 84.589112 -289.3441)
		)
		(stroke
			(width 0)
			(type solid)
		)
		(fill yes)
		(layer "F.Cu")
		(net "M_A_CPU1_SA_DQ<2>")
	)
	(gr_poly
		(pts
			(xy 84.690712 -288.711132) (xy 84.690712 -288.520632) (xy 84.589112 -288.48431) (xy 84.538312 -288.48431)
			(xy 84.538312 -288.7472) (xy 84.589112 -288.7472)
		)
		(stroke
			(width 0)
			(type solid)
		)
		(fill yes)
		(layer "F.Cu")
		(net "M_A_CPU1_SA_DQ<2>")
	)
	(gr_poly
		(pts
			(xy 84.690712 -288.114232) (xy 84.690712 -287.923732) (xy 84.589112 -287.88741) (xy 84.538312 -287.88741)
			(xy 84.538312 -288.1503) (xy 84.589112 -288.1503)
		)
		(stroke
			(width 0)
			(type solid)
		)
		(fill yes)
		(layer "F.Cu")
		(net "M_A_CPU1_SA_DQ<2>")
	)
	(gr_poly
		(pts
			(xy 84.690712 -287.517332) (xy 84.690712 -287.326832) (xy 84.589112 -287.29051) (xy 84.538312 -287.29051)
			(xy 84.538312 -287.5534) (xy 84.589112 -287.5534)
		)
		(stroke
			(width 0)
			(type solid)
		)
		(fill yes)
		(layer "F.Cu")
		(net "M_A_CPU1_SA_DQ<2>")
	)
	(gr_poly
		(pts
			(xy 84.690712 -286.920432) (xy 84.690712 -286.729932) (xy 84.589112 -286.69361) (xy 84.538312 -286.69361)
			(xy 84.538312 -286.9565) (xy 84.589112 -286.9565)
		)
		(stroke
			(width 0)
			(type solid)
		)
		(fill yes)
		(layer "F.Cu")
		(net "M_A_CPU1_SA_DQ<2>")
	)
	(gr_poly
		(pts
			(xy 84.690712 -286.323532) (xy 84.690712 -286.133032) (xy 84.589112 -286.09671) (xy 84.538312 -286.09671)
			(xy 84.538312 -286.3596) (xy 84.589112 -286.3596)
		)
		(stroke
			(width 0)
			(type solid)
		)
		(fill yes)
		(layer "F.Cu")
		(net "M_A_CPU1_SA_DQ<2>")
	)
	(gr_poly
		(pts
			(xy 84.690712 -285.726632) (xy 84.690712 -285.536132) (xy 84.589112 -285.49981) (xy 84.538312 -285.49981)
			(xy 84.538312 -285.7627) (xy 84.589112 -285.7627)
		)
		(stroke
			(width 0)
			(type solid)
		)
		(fill yes)
		(layer "F.Cu")
		(net "M_A_CPU1_SA_DQ<2>")
	)
	(gr_poly
		(pts
			(xy 84.690712 -285.129732) (xy 84.690712 -284.939232) (xy 84.589112 -284.90291) (xy 84.538312 -284.90291)
			(xy 84.538312 -285.1658) (xy 84.589112 -285.1658)
		)
		(stroke
			(width 0)
			(type solid)
		)
		(fill yes)
		(layer "F.Cu")
		(net "M_A_CPU1_SA_DQ<2>")
	)
	(gr_poly
		(pts
			(xy 84.690712 -284.532832) (xy 84.690712 -284.342332) (xy 84.589112 -284.30601) (xy 84.538312 -284.30601)
			(xy 84.538312 -284.5689) (xy 84.589112 -284.5689)
		)
		(stroke
			(width 0)
			(type solid)
		)
		(fill yes)
		(layer "F.Cu")
		(net "M_A_CPU1_SA_DQ<2>")
	)
	(gr_poly
		(pts
			(xy 84.690712 -283.935932) (xy 84.690712 -283.745432) (xy 84.589112 -283.70911) (xy 84.538312 -283.70911)
			(xy 84.538312 -283.972) (xy 84.589112 -283.972)
		)
		(stroke
			(width 0)
			(type solid)
		)
		(fill yes)
		(layer "F.Cu")
		(net "M_A_CPU1_SA_DQ<2>")
	)
	(gr_poly
		(pts
			(xy 84.690712 -283.339032) (xy 84.690712 -283.148532) (xy 84.589112 -283.11221) (xy 84.538312 -283.11221)
			(xy 84.538312 -283.3751) (xy 84.589112 -283.3751)
		)
		(stroke
			(width 0)
			(type solid)
		)
		(fill yes)
		(layer "F.Cu")
		(net "M_A_CPU1_SA_DQ<2>")
	)
	(gr_poly
		(pts
			(xy 84.72805 -282.357322) (xy 84.765642 -282.170378) (xy 84.673186 -282.115006) (xy 84.623402 -282.104846)
			(xy 84.571586 -282.362656) (xy 84.62137 -282.372816)
		)
		(stroke
			(width 0)
			(type solid)
		)
		(fill yes)
		(layer "F.Cu")
		(net "M_A_CPU1_SA_DQ<2>")
	)
	(gr_poly
		(pts
			(xy 84.753704 -217.80119) (xy 84.702904 -217.80119) (xy 84.601304 -217.837258) (xy 84.601304 -218.027758)
			(xy 84.702904 -218.063826) (xy 84.753704 -218.063826)
		)
		(stroke
			(width 0)
			(type solid)
		)
		(fill yes)
		(layer "F.Cu")
		(net "M_A_CPU1_SB_DQ<31>")
	)
	(gr_poly
		(pts
			(xy 84.753704 -217.20429) (xy 84.702904 -217.20429) (xy 84.601304 -217.240358) (xy 84.601304 -217.430858)
			(xy 84.702904 -217.466926) (xy 84.753704 -217.466926)
		)
		(stroke
			(width 0)
			(type solid)
		)
		(fill yes)
		(layer "F.Cu")
		(net "M_A_CPU1_SB_DQ<31>")
	)
	(gr_poly
		(pts
			(xy 84.753704 -216.60739) (xy 84.702904 -216.60739) (xy 84.601304 -216.643458) (xy 84.601304 -216.833958)
			(xy 84.702904 -216.870026) (xy 84.753704 -216.870026)
		)
		(stroke
			(width 0)
			(type solid)
		)
		(fill yes)
		(layer "F.Cu")
		(net "M_A_CPU1_SB_DQ<31>")
	)
	(gr_poly
		(pts
			(xy 84.843112 -296.54246) (xy 84.792312 -296.54246) (xy 84.690712 -296.578782) (xy 84.690712 -296.769282)
			(xy 84.792312 -296.80535) (xy 84.843112 -296.80535)
		)
		(stroke
			(width 0)
			(type solid)
		)
		(fill yes)
		(layer "F.Cu")
		(net "M_A_CPU1_SA_DQ<0>")
	)
	(gr_poly
		(pts
			(xy 84.843112 -295.94556) (xy 84.792312 -295.94556) (xy 84.690712 -295.981882) (xy 84.690712 -296.172382)
			(xy 84.792312 -296.20845) (xy 84.843112 -296.20845)
		)
		(stroke
			(width 0)
			(type solid)
		)
		(fill yes)
		(layer "F.Cu")
		(net "M_A_CPU1_SA_DQ<0>")
	)
	(gr_poly
		(pts
			(xy 84.843112 -295.34866) (xy 84.792312 -295.34866) (xy 84.690712 -295.384982) (xy 84.690712 -295.575482)
			(xy 84.792312 -295.61155) (xy 84.843112 -295.61155)
		)
		(stroke
			(width 0)
			(type solid)
		)
		(fill yes)
		(layer "F.Cu")
		(net "M_A_CPU1_SA_DQ<0>")
	)
	(gr_poly
		(pts
			(xy 84.843112 -294.75176) (xy 84.792312 -294.75176) (xy 84.690712 -294.788082) (xy 84.690712 -294.978582)
			(xy 84.792312 -295.01465) (xy 84.843112 -295.01465)
		)
		(stroke
			(width 0)
			(type solid)
		)
		(fill yes)
		(layer "F.Cu")
		(net "M_A_CPU1_SA_DQ<0>")
	)
	(gr_poly
		(pts
			(xy 84.843112 -294.15486) (xy 84.792312 -294.15486) (xy 84.690712 -294.191182) (xy 84.690712 -294.381682)
			(xy 84.792312 -294.41775) (xy 84.843112 -294.41775)
		)
		(stroke
			(width 0)
			(type solid)
		)
		(fill yes)
		(layer "F.Cu")
		(net "M_A_CPU1_SA_DQ<0>")
	)
	(gr_poly
		(pts
			(xy 84.843112 -293.55796) (xy 84.792312 -293.55796) (xy 84.690712 -293.594282) (xy 84.690712 -293.784782)
			(xy 84.792312 -293.82085) (xy 84.843112 -293.82085)
		)
		(stroke
			(width 0)
			(type solid)
		)
		(fill yes)
		(layer "F.Cu")
		(net "M_A_CPU1_SA_DQ<0>")
	)
	(gr_poly
		(pts
			(xy 84.843112 -292.96106) (xy 84.792312 -292.96106) (xy 84.690712 -292.997382) (xy 84.690712 -293.187882)
			(xy 84.792312 -293.22395) (xy 84.843112 -293.22395)
		)
		(stroke
			(width 0)
			(type solid)
		)
		(fill yes)
		(layer "F.Cu")
		(net "M_A_CPU1_SA_DQ<0>")
	)
	(gr_poly
		(pts
			(xy 84.843112 -292.36416) (xy 84.792312 -292.36416) (xy 84.690712 -292.400482) (xy 84.690712 -292.590982)
			(xy 84.792312 -292.62705) (xy 84.843112 -292.62705)
		)
		(stroke
			(width 0)
			(type solid)
		)
		(fill yes)
		(layer "F.Cu")
		(net "M_A_CPU1_SA_DQ<0>")
	)
	(gr_poly
		(pts
			(xy 84.843112 -291.76726) (xy 84.792312 -291.76726) (xy 84.690712 -291.803582) (xy 84.690712 -291.994082)
			(xy 84.792312 -292.03015) (xy 84.843112 -292.03015)
		)
		(stroke
			(width 0)
			(type solid)
		)
		(fill yes)
		(layer "F.Cu")
		(net "M_A_CPU1_SA_DQ<0>")
	)
	(gr_poly
		(pts
			(xy 84.843112 -291.17036) (xy 84.792312 -291.17036) (xy 84.690712 -291.206682) (xy 84.690712 -291.397182)
			(xy 84.792312 -291.43325) (xy 84.843112 -291.43325)
		)
		(stroke
			(width 0)
			(type solid)
		)
		(fill yes)
		(layer "F.Cu")
		(net "M_A_CPU1_SA_DQ<0>")
	)
	(gr_poly
		(pts
			(xy 84.843112 -290.57346) (xy 84.792312 -290.57346) (xy 84.690712 -290.609782) (xy 84.690712 -290.800282)
			(xy 84.792312 -290.83635) (xy 84.843112 -290.83635)
		)
		(stroke
			(width 0)
			(type solid)
		)
		(fill yes)
		(layer "F.Cu")
		(net "M_A_CPU1_SA_DQ<0>")
	)
	(gr_poly
		(pts
			(xy 84.843112 -289.97656) (xy 84.792312 -289.97656) (xy 84.690712 -290.012882) (xy 84.690712 -290.203382)
			(xy 84.792312 -290.23945) (xy 84.843112 -290.23945)
		)
		(stroke
			(width 0)
			(type solid)
		)
		(fill yes)
		(layer "F.Cu")
		(net "M_A_CPU1_SA_DQ<0>")
	)
	(gr_poly
		(pts
			(xy 84.843112 -289.37966) (xy 84.792312 -289.37966) (xy 84.690712 -289.415982) (xy 84.690712 -289.606482)
			(xy 84.792312 -289.64255) (xy 84.843112 -289.64255)
		)
		(stroke
			(width 0)
			(type solid)
		)
		(fill yes)
		(layer "F.Cu")
		(net "M_A_CPU1_SA_DQ<0>")
	)
	(gr_poly
		(pts
			(xy 84.843112 -288.78276) (xy 84.792312 -288.78276) (xy 84.690712 -288.819082) (xy 84.690712 -289.009582)
			(xy 84.792312 -289.04565) (xy 84.843112 -289.04565)
		)
		(stroke
			(width 0)
			(type solid)
		)
		(fill yes)
		(layer "F.Cu")
		(net "M_A_CPU1_SA_DQ<0>")
	)
	(gr_poly
		(pts
			(xy 84.843112 -288.18586) (xy 84.792312 -288.18586) (xy 84.690712 -288.222182) (xy 84.690712 -288.412682)
			(xy 84.792312 -288.44875) (xy 84.843112 -288.44875)
		)
		(stroke
			(width 0)
			(type solid)
		)
		(fill yes)
		(layer "F.Cu")
		(net "M_A_CPU1_SA_DQ<0>")
	)
	(gr_poly
		(pts
			(xy 84.843112 -287.58896) (xy 84.792312 -287.58896) (xy 84.690712 -287.625282) (xy 84.690712 -287.815782)
			(xy 84.792312 -287.85185) (xy 84.843112 -287.85185)
		)
		(stroke
			(width 0)
			(type solid)
		)
		(fill yes)
		(layer "F.Cu")
		(net "M_A_CPU1_SA_DQ<0>")
	)
	(gr_poly
		(pts
			(xy 84.843112 -286.99206) (xy 84.792312 -286.99206) (xy 84.690712 -287.028382) (xy 84.690712 -287.218882)
			(xy 84.792312 -287.25495) (xy 84.843112 -287.25495)
		)
		(stroke
			(width 0)
			(type solid)
		)
		(fill yes)
		(layer "F.Cu")
		(net "M_A_CPU1_SA_DQ<0>")
	)
	(gr_poly
		(pts
			(xy 84.843112 -286.39516) (xy 84.792312 -286.39516) (xy 84.690712 -286.431482) (xy 84.690712 -286.621982)
			(xy 84.792312 -286.65805) (xy 84.843112 -286.65805)
		)
		(stroke
			(width 0)
			(type solid)
		)
		(fill yes)
		(layer "F.Cu")
		(net "M_A_CPU1_SA_DQ<0>")
	)
	(gr_poly
		(pts
			(xy 84.843112 -285.79826) (xy 84.792312 -285.79826) (xy 84.690712 -285.834582) (xy 84.690712 -286.025082)
			(xy 84.792312 -286.06115) (xy 84.843112 -286.06115)
		)
		(stroke
			(width 0)
			(type solid)
		)
		(fill yes)
		(layer "F.Cu")
		(net "M_A_CPU1_SA_DQ<0>")
	)
	(gr_poly
		(pts
			(xy 84.843112 -285.20136) (xy 84.792312 -285.20136) (xy 84.690712 -285.237682) (xy 84.690712 -285.428182)
			(xy 84.792312 -285.46425) (xy 84.843112 -285.46425)
		)
		(stroke
			(width 0)
			(type solid)
		)
		(fill yes)
		(layer "F.Cu")
		(net "M_A_CPU1_SA_DQ<0>")
	)
	(gr_poly
		(pts
			(xy 84.843112 -284.60446) (xy 84.792312 -284.60446) (xy 84.690712 -284.640782) (xy 84.690712 -284.831282)
			(xy 84.792312 -284.86735) (xy 84.843112 -284.86735)
		)
		(stroke
			(width 0)
			(type solid)
		)
		(fill yes)
		(layer "F.Cu")
		(net "M_A_CPU1_SA_DQ<0>")
	)
	(gr_poly
		(pts
			(xy 84.843112 -284.00756) (xy 84.792312 -284.00756) (xy 84.690712 -284.043882) (xy 84.690712 -284.234382)
			(xy 84.792312 -284.27045) (xy 84.843112 -284.27045)
		)
		(stroke
			(width 0)
			(type solid)
		)
		(fill yes)
		(layer "F.Cu")
		(net "M_A_CPU1_SA_DQ<0>")
	)
	(gr_poly
		(pts
			(xy 84.843112 -283.41066) (xy 84.792312 -283.41066) (xy 84.690712 -283.446982) (xy 84.690712 -283.637482)
			(xy 84.792312 -283.67355) (xy 84.843112 -283.67355)
		)
		(stroke
			(width 0)
			(type solid)
		)
		(fill yes)
		(layer "F.Cu")
		(net "M_A_CPU1_SA_DQ<0>")
	)
	(gr_poly
		(pts
			(xy 84.843112 -282.81376) (xy 84.792312 -282.81376) (xy 84.690712 -282.850082) (xy 84.690712 -283.040582)
			(xy 84.792312 -283.07665) (xy 84.843112 -283.07665)
		)
		(stroke
			(width 0)
			(type solid)
		)
		(fill yes)
		(layer "F.Cu")
		(net "M_A_CPU1_SA_DQ<0>")
	)
	(gr_poly
		(pts
			(xy 84.845398 -281.771852) (xy 84.88299 -281.585162) (xy 84.790534 -281.52979) (xy 84.740496 -281.51963)
			(xy 84.688934 -281.77744) (xy 84.738718 -281.787346)
		)
		(stroke
			(width 0)
			(type solid)
		)
		(fill yes)
		(layer "F.Cu")
		(net "M_A_CPU1_SA_DQ<2>")
	)
	(gr_poly
		(pts
			(xy 84.906104 -217.729308) (xy 84.906104 -217.538808) (xy 84.804504 -217.502486) (xy 84.753704 -217.502486)
			(xy 84.753704 -217.76563) (xy 84.804504 -217.76563)
		)
		(stroke
			(width 0)
			(type solid)
		)
		(fill yes)
		(layer "F.Cu")
		(net "M_A_CPU1_SB_DQ<31>")
	)
	(gr_poly
		(pts
			(xy 84.906104 -217.132408) (xy 84.906104 -216.941908) (xy 84.804504 -216.905586) (xy 84.753704 -216.905586)
			(xy 84.753704 -217.16873) (xy 84.804504 -217.16873)
		)
		(stroke
			(width 0)
			(type solid)
		)
		(fill yes)
		(layer "F.Cu")
		(net "M_A_CPU1_SB_DQ<31>")
	)
	(gr_poly
		(pts
			(xy 84.987638 -281.873452) (xy 84.937854 -281.863546) (xy 84.83092 -281.87904) (xy 84.793582 -282.06573)
			(xy 84.886038 -282.121356) (xy 84.935822 -282.131262)
		)
		(stroke
			(width 0)
			(type solid)
		)
		(fill yes)
		(layer "F.Cu")
		(net "M_A_CPU1_SA_DQ<0>")
	)
	(gr_poly
		(pts
			(xy 84.995512 -296.470832) (xy 84.995512 -296.280332) (xy 84.893912 -296.24401) (xy 84.843112 -296.24401)
			(xy 84.843112 -296.5069) (xy 84.893912 -296.5069)
		)
		(stroke
			(width 0)
			(type solid)
		)
		(fill yes)
		(layer "F.Cu")
		(net "M_A_CPU1_SA_DQ<0>")
	)
	(gr_poly
		(pts
			(xy 84.995512 -295.873932) (xy 84.995512 -295.683432) (xy 84.893912 -295.64711) (xy 84.843112 -295.64711)
			(xy 84.843112 -295.91) (xy 84.893912 -295.91)
		)
		(stroke
			(width 0)
			(type solid)
		)
		(fill yes)
		(layer "F.Cu")
		(net "M_A_CPU1_SA_DQ<0>")
	)
	(gr_poly
		(pts
			(xy 84.995512 -295.277032) (xy 84.995512 -295.086532) (xy 84.893912 -295.05021) (xy 84.843112 -295.05021)
			(xy 84.843112 -295.3131) (xy 84.893912 -295.3131)
		)
		(stroke
			(width 0)
			(type solid)
		)
		(fill yes)
		(layer "F.Cu")
		(net "M_A_CPU1_SA_DQ<0>")
	)
	(gr_poly
		(pts
			(xy 84.995512 -294.680132) (xy 84.995512 -294.489632) (xy 84.893912 -294.45331) (xy 84.843112 -294.45331)
			(xy 84.843112 -294.7162) (xy 84.893912 -294.7162)
		)
		(stroke
			(width 0)
			(type solid)
		)
		(fill yes)
		(layer "F.Cu")
		(net "M_A_CPU1_SA_DQ<0>")
	)
	(gr_poly
		(pts
			(xy 84.995512 -294.083232) (xy 84.995512 -293.892732) (xy 84.893912 -293.85641) (xy 84.843112 -293.85641)
			(xy 84.843112 -294.1193) (xy 84.893912 -294.1193)
		)
		(stroke
			(width 0)
			(type solid)
		)
		(fill yes)
		(layer "F.Cu")
		(net "M_A_CPU1_SA_DQ<0>")
	)
	(gr_poly
		(pts
			(xy 84.995512 -293.486332) (xy 84.995512 -293.295832) (xy 84.893912 -293.25951) (xy 84.843112 -293.25951)
			(xy 84.843112 -293.5224) (xy 84.893912 -293.5224)
		)
		(stroke
			(width 0)
			(type solid)
		)
		(fill yes)
		(layer "F.Cu")
		(net "M_A_CPU1_SA_DQ<0>")
	)
	(gr_poly
		(pts
			(xy 84.995512 -292.889432) (xy 84.995512 -292.698932) (xy 84.893912 -292.66261) (xy 84.843112 -292.66261)
			(xy 84.843112 -292.9255) (xy 84.893912 -292.9255)
		)
		(stroke
			(width 0)
			(type solid)
		)
		(fill yes)
		(layer "F.Cu")
		(net "M_A_CPU1_SA_DQ<0>")
	)
	(gr_poly
		(pts
			(xy 84.995512 -292.292532) (xy 84.995512 -292.102032) (xy 84.893912 -292.06571) (xy 84.843112 -292.06571)
			(xy 84.843112 -292.3286) (xy 84.893912 -292.3286)
		)
		(stroke
			(width 0)
			(type solid)
		)
		(fill yes)
		(layer "F.Cu")
		(net "M_A_CPU1_SA_DQ<0>")
	)
	(gr_poly
		(pts
			(xy 84.995512 -291.695632) (xy 84.995512 -291.505132) (xy 84.893912 -291.46881) (xy 84.843112 -291.46881)
			(xy 84.843112 -291.7317) (xy 84.893912 -291.7317)
		)
		(stroke
			(width 0)
			(type solid)
		)
		(fill yes)
		(layer "F.Cu")
		(net "M_A_CPU1_SA_DQ<0>")
	)
	(gr_poly
		(pts
			(xy 84.995512 -291.098732) (xy 84.995512 -290.908232) (xy 84.893912 -290.87191) (xy 84.843112 -290.87191)
			(xy 84.843112 -291.1348) (xy 84.893912 -291.1348)
		)
		(stroke
			(width 0)
			(type solid)
		)
		(fill yes)
		(layer "F.Cu")
		(net "M_A_CPU1_SA_DQ<0>")
	)
	(gr_poly
		(pts
			(xy 84.995512 -290.501832) (xy 84.995512 -290.311332) (xy 84.893912 -290.27501) (xy 84.843112 -290.27501)
			(xy 84.843112 -290.5379) (xy 84.893912 -290.5379)
		)
		(stroke
			(width 0)
			(type solid)
		)
		(fill yes)
		(layer "F.Cu")
		(net "M_A_CPU1_SA_DQ<0>")
	)
	(gr_poly
		(pts
			(xy 84.995512 -289.904932) (xy 84.995512 -289.714432) (xy 84.893912 -289.67811) (xy 84.843112 -289.67811)
			(xy 84.843112 -289.941) (xy 84.893912 -289.941)
		)
		(stroke
			(width 0)
			(type solid)
		)
		(fill yes)
		(layer "F.Cu")
		(net "M_A_CPU1_SA_DQ<0>")
	)
	(gr_poly
		(pts
			(xy 84.995512 -289.308032) (xy 84.995512 -289.117532) (xy 84.893912 -289.08121) (xy 84.843112 -289.08121)
			(xy 84.843112 -289.3441) (xy 84.893912 -289.3441)
		)
		(stroke
			(width 0)
			(type solid)
		)
		(fill yes)
		(layer "F.Cu")
		(net "M_A_CPU1_SA_DQ<0>")
	)
	(gr_poly
		(pts
			(xy 84.995512 -288.711132) (xy 84.995512 -288.520632) (xy 84.893912 -288.48431) (xy 84.843112 -288.48431)
			(xy 84.843112 -288.7472) (xy 84.893912 -288.7472)
		)
		(stroke
			(width 0)
			(type solid)
		)
		(fill yes)
		(layer "F.Cu")
		(net "M_A_CPU1_SA_DQ<0>")
	)
	(gr_poly
		(pts
			(xy 84.995512 -288.114232) (xy 84.995512 -287.923732) (xy 84.893912 -287.88741) (xy 84.843112 -287.88741)
			(xy 84.843112 -288.1503) (xy 84.893912 -288.1503)
		)
		(stroke
			(width 0)
			(type solid)
		)
		(fill yes)
		(layer "F.Cu")
		(net "M_A_CPU1_SA_DQ<0>")
	)
	(gr_poly
		(pts
			(xy 84.995512 -287.517332) (xy 84.995512 -287.326832) (xy 84.893912 -287.29051) (xy 84.843112 -287.29051)
			(xy 84.843112 -287.5534) (xy 84.893912 -287.5534)
		)
		(stroke
			(width 0)
			(type solid)
		)
		(fill yes)
		(layer "F.Cu")
		(net "M_A_CPU1_SA_DQ<0>")
	)
	(gr_poly
		(pts
			(xy 84.995512 -286.920432) (xy 84.995512 -286.729932) (xy 84.893912 -286.69361) (xy 84.843112 -286.69361)
			(xy 84.843112 -286.9565) (xy 84.893912 -286.9565)
		)
		(stroke
			(width 0)
			(type solid)
		)
		(fill yes)
		(layer "F.Cu")
		(net "M_A_CPU1_SA_DQ<0>")
	)
	(gr_poly
		(pts
			(xy 84.995512 -286.323532) (xy 84.995512 -286.133032) (xy 84.893912 -286.09671) (xy 84.843112 -286.09671)
			(xy 84.843112 -286.3596) (xy 84.893912 -286.3596)
		)
		(stroke
			(width 0)
			(type solid)
		)
		(fill yes)
		(layer "F.Cu")
		(net "M_A_CPU1_SA_DQ<0>")
	)
	(gr_poly
		(pts
			(xy 84.995512 -285.726632) (xy 84.995512 -285.536132) (xy 84.893912 -285.49981) (xy 84.843112 -285.49981)
			(xy 84.843112 -285.7627) (xy 84.893912 -285.7627)
		)
		(stroke
			(width 0)
			(type solid)
		)
		(fill yes)
		(layer "F.Cu")
		(net "M_A_CPU1_SA_DQ<0>")
	)
	(gr_poly
		(pts
			(xy 84.995512 -285.129732) (xy 84.995512 -284.939232) (xy 84.893912 -284.90291) (xy 84.843112 -284.90291)
			(xy 84.843112 -285.1658) (xy 84.893912 -285.1658)
		)
		(stroke
			(width 0)
			(type solid)
		)
		(fill yes)
		(layer "F.Cu")
		(net "M_A_CPU1_SA_DQ<0>")
	)
	(gr_poly
		(pts
			(xy 84.995512 -284.532832) (xy 84.995512 -284.342332) (xy 84.893912 -284.30601) (xy 84.843112 -284.30601)
			(xy 84.843112 -284.5689) (xy 84.893912 -284.5689)
		)
		(stroke
			(width 0)
			(type solid)
		)
		(fill yes)
		(layer "F.Cu")
		(net "M_A_CPU1_SA_DQ<0>")
	)
	(gr_poly
		(pts
			(xy 84.995512 -283.935932) (xy 84.995512 -283.745432) (xy 84.893912 -283.70911) (xy 84.843112 -283.70911)
			(xy 84.843112 -283.972) (xy 84.893912 -283.972)
		)
		(stroke
			(width 0)
			(type solid)
		)
		(fill yes)
		(layer "F.Cu")
		(net "M_A_CPU1_SA_DQ<0>")
	)
	(gr_poly
		(pts
			(xy 84.995512 -283.339032) (xy 84.995512 -283.148532) (xy 84.893912 -283.11221) (xy 84.843112 -283.11221)
			(xy 84.843112 -283.3751) (xy 84.893912 -283.3751)
		)
		(stroke
			(width 0)
			(type solid)
		)
		(fill yes)
		(layer "F.Cu")
		(net "M_A_CPU1_SA_DQ<0>")
	)
	(gr_poly
		(pts
			(xy 85.033612 -282.418282) (xy 85.071204 -282.231592) (xy 84.978748 -282.175966) (xy 84.92871 -282.16606)
			(xy 84.877148 -282.42387) (xy 84.926932 -282.433776)
		)
		(stroke
			(width 0)
			(type solid)
		)
		(fill yes)
		(layer "F.Cu")
		(net "M_A_CPU1_SA_DQ<0>")
	)
	(gr_poly
		(pts
			(xy 85.151214 -281.833066) (xy 85.188552 -281.646376) (xy 85.096096 -281.59075) (xy 85.046312 -281.580844)
			(xy 84.99475 -281.838654) (xy 85.044534 -281.84856)
		)
		(stroke
			(width 0)
			(type solid)
		)
		(fill yes)
		(layer "F.Cu")
		(net "M_A_CPU1_SA_DQ<0>")
	)
	(gr_poly
		(pts
			(xy 139.126976 -295.413176) (xy 139.076176 -295.413176) (xy 138.974576 -295.449498) (xy 138.974576 -295.639998)
			(xy 139.076176 -295.676066) (xy 139.126976 -295.676066)
		)
		(stroke
			(width 0)
			(type solid)
		)
		(fill yes)
		(layer "F.Cu")
		(net "M_E_CPU1_SA_DQ<0>")
	)
	(gr_poly
		(pts
			(xy 139.126976 -294.816276) (xy 139.076176 -294.816276) (xy 138.974576 -294.852598) (xy 138.974576 -295.043098)
			(xy 139.076176 -295.079166) (xy 139.126976 -295.079166)
		)
		(stroke
			(width 0)
			(type solid)
		)
		(fill yes)
		(layer "F.Cu")
		(net "M_E_CPU1_SA_DQ<0>")
	)
	(gr_poly
		(pts
			(xy 139.126976 -294.219376) (xy 139.076176 -294.219376) (xy 138.974576 -294.255698) (xy 138.974576 -294.446198)
			(xy 139.076176 -294.482266) (xy 139.126976 -294.482266)
		)
		(stroke
			(width 0)
			(type solid)
		)
		(fill yes)
		(layer "F.Cu")
		(net "M_E_CPU1_SA_DQ<0>")
	)
	(gr_poly
		(pts
			(xy 139.126976 -293.622476) (xy 139.076176 -293.622476) (xy 138.974576 -293.658798) (xy 138.974576 -293.849298)
			(xy 139.076176 -293.885366) (xy 139.126976 -293.885366)
		)
		(stroke
			(width 0)
			(type solid)
		)
		(fill yes)
		(layer "F.Cu")
		(net "M_E_CPU1_SA_DQ<0>")
	)
	(gr_poly
		(pts
			(xy 139.126976 -293.025576) (xy 139.076176 -293.025576) (xy 138.974576 -293.061898) (xy 138.974576 -293.252398)
			(xy 139.076176 -293.288466) (xy 139.126976 -293.288466)
		)
		(stroke
			(width 0)
			(type solid)
		)
		(fill yes)
		(layer "F.Cu")
		(net "M_E_CPU1_SA_DQ<0>")
	)
	(gr_poly
		(pts
			(xy 139.126976 -292.428676) (xy 139.076176 -292.428676) (xy 138.974576 -292.464998) (xy 138.974576 -292.655498)
			(xy 139.076176 -292.691566) (xy 139.126976 -292.691566)
		)
		(stroke
			(width 0)
			(type solid)
		)
		(fill yes)
		(layer "F.Cu")
		(net "M_E_CPU1_SA_DQ<0>")
	)
	(gr_poly
		(pts
			(xy 139.126976 -291.831776) (xy 139.076176 -291.831776) (xy 138.974576 -291.868098) (xy 138.974576 -292.058598)
			(xy 139.076176 -292.094666) (xy 139.126976 -292.094666)
		)
		(stroke
			(width 0)
			(type solid)
		)
		(fill yes)
		(layer "F.Cu")
		(net "M_E_CPU1_SA_DQ<0>")
	)
	(gr_poly
		(pts
			(xy 139.126976 -291.234876) (xy 139.076176 -291.234876) (xy 138.974576 -291.271198) (xy 138.974576 -291.461698)
			(xy 139.076176 -291.497766) (xy 139.126976 -291.497766)
		)
		(stroke
			(width 0)
			(type solid)
		)
		(fill yes)
		(layer "F.Cu")
		(net "M_E_CPU1_SA_DQ<0>")
	)
	(gr_poly
		(pts
			(xy 139.126976 -290.637976) (xy 139.076176 -290.637976) (xy 138.974576 -290.674298) (xy 138.974576 -290.864798)
			(xy 139.076176 -290.900866) (xy 139.126976 -290.900866)
		)
		(stroke
			(width 0)
			(type solid)
		)
		(fill yes)
		(layer "F.Cu")
		(net "M_E_CPU1_SA_DQ<0>")
	)
	(gr_poly
		(pts
			(xy 139.126976 -290.041076) (xy 139.076176 -290.041076) (xy 138.974576 -290.077398) (xy 138.974576 -290.267898)
			(xy 139.076176 -290.303966) (xy 139.126976 -290.303966)
		)
		(stroke
			(width 0)
			(type solid)
		)
		(fill yes)
		(layer "F.Cu")
		(net "M_E_CPU1_SA_DQ<0>")
	)
	(gr_poly
		(pts
			(xy 139.126976 -289.444176) (xy 139.076176 -289.444176) (xy 138.974576 -289.480498) (xy 138.974576 -289.670998)
			(xy 139.076176 -289.707066) (xy 139.126976 -289.707066)
		)
		(stroke
			(width 0)
			(type solid)
		)
		(fill yes)
		(layer "F.Cu")
		(net "M_E_CPU1_SA_DQ<0>")
	)
	(gr_poly
		(pts
			(xy 139.126976 -288.847276) (xy 139.076176 -288.847276) (xy 138.974576 -288.883598) (xy 138.974576 -289.074098)
			(xy 139.076176 -289.110166) (xy 139.126976 -289.110166)
		)
		(stroke
			(width 0)
			(type solid)
		)
		(fill yes)
		(layer "F.Cu")
		(net "M_E_CPU1_SA_DQ<0>")
	)
	(gr_poly
		(pts
			(xy 139.126976 -288.250376) (xy 139.076176 -288.250376) (xy 138.974576 -288.286698) (xy 138.974576 -288.477198)
			(xy 139.076176 -288.513266) (xy 139.126976 -288.513266)
		)
		(stroke
			(width 0)
			(type solid)
		)
		(fill yes)
		(layer "F.Cu")
		(net "M_E_CPU1_SA_DQ<0>")
	)
	(gr_poly
		(pts
			(xy 139.126976 -287.653476) (xy 139.076176 -287.653476) (xy 138.974576 -287.689798) (xy 138.974576 -287.880298)
			(xy 139.076176 -287.916366) (xy 139.126976 -287.916366)
		)
		(stroke
			(width 0)
			(type solid)
		)
		(fill yes)
		(layer "F.Cu")
		(net "M_E_CPU1_SA_DQ<0>")
	)
	(gr_poly
		(pts
			(xy 139.126976 -287.056576) (xy 139.076176 -287.056576) (xy 138.974576 -287.092898) (xy 138.974576 -287.283398)
			(xy 139.076176 -287.319466) (xy 139.126976 -287.319466)
		)
		(stroke
			(width 0)
			(type solid)
		)
		(fill yes)
		(layer "F.Cu")
		(net "M_E_CPU1_SA_DQ<0>")
	)
	(gr_poly
		(pts
			(xy 139.126976 -286.459676) (xy 139.076176 -286.459676) (xy 138.974576 -286.495998) (xy 138.974576 -286.686498)
			(xy 139.076176 -286.722566) (xy 139.126976 -286.722566)
		)
		(stroke
			(width 0)
			(type solid)
		)
		(fill yes)
		(layer "F.Cu")
		(net "M_E_CPU1_SA_DQ<0>")
	)
	(gr_poly
		(pts
			(xy 139.126976 -285.862776) (xy 139.076176 -285.862776) (xy 138.974576 -285.899098) (xy 138.974576 -286.089598)
			(xy 139.076176 -286.125666) (xy 139.126976 -286.125666)
		)
		(stroke
			(width 0)
			(type solid)
		)
		(fill yes)
		(layer "F.Cu")
		(net "M_E_CPU1_SA_DQ<0>")
	)
	(gr_poly
		(pts
			(xy 139.126976 -285.265876) (xy 139.076176 -285.265876) (xy 138.974576 -285.302198) (xy 138.974576 -285.492698)
			(xy 139.076176 -285.528766) (xy 139.126976 -285.528766)
		)
		(stroke
			(width 0)
			(type solid)
		)
		(fill yes)
		(layer "F.Cu")
		(net "M_E_CPU1_SA_DQ<0>")
	)
	(gr_poly
		(pts
			(xy 139.126976 -284.668976) (xy 139.076176 -284.668976) (xy 138.974576 -284.705298) (xy 138.974576 -284.895798)
			(xy 139.076176 -284.931866) (xy 139.126976 -284.931866)
		)
		(stroke
			(width 0)
			(type solid)
		)
		(fill yes)
		(layer "F.Cu")
		(net "M_E_CPU1_SA_DQ<0>")
	)
	(gr_poly
		(pts
			(xy 139.126976 -284.072076) (xy 139.076176 -284.072076) (xy 138.974576 -284.108398) (xy 138.974576 -284.298898)
			(xy 139.076176 -284.334966) (xy 139.126976 -284.334966)
		)
		(stroke
			(width 0)
			(type solid)
		)
		(fill yes)
		(layer "F.Cu")
		(net "M_E_CPU1_SA_DQ<0>")
	)
	(gr_poly
		(pts
			(xy 139.126976 -283.475176) (xy 139.076176 -283.475176) (xy 138.974576 -283.511498) (xy 138.974576 -283.701998)
			(xy 139.076176 -283.738066) (xy 139.126976 -283.738066)
		)
		(stroke
			(width 0)
			(type solid)
		)
		(fill yes)
		(layer "F.Cu")
		(net "M_E_CPU1_SA_DQ<0>")
	)
	(gr_poly
		(pts
			(xy 139.126976 -282.878276) (xy 139.076176 -282.878276) (xy 138.974576 -282.914598) (xy 138.974576 -283.105098)
			(xy 139.076176 -283.141166) (xy 139.126976 -283.141166)
		)
		(stroke
			(width 0)
			(type solid)
		)
		(fill yes)
		(layer "F.Cu")
		(net "M_E_CPU1_SA_DQ<0>")
	)
	(gr_poly
		(pts
			(xy 139.126976 -282.281376) (xy 139.076176 -282.281376) (xy 138.974576 -282.317698) (xy 138.974576 -282.508198)
			(xy 139.076176 -282.544266) (xy 139.126976 -282.544266)
		)
		(stroke
			(width 0)
			(type solid)
		)
		(fill yes)
		(layer "F.Cu")
		(net "M_E_CPU1_SA_DQ<0>")
	)
	(gr_poly
		(pts
			(xy 139.126976 -281.684476) (xy 139.076176 -281.684476) (xy 138.974576 -281.720798) (xy 138.974576 -281.911298)
			(xy 139.076176 -281.947366) (xy 139.126976 -281.947366)
		)
		(stroke
			(width 0)
			(type solid)
		)
		(fill yes)
		(layer "F.Cu")
		(net "M_E_CPU1_SA_DQ<0>")
	)
	(gr_poly
		(pts
			(xy 139.279376 -295.341294) (xy 139.279376 -295.150794) (xy 139.177776 -295.114726) (xy 139.126976 -295.114726)
			(xy 139.126976 -295.377616) (xy 139.177776 -295.377616)
		)
		(stroke
			(width 0)
			(type solid)
		)
		(fill yes)
		(layer "F.Cu")
		(net "M_E_CPU1_SA_DQ<0>")
	)
	(gr_poly
		(pts
			(xy 139.279376 -294.744394) (xy 139.279376 -294.553894) (xy 139.177776 -294.517826) (xy 139.126976 -294.517826)
			(xy 139.126976 -294.780716) (xy 139.177776 -294.780716)
		)
		(stroke
			(width 0)
			(type solid)
		)
		(fill yes)
		(layer "F.Cu")
		(net "M_E_CPU1_SA_DQ<0>")
	)
	(gr_poly
		(pts
			(xy 139.279376 -294.147494) (xy 139.279376 -293.956994) (xy 139.177776 -293.920926) (xy 139.126976 -293.920926)
			(xy 139.126976 -294.183816) (xy 139.177776 -294.183816)
		)
		(stroke
			(width 0)
			(type solid)
		)
		(fill yes)
		(layer "F.Cu")
		(net "M_E_CPU1_SA_DQ<0>")
	)
	(gr_poly
		(pts
			(xy 139.279376 -293.550594) (xy 139.279376 -293.360094) (xy 139.177776 -293.324026) (xy 139.126976 -293.324026)
			(xy 139.126976 -293.586916) (xy 139.177776 -293.586916)
		)
		(stroke
			(width 0)
			(type solid)
		)
		(fill yes)
		(layer "F.Cu")
		(net "M_E_CPU1_SA_DQ<0>")
	)
	(gr_poly
		(pts
			(xy 139.279376 -292.953694) (xy 139.279376 -292.763194) (xy 139.177776 -292.727126) (xy 139.126976 -292.727126)
			(xy 139.126976 -292.990016) (xy 139.177776 -292.990016)
		)
		(stroke
			(width 0)
			(type solid)
		)
		(fill yes)
		(layer "F.Cu")
		(net "M_E_CPU1_SA_DQ<0>")
	)
	(gr_poly
		(pts
			(xy 139.279376 -292.356794) (xy 139.279376 -292.166294) (xy 139.177776 -292.130226) (xy 139.126976 -292.130226)
			(xy 139.126976 -292.393116) (xy 139.177776 -292.393116)
		)
		(stroke
			(width 0)
			(type solid)
		)
		(fill yes)
		(layer "F.Cu")
		(net "M_E_CPU1_SA_DQ<0>")
	)
	(gr_poly
		(pts
			(xy 139.279376 -291.759894) (xy 139.279376 -291.569394) (xy 139.177776 -291.533326) (xy 139.126976 -291.533326)
			(xy 139.126976 -291.796216) (xy 139.177776 -291.796216)
		)
		(stroke
			(width 0)
			(type solid)
		)
		(fill yes)
		(layer "F.Cu")
		(net "M_E_CPU1_SA_DQ<0>")
	)
	(gr_poly
		(pts
			(xy 139.279376 -291.162994) (xy 139.279376 -290.972494) (xy 139.177776 -290.936426) (xy 139.126976 -290.936426)
			(xy 139.126976 -291.199316) (xy 139.177776 -291.199316)
		)
		(stroke
			(width 0)
			(type solid)
		)
		(fill yes)
		(layer "F.Cu")
		(net "M_E_CPU1_SA_DQ<0>")
	)
	(gr_poly
		(pts
			(xy 139.279376 -290.566094) (xy 139.279376 -290.375594) (xy 139.177776 -290.339526) (xy 139.126976 -290.339526)
			(xy 139.126976 -290.602416) (xy 139.177776 -290.602416)
		)
		(stroke
			(width 0)
			(type solid)
		)
		(fill yes)
		(layer "F.Cu")
		(net "M_E_CPU1_SA_DQ<0>")
	)
	(gr_poly
		(pts
			(xy 139.279376 -289.969194) (xy 139.279376 -289.778694) (xy 139.177776 -289.742626) (xy 139.126976 -289.742626)
			(xy 139.126976 -290.005516) (xy 139.177776 -290.005516)
		)
		(stroke
			(width 0)
			(type solid)
		)
		(fill yes)
		(layer "F.Cu")
		(net "M_E_CPU1_SA_DQ<0>")
	)
	(gr_poly
		(pts
			(xy 139.279376 -289.372294) (xy 139.279376 -289.181794) (xy 139.177776 -289.145726) (xy 139.126976 -289.145726)
			(xy 139.126976 -289.408616) (xy 139.177776 -289.408616)
		)
		(stroke
			(width 0)
			(type solid)
		)
		(fill yes)
		(layer "F.Cu")
		(net "M_E_CPU1_SA_DQ<0>")
	)
	(gr_poly
		(pts
			(xy 139.279376 -288.775394) (xy 139.279376 -288.584894) (xy 139.177776 -288.548826) (xy 139.126976 -288.548826)
			(xy 139.126976 -288.811716) (xy 139.177776 -288.811716)
		)
		(stroke
			(width 0)
			(type solid)
		)
		(fill yes)
		(layer "F.Cu")
		(net "M_E_CPU1_SA_DQ<0>")
	)
	(gr_poly
		(pts
			(xy 139.279376 -288.178494) (xy 139.279376 -287.987994) (xy 139.177776 -287.951926) (xy 139.126976 -287.951926)
			(xy 139.126976 -288.214816) (xy 139.177776 -288.214816)
		)
		(stroke
			(width 0)
			(type solid)
		)
		(fill yes)
		(layer "F.Cu")
		(net "M_E_CPU1_SA_DQ<0>")
	)
	(gr_poly
		(pts
			(xy 139.279376 -287.581594) (xy 139.279376 -287.391094) (xy 139.177776 -287.355026) (xy 139.126976 -287.355026)
			(xy 139.126976 -287.617916) (xy 139.177776 -287.617916)
		)
		(stroke
			(width 0)
			(type solid)
		)
		(fill yes)
		(layer "F.Cu")
		(net "M_E_CPU1_SA_DQ<0>")
	)
	(gr_poly
		(pts
			(xy 139.279376 -286.984694) (xy 139.279376 -286.794194) (xy 139.177776 -286.758126) (xy 139.126976 -286.758126)
			(xy 139.126976 -287.021016) (xy 139.177776 -287.021016)
		)
		(stroke
			(width 0)
			(type solid)
		)
		(fill yes)
		(layer "F.Cu")
		(net "M_E_CPU1_SA_DQ<0>")
	)
	(gr_poly
		(pts
			(xy 139.279376 -286.387794) (xy 139.279376 -286.197294) (xy 139.177776 -286.161226) (xy 139.126976 -286.161226)
			(xy 139.126976 -286.424116) (xy 139.177776 -286.424116)
		)
		(stroke
			(width 0)
			(type solid)
		)
		(fill yes)
		(layer "F.Cu")
		(net "M_E_CPU1_SA_DQ<0>")
	)
	(gr_poly
		(pts
			(xy 139.279376 -285.790894) (xy 139.279376 -285.600394) (xy 139.177776 -285.564326) (xy 139.126976 -285.564326)
			(xy 139.126976 -285.827216) (xy 139.177776 -285.827216)
		)
		(stroke
			(width 0)
			(type solid)
		)
		(fill yes)
		(layer "F.Cu")
		(net "M_E_CPU1_SA_DQ<0>")
	)
	(gr_poly
		(pts
			(xy 139.279376 -285.193994) (xy 139.279376 -285.003494) (xy 139.177776 -284.967426) (xy 139.126976 -284.967426)
			(xy 139.126976 -285.230316) (xy 139.177776 -285.230316)
		)
		(stroke
			(width 0)
			(type solid)
		)
		(fill yes)
		(layer "F.Cu")
		(net "M_E_CPU1_SA_DQ<0>")
	)
	(gr_poly
		(pts
			(xy 139.279376 -284.597094) (xy 139.279376 -284.406594) (xy 139.177776 -284.370526) (xy 139.126976 -284.370526)
			(xy 139.126976 -284.633416) (xy 139.177776 -284.633416)
		)
		(stroke
			(width 0)
			(type solid)
		)
		(fill yes)
		(layer "F.Cu")
		(net "M_E_CPU1_SA_DQ<0>")
	)
	(gr_poly
		(pts
			(xy 139.279376 -284.000194) (xy 139.279376 -283.809694) (xy 139.177776 -283.773626) (xy 139.126976 -283.773626)
			(xy 139.126976 -284.036516) (xy 139.177776 -284.036516)
		)
		(stroke
			(width 0)
			(type solid)
		)
		(fill yes)
		(layer "F.Cu")
		(net "M_E_CPU1_SA_DQ<0>")
	)
	(gr_poly
		(pts
			(xy 139.279376 -283.403294) (xy 139.279376 -283.212794) (xy 139.177776 -283.176726) (xy 139.126976 -283.176726)
			(xy 139.126976 -283.439616) (xy 139.177776 -283.439616)
		)
		(stroke
			(width 0)
			(type solid)
		)
		(fill yes)
		(layer "F.Cu")
		(net "M_E_CPU1_SA_DQ<0>")
	)
	(gr_poly
		(pts
			(xy 139.279376 -282.806394) (xy 139.279376 -282.615894) (xy 139.177776 -282.579826) (xy 139.126976 -282.579826)
			(xy 139.126976 -282.842716) (xy 139.177776 -282.842716)
		)
		(stroke
			(width 0)
			(type solid)
		)
		(fill yes)
		(layer "F.Cu")
		(net "M_E_CPU1_SA_DQ<0>")
	)
	(gr_poly
		(pts
			(xy 139.279376 -282.209494) (xy 139.279376 -282.018994) (xy 139.177776 -281.982926) (xy 139.126976 -281.982926)
			(xy 139.126976 -282.245816) (xy 139.177776 -282.245816)
		)
		(stroke
			(width 0)
			(type solid)
		)
		(fill yes)
		(layer "F.Cu")
		(net "M_E_CPU1_SA_DQ<0>")
	)
	(gr_poly
		(pts
			(xy 139.279376 -281.612594) (xy 139.279376 -281.422094) (xy 139.177776 -281.386026) (xy 139.126976 -281.386026)
			(xy 139.126976 -281.648916) (xy 139.177776 -281.648916)
		)
		(stroke
			(width 0)
			(type solid)
		)
		(fill yes)
		(layer "F.Cu")
		(net "M_E_CPU1_SA_DQ<0>")
	)
	(gr_poly
		(pts
			(xy 139.431776 -294.816276) (xy 139.380976 -294.816276) (xy 139.279376 -294.852598) (xy 139.279376 -295.043098)
			(xy 139.380976 -295.079166) (xy 139.431776 -295.079166)
		)
		(stroke
			(width 0)
			(type solid)
		)
		(fill yes)
		(layer "F.Cu")
		(net "M_E_CPU1_SA_DQ<2>")
	)
	(gr_poly
		(pts
			(xy 139.431776 -294.219376) (xy 139.380976 -294.219376) (xy 139.279376 -294.255698) (xy 139.279376 -294.446198)
			(xy 139.380976 -294.482266) (xy 139.431776 -294.482266)
		)
		(stroke
			(width 0)
			(type solid)
		)
		(fill yes)
		(layer "F.Cu")
		(net "M_E_CPU1_SA_DQ<2>")
	)
	(gr_poly
		(pts
			(xy 139.431776 -293.622476) (xy 139.380976 -293.622476) (xy 139.279376 -293.658798) (xy 139.279376 -293.849298)
			(xy 139.380976 -293.885366) (xy 139.431776 -293.885366)
		)
		(stroke
			(width 0)
			(type solid)
		)
		(fill yes)
		(layer "F.Cu")
		(net "M_E_CPU1_SA_DQ<2>")
	)
	(gr_poly
		(pts
			(xy 139.431776 -293.025576) (xy 139.380976 -293.025576) (xy 139.279376 -293.061898) (xy 139.279376 -293.252398)
			(xy 139.380976 -293.288466) (xy 139.431776 -293.288466)
		)
		(stroke
			(width 0)
			(type solid)
		)
		(fill yes)
		(layer "F.Cu")
		(net "M_E_CPU1_SA_DQ<2>")
	)
	(gr_poly
		(pts
			(xy 139.431776 -292.428676) (xy 139.380976 -292.428676) (xy 139.279376 -292.464998) (xy 139.279376 -292.655498)
			(xy 139.380976 -292.691566) (xy 139.431776 -292.691566)
		)
		(stroke
			(width 0)
			(type solid)
		)
		(fill yes)
		(layer "F.Cu")
		(net "M_E_CPU1_SA_DQ<2>")
	)
	(gr_poly
		(pts
			(xy 139.431776 -291.831776) (xy 139.380976 -291.831776) (xy 139.279376 -291.868098) (xy 139.279376 -292.058598)
			(xy 139.380976 -292.094666) (xy 139.431776 -292.094666)
		)
		(stroke
			(width 0)
			(type solid)
		)
		(fill yes)
		(layer "F.Cu")
		(net "M_E_CPU1_SA_DQ<2>")
	)
	(gr_poly
		(pts
			(xy 139.431776 -291.234876) (xy 139.380976 -291.234876) (xy 139.279376 -291.271198) (xy 139.279376 -291.461698)
			(xy 139.380976 -291.497766) (xy 139.431776 -291.497766)
		)
		(stroke
			(width 0)
			(type solid)
		)
		(fill yes)
		(layer "F.Cu")
		(net "M_E_CPU1_SA_DQ<2>")
	)
	(gr_poly
		(pts
			(xy 139.431776 -290.637976) (xy 139.380976 -290.637976) (xy 139.279376 -290.674298) (xy 139.279376 -290.864798)
			(xy 139.380976 -290.900866) (xy 139.431776 -290.900866)
		)
		(stroke
			(width 0)
			(type solid)
		)
		(fill yes)
		(layer "F.Cu")
		(net "M_E_CPU1_SA_DQ<2>")
	)
	(gr_poly
		(pts
			(xy 139.431776 -290.041076) (xy 139.380976 -290.041076) (xy 139.279376 -290.077398) (xy 139.279376 -290.267898)
			(xy 139.380976 -290.303966) (xy 139.431776 -290.303966)
		)
		(stroke
			(width 0)
			(type solid)
		)
		(fill yes)
		(layer "F.Cu")
		(net "M_E_CPU1_SA_DQ<2>")
	)
	(gr_poly
		(pts
			(xy 139.431776 -289.444176) (xy 139.380976 -289.444176) (xy 139.279376 -289.480498) (xy 139.279376 -289.670998)
			(xy 139.380976 -289.707066) (xy 139.431776 -289.707066)
		)
		(stroke
			(width 0)
			(type solid)
		)
		(fill yes)
		(layer "F.Cu")
		(net "M_E_CPU1_SA_DQ<2>")
	)
	(gr_poly
		(pts
			(xy 139.431776 -288.847276) (xy 139.380976 -288.847276) (xy 139.279376 -288.883598) (xy 139.279376 -289.074098)
			(xy 139.380976 -289.110166) (xy 139.431776 -289.110166)
		)
		(stroke
			(width 0)
			(type solid)
		)
		(fill yes)
		(layer "F.Cu")
		(net "M_E_CPU1_SA_DQ<2>")
	)
	(gr_poly
		(pts
			(xy 139.431776 -288.250376) (xy 139.380976 -288.250376) (xy 139.279376 -288.286698) (xy 139.279376 -288.477198)
			(xy 139.380976 -288.513266) (xy 139.431776 -288.513266)
		)
		(stroke
			(width 0)
			(type solid)
		)
		(fill yes)
		(layer "F.Cu")
		(net "M_E_CPU1_SA_DQ<2>")
	)
	(gr_poly
		(pts
			(xy 139.431776 -287.653476) (xy 139.380976 -287.653476) (xy 139.279376 -287.689798) (xy 139.279376 -287.880298)
			(xy 139.380976 -287.916366) (xy 139.431776 -287.916366)
		)
		(stroke
			(width 0)
			(type solid)
		)
		(fill yes)
		(layer "F.Cu")
		(net "M_E_CPU1_SA_DQ<2>")
	)
	(gr_poly
		(pts
			(xy 139.431776 -287.056576) (xy 139.380976 -287.056576) (xy 139.279376 -287.092898) (xy 139.279376 -287.283398)
			(xy 139.380976 -287.319466) (xy 139.431776 -287.319466)
		)
		(stroke
			(width 0)
			(type solid)
		)
		(fill yes)
		(layer "F.Cu")
		(net "M_E_CPU1_SA_DQ<2>")
	)
	(gr_poly
		(pts
			(xy 139.431776 -286.459676) (xy 139.380976 -286.459676) (xy 139.279376 -286.495998) (xy 139.279376 -286.686498)
			(xy 139.380976 -286.722566) (xy 139.431776 -286.722566)
		)
		(stroke
			(width 0)
			(type solid)
		)
		(fill yes)
		(layer "F.Cu")
		(net "M_E_CPU1_SA_DQ<2>")
	)
	(gr_poly
		(pts
			(xy 139.431776 -285.862776) (xy 139.380976 -285.862776) (xy 139.279376 -285.899098) (xy 139.279376 -286.089598)
			(xy 139.380976 -286.125666) (xy 139.431776 -286.125666)
		)
		(stroke
			(width 0)
			(type solid)
		)
		(fill yes)
		(layer "F.Cu")
		(net "M_E_CPU1_SA_DQ<2>")
	)
	(gr_poly
		(pts
			(xy 139.431776 -285.265876) (xy 139.380976 -285.265876) (xy 139.279376 -285.302198) (xy 139.279376 -285.492698)
			(xy 139.380976 -285.528766) (xy 139.431776 -285.528766)
		)
		(stroke
			(width 0)
			(type solid)
		)
		(fill yes)
		(layer "F.Cu")
		(net "M_E_CPU1_SA_DQ<2>")
	)
	(gr_poly
		(pts
			(xy 139.431776 -284.668976) (xy 139.380976 -284.668976) (xy 139.279376 -284.705298) (xy 139.279376 -284.895798)
			(xy 139.380976 -284.931866) (xy 139.431776 -284.931866)
		)
		(stroke
			(width 0)
			(type solid)
		)
		(fill yes)
		(layer "F.Cu")
		(net "M_E_CPU1_SA_DQ<2>")
	)
	(gr_poly
		(pts
			(xy 139.431776 -284.072076) (xy 139.380976 -284.072076) (xy 139.279376 -284.108398) (xy 139.279376 -284.298898)
			(xy 139.380976 -284.334966) (xy 139.431776 -284.334966)
		)
		(stroke
			(width 0)
			(type solid)
		)
		(fill yes)
		(layer "F.Cu")
		(net "M_E_CPU1_SA_DQ<2>")
	)
	(gr_poly
		(pts
			(xy 139.431776 -283.475176) (xy 139.380976 -283.475176) (xy 139.279376 -283.511498) (xy 139.279376 -283.701998)
			(xy 139.380976 -283.738066) (xy 139.431776 -283.738066)
		)
		(stroke
			(width 0)
			(type solid)
		)
		(fill yes)
		(layer "F.Cu")
		(net "M_E_CPU1_SA_DQ<2>")
	)
	(gr_poly
		(pts
			(xy 139.431776 -282.878276) (xy 139.380976 -282.878276) (xy 139.279376 -282.914598) (xy 139.279376 -283.105098)
			(xy 139.380976 -283.141166) (xy 139.431776 -283.141166)
		)
		(stroke
			(width 0)
			(type solid)
		)
		(fill yes)
		(layer "F.Cu")
		(net "M_E_CPU1_SA_DQ<2>")
	)
	(gr_poly
		(pts
			(xy 139.431776 -282.281376) (xy 139.380976 -282.281376) (xy 139.279376 -282.317698) (xy 139.279376 -282.508198)
			(xy 139.380976 -282.544266) (xy 139.431776 -282.544266)
		)
		(stroke
			(width 0)
			(type solid)
		)
		(fill yes)
		(layer "F.Cu")
		(net "M_E_CPU1_SA_DQ<2>")
	)
	(gr_poly
		(pts
			(xy 139.431776 -281.684476) (xy 139.380976 -281.684476) (xy 139.279376 -281.720798) (xy 139.279376 -281.911298)
			(xy 139.380976 -281.947366) (xy 139.431776 -281.947366)
		)
		(stroke
			(width 0)
			(type solid)
		)
		(fill yes)
		(layer "F.Cu")
		(net "M_E_CPU1_SA_DQ<2>")
	)
	(gr_poly
		(pts
			(xy 139.584176 -295.341294) (xy 139.584176 -295.150794) (xy 139.482576 -295.114726) (xy 139.431776 -295.114726)
			(xy 139.431776 -295.377616) (xy 139.482576 -295.377616)
		)
		(stroke
			(width 0)
			(type solid)
		)
		(fill yes)
		(layer "F.Cu")
		(net "M_E_CPU1_SA_DQ<2>")
	)
	(gr_poly
		(pts
			(xy 139.584176 -294.744394) (xy 139.584176 -294.553894) (xy 139.482576 -294.517826) (xy 139.431776 -294.517826)
			(xy 139.431776 -294.780716) (xy 139.482576 -294.780716)
		)
		(stroke
			(width 0)
			(type solid)
		)
		(fill yes)
		(layer "F.Cu")
		(net "M_E_CPU1_SA_DQ<2>")
	)
	(gr_poly
		(pts
			(xy 139.584176 -294.147494) (xy 139.584176 -293.956994) (xy 139.482576 -293.920926) (xy 139.431776 -293.920926)
			(xy 139.431776 -294.183816) (xy 139.482576 -294.183816)
		)
		(stroke
			(width 0)
			(type solid)
		)
		(fill yes)
		(layer "F.Cu")
		(net "M_E_CPU1_SA_DQ<2>")
	)
	(gr_poly
		(pts
			(xy 139.584176 -293.550594) (xy 139.584176 -293.360094) (xy 139.482576 -293.324026) (xy 139.431776 -293.324026)
			(xy 139.431776 -293.586916) (xy 139.482576 -293.586916)
		)
		(stroke
			(width 0)
			(type solid)
		)
		(fill yes)
		(layer "F.Cu")
		(net "M_E_CPU1_SA_DQ<2>")
	)
	(gr_poly
		(pts
			(xy 139.584176 -292.953694) (xy 139.584176 -292.763194) (xy 139.482576 -292.727126) (xy 139.431776 -292.727126)
			(xy 139.431776 -292.990016) (xy 139.482576 -292.990016)
		)
		(stroke
			(width 0)
			(type solid)
		)
		(fill yes)
		(layer "F.Cu")
		(net "M_E_CPU1_SA_DQ<2>")
	)
	(gr_poly
		(pts
			(xy 139.584176 -292.356794) (xy 139.584176 -292.166294) (xy 139.482576 -292.130226) (xy 139.431776 -292.130226)
			(xy 139.431776 -292.393116) (xy 139.482576 -292.393116)
		)
		(stroke
			(width 0)
			(type solid)
		)
		(fill yes)
		(layer "F.Cu")
		(net "M_E_CPU1_SA_DQ<2>")
	)
	(gr_poly
		(pts
			(xy 139.584176 -291.759894) (xy 139.584176 -291.569394) (xy 139.482576 -291.533326) (xy 139.431776 -291.533326)
			(xy 139.431776 -291.796216) (xy 139.482576 -291.796216)
		)
		(stroke
			(width 0)
			(type solid)
		)
		(fill yes)
		(layer "F.Cu")
		(net "M_E_CPU1_SA_DQ<2>")
	)
	(gr_poly
		(pts
			(xy 139.584176 -291.162994) (xy 139.584176 -290.972494) (xy 139.482576 -290.936426) (xy 139.431776 -290.936426)
			(xy 139.431776 -291.199316) (xy 139.482576 -291.199316)
		)
		(stroke
			(width 0)
			(type solid)
		)
		(fill yes)
		(layer "F.Cu")
		(net "M_E_CPU1_SA_DQ<2>")
	)
	(gr_poly
		(pts
			(xy 139.584176 -290.566094) (xy 139.584176 -290.375594) (xy 139.482576 -290.339526) (xy 139.431776 -290.339526)
			(xy 139.431776 -290.602416) (xy 139.482576 -290.602416)
		)
		(stroke
			(width 0)
			(type solid)
		)
		(fill yes)
		(layer "F.Cu")
		(net "M_E_CPU1_SA_DQ<2>")
	)
	(gr_poly
		(pts
			(xy 139.584176 -289.969194) (xy 139.584176 -289.778694) (xy 139.482576 -289.742626) (xy 139.431776 -289.742626)
			(xy 139.431776 -290.005516) (xy 139.482576 -290.005516)
		)
		(stroke
			(width 0)
			(type solid)
		)
		(fill yes)
		(layer "F.Cu")
		(net "M_E_CPU1_SA_DQ<2>")
	)
	(gr_poly
		(pts
			(xy 139.584176 -289.372294) (xy 139.584176 -289.181794) (xy 139.482576 -289.145726) (xy 139.431776 -289.145726)
			(xy 139.431776 -289.408616) (xy 139.482576 -289.408616)
		)
		(stroke
			(width 0)
			(type solid)
		)
		(fill yes)
		(layer "F.Cu")
		(net "M_E_CPU1_SA_DQ<2>")
	)
	(gr_poly
		(pts
			(xy 139.584176 -288.775394) (xy 139.584176 -288.584894) (xy 139.482576 -288.548826) (xy 139.431776 -288.548826)
			(xy 139.431776 -288.811716) (xy 139.482576 -288.811716)
		)
		(stroke
			(width 0)
			(type solid)
		)
		(fill yes)
		(layer "F.Cu")
		(net "M_E_CPU1_SA_DQ<2>")
	)
	(gr_poly
		(pts
			(xy 139.584176 -288.178494) (xy 139.584176 -287.987994) (xy 139.482576 -287.951926) (xy 139.431776 -287.951926)
			(xy 139.431776 -288.214816) (xy 139.482576 -288.214816)
		)
		(stroke
			(width 0)
			(type solid)
		)
		(fill yes)
		(layer "F.Cu")
		(net "M_E_CPU1_SA_DQ<2>")
	)
	(gr_poly
		(pts
			(xy 139.584176 -287.581594) (xy 139.584176 -287.391094) (xy 139.482576 -287.355026) (xy 139.431776 -287.355026)
			(xy 139.431776 -287.617916) (xy 139.482576 -287.617916)
		)
		(stroke
			(width 0)
			(type solid)
		)
		(fill yes)
		(layer "F.Cu")
		(net "M_E_CPU1_SA_DQ<2>")
	)
	(gr_poly
		(pts
			(xy 139.584176 -286.984694) (xy 139.584176 -286.794194) (xy 139.482576 -286.758126) (xy 139.431776 -286.758126)
			(xy 139.431776 -287.021016) (xy 139.482576 -287.021016)
		)
		(stroke
			(width 0)
			(type solid)
		)
		(fill yes)
		(layer "F.Cu")
		(net "M_E_CPU1_SA_DQ<2>")
	)
	(gr_poly
		(pts
			(xy 139.584176 -286.387794) (xy 139.584176 -286.197294) (xy 139.482576 -286.161226) (xy 139.431776 -286.161226)
			(xy 139.431776 -286.424116) (xy 139.482576 -286.424116)
		)
		(stroke
			(width 0)
			(type solid)
		)
		(fill yes)
		(layer "F.Cu")
		(net "M_E_CPU1_SA_DQ<2>")
	)
	(gr_poly
		(pts
			(xy 139.584176 -285.790894) (xy 139.584176 -285.600394) (xy 139.482576 -285.564326) (xy 139.431776 -285.564326)
			(xy 139.431776 -285.827216) (xy 139.482576 -285.827216)
		)
		(stroke
			(width 0)
			(type solid)
		)
		(fill yes)
		(layer "F.Cu")
		(net "M_E_CPU1_SA_DQ<2>")
	)
	(gr_poly
		(pts
			(xy 139.584176 -285.193994) (xy 139.584176 -285.003494) (xy 139.482576 -284.967426) (xy 139.431776 -284.967426)
			(xy 139.431776 -285.230316) (xy 139.482576 -285.230316)
		)
		(stroke
			(width 0)
			(type solid)
		)
		(fill yes)
		(layer "F.Cu")
		(net "M_E_CPU1_SA_DQ<2>")
	)
	(gr_poly
		(pts
			(xy 139.584176 -284.597094) (xy 139.584176 -284.406594) (xy 139.482576 -284.370526) (xy 139.431776 -284.370526)
			(xy 139.431776 -284.633416) (xy 139.482576 -284.633416)
		)
		(stroke
			(width 0)
			(type solid)
		)
		(fill yes)
		(layer "F.Cu")
		(net "M_E_CPU1_SA_DQ<2>")
	)
	(gr_poly
		(pts
			(xy 139.584176 -284.000194) (xy 139.584176 -283.809694) (xy 139.482576 -283.773626) (xy 139.431776 -283.773626)
			(xy 139.431776 -284.036516) (xy 139.482576 -284.036516)
		)
		(stroke
			(width 0)
			(type solid)
		)
		(fill yes)
		(layer "F.Cu")
		(net "M_E_CPU1_SA_DQ<2>")
	)
	(gr_poly
		(pts
			(xy 139.584176 -283.403294) (xy 139.584176 -283.212794) (xy 139.482576 -283.176726) (xy 139.431776 -283.176726)
			(xy 139.431776 -283.439616) (xy 139.482576 -283.439616)
		)
		(stroke
			(width 0)
			(type solid)
		)
		(fill yes)
		(layer "F.Cu")
		(net "M_E_CPU1_SA_DQ<2>")
	)
	(gr_poly
		(pts
			(xy 139.584176 -282.806394) (xy 139.584176 -282.615894) (xy 139.482576 -282.579826) (xy 139.431776 -282.579826)
			(xy 139.431776 -282.842716) (xy 139.482576 -282.842716)
		)
		(stroke
			(width 0)
			(type solid)
		)
		(fill yes)
		(layer "F.Cu")
		(net "M_E_CPU1_SA_DQ<2>")
	)
	(gr_poly
		(pts
			(xy 139.584176 -282.209494) (xy 139.584176 -282.018994) (xy 139.482576 -281.982926) (xy 139.431776 -281.982926)
			(xy 139.431776 -282.245816) (xy 139.482576 -282.245816)
		)
		(stroke
			(width 0)
			(type solid)
		)
		(fill yes)
		(layer "F.Cu")
		(net "M_E_CPU1_SA_DQ<2>")
	)
	(gr_poly
		(pts
			(xy 139.584176 -281.612594) (xy 139.584176 -281.422094) (xy 139.482576 -281.386026) (xy 139.431776 -281.386026)
			(xy 139.431776 -281.648916) (xy 139.482576 -281.648916)
		)
		(stroke
			(width 0)
			(type solid)
		)
		(fill yes)
		(layer "F.Cu")
		(net "M_E_CPU1_SA_DQ<2>")
	)
	(gr_poly
		(pts
			(xy 139.707112 -224.01403) (xy 139.656312 -224.01403) (xy 139.554712 -224.050098) (xy 139.554712 -224.240598)
			(xy 139.656312 -224.27692) (xy 139.707112 -224.27692)
		)
		(stroke
			(width 0)
			(type solid)
		)
		(fill yes)
		(layer "F.Cu")
		(net "M_E_CPU1_SB_DQ<31>")
	)
	(gr_poly
		(pts
			(xy 139.707112 -223.41713) (xy 139.656312 -223.41713) (xy 139.554712 -223.453198) (xy 139.554712 -223.643698)
			(xy 139.656312 -223.68002) (xy 139.707112 -223.68002)
		)
		(stroke
			(width 0)
			(type solid)
		)
		(fill yes)
		(layer "F.Cu")
		(net "M_E_CPU1_SB_DQ<31>")
	)
	(gr_poly
		(pts
			(xy 139.707112 -222.82023) (xy 139.656312 -222.82023) (xy 139.554712 -222.856298) (xy 139.554712 -223.046798)
			(xy 139.656312 -223.08312) (xy 139.707112 -223.08312)
		)
		(stroke
			(width 0)
			(type solid)
		)
		(fill yes)
		(layer "F.Cu")
		(net "M_E_CPU1_SB_DQ<31>")
	)
	(gr_poly
		(pts
			(xy 139.707112 -222.22333) (xy 139.656312 -222.22333) (xy 139.554712 -222.259398) (xy 139.554712 -222.449898)
			(xy 139.656312 -222.48622) (xy 139.707112 -222.48622)
		)
		(stroke
			(width 0)
			(type solid)
		)
		(fill yes)
		(layer "F.Cu")
		(net "M_E_CPU1_SB_DQ<31>")
	)
	(gr_poly
		(pts
			(xy 139.707112 -221.62643) (xy 139.656312 -221.62643) (xy 139.554712 -221.662498) (xy 139.554712 -221.852998)
			(xy 139.656312 -221.88932) (xy 139.707112 -221.88932)
		)
		(stroke
			(width 0)
			(type solid)
		)
		(fill yes)
		(layer "F.Cu")
		(net "M_E_CPU1_SB_DQ<31>")
	)
	(gr_poly
		(pts
			(xy 139.707112 -221.02953) (xy 139.656312 -221.02953) (xy 139.554712 -221.065598) (xy 139.554712 -221.256098)
			(xy 139.656312 -221.29242) (xy 139.707112 -221.29242)
		)
		(stroke
			(width 0)
			(type solid)
		)
		(fill yes)
		(layer "F.Cu")
		(net "M_E_CPU1_SB_DQ<31>")
	)
	(gr_poly
		(pts
			(xy 139.707112 -220.43263) (xy 139.656312 -220.43263) (xy 139.554712 -220.468698) (xy 139.554712 -220.659198)
			(xy 139.656312 -220.69552) (xy 139.707112 -220.69552)
		)
		(stroke
			(width 0)
			(type solid)
		)
		(fill yes)
		(layer "F.Cu")
		(net "M_E_CPU1_SB_DQ<31>")
	)
	(gr_poly
		(pts
			(xy 139.707112 -219.83573) (xy 139.656312 -219.83573) (xy 139.554712 -219.871798) (xy 139.554712 -220.062298)
			(xy 139.656312 -220.09862) (xy 139.707112 -220.09862)
		)
		(stroke
			(width 0)
			(type solid)
		)
		(fill yes)
		(layer "F.Cu")
		(net "M_E_CPU1_SB_DQ<31>")
	)
	(gr_poly
		(pts
			(xy 139.707112 -219.23883) (xy 139.656312 -219.23883) (xy 139.554712 -219.274898) (xy 139.554712 -219.465398)
			(xy 139.656312 -219.50172) (xy 139.707112 -219.50172)
		)
		(stroke
			(width 0)
			(type solid)
		)
		(fill yes)
		(layer "F.Cu")
		(net "M_E_CPU1_SB_DQ<31>")
	)
	(gr_poly
		(pts
			(xy 139.707112 -218.64193) (xy 139.656312 -218.64193) (xy 139.554712 -218.677998) (xy 139.554712 -218.868498)
			(xy 139.656312 -218.90482) (xy 139.707112 -218.90482)
		)
		(stroke
			(width 0)
			(type solid)
		)
		(fill yes)
		(layer "F.Cu")
		(net "M_E_CPU1_SB_DQ<31>")
	)
	(gr_poly
		(pts
			(xy 139.707112 -218.04503) (xy 139.656312 -218.04503) (xy 139.554712 -218.081098) (xy 139.554712 -218.271598)
			(xy 139.656312 -218.30792) (xy 139.707112 -218.30792)
		)
		(stroke
			(width 0)
			(type solid)
		)
		(fill yes)
		(layer "F.Cu")
		(net "M_E_CPU1_SB_DQ<31>")
	)
	(gr_poly
		(pts
			(xy 139.707112 -217.44813) (xy 139.656312 -217.44813) (xy 139.554712 -217.484198) (xy 139.554712 -217.674698)
			(xy 139.656312 -217.71102) (xy 139.707112 -217.71102)
		)
		(stroke
			(width 0)
			(type solid)
		)
		(fill yes)
		(layer "F.Cu")
		(net "M_E_CPU1_SB_DQ<31>")
	)
	(gr_poly
		(pts
			(xy 139.707112 -216.85123) (xy 139.656312 -216.85123) (xy 139.554712 -216.887298) (xy 139.554712 -217.077798)
			(xy 139.656312 -217.11412) (xy 139.707112 -217.11412)
		)
		(stroke
			(width 0)
			(type solid)
		)
		(fill yes)
		(layer "F.Cu")
		(net "M_E_CPU1_SB_DQ<31>")
	)
	(gr_poly
		(pts
			(xy 139.707112 -216.25433) (xy 139.656312 -216.25433) (xy 139.554712 -216.290398) (xy 139.554712 -216.480898)
			(xy 139.656312 -216.51722) (xy 139.707112 -216.51722)
		)
		(stroke
			(width 0)
			(type solid)
		)
		(fill yes)
		(layer "F.Cu")
		(net "M_E_CPU1_SB_DQ<31>")
	)
	(gr_poly
		(pts
			(xy 139.707112 -215.65743) (xy 139.656312 -215.65743) (xy 139.554712 -215.693498) (xy 139.554712 -215.883998)
			(xy 139.656312 -215.92032) (xy 139.707112 -215.92032)
		)
		(stroke
			(width 0)
			(type solid)
		)
		(fill yes)
		(layer "F.Cu")
		(net "M_E_CPU1_SB_DQ<31>")
	)
	(gr_poly
		(pts
			(xy 139.736576 -295.413176) (xy 139.685776 -295.413176) (xy 139.584176 -295.449498) (xy 139.584176 -295.639998)
			(xy 139.685776 -295.676066) (xy 139.736576 -295.676066)
		)
		(stroke
			(width 0)
			(type solid)
		)
		(fill yes)
		(layer "F.Cu")
		(net "M_E_CPU1_SA_DQ<1>")
	)
	(gr_poly
		(pts
			(xy 139.736576 -294.816276) (xy 139.685776 -294.816276) (xy 139.584176 -294.852598) (xy 139.584176 -295.043098)
			(xy 139.685776 -295.079166) (xy 139.736576 -295.079166)
		)
		(stroke
			(width 0)
			(type solid)
		)
		(fill yes)
		(layer "F.Cu")
		(net "M_E_CPU1_SA_DQ<1>")
	)
	(gr_poly
		(pts
			(xy 139.736576 -294.219376) (xy 139.685776 -294.219376) (xy 139.584176 -294.255698) (xy 139.584176 -294.446198)
			(xy 139.685776 -294.482266) (xy 139.736576 -294.482266)
		)
		(stroke
			(width 0)
			(type solid)
		)
		(fill yes)
		(layer "F.Cu")
		(net "M_E_CPU1_SA_DQ<1>")
	)
	(gr_poly
		(pts
			(xy 139.736576 -293.622476) (xy 139.685776 -293.622476) (xy 139.584176 -293.658798) (xy 139.584176 -293.849298)
			(xy 139.685776 -293.885366) (xy 139.736576 -293.885366)
		)
		(stroke
			(width 0)
			(type solid)
		)
		(fill yes)
		(layer "F.Cu")
		(net "M_E_CPU1_SA_DQ<1>")
	)
	(gr_poly
		(pts
			(xy 139.736576 -293.025576) (xy 139.685776 -293.025576) (xy 139.584176 -293.061898) (xy 139.584176 -293.252398)
			(xy 139.685776 -293.288466) (xy 139.736576 -293.288466)
		)
		(stroke
			(width 0)
			(type solid)
		)
		(fill yes)
		(layer "F.Cu")
		(net "M_E_CPU1_SA_DQ<1>")
	)
	(gr_poly
		(pts
			(xy 139.736576 -292.428676) (xy 139.685776 -292.428676) (xy 139.584176 -292.464998) (xy 139.584176 -292.655498)
			(xy 139.685776 -292.691566) (xy 139.736576 -292.691566)
		)
		(stroke
			(width 0)
			(type solid)
		)
		(fill yes)
		(layer "F.Cu")
		(net "M_E_CPU1_SA_DQ<1>")
	)
	(gr_poly
		(pts
			(xy 139.736576 -291.831776) (xy 139.685776 -291.831776) (xy 139.584176 -291.868098) (xy 139.584176 -292.058598)
			(xy 139.685776 -292.094666) (xy 139.736576 -292.094666)
		)
		(stroke
			(width 0)
			(type solid)
		)
		(fill yes)
		(layer "F.Cu")
		(net "M_E_CPU1_SA_DQ<1>")
	)
	(gr_poly
		(pts
			(xy 139.736576 -291.234876) (xy 139.685776 -291.234876) (xy 139.584176 -291.271198) (xy 139.584176 -291.461698)
			(xy 139.685776 -291.497766) (xy 139.736576 -291.497766)
		)
		(stroke
			(width 0)
			(type solid)
		)
		(fill yes)
		(layer "F.Cu")
		(net "M_E_CPU1_SA_DQ<1>")
	)
	(gr_poly
		(pts
			(xy 139.736576 -290.637976) (xy 139.685776 -290.637976) (xy 139.584176 -290.674298) (xy 139.584176 -290.864798)
			(xy 139.685776 -290.900866) (xy 139.736576 -290.900866)
		)
		(stroke
			(width 0)
			(type solid)
		)
		(fill yes)
		(layer "F.Cu")
		(net "M_E_CPU1_SA_DQ<1>")
	)
	(gr_poly
		(pts
			(xy 139.736576 -290.041076) (xy 139.685776 -290.041076) (xy 139.584176 -290.077398) (xy 139.584176 -290.267898)
			(xy 139.685776 -290.303966) (xy 139.736576 -290.303966)
		)
		(stroke
			(width 0)
			(type solid)
		)
		(fill yes)
		(layer "F.Cu")
		(net "M_E_CPU1_SA_DQ<1>")
	)
	(gr_poly
		(pts
			(xy 139.736576 -289.444176) (xy 139.685776 -289.444176) (xy 139.584176 -289.480498) (xy 139.584176 -289.670998)
			(xy 139.685776 -289.707066) (xy 139.736576 -289.707066)
		)
		(stroke
			(width 0)
			(type solid)
		)
		(fill yes)
		(layer "F.Cu")
		(net "M_E_CPU1_SA_DQ<1>")
	)
	(gr_poly
		(pts
			(xy 139.736576 -288.847276) (xy 139.685776 -288.847276) (xy 139.584176 -288.883598) (xy 139.584176 -289.074098)
			(xy 139.685776 -289.110166) (xy 139.736576 -289.110166)
		)
		(stroke
			(width 0)
			(type solid)
		)
		(fill yes)
		(layer "F.Cu")
		(net "M_E_CPU1_SA_DQ<1>")
	)
	(gr_poly
		(pts
			(xy 139.736576 -288.250376) (xy 139.685776 -288.250376) (xy 139.584176 -288.286698) (xy 139.584176 -288.477198)
			(xy 139.685776 -288.513266) (xy 139.736576 -288.513266)
		)
		(stroke
			(width 0)
			(type solid)
		)
		(fill yes)
		(layer "F.Cu")
		(net "M_E_CPU1_SA_DQ<1>")
	)
	(gr_poly
		(pts
			(xy 139.736576 -287.653476) (xy 139.685776 -287.653476) (xy 139.584176 -287.689798) (xy 139.584176 -287.880298)
			(xy 139.685776 -287.916366) (xy 139.736576 -287.916366)
		)
		(stroke
			(width 0)
			(type solid)
		)
		(fill yes)
		(layer "F.Cu")
		(net "M_E_CPU1_SA_DQ<1>")
	)
	(gr_poly
		(pts
			(xy 139.736576 -287.056576) (xy 139.685776 -287.056576) (xy 139.584176 -287.092898) (xy 139.584176 -287.283398)
			(xy 139.685776 -287.319466) (xy 139.736576 -287.319466)
		)
		(stroke
			(width 0)
			(type solid)
		)
		(fill yes)
		(layer "F.Cu")
		(net "M_E_CPU1_SA_DQ<1>")
	)
	(gr_poly
		(pts
			(xy 139.736576 -286.459676) (xy 139.685776 -286.459676) (xy 139.584176 -286.495998) (xy 139.584176 -286.686498)
			(xy 139.685776 -286.722566) (xy 139.736576 -286.722566)
		)
		(stroke
			(width 0)
			(type solid)
		)
		(fill yes)
		(layer "F.Cu")
		(net "M_E_CPU1_SA_DQ<1>")
	)
	(gr_poly
		(pts
			(xy 139.736576 -285.862776) (xy 139.685776 -285.862776) (xy 139.584176 -285.899098) (xy 139.584176 -286.089598)
			(xy 139.685776 -286.125666) (xy 139.736576 -286.125666)
		)
		(stroke
			(width 0)
			(type solid)
		)
		(fill yes)
		(layer "F.Cu")
		(net "M_E_CPU1_SA_DQ<1>")
	)
	(gr_poly
		(pts
			(xy 139.736576 -285.265876) (xy 139.685776 -285.265876) (xy 139.584176 -285.302198) (xy 139.584176 -285.492698)
			(xy 139.685776 -285.528766) (xy 139.736576 -285.528766)
		)
		(stroke
			(width 0)
			(type solid)
		)
		(fill yes)
		(layer "F.Cu")
		(net "M_E_CPU1_SA_DQ<1>")
	)
	(gr_poly
		(pts
			(xy 139.736576 -284.668976) (xy 139.685776 -284.668976) (xy 139.584176 -284.705298) (xy 139.584176 -284.895798)
			(xy 139.685776 -284.931866) (xy 139.736576 -284.931866)
		)
		(stroke
			(width 0)
			(type solid)
		)
		(fill yes)
		(layer "F.Cu")
		(net "M_E_CPU1_SA_DQ<1>")
	)
	(gr_poly
		(pts
			(xy 139.736576 -284.072076) (xy 139.685776 -284.072076) (xy 139.584176 -284.108398) (xy 139.584176 -284.298898)
			(xy 139.685776 -284.334966) (xy 139.736576 -284.334966)
		)
		(stroke
			(width 0)
			(type solid)
		)
		(fill yes)
		(layer "F.Cu")
		(net "M_E_CPU1_SA_DQ<1>")
	)
	(gr_poly
		(pts
			(xy 139.736576 -283.475176) (xy 139.685776 -283.475176) (xy 139.584176 -283.511498) (xy 139.584176 -283.701998)
			(xy 139.685776 -283.738066) (xy 139.736576 -283.738066)
		)
		(stroke
			(width 0)
			(type solid)
		)
		(fill yes)
		(layer "F.Cu")
		(net "M_E_CPU1_SA_DQ<1>")
	)
	(gr_poly
		(pts
			(xy 139.736576 -282.878276) (xy 139.685776 -282.878276) (xy 139.584176 -282.914598) (xy 139.584176 -283.105098)
			(xy 139.685776 -283.141166) (xy 139.736576 -283.141166)
		)
		(stroke
			(width 0)
			(type solid)
		)
		(fill yes)
		(layer "F.Cu")
		(net "M_E_CPU1_SA_DQ<1>")
	)
	(gr_poly
		(pts
			(xy 139.736576 -282.281376) (xy 139.685776 -282.281376) (xy 139.584176 -282.317698) (xy 139.584176 -282.508198)
			(xy 139.685776 -282.544266) (xy 139.736576 -282.544266)
		)
		(stroke
			(width 0)
			(type solid)
		)
		(fill yes)
		(layer "F.Cu")
		(net "M_E_CPU1_SA_DQ<1>")
	)
	(gr_poly
		(pts
			(xy 139.736576 -281.684476) (xy 139.685776 -281.684476) (xy 139.584176 -281.720798) (xy 139.584176 -281.911298)
			(xy 139.685776 -281.947366) (xy 139.736576 -281.947366)
		)
		(stroke
			(width 0)
			(type solid)
		)
		(fill yes)
		(layer "F.Cu")
		(net "M_E_CPU1_SA_DQ<1>")
	)
	(gr_poly
		(pts
			(xy 139.859512 -224.539302) (xy 139.859512 -224.348802) (xy 139.757912 -224.31248) (xy 139.707112 -224.31248)
			(xy 139.707112 -224.57537) (xy 139.757912 -224.57537)
		)
		(stroke
			(width 0)
			(type solid)
		)
		(fill yes)
		(layer "F.Cu")
		(net "M_E_CPU1_SB_DQ<31>")
	)
	(gr_poly
		(pts
			(xy 139.859512 -223.942402) (xy 139.859512 -223.751902) (xy 139.757912 -223.71558) (xy 139.707112 -223.71558)
			(xy 139.707112 -223.97847) (xy 139.757912 -223.97847)
		)
		(stroke
			(width 0)
			(type solid)
		)
		(fill yes)
		(layer "F.Cu")
		(net "M_E_CPU1_SB_DQ<31>")
	)
	(gr_poly
		(pts
			(xy 139.859512 -223.345502) (xy 139.859512 -223.155002) (xy 139.757912 -223.11868) (xy 139.707112 -223.11868)
			(xy 139.707112 -223.38157) (xy 139.757912 -223.38157)
		)
		(stroke
			(width 0)
			(type solid)
		)
		(fill yes)
		(layer "F.Cu")
		(net "M_E_CPU1_SB_DQ<31>")
	)
	(gr_poly
		(pts
			(xy 139.859512 -222.748602) (xy 139.859512 -222.558102) (xy 139.757912 -222.52178) (xy 139.707112 -222.52178)
			(xy 139.707112 -222.78467) (xy 139.757912 -222.78467)
		)
		(stroke
			(width 0)
			(type solid)
		)
		(fill yes)
		(layer "F.Cu")
		(net "M_E_CPU1_SB_DQ<31>")
	)
	(gr_poly
		(pts
			(xy 139.859512 -222.151702) (xy 139.859512 -221.961202) (xy 139.757912 -221.92488) (xy 139.707112 -221.92488)
			(xy 139.707112 -222.18777) (xy 139.757912 -222.18777)
		)
		(stroke
			(width 0)
			(type solid)
		)
		(fill yes)
		(layer "F.Cu")
		(net "M_E_CPU1_SB_DQ<31>")
	)
	(gr_poly
		(pts
			(xy 139.859512 -221.554802) (xy 139.859512 -221.364302) (xy 139.757912 -221.32798) (xy 139.707112 -221.32798)
			(xy 139.707112 -221.59087) (xy 139.757912 -221.59087)
		)
		(stroke
			(width 0)
			(type solid)
		)
		(fill yes)
		(layer "F.Cu")
		(net "M_E_CPU1_SB_DQ<31>")
	)
	(gr_poly
		(pts
			(xy 139.859512 -220.957902) (xy 139.859512 -220.767402) (xy 139.757912 -220.73108) (xy 139.707112 -220.73108)
			(xy 139.707112 -220.99397) (xy 139.757912 -220.99397)
		)
		(stroke
			(width 0)
			(type solid)
		)
		(fill yes)
		(layer "F.Cu")
		(net "M_E_CPU1_SB_DQ<31>")
	)
	(gr_poly
		(pts
			(xy 139.859512 -220.361002) (xy 139.859512 -220.170502) (xy 139.757912 -220.13418) (xy 139.707112 -220.13418)
			(xy 139.707112 -220.39707) (xy 139.757912 -220.39707)
		)
		(stroke
			(width 0)
			(type solid)
		)
		(fill yes)
		(layer "F.Cu")
		(net "M_E_CPU1_SB_DQ<31>")
	)
	(gr_poly
		(pts
			(xy 139.859512 -219.764102) (xy 139.859512 -219.573602) (xy 139.757912 -219.53728) (xy 139.707112 -219.53728)
			(xy 139.707112 -219.80017) (xy 139.757912 -219.80017)
		)
		(stroke
			(width 0)
			(type solid)
		)
		(fill yes)
		(layer "F.Cu")
		(net "M_E_CPU1_SB_DQ<31>")
	)
	(gr_poly
		(pts
			(xy 139.859512 -219.167202) (xy 139.859512 -218.976702) (xy 139.757912 -218.94038) (xy 139.707112 -218.94038)
			(xy 139.707112 -219.20327) (xy 139.757912 -219.20327)
		)
		(stroke
			(width 0)
			(type solid)
		)
		(fill yes)
		(layer "F.Cu")
		(net "M_E_CPU1_SB_DQ<31>")
	)
	(gr_poly
		(pts
			(xy 139.859512 -218.570302) (xy 139.859512 -218.379802) (xy 139.757912 -218.34348) (xy 139.707112 -218.34348)
			(xy 139.707112 -218.60637) (xy 139.757912 -218.60637)
		)
		(stroke
			(width 0)
			(type solid)
		)
		(fill yes)
		(layer "F.Cu")
		(net "M_E_CPU1_SB_DQ<31>")
	)
	(gr_poly
		(pts
			(xy 139.859512 -217.973402) (xy 139.859512 -217.782902) (xy 139.757912 -217.74658) (xy 139.707112 -217.74658)
			(xy 139.707112 -218.00947) (xy 139.757912 -218.00947)
		)
		(stroke
			(width 0)
			(type solid)
		)
		(fill yes)
		(layer "F.Cu")
		(net "M_E_CPU1_SB_DQ<31>")
	)
	(gr_poly
		(pts
			(xy 139.859512 -217.376502) (xy 139.859512 -217.186002) (xy 139.757912 -217.14968) (xy 139.707112 -217.14968)
			(xy 139.707112 -217.41257) (xy 139.757912 -217.41257)
		)
		(stroke
			(width 0)
			(type solid)
		)
		(fill yes)
		(layer "F.Cu")
		(net "M_E_CPU1_SB_DQ<31>")
	)
	(gr_poly
		(pts
			(xy 139.859512 -216.779602) (xy 139.859512 -216.589102) (xy 139.757912 -216.55278) (xy 139.707112 -216.55278)
			(xy 139.707112 -216.81567) (xy 139.757912 -216.81567)
		)
		(stroke
			(width 0)
			(type solid)
		)
		(fill yes)
		(layer "F.Cu")
		(net "M_E_CPU1_SB_DQ<31>")
	)
	(gr_poly
		(pts
			(xy 139.859512 -216.182702) (xy 139.859512 -215.992202) (xy 139.757912 -215.95588) (xy 139.707112 -215.95588)
			(xy 139.707112 -216.21877) (xy 139.757912 -216.21877)
		)
		(stroke
			(width 0)
			(type solid)
		)
		(fill yes)
		(layer "F.Cu")
		(net "M_E_CPU1_SB_DQ<31>")
	)
	(gr_poly
		(pts
			(xy 139.888976 -295.341294) (xy 139.888976 -295.150794) (xy 139.787376 -295.114726) (xy 139.736576 -295.114726)
			(xy 139.736576 -295.377616) (xy 139.787376 -295.377616)
		)
		(stroke
			(width 0)
			(type solid)
		)
		(fill yes)
		(layer "F.Cu")
		(net "M_E_CPU1_SA_DQ<1>")
	)
	(gr_poly
		(pts
			(xy 139.888976 -294.744394) (xy 139.888976 -294.553894) (xy 139.787376 -294.517826) (xy 139.736576 -294.517826)
			(xy 139.736576 -294.780716) (xy 139.787376 -294.780716)
		)
		(stroke
			(width 0)
			(type solid)
		)
		(fill yes)
		(layer "F.Cu")
		(net "M_E_CPU1_SA_DQ<1>")
	)
	(gr_poly
		(pts
			(xy 139.888976 -294.147494) (xy 139.888976 -293.956994) (xy 139.787376 -293.920926) (xy 139.736576 -293.920926)
			(xy 139.736576 -294.183816) (xy 139.787376 -294.183816)
		)
		(stroke
			(width 0)
			(type solid)
		)
		(fill yes)
		(layer "F.Cu")
		(net "M_E_CPU1_SA_DQ<1>")
	)
	(gr_poly
		(pts
			(xy 139.888976 -293.550594) (xy 139.888976 -293.360094) (xy 139.787376 -293.324026) (xy 139.736576 -293.324026)
			(xy 139.736576 -293.586916) (xy 139.787376 -293.586916)
		)
		(stroke
			(width 0)
			(type solid)
		)
		(fill yes)
		(layer "F.Cu")
		(net "M_E_CPU1_SA_DQ<1>")
	)
	(gr_poly
		(pts
			(xy 139.888976 -292.953694) (xy 139.888976 -292.763194) (xy 139.787376 -292.727126) (xy 139.736576 -292.727126)
			(xy 139.736576 -292.990016) (xy 139.787376 -292.990016)
		)
		(stroke
			(width 0)
			(type solid)
		)
		(fill yes)
		(layer "F.Cu")
		(net "M_E_CPU1_SA_DQ<1>")
	)
	(gr_poly
		(pts
			(xy 139.888976 -292.356794) (xy 139.888976 -292.166294) (xy 139.787376 -292.130226) (xy 139.736576 -292.130226)
			(xy 139.736576 -292.393116) (xy 139.787376 -292.393116)
		)
		(stroke
			(width 0)
			(type solid)
		)
		(fill yes)
		(layer "F.Cu")
		(net "M_E_CPU1_SA_DQ<1>")
	)
	(gr_poly
		(pts
			(xy 139.888976 -291.759894) (xy 139.888976 -291.569394) (xy 139.787376 -291.533326) (xy 139.736576 -291.533326)
			(xy 139.736576 -291.796216) (xy 139.787376 -291.796216)
		)
		(stroke
			(width 0)
			(type solid)
		)
		(fill yes)
		(layer "F.Cu")
		(net "M_E_CPU1_SA_DQ<1>")
	)
	(gr_poly
		(pts
			(xy 139.888976 -291.162994) (xy 139.888976 -290.972494) (xy 139.787376 -290.936426) (xy 139.736576 -290.936426)
			(xy 139.736576 -291.199316) (xy 139.787376 -291.199316)
		)
		(stroke
			(width 0)
			(type solid)
		)
		(fill yes)
		(layer "F.Cu")
		(net "M_E_CPU1_SA_DQ<1>")
	)
	(gr_poly
		(pts
			(xy 139.888976 -290.566094) (xy 139.888976 -290.375594) (xy 139.787376 -290.339526) (xy 139.736576 -290.339526)
			(xy 139.736576 -290.602416) (xy 139.787376 -290.602416)
		)
		(stroke
			(width 0)
			(type solid)
		)
		(fill yes)
		(layer "F.Cu")
		(net "M_E_CPU1_SA_DQ<1>")
	)
	(gr_poly
		(pts
			(xy 139.888976 -289.969194) (xy 139.888976 -289.778694) (xy 139.787376 -289.742626) (xy 139.736576 -289.742626)
			(xy 139.736576 -290.005516) (xy 139.787376 -290.005516)
		)
		(stroke
			(width 0)
			(type solid)
		)
		(fill yes)
		(layer "F.Cu")
		(net "M_E_CPU1_SA_DQ<1>")
	)
	(gr_poly
		(pts
			(xy 139.888976 -289.372294) (xy 139.888976 -289.181794) (xy 139.787376 -289.145726) (xy 139.736576 -289.145726)
			(xy 139.736576 -289.408616) (xy 139.787376 -289.408616)
		)
		(stroke
			(width 0)
			(type solid)
		)
		(fill yes)
		(layer "F.Cu")
		(net "M_E_CPU1_SA_DQ<1>")
	)
	(gr_poly
		(pts
			(xy 139.888976 -288.775394) (xy 139.888976 -288.584894) (xy 139.787376 -288.548826) (xy 139.736576 -288.548826)
			(xy 139.736576 -288.811716) (xy 139.787376 -288.811716)
		)
		(stroke
			(width 0)
			(type solid)
		)
		(fill yes)
		(layer "F.Cu")
		(net "M_E_CPU1_SA_DQ<1>")
	)
	(gr_poly
		(pts
			(xy 139.888976 -288.178494) (xy 139.888976 -287.987994) (xy 139.787376 -287.951926) (xy 139.736576 -287.951926)
			(xy 139.736576 -288.214816) (xy 139.787376 -288.214816)
		)
		(stroke
			(width 0)
			(type solid)
		)
		(fill yes)
		(layer "F.Cu")
		(net "M_E_CPU1_SA_DQ<1>")
	)
	(gr_poly
		(pts
			(xy 139.888976 -287.581594) (xy 139.888976 -287.391094) (xy 139.787376 -287.355026) (xy 139.736576 -287.355026)
			(xy 139.736576 -287.617916) (xy 139.787376 -287.617916)
		)
		(stroke
			(width 0)
			(type solid)
		)
		(fill yes)
		(layer "F.Cu")
		(net "M_E_CPU1_SA_DQ<1>")
	)
	(gr_poly
		(pts
			(xy 139.888976 -286.984694) (xy 139.888976 -286.794194) (xy 139.787376 -286.758126) (xy 139.736576 -286.758126)
			(xy 139.736576 -287.021016) (xy 139.787376 -287.021016)
		)
		(stroke
			(width 0)
			(type solid)
		)
		(fill yes)
		(layer "F.Cu")
		(net "M_E_CPU1_SA_DQ<1>")
	)
	(gr_poly
		(pts
			(xy 139.888976 -286.387794) (xy 139.888976 -286.197294) (xy 139.787376 -286.161226) (xy 139.736576 -286.161226)
			(xy 139.736576 -286.424116) (xy 139.787376 -286.424116)
		)
		(stroke
			(width 0)
			(type solid)
		)
		(fill yes)
		(layer "F.Cu")
		(net "M_E_CPU1_SA_DQ<1>")
	)
	(gr_poly
		(pts
			(xy 139.888976 -285.790894) (xy 139.888976 -285.600394) (xy 139.787376 -285.564326) (xy 139.736576 -285.564326)
			(xy 139.736576 -285.827216) (xy 139.787376 -285.827216)
		)
		(stroke
			(width 0)
			(type solid)
		)
		(fill yes)
		(layer "F.Cu")
		(net "M_E_CPU1_SA_DQ<1>")
	)
	(gr_poly
		(pts
			(xy 139.888976 -285.193994) (xy 139.888976 -285.003494) (xy 139.787376 -284.967426) (xy 139.736576 -284.967426)
			(xy 139.736576 -285.230316) (xy 139.787376 -285.230316)
		)
		(stroke
			(width 0)
			(type solid)
		)
		(fill yes)
		(layer "F.Cu")
		(net "M_E_CPU1_SA_DQ<1>")
	)
	(gr_poly
		(pts
			(xy 139.888976 -284.597094) (xy 139.888976 -284.406594) (xy 139.787376 -284.370526) (xy 139.736576 -284.370526)
			(xy 139.736576 -284.633416) (xy 139.787376 -284.633416)
		)
		(stroke
			(width 0)
			(type solid)
		)
		(fill yes)
		(layer "F.Cu")
		(net "M_E_CPU1_SA_DQ<1>")
	)
	(gr_poly
		(pts
			(xy 139.888976 -284.000194) (xy 139.888976 -283.809694) (xy 139.787376 -283.773626) (xy 139.736576 -283.773626)
			(xy 139.736576 -284.036516) (xy 139.787376 -284.036516)
		)
		(stroke
			(width 0)
			(type solid)
		)
		(fill yes)
		(layer "F.Cu")
		(net "M_E_CPU1_SA_DQ<1>")
	)
	(gr_poly
		(pts
			(xy 139.888976 -283.403294) (xy 139.888976 -283.212794) (xy 139.787376 -283.176726) (xy 139.736576 -283.176726)
			(xy 139.736576 -283.439616) (xy 139.787376 -283.439616)
		)
		(stroke
			(width 0)
			(type solid)
		)
		(fill yes)
		(layer "F.Cu")
		(net "M_E_CPU1_SA_DQ<1>")
	)
	(gr_poly
		(pts
			(xy 139.888976 -282.806394) (xy 139.888976 -282.615894) (xy 139.787376 -282.579826) (xy 139.736576 -282.579826)
			(xy 139.736576 -282.842716) (xy 139.787376 -282.842716)
		)
		(stroke
			(width 0)
			(type solid)
		)
		(fill yes)
		(layer "F.Cu")
		(net "M_E_CPU1_SA_DQ<1>")
	)
	(gr_poly
		(pts
			(xy 139.888976 -282.209494) (xy 139.888976 -282.018994) (xy 139.787376 -281.982926) (xy 139.736576 -281.982926)
			(xy 139.736576 -282.245816) (xy 139.787376 -282.245816)
		)
		(stroke
			(width 0)
			(type solid)
		)
		(fill yes)
		(layer "F.Cu")
		(net "M_E_CPU1_SA_DQ<1>")
	)
	(gr_poly
		(pts
			(xy 139.888976 -281.612594) (xy 139.888976 -281.422094) (xy 139.787376 -281.386026) (xy 139.736576 -281.386026)
			(xy 139.736576 -281.648916) (xy 139.787376 -281.648916)
		)
		(stroke
			(width 0)
			(type solid)
		)
		(fill yes)
		(layer "F.Cu")
		(net "M_E_CPU1_SA_DQ<1>")
	)
	(gr_poly
		(pts
			(xy 140.011912 -224.61093) (xy 139.961112 -224.61093) (xy 139.859512 -224.646998) (xy 139.859512 -224.837498)
			(xy 139.961112 -224.87382) (xy 140.011912 -224.87382)
		)
		(stroke
			(width 0)
			(type solid)
		)
		(fill yes)
		(layer "F.Cu")
		(net "M_E_CPU1_SB_DQ<29>")
	)
	(gr_poly
		(pts
			(xy 140.011912 -224.01403) (xy 139.961112 -224.01403) (xy 139.859512 -224.050098) (xy 139.859512 -224.240598)
			(xy 139.961112 -224.27692) (xy 140.011912 -224.27692)
		)
		(stroke
			(width 0)
			(type solid)
		)
		(fill yes)
		(layer "F.Cu")
		(net "M_E_CPU1_SB_DQ<29>")
	)
	(gr_poly
		(pts
			(xy 140.011912 -223.41713) (xy 139.961112 -223.41713) (xy 139.859512 -223.453198) (xy 139.859512 -223.643698)
			(xy 139.961112 -223.68002) (xy 140.011912 -223.68002)
		)
		(stroke
			(width 0)
			(type solid)
		)
		(fill yes)
		(layer "F.Cu")
		(net "M_E_CPU1_SB_DQ<29>")
	)
	(gr_poly
		(pts
			(xy 140.011912 -222.82023) (xy 139.961112 -222.82023) (xy 139.859512 -222.856298) (xy 139.859512 -223.046798)
			(xy 139.961112 -223.08312) (xy 140.011912 -223.08312)
		)
		(stroke
			(width 0)
			(type solid)
		)
		(fill yes)
		(layer "F.Cu")
		(net "M_E_CPU1_SB_DQ<29>")
	)
	(gr_poly
		(pts
			(xy 140.011912 -222.22333) (xy 139.961112 -222.22333) (xy 139.859512 -222.259398) (xy 139.859512 -222.449898)
			(xy 139.961112 -222.48622) (xy 140.011912 -222.48622)
		)
		(stroke
			(width 0)
			(type solid)
		)
		(fill yes)
		(layer "F.Cu")
		(net "M_E_CPU1_SB_DQ<29>")
	)
	(gr_poly
		(pts
			(xy 140.011912 -221.62643) (xy 139.961112 -221.62643) (xy 139.859512 -221.662498) (xy 139.859512 -221.852998)
			(xy 139.961112 -221.88932) (xy 140.011912 -221.88932)
		)
		(stroke
			(width 0)
			(type solid)
		)
		(fill yes)
		(layer "F.Cu")
		(net "M_E_CPU1_SB_DQ<29>")
	)
	(gr_poly
		(pts
			(xy 140.011912 -221.02953) (xy 139.961112 -221.02953) (xy 139.859512 -221.065598) (xy 139.859512 -221.256098)
			(xy 139.961112 -221.29242) (xy 140.011912 -221.29242)
		)
		(stroke
			(width 0)
			(type solid)
		)
		(fill yes)
		(layer "F.Cu")
		(net "M_E_CPU1_SB_DQ<29>")
	)
	(gr_poly
		(pts
			(xy 140.011912 -220.43263) (xy 139.961112 -220.43263) (xy 139.859512 -220.468698) (xy 139.859512 -220.659198)
			(xy 139.961112 -220.69552) (xy 140.011912 -220.69552)
		)
		(stroke
			(width 0)
			(type solid)
		)
		(fill yes)
		(layer "F.Cu")
		(net "M_E_CPU1_SB_DQ<29>")
	)
	(gr_poly
		(pts
			(xy 140.011912 -219.83573) (xy 139.961112 -219.83573) (xy 139.859512 -219.871798) (xy 139.859512 -220.062298)
			(xy 139.961112 -220.09862) (xy 140.011912 -220.09862)
		)
		(stroke
			(width 0)
			(type solid)
		)
		(fill yes)
		(layer "F.Cu")
		(net "M_E_CPU1_SB_DQ<29>")
	)
	(gr_poly
		(pts
			(xy 140.011912 -219.23883) (xy 139.961112 -219.23883) (xy 139.859512 -219.274898) (xy 139.859512 -219.465398)
			(xy 139.961112 -219.50172) (xy 140.011912 -219.50172)
		)
		(stroke
			(width 0)
			(type solid)
		)
		(fill yes)
		(layer "F.Cu")
		(net "M_E_CPU1_SB_DQ<29>")
	)
	(gr_poly
		(pts
			(xy 140.011912 -218.64193) (xy 139.961112 -218.64193) (xy 139.859512 -218.677998) (xy 139.859512 -218.868498)
			(xy 139.961112 -218.90482) (xy 140.011912 -218.90482)
		)
		(stroke
			(width 0)
			(type solid)
		)
		(fill yes)
		(layer "F.Cu")
		(net "M_E_CPU1_SB_DQ<29>")
	)
	(gr_poly
		(pts
			(xy 140.011912 -218.04503) (xy 139.961112 -218.04503) (xy 139.859512 -218.081098) (xy 139.859512 -218.271598)
			(xy 139.961112 -218.30792) (xy 140.011912 -218.30792)
		)
		(stroke
			(width 0)
			(type solid)
		)
		(fill yes)
		(layer "F.Cu")
		(net "M_E_CPU1_SB_DQ<29>")
	)
	(gr_poly
		(pts
			(xy 140.011912 -217.44813) (xy 139.961112 -217.44813) (xy 139.859512 -217.484198) (xy 139.859512 -217.674698)
			(xy 139.961112 -217.71102) (xy 140.011912 -217.71102)
		)
		(stroke
			(width 0)
			(type solid)
		)
		(fill yes)
		(layer "F.Cu")
		(net "M_E_CPU1_SB_DQ<29>")
	)
	(gr_poly
		(pts
			(xy 140.011912 -216.85123) (xy 139.961112 -216.85123) (xy 139.859512 -216.887298) (xy 139.859512 -217.077798)
			(xy 139.961112 -217.11412) (xy 140.011912 -217.11412)
		)
		(stroke
			(width 0)
			(type solid)
		)
		(fill yes)
		(layer "F.Cu")
		(net "M_E_CPU1_SB_DQ<29>")
	)
	(gr_poly
		(pts
			(xy 140.011912 -216.25433) (xy 139.961112 -216.25433) (xy 139.859512 -216.290398) (xy 139.859512 -216.480898)
			(xy 139.961112 -216.51722) (xy 140.011912 -216.51722)
		)
		(stroke
			(width 0)
			(type solid)
		)
		(fill yes)
		(layer "F.Cu")
		(net "M_E_CPU1_SB_DQ<29>")
	)
	(gr_poly
		(pts
			(xy 140.011912 -215.65743) (xy 139.961112 -215.65743) (xy 139.859512 -215.693498) (xy 139.859512 -215.883998)
			(xy 139.961112 -215.92032) (xy 140.011912 -215.92032)
		)
		(stroke
			(width 0)
			(type solid)
		)
		(fill yes)
		(layer "F.Cu")
		(net "M_E_CPU1_SB_DQ<29>")
	)
	(gr_poly
		(pts
			(xy 140.041376 -295.413176) (xy 139.990576 -295.413176) (xy 139.888976 -295.449498) (xy 139.888976 -295.639998)
			(xy 139.990576 -295.676066) (xy 140.041376 -295.676066)
		)
		(stroke
			(width 0)
			(type solid)
		)
		(fill yes)
		(layer "F.Cu")
		(net "M_E_CPU1_SA_DQ<3>")
	)
	(gr_poly
		(pts
			(xy 140.041376 -294.816276) (xy 139.990576 -294.816276) (xy 139.888976 -294.852598) (xy 139.888976 -295.043098)
			(xy 139.990576 -295.079166) (xy 140.041376 -295.079166)
		)
		(stroke
			(width 0)
			(type solid)
		)
		(fill yes)
		(layer "F.Cu")
		(net "M_E_CPU1_SA_DQ<3>")
	)
	(gr_poly
		(pts
			(xy 140.041376 -294.219376) (xy 139.990576 -294.219376) (xy 139.888976 -294.255698) (xy 139.888976 -294.446198)
			(xy 139.990576 -294.482266) (xy 140.041376 -294.482266)
		)
		(stroke
			(width 0)
			(type solid)
		)
		(fill yes)
		(layer "F.Cu")
		(net "M_E_CPU1_SA_DQ<3>")
	)
	(gr_poly
		(pts
			(xy 140.041376 -293.622476) (xy 139.990576 -293.622476) (xy 139.888976 -293.658798) (xy 139.888976 -293.849298)
			(xy 139.990576 -293.885366) (xy 140.041376 -293.885366)
		)
		(stroke
			(width 0)
			(type solid)
		)
		(fill yes)
		(layer "F.Cu")
		(net "M_E_CPU1_SA_DQ<3>")
	)
	(gr_poly
		(pts
			(xy 140.041376 -293.025576) (xy 139.990576 -293.025576) (xy 139.888976 -293.061898) (xy 139.888976 -293.252398)
			(xy 139.990576 -293.288466) (xy 140.041376 -293.288466)
		)
		(stroke
			(width 0)
			(type solid)
		)
		(fill yes)
		(layer "F.Cu")
		(net "M_E_CPU1_SA_DQ<3>")
	)
	(gr_poly
		(pts
			(xy 140.041376 -292.428676) (xy 139.990576 -292.428676) (xy 139.888976 -292.464998) (xy 139.888976 -292.655498)
			(xy 139.990576 -292.691566) (xy 140.041376 -292.691566)
		)
		(stroke
			(width 0)
			(type solid)
		)
		(fill yes)
		(layer "F.Cu")
		(net "M_E_CPU1_SA_DQ<3>")
	)
	(gr_poly
		(pts
			(xy 140.041376 -291.831776) (xy 139.990576 -291.831776) (xy 139.888976 -291.868098) (xy 139.888976 -292.058598)
			(xy 139.990576 -292.094666) (xy 140.041376 -292.094666)
		)
		(stroke
			(width 0)
			(type solid)
		)
		(fill yes)
		(layer "F.Cu")
		(net "M_E_CPU1_SA_DQ<3>")
	)
	(gr_poly
		(pts
			(xy 140.041376 -291.234876) (xy 139.990576 -291.234876) (xy 139.888976 -291.271198) (xy 139.888976 -291.461698)
			(xy 139.990576 -291.497766) (xy 140.041376 -291.497766)
		)
		(stroke
			(width 0)
			(type solid)
		)
		(fill yes)
		(layer "F.Cu")
		(net "M_E_CPU1_SA_DQ<3>")
	)
	(gr_poly
		(pts
			(xy 140.041376 -290.637976) (xy 139.990576 -290.637976) (xy 139.888976 -290.674298) (xy 139.888976 -290.864798)
			(xy 139.990576 -290.900866) (xy 140.041376 -290.900866)
		)
		(stroke
			(width 0)
			(type solid)
		)
		(fill yes)
		(layer "F.Cu")
		(net "M_E_CPU1_SA_DQ<3>")
	)
	(gr_poly
		(pts
			(xy 140.041376 -290.041076) (xy 139.990576 -290.041076) (xy 139.888976 -290.077398) (xy 139.888976 -290.267898)
			(xy 139.990576 -290.303966) (xy 140.041376 -290.303966)
		)
		(stroke
			(width 0)
			(type solid)
		)
		(fill yes)
		(layer "F.Cu")
		(net "M_E_CPU1_SA_DQ<3>")
	)
	(gr_poly
		(pts
			(xy 140.041376 -289.444176) (xy 139.990576 -289.444176) (xy 139.888976 -289.480498) (xy 139.888976 -289.670998)
			(xy 139.990576 -289.707066) (xy 140.041376 -289.707066)
		)
		(stroke
			(width 0)
			(type solid)
		)
		(fill yes)
		(layer "F.Cu")
		(net "M_E_CPU1_SA_DQ<3>")
	)
	(gr_poly
		(pts
			(xy 140.041376 -288.847276) (xy 139.990576 -288.847276) (xy 139.888976 -288.883598) (xy 139.888976 -289.074098)
			(xy 139.990576 -289.110166) (xy 140.041376 -289.110166)
		)
		(stroke
			(width 0)
			(type solid)
		)
		(fill yes)
		(layer "F.Cu")
		(net "M_E_CPU1_SA_DQ<3>")
	)
	(gr_poly
		(pts
			(xy 140.041376 -288.250376) (xy 139.990576 -288.250376) (xy 139.888976 -288.286698) (xy 139.888976 -288.477198)
			(xy 139.990576 -288.513266) (xy 140.041376 -288.513266)
		)
		(stroke
			(width 0)
			(type solid)
		)
		(fill yes)
		(layer "F.Cu")
		(net "M_E_CPU1_SA_DQ<3>")
	)
	(gr_poly
		(pts
			(xy 140.041376 -287.653476) (xy 139.990576 -287.653476) (xy 139.888976 -287.689798) (xy 139.888976 -287.880298)
			(xy 139.990576 -287.916366) (xy 140.041376 -287.916366)
		)
		(stroke
			(width 0)
			(type solid)
		)
		(fill yes)
		(layer "F.Cu")
		(net "M_E_CPU1_SA_DQ<3>")
	)
	(gr_poly
		(pts
			(xy 140.041376 -287.056576) (xy 139.990576 -287.056576) (xy 139.888976 -287.092898) (xy 139.888976 -287.283398)
			(xy 139.990576 -287.319466) (xy 140.041376 -287.319466)
		)
		(stroke
			(width 0)
			(type solid)
		)
		(fill yes)
		(layer "F.Cu")
		(net "M_E_CPU1_SA_DQ<3>")
	)
	(gr_poly
		(pts
			(xy 140.041376 -286.459676) (xy 139.990576 -286.459676) (xy 139.888976 -286.495998) (xy 139.888976 -286.686498)
			(xy 139.990576 -286.722566) (xy 140.041376 -286.722566)
		)
		(stroke
			(width 0)
			(type solid)
		)
		(fill yes)
		(layer "F.Cu")
		(net "M_E_CPU1_SA_DQ<3>")
	)
	(gr_poly
		(pts
			(xy 140.041376 -285.862776) (xy 139.990576 -285.862776) (xy 139.888976 -285.899098) (xy 139.888976 -286.089598)
			(xy 139.990576 -286.125666) (xy 140.041376 -286.125666)
		)
		(stroke
			(width 0)
			(type solid)
		)
		(fill yes)
		(layer "F.Cu")
		(net "M_E_CPU1_SA_DQ<3>")
	)
	(gr_poly
		(pts
			(xy 140.041376 -285.265876) (xy 139.990576 -285.265876) (xy 139.888976 -285.302198) (xy 139.888976 -285.492698)
			(xy 139.990576 -285.528766) (xy 140.041376 -285.528766)
		)
		(stroke
			(width 0)
			(type solid)
		)
		(fill yes)
		(layer "F.Cu")
		(net "M_E_CPU1_SA_DQ<3>")
	)
	(gr_poly
		(pts
			(xy 140.041376 -284.668976) (xy 139.990576 -284.668976) (xy 139.888976 -284.705298) (xy 139.888976 -284.895798)
			(xy 139.990576 -284.931866) (xy 140.041376 -284.931866)
		)
		(stroke
			(width 0)
			(type solid)
		)
		(fill yes)
		(layer "F.Cu")
		(net "M_E_CPU1_SA_DQ<3>")
	)
	(gr_poly
		(pts
			(xy 140.041376 -284.072076) (xy 139.990576 -284.072076) (xy 139.888976 -284.108398) (xy 139.888976 -284.298898)
			(xy 139.990576 -284.334966) (xy 140.041376 -284.334966)
		)
		(stroke
			(width 0)
			(type solid)
		)
		(fill yes)
		(layer "F.Cu")
		(net "M_E_CPU1_SA_DQ<3>")
	)
	(gr_poly
		(pts
			(xy 140.041376 -283.475176) (xy 139.990576 -283.475176) (xy 139.888976 -283.511498) (xy 139.888976 -283.701998)
			(xy 139.990576 -283.738066) (xy 140.041376 -283.738066)
		)
		(stroke
			(width 0)
			(type solid)
		)
		(fill yes)
		(layer "F.Cu")
		(net "M_E_CPU1_SA_DQ<3>")
	)
	(gr_poly
		(pts
			(xy 140.041376 -282.878276) (xy 139.990576 -282.878276) (xy 139.888976 -282.914598) (xy 139.888976 -283.105098)
			(xy 139.990576 -283.141166) (xy 140.041376 -283.141166)
		)
		(stroke
			(width 0)
			(type solid)
		)
		(fill yes)
		(layer "F.Cu")
		(net "M_E_CPU1_SA_DQ<3>")
	)
	(gr_poly
		(pts
			(xy 140.041376 -282.281376) (xy 139.990576 -282.281376) (xy 139.888976 -282.317698) (xy 139.888976 -282.508198)
			(xy 139.990576 -282.544266) (xy 140.041376 -282.544266)
		)
		(stroke
			(width 0)
			(type solid)
		)
		(fill yes)
		(layer "F.Cu")
		(net "M_E_CPU1_SA_DQ<3>")
	)
	(gr_poly
		(pts
			(xy 140.041376 -281.684476) (xy 139.990576 -281.684476) (xy 139.888976 -281.720798) (xy 139.888976 -281.911298)
			(xy 139.990576 -281.947366) (xy 140.041376 -281.947366)
		)
		(stroke
			(width 0)
			(type solid)
		)
		(fill yes)
		(layer "F.Cu")
		(net "M_E_CPU1_SA_DQ<3>")
	)
	(gr_poly
		(pts
			(xy 140.164312 -224.539302) (xy 140.164312 -224.348802) (xy 140.062712 -224.31248) (xy 140.011912 -224.31248)
			(xy 140.011912 -224.57537) (xy 140.062712 -224.57537)
		)
		(stroke
			(width 0)
			(type solid)
		)
		(fill yes)
		(layer "F.Cu")
		(net "M_E_CPU1_SB_DQ<29>")
	)
	(gr_poly
		(pts
			(xy 140.164312 -223.942402) (xy 140.164312 -223.751902) (xy 140.062712 -223.71558) (xy 140.011912 -223.71558)
			(xy 140.011912 -223.97847) (xy 140.062712 -223.97847)
		)
		(stroke
			(width 0)
			(type solid)
		)
		(fill yes)
		(layer "F.Cu")
		(net "M_E_CPU1_SB_DQ<29>")
	)
	(gr_poly
		(pts
			(xy 140.164312 -223.345502) (xy 140.164312 -223.155002) (xy 140.062712 -223.11868) (xy 140.011912 -223.11868)
			(xy 140.011912 -223.38157) (xy 140.062712 -223.38157)
		)
		(stroke
			(width 0)
			(type solid)
		)
		(fill yes)
		(layer "F.Cu")
		(net "M_E_CPU1_SB_DQ<29>")
	)
	(gr_poly
		(pts
			(xy 140.164312 -222.748602) (xy 140.164312 -222.558102) (xy 140.062712 -222.52178) (xy 140.011912 -222.52178)
			(xy 140.011912 -222.78467) (xy 140.062712 -222.78467)
		)
		(stroke
			(width 0)
			(type solid)
		)
		(fill yes)
		(layer "F.Cu")
		(net "M_E_CPU1_SB_DQ<29>")
	)
	(gr_poly
		(pts
			(xy 140.164312 -222.151702) (xy 140.164312 -221.961202) (xy 140.062712 -221.92488) (xy 140.011912 -221.92488)
			(xy 140.011912 -222.18777) (xy 140.062712 -222.18777)
		)
		(stroke
			(width 0)
			(type solid)
		)
		(fill yes)
		(layer "F.Cu")
		(net "M_E_CPU1_SB_DQ<29>")
	)
	(gr_poly
		(pts
			(xy 140.164312 -221.554802) (xy 140.164312 -221.364302) (xy 140.062712 -221.32798) (xy 140.011912 -221.32798)
			(xy 140.011912 -221.59087) (xy 140.062712 -221.59087)
		)
		(stroke
			(width 0)
			(type solid)
		)
		(fill yes)
		(layer "F.Cu")
		(net "M_E_CPU1_SB_DQ<29>")
	)
	(gr_poly
		(pts
			(xy 140.164312 -220.957902) (xy 140.164312 -220.767402) (xy 140.062712 -220.73108) (xy 140.011912 -220.73108)
			(xy 140.011912 -220.99397) (xy 140.062712 -220.99397)
		)
		(stroke
			(width 0)
			(type solid)
		)
		(fill yes)
		(layer "F.Cu")
		(net "M_E_CPU1_SB_DQ<29>")
	)
	(gr_poly
		(pts
			(xy 140.164312 -220.361002) (xy 140.164312 -220.170502) (xy 140.062712 -220.13418) (xy 140.011912 -220.13418)
			(xy 140.011912 -220.39707) (xy 140.062712 -220.39707)
		)
		(stroke
			(width 0)
			(type solid)
		)
		(fill yes)
		(layer "F.Cu")
		(net "M_E_CPU1_SB_DQ<29>")
	)
	(gr_poly
		(pts
			(xy 140.164312 -219.764102) (xy 140.164312 -219.573602) (xy 140.062712 -219.53728) (xy 140.011912 -219.53728)
			(xy 140.011912 -219.80017) (xy 140.062712 -219.80017)
		)
		(stroke
			(width 0)
			(type solid)
		)
		(fill yes)
		(layer "F.Cu")
		(net "M_E_CPU1_SB_DQ<29>")
	)
	(gr_poly
		(pts
			(xy 140.164312 -219.167202) (xy 140.164312 -218.976702) (xy 140.062712 -218.94038) (xy 140.011912 -218.94038)
			(xy 140.011912 -219.20327) (xy 140.062712 -219.20327)
		)
		(stroke
			(width 0)
			(type solid)
		)
		(fill yes)
		(layer "F.Cu")
		(net "M_E_CPU1_SB_DQ<29>")
	)
	(gr_poly
		(pts
			(xy 140.164312 -218.570302) (xy 140.164312 -218.379802) (xy 140.062712 -218.34348) (xy 140.011912 -218.34348)
			(xy 140.011912 -218.60637) (xy 140.062712 -218.60637)
		)
		(stroke
			(width 0)
			(type solid)
		)
		(fill yes)
		(layer "F.Cu")
		(net "M_E_CPU1_SB_DQ<29>")
	)
	(gr_poly
		(pts
			(xy 140.164312 -217.973402) (xy 140.164312 -217.782902) (xy 140.062712 -217.74658) (xy 140.011912 -217.74658)
			(xy 140.011912 -218.00947) (xy 140.062712 -218.00947)
		)
		(stroke
			(width 0)
			(type solid)
		)
		(fill yes)
		(layer "F.Cu")
		(net "M_E_CPU1_SB_DQ<29>")
	)
	(gr_poly
		(pts
			(xy 140.164312 -217.376502) (xy 140.164312 -217.186002) (xy 140.062712 -217.14968) (xy 140.011912 -217.14968)
			(xy 140.011912 -217.41257) (xy 140.062712 -217.41257)
		)
		(stroke
			(width 0)
			(type solid)
		)
		(fill yes)
		(layer "F.Cu")
		(net "M_E_CPU1_SB_DQ<29>")
	)
	(gr_poly
		(pts
			(xy 140.164312 -216.779602) (xy 140.164312 -216.589102) (xy 140.062712 -216.55278) (xy 140.011912 -216.55278)
			(xy 140.011912 -216.81567) (xy 140.062712 -216.81567)
		)
		(stroke
			(width 0)
			(type solid)
		)
		(fill yes)
		(layer "F.Cu")
		(net "M_E_CPU1_SB_DQ<29>")
	)
	(gr_poly
		(pts
			(xy 140.164312 -216.182702) (xy 140.164312 -215.992202) (xy 140.062712 -215.95588) (xy 140.011912 -215.95588)
			(xy 140.011912 -216.21877) (xy 140.062712 -216.21877)
		)
		(stroke
			(width 0)
			(type solid)
		)
		(fill yes)
		(layer "F.Cu")
		(net "M_E_CPU1_SB_DQ<29>")
	)
	(gr_poly
		(pts
			(xy 140.164312 -215.585802) (xy 140.164312 -215.395302) (xy 140.062712 -215.35898) (xy 140.011912 -215.35898)
			(xy 140.011912 -215.62187) (xy 140.062712 -215.62187)
		)
		(stroke
			(width 0)
			(type solid)
		)
		(fill yes)
		(layer "F.Cu")
		(net "M_E_CPU1_SB_DQ<29>")
	)
	(gr_poly
		(pts
			(xy 140.193776 -295.341294) (xy 140.193776 -295.150794) (xy 140.092176 -295.114726) (xy 140.041376 -295.114726)
			(xy 140.041376 -295.377616) (xy 140.092176 -295.377616)
		)
		(stroke
			(width 0)
			(type solid)
		)
		(fill yes)
		(layer "F.Cu")
		(net "M_E_CPU1_SA_DQ<3>")
	)
	(gr_poly
		(pts
			(xy 140.193776 -294.744394) (xy 140.193776 -294.553894) (xy 140.092176 -294.517826) (xy 140.041376 -294.517826)
			(xy 140.041376 -294.780716) (xy 140.092176 -294.780716)
		)
		(stroke
			(width 0)
			(type solid)
		)
		(fill yes)
		(layer "F.Cu")
		(net "M_E_CPU1_SA_DQ<3>")
	)
	(gr_poly
		(pts
			(xy 140.193776 -294.147494) (xy 140.193776 -293.956994) (xy 140.092176 -293.920926) (xy 140.041376 -293.920926)
			(xy 140.041376 -294.183816) (xy 140.092176 -294.183816)
		)
		(stroke
			(width 0)
			(type solid)
		)
		(fill yes)
		(layer "F.Cu")
		(net "M_E_CPU1_SA_DQ<3>")
	)
	(gr_poly
		(pts
			(xy 140.193776 -293.550594) (xy 140.193776 -293.360094) (xy 140.092176 -293.324026) (xy 140.041376 -293.324026)
			(xy 140.041376 -293.586916) (xy 140.092176 -293.586916)
		)
		(stroke
			(width 0)
			(type solid)
		)
		(fill yes)
		(layer "F.Cu")
		(net "M_E_CPU1_SA_DQ<3>")
	)
	(gr_poly
		(pts
			(xy 140.193776 -292.953694) (xy 140.193776 -292.763194) (xy 140.092176 -292.727126) (xy 140.041376 -292.727126)
			(xy 140.041376 -292.990016) (xy 140.092176 -292.990016)
		)
		(stroke
			(width 0)
			(type solid)
		)
		(fill yes)
		(layer "F.Cu")
		(net "M_E_CPU1_SA_DQ<3>")
	)
	(gr_poly
		(pts
			(xy 140.193776 -292.356794) (xy 140.193776 -292.166294) (xy 140.092176 -292.130226) (xy 140.041376 -292.130226)
			(xy 140.041376 -292.393116) (xy 140.092176 -292.393116)
		)
		(stroke
			(width 0)
			(type solid)
		)
		(fill yes)
		(layer "F.Cu")
		(net "M_E_CPU1_SA_DQ<3>")
	)
	(gr_poly
		(pts
			(xy 140.193776 -291.759894) (xy 140.193776 -291.569394) (xy 140.092176 -291.533326) (xy 140.041376 -291.533326)
			(xy 140.041376 -291.796216) (xy 140.092176 -291.796216)
		)
		(stroke
			(width 0)
			(type solid)
		)
		(fill yes)
		(layer "F.Cu")
		(net "M_E_CPU1_SA_DQ<3>")
	)
	(gr_poly
		(pts
			(xy 140.193776 -291.162994) (xy 140.193776 -290.972494) (xy 140.092176 -290.936426) (xy 140.041376 -290.936426)
			(xy 140.041376 -291.199316) (xy 140.092176 -291.199316)
		)
		(stroke
			(width 0)
			(type solid)
		)
		(fill yes)
		(layer "F.Cu")
		(net "M_E_CPU1_SA_DQ<3>")
	)
	(gr_poly
		(pts
			(xy 140.193776 -290.566094) (xy 140.193776 -290.375594) (xy 140.092176 -290.339526) (xy 140.041376 -290.339526)
			(xy 140.041376 -290.602416) (xy 140.092176 -290.602416)
		)
		(stroke
			(width 0)
			(type solid)
		)
		(fill yes)
		(layer "F.Cu")
		(net "M_E_CPU1_SA_DQ<3>")
	)
	(gr_poly
		(pts
			(xy 140.193776 -289.969194) (xy 140.193776 -289.778694) (xy 140.092176 -289.742626) (xy 140.041376 -289.742626)
			(xy 140.041376 -290.005516) (xy 140.092176 -290.005516)
		)
		(stroke
			(width 0)
			(type solid)
		)
		(fill yes)
		(layer "F.Cu")
		(net "M_E_CPU1_SA_DQ<3>")
	)
	(gr_poly
		(pts
			(xy 140.193776 -289.372294) (xy 140.193776 -289.181794) (xy 140.092176 -289.145726) (xy 140.041376 -289.145726)
			(xy 140.041376 -289.408616) (xy 140.092176 -289.408616)
		)
		(stroke
			(width 0)
			(type solid)
		)
		(fill yes)
		(layer "F.Cu")
		(net "M_E_CPU1_SA_DQ<3>")
	)
	(gr_poly
		(pts
			(xy 140.193776 -288.775394) (xy 140.193776 -288.584894) (xy 140.092176 -288.548826) (xy 140.041376 -288.548826)
			(xy 140.041376 -288.811716) (xy 140.092176 -288.811716)
		)
		(stroke
			(width 0)
			(type solid)
		)
		(fill yes)
		(layer "F.Cu")
		(net "M_E_CPU1_SA_DQ<3>")
	)
	(gr_poly
		(pts
			(xy 140.193776 -288.178494) (xy 140.193776 -287.987994) (xy 140.092176 -287.951926) (xy 140.041376 -287.951926)
			(xy 140.041376 -288.214816) (xy 140.092176 -288.214816)
		)
		(stroke
			(width 0)
			(type solid)
		)
		(fill yes)
		(layer "F.Cu")
		(net "M_E_CPU1_SA_DQ<3>")
	)
	(gr_poly
		(pts
			(xy 140.193776 -287.581594) (xy 140.193776 -287.391094) (xy 140.092176 -287.355026) (xy 140.041376 -287.355026)
			(xy 140.041376 -287.617916) (xy 140.092176 -287.617916)
		)
		(stroke
			(width 0)
			(type solid)
		)
		(fill yes)
		(layer "F.Cu")
		(net "M_E_CPU1_SA_DQ<3>")
	)
	(gr_poly
		(pts
			(xy 140.193776 -286.984694) (xy 140.193776 -286.794194) (xy 140.092176 -286.758126) (xy 140.041376 -286.758126)
			(xy 140.041376 -287.021016) (xy 140.092176 -287.021016)
		)
		(stroke
			(width 0)
			(type solid)
		)
		(fill yes)
		(layer "F.Cu")
		(net "M_E_CPU1_SA_DQ<3>")
	)
	(gr_poly
		(pts
			(xy 140.193776 -286.387794) (xy 140.193776 -286.197294) (xy 140.092176 -286.161226) (xy 140.041376 -286.161226)
			(xy 140.041376 -286.424116) (xy 140.092176 -286.424116)
		)
		(stroke
			(width 0)
			(type solid)
		)
		(fill yes)
		(layer "F.Cu")
		(net "M_E_CPU1_SA_DQ<3>")
	)
	(gr_poly
		(pts
			(xy 140.193776 -285.790894) (xy 140.193776 -285.600394) (xy 140.092176 -285.564326) (xy 140.041376 -285.564326)
			(xy 140.041376 -285.827216) (xy 140.092176 -285.827216)
		)
		(stroke
			(width 0)
			(type solid)
		)
		(fill yes)
		(layer "F.Cu")
		(net "M_E_CPU1_SA_DQ<3>")
	)
	(gr_poly
		(pts
			(xy 140.193776 -285.193994) (xy 140.193776 -285.003494) (xy 140.092176 -284.967426) (xy 140.041376 -284.967426)
			(xy 140.041376 -285.230316) (xy 140.092176 -285.230316)
		)
		(stroke
			(width 0)
			(type solid)
		)
		(fill yes)
		(layer "F.Cu")
		(net "M_E_CPU1_SA_DQ<3>")
	)
	(gr_poly
		(pts
			(xy 140.193776 -284.597094) (xy 140.193776 -284.406594) (xy 140.092176 -284.370526) (xy 140.041376 -284.370526)
			(xy 140.041376 -284.633416) (xy 140.092176 -284.633416)
		)
		(stroke
			(width 0)
			(type solid)
		)
		(fill yes)
		(layer "F.Cu")
		(net "M_E_CPU1_SA_DQ<3>")
	)
	(gr_poly
		(pts
			(xy 140.193776 -284.000194) (xy 140.193776 -283.809694) (xy 140.092176 -283.773626) (xy 140.041376 -283.773626)
			(xy 140.041376 -284.036516) (xy 140.092176 -284.036516)
		)
		(stroke
			(width 0)
			(type solid)
		)
		(fill yes)
		(layer "F.Cu")
		(net "M_E_CPU1_SA_DQ<3>")
	)
	(gr_poly
		(pts
			(xy 140.193776 -283.403294) (xy 140.193776 -283.212794) (xy 140.092176 -283.176726) (xy 140.041376 -283.176726)
			(xy 140.041376 -283.439616) (xy 140.092176 -283.439616)
		)
		(stroke
			(width 0)
			(type solid)
		)
		(fill yes)
		(layer "F.Cu")
		(net "M_E_CPU1_SA_DQ<3>")
	)
	(gr_poly
		(pts
			(xy 140.193776 -282.806394) (xy 140.193776 -282.615894) (xy 140.092176 -282.579826) (xy 140.041376 -282.579826)
			(xy 140.041376 -282.842716) (xy 140.092176 -282.842716)
		)
		(stroke
			(width 0)
			(type solid)
		)
		(fill yes)
		(layer "F.Cu")
		(net "M_E_CPU1_SA_DQ<3>")
	)
	(gr_poly
		(pts
			(xy 140.193776 -282.209494) (xy 140.193776 -282.018994) (xy 140.092176 -281.982926) (xy 140.041376 -281.982926)
			(xy 140.041376 -282.245816) (xy 140.092176 -282.245816)
		)
		(stroke
			(width 0)
			(type solid)
		)
		(fill yes)
		(layer "F.Cu")
		(net "M_E_CPU1_SA_DQ<3>")
	)
	(gr_poly
		(pts
			(xy 140.193776 -281.612594) (xy 140.193776 -281.422094) (xy 140.092176 -281.386026) (xy 140.041376 -281.386026)
			(xy 140.041376 -281.648916) (xy 140.092176 -281.648916)
		)
		(stroke
			(width 0)
			(type solid)
		)
		(fill yes)
		(layer "F.Cu")
		(net "M_E_CPU1_SA_DQ<3>")
	)
	(gr_poly
		(pts
			(xy 140.255498 -276.101048) (xy 140.301726 -276.003766) (xy 140.167106 -275.868892) (xy 140.06957 -275.91512)
			(xy 140.033756 -275.951188) (xy 140.219684 -276.137116)
		)
		(stroke
			(width 0)
			(type solid)
		)
		(fill yes)
		(layer "F.Cu")
		(net "M_E_CPU1_SA_DQ<4>")
	)
	(gr_poly
		(pts
			(xy 140.304012 -268.393418) (xy 140.35024 -268.295882) (xy 140.215366 -268.161262) (xy 140.118084 -268.20749)
			(xy 140.082016 -268.243304) (xy 140.267944 -268.429232)
		)
		(stroke
			(width 0)
			(type solid)
		)
		(fill yes)
		(layer "F.Cu")
		(net "M_E_CPU1_SA_DQ<24>")
	)
	(gr_poly
		(pts
			(xy 140.316712 -224.61093) (xy 140.265912 -224.61093) (xy 140.164312 -224.646998) (xy 140.164312 -224.837498)
			(xy 140.265912 -224.87382) (xy 140.316712 -224.87382)
		)
		(stroke
			(width 0)
			(type solid)
		)
		(fill yes)
		(layer "F.Cu")
		(net "M_E_CPU1_SB_DQ<30>")
	)
	(gr_poly
		(pts
			(xy 140.316712 -224.01403) (xy 140.265912 -224.01403) (xy 140.164312 -224.050098) (xy 140.164312 -224.240598)
			(xy 140.265912 -224.27692) (xy 140.316712 -224.27692)
		)
		(stroke
			(width 0)
			(type solid)
		)
		(fill yes)
		(layer "F.Cu")
		(net "M_E_CPU1_SB_DQ<30>")
	)
	(gr_poly
		(pts
			(xy 140.316712 -223.41713) (xy 140.265912 -223.41713) (xy 140.164312 -223.453198) (xy 140.164312 -223.643698)
			(xy 140.265912 -223.68002) (xy 140.316712 -223.68002)
		)
		(stroke
			(width 0)
			(type solid)
		)
		(fill yes)
		(layer "F.Cu")
		(net "M_E_CPU1_SB_DQ<30>")
	)
	(gr_poly
		(pts
			(xy 140.316712 -222.82023) (xy 140.265912 -222.82023) (xy 140.164312 -222.856298) (xy 140.164312 -223.046798)
			(xy 140.265912 -223.08312) (xy 140.316712 -223.08312)
		)
		(stroke
			(width 0)
			(type solid)
		)
		(fill yes)
		(layer "F.Cu")
		(net "M_E_CPU1_SB_DQ<30>")
	)
	(gr_poly
		(pts
			(xy 140.316712 -222.22333) (xy 140.265912 -222.22333) (xy 140.164312 -222.259398) (xy 140.164312 -222.449898)
			(xy 140.265912 -222.48622) (xy 140.316712 -222.48622)
		)
		(stroke
			(width 0)
			(type solid)
		)
		(fill yes)
		(layer "F.Cu")
		(net "M_E_CPU1_SB_DQ<30>")
	)
	(gr_poly
		(pts
			(xy 140.316712 -221.62643) (xy 140.265912 -221.62643) (xy 140.164312 -221.662498) (xy 140.164312 -221.852998)
			(xy 140.265912 -221.88932) (xy 140.316712 -221.88932)
		)
		(stroke
			(width 0)
			(type solid)
		)
		(fill yes)
		(layer "F.Cu")
		(net "M_E_CPU1_SB_DQ<30>")
	)
	(gr_poly
		(pts
			(xy 140.316712 -221.02953) (xy 140.265912 -221.02953) (xy 140.164312 -221.065598) (xy 140.164312 -221.256098)
			(xy 140.265912 -221.29242) (xy 140.316712 -221.29242)
		)
		(stroke
			(width 0)
			(type solid)
		)
		(fill yes)
		(layer "F.Cu")
		(net "M_E_CPU1_SB_DQ<30>")
	)
	(gr_poly
		(pts
			(xy 140.316712 -220.43263) (xy 140.265912 -220.43263) (xy 140.164312 -220.468698) (xy 140.164312 -220.659198)
			(xy 140.265912 -220.69552) (xy 140.316712 -220.69552)
		)
		(stroke
			(width 0)
			(type solid)
		)
		(fill yes)
		(layer "F.Cu")
		(net "M_E_CPU1_SB_DQ<30>")
	)
	(gr_poly
		(pts
			(xy 140.316712 -219.83573) (xy 140.265912 -219.83573) (xy 140.164312 -219.871798) (xy 140.164312 -220.062298)
			(xy 140.265912 -220.09862) (xy 140.316712 -220.09862)
		)
		(stroke
			(width 0)
			(type solid)
		)
		(fill yes)
		(layer "F.Cu")
		(net "M_E_CPU1_SB_DQ<30>")
	)
	(gr_poly
		(pts
			(xy 140.316712 -219.23883) (xy 140.265912 -219.23883) (xy 140.164312 -219.274898) (xy 140.164312 -219.465398)
			(xy 140.265912 -219.50172) (xy 140.316712 -219.50172)
		)
		(stroke
			(width 0)
			(type solid)
		)
		(fill yes)
		(layer "F.Cu")
		(net "M_E_CPU1_SB_DQ<30>")
	)
	(gr_poly
		(pts
			(xy 140.316712 -218.64193) (xy 140.265912 -218.64193) (xy 140.164312 -218.677998) (xy 140.164312 -218.868498)
			(xy 140.265912 -218.90482) (xy 140.316712 -218.90482)
		)
		(stroke
			(width 0)
			(type solid)
		)
		(fill yes)
		(layer "F.Cu")
		(net "M_E_CPU1_SB_DQ<30>")
	)
	(gr_poly
		(pts
			(xy 140.316712 -218.04503) (xy 140.265912 -218.04503) (xy 140.164312 -218.081098) (xy 140.164312 -218.271598)
			(xy 140.265912 -218.30792) (xy 140.316712 -218.30792)
		)
		(stroke
			(width 0)
			(type solid)
		)
		(fill yes)
		(layer "F.Cu")
		(net "M_E_CPU1_SB_DQ<30>")
	)
	(gr_poly
		(pts
			(xy 140.316712 -217.44813) (xy 140.265912 -217.44813) (xy 140.164312 -217.484198) (xy 140.164312 -217.674698)
			(xy 140.265912 -217.71102) (xy 140.316712 -217.71102)
		)
		(stroke
			(width 0)
			(type solid)
		)
		(fill yes)
		(layer "F.Cu")
		(net "M_E_CPU1_SB_DQ<30>")
	)
	(gr_poly
		(pts
			(xy 140.316712 -216.85123) (xy 140.265912 -216.85123) (xy 140.164312 -216.887298) (xy 140.164312 -217.077798)
			(xy 140.265912 -217.11412) (xy 140.316712 -217.11412)
		)
		(stroke
			(width 0)
			(type solid)
		)
		(fill yes)
		(layer "F.Cu")
		(net "M_E_CPU1_SB_DQ<30>")
	)
	(gr_poly
		(pts
			(xy 140.316712 -216.25433) (xy 140.265912 -216.25433) (xy 140.164312 -216.290398) (xy 140.164312 -216.480898)
			(xy 140.265912 -216.51722) (xy 140.316712 -216.51722)
		)
		(stroke
			(width 0)
			(type solid)
		)
		(fill yes)
		(layer "F.Cu")
		(net "M_E_CPU1_SB_DQ<30>")
	)
	(gr_poly
		(pts
			(xy 140.316712 -215.65743) (xy 140.265912 -215.65743) (xy 140.164312 -215.693498) (xy 140.164312 -215.883998)
			(xy 140.265912 -215.92032) (xy 140.316712 -215.92032)
		)
		(stroke
			(width 0)
			(type solid)
		)
		(fill yes)
		(layer "F.Cu")
		(net "M_E_CPU1_SB_DQ<30>")
	)
	(gr_poly
		(pts
			(xy 140.39469 -276.384004) (xy 140.430504 -276.347936) (xy 140.24483 -276.162262) (xy 140.208762 -276.198076)
			(xy 140.162534 -276.295612) (xy 140.297154 -276.430232)
		)
		(stroke
			(width 0)
			(type solid)
		)
		(fill yes)
		(layer "F.Cu")
		(net "M_E_CPU1_SA_DQ<4>")
	)
	(gr_poly
		(pts
			(xy 140.406374 -275.528024) (xy 140.442442 -275.49221) (xy 140.256514 -275.306282) (xy 140.220446 -275.342096)
			(xy 140.174218 -275.439632) (xy 140.309092 -275.574252)
		)
		(stroke
			(width 0)
			(type solid)
		)
		(fill yes)
		(layer "F.Cu")
		(net "M_E_CPU1_SA_DQ<5>")
	)
	(gr_poly
		(pts
			(xy 140.452348 -267.822934) (xy 140.488162 -267.786866) (xy 140.302234 -267.600938) (xy 140.26642 -267.637006)
			(xy 140.220192 -267.734288) (xy 140.354812 -267.869162)
		)
		(stroke
			(width 0)
			(type solid)
		)
		(fill yes)
		(layer "F.Cu")
		(net "M_E_CPU1_SA_DQ<25>")
	)
	(gr_poly
		(pts
			(xy 140.469112 -224.539302) (xy 140.469112 -224.348802) (xy 140.367512 -224.31248) (xy 140.316712 -224.31248)
			(xy 140.316712 -224.57537) (xy 140.367512 -224.57537)
		)
		(stroke
			(width 0)
			(type solid)
		)
		(fill yes)
		(layer "F.Cu")
		(net "M_E_CPU1_SB_DQ<30>")
	)
	(gr_poly
		(pts
			(xy 140.469112 -223.942402) (xy 140.469112 -223.751902) (xy 140.367512 -223.71558) (xy 140.316712 -223.71558)
			(xy 140.316712 -223.97847) (xy 140.367512 -223.97847)
		)
		(stroke
			(width 0)
			(type solid)
		)
		(fill yes)
		(layer "F.Cu")
		(net "M_E_CPU1_SB_DQ<30>")
	)
	(gr_poly
		(pts
			(xy 140.469112 -223.345502) (xy 140.469112 -223.155002) (xy 140.367512 -223.11868) (xy 140.316712 -223.11868)
			(xy 140.316712 -223.38157) (xy 140.367512 -223.38157)
		)
		(stroke
			(width 0)
			(type solid)
		)
		(fill yes)
		(layer "F.Cu")
		(net "M_E_CPU1_SB_DQ<30>")
	)
	(gr_poly
		(pts
			(xy 140.469112 -222.748602) (xy 140.469112 -222.558102) (xy 140.367512 -222.52178) (xy 140.316712 -222.52178)
			(xy 140.316712 -222.78467) (xy 140.367512 -222.78467)
		)
		(stroke
			(width 0)
			(type solid)
		)
		(fill yes)
		(layer "F.Cu")
		(net "M_E_CPU1_SB_DQ<30>")
	)
	(gr_poly
		(pts
			(xy 140.469112 -222.151702) (xy 140.469112 -221.961202) (xy 140.367512 -221.92488) (xy 140.316712 -221.92488)
			(xy 140.316712 -222.18777) (xy 140.367512 -222.18777)
		)
		(stroke
			(width 0)
			(type solid)
		)
		(fill yes)
		(layer "F.Cu")
		(net "M_E_CPU1_SB_DQ<30>")
	)
	(gr_poly
		(pts
			(xy 140.469112 -221.554802) (xy 140.469112 -221.364302) (xy 140.367512 -221.32798) (xy 140.316712 -221.32798)
			(xy 140.316712 -221.59087) (xy 140.367512 -221.59087)
		)
		(stroke
			(width 0)
			(type solid)
		)
		(fill yes)
		(layer "F.Cu")
		(net "M_E_CPU1_SB_DQ<30>")
	)
	(gr_poly
		(pts
			(xy 140.469112 -220.957902) (xy 140.469112 -220.767402) (xy 140.367512 -220.73108) (xy 140.316712 -220.73108)
			(xy 140.316712 -220.99397) (xy 140.367512 -220.99397)
		)
		(stroke
			(width 0)
			(type solid)
		)
		(fill yes)
		(layer "F.Cu")
		(net "M_E_CPU1_SB_DQ<30>")
	)
	(gr_poly
		(pts
			(xy 140.469112 -220.361002) (xy 140.469112 -220.170502) (xy 140.367512 -220.13418) (xy 140.316712 -220.13418)
			(xy 140.316712 -220.39707) (xy 140.367512 -220.39707)
		)
		(stroke
			(width 0)
			(type solid)
		)
		(fill yes)
		(layer "F.Cu")
		(net "M_E_CPU1_SB_DQ<30>")
	)
	(gr_poly
		(pts
			(xy 140.469112 -219.764102) (xy 140.469112 -219.573602) (xy 140.367512 -219.53728) (xy 140.316712 -219.53728)
			(xy 140.316712 -219.80017) (xy 140.367512 -219.80017)
		)
		(stroke
			(width 0)
			(type solid)
		)
		(fill yes)
		(layer "F.Cu")
		(net "M_E_CPU1_SB_DQ<30>")
	)
	(gr_poly
		(pts
			(xy 140.469112 -219.167202) (xy 140.469112 -218.976702) (xy 140.367512 -218.94038) (xy 140.316712 -218.94038)
			(xy 140.316712 -219.20327) (xy 140.367512 -219.20327)
		)
		(stroke
			(width 0)
			(type solid)
		)
		(fill yes)
		(layer "F.Cu")
		(net "M_E_CPU1_SB_DQ<30>")
	)
	(gr_poly
		(pts
			(xy 140.469112 -218.570302) (xy 140.469112 -218.379802) (xy 140.367512 -218.34348) (xy 140.316712 -218.34348)
			(xy 140.316712 -218.60637) (xy 140.367512 -218.60637)
		)
		(stroke
			(width 0)
			(type solid)
		)
		(fill yes)
		(layer "F.Cu")
		(net "M_E_CPU1_SB_DQ<30>")
	)
	(gr_poly
		(pts
			(xy 140.469112 -217.973402) (xy 140.469112 -217.782902) (xy 140.367512 -217.74658) (xy 140.316712 -217.74658)
			(xy 140.316712 -218.00947) (xy 140.367512 -218.00947)
		)
		(stroke
			(width 0)
			(type solid)
		)
		(fill yes)
		(layer "F.Cu")
		(net "M_E_CPU1_SB_DQ<30>")
	)
	(gr_poly
		(pts
			(xy 140.469112 -217.376502) (xy 140.469112 -217.186002) (xy 140.367512 -217.14968) (xy 140.316712 -217.14968)
			(xy 140.316712 -217.41257) (xy 140.367512 -217.41257)
		)
		(stroke
			(width 0)
			(type solid)
		)
		(fill yes)
		(layer "F.Cu")
		(net "M_E_CPU1_SB_DQ<30>")
	)
	(gr_poly
		(pts
			(xy 140.469112 -216.779602) (xy 140.469112 -216.589102) (xy 140.367512 -216.55278) (xy 140.316712 -216.55278)
			(xy 140.316712 -216.81567) (xy 140.367512 -216.81567)
		)
		(stroke
			(width 0)
			(type solid)
		)
		(fill yes)
		(layer "F.Cu")
		(net "M_E_CPU1_SB_DQ<30>")
	)
	(gr_poly
		(pts
			(xy 140.469112 -216.182702) (xy 140.469112 -215.992202) (xy 140.367512 -215.95588) (xy 140.316712 -215.95588)
			(xy 140.316712 -216.21877) (xy 140.367512 -216.21877)
		)
		(stroke
			(width 0)
			(type solid)
		)
		(fill yes)
		(layer "F.Cu")
		(net "M_E_CPU1_SB_DQ<30>")
	)
	(gr_poly
		(pts
			(xy 140.469112 -215.585802) (xy 140.469112 -215.395302) (xy 140.367512 -215.35898) (xy 140.316712 -215.35898)
			(xy 140.316712 -215.62187) (xy 140.367512 -215.62187)
		)
		(stroke
			(width 0)
			(type solid)
		)
		(fill yes)
		(layer "F.Cu")
		(net "M_E_CPU1_SB_DQ<30>")
	)
	(gr_poly
		(pts
			(xy 140.47216 -275.884386) (xy 140.518388 -275.787104) (xy 140.383768 -275.65223) (xy 140.286232 -275.698458)
			(xy 140.250418 -275.734526) (xy 140.436346 -275.920454)
		)
		(stroke
			(width 0)
			(type solid)
		)
		(fill yes)
		(layer "F.Cu")
		(net "M_E_CPU1_SA_DQ<6>")
	)
	(gr_poly
		(pts
			(xy 140.519658 -268.177772) (xy 140.565886 -268.080236) (xy 140.431012 -267.945616) (xy 140.33373 -267.991844)
			(xy 140.297662 -268.027658) (xy 140.48359 -268.213586)
		)
		(stroke
			(width 0)
			(type solid)
		)
		(fill yes)
		(layer "F.Cu")
		(net "M_E_CPU1_SA_DQ<26>")
	)
	(gr_poly
		(pts
			(xy 140.611352 -276.167342) (xy 140.647166 -276.131274) (xy 140.461492 -275.9456) (xy 140.425424 -275.981414)
			(xy 140.379196 -276.07895) (xy 140.513816 -276.21357)
		)
		(stroke
			(width 0)
			(type solid)
		)
		(fill yes)
		(layer "F.Cu")
		(net "M_E_CPU1_SA_DQ<6>")
	)
	(gr_poly
		(pts
			(xy 140.621512 -224.61093) (xy 140.570712 -224.61093) (xy 140.469112 -224.646998) (xy 140.469112 -224.837498)
			(xy 140.570712 -224.87382) (xy 140.621512 -224.87382)
		)
		(stroke
			(width 0)
			(type solid)
		)
		(fill yes)
		(layer "F.Cu")
		(net "M_E_CPU1_SB_DQ<28>")
	)
	(gr_poly
		(pts
			(xy 140.621512 -224.01403) (xy 140.570712 -224.01403) (xy 140.469112 -224.050098) (xy 140.469112 -224.240598)
			(xy 140.570712 -224.27692) (xy 140.621512 -224.27692)
		)
		(stroke
			(width 0)
			(type solid)
		)
		(fill yes)
		(layer "F.Cu")
		(net "M_E_CPU1_SB_DQ<28>")
	)
	(gr_poly
		(pts
			(xy 140.621512 -223.41713) (xy 140.570712 -223.41713) (xy 140.469112 -223.453198) (xy 140.469112 -223.643698)
			(xy 140.570712 -223.68002) (xy 140.621512 -223.68002)
		)
		(stroke
			(width 0)
			(type solid)
		)
		(fill yes)
		(layer "F.Cu")
		(net "M_E_CPU1_SB_DQ<28>")
	)
	(gr_poly
		(pts
			(xy 140.621512 -222.82023) (xy 140.570712 -222.82023) (xy 140.469112 -222.856298) (xy 140.469112 -223.046798)
			(xy 140.570712 -223.08312) (xy 140.621512 -223.08312)
		)
		(stroke
			(width 0)
			(type solid)
		)
		(fill yes)
		(layer "F.Cu")
		(net "M_E_CPU1_SB_DQ<28>")
	)
	(gr_poly
		(pts
			(xy 140.621512 -222.22333) (xy 140.570712 -222.22333) (xy 140.469112 -222.259398) (xy 140.469112 -222.449898)
			(xy 140.570712 -222.48622) (xy 140.621512 -222.48622)
		)
		(stroke
			(width 0)
			(type solid)
		)
		(fill yes)
		(layer "F.Cu")
		(net "M_E_CPU1_SB_DQ<28>")
	)
	(gr_poly
		(pts
			(xy 140.621512 -221.62643) (xy 140.570712 -221.62643) (xy 140.469112 -221.662498) (xy 140.469112 -221.852998)
			(xy 140.570712 -221.88932) (xy 140.621512 -221.88932)
		)
		(stroke
			(width 0)
			(type solid)
		)
		(fill yes)
		(layer "F.Cu")
		(net "M_E_CPU1_SB_DQ<28>")
	)
	(gr_poly
		(pts
			(xy 140.621512 -221.02953) (xy 140.570712 -221.02953) (xy 140.469112 -221.065598) (xy 140.469112 -221.256098)
			(xy 140.570712 -221.29242) (xy 140.621512 -221.29242)
		)
		(stroke
			(width 0)
			(type solid)
		)
		(fill yes)
		(layer "F.Cu")
		(net "M_E_CPU1_SB_DQ<28>")
	)
	(gr_poly
		(pts
			(xy 140.621512 -220.43263) (xy 140.570712 -220.43263) (xy 140.469112 -220.468698) (xy 140.469112 -220.659198)
			(xy 140.570712 -220.69552) (xy 140.621512 -220.69552)
		)
		(stroke
			(width 0)
			(type solid)
		)
		(fill yes)
		(layer "F.Cu")
		(net "M_E_CPU1_SB_DQ<28>")
	)
	(gr_poly
		(pts
			(xy 140.621512 -219.83573) (xy 140.570712 -219.83573) (xy 140.469112 -219.871798) (xy 140.469112 -220.062298)
			(xy 140.570712 -220.09862) (xy 140.621512 -220.09862)
		)
		(stroke
			(width 0)
			(type solid)
		)
		(fill yes)
		(layer "F.Cu")
		(net "M_E_CPU1_SB_DQ<28>")
	)
	(gr_poly
		(pts
			(xy 140.621512 -219.23883) (xy 140.570712 -219.23883) (xy 140.469112 -219.274898) (xy 140.469112 -219.465398)
			(xy 140.570712 -219.50172) (xy 140.621512 -219.50172)
		)
		(stroke
			(width 0)
			(type solid)
		)
		(fill yes)
		(layer "F.Cu")
		(net "M_E_CPU1_SB_DQ<28>")
	)
	(gr_poly
		(pts
			(xy 140.621512 -218.64193) (xy 140.570712 -218.64193) (xy 140.469112 -218.677998) (xy 140.469112 -218.868498)
			(xy 140.570712 -218.90482) (xy 140.621512 -218.90482)
		)
		(stroke
			(width 0)
			(type solid)
		)
		(fill yes)
		(layer "F.Cu")
		(net "M_E_CPU1_SB_DQ<28>")
	)
	(gr_poly
		(pts
			(xy 140.621512 -218.04503) (xy 140.570712 -218.04503) (xy 140.469112 -218.081098) (xy 140.469112 -218.271598)
			(xy 140.570712 -218.30792) (xy 140.621512 -218.30792)
		)
		(stroke
			(width 0)
			(type solid)
		)
		(fill yes)
		(layer "F.Cu")
		(net "M_E_CPU1_SB_DQ<28>")
	)
	(gr_poly
		(pts
			(xy 140.621512 -217.44813) (xy 140.570712 -217.44813) (xy 140.469112 -217.484198) (xy 140.469112 -217.674698)
			(xy 140.570712 -217.71102) (xy 140.621512 -217.71102)
		)
		(stroke
			(width 0)
			(type solid)
		)
		(fill yes)
		(layer "F.Cu")
		(net "M_E_CPU1_SB_DQ<28>")
	)
	(gr_poly
		(pts
			(xy 140.621512 -216.85123) (xy 140.570712 -216.85123) (xy 140.469112 -216.887298) (xy 140.469112 -217.077798)
			(xy 140.570712 -217.11412) (xy 140.621512 -217.11412)
		)
		(stroke
			(width 0)
			(type solid)
		)
		(fill yes)
		(layer "F.Cu")
		(net "M_E_CPU1_SB_DQ<28>")
	)
	(gr_poly
		(pts
			(xy 140.621512 -216.25433) (xy 140.570712 -216.25433) (xy 140.469112 -216.290398) (xy 140.469112 -216.480898)
			(xy 140.570712 -216.51722) (xy 140.621512 -216.51722)
		)
		(stroke
			(width 0)
			(type solid)
		)
		(fill yes)
		(layer "F.Cu")
		(net "M_E_CPU1_SB_DQ<28>")
	)
	(gr_poly
		(pts
			(xy 140.622528 -275.31187) (xy 140.658596 -275.276056) (xy 140.472668 -275.090128) (xy 140.4366 -275.125942)
			(xy 140.390372 -275.223478) (xy 140.525246 -275.358098)
		)
		(stroke
			(width 0)
			(type solid)
		)
		(fill yes)
		(layer "F.Cu")
		(net "M_E_CPU1_SA_DQ<7>")
	)
	(gr_poly
		(pts
			(xy 140.65885 -268.460474) (xy 140.694664 -268.42466) (xy 140.508736 -268.238732) (xy 140.472922 -268.2748)
			(xy 140.426694 -268.372082) (xy 140.561314 -268.506956)
		)
		(stroke
			(width 0)
			(type solid)
		)
		(fill yes)
		(layer "F.Cu")
		(net "M_E_CPU1_SA_DQ<26>")
	)
	(gr_poly
		(pts
			(xy 140.661136 -263.210294) (xy 140.707364 -263.113012) (xy 140.572744 -262.978138) (xy 140.475208 -263.024366)
			(xy 140.439394 -263.060434) (xy 140.625322 -263.246362)
		)
		(stroke
			(width 0)
			(type solid)
		)
		(fill yes)
		(layer "F.Cu")
		(net "M_E_CPU1_SA_CB<0>")
	)
	(gr_poly
		(pts
			(xy 140.677646 -276.523196) (xy 140.723874 -276.42566) (xy 140.589 -276.29104) (xy 140.491718 -276.337268)
			(xy 140.45565 -276.373082) (xy 140.641578 -276.55901)
		)
		(stroke
			(width 0)
			(type solid)
		)
		(fill yes)
		(layer "F.Cu")
		(net "M_E_CPU1_SA_DQ<4>")
	)
	(gr_poly
		(pts
			(xy 140.68933 -275.667216) (xy 140.735558 -275.569934) (xy 140.600938 -275.43506) (xy 140.503402 -275.481288)
			(xy 140.467588 -275.517356) (xy 140.653516 -275.703284)
		)
		(stroke
			(width 0)
			(type solid)
		)
		(fill yes)
		(layer "F.Cu")
		(net "M_E_CPU1_SA_DQ<5>")
	)
	(gr_poly
		(pts
			(xy 140.725906 -268.815566) (xy 140.772134 -268.71803) (xy 140.637514 -268.58341) (xy 140.540232 -268.629638)
			(xy 140.504164 -268.665452) (xy 140.690092 -268.85138)
		)
		(stroke
			(width 0)
			(type solid)
		)
		(fill yes)
		(layer "F.Cu")
		(net "M_E_CPU1_SA_DQ<24>")
	)
	(gr_poly
		(pts
			(xy 140.73505 -267.962126) (xy 140.781532 -267.86459) (xy 140.646658 -267.72997) (xy 140.549376 -267.776198)
			(xy 140.513308 -267.812012) (xy 140.699236 -267.99794)
		)
		(stroke
			(width 0)
			(type solid)
		)
		(fill yes)
		(layer "F.Cu")
		(net "M_E_CPU1_SA_DQ<25>")
	)
	(gr_poly
		(pts
			(xy 140.769848 -245.919752) (xy 140.73378 -245.818152) (xy 140.54328 -245.818152) (xy 140.507212 -245.919752)
			(xy 140.507212 -245.970552) (xy 140.769848 -245.970552)
		)
		(stroke
			(width 0)
			(type solid)
		)
		(fill yes)
		(layer "F.Cu")
		(net "M_E_CPU1_SB_CS_N<1>")
	)
	(gr_poly
		(pts
			(xy 140.769848 -245.614952) (xy 140.73378 -245.513352) (xy 140.54328 -245.513352) (xy 140.507212 -245.614952)
			(xy 140.507212 -245.665752) (xy 140.769848 -245.665752)
		)
		(stroke
			(width 0)
			(type solid)
		)
		(fill yes)
		(layer "F.Cu")
		(net "M_E_CPU1_SB_CS_N<3>")
	)
	(gr_poly
		(pts
			(xy 140.773912 -224.539302) (xy 140.773912 -224.348802) (xy 140.672312 -224.31248) (xy 140.621512 -224.31248)
			(xy 140.621512 -224.57537) (xy 140.672312 -224.57537)
		)
		(stroke
			(width 0)
			(type solid)
		)
		(fill yes)
		(layer "F.Cu")
		(net "M_E_CPU1_SB_DQ<28>")
	)
	(gr_poly
		(pts
			(xy 140.773912 -223.942402) (xy 140.773912 -223.751902) (xy 140.672312 -223.71558) (xy 140.621512 -223.71558)
			(xy 140.621512 -223.97847) (xy 140.672312 -223.97847)
		)
		(stroke
			(width 0)
			(type solid)
		)
		(fill yes)
		(layer "F.Cu")
		(net "M_E_CPU1_SB_DQ<28>")
	)
	(gr_poly
		(pts
			(xy 140.773912 -223.345502) (xy 140.773912 -223.155002) (xy 140.672312 -223.11868) (xy 140.621512 -223.11868)
			(xy 140.621512 -223.38157) (xy 140.672312 -223.38157)
		)
		(stroke
			(width 0)
			(type solid)
		)
		(fill yes)
		(layer "F.Cu")
		(net "M_E_CPU1_SB_DQ<28>")
	)
	(gr_poly
		(pts
			(xy 140.773912 -222.748602) (xy 140.773912 -222.558102) (xy 140.672312 -222.52178) (xy 140.621512 -222.52178)
			(xy 140.621512 -222.78467) (xy 140.672312 -222.78467)
		)
		(stroke
			(width 0)
			(type solid)
		)
		(fill yes)
		(layer "F.Cu")
		(net "M_E_CPU1_SB_DQ<28>")
	)
	(gr_poly
		(pts
			(xy 140.773912 -222.151702) (xy 140.773912 -221.961202) (xy 140.672312 -221.92488) (xy 140.621512 -221.92488)
			(xy 140.621512 -222.18777) (xy 140.672312 -222.18777)
		)
		(stroke
			(width 0)
			(type solid)
		)
		(fill yes)
		(layer "F.Cu")
		(net "M_E_CPU1_SB_DQ<28>")
	)
	(gr_poly
		(pts
			(xy 140.773912 -221.554802) (xy 140.773912 -221.364302) (xy 140.672312 -221.32798) (xy 140.621512 -221.32798)
			(xy 140.621512 -221.59087) (xy 140.672312 -221.59087)
		)
		(stroke
			(width 0)
			(type solid)
		)
		(fill yes)
		(layer "F.Cu")
		(net "M_E_CPU1_SB_DQ<28>")
	)
	(gr_poly
		(pts
			(xy 140.773912 -220.957902) (xy 140.773912 -220.767402) (xy 140.672312 -220.73108) (xy 140.621512 -220.73108)
			(xy 140.621512 -220.99397) (xy 140.672312 -220.99397)
		)
		(stroke
			(width 0)
			(type solid)
		)
		(fill yes)
		(layer "F.Cu")
		(net "M_E_CPU1_SB_DQ<28>")
	)
	(gr_poly
		(pts
			(xy 140.773912 -220.361002) (xy 140.773912 -220.170502) (xy 140.672312 -220.13418) (xy 140.621512 -220.13418)
			(xy 140.621512 -220.39707) (xy 140.672312 -220.39707)
		)
		(stroke
			(width 0)
			(type solid)
		)
		(fill yes)
		(layer "F.Cu")
		(net "M_E_CPU1_SB_DQ<28>")
	)
	(gr_poly
		(pts
			(xy 140.773912 -219.764102) (xy 140.773912 -219.573602) (xy 140.672312 -219.53728) (xy 140.621512 -219.53728)
			(xy 140.621512 -219.80017) (xy 140.672312 -219.80017)
		)
		(stroke
			(width 0)
			(type solid)
		)
		(fill yes)
		(layer "F.Cu")
		(net "M_E_CPU1_SB_DQ<28>")
	)
	(gr_poly
		(pts
			(xy 140.773912 -219.167202) (xy 140.773912 -218.976702) (xy 140.672312 -218.94038) (xy 140.621512 -218.94038)
			(xy 140.621512 -219.20327) (xy 140.672312 -219.20327)
		)
		(stroke
			(width 0)
			(type solid)
		)
		(fill yes)
		(layer "F.Cu")
		(net "M_E_CPU1_SB_DQ<28>")
	)
	(gr_poly
		(pts
			(xy 140.773912 -218.570302) (xy 140.773912 -218.379802) (xy 140.672312 -218.34348) (xy 140.621512 -218.34348)
			(xy 140.621512 -218.60637) (xy 140.672312 -218.60637)
		)
		(stroke
			(width 0)
			(type solid)
		)
		(fill yes)
		(layer "F.Cu")
		(net "M_E_CPU1_SB_DQ<28>")
	)
	(gr_poly
		(pts
			(xy 140.773912 -217.973402) (xy 140.773912 -217.782902) (xy 140.672312 -217.74658) (xy 140.621512 -217.74658)
			(xy 140.621512 -218.00947) (xy 140.672312 -218.00947)
		)
		(stroke
			(width 0)
			(type solid)
		)
		(fill yes)
		(layer "F.Cu")
		(net "M_E_CPU1_SB_DQ<28>")
	)
	(gr_poly
		(pts
			(xy 140.773912 -217.376502) (xy 140.773912 -217.186002) (xy 140.672312 -217.14968) (xy 140.621512 -217.14968)
			(xy 140.621512 -217.41257) (xy 140.672312 -217.41257)
		)
		(stroke
			(width 0)
			(type solid)
		)
		(fill yes)
		(layer "F.Cu")
		(net "M_E_CPU1_SB_DQ<28>")
	)
	(gr_poly
		(pts
			(xy 140.773912 -216.779602) (xy 140.773912 -216.589102) (xy 140.672312 -216.55278) (xy 140.621512 -216.55278)
			(xy 140.621512 -216.81567) (xy 140.672312 -216.81567)
		)
		(stroke
			(width 0)
			(type solid)
		)
		(fill yes)
		(layer "F.Cu")
		(net "M_E_CPU1_SB_DQ<28>")
	)
	(gr_poly
		(pts
			(xy 140.773912 -216.182702) (xy 140.773912 -215.992202) (xy 140.672312 -215.95588) (xy 140.621512 -215.95588)
			(xy 140.621512 -216.21877) (xy 140.672312 -216.21877)
		)
		(stroke
			(width 0)
			(type solid)
		)
		(fill yes)
		(layer "F.Cu")
		(net "M_E_CPU1_SB_DQ<28>")
	)
	(gr_poly
		(pts
			(xy 140.811504 -242.944904) (xy 140.77569 -242.90909) (xy 140.678154 -242.862862) (xy 140.543534 -242.997482)
			(xy 140.589762 -243.095018) (xy 140.625576 -243.130832)
		)
		(stroke
			(width 0)
			(type solid)
		)
		(fill yes)
		(layer "F.Cu")
		(net "M_E_CPU1_SB_CB<7>")
	)
	(gr_poly
		(pts
			(xy 140.828522 -275.950172) (xy 140.864336 -275.914104) (xy 140.678662 -275.72843) (xy 140.642594 -275.764244)
			(xy 140.596366 -275.86178) (xy 140.730986 -275.9964)
		)
		(stroke
			(width 0)
			(type solid)
		)
		(fill yes)
		(layer "F.Cu")
		(net "M_E_CPU1_SA_DQ<5>")
	)
	(gr_poly
		(pts
			(xy 140.874242 -268.244828) (xy 140.91031 -268.209014) (xy 140.724382 -268.023086) (xy 140.688568 -268.0589)
			(xy 140.64234 -268.156436) (xy 140.77696 -268.291056)
		)
		(stroke
			(width 0)
			(type solid)
		)
		(fill yes)
		(layer "F.Cu")
		(net "M_E_CPU1_SA_DQ<25>")
	)
	(gr_poly
		(pts
			(xy 140.876782 -262.994648) (xy 140.92301 -262.897366) (xy 140.78839 -262.762492) (xy 140.690854 -262.80872)
			(xy 140.65504 -262.844788) (xy 140.840968 -263.030716)
		)
		(stroke
			(width 0)
			(type solid)
		)
		(fill yes)
		(layer "F.Cu")
		(net "M_E_CPU1_SA_CB<2>")
	)
	(gr_poly
		(pts
			(xy 140.894308 -276.306534) (xy 140.940536 -276.208998) (xy 140.805662 -276.074378) (xy 140.70838 -276.120606)
			(xy 140.672312 -276.15642) (xy 140.85824 -276.342348)
		)
		(stroke
			(width 0)
			(type solid)
		)
		(fill yes)
		(layer "F.Cu")
		(net "M_E_CPU1_SA_DQ<6>")
	)
	(gr_poly
		(pts
			(xy 140.895578 -277.15591) (xy 140.844016 -276.8981) (xy 140.794232 -276.908006) (xy 140.701776 -276.963378)
			(xy 140.739114 -277.150322) (xy 140.845794 -277.165816)
		)
		(stroke
			(width 0)
			(type solid)
		)
		(fill yes)
		(layer "F.Cu")
		(net "M_E_CPU1_SA_DQ<4>")
	)
	(gr_poly
		(pts
			(xy 140.898372 -243.504974) (xy 140.85189 -243.407438) (xy 140.816076 -243.371624) (xy 140.630148 -243.557552)
			(xy 140.666216 -243.593366) (xy 140.763498 -243.639594)
		)
		(stroke
			(width 0)
			(type solid)
		)
		(fill yes)
		(layer "F.Cu")
		(net "M_E_CPU1_SB_CB<5>")
	)
	(gr_poly
		(pts
			(xy 140.900912 -265.502898) (xy 140.94714 -265.405616) (xy 140.81252 -265.270742) (xy 140.714984 -265.31697)
			(xy 140.67917 -265.353038) (xy 140.865098 -265.538966)
		)
		(stroke
			(width 0)
			(type solid)
		)
		(fill yes)
		(layer "F.Cu")
		(net "M_E_CPU1_SA_DQ<28>")
	)
	(gr_poly
		(pts
			(xy 140.905484 -275.451062) (xy 140.951712 -275.35378) (xy 140.817092 -275.218906) (xy 140.719556 -275.265134)
			(xy 140.683742 -275.301202) (xy 140.86967 -275.48713)
		)
		(stroke
			(width 0)
			(type solid)
		)
		(fill yes)
		(layer "F.Cu")
		(net "M_E_CPU1_SA_DQ<7>")
	)
	(gr_poly
		(pts
			(xy 140.92301 -271.15135) (xy 140.969238 -271.053814) (xy 140.834618 -270.919194) (xy 140.737082 -270.965422)
			(xy 140.701268 -271.001236) (xy 140.886942 -271.187164)
		)
		(stroke
			(width 0)
			(type solid)
		)
		(fill yes)
		(layer "F.Cu")
		(net "M_E_CPU1_SA_DQ<20>")
	)
	(gr_poly
		(pts
			(xy 140.941552 -268.599666) (xy 140.98778 -268.502384) (xy 140.85316 -268.36751) (xy 140.755624 -268.413992)
			(xy 140.71981 -268.449806) (xy 140.905738 -268.635734)
		)
		(stroke
			(width 0)
			(type solid)
		)
		(fill yes)
		(layer "F.Cu")
		(net "M_E_CPU1_SA_DQ<26>")
	)
	(gr_poly
		(pts
			(xy 140.950696 -267.746226) (xy 140.996924 -267.648944) (xy 140.862304 -267.514324) (xy 140.764768 -267.560552)
			(xy 140.728954 -267.596366) (xy 140.914882 -267.782294)
		)
		(stroke
			(width 0)
			(type solid)
		)
		(fill yes)
		(layer "F.Cu")
		(net "M_E_CPU1_SA_DQ<27>")
	)
	(gr_poly
		(pts
			(xy 141.004036 -277.438612) (xy 141.096492 -277.382986) (xy 141.059154 -277.196296) (xy 140.952474 -277.180802)
			(xy 140.90269 -277.190708) (xy 140.954252 -277.448518)
		)
		(stroke
			(width 0)
			(type solid)
		)
		(fill yes)
		(layer "F.Cu")
		(net "M_E_CPU1_SA_DQ<4>")
	)
	(gr_poly
		(pts
			(xy 141.008608 -274.693634) (xy 141.054836 -274.596098) (xy 140.920216 -274.461478) (xy 140.82268 -274.507706)
			(xy 140.786866 -274.543774) (xy 140.97254 -274.729448)
		)
		(stroke
			(width 0)
			(type solid)
		)
		(fill yes)
		(layer "F.Cu")
		(net "M_E_CPU1_SA_DQ<16>")
	)
	(gr_poly
		(pts
			(xy 141.012926 -277.741126) (xy 140.96111 -277.483316) (xy 140.911326 -277.493222) (xy 140.81887 -277.548848)
			(xy 140.856208 -277.735538) (xy 140.963142 -277.751032)
		)
		(stroke
			(width 0)
			(type solid)
		)
		(fill yes)
		(layer "F.Cu")
		(net "M_E_CPU1_SA_DQ<4>")
	)
	(gr_poly
		(pts
			(xy 141.015974 -263.277604) (xy 141.051788 -263.241536) (xy 140.866114 -263.055862) (xy 140.830046 -263.091676)
			(xy 140.783818 -263.189212) (xy 140.918438 -263.323832)
		)
		(stroke
			(width 0)
			(type solid)
		)
		(fill yes)
		(layer "F.Cu")
		(net "M_E_CPU1_SA_CB<2>")
	)
	(gr_poly
		(pts
			(xy 141.02461 -230.424228) (xy 140.978382 -230.326692) (xy 140.942314 -230.290878) (xy 140.756386 -230.476806)
			(xy 140.792454 -230.51262) (xy 140.889736 -230.558848)
		)
		(stroke
			(width 0)
			(type solid)
		)
		(fill yes)
		(layer "F.Cu")
		(net "M_E_CPU1_SB_DQ<23>")
	)
	(gr_poly
		(pts
			(xy 141.02715 -243.16055) (xy 140.991336 -243.124736) (xy 140.8938 -243.078508) (xy 140.75918 -243.213128)
			(xy 140.805408 -243.310664) (xy 140.841222 -243.346478)
		)
		(stroke
			(width 0)
			(type solid)
		)
		(fill yes)
		(layer "F.Cu")
		(net "M_E_CPU1_SB_CB<5>")
	)
	(gr_poly
		(pts
			(xy 141.036294 -244.01399) (xy 141.00048 -243.977922) (xy 140.902944 -243.931694) (xy 140.768324 -244.066568)
			(xy 140.814552 -244.16385) (xy 140.850366 -244.199918)
		)
		(stroke
			(width 0)
			(type solid)
		)
		(fill yes)
		(layer "F.Cu")
		(net "M_E_CPU1_SB_CB<4>")
	)
	(gr_poly
		(pts
			(xy 141.040104 -265.785854) (xy 141.076172 -265.75004) (xy 140.890244 -265.564112) (xy 140.854176 -265.599926)
			(xy 140.807948 -265.697462) (xy 140.942568 -265.832082)
		)
		(stroke
			(width 0)
			(type solid)
		)
		(fill yes)
		(layer "F.Cu")
		(net "M_E_CPU1_SA_DQ<28>")
	)
	(gr_poly
		(pts
			(xy 141.044676 -275.734018) (xy 141.08049 -275.69795) (xy 140.894816 -275.512276) (xy 140.858748 -275.54809)
			(xy 140.81252 -275.645626) (xy 140.94714 -275.780246)
		)
		(stroke
			(width 0)
			(type solid)
		)
		(fill yes)
		(layer "F.Cu")
		(net "M_E_CPU1_SA_DQ<7>")
	)
	(gr_poly
		(pts
			(xy 141.062202 -271.434052) (xy 141.098016 -271.398238) (xy 140.912342 -271.21231) (xy 140.876274 -271.248124)
			(xy 140.830046 -271.34566) (xy 140.964666 -271.48028)
		)
		(stroke
			(width 0)
			(type solid)
		)
		(fill yes)
		(layer "F.Cu")
		(net "M_E_CPU1_SA_DQ<20>")
	)
	(gr_poly
		(pts
			(xy 141.068552 -246.326152) (xy 141.068552 -246.275352) (xy 140.805408 -246.275352) (xy 140.805408 -246.326152)
			(xy 140.84173 -246.427752) (xy 141.03223 -246.427752)
		)
		(stroke
			(width 0)
			(type solid)
		)
		(fill yes)
		(layer "F.Cu")
		(net "M_E_CPU1_SB_CS_N<2>")
	)
	(gr_poly
		(pts
			(xy 141.068552 -246.021352) (xy 141.068552 -245.970552) (xy 140.805408 -245.970552) (xy 140.805408 -246.021352)
			(xy 140.84173 -246.122952) (xy 141.03223 -246.122952)
		)
		(stroke
			(width 0)
			(type solid)
		)
		(fill yes)
		(layer "F.Cu")
		(net "M_E_CPU1_SB_CS_N<1>")
	)
	(gr_poly
		(pts
			(xy 141.068552 -245.716552) (xy 141.068552 -245.665752) (xy 140.805408 -245.665752) (xy 140.805408 -245.716552)
			(xy 140.84173 -245.818152) (xy 141.03223 -245.818152)
		)
		(stroke
			(width 0)
			(type solid)
		)
		(fill yes)
		(layer "F.Cu")
		(net "M_E_CPU1_SB_CS_N<3>")
	)
	(gr_poly
		(pts
			(xy 141.071854 -270.580104) (xy 141.107922 -270.54429) (xy 140.921994 -270.358362) (xy 140.885926 -270.394176)
			(xy 140.839698 -270.491712) (xy 140.974572 -270.626332)
		)
		(stroke
			(width 0)
			(type solid)
		)
		(fill yes)
		(layer "F.Cu")
		(net "M_E_CPU1_SA_DQ<21>")
	)
	(gr_poly
		(pts
			(xy 141.080744 -268.882622) (xy 141.116812 -268.846808) (xy 140.930884 -268.66088) (xy 140.894816 -268.696694)
			(xy 140.848588 -268.79423) (xy 140.983462 -268.92885)
		)
		(stroke
			(width 0)
			(type solid)
		)
		(fill yes)
		(layer "F.Cu")
		(net "M_E_CPU1_SA_DQ<26>")
	)
	(gr_poly
		(pts
			(xy 141.083284 -263.632442) (xy 141.129512 -263.534906) (xy 140.994638 -263.400286) (xy 140.897356 -263.446514)
			(xy 140.861288 -263.482328) (xy 141.047216 -263.668256)
		)
		(stroke
			(width 0)
			(type solid)
		)
		(fill yes)
		(layer "F.Cu")
		(net "M_E_CPU1_SA_CB<0>")
	)
	(gr_poly
		(pts
			(xy 141.089888 -268.029182) (xy 141.125956 -267.993368) (xy 140.940028 -267.80744) (xy 140.90396 -267.843254)
			(xy 140.857732 -267.94079) (xy 140.992606 -268.07541)
		)
		(stroke
			(width 0)
			(type solid)
		)
		(fill yes)
		(layer "F.Cu")
		(net "M_E_CPU1_SA_DQ<27>")
	)
	(gr_poly
		(pts
			(xy 141.092428 -262.779002) (xy 141.138656 -262.68172) (xy 141.004036 -262.546846) (xy 140.9065 -262.593074)
			(xy 140.870686 -262.629142) (xy 141.056614 -262.81507)
		)
		(stroke
			(width 0)
			(type solid)
		)
		(fill yes)
		(layer "F.Cu")
		(net "M_E_CPU1_SA_CB<1>")
	)
	(gr_poly
		(pts
			(xy 141.10462 -242.86718) (xy 141.058392 -242.769898) (xy 141.022578 -242.73383) (xy 140.83665 -242.919758)
			(xy 140.872464 -242.955572) (xy 140.97 -243.002054)
		)
		(stroke
			(width 0)
			(type solid)
		)
		(fill yes)
		(layer "F.Cu")
		(net "M_E_CPU1_SB_CB<7>")
	)
	(gr_poly
		(pts
			(xy 141.111478 -276.089364) (xy 141.157706 -275.991828) (xy 141.022832 -275.857208) (xy 140.92555 -275.903436)
			(xy 140.889482 -275.93925) (xy 141.07541 -276.125178)
		)
		(stroke
			(width 0)
			(type solid)
		)
		(fill yes)
		(layer "F.Cu")
		(net "M_E_CPU1_SA_DQ<5>")
	)
	(gr_poly
		(pts
			(xy 141.114018 -243.72062) (xy 141.067536 -243.623084) (xy 141.031722 -243.58727) (xy 140.845794 -243.773198)
			(xy 140.881862 -243.809012) (xy 140.979144 -243.85524)
		)
		(stroke
			(width 0)
			(type solid)
		)
		(fill yes)
		(layer "F.Cu")
		(net "M_E_CPU1_SB_CB<6>")
	)
	(gr_poly
		(pts
			(xy 141.116558 -265.287252) (xy 141.162786 -265.18997) (xy 141.028166 -265.055096) (xy 140.93063 -265.101324)
			(xy 140.894816 -265.137392) (xy 141.080744 -265.32332)
		)
		(stroke
			(width 0)
			(type solid)
		)
		(fill yes)
		(layer "F.Cu")
		(net "M_E_CPU1_SA_DQ<30>")
	)
	(gr_poly
		(pts
			(xy 141.12113 -278.023828) (xy 141.21384 -277.968456) (xy 141.176248 -277.781512) (xy 141.069568 -277.766018)
			(xy 141.019784 -277.775924) (xy 141.071346 -278.033734)
		)
		(stroke
			(width 0)
			(type solid)
		)
		(fill yes)
		(layer "F.Cu")
		(net "M_E_CPU1_SA_DQ<4>")
	)
	(gr_poly
		(pts
			(xy 141.13002 -278.326342) (xy 141.078458 -278.068532) (xy 141.028674 -278.078692) (xy 140.935964 -278.134064)
			(xy 140.973556 -278.320754) (xy 141.080236 -278.336502)
		)
		(stroke
			(width 0)
			(type solid)
		)
		(fill yes)
		(layer "F.Cu")
		(net "M_E_CPU1_SA_DQ<4>")
	)
	(gr_poly
		(pts
			(xy 141.139164 -270.934942) (xy 141.185392 -270.83766) (xy 141.050772 -270.702786) (xy 140.953236 -270.749014)
			(xy 140.917422 -270.785082) (xy 141.10335 -270.97101)
		)
		(stroke
			(width 0)
			(type solid)
		)
		(fill yes)
		(layer "F.Cu")
		(net "M_E_CPU1_SA_DQ<22>")
	)
	(gr_poly
		(pts
			(xy 141.1478 -274.97659) (xy 141.183614 -274.940522) (xy 140.997686 -274.754594) (xy 140.961872 -274.790662)
			(xy 140.915644 -274.887944) (xy 141.050264 -275.022818)
		)
		(stroke
			(width 0)
			(type solid)
		)
		(fill yes)
		(layer "F.Cu")
		(net "M_E_CPU1_SA_DQ<16>")
	)
	(gr_poly
		(pts
			(xy 141.148054 -269.23746) (xy 141.194282 -269.140178) (xy 141.059662 -269.005304) (xy 140.962126 -269.051532)
			(xy 140.926312 -269.0876) (xy 141.11224 -269.273528)
		)
		(stroke
			(width 0)
			(type solid)
		)
		(fill yes)
		(layer "F.Cu")
		(net "M_E_CPU1_SA_DQ<24>")
	)
	(gr_poly
		(pts
			(xy 141.153388 -230.079804) (xy 141.117574 -230.04399) (xy 141.020038 -229.997762) (xy 140.885418 -230.132382)
			(xy 140.931646 -230.229664) (xy 140.96746 -230.265732)
		)
		(stroke
			(width 0)
			(type solid)
		)
		(fill yes)
		(layer "F.Cu")
		(net "M_E_CPU1_SB_DQ<23>")
	)
	(gr_poly
		(pts
			(xy 141.156944 -274.12315) (xy 141.193012 -274.087336) (xy 141.007084 -273.901408) (xy 140.971016 -273.937222)
			(xy 140.924788 -274.034758) (xy 141.059408 -274.169378)
		)
		(stroke
			(width 0)
			(type solid)
		)
		(fill yes)
		(layer "F.Cu")
		(net "M_E_CPU1_SA_DQ<17>")
	)
	(gr_poly
		(pts
			(xy 141.157198 -268.38402) (xy 141.203426 -268.286738) (xy 141.068806 -268.151864) (xy 140.97127 -268.198092)
			(xy 140.935456 -268.23416) (xy 141.121384 -268.420088)
		)
		(stroke
			(width 0)
			(type solid)
		)
		(fill yes)
		(layer "F.Cu")
		(net "M_E_CPU1_SA_DQ<25>")
	)
	(gr_poly
		(pts
			(xy 141.189456 -233.49458) (xy 141.153642 -233.458766) (xy 141.056106 -233.412284) (xy 140.921486 -233.547158)
			(xy 140.967714 -233.64444) (xy 141.003528 -233.680508)
		)
		(stroke
			(width 0)
			(type solid)
		)
		(fill yes)
		(layer "F.Cu")
		(net "M_E_CPU1_SB_DQ<19>")
	)
	(gr_poly
		(pts
			(xy 141.195044 -277.095966) (xy 141.143482 -276.838156) (xy 141.093698 -276.848062) (xy 141.001242 -276.903434)
			(xy 141.03858 -277.090378) (xy 141.14526 -277.105872)
		)
		(stroke
			(width 0)
			(type solid)
		)
		(fill yes)
		(layer "F.Cu")
		(net "M_E_CPU1_SA_DQ<6>")
	)
	(gr_poly
		(pts
			(xy 141.224254 -274.477988) (xy 141.270482 -274.380452) (xy 141.135862 -274.245832) (xy 141.038326 -274.29206)
			(xy 141.002512 -274.328128) (xy 141.188186 -274.513802)
		)
		(stroke
			(width 0)
			(type solid)
		)
		(fill yes)
		(layer "F.Cu")
		(net "M_E_CPU1_SA_DQ<18>")
	)
	(gr_poly
		(pts
			(xy 141.23162 -263.061958) (xy 141.267434 -263.02589) (xy 141.08176 -262.840216) (xy 141.045692 -262.87603)
			(xy 140.999464 -262.973566) (xy 141.134084 -263.108186)
		)
		(stroke
			(width 0)
			(type solid)
		)
		(fill yes)
		(layer "F.Cu")
		(net "M_E_CPU1_SA_CB<1>")
	)
	(gr_poly
		(pts
			(xy 141.233652 -242.522756) (xy 141.197584 -242.486942) (xy 141.100302 -242.440714) (xy 140.965428 -242.575334)
			(xy 141.011656 -242.67287) (xy 141.047724 -242.708684)
		)
		(stroke
			(width 0)
			(type solid)
		)
		(fill yes)
		(layer "F.Cu")
		(net "M_E_CPU1_SB_CB<7>")
	)
	(gr_poly
		(pts
			(xy 141.238478 -278.609044) (xy 141.330934 -278.553672) (xy 141.293596 -278.366982) (xy 141.186916 -278.351234)
			(xy 141.136878 -278.361394) (xy 141.188694 -278.61895)
		)
		(stroke
			(width 0)
			(type solid)
		)
		(fill yes)
		(layer "F.Cu")
		(net "M_E_CPU1_SA_DQ<4>")
	)
	(gr_poly
		(pts
			(xy 141.240256 -230.639874) (xy 141.194028 -230.542338) (xy 141.15796 -230.506524) (xy 140.972032 -230.692452)
			(xy 141.0081 -230.728266) (xy 141.105382 -230.774494)
		)
		(stroke
			(width 0)
			(type solid)
		)
		(fill yes)
		(layer "F.Cu")
		(net "M_E_CPU1_SB_DQ<21>")
	)
	(gr_poly
		(pts
			(xy 141.242796 -243.376196) (xy 141.206982 -243.340382) (xy 141.109446 -243.294154) (xy 140.974826 -243.428774)
			(xy 141.021054 -243.52631) (xy 141.056868 -243.562124)
		)
		(stroke
			(width 0)
			(type solid)
		)
		(fill yes)
		(layer "F.Cu")
		(net "M_E_CPU1_SB_CB<6>")
	)
	(gr_poly
		(pts
			(xy 141.247114 -278.911812) (xy 141.195552 -278.654002) (xy 141.145768 -278.663908) (xy 141.053312 -278.71928)
			(xy 141.09065 -278.906224) (xy 141.19733 -278.921718)
		)
		(stroke
			(width 0)
			(type solid)
		)
		(fill yes)
		(layer "F.Cu")
		(net "M_E_CPU1_SA_DQ<4>")
	)
	(gr_poly
		(pts
			(xy 141.25575 -265.570208) (xy 141.291818 -265.534394) (xy 141.10589 -265.348466) (xy 141.069822 -265.38428)
			(xy 141.023594 -265.481816) (xy 141.158214 -265.616436)
		)
		(stroke
			(width 0)
			(type solid)
		)
		(fill yes)
		(layer "F.Cu")
		(net "M_E_CPU1_SA_DQ<30>")
	)
	(gr_poly
		(pts
			(xy 141.276324 -234.05465) (xy 141.230096 -233.957114) (xy 141.194028 -233.9213) (xy 141.0081 -234.107228)
			(xy 141.044168 -234.143042) (xy 141.14145 -234.18927)
		)
		(stroke
			(width 0)
			(type solid)
		)
		(fill yes)
		(layer "F.Cu")
		(net "M_E_CPU1_SB_DQ<17>")
	)
	(gr_poly
		(pts
			(xy 141.278356 -271.217898) (xy 141.314424 -271.182084) (xy 141.128496 -270.996156) (xy 141.092428 -271.03197)
			(xy 141.0462 -271.129506) (xy 141.18082 -271.264126)
		)
		(stroke
			(width 0)
			(type solid)
		)
		(fill yes)
		(layer "F.Cu")
		(net "M_E_CPU1_SA_DQ<22>")
	)
	(gr_poly
		(pts
			(xy 141.287754 -270.364204) (xy 141.323568 -270.32839) (xy 141.13764 -270.142462) (xy 141.101826 -270.17853)
			(xy 141.055598 -270.275812) (xy 141.190218 -270.410686)
		)
		(stroke
			(width 0)
			(type solid)
		)
		(fill yes)
		(layer "F.Cu")
		(net "M_E_CPU1_SA_DQ<23>")
	)
	(gr_poly
		(pts
			(xy 141.29639 -268.666976) (xy 141.332458 -268.631162) (xy 141.14653 -268.445234) (xy 141.110462 -268.481048)
			(xy 141.064234 -268.578584) (xy 141.199108 -268.713204)
		)
		(stroke
			(width 0)
			(type solid)
		)
		(fill yes)
		(layer "F.Cu")
		(net "M_E_CPU1_SA_DQ<25>")
	)
	(gr_poly
		(pts
			(xy 141.29893 -263.416796) (xy 141.345158 -263.31926) (xy 141.210284 -263.18464) (xy 141.113002 -263.230868)
			(xy 141.076934 -263.266682) (xy 141.262862 -263.45261)
		)
		(stroke
			(width 0)
			(type solid)
		)
		(fill yes)
		(layer "F.Cu")
		(net "M_E_CPU1_SA_CB<2>")
	)
	(gr_poly
		(pts
			(xy 141.303502 -277.378668) (xy 141.395958 -277.323042) (xy 141.35862 -277.136352) (xy 141.25194 -277.120858)
			(xy 141.202156 -277.130764) (xy 141.253718 -277.388574)
		)
		(stroke
			(width 0)
			(type solid)
		)
		(fill yes)
		(layer "F.Cu")
		(net "M_E_CPU1_SA_DQ<6>")
	)
	(gr_poly
		(pts
			(xy 141.308074 -262.563356) (xy 141.354302 -262.466074) (xy 141.219682 -262.3312) (xy 141.122146 -262.377428)
			(xy 141.086332 -262.413496) (xy 141.27226 -262.599424)
		)
		(stroke
			(width 0)
			(type solid)
		)
		(fill yes)
		(layer "F.Cu")
		(net "M_E_CPU1_SA_CB<3>")
	)
	(gr_poly
		(pts
			(xy 141.312138 -277.681182) (xy 141.260576 -277.423372) (xy 141.210792 -277.433278) (xy 141.118336 -277.488904)
			(xy 141.155674 -277.675594) (xy 141.262354 -277.691088)
		)
		(stroke
			(width 0)
			(type solid)
		)
		(fill yes)
		(layer "F.Cu")
		(net "M_E_CPU1_SA_DQ<6>")
	)
	(gr_poly
		(pts
			(xy 141.320266 -243.082826) (xy 141.274038 -242.985544) (xy 141.238224 -242.949476) (xy 141.052296 -243.135404)
			(xy 141.08811 -243.171218) (xy 141.185646 -243.2177)
		)
		(stroke
			(width 0)
			(type solid)
		)
		(fill yes)
		(layer "F.Cu")
		(net "M_E_CPU1_SB_CB<5>")
	)
	(gr_poly
		(pts
			(xy 141.32306 -265.925046) (xy 141.369288 -265.82751) (xy 141.234668 -265.69289) (xy 141.137132 -265.739118)
			(xy 141.101318 -265.775186) (xy 141.286992 -265.96086)
		)
		(stroke
			(width 0)
			(type solid)
		)
		(fill yes)
		(layer "F.Cu")
		(net "M_E_CPU1_SA_DQ<28>")
	)
	(gr_poly
		(pts
			(xy 141.327632 -275.87321) (xy 141.37386 -275.775674) (xy 141.238986 -275.641054) (xy 141.141704 -275.687282)
			(xy 141.105636 -275.723096) (xy 141.291564 -275.909024)
		)
		(stroke
			(width 0)
			(type solid)
		)
		(fill yes)
		(layer "F.Cu")
		(net "M_E_CPU1_SA_DQ<7>")
	)
	(gr_poly
		(pts
			(xy 141.329664 -243.936266) (xy 141.283182 -243.83873) (xy 141.247368 -243.802916) (xy 141.06144 -243.988844)
			(xy 141.097508 -244.024658) (xy 141.19479 -244.070886)
		)
		(stroke
			(width 0)
			(type solid)
		)
		(fill yes)
		(layer "F.Cu")
		(net "M_E_CPU1_SB_CB<4>")
	)
	(gr_poly
		(pts
			(xy 141.332458 -265.071606) (xy 141.378686 -264.97407) (xy 141.243812 -264.83945) (xy 141.14653 -264.885678)
			(xy 141.110462 -264.921492) (xy 141.29639 -265.10742)
		)
		(stroke
			(width 0)
			(type solid)
		)
		(fill yes)
		(layer "F.Cu")
		(net "M_E_CPU1_SA_DQ<29>")
	)
	(gr_poly
		(pts
			(xy 141.345158 -271.573244) (xy 141.391386 -271.475962) (xy 141.256766 -271.341088) (xy 141.15923 -271.387316)
			(xy 141.123416 -271.423384) (xy 141.30909 -271.609312)
		)
		(stroke
			(width 0)
			(type solid)
		)
		(fill yes)
		(layer "F.Cu")
		(net "M_E_CPU1_SA_DQ<20>")
	)
	(gr_poly
		(pts
			(xy 141.35481 -270.719296) (xy 141.401038 -270.62176) (xy 141.266418 -270.48714) (xy 141.168882 -270.533368)
			(xy 141.133068 -270.569436) (xy 141.318996 -270.755364)
		)
		(stroke
			(width 0)
			(type solid)
		)
		(fill yes)
		(layer "F.Cu")
		(net "M_E_CPU1_SA_DQ<21>")
	)
	(gr_poly
		(pts
			(xy 141.355572 -279.19426) (xy 141.448028 -279.138888) (xy 141.41069 -278.952198) (xy 141.30401 -278.936704)
			(xy 141.254226 -278.94661) (xy 141.305788 -279.20442)
		)
		(stroke
			(width 0)
			(type solid)
		)
		(fill yes)
		(layer "F.Cu")
		(net "M_E_CPU1_SA_DQ<4>")
	)
	(gr_poly
		(pts
			(xy 141.363446 -274.760944) (xy 141.39926 -274.724876) (xy 141.213332 -274.538948) (xy 141.177518 -274.575016)
			(xy 141.13129 -274.672298) (xy 141.26591 -274.807172)
		)
		(stroke
			(width 0)
			(type solid)
		)
		(fill yes)
		(layer "F.Cu")
		(net "M_E_CPU1_SA_DQ<18>")
	)
	(gr_poly
		(pts
			(xy 141.3637 -269.021814) (xy 141.409928 -268.924532) (xy 141.275308 -268.789658) (xy 141.177772 -268.835886)
			(xy 141.141958 -268.871954) (xy 141.327886 -269.057882)
		)
		(stroke
			(width 0)
			(type solid)
		)
		(fill yes)
		(layer "F.Cu")
		(net "M_E_CPU1_SA_DQ<26>")
	)
	(gr_poly
		(pts
			(xy 141.364462 -279.497028) (xy 141.312646 -279.239218) (xy 141.262862 -279.249124) (xy 141.170406 -279.304496)
			(xy 141.207744 -279.49144) (xy 141.314424 -279.506934)
		)
		(stroke
			(width 0)
			(type solid)
		)
		(fill yes)
		(layer "F.Cu")
		(net "M_E_CPU1_SA_DQ<4>")
	)
	(gr_poly
		(pts
			(xy 141.366748 -246.529352) (xy 141.33068 -246.427752) (xy 141.14018 -246.427752) (xy 141.104112 -246.529352)
			(xy 141.104112 -246.580152) (xy 141.366748 -246.580152)
		)
		(stroke
			(width 0)
			(type solid)
		)
		(fill yes)
		(layer "F.Cu")
		(net "M_E_CPU1_SB_CS_N<0>")
	)
	(gr_poly
		(pts
			(xy 141.366748 -246.224552) (xy 141.33068 -246.122952) (xy 141.14018 -246.122952) (xy 141.104112 -246.224552)
			(xy 141.104112 -246.275352) (xy 141.366748 -246.275352)
		)
		(stroke
			(width 0)
			(type solid)
		)
		(fill yes)
		(layer "F.Cu")
		(net "M_E_CPU1_SB_CS_N<2>")
	)
	(gr_poly
		(pts
			(xy 141.366748 -245.919752) (xy 141.33068 -245.818152) (xy 141.14018 -245.818152) (xy 141.104112 -245.919752)
			(xy 141.104112 -245.970552) (xy 141.366748 -245.970552)
		)
		(stroke
			(width 0)
			(type solid)
		)
		(fill yes)
		(layer "F.Cu")
		(net "M_E_CPU1_SB_CS_N<1>")
	)
	(gr_poly
		(pts
			(xy 141.366748 -245.614952) (xy 141.33068 -245.513352) (xy 141.14018 -245.513352) (xy 141.104112 -245.614952)
			(xy 141.104112 -245.665752) (xy 141.366748 -245.665752)
		)
		(stroke
			(width 0)
			(type solid)
		)
		(fill yes)
		(layer "F.Cu")
		(net "M_E_CPU1_SB_CS_N<3>")
	)
	(gr_poly
		(pts
			(xy 141.369034 -230.29545) (xy 141.33322 -230.259636) (xy 141.235684 -230.213408) (xy 141.101064 -230.348028)
			(xy 141.147292 -230.44531) (xy 141.183106 -230.481378)
		)
		(stroke
			(width 0)
			(type solid)
		)
		(fill yes)
		(layer "F.Cu")
		(net "M_E_CPU1_SB_DQ<21>")
	)
	(gr_poly
		(pts
			(xy 141.372844 -268.168374) (xy 141.419072 -268.071092) (xy 141.284452 -267.936218) (xy 141.186916 -267.982446)
			(xy 141.151102 -268.018514) (xy 141.33703 -268.204442)
		)
		(stroke
			(width 0)
			(type solid)
		)
		(fill yes)
		(layer "F.Cu")
		(net "M_E_CPU1_SA_DQ<27>")
	)
	(gr_poly
		(pts
			(xy 141.378178 -231.14889) (xy 141.342364 -231.112822) (xy 141.244828 -231.066594) (xy 141.110208 -231.201468)
			(xy 141.156436 -231.29875) (xy 141.19225 -231.334818)
		)
		(stroke
			(width 0)
			(type solid)
		)
		(fill yes)
		(layer "F.Cu")
		(net "M_E_CPU1_SB_DQ<20>")
	)
	(gr_poly
		(pts
			(xy 141.405102 -233.710226) (xy 141.369288 -233.674412) (xy 141.271752 -233.62793) (xy 141.137132 -233.762804)
			(xy 141.18336 -233.860086) (xy 141.219174 -233.896154)
		)
		(stroke
			(width 0)
			(type solid)
		)
		(fill yes)
		(layer "F.Cu")
		(net "M_E_CPU1_SB_DQ<17>")
	)
	(gr_poly
		(pts
			(xy 141.414246 -234.563666) (xy 141.378432 -234.527598) (xy 141.280896 -234.48137) (xy 141.146276 -234.61599)
			(xy 141.192504 -234.713526) (xy 141.228572 -234.74934)
		)
		(stroke
			(width 0)
			(type solid)
		)
		(fill yes)
		(layer "F.Cu")
		(net "M_E_CPU1_SB_DQ<16>")
	)
	(gr_poly
		(pts
			(xy 141.420596 -277.963884) (xy 141.513052 -277.908512) (xy 141.475714 -277.721568) (xy 141.369034 -277.706074)
			(xy 141.31925 -277.71598) (xy 141.370812 -277.97379)
		)
		(stroke
			(width 0)
			(type solid)
		)
		(fill yes)
		(layer "F.Cu")
		(net "M_E_CPU1_SA_DQ<6>")
	)
	(gr_poly
		(pts
			(xy 141.421866 -257.79603) (xy 141.457934 -257.760216) (xy 141.272006 -257.574288) (xy 141.235938 -257.610102)
			(xy 141.18971 -257.707638) (xy 141.324584 -257.842258)
		)
		(stroke
			(width 0)
			(type solid)
		)
		(fill yes)
		(layer "F.Cu")
		(net "M_E_CPU1_SA_CS_N<0>")
	)
	(gr_poly
		(pts
			(xy 141.429486 -278.266398) (xy 141.37767 -278.008588) (xy 141.327886 -278.018748) (xy 141.23543 -278.07412)
			(xy 141.272768 -278.26081) (xy 141.379448 -278.276558)
		)
		(stroke
			(width 0)
			(type solid)
		)
		(fill yes)
		(layer "F.Cu")
		(net "M_E_CPU1_SA_DQ<6>")
	)
	(gr_poly
		(pts
			(xy 141.430502 -275.115782) (xy 141.476984 -275.018246) (xy 141.34211 -274.883626) (xy 141.244828 -274.929854)
			(xy 141.20876 -274.965668) (xy 141.394688 -275.151596)
		)
		(stroke
			(width 0)
			(type solid)
		)
		(fill yes)
		(layer "F.Cu")
		(net "M_E_CPU1_SA_DQ<16>")
	)
	(gr_poly
		(pts
			(xy 141.438122 -263.699752) (xy 141.473936 -263.663684) (xy 141.288008 -263.477756) (xy 141.252194 -263.513824)
			(xy 141.205966 -263.611106) (xy 141.340586 -263.74598)
		)
		(stroke
			(width 0)
			(type solid)
		)
		(fill yes)
		(layer "F.Cu")
		(net "M_E_CPU1_SA_CB<2>")
	)
	(gr_poly
		(pts
			(xy 141.4399 -274.262342) (xy 141.486128 -274.164806) (xy 141.351508 -274.030186) (xy 141.253972 -274.076414)
			(xy 141.218158 -274.112482) (xy 141.403832 -274.298156)
		)
		(stroke
			(width 0)
			(type solid)
		)
		(fill yes)
		(layer "F.Cu")
		(net "M_E_CPU1_SA_DQ<17>")
	)
	(gr_poly
		(pts
			(xy 141.446504 -230.00208) (xy 141.400276 -229.904798) (xy 141.364462 -229.86873) (xy 141.178534 -230.054658)
			(xy 141.214348 -230.090472) (xy 141.311884 -230.136954)
		)
		(stroke
			(width 0)
			(type solid)
		)
		(fill yes)
		(layer "F.Cu")
		(net "M_E_CPU1_SB_DQ<23>")
	)
	(gr_poly
		(pts
			(xy 141.447266 -262.846312) (xy 141.48308 -262.810244) (xy 141.297406 -262.62457) (xy 141.261338 -262.660384)
			(xy 141.21511 -262.75792) (xy 141.34973 -262.89254)
		)
		(stroke
			(width 0)
			(type solid)
		)
		(fill yes)
		(layer "F.Cu")
		(net "M_E_CPU1_SA_CB<3>")
	)
	(gr_poly
		(pts
			(xy 141.449298 -242.738402) (xy 141.41323 -242.702588) (xy 141.315948 -242.65636) (xy 141.181074 -242.79098)
			(xy 141.227302 -242.888516) (xy 141.26337 -242.92433)
		)
		(stroke
			(width 0)
			(type solid)
		)
		(fill yes)
		(layer "F.Cu")
		(net "M_E_CPU1_SB_CB<5>")
	)
	(gr_poly
		(pts
			(xy 141.455902 -230.85552) (xy 141.409674 -230.757984) (xy 141.373606 -230.72217) (xy 141.187678 -230.908098)
			(xy 141.223746 -230.943912) (xy 141.321028 -230.99014)
		)
		(stroke
			(width 0)
			(type solid)
		)
		(fill yes)
		(layer "F.Cu")
		(net "M_E_CPU1_SB_DQ<22>")
	)
	(gr_poly
		(pts
			(xy 141.458442 -243.591842) (xy 141.422628 -243.556028) (xy 141.325092 -243.5098) (xy 141.190472 -243.64442)
			(xy 141.2367 -243.741956) (xy 141.272514 -243.77777)
		)
		(stroke
			(width 0)
			(type solid)
		)
		(fill yes)
		(layer "F.Cu")
		(net "M_E_CPU1_SB_CB<4>")
	)
	(gr_poly
		(pts
			(xy 141.462252 -266.208002) (xy 141.498066 -266.171934) (xy 141.312138 -265.986006) (xy 141.276324 -266.022074)
			(xy 141.230096 -266.119356) (xy 141.364716 -266.25423)
		)
		(stroke
			(width 0)
			(type solid)
		)
		(fill yes)
		(layer "F.Cu")
		(net "M_E_CPU1_SA_DQ<28>")
	)
	(gr_poly
		(pts
			(xy 141.466824 -276.156166) (xy 141.502638 -276.120098) (xy 141.31671 -275.93417) (xy 141.280896 -275.970238)
			(xy 141.234668 -276.06752) (xy 141.369288 -276.202394)
		)
		(stroke
			(width 0)
			(type solid)
		)
		(fill yes)
		(layer "F.Cu")
		(net "M_E_CPU1_SA_DQ<7>")
	)
	(gr_poly
		(pts
			(xy 141.47165 -265.354308) (xy 141.507464 -265.318494) (xy 141.321536 -265.132566) (xy 141.285722 -265.168634)
			(xy 141.239494 -265.265916) (xy 141.374114 -265.40079)
		)
		(stroke
			(width 0)
			(type solid)
		)
		(fill yes)
		(layer "F.Cu")
		(net "M_E_CPU1_SA_DQ<29>")
	)
	(gr_poly
		(pts
			(xy 141.472666 -279.77973) (xy 141.565376 -279.724358) (xy 141.527784 -279.537414) (xy 141.421104 -279.52192)
			(xy 141.37132 -279.531826) (xy 141.422882 -279.789636)
		)
		(stroke
			(width 0)
			(type solid)
		)
		(fill yes)
		(layer "F.Cu")
		(net "M_E_CPU1_SA_DQ<4>")
	)
	(gr_poly
		(pts
			(xy 141.481556 -280.082244) (xy 141.429994 -279.824434) (xy 141.38021 -279.834594) (xy 141.2875 -279.889966)
			(xy 141.325092 -280.076656) (xy 141.431772 -280.09215)
		)
		(stroke
			(width 0)
			(type solid)
		)
		(fill yes)
		(layer "F.Cu")
		(net "M_E_CPU1_SA_DQ<4>")
	)
	(gr_poly
		(pts
			(xy 141.482572 -233.416856) (xy 141.436344 -233.31932) (xy 141.40053 -233.283506) (xy 141.214602 -233.469434)
			(xy 141.250416 -233.505248) (xy 141.347952 -233.551476)
		)
		(stroke
			(width 0)
			(type solid)
		)
		(fill yes)
		(layer "F.Cu")
		(net "M_E_CPU1_SB_DQ<19>")
	)
	(gr_poly
		(pts
			(xy 141.48435 -271.8562) (xy 141.520164 -271.820132) (xy 141.33449 -271.634204) (xy 141.298422 -271.670272)
			(xy 141.252194 -271.767554) (xy 141.386814 -271.902428)
		)
		(stroke
			(width 0)
			(type solid)
		)
		(fill yes)
		(layer "F.Cu")
		(net "M_E_CPU1_SA_DQ<20>")
	)
	(gr_poly
		(pts
			(xy 141.48562 -276.733254) (xy 141.578076 -276.677882) (xy 141.540738 -276.491192) (xy 141.434058 -276.475698)
			(xy 141.384274 -276.485604) (xy 141.435836 -276.743414)
		)
		(stroke
			(width 0)
			(type solid)
		)
		(fill yes)
		(layer "F.Cu")
		(net "M_E_CPU1_SA_DQ<5>")
	)
	(gr_poly
		(pts
			(xy 141.49197 -234.270296) (xy 141.445742 -234.17276) (xy 141.409674 -234.136946) (xy 141.223746 -234.322874)
			(xy 141.259814 -234.358688) (xy 141.357096 -234.404916)
		)
		(stroke
			(width 0)
			(type solid)
		)
		(fill yes)
		(layer "F.Cu")
		(net "M_E_CPU1_SB_DQ<18>")
	)
	(gr_poly
		(pts
			(xy 141.494002 -271.002252) (xy 141.529816 -270.966184) (xy 141.344142 -270.78051) (xy 141.308074 -270.816324)
			(xy 141.261846 -270.91386) (xy 141.396466 -271.04848)
		)
		(stroke
			(width 0)
			(type solid)
		)
		(fill yes)
		(layer "F.Cu")
		(net "M_E_CPU1_SA_DQ<21>")
	)
	(gr_poly
		(pts
			(xy 141.494256 -277.036022) (xy 141.442694 -276.778212) (xy 141.39291 -276.788118) (xy 141.300454 -276.843744)
			(xy 141.337792 -277.030434) (xy 141.444472 -277.045928)
		)
		(stroke
			(width 0)
			(type solid)
		)
		(fill yes)
		(layer "F.Cu")
		(net "M_E_CPU1_SA_DQ<5>")
	)
	(gr_poly
		(pts
			(xy 141.498574 -257.297428) (xy 141.544802 -257.199892) (xy 141.409928 -257.065272) (xy 141.312646 -257.1115)
			(xy 141.276578 -257.147314) (xy 141.462506 -257.333242)
		)
		(stroke
			(width 0)
			(type solid)
		)
		(fill yes)
		(layer "F.Cu")
		(net "M_E_CPU1_SA_CS_N<2>")
	)
	(gr_poly
		(pts
			(xy 141.502892 -269.30477) (xy 141.538706 -269.268702) (xy 141.353032 -269.083028) (xy 141.316964 -269.118842)
			(xy 141.270736 -269.216378) (xy 141.405356 -269.350998)
		)
		(stroke
			(width 0)
			(type solid)
		)
		(fill yes)
		(layer "F.Cu")
		(net "M_E_CPU1_SA_DQ<26>")
	)
	(gr_poly
		(pts
			(xy 141.505178 -264.05459) (xy 141.551406 -263.957054) (xy 141.416786 -263.822434) (xy 141.319504 -263.868662)
			(xy 141.283436 -263.904476) (xy 141.469364 -264.090404)
		)
		(stroke
			(width 0)
			(type solid)
		)
		(fill yes)
		(layer "F.Cu")
		(net "M_E_CPU1_SA_CB<0>")
	)
	(gr_poly
		(pts
			(xy 141.512036 -268.45133) (xy 141.54785 -268.415262) (xy 141.362176 -268.229588) (xy 141.326108 -268.265402)
			(xy 141.27988 -268.362938) (xy 141.4145 -268.497558)
		)
		(stroke
			(width 0)
			(type solid)
		)
		(fill yes)
		(layer "F.Cu")
		(net "M_E_CPU1_SA_DQ<27>")
	)
	(gr_poly
		(pts
			(xy 141.513814 -238.381286) (xy 141.477492 -238.279686) (xy 141.286992 -238.279686) (xy 141.250924 -238.381286)
			(xy 141.250924 -238.432086) (xy 141.513814 -238.432086)
		)
		(stroke
			(width 0)
			(type solid)
		)
		(fill yes)
		(layer "F.Cu")
		(net "M_E_CPU1_SB_DQ<10>")
	)
	(gr_poly
		(pts
			(xy 141.513814 -237.771686) (xy 141.477492 -237.670086) (xy 141.286992 -237.670086) (xy 141.250924 -237.771686)
			(xy 141.250924 -237.822486) (xy 141.513814 -237.822486)
		)
		(stroke
			(width 0)
			(type solid)
		)
		(fill yes)
		(layer "F.Cu")
		(net "M_E_CPU1_SB_DQ<11>")
	)
	(gr_poly
		(pts
			(xy 141.514576 -263.20115) (xy 141.560804 -263.103614) (xy 141.42593 -262.968994) (xy 141.328648 -263.015222)
			(xy 141.29258 -263.051036) (xy 141.478508 -263.236964)
		)
		(stroke
			(width 0)
			(type solid)
		)
		(fill yes)
		(layer "F.Cu")
		(net "M_E_CPU1_SA_CB<1>")
	)
	(gr_poly
		(pts
			(xy 141.526768 -242.445286) (xy 141.48054 -242.34775) (xy 141.444472 -242.311936) (xy 141.258798 -242.49761)
			(xy 141.294612 -242.533678) (xy 141.392148 -242.579906)
		)
		(stroke
			(width 0)
			(type solid)
		)
		(fill yes)
		(layer "F.Cu")
		(net "M_E_CPU1_SB_CB<7>")
	)
	(gr_poly
		(pts
			(xy 141.535912 -243.298472) (xy 141.489684 -243.20119) (xy 141.45387 -243.165122) (xy 141.267942 -243.35105)
			(xy 141.303756 -243.386864) (xy 141.401292 -243.433346)
		)
		(stroke
			(width 0)
			(type solid)
		)
		(fill yes)
		(layer "F.Cu")
		(net "M_E_CPU1_SB_CB<6>")
	)
	(gr_poly
		(pts
			(xy 141.53769 -278.5491) (xy 141.6304 -278.493728) (xy 141.592808 -278.307038) (xy 141.486128 -278.29129)
			(xy 141.436344 -278.30145) (xy 141.487906 -278.559006)
		)
		(stroke
			(width 0)
			(type solid)
		)
		(fill yes)
		(layer "F.Cu")
		(net "M_E_CPU1_SA_DQ<6>")
	)
	(gr_poly
		(pts
			(xy 141.538706 -265.7094) (xy 141.584934 -265.611864) (xy 141.450314 -265.477244) (xy 141.352778 -265.523472)
			(xy 141.316964 -265.55954) (xy 141.502638 -265.745214)
		)
		(stroke
			(width 0)
			(type solid)
		)
		(fill yes)
		(layer "F.Cu")
		(net "M_E_CPU1_SA_DQ<30>")
	)
	(gr_poly
		(pts
			(xy 141.54658 -278.851868) (xy 141.495018 -278.594058) (xy 141.445234 -278.603964) (xy 141.352524 -278.659336)
			(xy 141.390116 -278.84628) (xy 141.496796 -278.861774)
		)
		(stroke
			(width 0)
			(type solid)
		)
		(fill yes)
		(layer "F.Cu")
		(net "M_E_CPU1_SA_DQ<6>")
	)
	(gr_poly
		(pts
			(xy 141.548104 -264.855706) (xy 141.594332 -264.758424) (xy 141.459712 -264.62355) (xy 141.362176 -264.669778)
			(xy 141.326362 -264.705846) (xy 141.51229 -264.891774)
		)
		(stroke
			(width 0)
			(type solid)
		)
		(fill yes)
		(layer "F.Cu")
		(net "M_E_CPU1_SA_DQ<31>")
	)
	(gr_poly
		(pts
			(xy 141.561312 -271.35709) (xy 141.60754 -271.259554) (xy 141.47292 -271.124934) (xy 141.375384 -271.171162)
			(xy 141.339316 -271.206976) (xy 141.525244 -271.392904)
		)
		(stroke
			(width 0)
			(type solid)
		)
		(fill yes)
		(layer "F.Cu")
		(net "M_E_CPU1_SA_DQ<22>")
	)
	(gr_poly
		(pts
			(xy 141.562582 -260.660642) (xy 141.60881 -260.563106) (xy 141.47419 -260.428486) (xy 141.376654 -260.474714)
			(xy 141.34084 -260.510782) (xy 141.526768 -260.69671)
		)
		(stroke
			(width 0)
			(type solid)
		)
		(fill yes)
		(layer "F.Cu")
		(net "M_E_CPU1_SA_CB<4>")
	)
	(gr_poly
		(pts
			(xy 141.569948 -275.398484) (xy 141.605762 -275.36267) (xy 141.419834 -275.176742) (xy 141.38402 -275.212556)
			(xy 141.337792 -275.310092) (xy 141.472412 -275.444712)
		)
		(stroke
			(width 0)
			(type solid)
		)
		(fill yes)
		(layer "F.Cu")
		(net "M_E_CPU1_SA_DQ<16>")
	)
	(gr_poly
		(pts
			(xy 141.570202 -269.659608) (xy 141.61643 -269.562072) (xy 141.48181 -269.427452) (xy 141.384274 -269.47368)
			(xy 141.34846 -269.509748) (xy 141.534134 -269.695422)
		)
		(stroke
			(width 0)
			(type solid)
		)
		(fill yes)
		(layer "F.Cu")
		(net "M_E_CPU1_SA_DQ<24>")
	)
	(gr_poly
		(pts
			(xy 141.570456 -290.118546) (xy 141.519656 -290.118546) (xy 141.418056 -290.154868) (xy 141.418056 -290.345368)
			(xy 141.519656 -290.381436) (xy 141.570456 -290.381436)
		)
		(stroke
			(width 0)
			(type solid)
		)
		(fill yes)
		(layer "F.Cu")
		(net "M_E_CPU1_SA_DQ<4>")
	)
	(gr_poly
		(pts
			(xy 141.570456 -289.521646) (xy 141.519656 -289.521646) (xy 141.418056 -289.557968) (xy 141.418056 -289.748468)
			(xy 141.519656 -289.784536) (xy 141.570456 -289.784536)
		)
		(stroke
			(width 0)
			(type solid)
		)
		(fill yes)
		(layer "F.Cu")
		(net "M_E_CPU1_SA_DQ<4>")
	)
	(gr_poly
		(pts
			(xy 141.570456 -288.924746) (xy 141.519656 -288.924746) (xy 141.418056 -288.961068) (xy 141.418056 -289.151568)
			(xy 141.519656 -289.187636) (xy 141.570456 -289.187636)
		)
		(stroke
			(width 0)
			(type solid)
		)
		(fill yes)
		(layer "F.Cu")
		(net "M_E_CPU1_SA_DQ<4>")
	)
	(gr_poly
		(pts
			(xy 141.570456 -288.327846) (xy 141.519656 -288.327846) (xy 141.418056 -288.364168) (xy 141.418056 -288.554668)
			(xy 141.519656 -288.590736) (xy 141.570456 -288.590736)
		)
		(stroke
			(width 0)
			(type solid)
		)
		(fill yes)
		(layer "F.Cu")
		(net "M_E_CPU1_SA_DQ<4>")
	)
	(gr_poly
		(pts
			(xy 141.570456 -287.730946) (xy 141.519656 -287.730946) (xy 141.418056 -287.767268) (xy 141.418056 -287.957768)
			(xy 141.519656 -287.993836) (xy 141.570456 -287.993836)
		)
		(stroke
			(width 0)
			(type solid)
		)
		(fill yes)
		(layer "F.Cu")
		(net "M_E_CPU1_SA_DQ<4>")
	)
	(gr_poly
		(pts
			(xy 141.570456 -287.134046) (xy 141.519656 -287.134046) (xy 141.418056 -287.170368) (xy 141.418056 -287.360868)
			(xy 141.519656 -287.396936) (xy 141.570456 -287.396936)
		)
		(stroke
			(width 0)
			(type solid)
		)
		(fill yes)
		(layer "F.Cu")
		(net "M_E_CPU1_SA_DQ<4>")
	)
	(gr_poly
		(pts
			(xy 141.570456 -286.537146) (xy 141.519656 -286.537146) (xy 141.418056 -286.573468) (xy 141.418056 -286.763968)
			(xy 141.519656 -286.800036) (xy 141.570456 -286.800036)
		)
		(stroke
			(width 0)
			(type solid)
		)
		(fill yes)
		(layer "F.Cu")
		(net "M_E_CPU1_SA_DQ<4>")
	)
	(gr_poly
		(pts
			(xy 141.570456 -285.940246) (xy 141.519656 -285.940246) (xy 141.418056 -285.976568) (xy 141.418056 -286.167068)
			(xy 141.519656 -286.203136) (xy 141.570456 -286.203136)
		)
		(stroke
			(width 0)
			(type solid)
		)
		(fill yes)
		(layer "F.Cu")
		(net "M_E_CPU1_SA_DQ<4>")
	)
	(gr_poly
		(pts
			(xy 141.570456 -285.343346) (xy 141.519656 -285.343346) (xy 141.418056 -285.379668) (xy 141.418056 -285.570168)
			(xy 141.519656 -285.606236) (xy 141.570456 -285.606236)
		)
		(stroke
			(width 0)
			(type solid)
		)
		(fill yes)
		(layer "F.Cu")
		(net "M_E_CPU1_SA_DQ<4>")
	)
	(gr_poly
		(pts
			(xy 141.570456 -284.746446) (xy 141.519656 -284.746446) (xy 141.418056 -284.782768) (xy 141.418056 -284.973268)
			(xy 141.519656 -285.009336) (xy 141.570456 -285.009336)
		)
		(stroke
			(width 0)
			(type solid)
		)
		(fill yes)
		(layer "F.Cu")
		(net "M_E_CPU1_SA_DQ<4>")
	)
	(gr_poly
		(pts
			(xy 141.570456 -284.149546) (xy 141.519656 -284.149546) (xy 141.418056 -284.185868) (xy 141.418056 -284.376368)
			(xy 141.519656 -284.412436) (xy 141.570456 -284.412436)
		)
		(stroke
			(width 0)
			(type solid)
		)
		(fill yes)
		(layer "F.Cu")
		(net "M_E_CPU1_SA_DQ<4>")
	)
	(gr_poly
		(pts
			(xy 141.570456 -283.552646) (xy 141.519656 -283.552646) (xy 141.418056 -283.588968) (xy 141.418056 -283.779468)
			(xy 141.519656 -283.815536) (xy 141.570456 -283.815536)
		)
		(stroke
			(width 0)
			(type solid)
		)
		(fill yes)
		(layer "F.Cu")
		(net "M_E_CPU1_SA_DQ<4>")
	)
	(gr_poly
		(pts
			(xy 141.570456 -282.955746) (xy 141.519656 -282.955746) (xy 141.418056 -282.992068) (xy 141.418056 -283.182568)
			(xy 141.519656 -283.218636) (xy 141.570456 -283.218636)
		)
		(stroke
			(width 0)
			(type solid)
		)
		(fill yes)
		(layer "F.Cu")
		(net "M_E_CPU1_SA_DQ<4>")
	)
	(gr_poly
		(pts
			(xy 141.570456 -282.358846) (xy 141.519656 -282.358846) (xy 141.418056 -282.395168) (xy 141.418056 -282.585668)
			(xy 141.519656 -282.621736) (xy 141.570456 -282.621736)
		)
		(stroke
			(width 0)
			(type solid)
		)
		(fill yes)
		(layer "F.Cu")
		(net "M_E_CPU1_SA_DQ<4>")
	)
	(gr_poly
		(pts
			(xy 141.570456 -281.761946) (xy 141.519656 -281.761946) (xy 141.418056 -281.798268) (xy 141.418056 -281.988768)
			(xy 141.519656 -282.024836) (xy 141.570456 -282.024836)
		)
		(stroke
			(width 0)
			(type solid)
		)
		(fill yes)
		(layer "F.Cu")
		(net "M_E_CPU1_SA_DQ<4>")
	)
	(gr_poly
		(pts
			(xy 141.570456 -281.165046) (xy 141.519656 -281.165046) (xy 141.418056 -281.201368) (xy 141.418056 -281.391868)
			(xy 141.519656 -281.427936) (xy 141.570456 -281.427936)
		)
		(stroke
			(width 0)
			(type solid)
		)
		(fill yes)
		(layer "F.Cu")
		(net "M_E_CPU1_SA_DQ<4>")
	)
	(gr_poly
		(pts
			(xy 141.570456 -270.503396) (xy 141.616684 -270.406114) (xy 141.482064 -270.271494) (xy 141.384528 -270.317722)
			(xy 141.348714 -270.353536) (xy 141.534642 -270.539464)
		)
		(stroke
			(width 0)
			(type solid)
		)
		(fill yes)
		(layer "F.Cu")
		(net "M_E_CPU1_SA_DQ<23>")
	)
	(gr_poly
		(pts
			(xy 141.575536 -229.657656) (xy 141.539468 -229.621842) (xy 141.442186 -229.575614) (xy 141.307312 -229.710234)
			(xy 141.35354 -229.80777) (xy 141.389608 -229.843584)
		)
		(stroke
			(width 0)
			(type solid)
		)
		(fill yes)
		(layer "F.Cu")
		(net "M_E_CPU1_SB_DQ<23>")
	)
	(gr_poly
		(pts
			(xy 141.579092 -274.545298) (xy 141.614906 -274.50923) (xy 141.428978 -274.323302) (xy 141.393164 -274.35937)
			(xy 141.346936 -274.456652) (xy 141.481556 -274.591526)
		)
		(stroke
			(width 0)
			(type solid)
		)
		(fill yes)
		(layer "F.Cu")
		(net "M_E_CPU1_SA_DQ<17>")
	)
	(gr_poly
		(pts
			(xy 141.579346 -268.806168) (xy 141.625574 -268.708632) (xy 141.490954 -268.574012) (xy 141.393418 -268.62024)
			(xy 141.357604 -268.656308) (xy 141.543278 -268.841982)
		)
		(stroke
			(width 0)
			(type solid)
		)
		(fill yes)
		(layer "F.Cu")
		(net "M_E_CPU1_SA_DQ<25>")
	)
	(gr_poly
		(pts
			(xy 141.58468 -230.511096) (xy 141.548866 -230.475282) (xy 141.45133 -230.429054) (xy 141.31671 -230.563674)
			(xy 141.362938 -230.660956) (xy 141.398752 -230.697024)
		)
		(stroke
			(width 0)
			(type solid)
		)
		(fill yes)
		(layer "F.Cu")
		(net "M_E_CPU1_SB_DQ<22>")
	)
	(gr_poly
		(pts
			(xy 141.602714 -277.318724) (xy 141.69517 -277.263352) (xy 141.657832 -277.076408) (xy 141.551152 -277.060914)
			(xy 141.501368 -277.07082) (xy 141.55293 -277.32863)
		)
		(stroke
			(width 0)
			(type solid)
		)
		(fill yes)
		(layer "F.Cu")
		(net "M_E_CPU1_SA_DQ<5>")
	)
	(gr_poly
		(pts
			(xy 141.611604 -277.621238) (xy 141.560042 -277.363428) (xy 141.510004 -277.373588) (xy 141.417548 -277.42896)
			(xy 141.454886 -277.61565) (xy 141.56182 -277.631144)
		)
		(stroke
			(width 0)
			(type solid)
		)
		(fill yes)
		(layer "F.Cu")
		(net "M_E_CPU1_SA_DQ<5>")
	)
	(gr_poly
		(pts
			(xy 141.611604 -233.072432) (xy 141.575536 -233.036618) (xy 141.478254 -232.99039) (xy 141.34338 -233.12501)
			(xy 141.389608 -233.222546) (xy 141.425676 -233.25836)
		)
		(stroke
			(width 0)
			(type solid)
		)
		(fill yes)
		(layer "F.Cu")
		(net "M_E_CPU1_SB_DQ<19>")
	)
	(gr_poly
		(pts
			(xy 141.620748 -233.925872) (xy 141.584934 -233.890058) (xy 141.487398 -233.843576) (xy 141.352778 -233.97845)
			(xy 141.399006 -234.075732) (xy 141.43482 -234.1118)
		)
		(stroke
			(width 0)
			(type solid)
		)
		(fill yes)
		(layer "F.Cu")
		(net "M_E_CPU1_SB_DQ<18>")
	)
	(gr_poly
		(pts
			(xy 141.637766 -257.580384) (xy 141.67358 -257.544316) (xy 141.487652 -257.358388) (xy 141.451838 -257.394456)
			(xy 141.40561 -257.491738) (xy 141.54023 -257.626612)
		)
		(stroke
			(width 0)
			(type solid)
		)
		(fill yes)
		(layer "F.Cu")
		(net "M_E_CPU1_SA_CS_N<2>")
	)
	(gr_poly
		(pts
			(xy 141.64437 -264.337292) (xy 141.680438 -264.301478) (xy 141.49451 -264.11555) (xy 141.458696 -264.151364)
			(xy 141.412214 -264.2489) (xy 141.547088 -264.38352)
		)
		(stroke
			(width 0)
			(type solid)
		)
		(fill yes)
		(layer "F.Cu")
		(net "M_E_CPU1_SA_CB<0>")
	)
	(gr_poly
		(pts
			(xy 141.646148 -274.900136) (xy 141.69263 -274.8026) (xy 141.557756 -274.66798) (xy 141.460474 -274.714208)
			(xy 141.424406 -274.750022) (xy 141.610334 -274.93595)
		)
		(stroke
			(width 0)
			(type solid)
		)
		(fill yes)
		(layer "F.Cu")
		(net "M_E_CPU1_SA_DQ<18>")
	)
	(gr_poly
		(pts
			(xy 141.64691 -256.726944) (xy 141.682724 -256.690876) (xy 141.49705 -256.505202) (xy 141.460982 -256.541016)
			(xy 141.414754 -256.638552) (xy 141.549374 -256.773172)
		)
		(stroke
			(width 0)
			(type solid)
		)
		(fill yes)
		(layer "F.Cu")
		(net "M_E_CPU1_SA_CS_N<3>")
	)
	(gr_poly
		(pts
			(xy 141.653768 -263.484106) (xy 141.689582 -263.448038) (xy 141.503654 -263.26211) (xy 141.46784 -263.298178)
			(xy 141.421612 -263.39546) (xy 141.556232 -263.530334)
		)
		(stroke
			(width 0)
			(type solid)
		)
		(fill yes)
		(layer "F.Cu")
		(net "M_E_CPU1_SA_CB<1>")
	)
	(gr_poly
		(pts
			(xy 141.655038 -279.13457) (xy 141.747494 -279.078944) (xy 141.710156 -278.892254) (xy 141.603222 -278.87676)
			(xy 141.553438 -278.886666) (xy 141.605 -279.144476)
		)
		(stroke
			(width 0)
			(type solid)
		)
		(fill yes)
		(layer "F.Cu")
		(net "M_E_CPU1_SA_DQ<6>")
	)
	(gr_poly
		(pts
			(xy 141.655546 -242.100862) (xy 141.619732 -242.064794) (xy 141.522196 -242.018566) (xy 141.387576 -242.153186)
			(xy 141.433804 -242.250722) (xy 141.469618 -242.28679)
		)
		(stroke
			(width 0)
			(type solid)
		)
		(fill yes)
		(layer "F.Cu")
		(net "M_E_CPU1_SB_CB<7>")
	)
	(gr_poly
		(pts
			(xy 141.6558 -274.046442) (xy 141.702028 -273.948906) (xy 141.567408 -273.814286) (xy 141.469872 -273.860514)
			(xy 141.434058 -273.896582) (xy 141.619732 -274.082256)
		)
		(stroke
			(width 0)
			(type solid)
		)
		(fill yes)
		(layer "F.Cu")
		(net "M_E_CPU1_SA_DQ<19>")
	)
	(gr_poly
		(pts
			(xy 141.66215 -230.217726) (xy 141.615922 -230.120444) (xy 141.580108 -230.084376) (xy 141.39418 -230.270304)
			(xy 141.429994 -230.306118) (xy 141.52753 -230.3526)
		)
		(stroke
			(width 0)
			(type solid)
		)
		(fill yes)
		(layer "F.Cu")
		(net "M_E_CPU1_SB_DQ<21>")
	)
	(gr_poly
		(pts
			(xy 141.663674 -279.437084) (xy 141.612112 -279.179274) (xy 141.562328 -279.18918) (xy 141.469872 -279.244806)
			(xy 141.50721 -279.431496) (xy 141.61389 -279.44699)
		)
		(stroke
			(width 0)
			(type solid)
		)
		(fill yes)
		(layer "F.Cu")
		(net "M_E_CPU1_SA_DQ<6>")
	)
	(gr_poly
		(pts
			(xy 141.664944 -242.954048) (xy 141.628876 -242.918234) (xy 141.531594 -242.872006) (xy 141.39672 -243.006626)
			(xy 141.442948 -243.104162) (xy 141.479016 -243.139976)
		)
		(stroke
			(width 0)
			(type solid)
		)
		(fill yes)
		(layer "F.Cu")
		(net "M_E_CPU1_SB_CB<6>")
	)
	(gr_poly
		(pts
			(xy 141.665452 -247.240552) (xy 141.665452 -247.189752) (xy 141.402308 -247.189752) (xy 141.402308 -247.240552)
			(xy 141.43863 -247.342152) (xy 141.62913 -247.342152)
		)
		(stroke
			(width 0)
			(type solid)
		)
		(fill yes)
		(layer "F.Cu")
		(net "M_E_CPU1_SB_CA<6>")
	)
	(gr_poly
		(pts
			(xy 141.665452 -246.935752) (xy 141.665452 -246.884952) (xy 141.402308 -246.884952) (xy 141.402308 -246.935752)
			(xy 141.43863 -247.037352) (xy 141.62913 -247.037352)
		)
		(stroke
			(width 0)
			(type solid)
		)
		(fill yes)
		(layer "F.Cu")
		(net "M_E_CPU1_SB_PAR")
	)
	(gr_poly
		(pts
			(xy 141.665452 -246.630952) (xy 141.665452 -246.580152) (xy 141.402308 -246.580152) (xy 141.402308 -246.630952)
			(xy 141.43863 -246.732552) (xy 141.62913 -246.732552)
		)
		(stroke
			(width 0)
			(type solid)
		)
		(fill yes)
		(layer "F.Cu")
		(net "M_E_CPU1_SB_CS_N<0>")
	)
	(gr_poly
		(pts
			(xy 141.665452 -246.326152) (xy 141.665452 -246.275352) (xy 141.402308 -246.275352) (xy 141.402308 -246.326152)
			(xy 141.43863 -246.427752) (xy 141.62913 -246.427752)
		)
		(stroke
			(width 0)
			(type solid)
		)
		(fill yes)
		(layer "F.Cu")
		(net "M_E_CPU1_SB_CS_N<2>")
	)
	(gr_poly
		(pts
			(xy 141.665452 -246.021352) (xy 141.665452 -245.970552) (xy 141.402308 -245.970552) (xy 141.402308 -246.021352)
			(xy 141.43863 -246.122952) (xy 141.62913 -246.122952)
		)
		(stroke
			(width 0)
			(type solid)
		)
		(fill yes)
		(layer "F.Cu")
		(net "M_E_CPU1_SB_CS_N<1>")
	)
	(gr_poly
		(pts
			(xy 141.665452 -245.716552) (xy 141.665452 -245.665752) (xy 141.402308 -245.665752) (xy 141.402308 -245.716552)
			(xy 141.43863 -245.818152) (xy 141.62913 -245.818152)
		)
		(stroke
			(width 0)
			(type solid)
		)
		(fill yes)
		(layer "F.Cu")
		(net "M_E_CPU1_SB_CS_N<3>")
	)
	(gr_poly
		(pts
			(xy 141.671548 -231.071166) (xy 141.62532 -230.97363) (xy 141.589252 -230.937816) (xy 141.403324 -231.123744)
			(xy 141.439392 -231.159558) (xy 141.536674 -231.205786)
		)
		(stroke
			(width 0)
			(type solid)
		)
		(fill yes)
		(layer "F.Cu")
		(net "M_E_CPU1_SB_DQ<20>")
	)
	(gr_poly
		(pts
			(xy 141.677898 -265.992356) (xy 141.713712 -265.956288) (xy 141.527784 -265.77036) (xy 141.49197 -265.806428)
			(xy 141.445742 -265.90371) (xy 141.580362 -266.038584)
		)
		(stroke
			(width 0)
			(type solid)
		)
		(fill yes)
		(layer "F.Cu")
		(net "M_E_CPU1_SA_DQ<30>")
	)
	(gr_poly
		(pts
			(xy 141.687296 -265.138662) (xy 141.723364 -265.102848) (xy 141.537436 -264.91692) (xy 141.501368 -264.952734)
			(xy 141.45514 -265.05027) (xy 141.58976 -265.18489)
		)
		(stroke
			(width 0)
			(type solid)
		)
		(fill yes)
		(layer "F.Cu")
		(net "M_E_CPU1_SA_DQ<31>")
	)
	(gr_poly
		(pts
			(xy 141.698218 -233.632502) (xy 141.65199 -233.534966) (xy 141.616176 -233.499152) (xy 141.430248 -233.68508)
			(xy 141.466062 -233.720894) (xy 141.563598 -233.767122)
		)
		(stroke
			(width 0)
			(type solid)
		)
		(fill yes)
		(layer "F.Cu")
		(net "M_E_CPU1_SB_DQ<17>")
	)
	(gr_poly
		(pts
			(xy 141.700504 -271.640046) (xy 141.736318 -271.603978) (xy 141.55039 -271.41805) (xy 141.514576 -271.454118)
			(xy 141.468348 -271.5514) (xy 141.602968 -271.686274)
		)
		(stroke
			(width 0)
			(type solid)
		)
		(fill yes)
		(layer "F.Cu")
		(net "M_E_CPU1_SA_DQ<22>")
	)
	(gr_poly
		(pts
			(xy 141.701774 -260.943598) (xy 141.737588 -260.90753) (xy 141.551914 -260.721856) (xy 141.515846 -260.75767)
			(xy 141.469618 -260.855206) (xy 141.604238 -260.989826)
		)
		(stroke
			(width 0)
			(type solid)
		)
		(fill yes)
		(layer "F.Cu")
		(net "M_E_CPU1_SA_CB<4>")
	)
	(gr_poly
		(pts
			(xy 141.704822 -257.935222) (xy 141.75105 -257.837686) (xy 141.61643 -257.703066) (xy 141.518894 -257.749294)
			(xy 141.48308 -257.785362) (xy 141.668754 -257.971036)
		)
		(stroke
			(width 0)
			(type solid)
		)
		(fill yes)
		(layer "F.Cu")
		(net "M_E_CPU1_SA_CS_N<0>")
	)
	(gr_poly
		(pts
			(xy 141.707616 -234.485942) (xy 141.661388 -234.388406) (xy 141.62532 -234.352592) (xy 141.439392 -234.53852)
			(xy 141.47546 -234.574334) (xy 141.572742 -234.620562)
		)
		(stroke
			(width 0)
			(type solid)
		)
		(fill yes)
		(layer "F.Cu")
		(net "M_E_CPU1_SB_DQ<16>")
	)
	(gr_poly
		(pts
			(xy 141.709394 -269.942564) (xy 141.745208 -269.906496) (xy 141.55928 -269.720568) (xy 141.523466 -269.756636)
			(xy 141.477238 -269.853918) (xy 141.611858 -269.988792)
		)
		(stroke
			(width 0)
			(type solid)
		)
		(fill yes)
		(layer "F.Cu")
		(net "M_E_CPU1_SA_DQ<24>")
	)
	(gr_poly
		(pts
			(xy 141.709648 -270.786352) (xy 141.745716 -270.750538) (xy 141.559788 -270.56461) (xy 141.52372 -270.600424)
			(xy 141.477492 -270.69796) (xy 141.612366 -270.83258)
		)
		(stroke
			(width 0)
			(type solid)
		)
		(fill yes)
		(layer "F.Cu")
		(net "M_E_CPU1_SA_DQ<23>")
	)
	(gr_poly
		(pts
			(xy 141.71422 -257.081782) (xy 141.760448 -256.984246) (xy 141.625574 -256.849626) (xy 141.528292 -256.895854)
			(xy 141.492224 -256.931668) (xy 141.678152 -257.117596)
		)
		(stroke
			(width 0)
			(type solid)
		)
		(fill yes)
		(layer "F.Cu")
		(net "M_E_CPU1_SA_CS_N<1>")
	)
	(gr_poly
		(pts
			(xy 141.718538 -269.089124) (xy 141.754352 -269.053056) (xy 141.568424 -268.867128) (xy 141.53261 -268.903196)
			(xy 141.486382 -269.000478) (xy 141.621002 -269.135352)
		)
		(stroke
			(width 0)
			(type solid)
		)
		(fill yes)
		(layer "F.Cu")
		(net "M_E_CPU1_SA_DQ<25>")
	)
	(gr_poly
		(pts
			(xy 141.719808 -277.90394) (xy 141.812518 -277.848568) (xy 141.774926 -277.661624) (xy 141.668246 -277.64613)
			(xy 141.618462 -277.656036) (xy 141.670024 -277.913846)
		)
		(stroke
			(width 0)
			(type solid)
		)
		(fill yes)
		(layer "F.Cu")
		(net "M_E_CPU1_SA_DQ<5>")
	)
	(gr_poly
		(pts
			(xy 141.720824 -263.838944) (xy 141.767052 -263.741408) (xy 141.632432 -263.606788) (xy 141.53515 -263.653016)
			(xy 141.499082 -263.68883) (xy 141.68501 -263.874758)
		)
		(stroke
			(width 0)
			(type solid)
		)
		(fill yes)
		(layer "F.Cu")
		(net "M_E_CPU1_SA_CB<2>")
	)
	(gr_poly
		(pts
			(xy 141.722856 -290.643818) (xy 141.722856 -290.453318) (xy 141.621256 -290.416996) (xy 141.570456 -290.416996)
			(xy 141.570456 -290.679886) (xy 141.621256 -290.679886)
		)
		(stroke
			(width 0)
			(type solid)
		)
		(fill yes)
		(layer "F.Cu")
		(net "M_E_CPU1_SA_DQ<4>")
	)
	(gr_poly
		(pts
			(xy 141.722856 -290.046918) (xy 141.722856 -289.856418) (xy 141.621256 -289.820096) (xy 141.570456 -289.820096)
			(xy 141.570456 -290.082986) (xy 141.621256 -290.082986)
		)
		(stroke
			(width 0)
			(type solid)
		)
		(fill yes)
		(layer "F.Cu")
		(net "M_E_CPU1_SA_DQ<4>")
	)
	(gr_poly
		(pts
			(xy 141.722856 -289.450018) (xy 141.722856 -289.259518) (xy 141.621256 -289.223196) (xy 141.570456 -289.223196)
			(xy 141.570456 -289.486086) (xy 141.621256 -289.486086)
		)
		(stroke
			(width 0)
			(type solid)
		)
		(fill yes)
		(layer "F.Cu")
		(net "M_E_CPU1_SA_DQ<4>")
	)
	(gr_poly
		(pts
			(xy 141.722856 -288.853118) (xy 141.722856 -288.662618) (xy 141.621256 -288.626296) (xy 141.570456 -288.626296)
			(xy 141.570456 -288.889186) (xy 141.621256 -288.889186)
		)
		(stroke
			(width 0)
			(type solid)
		)
		(fill yes)
		(layer "F.Cu")
		(net "M_E_CPU1_SA_DQ<4>")
	)
	(gr_poly
		(pts
			(xy 141.722856 -288.256218) (xy 141.722856 -288.065718) (xy 141.621256 -288.029396) (xy 141.570456 -288.029396)
			(xy 141.570456 -288.292286) (xy 141.621256 -288.292286)
		)
		(stroke
			(width 0)
			(type solid)
		)
		(fill yes)
		(layer "F.Cu")
		(net "M_E_CPU1_SA_DQ<4>")
	)
	(gr_poly
		(pts
			(xy 141.722856 -287.659318) (xy 141.722856 -287.468818) (xy 141.621256 -287.432496) (xy 141.570456 -287.432496)
			(xy 141.570456 -287.695386) (xy 141.621256 -287.695386)
		)
		(stroke
			(width 0)
			(type solid)
		)
		(fill yes)
		(layer "F.Cu")
		(net "M_E_CPU1_SA_DQ<4>")
	)
	(gr_poly
		(pts
			(xy 141.722856 -287.062418) (xy 141.722856 -286.871918) (xy 141.621256 -286.835596) (xy 141.570456 -286.835596)
			(xy 141.570456 -287.098486) (xy 141.621256 -287.098486)
		)
		(stroke
			(width 0)
			(type solid)
		)
		(fill yes)
		(layer "F.Cu")
		(net "M_E_CPU1_SA_DQ<4>")
	)
	(gr_poly
		(pts
			(xy 141.722856 -286.465518) (xy 141.722856 -286.275018) (xy 141.621256 -286.238696) (xy 141.570456 -286.238696)
			(xy 141.570456 -286.501586) (xy 141.621256 -286.501586)
		)
		(stroke
			(width 0)
			(type solid)
		)
		(fill yes)
		(layer "F.Cu")
		(net "M_E_CPU1_SA_DQ<4>")
	)
	(gr_poly
		(pts
			(xy 141.722856 -285.868618) (xy 141.722856 -285.678118) (xy 141.621256 -285.641796) (xy 141.570456 -285.641796)
			(xy 141.570456 -285.904686) (xy 141.621256 -285.904686)
		)
		(stroke
			(width 0)
			(type solid)
		)
		(fill yes)
		(layer "F.Cu")
		(net "M_E_CPU1_SA_DQ<4>")
	)
	(gr_poly
		(pts
			(xy 141.722856 -285.271718) (xy 141.722856 -285.081218) (xy 141.621256 -285.044896) (xy 141.570456 -285.044896)
			(xy 141.570456 -285.307786) (xy 141.621256 -285.307786)
		)
		(stroke
			(width 0)
			(type solid)
		)
		(fill yes)
		(layer "F.Cu")
		(net "M_E_CPU1_SA_DQ<4>")
	)
	(gr_poly
		(pts
			(xy 141.722856 -284.674818) (xy 141.722856 -284.484318) (xy 141.621256 -284.447996) (xy 141.570456 -284.447996)
			(xy 141.570456 -284.710886) (xy 141.621256 -284.710886)
		)
		(stroke
			(width 0)
			(type solid)
		)
		(fill yes)
		(layer "F.Cu")
		(net "M_E_CPU1_SA_DQ<4>")
	)
	(gr_poly
		(pts
			(xy 141.722856 -284.077918) (xy 141.722856 -283.887418) (xy 141.621256 -283.851096) (xy 141.570456 -283.851096)
			(xy 141.570456 -284.113986) (xy 141.621256 -284.113986)
		)
		(stroke
			(width 0)
			(type solid)
		)
		(fill yes)
		(layer "F.Cu")
		(net "M_E_CPU1_SA_DQ<4>")
	)
	(gr_poly
		(pts
			(xy 141.722856 -283.481018) (xy 141.722856 -283.290518) (xy 141.621256 -283.254196) (xy 141.570456 -283.254196)
			(xy 141.570456 -283.517086) (xy 141.621256 -283.517086)
		)
		(stroke
			(width 0)
			(type solid)
		)
		(fill yes)
		(layer "F.Cu")
		(net "M_E_CPU1_SA_DQ<4>")
	)
	(gr_poly
		(pts
			(xy 141.722856 -282.884118) (xy 141.722856 -282.693618) (xy 141.621256 -282.657296) (xy 141.570456 -282.657296)
			(xy 141.570456 -282.920186) (xy 141.621256 -282.920186)
		)
		(stroke
			(width 0)
			(type solid)
		)
		(fill yes)
		(layer "F.Cu")
		(net "M_E_CPU1_SA_DQ<4>")
	)
	(gr_poly
		(pts
			(xy 141.722856 -282.287218) (xy 141.722856 -282.096718) (xy 141.621256 -282.060396) (xy 141.570456 -282.060396)
			(xy 141.570456 -282.323286) (xy 141.621256 -282.323286)
		)
		(stroke
			(width 0)
			(type solid)
		)
		(fill yes)
		(layer "F.Cu")
		(net "M_E_CPU1_SA_DQ<4>")
	)
	(gr_poly
		(pts
			(xy 141.722856 -281.690318) (xy 141.722856 -281.499818) (xy 141.621256 -281.463496) (xy 141.570456 -281.463496)
			(xy 141.570456 -281.726386) (xy 141.621256 -281.726386)
		)
		(stroke
			(width 0)
			(type solid)
		)
		(fill yes)
		(layer "F.Cu")
		(net "M_E_CPU1_SA_DQ<4>")
	)
	(gr_poly
		(pts
			(xy 141.722856 -281.093418) (xy 141.722856 -280.902918) (xy 141.621256 -280.866596) (xy 141.570456 -280.866596)
			(xy 141.570456 -281.129486) (xy 141.621256 -281.129486)
		)
		(stroke
			(width 0)
			(type solid)
		)
		(fill yes)
		(layer "F.Cu")
		(net "M_E_CPU1_SA_DQ<4>")
	)
	(gr_poly
		(pts
			(xy 141.723618 -256.228596) (xy 141.769846 -256.13106) (xy 141.634972 -255.99644) (xy 141.53769 -256.042668)
			(xy 141.501622 -256.078482) (xy 141.68755 -256.26441)
		)
		(stroke
			(width 0)
			(type solid)
		)
		(fill yes)
		(layer "F.Cu")
		(net "M_E_CPU1_SA_CA<0>")
	)
	(gr_poly
		(pts
			(xy 141.728698 -278.206454) (xy 141.677136 -277.948898) (xy 141.627352 -277.958804) (xy 141.534642 -278.014176)
			(xy 141.572234 -278.200866) (xy 141.678914 -278.216614)
		)
		(stroke
			(width 0)
			(type solid)
		)
		(fill yes)
		(layer "F.Cu")
		(net "M_E_CPU1_SA_DQ<5>")
	)
	(gr_poly
		(pts
			(xy 141.730222 -262.985504) (xy 141.77645 -262.887968) (xy 141.641576 -262.753348) (xy 141.544294 -262.799576)
			(xy 141.508226 -262.83539) (xy 141.694154 -263.021318)
		)
		(stroke
			(width 0)
			(type solid)
		)
		(fill yes)
		(layer "F.Cu")
		(net "M_E_CPU1_SA_CB<3>")
	)
	(gr_poly
		(pts
			(xy 141.742414 -242.660932) (xy 141.696186 -242.563396) (xy 141.660118 -242.527582) (xy 141.474444 -242.713256)
			(xy 141.510258 -242.749324) (xy 141.607794 -242.795552)
		)
		(stroke
			(width 0)
			(type solid)
		)
		(fill yes)
		(layer "F.Cu")
		(net "M_E_CPU1_SB_CB<5>")
	)
	(gr_poly
		(pts
			(xy 141.744954 -266.347194) (xy 141.791436 -266.249658) (xy 141.656562 -266.115038) (xy 141.55928 -266.161266)
			(xy 141.523212 -266.19708) (xy 141.70914 -266.383008)
		)
		(stroke
			(width 0)
			(type solid)
		)
		(fill yes)
		(layer "F.Cu")
		(net "M_E_CPU1_SA_DQ<28>")
	)
	(gr_poly
		(pts
			(xy 141.751558 -243.514118) (xy 141.70533 -243.416836) (xy 141.669516 -243.380768) (xy 141.483588 -243.566696)
			(xy 141.519402 -243.60251) (xy 141.616938 -243.648992)
		)
		(stroke
			(width 0)
			(type solid)
		)
		(fill yes)
		(layer "F.Cu")
		(net "M_E_CPU1_SB_CB<4>")
	)
	(gr_poly
		(pts
			(xy 141.754352 -265.4935) (xy 141.80058 -265.396218) (xy 141.66596 -265.261598) (xy 141.568424 -265.307826)
			(xy 141.53261 -265.34364) (xy 141.718538 -265.529568)
		)
		(stroke
			(width 0)
			(type solid)
		)
		(fill yes)
		(layer "F.Cu")
		(net "M_E_CPU1_SA_DQ<29>")
	)
	(gr_poly
		(pts
			(xy 141.767306 -271.995392) (xy 141.813534 -271.897856) (xy 141.678914 -271.763236) (xy 141.581378 -271.809464)
			(xy 141.545564 -271.845278) (xy 141.731238 -272.031206)
		)
		(stroke
			(width 0)
			(type solid)
		)
		(fill yes)
		(layer "F.Cu")
		(net "M_E_CPU1_SA_DQ<20>")
	)
	(gr_poly
		(pts
			(xy 141.772132 -279.719786) (xy 141.864588 -279.664414) (xy 141.82725 -279.47747) (xy 141.72057 -279.461976)
			(xy 141.670532 -279.471882) (xy 141.722348 -279.729692)
		)
		(stroke
			(width 0)
			(type solid)
		)
		(fill yes)
		(layer "F.Cu")
		(net "M_E_CPU1_SA_DQ<6>")
	)
	(gr_poly
		(pts
			(xy 141.776958 -271.141444) (xy 141.823186 -271.043908) (xy 141.688312 -270.909288) (xy 141.59103 -270.955516)
			(xy 141.554962 -270.99133) (xy 141.74089 -271.177258)
		)
		(stroke
			(width 0)
			(type solid)
		)
		(fill yes)
		(layer "F.Cu")
		(net "M_E_CPU1_SA_DQ<21>")
	)
	(gr_poly
		(pts
			(xy 141.778228 -260.444996) (xy 141.824456 -260.34746) (xy 141.689836 -260.21284) (xy 141.5923 -260.259068)
			(xy 141.556486 -260.295136) (xy 141.742414 -260.481064)
		)
		(stroke
			(width 0)
			(type solid)
		)
		(fill yes)
		(layer "F.Cu")
		(net "M_E_CPU1_SA_CB<6>")
	)
	(gr_poly
		(pts
			(xy 141.780768 -280.0223) (xy 141.729206 -279.76449) (xy 141.679422 -279.77465) (xy 141.586966 -279.830022)
			(xy 141.624304 -280.016712) (xy 141.730984 -280.032206)
		)
		(stroke
			(width 0)
			(type solid)
		)
		(fill yes)
		(layer "F.Cu")
		(net "M_E_CPU1_SA_DQ<6>")
	)
	(gr_poly
		(pts
			(xy 141.785086 -276.673564) (xy 141.877542 -276.617938) (xy 141.840204 -276.431248) (xy 141.73327 -276.415754)
			(xy 141.683486 -276.42566) (xy 141.735302 -276.68347)
		)
		(stroke
			(width 0)
			(type solid)
		)
		(fill yes)
		(layer "F.Cu")
		(net "M_E_CPU1_SA_DQ<7>")
	)
	(gr_poly
		(pts
			(xy 141.785594 -275.182838) (xy 141.821408 -275.147024) (xy 141.63548 -274.961096) (xy 141.599666 -274.99691)
			(xy 141.553438 -275.094446) (xy 141.688058 -275.229066)
		)
		(stroke
			(width 0)
			(type solid)
		)
		(fill yes)
		(layer "F.Cu")
		(net "M_E_CPU1_SA_DQ<18>")
	)
	(gr_poly
		(pts
			(xy 141.785848 -269.443962) (xy 141.832076 -269.346426) (xy 141.697202 -269.211806) (xy 141.59992 -269.258034)
			(xy 141.563852 -269.293848) (xy 141.74978 -269.479776)
		)
		(stroke
			(width 0)
			(type solid)
		)
		(fill yes)
		(layer "F.Cu")
		(net "M_E_CPU1_SA_DQ<26>")
	)
	(gr_poly
		(pts
			(xy 141.791182 -229.873302) (xy 141.755114 -229.837488) (xy 141.657832 -229.79126) (xy 141.522958 -229.92588)
			(xy 141.569186 -230.023416) (xy 141.605254 -230.05923)
		)
		(stroke
			(width 0)
			(type solid)
		)
		(fill yes)
		(layer "F.Cu")
		(net "M_E_CPU1_SB_DQ<21>")
	)
	(gr_poly
		(pts
			(xy 141.793722 -276.976078) (xy 141.74216 -276.718268) (xy 141.692376 -276.728174) (xy 141.59992 -276.7838)
			(xy 141.637258 -276.97049) (xy 141.743938 -276.985984)
		)
		(stroke
			(width 0)
			(type solid)
		)
		(fill yes)
		(layer "F.Cu")
		(net "M_E_CPU1_SA_DQ<7>")
	)
	(gr_poly
		(pts
			(xy 141.794992 -274.329398) (xy 141.830806 -274.29333) (xy 141.644878 -274.107402) (xy 141.609064 -274.14347)
			(xy 141.562836 -274.240752) (xy 141.697456 -274.375626)
		)
		(stroke
			(width 0)
			(type solid)
		)
		(fill yes)
		(layer "F.Cu")
		(net "M_E_CPU1_SA_DQ<19>")
	)
	(gr_poly
		(pts
			(xy 141.794992 -268.590522) (xy 141.84122 -268.492986) (xy 141.706346 -268.358366) (xy 141.609064 -268.404594)
			(xy 141.572996 -268.440408) (xy 141.758924 -268.626336)
		)
		(stroke
			(width 0)
			(type solid)
		)
		(fill yes)
		(layer "F.Cu")
		(net "M_E_CPU1_SA_DQ<27>")
	)
	(gr_poly
		(pts
			(xy 141.800326 -230.726742) (xy 141.764512 -230.690928) (xy 141.666976 -230.6447) (xy 141.532356 -230.77932)
			(xy 141.578584 -230.876602) (xy 141.614398 -230.91267)
		)
		(stroke
			(width 0)
			(type solid)
		)
		(fill yes)
		(layer "F.Cu")
		(net "M_E_CPU1_SB_DQ<20>")
	)
	(gr_poly
		(pts
			(xy 141.812264 -238.787686) (xy 141.812264 -238.736886) (xy 141.549374 -238.736886) (xy 141.549374 -238.787686)
			(xy 141.585696 -238.889286) (xy 141.776196 -238.889286)
		)
		(stroke
			(width 0)
			(type solid)
		)
		(fill yes)
		(layer "F.Cu")
		(net "M_E_CPU1_SB_DQ<8>")
	)
	(gr_poly
		(pts
			(xy 141.812264 -238.482886) (xy 141.812264 -238.432086) (xy 141.549374 -238.432086) (xy 141.549374 -238.482886)
			(xy 141.585696 -238.584486) (xy 141.776196 -238.584486)
		)
		(stroke
			(width 0)
			(type solid)
		)
		(fill yes)
		(layer "F.Cu")
		(net "M_E_CPU1_SB_DQ<10>")
	)
	(gr_poly
		(pts
			(xy 141.812264 -237.873286) (xy 141.812264 -237.822486) (xy 141.549374 -237.822486) (xy 141.549374 -237.873286)
			(xy 141.585696 -237.974886) (xy 141.776196 -237.974886)
		)
		(stroke
			(width 0)
			(type solid)
		)
		(fill yes)
		(layer "F.Cu")
		(net "M_E_CPU1_SB_DQ<11>")
	)
	(gr_poly
		(pts
			(xy 141.82725 -233.288078) (xy 141.791182 -233.252264) (xy 141.6939 -233.206036) (xy 141.559026 -233.340656)
			(xy 141.605254 -233.438192) (xy 141.641322 -233.474006)
		)
		(stroke
			(width 0)
			(type solid)
		)
		(fill yes)
		(layer "F.Cu")
		(net "M_E_CPU1_SB_DQ<17>")
	)
	(gr_poly
		(pts
			(xy 141.835886 -234.985306) (xy 141.800072 -234.949238) (xy 141.702536 -234.90301) (xy 141.567916 -235.03763)
			(xy 141.614144 -235.135166) (xy 141.650212 -235.17098)
		)
		(stroke
			(width 0)
			(type solid)
		)
		(fill yes)
		(layer "F.Cu")
		(net "M_E_CPU1_SB_DQ<15>")
	)
	(gr_poly
		(pts
			(xy 141.836394 -234.141518) (xy 141.80058 -234.105704) (xy 141.703044 -234.059222) (xy 141.568424 -234.194096)
			(xy 141.614652 -234.291378) (xy 141.650466 -234.327446)
		)
		(stroke
			(width 0)
			(type solid)
		)
		(fill yes)
		(layer "F.Cu")
		(net "M_E_CPU1_SB_DQ<16>")
	)
	(gr_poly
		(pts
			(xy 141.837156 -278.489156) (xy 141.929612 -278.433784) (xy 141.892274 -278.247094) (xy 141.785594 -278.231346)
			(xy 141.73581 -278.241506) (xy 141.787372 -278.499316)
		)
		(stroke
			(width 0)
			(type solid)
		)
		(fill yes)
		(layer "F.Cu")
		(net "M_E_CPU1_SA_DQ<5>")
	)
	(gr_poly
		(pts
			(xy 141.844014 -258.218178) (xy 141.879828 -258.18211) (xy 141.6939 -257.996182) (xy 141.658086 -258.03225)
			(xy 141.611858 -258.129786) (xy 141.746478 -258.264406)
		)
		(stroke
			(width 0)
			(type solid)
		)
		(fill yes)
		(layer "F.Cu")
		(net "M_E_CPU1_SA_CS_N<0>")
	)
	(gr_poly
		(pts
			(xy 141.845792 -278.791924) (xy 141.79423 -278.534114) (xy 141.744446 -278.54402) (xy 141.65199 -278.599392)
			(xy 141.689328 -278.786336) (xy 141.796008 -278.80183)
		)
		(stroke
			(width 0)
			(type solid)
		)
		(fill yes)
		(layer "F.Cu")
		(net "M_E_CPU1_SA_DQ<5>")
	)
	(gr_poly
		(pts
			(xy 141.85265 -275.537676) (xy 141.898878 -275.440394) (xy 141.764258 -275.30552) (xy 141.666722 -275.352002)
			(xy 141.630908 -275.387816) (xy 141.816836 -275.573744)
		)
		(stroke
			(width 0)
			(type solid)
		)
		(fill yes)
		(layer "F.Cu")
		(net "M_E_CPU1_SA_DQ<16>")
	)
	(gr_poly
		(pts
			(xy 141.853412 -257.364738) (xy 141.889226 -257.32867) (xy 141.703298 -257.142742) (xy 141.667484 -257.17881)
			(xy 141.621256 -257.276092) (xy 141.755876 -257.410966)
		)
		(stroke
			(width 0)
			(type solid)
		)
		(fill yes)
		(layer "F.Cu")
		(net "M_E_CPU1_SA_CS_N<1>")
	)
	(gr_poly
		(pts
			(xy 141.860016 -264.121646) (xy 141.896084 -264.085832) (xy 141.710156 -263.899904) (xy 141.674342 -263.935718)
			(xy 141.62786 -264.033254) (xy 141.762734 -264.167874)
		)
		(stroke
			(width 0)
			(type solid)
		)
		(fill yes)
		(layer "F.Cu")
		(net "M_E_CPU1_SA_CB<2>")
	)
	(gr_poly
		(pts
			(xy 141.861794 -274.68449) (xy 141.908276 -274.586954) (xy 141.773402 -274.452334) (xy 141.67612 -274.498562)
			(xy 141.640052 -274.534376) (xy 141.82598 -274.720304)
		)
		(stroke
			(width 0)
			(type solid)
		)
		(fill yes)
		(layer "F.Cu")
		(net "M_E_CPU1_SA_DQ<17>")
	)
	(gr_poly
		(pts
			(xy 141.862556 -256.511298) (xy 141.89837 -256.47523) (xy 141.712696 -256.289556) (xy 141.676628 -256.32537)
			(xy 141.6304 -256.422906) (xy 141.76502 -256.557526)
		)
		(stroke
			(width 0)
			(type solid)
		)
		(fill yes)
		(layer "F.Cu")
		(net "M_E_CPU1_SA_CA<0>")
	)
	(gr_poly
		(pts
			(xy 141.868652 -229.580186) (xy 141.822424 -229.48265) (xy 141.78661 -229.446582) (xy 141.600682 -229.63251)
			(xy 141.636496 -229.668578) (xy 141.734032 -229.714806)
		)
		(stroke
			(width 0)
			(type solid)
		)
		(fill yes)
		(layer "F.Cu")
		(net "M_E_CPU1_SB_DQ<23>")
	)
	(gr_poly
		(pts
			(xy 141.869414 -263.26846) (xy 141.905228 -263.232392) (xy 141.7193 -263.046464) (xy 141.683486 -263.082532)
			(xy 141.637258 -263.179814) (xy 141.771878 -263.314688)
		)
		(stroke
			(width 0)
			(type solid)
		)
		(fill yes)
		(layer "F.Cu")
		(net "M_E_CPU1_SA_CB<3>")
	)
	(gr_poly
		(pts
			(xy 141.871192 -242.316508) (xy 141.835378 -242.28044) (xy 141.737842 -242.234212) (xy 141.603222 -242.368832)
			(xy 141.64945 -242.466368) (xy 141.685264 -242.502436)
		)
		(stroke
			(width 0)
			(type solid)
		)
		(fill yes)
		(layer "F.Cu")
		(net "M_E_CPU1_SB_CB<5>")
	)
	(gr_poly
		(pts
			(xy 141.871954 -255.658112) (xy 141.907768 -255.622044) (xy 141.722094 -255.43637) (xy 141.686026 -255.472184)
			(xy 141.639798 -255.56972) (xy 141.774418 -255.70434)
		)
		(stroke
			(width 0)
			(type solid)
		)
		(fill yes)
		(layer "F.Cu")
		(net "M_E_CPU1_SA_CA<2>")
	)
	(gr_poly
		(pts
			(xy 141.875256 -290.118546) (xy 141.824456 -290.118546) (xy 141.722856 -290.154868) (xy 141.722856 -290.345368)
			(xy 141.824456 -290.381436) (xy 141.875256 -290.381436)
		)
		(stroke
			(width 0)
			(type solid)
		)
		(fill yes)
		(layer "F.Cu")
		(net "M_E_CPU1_SA_DQ<6>")
	)
	(gr_poly
		(pts
			(xy 141.875256 -289.521646) (xy 141.824456 -289.521646) (xy 141.722856 -289.557968) (xy 141.722856 -289.748468)
			(xy 141.824456 -289.784536) (xy 141.875256 -289.784536)
		)
		(stroke
			(width 0)
			(type solid)
		)
		(fill yes)
		(layer "F.Cu")
		(net "M_E_CPU1_SA_DQ<6>")
	)
	(gr_poly
		(pts
			(xy 141.875256 -288.924746) (xy 141.824456 -288.924746) (xy 141.722856 -288.961068) (xy 141.722856 -289.151568)
			(xy 141.824456 -289.187636) (xy 141.875256 -289.187636)
		)
		(stroke
			(width 0)
			(type solid)
		)
		(fill yes)
		(layer "F.Cu")
		(net "M_E_CPU1_SA_DQ<6>")
	)
	(gr_poly
		(pts
			(xy 141.875256 -288.327846) (xy 141.824456 -288.327846) (xy 141.722856 -288.364168) (xy 141.722856 -288.554668)
			(xy 141.824456 -288.590736) (xy 141.875256 -288.590736)
		)
		(stroke
			(width 0)
			(type solid)
		)
		(fill yes)
		(layer "F.Cu")
		(net "M_E_CPU1_SA_DQ<6>")
	)
	(gr_poly
		(pts
			(xy 141.875256 -287.730946) (xy 141.824456 -287.730946) (xy 141.722856 -287.767268) (xy 141.722856 -287.957768)
			(xy 141.824456 -287.993836) (xy 141.875256 -287.993836)
		)
		(stroke
			(width 0)
			(type solid)
		)
		(fill yes)
		(layer "F.Cu")
		(net "M_E_CPU1_SA_DQ<6>")
	)
	(gr_poly
		(pts
			(xy 141.875256 -287.134046) (xy 141.824456 -287.134046) (xy 141.722856 -287.170368) (xy 141.722856 -287.360868)
			(xy 141.824456 -287.396936) (xy 141.875256 -287.396936)
		)
		(stroke
			(width 0)
			(type solid)
		)
		(fill yes)
		(layer "F.Cu")
		(net "M_E_CPU1_SA_DQ<6>")
	)
	(gr_poly
		(pts
			(xy 141.875256 -286.537146) (xy 141.824456 -286.537146) (xy 141.722856 -286.573468) (xy 141.722856 -286.763968)
			(xy 141.824456 -286.800036) (xy 141.875256 -286.800036)
		)
		(stroke
			(width 0)
			(type solid)
		)
		(fill yes)
		(layer "F.Cu")
		(net "M_E_CPU1_SA_DQ<6>")
	)
	(gr_poly
		(pts
			(xy 141.875256 -285.940246) (xy 141.824456 -285.940246) (xy 141.722856 -285.976568) (xy 141.722856 -286.167068)
			(xy 141.824456 -286.203136) (xy 141.875256 -286.203136)
		)
		(stroke
			(width 0)
			(type solid)
		)
		(fill yes)
		(layer "F.Cu")
		(net "M_E_CPU1_SA_DQ<6>")
	)
	(gr_poly
		(pts
			(xy 141.875256 -285.343346) (xy 141.824456 -285.343346) (xy 141.722856 -285.379668) (xy 141.722856 -285.570168)
			(xy 141.824456 -285.606236) (xy 141.875256 -285.606236)
		)
		(stroke
			(width 0)
			(type solid)
		)
		(fill yes)
		(layer "F.Cu")
		(net "M_E_CPU1_SA_DQ<6>")
	)
	(gr_poly
		(pts
			(xy 141.875256 -284.746446) (xy 141.824456 -284.746446) (xy 141.722856 -284.782768) (xy 141.722856 -284.973268)
			(xy 141.824456 -285.009336) (xy 141.875256 -285.009336)
		)
		(stroke
			(width 0)
			(type solid)
		)
		(fill yes)
		(layer "F.Cu")
		(net "M_E_CPU1_SA_DQ<6>")
	)
	(gr_poly
		(pts
			(xy 141.875256 -284.149546) (xy 141.824456 -284.149546) (xy 141.722856 -284.185868) (xy 141.722856 -284.376368)
			(xy 141.824456 -284.412436) (xy 141.875256 -284.412436)
		)
		(stroke
			(width 0)
			(type solid)
		)
		(fill yes)
		(layer "F.Cu")
		(net "M_E_CPU1_SA_DQ<6>")
	)
	(gr_poly
		(pts
			(xy 141.875256 -283.552646) (xy 141.824456 -283.552646) (xy 141.722856 -283.588968) (xy 141.722856 -283.779468)
			(xy 141.824456 -283.815536) (xy 141.875256 -283.815536)
		)
		(stroke
			(width 0)
			(type solid)
		)
		(fill yes)
		(layer "F.Cu")
		(net "M_E_CPU1_SA_DQ<6>")
	)
	(gr_poly
		(pts
			(xy 141.875256 -282.955746) (xy 141.824456 -282.955746) (xy 141.722856 -282.992068) (xy 141.722856 -283.182568)
			(xy 141.824456 -283.218636) (xy 141.875256 -283.218636)
		)
		(stroke
			(width 0)
			(type solid)
		)
		(fill yes)
		(layer "F.Cu")
		(net "M_E_CPU1_SA_DQ<6>")
	)
	(gr_poly
		(pts
			(xy 141.875256 -282.358846) (xy 141.824456 -282.358846) (xy 141.722856 -282.395168) (xy 141.722856 -282.585668)
			(xy 141.824456 -282.621736) (xy 141.875256 -282.621736)
		)
		(stroke
			(width 0)
			(type solid)
		)
		(fill yes)
		(layer "F.Cu")
		(net "M_E_CPU1_SA_DQ<6>")
	)
	(gr_poly
		(pts
			(xy 141.875256 -281.761946) (xy 141.824456 -281.761946) (xy 141.722856 -281.798268) (xy 141.722856 -281.988768)
			(xy 141.824456 -282.024836) (xy 141.875256 -282.024836)
		)
		(stroke
			(width 0)
			(type solid)
		)
		(fill yes)
		(layer "F.Cu")
		(net "M_E_CPU1_SA_DQ<6>")
	)
	(gr_poly
		(pts
			(xy 141.875256 -281.165046) (xy 141.824456 -281.165046) (xy 141.722856 -281.201368) (xy 141.722856 -281.391868)
			(xy 141.824456 -281.427936) (xy 141.875256 -281.427936)
		)
		(stroke
			(width 0)
			(type solid)
		)
		(fill yes)
		(layer "F.Cu")
		(net "M_E_CPU1_SA_DQ<6>")
	)
	(gr_poly
		(pts
			(xy 141.877796 -230.433372) (xy 141.831568 -230.33609) (xy 141.795754 -230.300022) (xy 141.609826 -230.48595)
			(xy 141.64564 -230.521764) (xy 141.743176 -230.568246)
		)
		(stroke
			(width 0)
			(type solid)
		)
		(fill yes)
		(layer "F.Cu")
		(net "M_E_CPU1_SB_DQ<22>")
	)
	(gr_poly
		(pts
			(xy 141.88059 -243.169694) (xy 141.844522 -243.13388) (xy 141.74724 -243.087652) (xy 141.612366 -243.222272)
			(xy 141.658594 -243.319808) (xy 141.694662 -243.355622)
		)
		(stroke
			(width 0)
			(type solid)
		)
		(fill yes)
		(layer "F.Cu")
		(net "M_E_CPU1_SB_CB<4>")
	)
	(gr_poly
		(pts
			(xy 141.8844 -266.629896) (xy 141.920214 -266.594082) (xy 141.734286 -266.408154) (xy 141.698472 -266.443968)
			(xy 141.652244 -266.541504) (xy 141.786864 -266.676124)
		)
		(stroke
			(width 0)
			(type solid)
		)
		(fill yes)
		(layer "F.Cu")
		(net "M_E_CPU1_SA_DQ<28>")
	)
	(gr_poly
		(pts
			(xy 141.893544 -265.776456) (xy 141.929612 -265.740642) (xy 141.743684 -265.554714) (xy 141.707616 -265.590528)
			(xy 141.661388 -265.688064) (xy 141.796262 -265.822684)
		)
		(stroke
			(width 0)
			(type solid)
		)
		(fill yes)
		(layer "F.Cu")
		(net "M_E_CPU1_SA_DQ<29>")
	)
	(gr_poly
		(pts
			(xy 141.90218 -277.25878) (xy 141.994636 -277.203408) (xy 141.957298 -277.016464) (xy 141.850618 -277.00097)
			(xy 141.800834 -277.010876) (xy 141.852396 -277.268686)
		)
		(stroke
			(width 0)
			(type solid)
		)
		(fill yes)
		(layer "F.Cu")
		(net "M_E_CPU1_SA_DQ<7>")
	)
	(gr_poly
		(pts
			(xy 141.90472 -232.994708) (xy 141.858492 -232.897426) (xy 141.822678 -232.861358) (xy 141.63675 -233.047286)
			(xy 141.672564 -233.083354) (xy 141.7701 -233.129582)
		)
		(stroke
			(width 0)
			(type solid)
		)
		(fill yes)
		(layer "F.Cu")
		(net "M_E_CPU1_SB_DQ<19>")
	)
	(gr_poly
		(pts
			(xy 141.906498 -272.278094) (xy 141.942312 -272.24228) (xy 141.756638 -272.056352) (xy 141.72057 -272.092166)
			(xy 141.674342 -272.189702) (xy 141.808962 -272.324322)
		)
		(stroke
			(width 0)
			(type solid)
		)
		(fill yes)
		(layer "F.Cu")
		(net "M_E_CPU1_SA_DQ<20>")
	)
	(gr_poly
		(pts
			(xy 141.910816 -277.561294) (xy 141.859254 -277.303484) (xy 141.80947 -277.313644) (xy 141.717014 -277.369016)
			(xy 141.754352 -277.555706) (xy 141.861032 -277.5712)
		)
		(stroke
			(width 0)
			(type solid)
		)
		(fill yes)
		(layer "F.Cu")
		(net "M_E_CPU1_SA_DQ<7>")
	)
	(gr_poly
		(pts
			(xy 141.913864 -233.848148) (xy 141.867636 -233.750612) (xy 141.831822 -233.714798) (xy 141.645894 -233.900726)
			(xy 141.681708 -233.93654) (xy 141.779244 -233.982768)
		)
		(stroke
			(width 0)
			(type solid)
		)
		(fill yes)
		(layer "F.Cu")
		(net "M_E_CPU1_SB_DQ<18>")
	)
	(gr_poly
		(pts
			(xy 141.91615 -271.424146) (xy 141.951964 -271.388332) (xy 141.766036 -271.202404) (xy 141.730222 -271.238472)
			(xy 141.683994 -271.335754) (xy 141.818614 -271.470628)
		)
		(stroke
			(width 0)
			(type solid)
		)
		(fill yes)
		(layer "F.Cu")
		(net "M_E_CPU1_SA_DQ<21>")
	)
	(gr_poly
		(pts
			(xy 141.91742 -260.727952) (xy 141.953234 -260.691884) (xy 141.76756 -260.50621) (xy 141.731492 -260.542024)
			(xy 141.685264 -260.63956) (xy 141.819884 -260.77418)
		)
		(stroke
			(width 0)
			(type solid)
		)
		(fill yes)
		(layer "F.Cu")
		(net "M_E_CPU1_SA_CB<6>")
	)
	(gr_poly
		(pts
			(xy 141.920468 -257.719576) (xy 141.966696 -257.62204) (xy 141.832076 -257.48742) (xy 141.734794 -257.533648)
			(xy 141.698726 -257.569462) (xy 141.884654 -257.75539)
		)
		(stroke
			(width 0)
			(type solid)
		)
		(fill yes)
		(layer "F.Cu")
		(net "M_E_CPU1_SA_CS_N<2>")
	)
	(gr_poly
		(pts
			(xy 141.92504 -269.726918) (xy 141.960854 -269.69085) (xy 141.774926 -269.504922) (xy 141.739112 -269.54099)
			(xy 141.692884 -269.638272) (xy 141.827504 -269.773146)
		)
		(stroke
			(width 0)
			(type solid)
		)
		(fill yes)
		(layer "F.Cu")
		(net "M_E_CPU1_SA_DQ<26>")
	)
	(gr_poly
		(pts
			(xy 141.927326 -264.476484) (xy 141.973554 -264.379202) (xy 141.838934 -264.244328) (xy 141.741398 -264.290556)
			(xy 141.705584 -264.326624) (xy 141.891512 -264.512552)
		)
		(stroke
			(width 0)
			(type solid)
		)
		(fill yes)
		(layer "F.Cu")
		(net "M_E_CPU1_SA_CB<0>")
	)
	(gr_poly
		(pts
			(xy 141.929866 -256.866136) (xy 141.976094 -256.7686) (xy 141.84122 -256.63398) (xy 141.743938 -256.680208)
			(xy 141.70787 -256.716022) (xy 141.893798 -256.90195)
		)
		(stroke
			(width 0)
			(type solid)
		)
		(fill yes)
		(layer "F.Cu")
		(net "M_E_CPU1_SA_CS_N<3>")
	)
	(gr_poly
		(pts
			(xy 141.934184 -268.873478) (xy 141.969998 -268.83741) (xy 141.78407 -268.651482) (xy 141.748256 -268.68755)
			(xy 141.702028 -268.784832) (xy 141.836648 -268.919706)
		)
		(stroke
			(width 0)
			(type solid)
		)
		(fill yes)
		(layer "F.Cu")
		(net "M_E_CPU1_SA_DQ<27>")
	)
	(gr_poly
		(pts
			(xy 141.93647 -263.623298) (xy 141.982698 -263.525762) (xy 141.848078 -263.391142) (xy 141.750796 -263.43737)
			(xy 141.714728 -263.473184) (xy 141.900656 -263.659112)
		)
		(stroke
			(width 0)
			(type solid)
		)
		(fill yes)
		(layer "F.Cu")
		(net "M_E_CPU1_SA_CB<1>")
	)
	(gr_poly
		(pts
			(xy 141.939264 -256.01295) (xy 141.985492 -255.915414) (xy 141.850618 -255.780794) (xy 141.753336 -255.827022)
			(xy 141.717268 -255.862836) (xy 141.903196 -256.048764)
		)
		(stroke
			(width 0)
			(type solid)
		)
		(fill yes)
		(layer "F.Cu")
		(net "M_E_CPU1_SA_CA<1>")
	)
	(gr_poly
		(pts
			(xy 141.948916 -242.023138) (xy 141.902688 -241.925602) (xy 141.86662 -241.889788) (xy 141.680692 -242.075716)
			(xy 141.71676 -242.11153) (xy 141.814042 -242.157758)
		)
		(stroke
			(width 0)
			(type solid)
		)
		(fill yes)
		(layer "F.Cu")
		(net "M_E_CPU1_SB_CB<7>")
	)
	(gr_poly
		(pts
			(xy 141.95425 -279.074626) (xy 142.046706 -279.019) (xy 142.009368 -278.83231) (xy 141.902688 -278.816816)
			(xy 141.852904 -278.826722) (xy 141.904466 -279.084532)
		)
		(stroke
			(width 0)
			(type solid)
		)
		(fill yes)
		(layer "F.Cu")
		(net "M_E_CPU1_SA_DQ<5>")
	)
	(gr_poly
		(pts
			(xy 141.95806 -242.876578) (xy 141.911832 -242.779042) (xy 141.875764 -242.743228) (xy 141.69009 -242.928902)
			(xy 141.725904 -242.96497) (xy 141.82344 -243.011198)
		)
		(stroke
			(width 0)
			(type solid)
		)
		(fill yes)
		(layer "F.Cu")
		(net "M_E_CPU1_SB_CB<6>")
	)
	(gr_poly
		(pts
			(xy 141.9606 -266.131548) (xy 142.007082 -266.034012) (xy 141.872208 -265.899392) (xy 141.774926 -265.94562)
			(xy 141.738858 -265.981434) (xy 141.924786 -266.167362)
		)
		(stroke
			(width 0)
			(type solid)
		)
		(fill yes)
		(layer "F.Cu")
		(net "M_E_CPU1_SA_DQ<30>")
	)
	(gr_poly
		(pts
			(xy 141.96314 -279.37714) (xy 141.911324 -279.11933) (xy 141.86154 -279.129236) (xy 141.769084 -279.184862)
			(xy 141.806422 -279.371552) (xy 141.913356 -279.387046)
		)
		(stroke
			(width 0)
			(type solid)
		)
		(fill yes)
		(layer "F.Cu")
		(net "M_E_CPU1_SA_DQ<5>")
	)
	(gr_poly
		(pts
			(xy 141.963648 -247.748552) (xy 141.92758 -247.646952) (xy 141.73708 -247.646952) (xy 141.701012 -247.748552)
			(xy 141.701012 -247.799352) (xy 141.963648 -247.799352)
		)
		(stroke
			(width 0)
			(type solid)
		)
		(fill yes)
		(layer "F.Cu")
		(net "M_E_CPU1_SB_CA<4>")
	)
	(gr_poly
		(pts
			(xy 141.963648 -247.443752) (xy 141.92758 -247.342152) (xy 141.73708 -247.342152) (xy 141.701012 -247.443752)
			(xy 141.701012 -247.494552) (xy 141.963648 -247.494552)
		)
		(stroke
			(width 0)
			(type solid)
		)
		(fill yes)
		(layer "F.Cu")
		(net "M_E_CPU1_SB_CA<5>")
	)
	(gr_poly
		(pts
			(xy 141.963648 -247.138952) (xy 141.92758 -247.037352) (xy 141.73708 -247.037352) (xy 141.701012 -247.138952)
			(xy 141.701012 -247.189752) (xy 141.963648 -247.189752)
		)
		(stroke
			(width 0)
			(type solid)
		)
		(fill yes)
		(layer "F.Cu")
		(net "M_E_CPU1_SB_CA<6>")
	)
	(gr_poly
		(pts
			(xy 141.963648 -246.834152) (xy 141.92758 -246.732552) (xy 141.73708 -246.732552) (xy 141.701012 -246.834152)
			(xy 141.701012 -246.884952) (xy 141.963648 -246.884952)
		)
		(stroke
			(width 0)
			(type solid)
		)
		(fill yes)
		(layer "F.Cu")
		(net "M_E_CPU1_SB_PAR")
	)
	(gr_poly
		(pts
			(xy 141.963648 -246.529352) (xy 141.92758 -246.427752) (xy 141.73708 -246.427752) (xy 141.701012 -246.529352)
			(xy 141.701012 -246.580152) (xy 141.963648 -246.580152)
		)
		(stroke
			(width 0)
			(type solid)
		)
		(fill yes)
		(layer "F.Cu")
		(net "M_E_CPU1_SB_CS_N<0>")
	)
	(gr_poly
		(pts
			(xy 141.963648 -246.224552) (xy 141.92758 -246.122952) (xy 141.73708 -246.122952) (xy 141.701012 -246.224552)
			(xy 141.701012 -246.275352) (xy 141.963648 -246.275352)
		)
		(stroke
			(width 0)
			(type solid)
		)
		(fill yes)
		(layer "F.Cu")
		(net "M_E_CPU1_SB_CS_N<2>")
	)
	(gr_poly
		(pts
			(xy 141.963648 -245.919752) (xy 141.92758 -245.818152) (xy 141.73708 -245.818152) (xy 141.701012 -245.919752)
			(xy 141.701012 -245.970552) (xy 141.963648 -245.970552)
		)
		(stroke
			(width 0)
			(type solid)
		)
		(fill yes)
		(layer "F.Cu")
		(net "M_E_CPU1_SB_CS_N<1>")
	)
	(gr_poly
		(pts
			(xy 141.963648 -245.614952) (xy 141.92758 -245.513352) (xy 141.73708 -245.513352) (xy 141.701012 -245.614952)
			(xy 141.701012 -245.665752) (xy 141.963648 -245.665752)
		)
		(stroke
			(width 0)
			(type solid)
		)
		(fill yes)
		(layer "F.Cu")
		(net "M_E_CPU1_SB_CS_N<3>")
	)
	(gr_poly
		(pts
			(xy 141.970252 -265.277854) (xy 142.01648 -265.180318) (xy 141.88186 -265.045698) (xy 141.784324 -265.091926)
			(xy 141.74851 -265.127994) (xy 141.934184 -265.313668)
		)
		(stroke
			(width 0)
			(type solid)
		)
		(fill yes)
		(layer "F.Cu")
		(net "M_E_CPU1_SA_DQ<31>")
	)
	(gr_poly
		(pts
			(xy 141.983206 -271.779238) (xy 142.029688 -271.681702) (xy 141.894814 -271.547082) (xy 141.797532 -271.59331)
			(xy 141.761464 -271.629124) (xy 141.947392 -271.815052)
		)
		(stroke
			(width 0)
			(type solid)
		)
		(fill yes)
		(layer "F.Cu")
		(net "M_E_CPU1_SA_DQ<22>")
	)
	(gr_poly
		(pts
			(xy 141.98473 -261.08279) (xy 142.030958 -260.985254) (xy 141.896084 -260.850634) (xy 141.798802 -260.896862)
			(xy 141.762734 -260.932676) (xy 141.948662 -261.118604)
		)
		(stroke
			(width 0)
			(type solid)
		)
		(fill yes)
		(layer "F.Cu")
		(net "M_E_CPU1_SA_CB<4>")
	)
	(gr_poly
		(pts
			(xy 141.991842 -275.820632) (xy 142.02791 -275.784818) (xy 141.841982 -275.59889) (xy 141.805914 -275.634704)
			(xy 141.759686 -275.73224) (xy 141.89456 -275.86686)
		)
		(stroke
			(width 0)
			(type solid)
		)
		(fill yes)
		(layer "F.Cu")
		(net "M_E_CPU1_SA_DQ<16>")
	)
	(gr_poly
		(pts
			(xy 141.99235 -270.081756) (xy 142.038578 -269.98422) (xy 141.903704 -269.8496) (xy 141.806422 -269.895828)
			(xy 141.770354 -269.931642) (xy 141.956282 -270.11757)
		)
		(stroke
			(width 0)
			(type solid)
		)
		(fill yes)
		(layer "F.Cu")
		(net "M_E_CPU1_SA_DQ<24>")
	)
	(gr_poly
		(pts
			(xy 141.992604 -270.925544) (xy 142.038832 -270.828262) (xy 141.904212 -270.693388) (xy 141.806676 -270.739616)
			(xy 141.770862 -270.775684) (xy 141.95679 -270.961612)
		)
		(stroke
			(width 0)
			(type solid)
		)
		(fill yes)
		(layer "F.Cu")
		(net "M_E_CPU1_SA_DQ<23>")
	)
	(gr_poly
		(pts
			(xy 141.993874 -260.22935) (xy 142.040102 -260.131814) (xy 141.905482 -259.997194) (xy 141.807946 -260.043422)
			(xy 141.772132 -260.07949) (xy 141.95806 -260.265418)
		)
		(stroke
			(width 0)
			(type solid)
		)
		(fill yes)
		(layer "F.Cu")
		(net "M_E_CPU1_SA_CB<5>")
	)
	(gr_poly
		(pts
			(xy 142.00124 -274.967192) (xy 142.037054 -274.931378) (xy 141.851126 -274.74545) (xy 141.815312 -274.781264)
			(xy 141.769084 -274.8788) (xy 141.903704 -275.01342)
		)
		(stroke
			(width 0)
			(type solid)
		)
		(fill yes)
		(layer "F.Cu")
		(net "M_E_CPU1_SA_DQ<17>")
	)
	(gr_poly
		(pts
			(xy 142.001494 -269.228316) (xy 142.047722 -269.13078) (xy 141.912848 -268.99616) (xy 141.815566 -269.042388)
			(xy 141.779498 -269.078202) (xy 141.965426 -269.26413)
		)
		(stroke
			(width 0)
			(type solid)
		)
		(fill yes)
		(layer "F.Cu")
		(net "M_E_CPU1_SA_DQ<25>")
	)
	(gr_poly
		(pts
			(xy 142.006828 -230.088948) (xy 141.97076 -230.053134) (xy 141.873478 -230.006906) (xy 141.738604 -230.141526)
			(xy 141.784832 -230.239062) (xy 141.8209 -230.274876)
		)
		(stroke
			(width 0)
			(type solid)
		)
		(fill yes)
		(layer "F.Cu")
		(net "M_E_CPU1_SB_DQ<22>")
	)
	(gr_poly
		(pts
			(xy 142.019274 -277.843996) (xy 142.11173 -277.788624) (xy 142.074392 -277.60168) (xy 141.967712 -277.586186)
			(xy 141.917928 -277.596092) (xy 141.96949 -277.853902)
		)
		(stroke
			(width 0)
			(type solid)
		)
		(fill yes)
		(layer "F.Cu")
		(net "M_E_CPU1_SA_DQ<7>")
	)
	(gr_poly
		(pts
			(xy 142.027656 -290.046918) (xy 142.027656 -289.856418) (xy 141.926056 -289.820096) (xy 141.875256 -289.820096)
			(xy 141.875256 -290.082986) (xy 141.926056 -290.082986)
		)
		(stroke
			(width 0)
			(type solid)
		)
		(fill yes)
		(layer "F.Cu")
		(net "M_E_CPU1_SA_DQ<6>")
	)
	(gr_poly
		(pts
			(xy 142.027656 -289.450018) (xy 142.027656 -289.259518) (xy 141.926056 -289.223196) (xy 141.875256 -289.223196)
			(xy 141.875256 -289.486086) (xy 141.926056 -289.486086)
		)
		(stroke
			(width 0)
			(type solid)
		)
		(fill yes)
		(layer "F.Cu")
		(net "M_E_CPU1_SA_DQ<6>")
	)
	(gr_poly
		(pts
			(xy 142.027656 -288.853118) (xy 142.027656 -288.662618) (xy 141.926056 -288.626296) (xy 141.875256 -288.626296)
			(xy 141.875256 -288.889186) (xy 141.926056 -288.889186)
		)
		(stroke
			(width 0)
			(type solid)
		)
		(fill yes)
		(layer "F.Cu")
		(net "M_E_CPU1_SA_DQ<6>")
	)
	(gr_poly
		(pts
			(xy 142.027656 -288.256218) (xy 142.027656 -288.065718) (xy 141.926056 -288.029396) (xy 141.875256 -288.029396)
			(xy 141.875256 -288.292286) (xy 141.926056 -288.292286)
		)
		(stroke
			(width 0)
			(type solid)
		)
		(fill yes)
		(layer "F.Cu")
		(net "M_E_CPU1_SA_DQ<6>")
	)
	(gr_poly
		(pts
			(xy 142.027656 -287.659318) (xy 142.027656 -287.468818) (xy 141.926056 -287.432496) (xy 141.875256 -287.432496)
			(xy 141.875256 -287.695386) (xy 141.926056 -287.695386)
		)
		(stroke
			(width 0)
			(type solid)
		)
		(fill yes)
		(layer "F.Cu")
		(net "M_E_CPU1_SA_DQ<6>")
	)
	(gr_poly
		(pts
			(xy 142.027656 -287.062418) (xy 142.027656 -286.871918) (xy 141.926056 -286.835596) (xy 141.875256 -286.835596)
			(xy 141.875256 -287.098486) (xy 141.926056 -287.098486)
		)
		(stroke
			(width 0)
			(type solid)
		)
		(fill yes)
		(layer "F.Cu")
		(net "M_E_CPU1_SA_DQ<6>")
	)
	(gr_poly
		(pts
			(xy 142.027656 -286.465518) (xy 142.027656 -286.275018) (xy 141.926056 -286.238696) (xy 141.875256 -286.238696)
			(xy 141.875256 -286.501586) (xy 141.926056 -286.501586)
		)
		(stroke
			(width 0)
			(type solid)
		)
		(fill yes)
		(layer "F.Cu")
		(net "M_E_CPU1_SA_DQ<6>")
	)
	(gr_poly
		(pts
			(xy 142.027656 -285.868618) (xy 142.027656 -285.678118) (xy 141.926056 -285.641796) (xy 141.875256 -285.641796)
			(xy 141.875256 -285.904686) (xy 141.926056 -285.904686)
		)
		(stroke
			(width 0)
			(type solid)
		)
		(fill yes)
		(layer "F.Cu")
		(net "M_E_CPU1_SA_DQ<6>")
	)
	(gr_poly
		(pts
			(xy 142.027656 -285.271718) (xy 142.027656 -285.081218) (xy 141.926056 -285.044896) (xy 141.875256 -285.044896)
			(xy 141.875256 -285.307786) (xy 141.926056 -285.307786)
		)
		(stroke
			(width 0)
			(type solid)
		)
		(fill yes)
		(layer "F.Cu")
		(net "M_E_CPU1_SA_DQ<6>")
	)
	(gr_poly
		(pts
			(xy 142.027656 -284.674818) (xy 142.027656 -284.484318) (xy 141.926056 -284.447996) (xy 141.875256 -284.447996)
			(xy 141.875256 -284.710886) (xy 141.926056 -284.710886)
		)
		(stroke
			(width 0)
			(type solid)
		)
		(fill yes)
		(layer "F.Cu")
		(net "M_E_CPU1_SA_DQ<6>")
	)
	(gr_poly
		(pts
			(xy 142.027656 -284.077918) (xy 142.027656 -283.887418) (xy 141.926056 -283.851096) (xy 141.875256 -283.851096)
			(xy 141.875256 -284.113986) (xy 141.926056 -284.113986)
		)
		(stroke
			(width 0)
			(type solid)
		)
		(fill yes)
		(layer "F.Cu")
		(net "M_E_CPU1_SA_DQ<6>")
	)
	(gr_poly
		(pts
			(xy 142.027656 -283.481018) (xy 142.027656 -283.290518) (xy 141.926056 -283.254196) (xy 141.875256 -283.254196)
			(xy 141.875256 -283.517086) (xy 141.926056 -283.517086)
		)
		(stroke
			(width 0)
			(type solid)
		)
		(fill yes)
		(layer "F.Cu")
		(net "M_E_CPU1_SA_DQ<6>")
	)
	(gr_poly
		(pts
			(xy 142.027656 -282.884118) (xy 142.027656 -282.693618) (xy 141.926056 -282.657296) (xy 141.875256 -282.657296)
			(xy 141.875256 -282.920186) (xy 141.926056 -282.920186)
		)
		(stroke
			(width 0)
			(type solid)
		)
		(fill yes)
		(layer "F.Cu")
		(net "M_E_CPU1_SA_DQ<6>")
	)
	(gr_poly
		(pts
			(xy 142.027656 -282.287218) (xy 142.027656 -282.096718) (xy 141.926056 -282.060396) (xy 141.875256 -282.060396)
			(xy 141.875256 -282.323286) (xy 141.926056 -282.323286)
		)
		(stroke
			(width 0)
			(type solid)
		)
		(fill yes)
		(layer "F.Cu")
		(net "M_E_CPU1_SA_DQ<6>")
	)
	(gr_poly
		(pts
			(xy 142.027656 -281.690318) (xy 142.027656 -281.499818) (xy 141.926056 -281.463496) (xy 141.875256 -281.463496)
			(xy 141.875256 -281.726386) (xy 141.926056 -281.726386)
		)
		(stroke
			(width 0)
			(type solid)
		)
		(fill yes)
		(layer "F.Cu")
		(net "M_E_CPU1_SA_DQ<6>")
	)
	(gr_poly
		(pts
			(xy 142.027656 -281.093418) (xy 142.027656 -280.902918) (xy 141.926056 -280.866596) (xy 141.875256 -280.866596)
			(xy 141.875256 -281.129486) (xy 141.926056 -281.129486)
		)
		(stroke
			(width 0)
			(type solid)
		)
		(fill yes)
		(layer "F.Cu")
		(net "M_E_CPU1_SA_DQ<6>")
	)
	(gr_poly
		(pts
			(xy 142.028164 -278.14651) (xy 141.976602 -277.888954) (xy 141.926564 -277.89886) (xy 141.834108 -277.954232)
			(xy 141.871446 -278.141176) (xy 141.97838 -278.15667)
		)
		(stroke
			(width 0)
			(type solid)
		)
		(fill yes)
		(layer "F.Cu")
		(net "M_E_CPU1_SA_DQ<7>")
	)
	(gr_poly
		(pts
			(xy 142.033498 -232.650538) (xy 141.997684 -232.61447) (xy 141.900148 -232.568242) (xy 141.765528 -232.702862)
			(xy 141.811756 -232.800398) (xy 141.847824 -232.836212)
		)
		(stroke
			(width 0)
			(type solid)
		)
		(fill yes)
		(layer "F.Cu")
		(net "M_E_CPU1_SB_DQ<19>")
	)
	(gr_poly
		(pts
			(xy 142.042896 -233.503724) (xy 142.006828 -233.46791) (xy 141.909546 -233.421682) (xy 141.774672 -233.556302)
			(xy 141.8209 -233.653838) (xy 141.856968 -233.689652)
		)
		(stroke
			(width 0)
			(type solid)
		)
		(fill yes)
		(layer "F.Cu")
		(net "M_E_CPU1_SB_DQ<18>")
	)
	(gr_poly
		(pts
			(xy 142.051532 -235.200952) (xy 142.015718 -235.164884) (xy 141.918182 -235.118656) (xy 141.783562 -235.253276)
			(xy 141.82979 -235.350812) (xy 141.865858 -235.386626)
		)
		(stroke
			(width 0)
			(type solid)
		)
		(fill yes)
		(layer "F.Cu")
		(net "M_E_CPU1_SB_DQ<13>")
	)
	(gr_poly
		(pts
			(xy 142.05966 -258.002278) (xy 142.095728 -257.966464) (xy 141.9098 -257.780536) (xy 141.873986 -257.81635)
			(xy 141.827504 -257.913886) (xy 141.962378 -258.048506)
		)
		(stroke
			(width 0)
			(type solid)
		)
		(fill yes)
		(layer "F.Cu")
		(net "M_E_CPU1_SA_CS_N<2>")
	)
	(gr_poly
		(pts
			(xy 142.062962 -239.24514) (xy 142.02664 -239.14354) (xy 141.83614 -239.14354) (xy 141.800072 -239.24514)
			(xy 141.800072 -239.29594) (xy 142.062962 -239.29594)
		)
		(stroke
			(width 0)
			(type solid)
		)
		(fill yes)
		(layer "F.Cu")
		(net "M_E_CPU1_SB_CB<3>")
	)
	(gr_poly
		(pts
			(xy 142.066518 -264.75944) (xy 142.102586 -264.723626) (xy 141.916658 -264.537698) (xy 141.88059 -264.573512)
			(xy 141.834362 -264.671048) (xy 141.968982 -264.805668)
		)
		(stroke
			(width 0)
			(type solid)
		)
		(fill yes)
		(layer "F.Cu")
		(net "M_E_CPU1_SA_CB<0>")
	)
	(gr_poly
		(pts
			(xy 142.068296 -275.32203) (xy 142.114524 -275.224748) (xy 141.979904 -275.089874) (xy 141.882368 -275.136356)
			(xy 141.846554 -275.17217) (xy 142.032482 -275.358098)
		)
		(stroke
			(width 0)
			(type solid)
		)
		(fill yes)
		(layer "F.Cu")
		(net "M_E_CPU1_SA_DQ<18>")
	)
	(gr_poly
		(pts
			(xy 142.069058 -257.149092) (xy 142.104872 -257.113024) (xy 141.918944 -256.927096) (xy 141.88313 -256.963164)
			(xy 141.836902 -257.060446) (xy 141.971522 -257.19532)
		)
		(stroke
			(width 0)
			(type solid)
		)
		(fill yes)
		(layer "F.Cu")
		(net "M_E_CPU1_SA_CS_N<3>")
	)
	(gr_poly
		(pts
			(xy 142.071344 -279.659842) (xy 142.164054 -279.60447) (xy 142.126462 -279.417526) (xy 142.019782 -279.402032)
			(xy 141.969998 -279.411938) (xy 142.02156 -279.669748)
		)
		(stroke
			(width 0)
			(type solid)
		)
		(fill yes)
		(layer "F.Cu")
		(net "M_E_CPU1_SA_DQ<5>")
	)
	(gr_poly
		(pts
			(xy 142.075662 -263.906) (xy 142.11173 -263.870186) (xy 141.925802 -263.684258) (xy 141.889988 -263.720072)
			(xy 141.843506 -263.817608) (xy 141.97838 -263.952228)
		)
		(stroke
			(width 0)
			(type solid)
		)
		(fill yes)
		(layer "F.Cu")
		(net "M_E_CPU1_SA_CB<1>")
	)
	(gr_poly
		(pts
			(xy 142.077694 -274.46859) (xy 142.124176 -274.371054) (xy 141.989302 -274.236434) (xy 141.89202 -274.282662)
			(xy 141.855952 -274.318476) (xy 142.04188 -274.504404)
		)
		(stroke
			(width 0)
			(type solid)
		)
		(fill yes)
		(layer "F.Cu")
		(net "M_E_CPU1_SA_DQ<19>")
	)
	(gr_poly
		(pts
			(xy 142.078202 -256.295652) (xy 142.114016 -256.259584) (xy 141.928342 -256.07391) (xy 141.892274 -256.109724)
			(xy 141.846046 -256.20726) (xy 141.980666 -256.34188)
		)
		(stroke
			(width 0)
			(type solid)
		)
		(fill yes)
		(layer "F.Cu")
		(net "M_E_CPU1_SA_CA<1>")
	)
	(gr_poly
		(pts
			(xy 142.080234 -279.962356) (xy 142.028672 -279.704546) (xy 141.978888 -279.714706) (xy 141.886178 -279.770078)
			(xy 141.92377 -279.956768) (xy 142.03045 -279.972516)
		)
		(stroke
			(width 0)
			(type solid)
		)
		(fill yes)
		(layer "F.Cu")
		(net "M_E_CPU1_SA_DQ<5>")
	)
	(gr_poly
		(pts
			(xy 142.084298 -229.795832) (xy 142.03807 -229.698296) (xy 142.002256 -229.662228) (xy 141.816328 -229.848156)
			(xy 141.852142 -229.884224) (xy 141.949678 -229.930452)
		)
		(stroke
			(width 0)
			(type solid)
		)
		(fill yes)
		(layer "F.Cu")
		(net "M_E_CPU1_SB_DQ<21>")
	)
	(gr_poly
		(pts
			(xy 142.086838 -242.532154) (xy 142.051024 -242.496086) (xy 141.953488 -242.449858) (xy 141.818868 -242.584478)
			(xy 141.865096 -242.682014) (xy 141.90091 -242.718082)
		)
		(stroke
			(width 0)
			(type solid)
		)
		(fill yes)
		(layer "F.Cu")
		(net "M_E_CPU1_SB_CB<6>")
	)
	(gr_poly
		(pts
			(xy 142.0876 -255.442466) (xy 142.123414 -255.406398) (xy 141.93774 -255.220724) (xy 141.901672 -255.256538)
			(xy 141.855444 -255.354074) (xy 141.990064 -255.488694)
		)
		(stroke
			(width 0)
			(type solid)
		)
		(fill yes)
		(layer "F.Cu")
		(net "M_E_CPU1_SA_CA<3>")
	)
	(gr_poly
		(pts
			(xy 142.093442 -230.649018) (xy 142.047214 -230.551736) (xy 142.0114 -230.515668) (xy 141.825472 -230.701596)
			(xy 141.861286 -230.73741) (xy 141.958822 -230.783892)
		)
		(stroke
			(width 0)
			(type solid)
		)
		(fill yes)
		(layer "F.Cu")
		(net "M_E_CPU1_SB_DQ<20>")
	)
	(gr_poly
		(pts
			(xy 142.100046 -266.41425) (xy 142.13586 -266.378436) (xy 141.949932 -266.192508) (xy 141.914118 -266.228322)
			(xy 141.86789 -266.325858) (xy 142.00251 -266.460478)
		)
		(stroke
			(width 0)
			(type solid)
		)
		(fill yes)
		(layer "F.Cu")
		(net "M_E_CPU1_SA_DQ<30>")
	)
	(gr_poly
		(pts
			(xy 142.109444 -265.56081) (xy 142.145258 -265.524742) (xy 141.95933 -265.338814) (xy 141.923516 -265.374882)
			(xy 141.877288 -265.472164) (xy 142.011908 -265.607038)
		)
		(stroke
			(width 0)
			(type solid)
		)
		(fill yes)
		(layer "F.Cu")
		(net "M_E_CPU1_SA_DQ<31>")
	)
	(gr_poly
		(pts
			(xy 142.110714 -238.686086) (xy 142.074392 -238.584486) (xy 141.883892 -238.584486) (xy 141.847824 -238.686086)
			(xy 141.847824 -238.736886) (xy 142.110714 -238.736886)
		)
		(stroke
			(width 0)
			(type solid)
		)
		(fill yes)
		(layer "F.Cu")
		(net "M_E_CPU1_SB_DQ<8>")
	)
	(gr_poly
		(pts
			(xy 142.110714 -238.381286) (xy 142.074392 -238.279686) (xy 141.883892 -238.279686) (xy 141.847824 -238.381286)
			(xy 141.847824 -238.432086) (xy 142.110714 -238.432086)
		)
		(stroke
			(width 0)
			(type solid)
		)
		(fill yes)
		(layer "F.Cu")
		(net "M_E_CPU1_SB_DQ<10>")
	)
	(gr_poly
		(pts
			(xy 142.110714 -237.771686) (xy 142.074392 -237.670086) (xy 141.883892 -237.670086) (xy 141.847824 -237.771686)
			(xy 141.847824 -237.822486) (xy 142.110714 -237.822486)
		)
		(stroke
			(width 0)
			(type solid)
		)
		(fill yes)
		(layer "F.Cu")
		(net "M_E_CPU1_SB_DQ<11>")
	)
	(gr_poly
		(pts
			(xy 142.120366 -233.210354) (xy 142.074138 -233.113072) (xy 142.038324 -233.077004) (xy 141.852396 -233.262932)
			(xy 141.88821 -233.299) (xy 141.985746 -233.345228)
		)
		(stroke
			(width 0)
			(type solid)
		)
		(fill yes)
		(layer "F.Cu")
		(net "M_E_CPU1_SB_DQ<17>")
	)
	(gr_poly
		(pts
			(xy 142.122398 -272.06194) (xy 142.158466 -272.026126) (xy 141.972538 -271.840198) (xy 141.936724 -271.876012)
			(xy 141.890496 -271.973548) (xy 142.025116 -272.108168)
		)
		(stroke
			(width 0)
			(type solid)
		)
		(fill yes)
		(layer "F.Cu")
		(net "M_E_CPU1_SA_DQ<22>")
	)
	(gr_poly
		(pts
			(xy 142.123922 -261.365492) (xy 142.159736 -261.329678) (xy 141.973808 -261.14375) (xy 141.937994 -261.179818)
			(xy 141.891766 -261.2771) (xy 142.026386 -261.411974)
		)
		(stroke
			(width 0)
			(type solid)
		)
		(fill yes)
		(layer "F.Cu")
		(net "M_E_CPU1_SA_CB<4>")
	)
	(gr_poly
		(pts
			(xy 142.12697 -258.35737) (xy 142.173198 -258.259834) (xy 142.038324 -258.125214) (xy 141.941042 -258.171442)
			(xy 141.904974 -258.207256) (xy 142.090902 -258.393184)
		)
		(stroke
			(width 0)
			(type solid)
		)
		(fill yes)
		(layer "F.Cu")
		(net "M_E_CPU1_SA_CS_N<0>")
	)
	(gr_poly
		(pts
			(xy 142.129256 -234.907582) (xy 142.083028 -234.810046) (xy 142.04696 -234.774232) (xy 141.861032 -234.96016)
			(xy 141.8971 -234.995974) (xy 141.994382 -235.042202)
		)
		(stroke
			(width 0)
			(type solid)
		)
		(fill yes)
		(layer "F.Cu")
		(net "M_E_CPU1_SB_DQ<15>")
	)
	(gr_poly
		(pts
			(xy 142.12951 -234.063794) (xy 142.083282 -233.966258) (xy 142.047468 -233.930444) (xy 141.86154 -234.116372)
			(xy 141.897354 -234.152186) (xy 141.99489 -234.198414)
		)
		(stroke
			(width 0)
			(type solid)
		)
		(fill yes)
		(layer "F.Cu")
		(net "M_E_CPU1_SB_DQ<16>")
	)
	(gr_poly
		(pts
			(xy 142.131542 -270.364458) (xy 142.167356 -270.328644) (xy 141.981428 -270.142716) (xy 141.945614 -270.178784)
			(xy 141.899386 -270.276066) (xy 142.034006 -270.410686)
		)
		(stroke
			(width 0)
			(type solid)
		)
		(fill yes)
		(layer "F.Cu")
		(net "M_E_CPU1_SA_DQ<24>")
	)
	(gr_poly
		(pts
			(xy 142.131796 -271.2085) (xy 142.16761 -271.172432) (xy 141.981936 -270.986758) (xy 141.945868 -271.022572)
			(xy 141.89964 -271.120108) (xy 142.03426 -271.254728)
		)
		(stroke
			(width 0)
			(type solid)
		)
		(fill yes)
		(layer "F.Cu")
		(net "M_E_CPU1_SA_DQ<23>")
	)
	(gr_poly
		(pts
			(xy 142.133066 -260.512306) (xy 142.16888 -260.476238) (xy 141.983206 -260.290564) (xy 141.947138 -260.326378)
			(xy 141.90091 -260.423914) (xy 142.03553 -260.558534)
		)
		(stroke
			(width 0)
			(type solid)
		)
		(fill yes)
		(layer "F.Cu")
		(net "M_E_CPU1_SA_CB<5>")
	)
	(gr_poly
		(pts
			(xy 142.136114 -257.50393) (xy 142.182342 -257.406394) (xy 142.047722 -257.271774) (xy 141.95044 -257.318002)
			(xy 141.914372 -257.353816) (xy 142.1003 -257.539744)
		)
		(stroke
			(width 0)
			(type solid)
		)
		(fill yes)
		(layer "F.Cu")
		(net "M_E_CPU1_SA_CS_N<1>")
	)
	(gr_poly
		(pts
			(xy 142.136368 -278.429212) (xy 142.229078 -278.37384) (xy 142.19174 -278.18715) (xy 142.084806 -278.171402)
			(xy 142.035022 -278.181562) (xy 142.086584 -278.439372)
		)
		(stroke
			(width 0)
			(type solid)
		)
		(fill yes)
		(layer "F.Cu")
		(net "M_E_CPU1_SA_DQ<7>")
	)
	(gr_poly
		(pts
			(xy 142.1384 -235.761022) (xy 142.092172 -235.663486) (xy 142.056358 -235.627418) (xy 141.87043 -235.813346)
			(xy 141.906244 -235.849414) (xy 142.00378 -235.895642)
		)
		(stroke
			(width 0)
			(type solid)
		)
		(fill yes)
		(layer "F.Cu")
		(net "M_E_CPU1_SB_DQ<14>")
	)
	(gr_poly
		(pts
			(xy 142.140686 -269.511018) (xy 142.1765 -269.475204) (xy 141.990572 -269.289276) (xy 141.954758 -269.325344)
			(xy 141.90853 -269.422626) (xy 142.04315 -269.557246)
		)
		(stroke
			(width 0)
			(type solid)
		)
		(fill yes)
		(layer "F.Cu")
		(net "M_E_CPU1_SA_DQ<25>")
	)
	(gr_poly
		(pts
			(xy 142.142972 -264.260838) (xy 142.1892 -264.163556) (xy 142.05458 -264.028682) (xy 141.957044 -264.07491)
			(xy 141.92123 -264.110978) (xy 142.107158 -264.296906)
		)
		(stroke
			(width 0)
			(type solid)
		)
		(fill yes)
		(layer "F.Cu")
		(net "M_E_CPU1_SA_CB<2>")
	)
	(gr_poly
		(pts
			(xy 142.145258 -278.73198) (xy 142.093696 -278.47417) (xy 142.043912 -278.484076) (xy 141.951456 -278.539448)
			(xy 141.988794 -278.726392) (xy 142.095474 -278.741886)
		)
		(stroke
			(width 0)
			(type solid)
		)
		(fill yes)
		(layer "F.Cu")
		(net "M_E_CPU1_SA_DQ<7>")
	)
	(gr_poly
		(pts
			(xy 142.145512 -256.65049) (xy 142.19174 -256.552954) (xy 142.056866 -256.418334) (xy 141.959584 -256.464562)
			(xy 141.923516 -256.500376) (xy 142.109444 -256.686304)
		)
		(stroke
			(width 0)
			(type solid)
		)
		(fill yes)
		(layer "F.Cu")
		(net "M_E_CPU1_SA_CA<0>")
	)
	(gr_poly
		(pts
			(xy 142.145512 -225.009456) (xy 142.094712 -225.009456) (xy 141.993112 -225.045778) (xy 141.993112 -225.236278)
			(xy 142.094712 -225.272346) (xy 142.145512 -225.272346)
		)
		(stroke
			(width 0)
			(type solid)
		)
		(fill yes)
		(layer "F.Cu")
		(net "M_E_CPU1_SB_DQ<27>")
	)
	(gr_poly
		(pts
			(xy 142.145512 -224.412556) (xy 142.094712 -224.412556) (xy 141.993112 -224.448878) (xy 141.993112 -224.639378)
			(xy 142.094712 -224.675446) (xy 142.145512 -224.675446)
		)
		(stroke
			(width 0)
			(type solid)
		)
		(fill yes)
		(layer "F.Cu")
		(net "M_E_CPU1_SB_DQ<27>")
	)
	(gr_poly
		(pts
			(xy 142.145512 -223.815656) (xy 142.094712 -223.815656) (xy 141.993112 -223.851978) (xy 141.993112 -224.042478)
			(xy 142.094712 -224.078546) (xy 142.145512 -224.078546)
		)
		(stroke
			(width 0)
			(type solid)
		)
		(fill yes)
		(layer "F.Cu")
		(net "M_E_CPU1_SB_DQ<27>")
	)
	(gr_poly
		(pts
			(xy 142.145512 -223.218756) (xy 142.094712 -223.218756) (xy 141.993112 -223.255078) (xy 141.993112 -223.445578)
			(xy 142.094712 -223.481646) (xy 142.145512 -223.481646)
		)
		(stroke
			(width 0)
			(type solid)
		)
		(fill yes)
		(layer "F.Cu")
		(net "M_E_CPU1_SB_DQ<27>")
	)
	(gr_poly
		(pts
			(xy 142.145512 -222.621856) (xy 142.094712 -222.621856) (xy 141.993112 -222.658178) (xy 141.993112 -222.848678)
			(xy 142.094712 -222.884746) (xy 142.145512 -222.884746)
		)
		(stroke
			(width 0)
			(type solid)
		)
		(fill yes)
		(layer "F.Cu")
		(net "M_E_CPU1_SB_DQ<27>")
	)
	(gr_poly
		(pts
			(xy 142.145512 -222.024956) (xy 142.094712 -222.024956) (xy 141.993112 -222.061278) (xy 141.993112 -222.251778)
			(xy 142.094712 -222.287846) (xy 142.145512 -222.287846)
		)
		(stroke
			(width 0)
			(type solid)
		)
		(fill yes)
		(layer "F.Cu")
		(net "M_E_CPU1_SB_DQ<27>")
	)
	(gr_poly
		(pts
			(xy 142.145512 -221.428056) (xy 142.094712 -221.428056) (xy 141.993112 -221.464378) (xy 141.993112 -221.654878)
			(xy 142.094712 -221.690946) (xy 142.145512 -221.690946)
		)
		(stroke
			(width 0)
			(type solid)
		)
		(fill yes)
		(layer "F.Cu")
		(net "M_E_CPU1_SB_DQ<27>")
	)
	(gr_poly
		(pts
			(xy 142.145512 -220.831156) (xy 142.094712 -220.831156) (xy 141.993112 -220.867478) (xy 141.993112 -221.057978)
			(xy 142.094712 -221.094046) (xy 142.145512 -221.094046)
		)
		(stroke
			(width 0)
			(type solid)
		)
		(fill yes)
		(layer "F.Cu")
		(net "M_E_CPU1_SB_DQ<27>")
	)
	(gr_poly
		(pts
			(xy 142.145512 -220.234256) (xy 142.094712 -220.234256) (xy 141.993112 -220.270578) (xy 141.993112 -220.461078)
			(xy 142.094712 -220.497146) (xy 142.145512 -220.497146)
		)
		(stroke
			(width 0)
			(type solid)
		)
		(fill yes)
		(layer "F.Cu")
		(net "M_E_CPU1_SB_DQ<27>")
	)
	(gr_poly
		(pts
			(xy 142.145512 -219.637356) (xy 142.094712 -219.637356) (xy 141.993112 -219.673678) (xy 141.993112 -219.864178)
			(xy 142.094712 -219.900246) (xy 142.145512 -219.900246)
		)
		(stroke
			(width 0)
			(type solid)
		)
		(fill yes)
		(layer "F.Cu")
		(net "M_E_CPU1_SB_DQ<27>")
	)
	(gr_poly
		(pts
			(xy 142.145512 -219.040456) (xy 142.094712 -219.040456) (xy 141.993112 -219.076778) (xy 141.993112 -219.267278)
			(xy 142.094712 -219.303346) (xy 142.145512 -219.303346)
		)
		(stroke
			(width 0)
			(type solid)
		)
		(fill yes)
		(layer "F.Cu")
		(net "M_E_CPU1_SB_DQ<27>")
	)
	(gr_poly
		(pts
			(xy 142.145512 -218.443556) (xy 142.094712 -218.443556) (xy 141.993112 -218.479878) (xy 141.993112 -218.670378)
			(xy 142.094712 -218.706446) (xy 142.145512 -218.706446)
		)
		(stroke
			(width 0)
			(type solid)
		)
		(fill yes)
		(layer "F.Cu")
		(net "M_E_CPU1_SB_DQ<27>")
	)
	(gr_poly
		(pts
			(xy 142.145512 -217.846656) (xy 142.094712 -217.846656) (xy 141.993112 -217.882978) (xy 141.993112 -218.073478)
			(xy 142.094712 -218.109546) (xy 142.145512 -218.109546)
		)
		(stroke
			(width 0)
			(type solid)
		)
		(fill yes)
		(layer "F.Cu")
		(net "M_E_CPU1_SB_DQ<27>")
	)
	(gr_poly
		(pts
			(xy 142.145512 -217.249756) (xy 142.094712 -217.249756) (xy 141.993112 -217.286078) (xy 141.993112 -217.476578)
			(xy 142.094712 -217.512646) (xy 142.145512 -217.512646)
		)
		(stroke
			(width 0)
			(type solid)
		)
		(fill yes)
		(layer "F.Cu")
		(net "M_E_CPU1_SB_DQ<27>")
	)
	(gr_poly
		(pts
			(xy 142.145512 -216.652856) (xy 142.094712 -216.652856) (xy 141.993112 -216.689178) (xy 141.993112 -216.879678)
			(xy 142.094712 -216.915746) (xy 142.145512 -216.915746)
		)
		(stroke
			(width 0)
			(type solid)
		)
		(fill yes)
		(layer "F.Cu")
		(net "M_E_CPU1_SB_DQ<27>")
	)
	(gr_poly
		(pts
			(xy 142.145512 -216.055956) (xy 142.094712 -216.055956) (xy 141.993112 -216.092278) (xy 141.993112 -216.282778)
			(xy 142.094712 -216.318846) (xy 142.145512 -216.318846)
		)
		(stroke
			(width 0)
			(type solid)
		)
		(fill yes)
		(layer "F.Cu")
		(net "M_E_CPU1_SB_DQ<27>")
	)
	(gr_poly
		(pts
			(xy 142.152116 -263.407652) (xy 142.198344 -263.310116) (xy 142.063724 -263.175496) (xy 141.966442 -263.221724)
			(xy 141.930374 -263.257538) (xy 142.116302 -263.443466)
		)
		(stroke
			(width 0)
			(type solid)
		)
		(fill yes)
		(layer "F.Cu")
		(net "M_E_CPU1_SA_CB<3>")
	)
	(gr_poly
		(pts
			(xy 142.15491 -255.797304) (xy 142.201138 -255.699768) (xy 142.066264 -255.565148) (xy 141.968982 -255.611376)
			(xy 141.932914 -255.64719) (xy 142.118842 -255.833118)
		)
		(stroke
			(width 0)
			(type solid)
		)
		(fill yes)
		(layer "F.Cu")
		(net "M_E_CPU1_SA_CA<2>")
	)
	(gr_poly
		(pts
			(xy 142.164054 -254.943864) (xy 142.210282 -254.846328) (xy 142.075408 -254.711708) (xy 141.978126 -254.757936)
			(xy 141.942058 -254.79375) (xy 142.127986 -254.979678)
		)
		(stroke
			(width 0)
			(type solid)
		)
		(fill yes)
		(layer "F.Cu")
		(net "M_E_CPU1_SA_CA<4>")
	)
	(gr_poly
		(pts
			(xy 142.167102 -266.769088) (xy 142.21333 -266.671806) (xy 142.07871 -266.536932) (xy 141.981174 -266.58316)
			(xy 141.94536 -266.619228) (xy 142.131288 -266.805156)
		)
		(stroke
			(width 0)
			(type solid)
		)
		(fill yes)
		(layer "F.Cu")
		(net "M_E_CPU1_SA_DQ<28>")
	)
	(gr_poly
		(pts
			(xy 142.173706 -243.092224) (xy 142.127478 -242.994688) (xy 142.09141 -242.958874) (xy 141.905736 -243.144548)
			(xy 141.94155 -243.180616) (xy 142.039086 -243.226844)
		)
		(stroke
			(width 0)
			(type solid)
		)
		(fill yes)
		(layer "F.Cu")
		(net "M_E_CPU1_SB_CB<4>")
	)
	(gr_poly
		(pts
			(xy 142.1765 -265.915648) (xy 142.222728 -265.818366) (xy 142.088108 -265.683492) (xy 141.990572 -265.72972)
			(xy 141.954758 -265.765788) (xy 142.140686 -265.951716)
		)
		(stroke
			(width 0)
			(type solid)
		)
		(fill yes)
		(layer "F.Cu")
		(net "M_E_CPU1_SA_DQ<29>")
	)
	(gr_poly
		(pts
			(xy 142.180056 -289.521646) (xy 142.129256 -289.521646) (xy 142.027656 -289.557968) (xy 142.027656 -289.748468)
			(xy 142.129256 -289.784536) (xy 142.180056 -289.784536)
		)
		(stroke
			(width 0)
			(type solid)
		)
		(fill yes)
		(layer "F.Cu")
		(net "M_E_CPU1_SA_DQ<5>")
	)
	(gr_poly
		(pts
			(xy 142.180056 -288.924746) (xy 142.129256 -288.924746) (xy 142.027656 -288.961068) (xy 142.027656 -289.151568)
			(xy 142.129256 -289.187636) (xy 142.180056 -289.187636)
		)
		(stroke
			(width 0)
			(type solid)
		)
		(fill yes)
		(layer "F.Cu")
		(net "M_E_CPU1_SA_DQ<5>")
	)
	(gr_poly
		(pts
			(xy 142.180056 -288.327846) (xy 142.129256 -288.327846) (xy 142.027656 -288.364168) (xy 142.027656 -288.554668)
			(xy 142.129256 -288.590736) (xy 142.180056 -288.590736)
		)
		(stroke
			(width 0)
			(type solid)
		)
		(fill yes)
		(layer "F.Cu")
		(net "M_E_CPU1_SA_DQ<5>")
	)
	(gr_poly
		(pts
			(xy 142.180056 -287.730946) (xy 142.129256 -287.730946) (xy 142.027656 -287.767268) (xy 142.027656 -287.957768)
			(xy 142.129256 -287.993836) (xy 142.180056 -287.993836)
		)
		(stroke
			(width 0)
			(type solid)
		)
		(fill yes)
		(layer "F.Cu")
		(net "M_E_CPU1_SA_DQ<5>")
	)
	(gr_poly
		(pts
			(xy 142.180056 -287.134046) (xy 142.129256 -287.134046) (xy 142.027656 -287.170368) (xy 142.027656 -287.360868)
			(xy 142.129256 -287.396936) (xy 142.180056 -287.396936)
		)
		(stroke
			(width 0)
			(type solid)
		)
		(fill yes)
		(layer "F.Cu")
		(net "M_E_CPU1_SA_DQ<5>")
	)
	(gr_poly
		(pts
			(xy 142.180056 -286.537146) (xy 142.129256 -286.537146) (xy 142.027656 -286.573468) (xy 142.027656 -286.763968)
			(xy 142.129256 -286.800036) (xy 142.180056 -286.800036)
		)
		(stroke
			(width 0)
			(type solid)
		)
		(fill yes)
		(layer "F.Cu")
		(net "M_E_CPU1_SA_DQ<5>")
	)
	(gr_poly
		(pts
			(xy 142.180056 -285.940246) (xy 142.129256 -285.940246) (xy 142.027656 -285.976568) (xy 142.027656 -286.167068)
			(xy 142.129256 -286.203136) (xy 142.180056 -286.203136)
		)
		(stroke
			(width 0)
			(type solid)
		)
		(fill yes)
		(layer "F.Cu")
		(net "M_E_CPU1_SA_DQ<5>")
	)
	(gr_poly
		(pts
			(xy 142.180056 -285.343346) (xy 142.129256 -285.343346) (xy 142.027656 -285.379668) (xy 142.027656 -285.570168)
			(xy 142.129256 -285.606236) (xy 142.180056 -285.606236)
		)
		(stroke
			(width 0)
			(type solid)
		)
		(fill yes)
		(layer "F.Cu")
		(net "M_E_CPU1_SA_DQ<5>")
	)
	(gr_poly
		(pts
			(xy 142.180056 -284.746446) (xy 142.129256 -284.746446) (xy 142.027656 -284.782768) (xy 142.027656 -284.973268)
			(xy 142.129256 -285.009336) (xy 142.180056 -285.009336)
		)
		(stroke
			(width 0)
			(type solid)
		)
		(fill yes)
		(layer "F.Cu")
		(net "M_E_CPU1_SA_DQ<5>")
	)
	(gr_poly
		(pts
			(xy 142.180056 -284.149546) (xy 142.129256 -284.149546) (xy 142.027656 -284.185868) (xy 142.027656 -284.376368)
			(xy 142.129256 -284.412436) (xy 142.180056 -284.412436)
		)
		(stroke
			(width 0)
			(type solid)
		)
		(fill yes)
		(layer "F.Cu")
		(net "M_E_CPU1_SA_DQ<5>")
	)
	(gr_poly
		(pts
			(xy 142.180056 -283.552646) (xy 142.129256 -283.552646) (xy 142.027656 -283.588968) (xy 142.027656 -283.779468)
			(xy 142.129256 -283.815536) (xy 142.180056 -283.815536)
		)
		(stroke
			(width 0)
			(type solid)
		)
		(fill yes)
		(layer "F.Cu")
		(net "M_E_CPU1_SA_DQ<5>")
	)
	(gr_poly
		(pts
			(xy 142.180056 -282.955746) (xy 142.129256 -282.955746) (xy 142.027656 -282.992068) (xy 142.027656 -283.182568)
			(xy 142.129256 -283.218636) (xy 142.180056 -283.218636)
		)
		(stroke
			(width 0)
			(type solid)
		)
		(fill yes)
		(layer "F.Cu")
		(net "M_E_CPU1_SA_DQ<5>")
	)
	(gr_poly
		(pts
			(xy 142.180056 -282.358846) (xy 142.129256 -282.358846) (xy 142.027656 -282.395168) (xy 142.027656 -282.585668)
			(xy 142.129256 -282.621736) (xy 142.180056 -282.621736)
		)
		(stroke
			(width 0)
			(type solid)
		)
		(fill yes)
		(layer "F.Cu")
		(net "M_E_CPU1_SA_DQ<5>")
	)
	(gr_poly
		(pts
			(xy 142.180056 -281.761946) (xy 142.129256 -281.761946) (xy 142.027656 -281.798268) (xy 142.027656 -281.988768)
			(xy 142.129256 -282.024836) (xy 142.180056 -282.024836)
		)
		(stroke
			(width 0)
			(type solid)
		)
		(fill yes)
		(layer "F.Cu")
		(net "M_E_CPU1_SA_DQ<5>")
	)
	(gr_poly
		(pts
			(xy 142.180056 -281.165046) (xy 142.129256 -281.165046) (xy 142.027656 -281.201368) (xy 142.027656 -281.391868)
			(xy 142.129256 -281.427936) (xy 142.180056 -281.427936)
		)
		(stroke
			(width 0)
			(type solid)
		)
		(fill yes)
		(layer "F.Cu")
		(net "M_E_CPU1_SA_DQ<5>")
	)
	(gr_poly
		(pts
			(xy 142.189454 -272.417286) (xy 142.235682 -272.31975) (xy 142.101062 -272.18513) (xy 142.003526 -272.231358)
			(xy 141.967712 -272.267426) (xy 142.153386 -272.4531)
		)
		(stroke
			(width 0)
			(type solid)
		)
		(fill yes)
		(layer "F.Cu")
		(net "M_E_CPU1_SA_DQ<20>")
	)
	(gr_poly
		(pts
			(xy 142.198852 -271.563338) (xy 142.24508 -271.466056) (xy 142.11046 -271.331436) (xy 142.012924 -271.377664)
			(xy 141.97711 -271.413478) (xy 142.163038 -271.599406)
		)
		(stroke
			(width 0)
			(type solid)
		)
		(fill yes)
		(layer "F.Cu")
		(net "M_E_CPU1_SA_DQ<21>")
	)
	(gr_poly
		(pts
			(xy 142.200376 -260.867144) (xy 142.246604 -260.769608) (xy 142.11173 -260.634988) (xy 142.014448 -260.681216)
			(xy 141.97838 -260.71703) (xy 142.164308 -260.902958)
		)
		(stroke
			(width 0)
			(type solid)
		)
		(fill yes)
		(layer "F.Cu")
		(net "M_E_CPU1_SA_CB<6>")
	)
	(gr_poly
		(pts
			(xy 142.207488 -275.604986) (xy 142.243556 -275.569172) (xy 142.057628 -275.383244) (xy 142.02156 -275.419058)
			(xy 141.975332 -275.516594) (xy 142.110206 -275.651214)
		)
		(stroke
			(width 0)
			(type solid)
		)
		(fill yes)
		(layer "F.Cu")
		(net "M_E_CPU1_SA_DQ<18>")
	)
	(gr_poly
		(pts
			(xy 142.207742 -269.86611) (xy 142.25397 -269.768574) (xy 142.11935 -269.633954) (xy 142.022068 -269.680182)
			(xy 141.986 -269.715996) (xy 142.171928 -269.901924)
		)
		(stroke
			(width 0)
			(type solid)
		)
		(fill yes)
		(layer "F.Cu")
		(net "M_E_CPU1_SA_DQ<26>")
	)
	(gr_poly
		(pts
			(xy 142.20952 -260.013704) (xy 142.255748 -259.916168) (xy 142.121128 -259.781548) (xy 142.023592 -259.827776)
			(xy 141.987778 -259.863844) (xy 142.173706 -260.049772)
		)
		(stroke
			(width 0)
			(type solid)
		)
		(fill yes)
		(layer "F.Cu")
		(net "M_E_CPU1_SA_CB<7>")
	)
	(gr_poly
		(pts
			(xy 142.213076 -229.451408) (xy 142.177262 -229.41534) (xy 142.079726 -229.369112) (xy 141.945106 -229.503732)
			(xy 141.991334 -229.601268) (xy 142.027402 -229.637082)
		)
		(stroke
			(width 0)
			(type solid)
		)
		(fill yes)
		(layer "F.Cu")
		(net "M_E_CPU1_SB_DQ<21>")
	)
	(gr_poly
		(pts
			(xy 142.216886 -269.01267) (xy 142.263114 -268.915134) (xy 142.128494 -268.780514) (xy 142.031212 -268.826742)
			(xy 141.995144 -268.862556) (xy 142.181072 -269.048484)
		)
		(stroke
			(width 0)
			(type solid)
		)
		(fill yes)
		(layer "F.Cu")
		(net "M_E_CPU1_SA_DQ<27>")
	)
	(gr_poly
		(pts
			(xy 142.21714 -274.751292) (xy 142.252954 -274.715478) (xy 142.067026 -274.52955) (xy 142.031212 -274.565364)
			(xy 141.984984 -274.6629) (xy 142.119604 -274.79752)
		)
		(stroke
			(width 0)
			(type solid)
		)
		(fill yes)
		(layer "F.Cu")
		(net "M_E_CPU1_SA_DQ<19>")
	)
	(gr_poly
		(pts
			(xy 142.222474 -230.304594) (xy 142.186406 -230.26878) (xy 142.089124 -230.222552) (xy 141.95425 -230.357172)
			(xy 142.000478 -230.454708) (xy 142.036546 -230.490522)
		)
		(stroke
			(width 0)
			(type solid)
		)
		(fill yes)
		(layer "F.Cu")
		(net "M_E_CPU1_SB_DQ<20>")
	)
	(gr_poly
		(pts
			(xy 142.249144 -232.866184) (xy 142.21333 -232.830116) (xy 142.115794 -232.783888) (xy 141.981174 -232.918508)
			(xy 142.027402 -233.016044) (xy 142.06347 -233.051858)
		)
		(stroke
			(width 0)
			(type solid)
		)
		(fill yes)
		(layer "F.Cu")
		(net "M_E_CPU1_SB_DQ<17>")
	)
	(gr_poly
		(pts
			(xy 142.253716 -279.014682) (xy 142.346172 -278.959056) (xy 142.308834 -278.772366) (xy 142.202154 -278.756872)
			(xy 142.15237 -278.766778) (xy 142.203932 -279.024588)
		)
		(stroke
			(width 0)
			(type solid)
		)
		(fill yes)
		(layer "F.Cu")
		(net "M_E_CPU1_SA_DQ<7>")
	)
	(gr_poly
		(pts
			(xy 142.258034 -234.563158) (xy 142.22222 -234.527344) (xy 142.124684 -234.480862) (xy 141.990064 -234.615736)
			(xy 142.036292 -234.713018) (xy 142.072106 -234.749086)
		)
		(stroke
			(width 0)
			(type solid)
		)
		(fill yes)
		(layer "F.Cu")
		(net "M_E_CPU1_SB_DQ<15>")
	)
	(gr_poly
		(pts
			(xy 142.258542 -233.71937) (xy 142.222474 -233.683556) (xy 142.125192 -233.637328) (xy 141.990318 -233.771948)
			(xy 142.036546 -233.869484) (xy 142.072614 -233.905298)
		)
		(stroke
			(width 0)
			(type solid)
		)
		(fill yes)
		(layer "F.Cu")
		(net "M_E_CPU1_SB_DQ<16>")
	)
	(gr_poly
		(pts
			(xy 142.262352 -279.317196) (xy 142.21079 -279.059386) (xy 142.161006 -279.069292) (xy 142.06855 -279.124918)
			(xy 142.105888 -279.311608) (xy 142.212568 -279.327102)
		)
		(stroke
			(width 0)
			(type solid)
		)
		(fill yes)
		(layer "F.Cu")
		(net "M_E_CPU1_SA_DQ<7>")
	)
	(gr_poly
		(pts
			(xy 142.262352 -248.459752) (xy 142.262352 -248.408952) (xy 141.999208 -248.408952) (xy 141.999208 -248.459752)
			(xy 142.03553 -248.561352) (xy 142.22603 -248.561352)
		)
		(stroke
			(width 0)
			(type solid)
		)
		(fill yes)
		(layer "F.Cu")
		(net "M_E_CPU1_SB_CA<2>")
	)
	(gr_poly
		(pts
			(xy 142.262352 -248.154952) (xy 142.262352 -248.104152) (xy 141.999208 -248.104152) (xy 141.999208 -248.154952)
			(xy 142.03553 -248.256552) (xy 142.22603 -248.256552)
		)
		(stroke
			(width 0)
			(type solid)
		)
		(fill yes)
		(layer "F.Cu")
		(net "M_E_CPU1_SB_CA<3>")
	)
	(gr_poly
		(pts
			(xy 142.262352 -247.850152) (xy 142.262352 -247.799352) (xy 141.999208 -247.799352) (xy 141.999208 -247.850152)
			(xy 142.03553 -247.951752) (xy 142.22603 -247.951752)
		)
		(stroke
			(width 0)
			(type solid)
		)
		(fill yes)
		(layer "F.Cu")
		(net "M_E_CPU1_SB_CA<4>")
	)
	(gr_poly
		(pts
			(xy 142.262352 -247.545352) (xy 142.262352 -247.494552) (xy 141.999208 -247.494552) (xy 141.999208 -247.545352)
			(xy 142.03553 -247.646952) (xy 142.22603 -247.646952)
		)
		(stroke
			(width 0)
			(type solid)
		)
		(fill yes)
		(layer "F.Cu")
		(net "M_E_CPU1_SB_CA<5>")
	)
	(gr_poly
		(pts
			(xy 142.262352 -247.240552) (xy 142.262352 -247.189752) (xy 141.999208 -247.189752) (xy 141.999208 -247.240552)
			(xy 142.03553 -247.342152) (xy 142.22603 -247.342152)
		)
		(stroke
			(width 0)
			(type solid)
		)
		(fill yes)
		(layer "F.Cu")
		(net "M_E_CPU1_SB_CA<6>")
	)
	(gr_poly
		(pts
			(xy 142.262352 -246.935752) (xy 142.262352 -246.884952) (xy 141.999208 -246.884952) (xy 141.999208 -246.935752)
			(xy 142.03553 -247.037352) (xy 142.22603 -247.037352)
		)
		(stroke
			(width 0)
			(type solid)
		)
		(fill yes)
		(layer "F.Cu")
		(net "M_E_CPU1_SB_PAR")
	)
	(gr_poly
		(pts
			(xy 142.262352 -246.630952) (xy 142.262352 -246.580152) (xy 141.999208 -246.580152) (xy 141.999208 -246.630952)
			(xy 142.03553 -246.732552) (xy 142.22603 -246.732552)
		)
		(stroke
			(width 0)
			(type solid)
		)
		(fill yes)
		(layer "F.Cu")
		(net "M_E_CPU1_SB_CS_N<0>")
	)
	(gr_poly
		(pts
			(xy 142.262352 -246.326152) (xy 142.262352 -246.275352) (xy 141.999208 -246.275352) (xy 141.999208 -246.326152)
			(xy 142.03553 -246.427752) (xy 142.22603 -246.427752)
		)
		(stroke
			(width 0)
			(type solid)
		)
		(fill yes)
		(layer "F.Cu")
		(net "M_E_CPU1_SB_CS_N<2>")
	)
	(gr_poly
		(pts
			(xy 142.262352 -246.021352) (xy 142.262352 -245.970552) (xy 141.999208 -245.970552) (xy 141.999208 -246.021352)
			(xy 142.03553 -246.122952) (xy 142.22603 -246.122952)
		)
		(stroke
			(width 0)
			(type solid)
		)
		(fill yes)
		(layer "F.Cu")
		(net "M_E_CPU1_SB_CS_N<1>")
	)
	(gr_poly
		(pts
			(xy 142.262352 -245.716552) (xy 142.262352 -245.665752) (xy 141.999208 -245.665752) (xy 141.999208 -245.716552)
			(xy 142.03553 -245.818152) (xy 142.22603 -245.818152)
		)
		(stroke
			(width 0)
			(type solid)
		)
		(fill yes)
		(layer "F.Cu")
		(net "M_E_CPU1_SB_CS_N<3>")
	)
	(gr_poly
		(pts
			(xy 142.266162 -258.640072) (xy 142.301976 -258.604258) (xy 142.116048 -258.41833) (xy 142.080234 -258.454398)
			(xy 142.034006 -258.55168) (xy 142.168626 -258.686554)
		)
		(stroke
			(width 0)
			(type solid)
		)
		(fill yes)
		(layer "F.Cu")
		(net "M_E_CPU1_SA_CS_N<0>")
	)
	(gr_poly
		(pts
			(xy 142.267178 -235.416598) (xy 142.231364 -235.38053) (xy 142.133828 -235.334302) (xy 141.999208 -235.468922)
			(xy 142.045436 -235.566458) (xy 142.081504 -235.602272)
		)
		(stroke
			(width 0)
			(type solid)
		)
		(fill yes)
		(layer "F.Cu")
		(net "M_E_CPU1_SB_DQ<14>")
	)
	(gr_poly
		(pts
			(xy 142.275306 -257.786632) (xy 142.311374 -257.750818) (xy 142.125446 -257.56489) (xy 142.089632 -257.600704)
			(xy 142.04315 -257.69824) (xy 142.178024 -257.83286)
		)
		(stroke
			(width 0)
			(type solid)
		)
		(fill yes)
		(layer "F.Cu")
		(net "M_E_CPU1_SA_CS_N<1>")
	)
	(gr_poly
		(pts
			(xy 142.282164 -264.543794) (xy 142.318232 -264.50798) (xy 142.132304 -264.322052) (xy 142.096236 -264.357866)
			(xy 142.050008 -264.455402) (xy 142.184628 -264.590022)
		)
		(stroke
			(width 0)
			(type solid)
		)
		(fill yes)
		(layer "F.Cu")
		(net "M_E_CPU1_SA_CB<2>")
	)
	(gr_poly
		(pts
			(xy 142.283434 -276.492462) (xy 142.231872 -276.234652) (xy 142.182088 -276.244812) (xy 142.089632 -276.300184)
			(xy 142.12697 -276.486874) (xy 142.23365 -276.502622)
		)
		(stroke
			(width 0)
			(type solid)
		)
		(fill yes)
		(layer "F.Cu")
		(net "M_E_CPU1_SA_DQ<16>")
	)
	(gr_poly
		(pts
			(xy 142.283942 -275.106384) (xy 142.33017 -275.009102) (xy 142.19555 -274.874228) (xy 142.098014 -274.92071)
			(xy 142.0622 -274.956524) (xy 142.248128 -275.142452)
		)
		(stroke
			(width 0)
			(type solid)
		)
		(fill yes)
		(layer "F.Cu")
		(net "M_E_CPU1_SA_DQ<17>")
	)
	(gr_poly
		(pts
			(xy 142.284704 -256.933446) (xy 142.320518 -256.897378) (xy 142.13459 -256.71145) (xy 142.098776 -256.747518)
			(xy 142.052548 -256.8448) (xy 142.187168 -256.979674)
		)
		(stroke
			(width 0)
			(type solid)
		)
		(fill yes)
		(layer "F.Cu")
		(net "M_E_CPU1_SA_CA<0>")
	)
	(gr_poly
		(pts
			(xy 142.2908 -229.158038) (xy 142.244572 -229.060502) (xy 142.208504 -229.024688) (xy 142.022576 -229.210616)
			(xy 142.058644 -229.24643) (xy 142.155926 -229.292658)
		)
		(stroke
			(width 0)
			(type solid)
		)
		(fill yes)
		(layer "F.Cu")
		(net "M_E_CPU1_SB_DQ<23>")
	)
	(gr_poly
		(pts
			(xy 142.291308 -263.690354) (xy 142.327376 -263.65454) (xy 142.141448 -263.468612) (xy 142.105634 -263.504426)
			(xy 142.059152 -263.601962) (xy 142.194026 -263.736582)
		)
		(stroke
			(width 0)
			(type solid)
		)
		(fill yes)
		(layer "F.Cu")
		(net "M_E_CPU1_SA_CB<3>")
	)
	(gr_poly
		(pts
			(xy 142.293848 -256.080006) (xy 142.329662 -256.043938) (xy 142.143988 -255.858264) (xy 142.10792 -255.894078)
			(xy 142.061692 -255.991614) (xy 142.196312 -256.126234)
		)
		(stroke
			(width 0)
			(type solid)
		)
		(fill yes)
		(layer "F.Cu")
		(net "M_E_CPU1_SA_CA<2>")
	)
	(gr_poly
		(pts
			(xy 142.297912 -224.937574) (xy 142.297912 -224.747074) (xy 142.196312 -224.711006) (xy 142.145512 -224.711006)
			(xy 142.145512 -224.973896) (xy 142.196312 -224.973896)
		)
		(stroke
			(width 0)
			(type solid)
		)
		(fill yes)
		(layer "F.Cu")
		(net "M_E_CPU1_SB_DQ<27>")
	)
	(gr_poly
		(pts
			(xy 142.297912 -224.340674) (xy 142.297912 -224.150174) (xy 142.196312 -224.114106) (xy 142.145512 -224.114106)
			(xy 142.145512 -224.376996) (xy 142.196312 -224.376996)
		)
		(stroke
			(width 0)
			(type solid)
		)
		(fill yes)
		(layer "F.Cu")
		(net "M_E_CPU1_SB_DQ<27>")
	)
	(gr_poly
		(pts
			(xy 142.297912 -223.743774) (xy 142.297912 -223.553274) (xy 142.196312 -223.517206) (xy 142.145512 -223.517206)
			(xy 142.145512 -223.780096) (xy 142.196312 -223.780096)
		)
		(stroke
			(width 0)
			(type solid)
		)
		(fill yes)
		(layer "F.Cu")
		(net "M_E_CPU1_SB_DQ<27>")
	)
	(gr_poly
		(pts
			(xy 142.297912 -223.146874) (xy 142.297912 -222.956374) (xy 142.196312 -222.920306) (xy 142.145512 -222.920306)
			(xy 142.145512 -223.183196) (xy 142.196312 -223.183196)
		)
		(stroke
			(width 0)
			(type solid)
		)
		(fill yes)
		(layer "F.Cu")
		(net "M_E_CPU1_SB_DQ<27>")
	)
	(gr_poly
		(pts
			(xy 142.297912 -222.549974) (xy 142.297912 -222.359474) (xy 142.196312 -222.323406) (xy 142.145512 -222.323406)
			(xy 142.145512 -222.586296) (xy 142.196312 -222.586296)
		)
		(stroke
			(width 0)
			(type solid)
		)
		(fill yes)
		(layer "F.Cu")
		(net "M_E_CPU1_SB_DQ<27>")
	)
	(gr_poly
		(pts
			(xy 142.297912 -221.953074) (xy 142.297912 -221.762574) (xy 142.196312 -221.726506) (xy 142.145512 -221.726506)
			(xy 142.145512 -221.989396) (xy 142.196312 -221.989396)
		)
		(stroke
			(width 0)
			(type solid)
		)
		(fill yes)
		(layer "F.Cu")
		(net "M_E_CPU1_SB_DQ<27>")
	)
	(gr_poly
		(pts
			(xy 142.297912 -221.356174) (xy 142.297912 -221.165674) (xy 142.196312 -221.129606) (xy 142.145512 -221.129606)
			(xy 142.145512 -221.392496) (xy 142.196312 -221.392496)
		)
		(stroke
			(width 0)
			(type solid)
		)
		(fill yes)
		(layer "F.Cu")
		(net "M_E_CPU1_SB_DQ<27>")
	)
	(gr_poly
		(pts
			(xy 142.297912 -220.759274) (xy 142.297912 -220.568774) (xy 142.196312 -220.532706) (xy 142.145512 -220.532706)
			(xy 142.145512 -220.795596) (xy 142.196312 -220.795596)
		)
		(stroke
			(width 0)
			(type solid)
		)
		(fill yes)
		(layer "F.Cu")
		(net "M_E_CPU1_SB_DQ<27>")
	)
	(gr_poly
		(pts
			(xy 142.297912 -220.162374) (xy 142.297912 -219.971874) (xy 142.196312 -219.935806) (xy 142.145512 -219.935806)
			(xy 142.145512 -220.198696) (xy 142.196312 -220.198696)
		)
		(stroke
			(width 0)
			(type solid)
		)
		(fill yes)
		(layer "F.Cu")
		(net "M_E_CPU1_SB_DQ<27>")
	)
	(gr_poly
		(pts
			(xy 142.297912 -219.565474) (xy 142.297912 -219.374974) (xy 142.196312 -219.338906) (xy 142.145512 -219.338906)
			(xy 142.145512 -219.601796) (xy 142.196312 -219.601796)
		)
		(stroke
			(width 0)
			(type solid)
		)
		(fill yes)
		(layer "F.Cu")
		(net "M_E_CPU1_SB_DQ<27>")
	)
	(gr_poly
		(pts
			(xy 142.297912 -218.968574) (xy 142.297912 -218.778074) (xy 142.196312 -218.742006) (xy 142.145512 -218.742006)
			(xy 142.145512 -219.004896) (xy 142.196312 -219.004896)
		)
		(stroke
			(width 0)
			(type solid)
		)
		(fill yes)
		(layer "F.Cu")
		(net "M_E_CPU1_SB_DQ<27>")
	)
	(gr_poly
		(pts
			(xy 142.297912 -218.371674) (xy 142.297912 -218.181174) (xy 142.196312 -218.145106) (xy 142.145512 -218.145106)
			(xy 142.145512 -218.407996) (xy 142.196312 -218.407996)
		)
		(stroke
			(width 0)
			(type solid)
		)
		(fill yes)
		(layer "F.Cu")
		(net "M_E_CPU1_SB_DQ<27>")
	)
	(gr_poly
		(pts
			(xy 142.297912 -217.774774) (xy 142.297912 -217.584274) (xy 142.196312 -217.548206) (xy 142.145512 -217.548206)
			(xy 142.145512 -217.811096) (xy 142.196312 -217.811096)
		)
		(stroke
			(width 0)
			(type solid)
		)
		(fill yes)
		(layer "F.Cu")
		(net "M_E_CPU1_SB_DQ<27>")
	)
	(gr_poly
		(pts
			(xy 142.297912 -217.177874) (xy 142.297912 -216.987374) (xy 142.196312 -216.951306) (xy 142.145512 -216.951306)
			(xy 142.145512 -217.214196) (xy 142.196312 -217.214196)
		)
		(stroke
			(width 0)
			(type solid)
		)
		(fill yes)
		(layer "F.Cu")
		(net "M_E_CPU1_SB_DQ<27>")
	)
	(gr_poly
		(pts
			(xy 142.297912 -216.580974) (xy 142.297912 -216.390474) (xy 142.196312 -216.354406) (xy 142.145512 -216.354406)
			(xy 142.145512 -216.617296) (xy 142.196312 -216.617296)
		)
		(stroke
			(width 0)
			(type solid)
		)
		(fill yes)
		(layer "F.Cu")
		(net "M_E_CPU1_SB_DQ<27>")
	)
	(gr_poly
		(pts
			(xy 142.297912 -215.984074) (xy 142.297912 -215.793574) (xy 142.196312 -215.757506) (xy 142.145512 -215.757506)
			(xy 142.145512 -216.020396) (xy 142.196312 -216.020396)
		)
		(stroke
			(width 0)
			(type solid)
		)
		(fill yes)
		(layer "F.Cu")
		(net "M_E_CPU1_SB_DQ<27>")
	)
	(gr_poly
		(pts
			(xy 142.299944 -230.011478) (xy 142.253716 -229.913942) (xy 142.217902 -229.877874) (xy 142.031974 -230.063802)
			(xy 142.067788 -230.09987) (xy 142.165324 -230.146098)
		)
		(stroke
			(width 0)
			(type solid)
		)
		(fill yes)
		(layer "F.Cu")
		(net "M_E_CPU1_SB_DQ<22>")
	)
	(gr_poly
		(pts
			(xy 142.302484 -242.7478) (xy 142.26667 -242.711732) (xy 142.169134 -242.665504) (xy 142.034514 -242.800124)
			(xy 142.080742 -242.89766) (xy 142.116556 -242.933728)
		)
		(stroke
			(width 0)
			(type solid)
		)
		(fill yes)
		(layer "F.Cu")
		(net "M_E_CPU1_SB_CB<4>")
	)
	(gr_poly
		(pts
			(xy 142.303246 -255.22682) (xy 142.33906 -255.190752) (xy 142.153132 -255.004824) (xy 142.117318 -255.040892)
			(xy 142.07109 -255.138174) (xy 142.20571 -255.273048)
		)
		(stroke
			(width 0)
			(type solid)
		)
		(fill yes)
		(layer "F.Cu")
		(net "M_E_CPU1_SA_CA<4>")
	)
	(gr_poly
		(pts
			(xy 142.306294 -267.052044) (xy 142.342362 -267.01623) (xy 142.156434 -266.830302) (xy 142.120366 -266.866116)
			(xy 142.074138 -266.963652) (xy 142.209012 -267.098272)
		)
		(stroke
			(width 0)
			(type solid)
		)
		(fill yes)
		(layer "F.Cu")
		(net "M_E_CPU1_SA_DQ<28>")
	)
	(gr_poly
		(pts
			(xy 142.315692 -266.198604) (xy 142.351506 -266.162536) (xy 142.165832 -265.976862) (xy 142.129764 -266.012676)
			(xy 142.083536 -266.110212) (xy 142.218156 -266.244832)
		)
		(stroke
			(width 0)
			(type solid)
		)
		(fill yes)
		(layer "F.Cu")
		(net "M_E_CPU1_SA_DQ<29>")
	)
	(gr_poly
		(pts
			(xy 142.326868 -232.572814) (xy 142.28064 -232.475278) (xy 142.244572 -232.439464) (xy 142.058644 -232.625392)
			(xy 142.094712 -232.661206) (xy 142.191994 -232.707434)
		)
		(stroke
			(width 0)
			(type solid)
		)
		(fill yes)
		(layer "F.Cu")
		(net "M_E_CPU1_SB_DQ<19>")
	)
	(gr_poly
		(pts
			(xy 142.328646 -272.700242) (xy 142.36446 -272.664174) (xy 142.178532 -272.478246) (xy 142.142718 -272.514314)
			(xy 142.09649 -272.611596) (xy 142.23111 -272.74647)
		)
		(stroke
			(width 0)
			(type solid)
		)
		(fill yes)
		(layer "F.Cu")
		(net "M_E_CPU1_SA_DQ<20>")
	)
	(gr_poly
		(pts
			(xy 142.332456 -290.046918) (xy 142.332456 -289.856418) (xy 142.230856 -289.820096) (xy 142.180056 -289.820096)
			(xy 142.180056 -290.082986) (xy 142.230856 -290.082986)
		)
		(stroke
			(width 0)
			(type solid)
		)
		(fill yes)
		(layer "F.Cu")
		(net "M_E_CPU1_SA_DQ<5>")
	)
	(gr_poly
		(pts
			(xy 142.332456 -289.450018) (xy 142.332456 -289.259518) (xy 142.230856 -289.223196) (xy 142.180056 -289.223196)
			(xy 142.180056 -289.486086) (xy 142.230856 -289.486086)
		)
		(stroke
			(width 0)
			(type solid)
		)
		(fill yes)
		(layer "F.Cu")
		(net "M_E_CPU1_SA_DQ<5>")
	)
	(gr_poly
		(pts
			(xy 142.332456 -288.853118) (xy 142.332456 -288.662618) (xy 142.230856 -288.626296) (xy 142.180056 -288.626296)
			(xy 142.180056 -288.889186) (xy 142.230856 -288.889186)
		)
		(stroke
			(width 0)
			(type solid)
		)
		(fill yes)
		(layer "F.Cu")
		(net "M_E_CPU1_SA_DQ<5>")
	)
	(gr_poly
		(pts
			(xy 142.332456 -288.256218) (xy 142.332456 -288.065718) (xy 142.230856 -288.029396) (xy 142.180056 -288.029396)
			(xy 142.180056 -288.292286) (xy 142.230856 -288.292286)
		)
		(stroke
			(width 0)
			(type solid)
		)
		(fill yes)
		(layer "F.Cu")
		(net "M_E_CPU1_SA_DQ<5>")
	)
	(gr_poly
		(pts
			(xy 142.332456 -287.659318) (xy 142.332456 -287.468818) (xy 142.230856 -287.432496) (xy 142.180056 -287.432496)
			(xy 142.180056 -287.695386) (xy 142.230856 -287.695386)
		)
		(stroke
			(width 0)
			(type solid)
		)
		(fill yes)
		(layer "F.Cu")
		(net "M_E_CPU1_SA_DQ<5>")
	)
	(gr_poly
		(pts
			(xy 142.332456 -287.062418) (xy 142.332456 -286.871918) (xy 142.230856 -286.835596) (xy 142.180056 -286.835596)
			(xy 142.180056 -287.098486) (xy 142.230856 -287.098486)
		)
		(stroke
			(width 0)
			(type solid)
		)
		(fill yes)
		(layer "F.Cu")
		(net "M_E_CPU1_SA_DQ<5>")
	)
	(gr_poly
		(pts
			(xy 142.332456 -286.465518) (xy 142.332456 -286.275018) (xy 142.230856 -286.238696) (xy 142.180056 -286.238696)
			(xy 142.180056 -286.501586) (xy 142.230856 -286.501586)
		)
		(stroke
			(width 0)
			(type solid)
		)
		(fill yes)
		(layer "F.Cu")
		(net "M_E_CPU1_SA_DQ<5>")
	)
	(gr_poly
		(pts
			(xy 142.332456 -285.868618) (xy 142.332456 -285.678118) (xy 142.230856 -285.641796) (xy 142.180056 -285.641796)
			(xy 142.180056 -285.904686) (xy 142.230856 -285.904686)
		)
		(stroke
			(width 0)
			(type solid)
		)
		(fill yes)
		(layer "F.Cu")
		(net "M_E_CPU1_SA_DQ<5>")
	)
	(gr_poly
		(pts
			(xy 142.332456 -285.271718) (xy 142.332456 -285.081218) (xy 142.230856 -285.044896) (xy 142.180056 -285.044896)
			(xy 142.180056 -285.307786) (xy 142.230856 -285.307786)
		)
		(stroke
			(width 0)
			(type solid)
		)
		(fill yes)
		(layer "F.Cu")
		(net "M_E_CPU1_SA_DQ<5>")
	)
	(gr_poly
		(pts
			(xy 142.332456 -284.674818) (xy 142.332456 -284.484318) (xy 142.230856 -284.447996) (xy 142.180056 -284.447996)
			(xy 142.180056 -284.710886) (xy 142.230856 -284.710886)
		)
		(stroke
			(width 0)
			(type solid)
		)
		(fill yes)
		(layer "F.Cu")
		(net "M_E_CPU1_SA_DQ<5>")
	)
	(gr_poly
		(pts
			(xy 142.332456 -284.077918) (xy 142.332456 -283.887418) (xy 142.230856 -283.851096) (xy 142.180056 -283.851096)
			(xy 142.180056 -284.113986) (xy 142.230856 -284.113986)
		)
		(stroke
			(width 0)
			(type solid)
		)
		(fill yes)
		(layer "F.Cu")
		(net "M_E_CPU1_SA_DQ<5>")
	)
	(gr_poly
		(pts
			(xy 142.332456 -283.481018) (xy 142.332456 -283.290518) (xy 142.230856 -283.254196) (xy 142.180056 -283.254196)
			(xy 142.180056 -283.517086) (xy 142.230856 -283.517086)
		)
		(stroke
			(width 0)
			(type solid)
		)
		(fill yes)
		(layer "F.Cu")
		(net "M_E_CPU1_SA_DQ<5>")
	)
	(gr_poly
		(pts
			(xy 142.332456 -282.884118) (xy 142.332456 -282.693618) (xy 142.230856 -282.657296) (xy 142.180056 -282.657296)
			(xy 142.180056 -282.920186) (xy 142.230856 -282.920186)
		)
		(stroke
			(width 0)
			(type solid)
		)
		(fill yes)
		(layer "F.Cu")
		(net "M_E_CPU1_SA_DQ<5>")
	)
	(gr_poly
		(pts
			(xy 142.332456 -282.287218) (xy 142.332456 -282.096718) (xy 142.230856 -282.060396) (xy 142.180056 -282.060396)
			(xy 142.180056 -282.323286) (xy 142.230856 -282.323286)
		)
		(stroke
			(width 0)
			(type solid)
		)
		(fill yes)
		(layer "F.Cu")
		(net "M_E_CPU1_SA_DQ<5>")
	)
	(gr_poly
		(pts
			(xy 142.332456 -281.690318) (xy 142.332456 -281.499818) (xy 142.230856 -281.463496) (xy 142.180056 -281.463496)
			(xy 142.180056 -281.726386) (xy 142.230856 -281.726386)
		)
		(stroke
			(width 0)
			(type solid)
		)
		(fill yes)
		(layer "F.Cu")
		(net "M_E_CPU1_SA_DQ<5>")
	)
	(gr_poly
		(pts
			(xy 142.332456 -281.093418) (xy 142.332456 -280.902918) (xy 142.230856 -280.866596) (xy 142.180056 -280.866596)
			(xy 142.180056 -281.129486) (xy 142.230856 -281.129486)
		)
		(stroke
			(width 0)
			(type solid)
		)
		(fill yes)
		(layer "F.Cu")
		(net "M_E_CPU1_SA_DQ<5>")
	)
	(gr_poly
		(pts
			(xy 142.336012 -233.426) (xy 142.289784 -233.328718) (xy 142.25397 -233.29265) (xy 142.068042 -233.478578)
			(xy 142.103856 -233.514646) (xy 142.201392 -233.560874)
		)
		(stroke
			(width 0)
			(type solid)
		)
		(fill yes)
		(layer "F.Cu")
		(net "M_E_CPU1_SB_DQ<18>")
	)
	(gr_poly
		(pts
			(xy 142.338044 -271.846294) (xy 142.374112 -271.81048) (xy 142.188184 -271.624552) (xy 142.152116 -271.660366)
			(xy 142.105888 -271.757902) (xy 142.240762 -271.892522)
		)
		(stroke
			(width 0)
			(type solid)
		)
		(fill yes)
		(layer "F.Cu")
		(net "M_E_CPU1_SA_DQ<21>")
	)
	(gr_poly
		(pts
			(xy 142.339568 -261.149846) (xy 142.375382 -261.114032) (xy 142.189454 -260.928104) (xy 142.15364 -260.964172)
			(xy 142.107412 -261.061454) (xy 142.242032 -261.196328)
		)
		(stroke
			(width 0)
			(type solid)
		)
		(fill yes)
		(layer "F.Cu")
		(net "M_E_CPU1_SA_CB<6>")
	)
	(gr_poly
		(pts
			(xy 142.342616 -258.14147) (xy 142.388844 -258.044188) (xy 142.254224 -257.909314) (xy 142.156688 -257.955542)
			(xy 142.120874 -257.99161) (xy 142.306802 -258.177538)
		)
		(stroke
			(width 0)
			(type solid)
		)
		(fill yes)
		(layer "F.Cu")
		(net "M_E_CPU1_SA_CS_N<2>")
	)
	(gr_poly
		(pts
			(xy 142.344902 -235.123228) (xy 142.298674 -235.025692) (xy 142.262606 -234.989878) (xy 142.076678 -235.175806)
			(xy 142.112746 -235.21162) (xy 142.210028 -235.257848)
		)
		(stroke
			(width 0)
			(type solid)
		)
		(fill yes)
		(layer "F.Cu")
		(net "M_E_CPU1_SB_DQ<13>")
	)
	(gr_poly
		(pts
			(xy 142.346934 -270.148812) (xy 142.383002 -270.112998) (xy 142.197074 -269.92707) (xy 142.16126 -269.962884)
			(xy 142.114778 -270.06042) (xy 142.249652 -270.19504)
		)
		(stroke
			(width 0)
			(type solid)
		)
		(fill yes)
		(layer "F.Cu")
		(net "M_E_CPU1_SA_DQ<26>")
	)
	(gr_poly
		(pts
			(xy 142.348712 -260.29666) (xy 142.384526 -260.260592) (xy 142.198852 -260.074918) (xy 142.162784 -260.110732)
			(xy 142.116556 -260.208268) (xy 142.251176 -260.342888)
		)
		(stroke
			(width 0)
			(type solid)
		)
		(fill yes)
		(layer "F.Cu")
		(net "M_E_CPU1_SA_CB<7>")
	)
	(gr_poly
		(pts
			(xy 142.349474 -264.898632) (xy 142.395702 -264.801096) (xy 142.261082 -264.666476) (xy 142.163546 -264.712704)
			(xy 142.127732 -264.748772) (xy 142.313406 -264.934446)
		)
		(stroke
			(width 0)
			(type solid)
		)
		(fill yes)
		(layer "F.Cu")
		(net "M_E_CPU1_SA_CB<0>")
	)
	(gr_poly
		(pts
			(xy 142.35176 -257.288284) (xy 142.397988 -257.190748) (xy 142.263368 -257.056128) (xy 142.166086 -257.102356)
			(xy 142.130018 -257.13817) (xy 142.315946 -257.324098)
		)
		(stroke
			(width 0)
			(type solid)
		)
		(fill yes)
		(layer "F.Cu")
		(net "M_E_CPU1_SA_CS_N<3>")
	)
	(gr_poly
		(pts
			(xy 142.356078 -269.295372) (xy 142.392146 -269.259558) (xy 142.206218 -269.07363) (xy 142.170404 -269.109444)
			(xy 142.123922 -269.20698) (xy 142.258796 -269.3416)
		)
		(stroke
			(width 0)
			(type solid)
		)
		(fill yes)
		(layer "F.Cu")
		(net "M_E_CPU1_SA_DQ<27>")
	)
	(gr_poly
		(pts
			(xy 142.358618 -264.045192) (xy 142.404846 -263.94791) (xy 142.270226 -263.813036) (xy 142.17269 -263.859264)
			(xy 142.136876 -263.895332) (xy 142.322804 -264.08126)
		)
		(stroke
			(width 0)
			(type solid)
		)
		(fill yes)
		(layer "F.Cu")
		(net "M_E_CPU1_SA_CB<1>")
	)
	(gr_poly
		(pts
			(xy 142.361158 -256.434844) (xy 142.407386 -256.337308) (xy 142.272512 -256.202688) (xy 142.17523 -256.248916)
			(xy 142.139162 -256.28473) (xy 142.32509 -256.470658)
		)
		(stroke
			(width 0)
			(type solid)
		)
		(fill yes)
		(layer "F.Cu")
		(net "M_E_CPU1_SA_CA<1>")
	)
	(gr_poly
		(pts
			(xy 142.361412 -239.95634) (xy 142.361412 -239.90554) (xy 142.098522 -239.90554) (xy 142.098522 -239.95634)
			(xy 142.134844 -240.05794) (xy 142.325344 -240.05794)
		)
		(stroke
			(width 0)
			(type solid)
		)
		(fill yes)
		(layer "F.Cu")
		(net "M_E_CPU1_SB_CB<2>")
	)
	(gr_poly
		(pts
			(xy 142.361412 -239.65154) (xy 142.361412 -239.60074) (xy 142.098522 -239.60074) (xy 142.098522 -239.65154)
			(xy 142.134844 -239.75314) (xy 142.325344 -239.75314)
		)
		(stroke
			(width 0)
			(type solid)
		)
		(fill yes)
		(layer "F.Cu")
		(net "M_E_CPU1_SB_CB<1>")
	)
	(gr_poly
		(pts
			(xy 142.361412 -239.34674) (xy 142.361412 -239.29594) (xy 142.098522 -239.29594) (xy 142.098522 -239.34674)
			(xy 142.134844 -239.44834) (xy 142.325344 -239.44834)
		)
		(stroke
			(width 0)
			(type solid)
		)
		(fill yes)
		(layer "F.Cu")
		(net "M_E_CPU1_SB_CB<3>")
	)
	(gr_poly
		(pts
			(xy 142.370556 -255.581658) (xy 142.416784 -255.484122) (xy 142.28191 -255.349502) (xy 142.184628 -255.39573)
			(xy 142.14856 -255.431544) (xy 142.334488 -255.617472)
		)
		(stroke
			(width 0)
			(type solid)
		)
		(fill yes)
		(layer "F.Cu")
		(net "M_E_CPU1_SA_CA<3>")
	)
	(gr_poly
		(pts
			(xy 142.37081 -279.599898) (xy 142.463266 -279.544526) (xy 142.425928 -279.357582) (xy 142.319248 -279.342088)
			(xy 142.269464 -279.351994) (xy 142.321026 -279.609804)
		)
		(stroke
			(width 0)
			(type solid)
		)
		(fill yes)
		(layer "F.Cu")
		(net "M_E_CPU1_SA_DQ<7>")
	)
	(gr_poly
		(pts
			(xy 142.3797 -279.902412) (xy 142.327884 -279.644602) (xy 142.2781 -279.654762) (xy 142.185644 -279.710134)
			(xy 142.222982 -279.896824) (xy 142.329662 -279.912572)
		)
		(stroke
			(width 0)
			(type solid)
		)
		(fill yes)
		(layer "F.Cu")
		(net "M_E_CPU1_SA_DQ<7>")
	)
	(gr_poly
		(pts
			(xy 142.3797 -254.728218) (xy 142.425928 -254.630936) (xy 142.291308 -254.496062) (xy 142.193772 -254.54229)
			(xy 142.157958 -254.578358) (xy 142.343886 -254.764286)
		)
		(stroke
			(width 0)
			(type solid)
		)
		(fill yes)
		(layer "F.Cu")
		(net "M_E_CPU1_SA_CA<5>")
	)
	(gr_poly
		(pts
			(xy 142.382748 -266.553442) (xy 142.428976 -266.45616) (xy 142.294356 -266.321286) (xy 142.19682 -266.367514)
			(xy 142.161006 -266.403582) (xy 142.346934 -266.58951)
		)
		(stroke
			(width 0)
			(type solid)
		)
		(fill yes)
		(layer "F.Cu")
		(net "M_E_CPU1_SA_DQ<30>")
	)
	(gr_poly
		(pts
			(xy 142.391892 -276.775164) (xy 142.484348 -276.719792) (xy 142.44701 -276.533102) (xy 142.34033 -276.517354)
			(xy 142.290292 -276.527514) (xy 142.341854 -276.785324)
		)
		(stroke
			(width 0)
			(type solid)
		)
		(fill yes)
		(layer "F.Cu")
		(net "M_E_CPU1_SA_DQ<16>")
	)
	(gr_poly
		(pts
			(xy 142.392146 -265.700002) (xy 142.438628 -265.602466) (xy 142.303754 -265.467846) (xy 142.206472 -265.514074)
			(xy 142.170404 -265.549888) (xy 142.356332 -265.735816)
		)
		(stroke
			(width 0)
			(type solid)
		)
		(fill yes)
		(layer "F.Cu")
		(net "M_E_CPU1_SA_DQ<31>")
	)
	(gr_poly
		(pts
			(xy 142.400528 -277.077932) (xy 142.348966 -276.820122) (xy 142.298928 -276.830028) (xy 142.206472 -276.8854)
			(xy 142.24381 -277.072344) (xy 142.35049 -277.087838)
		)
		(stroke
			(width 0)
			(type solid)
		)
		(fill yes)
		(layer "F.Cu")
		(net "M_E_CPU1_SA_DQ<16>")
	)
	(gr_poly
		(pts
			(xy 142.405354 -272.201132) (xy 142.451582 -272.10385) (xy 142.316962 -271.968976) (xy 142.219426 -272.015204)
			(xy 142.183612 -272.051272) (xy 142.36954 -272.2372)
		)
		(stroke
			(width 0)
			(type solid)
		)
		(fill yes)
		(layer "F.Cu")
		(net "M_E_CPU1_SA_DQ<22>")
	)
	(gr_poly
		(pts
			(xy 142.406624 -261.504684) (xy 142.452852 -261.407402) (xy 142.318232 -261.272782) (xy 142.220696 -261.31901)
			(xy 142.184882 -261.354824) (xy 142.37081 -261.540752)
		)
		(stroke
			(width 0)
			(type solid)
		)
		(fill yes)
		(layer "F.Cu")
		(net "M_E_CPU1_SA_CB<4>")
	)
	(gr_poly
		(pts
			(xy 142.409164 -238.787686) (xy 142.409164 -238.736886) (xy 142.146274 -238.736886) (xy 142.146274 -238.787686)
			(xy 142.182596 -238.889286) (xy 142.373096 -238.889286)
		)
		(stroke
			(width 0)
			(type solid)
		)
		(fill yes)
		(layer "F.Cu")
		(net "M_E_CPU1_SB_DQ<8>")
	)
	(gr_poly
		(pts
			(xy 142.409164 -238.482886) (xy 142.409164 -238.432086) (xy 142.146274 -238.432086) (xy 142.146274 -238.482886)
			(xy 142.182596 -238.584486) (xy 142.373096 -238.584486)
		)
		(stroke
			(width 0)
			(type solid)
		)
		(fill yes)
		(layer "F.Cu")
		(net "M_E_CPU1_SB_DQ<10>")
	)
	(gr_poly
		(pts
			(xy 142.409164 -238.178086) (xy 142.409164 -238.127286) (xy 142.146274 -238.127286) (xy 142.146274 -238.178086)
			(xy 142.182596 -238.279686) (xy 142.373096 -238.279686)
		)
		(stroke
			(width 0)
			(type solid)
		)
		(fill yes)
		(layer "F.Cu")
		(net "M_E_CPU1_SB_DQ<9>")
	)
	(gr_poly
		(pts
			(xy 142.414244 -270.50365) (xy 142.460472 -270.406368) (xy 142.325852 -270.271494) (xy 142.228316 -270.317976)
			(xy 142.192502 -270.35379) (xy 142.37843 -270.539718)
		)
		(stroke
			(width 0)
			(type solid)
		)
		(fill yes)
		(layer "F.Cu")
		(net "M_E_CPU1_SA_DQ<24>")
	)
	(gr_poly
		(pts
			(xy 142.414752 -271.347692) (xy 142.46098 -271.250156) (xy 142.326106 -271.115536) (xy 142.228824 -271.161764)
			(xy 142.192756 -271.197578) (xy 142.378684 -271.383506)
		)
		(stroke
			(width 0)
			(type solid)
		)
		(fill yes)
		(layer "F.Cu")
		(net "M_E_CPU1_SA_DQ<23>")
	)
	(gr_poly
		(pts
			(xy 142.416022 -260.651498) (xy 142.46225 -260.553962) (xy 142.327376 -260.419342) (xy 142.230094 -260.46557)
			(xy 142.194026 -260.501384) (xy 142.379954 -260.687312)
		)
		(stroke
			(width 0)
			(type solid)
		)
		(fill yes)
		(layer "F.Cu")
		(net "M_E_CPU1_SA_CB<5>")
	)
	(gr_poly
		(pts
			(xy 142.423134 -275.38934) (xy 142.459202 -275.353526) (xy 142.273274 -275.167598) (xy 142.237206 -275.203412)
			(xy 142.190978 -275.300948) (xy 142.325852 -275.435568)
		)
		(stroke
			(width 0)
			(type solid)
		)
		(fill yes)
		(layer "F.Cu")
		(net "M_E_CPU1_SA_DQ<17>")
	)
	(gr_poly
		(pts
			(xy 142.423388 -269.65021) (xy 142.469616 -269.552928) (xy 142.334996 -269.418054) (xy 142.23746 -269.464536)
			(xy 142.201646 -269.50035) (xy 142.387574 -269.686278)
		)
		(stroke
			(width 0)
			(type solid)
		)
		(fill yes)
		(layer "F.Cu")
		(net "M_E_CPU1_SA_DQ<25>")
	)
	(gr_poly
		(pts
			(xy 142.428722 -229.667054) (xy 142.392908 -229.630986) (xy 142.295372 -229.584758) (xy 142.160752 -229.719378)
			(xy 142.20698 -229.816914) (xy 142.243048 -229.852728)
		)
		(stroke
			(width 0)
			(type solid)
		)
		(fill yes)
		(layer "F.Cu")
		(net "M_E_CPU1_SB_DQ<22>")
	)
	(gr_poly
		(pts
			(xy 142.450312 -225.009456) (xy 142.399512 -225.009456) (xy 142.297912 -225.045778) (xy 142.297912 -225.236278)
			(xy 142.399512 -225.272346) (xy 142.450312 -225.272346)
		)
		(stroke
			(width 0)
			(type solid)
		)
		(fill yes)
		(layer "F.Cu")
		(net "M_E_CPU1_SB_DQ<25>")
	)
	(gr_poly
		(pts
			(xy 142.450312 -224.412556) (xy 142.399512 -224.412556) (xy 142.297912 -224.448878) (xy 142.297912 -224.639378)
			(xy 142.399512 -224.675446) (xy 142.450312 -224.675446)
		)
		(stroke
			(width 0)
			(type solid)
		)
		(fill yes)
		(layer "F.Cu")
		(net "M_E_CPU1_SB_DQ<25>")
	)
	(gr_poly
		(pts
			(xy 142.450312 -223.815656) (xy 142.399512 -223.815656) (xy 142.297912 -223.851978) (xy 142.297912 -224.042478)
			(xy 142.399512 -224.078546) (xy 142.450312 -224.078546)
		)
		(stroke
			(width 0)
			(type solid)
		)
		(fill yes)
		(layer "F.Cu")
		(net "M_E_CPU1_SB_DQ<25>")
	)
	(gr_poly
		(pts
			(xy 142.450312 -223.218756) (xy 142.399512 -223.218756) (xy 142.297912 -223.255078) (xy 142.297912 -223.445578)
			(xy 142.399512 -223.481646) (xy 142.450312 -223.481646)
		)
		(stroke
			(width 0)
			(type solid)
		)
		(fill yes)
		(layer "F.Cu")
		(net "M_E_CPU1_SB_DQ<25>")
	)
	(gr_poly
		(pts
			(xy 142.450312 -222.621856) (xy 142.399512 -222.621856) (xy 142.297912 -222.658178) (xy 142.297912 -222.848678)
			(xy 142.399512 -222.884746) (xy 142.450312 -222.884746)
		)
		(stroke
			(width 0)
			(type solid)
		)
		(fill yes)
		(layer "F.Cu")
		(net "M_E_CPU1_SB_DQ<25>")
	)
	(gr_poly
		(pts
			(xy 142.450312 -222.024956) (xy 142.399512 -222.024956) (xy 142.297912 -222.061278) (xy 142.297912 -222.251778)
			(xy 142.399512 -222.287846) (xy 142.450312 -222.287846)
		)
		(stroke
			(width 0)
			(type solid)
		)
		(fill yes)
		(layer "F.Cu")
		(net "M_E_CPU1_SB_DQ<25>")
	)
	(gr_poly
		(pts
			(xy 142.450312 -221.428056) (xy 142.399512 -221.428056) (xy 142.297912 -221.464378) (xy 142.297912 -221.654878)
			(xy 142.399512 -221.690946) (xy 142.450312 -221.690946)
		)
		(stroke
			(width 0)
			(type solid)
		)
		(fill yes)
		(layer "F.Cu")
		(net "M_E_CPU1_SB_DQ<25>")
	)
	(gr_poly
		(pts
			(xy 142.450312 -220.831156) (xy 142.399512 -220.831156) (xy 142.297912 -220.867478) (xy 142.297912 -221.057978)
			(xy 142.399512 -221.094046) (xy 142.450312 -221.094046)
		)
		(stroke
			(width 0)
			(type solid)
		)
		(fill yes)
		(layer "F.Cu")
		(net "M_E_CPU1_SB_DQ<25>")
	)
	(gr_poly
		(pts
			(xy 142.450312 -220.234256) (xy 142.399512 -220.234256) (xy 142.297912 -220.270578) (xy 142.297912 -220.461078)
			(xy 142.399512 -220.497146) (xy 142.450312 -220.497146)
		)
		(stroke
			(width 0)
			(type solid)
		)
		(fill yes)
		(layer "F.Cu")
		(net "M_E_CPU1_SB_DQ<25>")
	)
	(gr_poly
		(pts
			(xy 142.450312 -219.637356) (xy 142.399512 -219.637356) (xy 142.297912 -219.673678) (xy 142.297912 -219.864178)
			(xy 142.399512 -219.900246) (xy 142.450312 -219.900246)
		)
		(stroke
			(width 0)
			(type solid)
		)
		(fill yes)
		(layer "F.Cu")
		(net "M_E_CPU1_SB_DQ<25>")
	)
	(gr_poly
		(pts
			(xy 142.450312 -219.040456) (xy 142.399512 -219.040456) (xy 142.297912 -219.076778) (xy 142.297912 -219.267278)
			(xy 142.399512 -219.303346) (xy 142.450312 -219.303346)
		)
		(stroke
			(width 0)
			(type solid)
		)
		(fill yes)
		(layer "F.Cu")
		(net "M_E_CPU1_SB_DQ<25>")
	)
	(gr_poly
		(pts
			(xy 142.450312 -218.443556) (xy 142.399512 -218.443556) (xy 142.297912 -218.479878) (xy 142.297912 -218.670378)
			(xy 142.399512 -218.706446) (xy 142.450312 -218.706446)
		)
		(stroke
			(width 0)
			(type solid)
		)
		(fill yes)
		(layer "F.Cu")
		(net "M_E_CPU1_SB_DQ<25>")
	)
	(gr_poly
		(pts
			(xy 142.450312 -217.846656) (xy 142.399512 -217.846656) (xy 142.297912 -217.882978) (xy 142.297912 -218.073478)
			(xy 142.399512 -218.109546) (xy 142.450312 -218.109546)
		)
		(stroke
			(width 0)
			(type solid)
		)
		(fill yes)
		(layer "F.Cu")
		(net "M_E_CPU1_SB_DQ<25>")
	)
	(gr_poly
		(pts
			(xy 142.450312 -217.249756) (xy 142.399512 -217.249756) (xy 142.297912 -217.286078) (xy 142.297912 -217.476578)
			(xy 142.399512 -217.512646) (xy 142.450312 -217.512646)
		)
		(stroke
			(width 0)
			(type solid)
		)
		(fill yes)
		(layer "F.Cu")
		(net "M_E_CPU1_SB_DQ<25>")
	)
	(gr_poly
		(pts
			(xy 142.450312 -216.652856) (xy 142.399512 -216.652856) (xy 142.297912 -216.689178) (xy 142.297912 -216.879678)
			(xy 142.399512 -216.915746) (xy 142.450312 -216.915746)
		)
		(stroke
			(width 0)
			(type solid)
		)
		(fill yes)
		(layer "F.Cu")
		(net "M_E_CPU1_SB_DQ<25>")
	)
	(gr_poly
		(pts
			(xy 142.450312 -216.055956) (xy 142.399512 -216.055956) (xy 142.297912 -216.092278) (xy 142.297912 -216.282778)
			(xy 142.399512 -216.318846) (xy 142.450312 -216.318846)
		)
		(stroke
			(width 0)
			(type solid)
		)
		(fill yes)
		(layer "F.Cu")
		(net "M_E_CPU1_SB_DQ<25>")
	)
	(gr_poly
		(pts
			(xy 142.455646 -232.22839) (xy 142.419832 -232.192322) (xy 142.322296 -232.146094) (xy 142.187676 -232.280968)
			(xy 142.233904 -232.37825) (xy 142.269718 -232.414318)
		)
		(stroke
			(width 0)
			(type solid)
		)
		(fill yes)
		(layer "F.Cu")
		(net "M_E_CPU1_SB_DQ<19>")
	)
	(gr_poly
		(pts
			(xy 142.46479 -233.08183) (xy 142.428976 -233.045762) (xy 142.33144 -232.999534) (xy 142.19682 -233.134154)
			(xy 142.243048 -233.23169) (xy 142.279116 -233.267504)
		)
		(stroke
			(width 0)
			(type solid)
		)
		(fill yes)
		(layer "F.Cu")
		(net "M_E_CPU1_SB_DQ<18>")
	)
	(gr_poly
		(pts
			(xy 142.47368 -234.778804) (xy 142.437866 -234.74299) (xy 142.34033 -234.696508) (xy 142.20571 -234.831382)
			(xy 142.251938 -234.928664) (xy 142.287752 -234.964732)
		)
		(stroke
			(width 0)
			(type solid)
		)
		(fill yes)
		(layer "F.Cu")
		(net "M_E_CPU1_SB_DQ<13>")
	)
	(gr_poly
		(pts
			(xy 142.481808 -258.424426) (xy 142.517876 -258.388612) (xy 142.331948 -258.202684) (xy 142.29588 -258.238498)
			(xy 142.249652 -258.336034) (xy 142.384526 -258.470654)
		)
		(stroke
			(width 0)
			(type solid)
		)
		(fill yes)
		(layer "F.Cu")
		(net "M_E_CPU1_SA_CS_N<2>")
	)
	(gr_poly
		(pts
			(xy 142.482824 -235.632244) (xy 142.44701 -235.596176) (xy 142.349474 -235.549948) (xy 142.214854 -235.684568)
			(xy 142.261082 -235.782104) (xy 142.29715 -235.817918)
		)
		(stroke
			(width 0)
			(type solid)
		)
		(fill yes)
		(layer "F.Cu")
		(net "M_E_CPU1_SB_DQ<12>")
	)
	(gr_poly
		(pts
			(xy 142.484856 -289.521646) (xy 142.434056 -289.521646) (xy 142.332456 -289.557968) (xy 142.332456 -289.748468)
			(xy 142.434056 -289.784536) (xy 142.484856 -289.784536)
		)
		(stroke
			(width 0)
			(type solid)
		)
		(fill yes)
		(layer "F.Cu")
		(net "M_E_CPU1_SA_DQ<7>")
	)
	(gr_poly
		(pts
			(xy 142.484856 -288.924746) (xy 142.434056 -288.924746) (xy 142.332456 -288.961068) (xy 142.332456 -289.151568)
			(xy 142.434056 -289.187636) (xy 142.484856 -289.187636)
		)
		(stroke
			(width 0)
			(type solid)
		)
		(fill yes)
		(layer "F.Cu")
		(net "M_E_CPU1_SA_DQ<7>")
	)
	(gr_poly
		(pts
			(xy 142.484856 -288.327846) (xy 142.434056 -288.327846) (xy 142.332456 -288.364168) (xy 142.332456 -288.554668)
			(xy 142.434056 -288.590736) (xy 142.484856 -288.590736)
		)
		(stroke
			(width 0)
			(type solid)
		)
		(fill yes)
		(layer "F.Cu")
		(net "M_E_CPU1_SA_DQ<7>")
	)
	(gr_poly
		(pts
			(xy 142.484856 -287.730946) (xy 142.434056 -287.730946) (xy 142.332456 -287.767268) (xy 142.332456 -287.957768)
			(xy 142.434056 -287.993836) (xy 142.484856 -287.993836)
		)
		(stroke
			(width 0)
			(type solid)
		)
		(fill yes)
		(layer "F.Cu")
		(net "M_E_CPU1_SA_DQ<7>")
	)
	(gr_poly
		(pts
			(xy 142.484856 -287.134046) (xy 142.434056 -287.134046) (xy 142.332456 -287.170368) (xy 142.332456 -287.360868)
			(xy 142.434056 -287.396936) (xy 142.484856 -287.396936)
		)
		(stroke
			(width 0)
			(type solid)
		)
		(fill yes)
		(layer "F.Cu")
		(net "M_E_CPU1_SA_DQ<7>")
	)
	(gr_poly
		(pts
			(xy 142.484856 -286.537146) (xy 142.434056 -286.537146) (xy 142.332456 -286.573468) (xy 142.332456 -286.763968)
			(xy 142.434056 -286.800036) (xy 142.484856 -286.800036)
		)
		(stroke
			(width 0)
			(type solid)
		)
		(fill yes)
		(layer "F.Cu")
		(net "M_E_CPU1_SA_DQ<7>")
	)
	(gr_poly
		(pts
			(xy 142.484856 -285.940246) (xy 142.434056 -285.940246) (xy 142.332456 -285.976568) (xy 142.332456 -286.167068)
			(xy 142.434056 -286.203136) (xy 142.484856 -286.203136)
		)
		(stroke
			(width 0)
			(type solid)
		)
		(fill yes)
		(layer "F.Cu")
		(net "M_E_CPU1_SA_DQ<7>")
	)
	(gr_poly
		(pts
			(xy 142.484856 -285.343346) (xy 142.434056 -285.343346) (xy 142.332456 -285.379668) (xy 142.332456 -285.570168)
			(xy 142.434056 -285.606236) (xy 142.484856 -285.606236)
		)
		(stroke
			(width 0)
			(type solid)
		)
		(fill yes)
		(layer "F.Cu")
		(net "M_E_CPU1_SA_DQ<7>")
	)
	(gr_poly
		(pts
			(xy 142.484856 -284.746446) (xy 142.434056 -284.746446) (xy 142.332456 -284.782768) (xy 142.332456 -284.973268)
			(xy 142.434056 -285.009336) (xy 142.484856 -285.009336)
		)
		(stroke
			(width 0)
			(type solid)
		)
		(fill yes)
		(layer "F.Cu")
		(net "M_E_CPU1_SA_DQ<7>")
	)
	(gr_poly
		(pts
			(xy 142.484856 -284.149546) (xy 142.434056 -284.149546) (xy 142.332456 -284.185868) (xy 142.332456 -284.376368)
			(xy 142.434056 -284.412436) (xy 142.484856 -284.412436)
		)
		(stroke
			(width 0)
			(type solid)
		)
		(fill yes)
		(layer "F.Cu")
		(net "M_E_CPU1_SA_DQ<7>")
	)
	(gr_poly
		(pts
			(xy 142.484856 -283.552646) (xy 142.434056 -283.552646) (xy 142.332456 -283.588968) (xy 142.332456 -283.779468)
			(xy 142.434056 -283.815536) (xy 142.484856 -283.815536)
		)
		(stroke
			(width 0)
			(type solid)
		)
		(fill yes)
		(layer "F.Cu")
		(net "M_E_CPU1_SA_DQ<7>")
	)
	(gr_poly
		(pts
			(xy 142.484856 -282.955746) (xy 142.434056 -282.955746) (xy 142.332456 -282.992068) (xy 142.332456 -283.182568)
			(xy 142.434056 -283.218636) (xy 142.484856 -283.218636)
		)
		(stroke
			(width 0)
			(type solid)
		)
		(fill yes)
		(layer "F.Cu")
		(net "M_E_CPU1_SA_DQ<7>")
	)
	(gr_poly
		(pts
			(xy 142.484856 -282.358846) (xy 142.434056 -282.358846) (xy 142.332456 -282.395168) (xy 142.332456 -282.585668)
			(xy 142.434056 -282.621736) (xy 142.484856 -282.621736)
		)
		(stroke
			(width 0)
			(type solid)
		)
		(fill yes)
		(layer "F.Cu")
		(net "M_E_CPU1_SA_DQ<7>")
	)
	(gr_poly
		(pts
			(xy 142.484856 -281.761946) (xy 142.434056 -281.761946) (xy 142.332456 -281.798268) (xy 142.332456 -281.988768)
			(xy 142.434056 -282.024836) (xy 142.484856 -282.024836)
		)
		(stroke
			(width 0)
			(type solid)
		)
		(fill yes)
		(layer "F.Cu")
		(net "M_E_CPU1_SA_DQ<7>")
	)
	(gr_poly
		(pts
			(xy 142.484856 -281.165046) (xy 142.434056 -281.165046) (xy 142.332456 -281.201368) (xy 142.332456 -281.391868)
			(xy 142.434056 -281.427936) (xy 142.484856 -281.427936)
		)
		(stroke
			(width 0)
			(type solid)
		)
		(fill yes)
		(layer "F.Cu")
		(net "M_E_CPU1_SA_DQ<7>")
	)
	(gr_poly
		(pts
			(xy 142.488666 -265.181588) (xy 142.52448 -265.14552) (xy 142.338552 -264.959592) (xy 142.302738 -264.99566)
			(xy 142.25651 -265.092942) (xy 142.39113 -265.227816)
		)
		(stroke
			(width 0)
			(type solid)
		)
		(fill yes)
		(layer "F.Cu")
		(net "M_E_CPU1_SA_CB<0>")
	)
	(gr_poly
		(pts
			(xy 142.490952 -257.570986) (xy 142.52702 -257.535172) (xy 142.341092 -257.349244) (xy 142.305278 -257.385058)
			(xy 142.258796 -257.482594) (xy 142.39367 -257.617214)
		)
		(stroke
			(width 0)
			(type solid)
		)
		(fill yes)
		(layer "F.Cu")
		(net "M_E_CPU1_SA_CS_N<3>")
	)
	(gr_poly
		(pts
			(xy 142.49781 -264.328148) (xy 142.533878 -264.292334) (xy 142.34795 -264.106406) (xy 142.311882 -264.14222)
			(xy 142.265654 -264.239756) (xy 142.400274 -264.374376)
		)
		(stroke
			(width 0)
			(type solid)
		)
		(fill yes)
		(layer "F.Cu")
		(net "M_E_CPU1_SA_CB<1>")
	)
	(gr_poly
		(pts
			(xy 142.499842 -274.890484) (xy 142.54607 -274.793202) (xy 142.41145 -274.658328) (xy 142.313914 -274.70481)
			(xy 142.2781 -274.740624) (xy 142.464028 -274.926552)
		)
		(stroke
			(width 0)
			(type solid)
		)
		(fill yes)
		(layer "F.Cu")
		(net "M_E_CPU1_SA_DQ<19>")
	)
	(gr_poly
		(pts
			(xy 142.50035 -256.7178) (xy 142.536164 -256.681732) (xy 142.350236 -256.495804) (xy 142.314422 -256.531872)
			(xy 142.268194 -256.629154) (xy 142.402814 -256.764028)
		)
		(stroke
			(width 0)
			(type solid)
		)
		(fill yes)
		(layer "F.Cu")
		(net "M_E_CPU1_SA_CA<1>")
	)
	(gr_poly
		(pts
			(xy 142.506446 -229.373684) (xy 142.460218 -229.276148) (xy 142.42415 -229.240334) (xy 142.238222 -229.426262)
			(xy 142.27429 -229.462076) (xy 142.371572 -229.508304)
		)
		(stroke
			(width 0)
			(type solid)
		)
		(fill yes)
		(layer "F.Cu")
		(net "M_E_CPU1_SB_DQ<21>")
	)
	(gr_poly
		(pts
			(xy 142.508732 -277.360634) (xy 142.601188 -277.305262) (xy 142.56385 -277.118318) (xy 142.45717 -277.102824)
			(xy 142.407386 -277.11273) (xy 142.458948 -277.37054)
		)
		(stroke
			(width 0)
			(type solid)
		)
		(fill yes)
		(layer "F.Cu")
		(net "M_E_CPU1_SA_DQ<16>")
	)
	(gr_poly
		(pts
			(xy 142.509494 -255.86436) (xy 142.545308 -255.828292) (xy 142.359634 -255.642618) (xy 142.323566 -255.678432)
			(xy 142.277338 -255.775968) (xy 142.411958 -255.910588)
		)
		(stroke
			(width 0)
			(type solid)
		)
		(fill yes)
		(layer "F.Cu")
		(net "M_E_CPU1_SA_CA<3>")
	)
	(gr_poly
		(pts
			(xy 142.51559 -230.227124) (xy 142.469362 -230.129588) (xy 142.433548 -230.09352) (xy 142.24762 -230.279448)
			(xy 142.283434 -230.315516) (xy 142.38097 -230.361744)
		)
		(stroke
			(width 0)
			(type solid)
		)
		(fill yes)
		(layer "F.Cu")
		(net "M_E_CPU1_SB_DQ<20>")
	)
	(gr_poly
		(pts
			(xy 142.517368 -277.663148) (xy 142.465806 -277.405338) (xy 142.416022 -277.415498) (xy 142.323312 -277.47087)
			(xy 142.36065 -277.65756) (xy 142.467584 -277.673308)
		)
		(stroke
			(width 0)
			(type solid)
		)
		(fill yes)
		(layer "F.Cu")
		(net "M_E_CPU1_SA_DQ<16>")
	)
	(gr_poly
		(pts
			(xy 142.518892 -255.011174) (xy 142.554706 -254.975106) (xy 142.369032 -254.789432) (xy 142.332964 -254.825246)
			(xy 142.286736 -254.922782) (xy 142.421356 -255.057402)
		)
		(stroke
			(width 0)
			(type solid)
		)
		(fill yes)
		(layer "F.Cu")
		(net "M_E_CPU1_SA_CA<5>")
	)
	(gr_poly
		(pts
			(xy 142.52194 -266.836398) (xy 142.558008 -266.800584) (xy 142.37208 -266.614656) (xy 142.336012 -266.65047)
			(xy 142.289784 -266.748006) (xy 142.424658 -266.882626)
		)
		(stroke
			(width 0)
			(type solid)
		)
		(fill yes)
		(layer "F.Cu")
		(net "M_E_CPU1_SA_DQ<30>")
	)
	(gr_poly
		(pts
			(xy 142.528036 -254.15748) (xy 142.56385 -254.121666) (xy 142.377922 -253.935738) (xy 142.342108 -253.971806)
			(xy 142.29588 -254.069088) (xy 142.4305 -254.203962)
		)
		(stroke
			(width 0)
			(type solid)
		)
		(fill yes)
		(layer "F.Cu")
		(net "M_E_CPU1_SA_PAR")
	)
	(gr_poly
		(pts
			(xy 142.531592 -265.982704) (xy 142.567406 -265.94689) (xy 142.381478 -265.760962) (xy 142.345664 -265.796776)
			(xy 142.299436 -265.894312) (xy 142.434056 -266.028932)
		)
		(stroke
			(width 0)
			(type solid)
		)
		(fill yes)
		(layer "F.Cu")
		(net "M_E_CPU1_SA_DQ<31>")
	)
	(gr_poly
		(pts
			(xy 142.542514 -232.78846) (xy 142.496286 -232.690924) (xy 142.460218 -232.65511) (xy 142.27429 -232.841038)
			(xy 142.310358 -232.876852) (xy 142.40764 -232.92308)
		)
		(stroke
			(width 0)
			(type solid)
		)
		(fill yes)
		(layer "F.Cu")
		(net "M_E_CPU1_SB_DQ<17>")
	)
	(gr_poly
		(pts
			(xy 142.544546 -272.484088) (xy 142.580614 -272.448274) (xy 142.394686 -272.262346) (xy 142.358618 -272.29816)
			(xy 142.31239 -272.395696) (xy 142.447264 -272.530316)
		)
		(stroke
			(width 0)
			(type solid)
		)
		(fill yes)
		(layer "F.Cu")
		(net "M_E_CPU1_SA_DQ<22>")
	)
	(gr_poly
		(pts
			(xy 142.545816 -261.78764) (xy 142.581884 -261.751826) (xy 142.395956 -261.565898) (xy 142.359888 -261.601712)
			(xy 142.31366 -261.699248) (xy 142.448534 -261.833868)
		)
		(stroke
			(width 0)
			(type solid)
		)
		(fill yes)
		(layer "F.Cu")
		(net "M_E_CPU1_SA_CB<4>")
	)
	(gr_poly
		(pts
			(xy 142.548864 -258.779264) (xy 142.595092 -258.681982) (xy 142.460472 -258.547362) (xy 142.362936 -258.59359)
			(xy 142.327122 -258.629404) (xy 142.51305 -258.815332)
		)
		(stroke
			(width 0)
			(type solid)
		)
		(fill yes)
		(layer "F.Cu")
		(net "M_E_CPU1_SA_CS_N<0>")
	)
	(gr_poly
		(pts
			(xy 142.55115 -234.485434) (xy 142.504922 -234.387898) (xy 142.469108 -234.352084) (xy 142.28318 -234.538012)
			(xy 142.318994 -234.573826) (xy 142.41653 -234.620054)
		)
		(stroke
			(width 0)
			(type solid)
		)
		(fill yes)
		(layer "F.Cu")
		(net "M_E_CPU1_SB_DQ<15>")
	)
	(gr_poly
		(pts
			(xy 142.551658 -233.641646) (xy 142.50543 -233.544364) (xy 142.469616 -233.508296) (xy 142.283688 -233.694224)
			(xy 142.319502 -233.730292) (xy 142.417038 -233.77652)
		)
		(stroke
			(width 0)
			(type solid)
		)
		(fill yes)
		(layer "F.Cu")
		(net "M_E_CPU1_SB_DQ<16>")
	)
	(gr_poly
		(pts
			(xy 142.553436 -270.786606) (xy 142.589504 -270.750792) (xy 142.403576 -270.564864) (xy 142.367508 -270.600678)
			(xy 142.32128 -270.698214) (xy 142.456154 -270.832834)
		)
		(stroke
			(width 0)
			(type solid)
		)
		(fill yes)
		(layer "F.Cu")
		(net "M_E_CPU1_SA_DQ<24>")
	)
	(gr_poly
		(pts
			(xy 142.553944 -271.630648) (xy 142.589758 -271.59458) (xy 142.40383 -271.408652) (xy 142.368016 -271.44472)
			(xy 142.321788 -271.542002) (xy 142.456408 -271.676876)
		)
		(stroke
			(width 0)
			(type solid)
		)
		(fill yes)
		(layer "F.Cu")
		(net "M_E_CPU1_SA_DQ<23>")
	)
	(gr_poly
		(pts
			(xy 142.555214 -260.9342) (xy 142.591028 -260.898386) (xy 142.4051 -260.712458) (xy 142.369286 -260.748526)
			(xy 142.323058 -260.845808) (xy 142.457678 -260.980682)
		)
		(stroke
			(width 0)
			(type solid)
		)
		(fill yes)
		(layer "F.Cu")
		(net "M_E_CPU1_SA_CB<5>")
	)
	(gr_poly
		(pts
			(xy 142.558262 -257.925824) (xy 142.60449 -257.828542) (xy 142.46987 -257.693668) (xy 142.372334 -257.739896)
			(xy 142.33652 -257.775964) (xy 142.522448 -257.961892)
		)
		(stroke
			(width 0)
			(type solid)
		)
		(fill yes)
		(layer "F.Cu")
		(net "M_E_CPU1_SA_CS_N<1>")
	)
	(gr_poly
		(pts
			(xy 142.560548 -248.967752) (xy 142.52448 -248.866152) (xy 142.33398 -248.866152) (xy 142.297912 -248.967752)
			(xy 142.297912 -249.018552) (xy 142.560548 -249.018552)
		)
		(stroke
			(width 0)
			(type solid)
		)
		(fill yes)
		(layer "F.Cu")
		(net "M_E_CPU1_SB_CA<0>")
	)
	(gr_poly
		(pts
			(xy 142.560548 -248.662952) (xy 142.52448 -248.561352) (xy 142.33398 -248.561352) (xy 142.297912 -248.662952)
			(xy 142.297912 -248.713752) (xy 142.560548 -248.713752)
		)
		(stroke
			(width 0)
			(type solid)
		)
		(fill yes)
		(layer "F.Cu")
		(net "M_E_CPU1_SB_CA<1>")
	)
	(gr_poly
		(pts
			(xy 142.560548 -248.358152) (xy 142.52448 -248.256552) (xy 142.33398 -248.256552) (xy 142.297912 -248.358152)
			(xy 142.297912 -248.408952) (xy 142.560548 -248.408952)
		)
		(stroke
			(width 0)
			(type solid)
		)
		(fill yes)
		(layer "F.Cu")
		(net "M_E_CPU1_SB_CA<2>")
	)
	(gr_poly
		(pts
			(xy 142.560548 -248.053352) (xy 142.52448 -247.951752) (xy 142.33398 -247.951752) (xy 142.297912 -248.053352)
			(xy 142.297912 -248.104152) (xy 142.560548 -248.104152)
		)
		(stroke
			(width 0)
			(type solid)
		)
		(fill yes)
		(layer "F.Cu")
		(net "M_E_CPU1_SB_CA<3>")
	)
	(gr_poly
		(pts
			(xy 142.560548 -247.748552) (xy 142.52448 -247.646952) (xy 142.33398 -247.646952) (xy 142.297912 -247.748552)
			(xy 142.297912 -247.799352) (xy 142.560548 -247.799352)
		)
		(stroke
			(width 0)
			(type solid)
		)
		(fill yes)
		(layer "F.Cu")
		(net "M_E_CPU1_SB_CA<4>")
	)
	(gr_poly
		(pts
			(xy 142.560548 -247.443752) (xy 142.52448 -247.342152) (xy 142.33398 -247.342152) (xy 142.297912 -247.443752)
			(xy 142.297912 -247.494552) (xy 142.560548 -247.494552)
		)
		(stroke
			(width 0)
			(type solid)
		)
		(fill yes)
		(layer "F.Cu")
		(net "M_E_CPU1_SB_CA<5>")
	)
	(gr_poly
		(pts
			(xy 142.560548 -247.138952) (xy 142.52448 -247.037352) (xy 142.33398 -247.037352) (xy 142.297912 -247.138952)
			(xy 142.297912 -247.189752) (xy 142.560548 -247.189752)
		)
		(stroke
			(width 0)
			(type solid)
		)
		(fill yes)
		(layer "F.Cu")
		(net "M_E_CPU1_SB_CA<6>")
	)
	(gr_poly
		(pts
			(xy 142.560548 -246.834152) (xy 142.52448 -246.732552) (xy 142.33398 -246.732552) (xy 142.297912 -246.834152)
			(xy 142.297912 -246.884952) (xy 142.560548 -246.884952)
		)
		(stroke
			(width 0)
			(type solid)
		)
		(fill yes)
		(layer "F.Cu")
		(net "M_E_CPU1_SB_PAR")
	)
	(gr_poly
		(pts
			(xy 142.560548 -246.529352) (xy 142.52448 -246.427752) (xy 142.33398 -246.427752) (xy 142.297912 -246.529352)
			(xy 142.297912 -246.580152) (xy 142.560548 -246.580152)
		)
		(stroke
			(width 0)
			(type solid)
		)
		(fill yes)
		(layer "F.Cu")
		(net "M_E_CPU1_SB_CS_N<0>")
	)
	(gr_poly
		(pts
			(xy 142.560548 -246.224552) (xy 142.52448 -246.122952) (xy 142.33398 -246.122952) (xy 142.297912 -246.224552)
			(xy 142.297912 -246.275352) (xy 142.560548 -246.275352)
		)
		(stroke
			(width 0)
			(type solid)
		)
		(fill yes)
		(layer "F.Cu")
		(net "M_E_CPU1_SB_CS_N<2>")
	)
	(gr_poly
		(pts
			(xy 142.560548 -245.919752) (xy 142.52448 -245.818152) (xy 142.33398 -245.818152) (xy 142.297912 -245.919752)
			(xy 142.297912 -245.970552) (xy 142.560548 -245.970552)
		)
		(stroke
			(width 0)
			(type solid)
		)
		(fill yes)
		(layer "F.Cu")
		(net "M_E_CPU1_SB_CS_N<1>")
	)
	(gr_poly
		(pts
			(xy 142.560548 -245.614952) (xy 142.52448 -245.513352) (xy 142.33398 -245.513352) (xy 142.297912 -245.614952)
			(xy 142.297912 -245.665752) (xy 142.560548 -245.665752)
		)
		(stroke
			(width 0)
			(type solid)
		)
		(fill yes)
		(layer "F.Cu")
		(net "M_E_CPU1_SB_CS_N<3>")
	)
	(gr_poly
		(pts
			(xy 142.560548 -235.338874) (xy 142.51432 -235.241338) (xy 142.478252 -235.205524) (xy 142.292324 -235.391452)
			(xy 142.328392 -235.427266) (xy 142.425674 -235.473494)
		)
		(stroke
			(width 0)
			(type solid)
		)
		(fill yes)
		(layer "F.Cu")
		(net "M_E_CPU1_SB_DQ<14>")
	)
	(gr_poly
		(pts
			(xy 142.56258 -269.933166) (xy 142.598648 -269.897352) (xy 142.41272 -269.711424) (xy 142.376652 -269.747238)
			(xy 142.330424 -269.844774) (xy 142.465298 -269.979394)
		)
		(stroke
			(width 0)
			(type solid)
		)
		(fill yes)
		(layer "F.Cu")
		(net "M_E_CPU1_SA_DQ<25>")
	)
	(gr_poly
		(pts
			(xy 142.56512 -264.682986) (xy 142.611348 -264.58545) (xy 142.476728 -264.45083) (xy 142.379192 -264.497058)
			(xy 142.343378 -264.533126) (xy 142.529052 -264.7188)
		)
		(stroke
			(width 0)
			(type solid)
		)
		(fill yes)
		(layer "F.Cu")
		(net "M_E_CPU1_SA_CB<2>")
	)
	(gr_poly
		(pts
			(xy 142.567406 -257.072638) (xy 142.613634 -256.975102) (xy 142.479014 -256.840482) (xy 142.381732 -256.88671)
			(xy 142.345664 -256.922524) (xy 142.531592 -257.108452)
		)
		(stroke
			(width 0)
			(type solid)
		)
		(fill yes)
		(layer "F.Cu")
		(net "M_E_CPU1_SA_CA<0>")
	)
	(gr_poly
		(pts
			(xy 142.574264 -263.829546) (xy 142.620492 -263.732264) (xy 142.485872 -263.59739) (xy 142.388336 -263.643618)
			(xy 142.352522 -263.679686) (xy 142.53845 -263.865614)
		)
		(stroke
			(width 0)
			(type solid)
		)
		(fill yes)
		(layer "F.Cu")
		(net "M_E_CPU1_SA_CB<3>")
	)
	(gr_poly
		(pts
			(xy 142.576804 -256.219198) (xy 142.623032 -256.121662) (xy 142.488158 -255.987042) (xy 142.390876 -256.03327)
			(xy 142.354808 -256.069084) (xy 142.540736 -256.255012)
		)
		(stroke
			(width 0)
			(type solid)
		)
		(fill yes)
		(layer "F.Cu")
		(net "M_E_CPU1_SA_CA<2>")
	)
	(gr_poly
		(pts
			(xy 142.582646 -276.432772) (xy 142.531084 -276.174962) (xy 142.4813 -276.184868) (xy 142.388844 -276.240494)
			(xy 142.426182 -276.427184) (xy 142.532862 -276.442678)
		)
		(stroke
			(width 0)
			(type solid)
		)
		(fill yes)
		(layer "F.Cu")
		(net "M_E_CPU1_SA_DQ<18>")
	)
	(gr_poly
		(pts
			(xy 142.585948 -255.366012) (xy 142.632176 -255.268476) (xy 142.497556 -255.133856) (xy 142.400274 -255.180084)
			(xy 142.364206 -255.215898) (xy 142.550134 -255.401826)
		)
		(stroke
			(width 0)
			(type solid)
		)
		(fill yes)
		(layer "F.Cu")
		(net "M_E_CPU1_SA_CA<4>")
	)
	(gr_poly
		(pts
			(xy 142.58925 -267.191236) (xy 142.635478 -267.0937) (xy 142.500858 -266.95908) (xy 142.403322 -267.005308)
			(xy 142.367508 -267.041376) (xy 142.553182 -267.22705)
		)
		(stroke
			(width 0)
			(type solid)
		)
		(fill yes)
		(layer "F.Cu")
		(net "M_E_CPU1_SA_DQ<28>")
	)
	(gr_poly
		(pts
			(xy 142.595092 -254.512318) (xy 142.64132 -254.415036) (xy 142.5067 -254.280416) (xy 142.409164 -254.326644)
			(xy 142.37335 -254.362458) (xy 142.559278 -254.548386)
		)
		(stroke
			(width 0)
			(type solid)
		)
		(fill yes)
		(layer "F.Cu")
		(net "M_E_CPU1_SA_CA<6>")
	)
	(gr_poly
		(pts
			(xy 142.598648 -266.337796) (xy 142.644876 -266.24026) (xy 142.510002 -266.10564) (xy 142.41272 -266.151868)
			(xy 142.376652 -266.187682) (xy 142.56258 -266.37361)
		)
		(stroke
			(width 0)
			(type solid)
		)
		(fill yes)
		(layer "F.Cu")
		(net "M_E_CPU1_SA_DQ<29>")
	)
	(gr_poly
		(pts
			(xy 142.602712 -224.937574) (xy 142.602712 -224.747074) (xy 142.501112 -224.711006) (xy 142.450312 -224.711006)
			(xy 142.450312 -224.973896) (xy 142.501112 -224.973896)
		)
		(stroke
			(width 0)
			(type solid)
		)
		(fill yes)
		(layer "F.Cu")
		(net "M_E_CPU1_SB_DQ<25>")
	)
	(gr_poly
		(pts
			(xy 142.602712 -224.340674) (xy 142.602712 -224.150174) (xy 142.501112 -224.114106) (xy 142.450312 -224.114106)
			(xy 142.450312 -224.376996) (xy 142.501112 -224.376996)
		)
		(stroke
			(width 0)
			(type solid)
		)
		(fill yes)
		(layer "F.Cu")
		(net "M_E_CPU1_SB_DQ<25>")
	)
	(gr_poly
		(pts
			(xy 142.602712 -223.743774) (xy 142.602712 -223.553274) (xy 142.501112 -223.517206) (xy 142.450312 -223.517206)
			(xy 142.450312 -223.780096) (xy 142.501112 -223.780096)
		)
		(stroke
			(width 0)
			(type solid)
		)
		(fill yes)
		(layer "F.Cu")
		(net "M_E_CPU1_SB_DQ<25>")
	)
	(gr_poly
		(pts
			(xy 142.602712 -223.146874) (xy 142.602712 -222.956374) (xy 142.501112 -222.920306) (xy 142.450312 -222.920306)
			(xy 142.450312 -223.183196) (xy 142.501112 -223.183196)
		)
		(stroke
			(width 0)
			(type solid)
		)
		(fill yes)
		(layer "F.Cu")
		(net "M_E_CPU1_SB_DQ<25>")
	)
	(gr_poly
		(pts
			(xy 142.602712 -222.549974) (xy 142.602712 -222.359474) (xy 142.501112 -222.323406) (xy 142.450312 -222.323406)
			(xy 142.450312 -222.586296) (xy 142.501112 -222.586296)
		)
		(stroke
			(width 0)
			(type solid)
		)
		(fill yes)
		(layer "F.Cu")
		(net "M_E_CPU1_SB_DQ<25>")
	)
	(gr_poly
		(pts
			(xy 142.602712 -221.953074) (xy 142.602712 -221.762574) (xy 142.501112 -221.726506) (xy 142.450312 -221.726506)
			(xy 142.450312 -221.989396) (xy 142.501112 -221.989396)
		)
		(stroke
			(width 0)
			(type solid)
		)
		(fill yes)
		(layer "F.Cu")
		(net "M_E_CPU1_SB_DQ<25>")
	)
	(gr_poly
		(pts
			(xy 142.602712 -221.356174) (xy 142.602712 -221.165674) (xy 142.501112 -221.129606) (xy 142.450312 -221.129606)
			(xy 142.450312 -221.392496) (xy 142.501112 -221.392496)
		)
		(stroke
			(width 0)
			(type solid)
		)
		(fill yes)
		(layer "F.Cu")
		(net "M_E_CPU1_SB_DQ<25>")
	)
	(gr_poly
		(pts
			(xy 142.602712 -220.759274) (xy 142.602712 -220.568774) (xy 142.501112 -220.532706) (xy 142.450312 -220.532706)
			(xy 142.450312 -220.795596) (xy 142.501112 -220.795596)
		)
		(stroke
			(width 0)
			(type solid)
		)
		(fill yes)
		(layer "F.Cu")
		(net "M_E_CPU1_SB_DQ<25>")
	)
	(gr_poly
		(pts
			(xy 142.602712 -220.162374) (xy 142.602712 -219.971874) (xy 142.501112 -219.935806) (xy 142.450312 -219.935806)
			(xy 142.450312 -220.198696) (xy 142.501112 -220.198696)
		)
		(stroke
			(width 0)
			(type solid)
		)
		(fill yes)
		(layer "F.Cu")
		(net "M_E_CPU1_SB_DQ<25>")
	)
	(gr_poly
		(pts
			(xy 142.602712 -219.565474) (xy 142.602712 -219.374974) (xy 142.501112 -219.338906) (xy 142.450312 -219.338906)
			(xy 142.450312 -219.601796) (xy 142.501112 -219.601796)
		)
		(stroke
			(width 0)
			(type solid)
		)
		(fill yes)
		(layer "F.Cu")
		(net "M_E_CPU1_SB_DQ<25>")
	)
	(gr_poly
		(pts
			(xy 142.602712 -218.968574) (xy 142.602712 -218.778074) (xy 142.501112 -218.742006) (xy 142.450312 -218.742006)
			(xy 142.450312 -219.004896) (xy 142.501112 -219.004896)
		)
		(stroke
			(width 0)
			(type solid)
		)
		(fill yes)
		(layer "F.Cu")
		(net "M_E_CPU1_SB_DQ<25>")
	)
	(gr_poly
		(pts
			(xy 142.602712 -218.371674) (xy 142.602712 -218.181174) (xy 142.501112 -218.145106) (xy 142.450312 -218.145106)
			(xy 142.450312 -218.407996) (xy 142.501112 -218.407996)
		)
		(stroke
			(width 0)
			(type solid)
		)
		(fill yes)
		(layer "F.Cu")
		(net "M_E_CPU1_SB_DQ<25>")
	)
	(gr_poly
		(pts
			(xy 142.602712 -217.774774) (xy 142.602712 -217.584274) (xy 142.501112 -217.548206) (xy 142.450312 -217.548206)
			(xy 142.450312 -217.811096) (xy 142.501112 -217.811096)
		)
		(stroke
			(width 0)
			(type solid)
		)
		(fill yes)
		(layer "F.Cu")
		(net "M_E_CPU1_SB_DQ<25>")
	)
	(gr_poly
		(pts
			(xy 142.602712 -217.177874) (xy 142.602712 -216.987374) (xy 142.501112 -216.951306) (xy 142.450312 -216.951306)
			(xy 142.450312 -217.214196) (xy 142.501112 -217.214196)
		)
		(stroke
			(width 0)
			(type solid)
		)
		(fill yes)
		(layer "F.Cu")
		(net "M_E_CPU1_SB_DQ<25>")
	)
	(gr_poly
		(pts
			(xy 142.602712 -216.580974) (xy 142.602712 -216.390474) (xy 142.501112 -216.354406) (xy 142.450312 -216.354406)
			(xy 142.450312 -216.617296) (xy 142.501112 -216.617296)
		)
		(stroke
			(width 0)
			(type solid)
		)
		(fill yes)
		(layer "F.Cu")
		(net "M_E_CPU1_SB_DQ<25>")
	)
	(gr_poly
		(pts
			(xy 142.602712 -215.984074) (xy 142.602712 -215.793574) (xy 142.501112 -215.757506) (xy 142.450312 -215.757506)
			(xy 142.450312 -216.020396) (xy 142.501112 -216.020396)
		)
		(stroke
			(width 0)
			(type solid)
		)
		(fill yes)
		(layer "F.Cu")
		(net "M_E_CPU1_SB_DQ<25>")
	)
	(gr_poly
		(pts
			(xy 142.611602 -272.83918) (xy 142.65783 -272.741898) (xy 142.52321 -272.607024) (xy 142.425674 -272.653506)
			(xy 142.389606 -272.68932) (xy 142.575534 -272.875248)
		)
		(stroke
			(width 0)
			(type solid)
		)
		(fill yes)
		(layer "F.Cu")
		(net "M_E_CPU1_SA_DQ<20>")
	)
	(gr_poly
		(pts
			(xy 142.621 -271.985486) (xy 142.667228 -271.888204) (xy 142.532608 -271.75333) (xy 142.435072 -271.799558)
			(xy 142.399258 -271.835626) (xy 142.585186 -272.021554)
		)
		(stroke
			(width 0)
			(type solid)
		)
		(fill yes)
		(layer "F.Cu")
		(net "M_E_CPU1_SA_DQ<21>")
	)
	(gr_poly
		(pts
			(xy 142.62227 -261.289038) (xy 142.668498 -261.191756) (xy 142.533878 -261.057136) (xy 142.436342 -261.103364)
			(xy 142.400528 -261.139178) (xy 142.586456 -261.325106)
		)
		(stroke
			(width 0)
			(type solid)
		)
		(fill yes)
		(layer "F.Cu")
		(net "M_E_CPU1_SA_CB<6>")
	)
	(gr_poly
		(pts
			(xy 142.625572 -277.94585) (xy 142.718028 -277.890478) (xy 142.68069 -277.703788) (xy 142.57401 -277.68804)
			(xy 142.524226 -277.6982) (xy 142.575788 -277.95601)
		)
		(stroke
			(width 0)
			(type solid)
		)
		(fill yes)
		(layer "F.Cu")
		(net "M_E_CPU1_SA_DQ<16>")
	)
	(gr_poly
		(pts
			(xy 142.62989 -270.288004) (xy 142.676118 -270.190722) (xy 142.541498 -270.055848) (xy 142.443962 -270.102076)
			(xy 142.408148 -270.138144) (xy 142.594076 -270.324072)
		)
		(stroke
			(width 0)
			(type solid)
		)
		(fill yes)
		(layer "F.Cu")
		(net "M_E_CPU1_SA_DQ<26>")
	)
	(gr_poly
		(pts
			(xy 142.631668 -260.435852) (xy 142.677896 -260.338316) (xy 142.543022 -260.203696) (xy 142.44574 -260.249924)
			(xy 142.409672 -260.285738) (xy 142.5956 -260.471666)
		)
		(stroke
			(width 0)
			(type solid)
		)
		(fill yes)
		(layer "F.Cu")
		(net "M_E_CPU1_SA_CB<7>")
	)
	(gr_poly
		(pts
			(xy 142.634208 -278.248618) (xy 142.582646 -277.990808) (xy 142.532862 -278.000714) (xy 142.440406 -278.056086)
			(xy 142.477744 -278.24303) (xy 142.584424 -278.258524)
		)
		(stroke
			(width 0)
			(type solid)
		)
		(fill yes)
		(layer "F.Cu")
		(net "M_E_CPU1_SA_DQ<16>")
	)
	(gr_poly
		(pts
			(xy 142.635224 -229.02926) (xy 142.59941 -228.993446) (xy 142.501874 -228.946964) (xy 142.367254 -229.081838)
			(xy 142.413482 -229.17912) (xy 142.449296 -229.215188)
		)
		(stroke
			(width 0)
			(type solid)
		)
		(fill yes)
		(layer "F.Cu")
		(net "M_E_CPU1_SB_DQ<21>")
	)
	(gr_poly
		(pts
			(xy 142.637256 -290.046918) (xy 142.637256 -289.856418) (xy 142.535656 -289.820096) (xy 142.484856 -289.820096)
			(xy 142.484856 -290.082986) (xy 142.535656 -290.082986)
		)
		(stroke
			(width 0)
			(type solid)
		)
		(fill yes)
		(layer "F.Cu")
		(net "M_E_CPU1_SA_DQ<7>")
	)
	(gr_poly
		(pts
			(xy 142.637256 -289.450018) (xy 142.637256 -289.259518) (xy 142.535656 -289.223196) (xy 142.484856 -289.223196)
			(xy 142.484856 -289.486086) (xy 142.535656 -289.486086)
		)
		(stroke
			(width 0)
			(type solid)
		)
		(fill yes)
		(layer "F.Cu")
		(net "M_E_CPU1_SA_DQ<7>")
	)
	(gr_poly
		(pts
			(xy 142.637256 -288.853118) (xy 142.637256 -288.662618) (xy 142.535656 -288.626296) (xy 142.484856 -288.626296)
			(xy 142.484856 -288.889186) (xy 142.535656 -288.889186)
		)
		(stroke
			(width 0)
			(type solid)
		)
		(fill yes)
		(layer "F.Cu")
		(net "M_E_CPU1_SA_DQ<7>")
	)
	(gr_poly
		(pts
			(xy 142.637256 -288.256218) (xy 142.637256 -288.065718) (xy 142.535656 -288.029396) (xy 142.484856 -288.029396)
			(xy 142.484856 -288.292286) (xy 142.535656 -288.292286)
		)
		(stroke
			(width 0)
			(type solid)
		)
		(fill yes)
		(layer "F.Cu")
		(net "M_E_CPU1_SA_DQ<7>")
	)
	(gr_poly
		(pts
			(xy 142.637256 -287.659318) (xy 142.637256 -287.468818) (xy 142.535656 -287.432496) (xy 142.484856 -287.432496)
			(xy 142.484856 -287.695386) (xy 142.535656 -287.695386)
		)
		(stroke
			(width 0)
			(type solid)
		)
		(fill yes)
		(layer "F.Cu")
		(net "M_E_CPU1_SA_DQ<7>")
	)
	(gr_poly
		(pts
			(xy 142.637256 -287.062418) (xy 142.637256 -286.871918) (xy 142.535656 -286.835596) (xy 142.484856 -286.835596)
			(xy 142.484856 -287.098486) (xy 142.535656 -287.098486)
		)
		(stroke
			(width 0)
			(type solid)
		)
		(fill yes)
		(layer "F.Cu")
		(net "M_E_CPU1_SA_DQ<7>")
	)
	(gr_poly
		(pts
			(xy 142.637256 -286.465518) (xy 142.637256 -286.275018) (xy 142.535656 -286.238696) (xy 142.484856 -286.238696)
			(xy 142.484856 -286.501586) (xy 142.535656 -286.501586)
		)
		(stroke
			(width 0)
			(type solid)
		)
		(fill yes)
		(layer "F.Cu")
		(net "M_E_CPU1_SA_DQ<7>")
	)
	(gr_poly
		(pts
			(xy 142.637256 -285.868618) (xy 142.637256 -285.678118) (xy 142.535656 -285.641796) (xy 142.484856 -285.641796)
			(xy 142.484856 -285.904686) (xy 142.535656 -285.904686)
		)
		(stroke
			(width 0)
			(type solid)
		)
		(fill yes)
		(layer "F.Cu")
		(net "M_E_CPU1_SA_DQ<7>")
	)
	(gr_poly
		(pts
			(xy 142.637256 -285.271718) (xy 142.637256 -285.081218) (xy 142.535656 -285.044896) (xy 142.484856 -285.044896)
			(xy 142.484856 -285.307786) (xy 142.535656 -285.307786)
		)
		(stroke
			(width 0)
			(type solid)
		)
		(fill yes)
		(layer "F.Cu")
		(net "M_E_CPU1_SA_DQ<7>")
	)
	(gr_poly
		(pts
			(xy 142.637256 -284.674818) (xy 142.637256 -284.484318) (xy 142.535656 -284.447996) (xy 142.484856 -284.447996)
			(xy 142.484856 -284.710886) (xy 142.535656 -284.710886)
		)
		(stroke
			(width 0)
			(type solid)
		)
		(fill yes)
		(layer "F.Cu")
		(net "M_E_CPU1_SA_DQ<7>")
	)
	(gr_poly
		(pts
			(xy 142.637256 -284.077918) (xy 142.637256 -283.887418) (xy 142.535656 -283.851096) (xy 142.484856 -283.851096)
			(xy 142.484856 -284.113986) (xy 142.535656 -284.113986)
		)
		(stroke
			(width 0)
			(type solid)
		)
		(fill yes)
		(layer "F.Cu")
		(net "M_E_CPU1_SA_DQ<7>")
	)
	(gr_poly
		(pts
			(xy 142.637256 -283.481018) (xy 142.637256 -283.290518) (xy 142.535656 -283.254196) (xy 142.484856 -283.254196)
			(xy 142.484856 -283.517086) (xy 142.535656 -283.517086)
		)
		(stroke
			(width 0)
			(type solid)
		)
		(fill yes)
		(layer "F.Cu")
		(net "M_E_CPU1_SA_DQ<7>")
	)
	(gr_poly
		(pts
			(xy 142.637256 -282.884118) (xy 142.637256 -282.693618) (xy 142.535656 -282.657296) (xy 142.484856 -282.657296)
			(xy 142.484856 -282.920186) (xy 142.535656 -282.920186)
		)
		(stroke
			(width 0)
			(type solid)
		)
		(fill yes)
		(layer "F.Cu")
		(net "M_E_CPU1_SA_DQ<7>")
	)
	(gr_poly
		(pts
			(xy 142.637256 -282.287218) (xy 142.637256 -282.096718) (xy 142.535656 -282.060396) (xy 142.484856 -282.060396)
			(xy 142.484856 -282.323286) (xy 142.535656 -282.323286)
		)
		(stroke
			(width 0)
			(type solid)
		)
		(fill yes)
		(layer "F.Cu")
		(net "M_E_CPU1_SA_DQ<7>")
	)
	(gr_poly
		(pts
			(xy 142.637256 -281.690318) (xy 142.637256 -281.499818) (xy 142.535656 -281.463496) (xy 142.484856 -281.463496)
			(xy 142.484856 -281.726386) (xy 142.535656 -281.726386)
		)
		(stroke
			(width 0)
			(type solid)
		)
		(fill yes)
		(layer "F.Cu")
		(net "M_E_CPU1_SA_DQ<7>")
	)
	(gr_poly
		(pts
			(xy 142.637256 -281.093418) (xy 142.637256 -280.902918) (xy 142.535656 -280.866596) (xy 142.484856 -280.866596)
			(xy 142.484856 -281.129486) (xy 142.535656 -281.129486)
		)
		(stroke
			(width 0)
			(type solid)
		)
		(fill yes)
		(layer "F.Cu")
		(net "M_E_CPU1_SA_DQ<7>")
	)
	(gr_poly
		(pts
			(xy 142.639034 -275.17344) (xy 142.675102 -275.137626) (xy 142.489174 -274.951698) (xy 142.453106 -274.987512)
			(xy 142.406878 -275.085048) (xy 142.541752 -275.219668)
		)
		(stroke
			(width 0)
			(type solid)
		)
		(fill yes)
		(layer "F.Cu")
		(net "M_E_CPU1_SA_DQ<19>")
	)
	(gr_poly
		(pts
			(xy 142.639034 -269.434564) (xy 142.685262 -269.337282) (xy 142.550642 -269.202408) (xy 142.453106 -269.248636)
			(xy 142.417292 -269.284704) (xy 142.60322 -269.470632)
		)
		(stroke
			(width 0)
			(type solid)
		)
		(fill yes)
		(layer "F.Cu")
		(net "M_E_CPU1_SA_DQ<27>")
	)
	(gr_poly
		(pts
			(xy 142.644368 -229.8827) (xy 142.608554 -229.846632) (xy 142.511018 -229.800404) (xy 142.376398 -229.935024)
			(xy 142.422626 -230.03256) (xy 142.458694 -230.068374)
		)
		(stroke
			(width 0)
			(type solid)
		)
		(fill yes)
		(layer "F.Cu")
		(net "M_E_CPU1_SB_DQ<20>")
	)
	(gr_poly
		(pts
			(xy 142.659862 -240.15954) (xy 142.62354 -240.05794) (xy 142.43304 -240.05794) (xy 142.396972 -240.15954)
			(xy 142.396972 -240.21034) (xy 142.659862 -240.21034)
		)
		(stroke
			(width 0)
			(type solid)
		)
		(fill yes)
		(layer "F.Cu")
		(net "M_E_CPU1_SB_CB<0>")
	)
	(gr_poly
		(pts
			(xy 142.659862 -239.85474) (xy 142.62354 -239.75314) (xy 142.43304 -239.75314) (xy 142.396972 -239.85474)
			(xy 142.396972 -239.90554) (xy 142.659862 -239.90554)
		)
		(stroke
			(width 0)
			(type solid)
		)
		(fill yes)
		(layer "F.Cu")
		(net "M_E_CPU1_SB_CB<2>")
	)
	(gr_poly
		(pts
			(xy 142.659862 -239.54994) (xy 142.62354 -239.44834) (xy 142.43304 -239.44834) (xy 142.396972 -239.54994)
			(xy 142.396972 -239.60074) (xy 142.659862 -239.60074)
		)
		(stroke
			(width 0)
			(type solid)
		)
		(fill yes)
		(layer "F.Cu")
		(net "M_E_CPU1_SB_CB<1>")
	)
	(gr_poly
		(pts
			(xy 142.659862 -239.24514) (xy 142.62354 -239.14354) (xy 142.43304 -239.14354) (xy 142.396972 -239.24514)
			(xy 142.396972 -239.29594) (xy 142.659862 -239.29594)
		)
		(stroke
			(width 0)
			(type solid)
		)
		(fill yes)
		(layer "F.Cu")
		(net "M_E_CPU1_SB_CB<3>")
	)
	(gr_poly
		(pts
			(xy 142.671292 -232.444036) (xy 142.635478 -232.407968) (xy 142.537942 -232.36174) (xy 142.403322 -232.496614)
			(xy 142.44955 -232.593896) (xy 142.485364 -232.629964)
		)
		(stroke
			(width 0)
			(type solid)
		)
		(fill yes)
		(layer "F.Cu")
		(net "M_E_CPU1_SB_DQ<17>")
	)
	(gr_poly
		(pts
			(xy 142.680182 -234.14101) (xy 142.644114 -234.105196) (xy 142.546832 -234.058968) (xy 142.411958 -234.193588)
			(xy 142.458186 -234.291124) (xy 142.494254 -234.326938)
		)
		(stroke
			(width 0)
			(type solid)
		)
		(fill yes)
		(layer "F.Cu")
		(net "M_E_CPU1_SB_DQ<15>")
	)
	(gr_poly
		(pts
			(xy 142.680436 -233.297476) (xy 142.644622 -233.261408) (xy 142.547086 -233.21518) (xy 142.412466 -233.3498)
			(xy 142.458694 -233.447336) (xy 142.494762 -233.48315)
		)
		(stroke
			(width 0)
			(type solid)
		)
		(fill yes)
		(layer "F.Cu")
		(net "M_E_CPU1_SB_DQ<16>")
	)
	(gr_poly
		(pts
			(xy 142.688056 -259.06222) (xy 142.724124 -259.026406) (xy 142.538196 -258.840478) (xy 142.502128 -258.876292)
			(xy 142.4559 -258.973828) (xy 142.590774 -259.108448)
		)
		(stroke
			(width 0)
			(type solid)
		)
		(fill yes)
		(layer "F.Cu")
		(net "M_E_CPU1_SA_CS_N<0>")
	)
	(gr_poly
		(pts
			(xy 142.688564 -242.395756) (xy 142.688564 -242.344956) (xy 142.425674 -242.344956) (xy 142.425674 -242.395756)
			(xy 142.461996 -242.497356) (xy 142.652496 -242.497356)
		)
		(stroke
			(width 0)
			(type solid)
		)
		(fill yes)
		(layer "F.Cu")
		(net "M_E_CPU1_SB_CB<6>")
	)
	(gr_poly
		(pts
			(xy 142.688564 -242.090956) (xy 142.688564 -242.040156) (xy 142.425674 -242.040156) (xy 142.425674 -242.090956)
			(xy 142.461996 -242.192556) (xy 142.652496 -242.192556)
		)
		(stroke
			(width 0)
			(type solid)
		)
		(fill yes)
		(layer "F.Cu")
		(net "M_E_CPU1_SB_CB<5>")
	)
	(gr_poly
		(pts
			(xy 142.688564 -241.786156) (xy 142.688564 -241.735356) (xy 142.425674 -241.735356) (xy 142.425674 -241.786156)
			(xy 142.461996 -241.887756) (xy 142.652496 -241.887756)
		)
		(stroke
			(width 0)
			(type solid)
		)
		(fill yes)
		(layer "F.Cu")
		(net "M_E_CPU1_SB_CB<7>")
	)
	(gr_poly
		(pts
			(xy 142.689326 -234.99445) (xy 142.653512 -234.958636) (xy 142.555976 -234.912154) (xy 142.421356 -235.047028)
			(xy 142.467584 -235.14431) (xy 142.503398 -235.180378)
		)
		(stroke
			(width 0)
			(type solid)
		)
		(fill yes)
		(layer "F.Cu")
		(net "M_E_CPU1_SB_DQ<14>")
	)
	(gr_poly
		(pts
			(xy 142.691104 -276.715474) (xy 142.78356 -276.660102) (xy 142.746222 -276.473412) (xy 142.639542 -276.457664)
			(xy 142.589758 -276.46757) (xy 142.64132 -276.72538)
		)
		(stroke
			(width 0)
			(type solid)
		)
		(fill yes)
		(layer "F.Cu")
		(net "M_E_CPU1_SA_DQ<18>")
	)
	(gr_poly
		(pts
			(xy 142.697454 -258.20878) (xy 142.733522 -258.172966) (xy 142.547594 -257.987038) (xy 142.511526 -258.022852)
			(xy 142.465298 -258.120388) (xy 142.600172 -258.255008)
		)
		(stroke
			(width 0)
			(type solid)
		)
		(fill yes)
		(layer "F.Cu")
		(net "M_E_CPU1_SA_CS_N<1>")
	)
	(gr_poly
		(pts
			(xy 142.69974 -277.017988) (xy 142.648178 -276.760432) (xy 142.598394 -276.770338) (xy 142.505938 -276.82571)
			(xy 142.543276 -277.0124) (xy 142.649956 -277.028148)
		)
		(stroke
			(width 0)
			(type solid)
		)
		(fill yes)
		(layer "F.Cu")
		(net "M_E_CPU1_SA_DQ<18>")
	)
	(gr_poly
		(pts
			(xy 142.704312 -264.965942) (xy 142.740126 -264.929874) (xy 142.554198 -264.743946) (xy 142.518384 -264.780014)
			(xy 142.472156 -264.877296) (xy 142.606776 -265.01217)
		)
		(stroke
			(width 0)
			(type solid)
		)
		(fill yes)
		(layer "F.Cu")
		(net "M_E_CPU1_SA_CB<2>")
	)
	(gr_poly
		(pts
			(xy 142.706598 -257.35534) (xy 142.742666 -257.319526) (xy 142.556738 -257.133598) (xy 142.520924 -257.169412)
			(xy 142.474442 -257.266948) (xy 142.609316 -257.401568)
		)
		(stroke
			(width 0)
			(type solid)
		)
		(fill yes)
		(layer "F.Cu")
		(net "M_E_CPU1_SA_CA<0>")
	)
	(gr_poly
		(pts
			(xy 142.712694 -228.73589) (xy 142.666466 -228.638354) (xy 142.630652 -228.60254) (xy 142.444724 -228.788468)
			(xy 142.480538 -228.824282) (xy 142.578074 -228.87051)
		)
		(stroke
			(width 0)
			(type solid)
		)
		(fill yes)
		(layer "F.Cu")
		(net "M_E_CPU1_SB_DQ<23>")
	)
	(gr_poly
		(pts
			(xy 142.713456 -264.112502) (xy 142.749524 -264.076688) (xy 142.563596 -263.89076) (xy 142.527528 -263.926574)
			(xy 142.4813 -264.02411) (xy 142.61592 -264.15873)
		)
		(stroke
			(width 0)
			(type solid)
		)
		(fill yes)
		(layer "F.Cu")
		(net "M_E_CPU1_SA_CB<3>")
	)
	(gr_poly
		(pts
			(xy 142.715996 -256.502154) (xy 142.75181 -256.466086) (xy 142.565882 -256.280158) (xy 142.530068 -256.316226)
			(xy 142.48384 -256.413508) (xy 142.61846 -256.548382)
		)
		(stroke
			(width 0)
			(type solid)
		)
		(fill yes)
		(layer "F.Cu")
		(net "M_E_CPU1_SA_CA<2>")
	)
	(gr_poly
		(pts
			(xy 142.722092 -229.58933) (xy 142.675864 -229.491794) (xy 142.639796 -229.45598) (xy 142.453868 -229.641908)
			(xy 142.489936 -229.677722) (xy 142.587218 -229.72395)
		)
		(stroke
			(width 0)
			(type solid)
		)
		(fill yes)
		(layer "F.Cu")
		(net "M_E_CPU1_SB_DQ<22>")
	)
	(gr_poly
		(pts
			(xy 142.72514 -255.648714) (xy 142.760954 -255.612646) (xy 142.57528 -255.426972) (xy 142.539212 -255.462786)
			(xy 142.492984 -255.560322) (xy 142.627604 -255.694942)
		)
		(stroke
			(width 0)
			(type solid)
		)
		(fill yes)
		(layer "F.Cu")
		(net "M_E_CPU1_SA_CA<4>")
	)
	(gr_poly
		(pts
			(xy 142.728442 -267.474192) (xy 142.764256 -267.438124) (xy 142.578328 -267.252196) (xy 142.542514 -267.288264)
			(xy 142.496286 -267.385546) (xy 142.630906 -267.52042)
		)
		(stroke
			(width 0)
			(type solid)
		)
		(fill yes)
		(layer "F.Cu")
		(net "M_E_CPU1_SA_DQ<28>")
	)
	(gr_poly
		(pts
			(xy 142.734284 -254.795274) (xy 142.770352 -254.75946) (xy 142.584424 -254.573532) (xy 142.548356 -254.609346)
			(xy 142.502128 -254.706882) (xy 142.637002 -254.841502)
		)
		(stroke
			(width 0)
			(type solid)
		)
		(fill yes)
		(layer "F.Cu")
		(net "M_E_CPU1_SA_CA<6>")
	)
	(gr_poly
		(pts
			(xy 142.73784 -266.620752) (xy 142.773654 -266.584684) (xy 142.587726 -266.398756) (xy 142.551912 -266.434824)
			(xy 142.505684 -266.532106) (xy 142.640304 -266.66698)
		)
		(stroke
			(width 0)
			(type solid)
		)
		(fill yes)
		(layer "F.Cu")
		(net "M_E_CPU1_SA_DQ<29>")
	)
	(gr_poly
		(pts
			(xy 142.742412 -278.53132) (xy 142.834868 -278.475948) (xy 142.79753 -278.289004) (xy 142.69085 -278.27351)
			(xy 142.641066 -278.283416) (xy 142.692628 -278.541226)
		)
		(stroke
			(width 0)
			(type solid)
		)
		(fill yes)
		(layer "F.Cu")
		(net "M_E_CPU1_SA_DQ<16>")
	)
	(gr_poly
		(pts
			(xy 142.749016 -232.150666) (xy 142.702534 -232.05313) (xy 142.66672 -232.017316) (xy 142.480792 -232.203244)
			(xy 142.51686 -232.239058) (xy 142.614142 -232.285286)
		)
		(stroke
			(width 0)
			(type solid)
		)
		(fill yes)
		(layer "F.Cu")
		(net "M_E_CPU1_SB_DQ<19>")
	)
	(gr_poly
		(pts
			(xy 142.750794 -273.122136) (xy 142.786608 -273.086322) (xy 142.60068 -272.900394) (xy 142.564866 -272.936208)
			(xy 142.518638 -273.033744) (xy 142.653258 -273.168364)
		)
		(stroke
			(width 0)
			(type solid)
		)
		(fill yes)
		(layer "F.Cu")
		(net "M_E_CPU1_SA_DQ<20>")
	)
	(gr_poly
		(pts
			(xy 142.751048 -278.833834) (xy 142.699486 -278.576024) (xy 142.649702 -278.586184) (xy 142.557246 -278.641556)
			(xy 142.594584 -278.828246) (xy 142.701264 -278.843994)
		)
		(stroke
			(width 0)
			(type solid)
		)
		(fill yes)
		(layer "F.Cu")
		(net "M_E_CPU1_SA_DQ<16>")
	)
	(gr_poly
		(pts
			(xy 142.755112 -225.009456) (xy 142.704312 -225.009456) (xy 142.602712 -225.045778) (xy 142.602712 -225.236278)
			(xy 142.704312 -225.272346) (xy 142.755112 -225.272346)
		)
		(stroke
			(width 0)
			(type solid)
		)
		(fill yes)
		(layer "F.Cu")
		(net "M_E_CPU1_SB_DQ<26>")
	)
	(gr_poly
		(pts
			(xy 142.755112 -224.412556) (xy 142.704312 -224.412556) (xy 142.602712 -224.448878) (xy 142.602712 -224.639378)
			(xy 142.704312 -224.675446) (xy 142.755112 -224.675446)
		)
		(stroke
			(width 0)
			(type solid)
		)
		(fill yes)
		(layer "F.Cu")
		(net "M_E_CPU1_SB_DQ<26>")
	)
	(gr_poly
		(pts
			(xy 142.755112 -223.815656) (xy 142.704312 -223.815656) (xy 142.602712 -223.851978) (xy 142.602712 -224.042478)
			(xy 142.704312 -224.078546) (xy 142.755112 -224.078546)
		)
		(stroke
			(width 0)
			(type solid)
		)
		(fill yes)
		(layer "F.Cu")
		(net "M_E_CPU1_SB_DQ<26>")
	)
	(gr_poly
		(pts
			(xy 142.755112 -223.218756) (xy 142.704312 -223.218756) (xy 142.602712 -223.255078) (xy 142.602712 -223.445578)
			(xy 142.704312 -223.481646) (xy 142.755112 -223.481646)
		)
		(stroke
			(width 0)
			(type solid)
		)
		(fill yes)
		(layer "F.Cu")
		(net "M_E_CPU1_SB_DQ<26>")
	)
	(gr_poly
		(pts
			(xy 142.755112 -222.621856) (xy 142.704312 -222.621856) (xy 142.602712 -222.658178) (xy 142.602712 -222.848678)
			(xy 142.704312 -222.884746) (xy 142.755112 -222.884746)
		)
		(stroke
			(width 0)
			(type solid)
		)
		(fill yes)
		(layer "F.Cu")
		(net "M_E_CPU1_SB_DQ<26>")
	)
	(gr_poly
		(pts
			(xy 142.755112 -222.024956) (xy 142.704312 -222.024956) (xy 142.602712 -222.061278) (xy 142.602712 -222.251778)
			(xy 142.704312 -222.287846) (xy 142.755112 -222.287846)
		)
		(stroke
			(width 0)
			(type solid)
		)
		(fill yes)
		(layer "F.Cu")
		(net "M_E_CPU1_SB_DQ<26>")
	)
	(gr_poly
		(pts
			(xy 142.755112 -221.428056) (xy 142.704312 -221.428056) (xy 142.602712 -221.464378) (xy 142.602712 -221.654878)
			(xy 142.704312 -221.690946) (xy 142.755112 -221.690946)
		)
		(stroke
			(width 0)
			(type solid)
		)
		(fill yes)
		(layer "F.Cu")
		(net "M_E_CPU1_SB_DQ<26>")
	)
	(gr_poly
		(pts
			(xy 142.755112 -220.831156) (xy 142.704312 -220.831156) (xy 142.602712 -220.867478) (xy 142.602712 -221.057978)
			(xy 142.704312 -221.094046) (xy 142.755112 -221.094046)
		)
		(stroke
			(width 0)
			(type solid)
		)
		(fill yes)
		(layer "F.Cu")
		(net "M_E_CPU1_SB_DQ<26>")
	)
	(gr_poly
		(pts
			(xy 142.755112 -220.234256) (xy 142.704312 -220.234256) (xy 142.602712 -220.270578) (xy 142.602712 -220.461078)
			(xy 142.704312 -220.497146) (xy 142.755112 -220.497146)
		)
		(stroke
			(width 0)
			(type solid)
		)
		(fill yes)
		(layer "F.Cu")
		(net "M_E_CPU1_SB_DQ<26>")
	)
	(gr_poly
		(pts
			(xy 142.755112 -219.637356) (xy 142.704312 -219.637356) (xy 142.602712 -219.673678) (xy 142.602712 -219.864178)
			(xy 142.704312 -219.900246) (xy 142.755112 -219.900246)
		)
		(stroke
			(width 0)
			(type solid)
		)
		(fill yes)
		(layer "F.Cu")
		(net "M_E_CPU1_SB_DQ<26>")
	)
	(gr_poly
		(pts
			(xy 142.755112 -219.040456) (xy 142.704312 -219.040456) (xy 142.602712 -219.076778) (xy 142.602712 -219.267278)
			(xy 142.704312 -219.303346) (xy 142.755112 -219.303346)
		)
		(stroke
			(width 0)
			(type solid)
		)
		(fill yes)
		(layer "F.Cu")
		(net "M_E_CPU1_SB_DQ<26>")
	)
	(gr_poly
		(pts
			(xy 142.755112 -218.443556) (xy 142.704312 -218.443556) (xy 142.602712 -218.479878) (xy 142.602712 -218.670378)
			(xy 142.704312 -218.706446) (xy 142.755112 -218.706446)
		)
		(stroke
			(width 0)
			(type solid)
		)
		(fill yes)
		(layer "F.Cu")
		(net "M_E_CPU1_SB_DQ<26>")
	)
	(gr_poly
		(pts
			(xy 142.755112 -217.846656) (xy 142.704312 -217.846656) (xy 142.602712 -217.882978) (xy 142.602712 -218.073478)
			(xy 142.704312 -218.109546) (xy 142.755112 -218.109546)
		)
		(stroke
			(width 0)
			(type solid)
		)
		(fill yes)
		(layer "F.Cu")
		(net "M_E_CPU1_SB_DQ<26>")
	)
	(gr_poly
		(pts
			(xy 142.755112 -217.249756) (xy 142.704312 -217.249756) (xy 142.602712 -217.286078) (xy 142.602712 -217.476578)
			(xy 142.704312 -217.512646) (xy 142.755112 -217.512646)
		)
		(stroke
			(width 0)
			(type solid)
		)
		(fill yes)
		(layer "F.Cu")
		(net "M_E_CPU1_SB_DQ<26>")
	)
	(gr_poly
		(pts
			(xy 142.755112 -216.652856) (xy 142.704312 -216.652856) (xy 142.602712 -216.689178) (xy 142.602712 -216.879678)
			(xy 142.704312 -216.915746) (xy 142.755112 -216.915746)
		)
		(stroke
			(width 0)
			(type solid)
		)
		(fill yes)
		(layer "F.Cu")
		(net "M_E_CPU1_SB_DQ<26>")
	)
	(gr_poly
		(pts
			(xy 142.755112 -216.055956) (xy 142.704312 -216.055956) (xy 142.602712 -216.092278) (xy 142.602712 -216.282778)
			(xy 142.704312 -216.318846) (xy 142.755112 -216.318846)
		)
		(stroke
			(width 0)
			(type solid)
		)
		(fill yes)
		(layer "F.Cu")
		(net "M_E_CPU1_SB_DQ<26>")
	)
	(gr_poly
		(pts
			(xy 142.75816 -233.004106) (xy 142.711932 -232.90657) (xy 142.675864 -232.870756) (xy 142.489936 -233.056684)
			(xy 142.526004 -233.092498) (xy 142.623286 -233.138726)
		)
		(stroke
			(width 0)
			(type solid)
		)
		(fill yes)
		(layer "F.Cu")
		(net "M_E_CPU1_SB_DQ<18>")
	)
	(gr_poly
		(pts
			(xy 142.760192 -272.268442) (xy 142.796006 -272.232374) (xy 142.610332 -272.0467) (xy 142.574264 -272.082514)
			(xy 142.528036 -272.18005) (xy 142.662656 -272.31467)
		)
		(stroke
			(width 0)
			(type solid)
		)
		(fill yes)
		(layer "F.Cu")
		(net "M_E_CPU1_SA_DQ<21>")
	)
	(gr_poly
		(pts
			(xy 142.761462 -261.571994) (xy 142.79753 -261.53618) (xy 142.611602 -261.350252) (xy 142.575534 -261.386066)
			(xy 142.529306 -261.483602) (xy 142.66418 -261.618222)
		)
		(stroke
			(width 0)
			(type solid)
		)
		(fill yes)
		(layer "F.Cu")
		(net "M_E_CPU1_SA_CB<6>")
	)
	(gr_poly
		(pts
			(xy 142.764764 -258.563618) (xy 142.810992 -258.466082) (xy 142.676372 -258.331462) (xy 142.578836 -258.37769)
			(xy 142.543022 -258.413758) (xy 142.728696 -258.599432)
		)
		(stroke
			(width 0)
			(type solid)
		)
		(fill yes)
		(layer "F.Cu")
		(net "M_E_CPU1_SA_CS_N<2>")
	)
	(gr_poly
		(pts
			(xy 142.766796 -234.70108) (xy 142.720568 -234.603544) (xy 142.684754 -234.56773) (xy 142.498826 -234.753658)
			(xy 142.53464 -234.789472) (xy 142.632176 -234.8357)
		)
		(stroke
			(width 0)
			(type solid)
		)
		(fill yes)
		(layer "F.Cu")
		(net "M_E_CPU1_SB_DQ<13>")
	)
	(gr_poly
		(pts
			(xy 142.769082 -270.57096) (xy 142.80515 -270.535146) (xy 142.619222 -270.349218) (xy 142.583154 -270.385032)
			(xy 142.536926 -270.482568) (xy 142.671546 -270.617188)
		)
		(stroke
			(width 0)
			(type solid)
		)
		(fill yes)
		(layer "F.Cu")
		(net "M_E_CPU1_SA_DQ<26>")
	)
	(gr_poly
		(pts
			(xy 142.77086 -260.718554) (xy 142.806674 -260.68274) (xy 142.620746 -260.496812) (xy 142.584932 -260.53288)
			(xy 142.538704 -260.630162) (xy 142.673324 -260.765036)
		)
		(stroke
			(width 0)
			(type solid)
		)
		(fill yes)
		(layer "F.Cu")
		(net "M_E_CPU1_SA_CB<7>")
	)
	(gr_poly
		(pts
			(xy 142.771368 -265.32078) (xy 142.81785 -265.223244) (xy 142.682976 -265.088624) (xy 142.585694 -265.134852)
			(xy 142.549626 -265.170666) (xy 142.735554 -265.356594)
		)
		(stroke
			(width 0)
			(type solid)
		)
		(fill yes)
		(layer "F.Cu")
		(net "M_E_CPU1_SA_CB<0>")
	)
	(gr_poly
		(pts
			(xy 142.773908 -257.710178) (xy 142.820136 -257.612896) (xy 142.685516 -257.478022) (xy 142.58798 -257.52425)
			(xy 142.552166 -257.560318) (xy 142.738094 -257.746246)
		)
		(stroke
			(width 0)
			(type solid)
		)
		(fill yes)
		(layer "F.Cu")
		(net "M_E_CPU1_SA_CS_N<3>")
	)
	(gr_poly
		(pts
			(xy 142.776194 -235.55452) (xy 142.729966 -235.456984) (xy 142.693898 -235.42117) (xy 142.50797 -235.607098)
			(xy 142.544038 -235.642912) (xy 142.64132 -235.68914)
		)
		(stroke
			(width 0)
			(type solid)
		)
		(fill yes)
		(layer "F.Cu")
		(net "M_E_CPU1_SB_DQ<12>")
	)
	(gr_poly
		(pts
			(xy 142.778226 -269.71752) (xy 142.814294 -269.681706) (xy 142.628366 -269.495778) (xy 142.592298 -269.531592)
			(xy 142.54607 -269.629128) (xy 142.68069 -269.763748)
		)
		(stroke
			(width 0)
			(type solid)
		)
		(fill yes)
		(layer "F.Cu")
		(net "M_E_CPU1_SA_DQ<27>")
	)
	(gr_poly
		(pts
			(xy 142.780766 -264.46734) (xy 142.826994 -264.369804) (xy 142.692374 -264.235184) (xy 142.594838 -264.281412)
			(xy 142.559024 -264.31748) (xy 142.744698 -264.503154)
		)
		(stroke
			(width 0)
			(type solid)
		)
		(fill yes)
		(layer "F.Cu")
		(net "M_E_CPU1_SA_CB<1>")
	)
	(gr_poly
		(pts
			(xy 142.783052 -256.856992) (xy 142.82928 -256.759456) (xy 142.69466 -256.624836) (xy 142.597378 -256.671064)
			(xy 142.56131 -256.706878) (xy 142.747238 -256.892806)
		)
		(stroke
			(width 0)
			(type solid)
		)
		(fill yes)
		(layer "F.Cu")
		(net "M_E_CPU1_SA_CA<1>")
	)
	(gr_poly
		(pts
			(xy 142.79245 -256.003552) (xy 142.838678 -255.906016) (xy 142.703804 -255.771396) (xy 142.606522 -255.817624)
			(xy 142.570454 -255.853438) (xy 142.756382 -256.039366)
		)
		(stroke
			(width 0)
			(type solid)
		)
		(fill yes)
		(layer "F.Cu")
		(net "M_E_CPU1_SA_CA<3>")
	)
	(gr_poly
		(pts
			(xy 142.801594 -255.150112) (xy 142.847822 -255.05283) (xy 142.713202 -254.917956) (xy 142.615666 -254.964184)
			(xy 142.579852 -255.000252) (xy 142.76578 -255.18618)
		)
		(stroke
			(width 0)
			(type solid)
		)
		(fill yes)
		(layer "F.Cu")
		(net "M_E_CPU1_SA_CA<5>")
	)
	(gr_poly
		(pts
			(xy 142.804896 -266.97559) (xy 142.851124 -266.878054) (xy 142.716504 -266.743434) (xy 142.618968 -266.789662)
			(xy 142.583154 -266.82573) (xy 142.768828 -267.011404)
		)
		(stroke
			(width 0)
			(type solid)
		)
		(fill yes)
		(layer "F.Cu")
		(net "M_E_CPU1_SA_DQ<30>")
	)
	(gr_poly
		(pts
			(xy 142.808198 -277.30069) (xy 142.900654 -277.245318) (xy 142.863316 -277.058628) (xy 142.756636 -277.043134)
			(xy 142.706852 -277.05304) (xy 142.758414 -277.31085)
		)
		(stroke
			(width 0)
			(type solid)
		)
		(fill yes)
		(layer "F.Cu")
		(net "M_E_CPU1_SA_DQ<18>")
	)
	(gr_poly
		(pts
			(xy 142.810738 -254.296672) (xy 142.856966 -254.19939) (xy 142.722346 -254.06477) (xy 142.62481 -254.110998)
			(xy 142.588996 -254.146812) (xy 142.774924 -254.33274)
		)
		(stroke
			(width 0)
			(type solid)
		)
		(fill yes)
		(layer "F.Cu")
		(net "M_E_CPU1_SA_PAR")
	)
	(gr_poly
		(pts
			(xy 142.814294 -266.121896) (xy 142.860522 -266.024614) (xy 142.725902 -265.88974) (xy 142.628366 -265.935968)
			(xy 142.592552 -265.972036) (xy 142.77848 -266.157964)
		)
		(stroke
			(width 0)
			(type solid)
		)
		(fill yes)
		(layer "F.Cu")
		(net "M_E_CPU1_SA_DQ<31>")
	)
	(gr_poly
		(pts
			(xy 142.816834 -277.603458) (xy 142.765272 -277.345648) (xy 142.715488 -277.355554) (xy 142.623032 -277.410926)
			(xy 142.66037 -277.59787) (xy 142.76705 -277.613364)
		)
		(stroke
			(width 0)
			(type solid)
		)
		(fill yes)
		(layer "F.Cu")
		(net "M_E_CPU1_SA_DQ<18>")
	)
	(gr_poly
		(pts
			(xy 142.827502 -272.62328) (xy 142.87373 -272.525744) (xy 142.73911 -272.391124) (xy 142.641574 -272.437352)
			(xy 142.60576 -272.47342) (xy 142.791434 -272.659094)
		)
		(stroke
			(width 0)
			(type solid)
		)
		(fill yes)
		(layer "F.Cu")
		(net "M_E_CPU1_SA_DQ<22>")
	)
	(gr_poly
		(pts
			(xy 142.828772 -261.926832) (xy 142.875 -261.82955) (xy 142.74038 -261.694676) (xy 142.642844 -261.740904)
			(xy 142.60703 -261.776972) (xy 142.792958 -261.9629)
		)
		(stroke
			(width 0)
			(type solid)
		)
		(fill yes)
		(layer "F.Cu")
		(net "M_E_CPU1_SA_CB<4>")
	)
	(gr_poly
		(pts
			(xy 142.836392 -270.925798) (xy 142.88262 -270.828262) (xy 142.748 -270.693642) (xy 142.650464 -270.73987)
			(xy 142.61465 -270.775938) (xy 142.800324 -270.961612)
		)
		(stroke
			(width 0)
			(type solid)
		)
		(fill yes)
		(layer "F.Cu")
		(net "M_E_CPU1_SA_DQ<24>")
	)
	(gr_poly
		(pts
			(xy 142.836646 -271.76984) (xy 142.882874 -271.672304) (xy 142.748254 -271.537684) (xy 142.650972 -271.583912)
			(xy 142.614904 -271.619726) (xy 142.800832 -271.805654)
		)
		(stroke
			(width 0)
			(type solid)
		)
		(fill yes)
		(layer "F.Cu")
		(net "M_E_CPU1_SA_DQ<23>")
	)
	(gr_poly
		(pts
			(xy 142.837916 -261.073392) (xy 142.884144 -260.97611) (xy 142.749524 -260.84149) (xy 142.651988 -260.887718)
			(xy 142.616174 -260.923532) (xy 142.802102 -261.10946)
		)
		(stroke
			(width 0)
			(type solid)
		)
		(fill yes)
		(layer "F.Cu")
		(net "M_E_CPU1_SA_CB<5>")
	)
	(gr_poly
		(pts
			(xy 142.845536 -270.072358) (xy 142.891764 -269.974822) (xy 142.757144 -269.840202) (xy 142.659608 -269.88643)
			(xy 142.623794 -269.922498) (xy 142.809722 -270.108426)
		)
		(stroke
			(width 0)
			(type solid)
		)
		(fill yes)
		(layer "F.Cu")
		(net "M_E_CPU1_SA_DQ<25>")
	)
	(gr_poly
		(pts
			(xy 142.85087 -229.244906) (xy 142.815056 -229.209092) (xy 142.71752 -229.16261) (xy 142.5829 -229.297484)
			(xy 142.629128 -229.394766) (xy 142.664942 -229.430834)
		)
		(stroke
			(width 0)
			(type solid)
		)
		(fill yes)
		(layer "F.Cu")
		(net "M_E_CPU1_SB_DQ<22>")
	)
	(gr_poly
		(pts
			(xy 142.859252 -279.116536) (xy 142.951962 -279.061164) (xy 142.91437 -278.874474) (xy 142.80769 -278.858726)
			(xy 142.757906 -278.868886) (xy 142.809468 -279.126696)
		)
		(stroke
			(width 0)
			(type solid)
		)
		(fill yes)
		(layer "F.Cu")
		(net "M_E_CPU1_SA_DQ<16>")
	)
	(gr_poly
		(pts
			(xy 142.859252 -249.069352) (xy 142.859252 -249.018552) (xy 142.596108 -249.018552) (xy 142.596108 -249.069352)
			(xy 142.63243 -249.170952) (xy 142.82293 -249.170952)
		)
		(stroke
			(width 0)
			(type solid)
		)
		(fill yes)
		(layer "F.Cu")
		(net "M_E_CPU1_SB_CA<0>")
	)
	(gr_poly
		(pts
			(xy 142.859252 -248.764552) (xy 142.859252 -248.713752) (xy 142.596108 -248.713752) (xy 142.596108 -248.764552)
			(xy 142.63243 -248.866152) (xy 142.82293 -248.866152)
		)
		(stroke
			(width 0)
			(type solid)
		)
		(fill yes)
		(layer "F.Cu")
		(net "M_E_CPU1_SB_CA<1>")
	)
	(gr_poly
		(pts
			(xy 142.859252 -248.459752) (xy 142.859252 -248.408952) (xy 142.596108 -248.408952) (xy 142.596108 -248.459752)
			(xy 142.63243 -248.561352) (xy 142.82293 -248.561352)
		)
		(stroke
			(width 0)
			(type solid)
		)
		(fill yes)
		(layer "F.Cu")
		(net "M_E_CPU1_SB_CA<2>")
	)
	(gr_poly
		(pts
			(xy 142.859252 -248.154952) (xy 142.859252 -248.104152) (xy 142.596108 -248.104152) (xy 142.596108 -248.154952)
			(xy 142.63243 -248.256552) (xy 142.82293 -248.256552)
		)
		(stroke
			(width 0)
			(type solid)
		)
		(fill yes)
		(layer "F.Cu")
		(net "M_E_CPU1_SB_CA<3>")
	)
	(gr_poly
		(pts
			(xy 142.859252 -247.850152) (xy 142.859252 -247.799352) (xy 142.596108 -247.799352) (xy 142.596108 -247.850152)
			(xy 142.63243 -247.951752) (xy 142.82293 -247.951752)
		)
		(stroke
			(width 0)
			(type solid)
		)
		(fill yes)
		(layer "F.Cu")
		(net "M_E_CPU1_SB_CA<4>")
	)
	(gr_poly
		(pts
			(xy 142.859252 -247.545352) (xy 142.859252 -247.494552) (xy 142.596108 -247.494552) (xy 142.596108 -247.545352)
			(xy 142.63243 -247.646952) (xy 142.82293 -247.646952)
		)
		(stroke
			(width 0)
			(type solid)
		)
		(fill yes)
		(layer "F.Cu")
		(net "M_E_CPU1_SB_CA<5>")
	)
	(gr_poly
		(pts
			(xy 142.859252 -247.240552) (xy 142.859252 -247.189752) (xy 142.596108 -247.189752) (xy 142.596108 -247.240552)
			(xy 142.63243 -247.342152) (xy 142.82293 -247.342152)
		)
		(stroke
			(width 0)
			(type solid)
		)
		(fill yes)
		(layer "F.Cu")
		(net "M_E_CPU1_SB_CA<6>")
	)
	(gr_poly
		(pts
			(xy 142.859252 -246.935752) (xy 142.859252 -246.884952) (xy 142.596108 -246.884952) (xy 142.596108 -246.935752)
			(xy 142.63243 -247.037352) (xy 142.82293 -247.037352)
		)
		(stroke
			(width 0)
			(type solid)
		)
		(fill yes)
		(layer "F.Cu")
		(net "M_E_CPU1_SB_PAR")
	)
	(gr_poly
		(pts
			(xy 142.859252 -246.630952) (xy 142.859252 -246.580152) (xy 142.596108 -246.580152) (xy 142.596108 -246.630952)
			(xy 142.63243 -246.732552) (xy 142.82293 -246.732552)
		)
		(stroke
			(width 0)
			(type solid)
		)
		(fill yes)
		(layer "F.Cu")
		(net "M_E_CPU1_SB_CS_N<0>")
	)
	(gr_poly
		(pts
			(xy 142.859252 -246.326152) (xy 142.859252 -246.275352) (xy 142.596108 -246.275352) (xy 142.596108 -246.326152)
			(xy 142.63243 -246.427752) (xy 142.82293 -246.427752)
		)
		(stroke
			(width 0)
			(type solid)
		)
		(fill yes)
		(layer "F.Cu")
		(net "M_E_CPU1_SB_CS_N<2>")
	)
	(gr_poly
		(pts
			(xy 142.859252 -246.021352) (xy 142.859252 -245.970552) (xy 142.596108 -245.970552) (xy 142.596108 -246.021352)
			(xy 142.63243 -246.122952) (xy 142.82293 -246.122952)
		)
		(stroke
			(width 0)
			(type solid)
		)
		(fill yes)
		(layer "F.Cu")
		(net "M_E_CPU1_SB_CS_N<1>")
	)
	(gr_poly
		(pts
			(xy 142.867888 -279.419304) (xy 142.816326 -279.161494) (xy 142.766542 -279.1714) (xy 142.674086 -279.226772)
			(xy 142.711424 -279.413716) (xy 142.818104 -279.42921)
		)
		(stroke
			(width 0)
			(type solid)
		)
		(fill yes)
		(layer "F.Cu")
		(net "M_E_CPU1_SA_DQ<16>")
	)
	(gr_poly
		(pts
			(xy 142.873476 -276.070314) (xy 142.966186 -276.014942) (xy 142.928848 -275.828252) (xy 142.822168 -275.812504)
			(xy 142.77213 -275.82241) (xy 142.823692 -276.08022)
		)
		(stroke
			(width 0)
			(type solid)
		)
		(fill yes)
		(layer "F.Cu")
		(net "M_E_CPU1_SA_DQ<17>")
	)
	(gr_poly
		(pts
			(xy 142.877794 -231.806242) (xy 142.841726 -231.770428) (xy 142.744444 -231.7242) (xy 142.609824 -231.85882)
			(xy 142.656052 -231.956356) (xy 142.691866 -231.99217)
		)
		(stroke
			(width 0)
			(type solid)
		)
		(fill yes)
		(layer "F.Cu")
		(net "M_E_CPU1_SB_DQ<19>")
	)
	(gr_poly
		(pts
			(xy 142.882366 -276.373082) (xy 142.830804 -276.115272) (xy 142.78102 -276.125178) (xy 142.68831 -276.18055)
			(xy 142.725648 -276.367494) (xy 142.832582 -276.382988)
		)
		(stroke
			(width 0)
			(type solid)
		)
		(fill yes)
		(layer "F.Cu")
		(net "M_E_CPU1_SA_DQ<17>")
	)
	(gr_poly
		(pts
			(xy 142.886938 -232.659682) (xy 142.851124 -232.623614) (xy 142.753588 -232.577386) (xy 142.618968 -232.71226)
			(xy 142.665196 -232.809542) (xy 142.70101 -232.84561)
		)
		(stroke
			(width 0)
			(type solid)
		)
		(fill yes)
		(layer "F.Cu")
		(net "M_E_CPU1_SB_DQ<18>")
	)
	(gr_poly
		(pts
			(xy 142.895828 -234.356656) (xy 142.85976 -234.320842) (xy 142.762478 -234.274614) (xy 142.627604 -234.409234)
			(xy 142.673832 -234.50677) (xy 142.7099 -234.542584)
		)
		(stroke
			(width 0)
			(type solid)
		)
		(fill yes)
		(layer "F.Cu")
		(net "M_E_CPU1_SB_DQ<13>")
	)
	(gr_poly
		(pts
			(xy 142.903956 -258.846574) (xy 142.93977 -258.810506) (xy 142.753842 -258.624578) (xy 142.718028 -258.660646)
			(xy 142.6718 -258.757928) (xy 142.80642 -258.892802)
		)
		(stroke
			(width 0)
			(type solid)
		)
		(fill yes)
		(layer "F.Cu")
		(net "M_E_CPU1_SA_CS_N<2>")
	)
	(gr_poly
		(pts
			(xy 142.904972 -235.210096) (xy 142.869158 -235.174282) (xy 142.771622 -235.1278) (xy 142.637002 -235.262674)
			(xy 142.68323 -235.359956) (xy 142.719044 -235.396024)
		)
		(stroke
			(width 0)
			(type solid)
		)
		(fill yes)
		(layer "F.Cu")
		(net "M_E_CPU1_SB_DQ<12>")
	)
	(gr_poly
		(pts
			(xy 142.907512 -224.937574) (xy 142.907512 -224.747074) (xy 142.805912 -224.711006) (xy 142.755112 -224.711006)
			(xy 142.755112 -224.973896) (xy 142.805912 -224.973896)
		)
		(stroke
			(width 0)
			(type solid)
		)
		(fill yes)
		(layer "F.Cu")
		(net "M_E_CPU1_SB_DQ<26>")
	)
	(gr_poly
		(pts
			(xy 142.907512 -224.340674) (xy 142.907512 -224.150174) (xy 142.805912 -224.114106) (xy 142.755112 -224.114106)
			(xy 142.755112 -224.376996) (xy 142.805912 -224.376996)
		)
		(stroke
			(width 0)
			(type solid)
		)
		(fill yes)
		(layer "F.Cu")
		(net "M_E_CPU1_SB_DQ<26>")
	)
	(gr_poly
		(pts
			(xy 142.907512 -223.743774) (xy 142.907512 -223.553274) (xy 142.805912 -223.517206) (xy 142.755112 -223.517206)
			(xy 142.755112 -223.780096) (xy 142.805912 -223.780096)
		)
		(stroke
			(width 0)
			(type solid)
		)
		(fill yes)
		(layer "F.Cu")
		(net "M_E_CPU1_SB_DQ<26>")
	)
	(gr_poly
		(pts
			(xy 142.907512 -223.146874) (xy 142.907512 -222.956374) (xy 142.805912 -222.920306) (xy 142.755112 -222.920306)
			(xy 142.755112 -223.183196) (xy 142.805912 -223.183196)
		)
		(stroke
			(width 0)
			(type solid)
		)
		(fill yes)
		(layer "F.Cu")
		(net "M_E_CPU1_SB_DQ<26>")
	)
	(gr_poly
		(pts
			(xy 142.907512 -222.549974) (xy 142.907512 -222.359474) (xy 142.805912 -222.323406) (xy 142.755112 -222.323406)
			(xy 142.755112 -222.586296) (xy 142.805912 -222.586296)
		)
		(stroke
			(width 0)
			(type solid)
		)
		(fill yes)
		(layer "F.Cu")
		(net "M_E_CPU1_SB_DQ<26>")
	)
	(gr_poly
		(pts
			(xy 142.907512 -221.953074) (xy 142.907512 -221.762574) (xy 142.805912 -221.726506) (xy 142.755112 -221.726506)
			(xy 142.755112 -221.989396) (xy 142.805912 -221.989396)
		)
		(stroke
			(width 0)
			(type solid)
		)
		(fill yes)
		(layer "F.Cu")
		(net "M_E_CPU1_SB_DQ<26>")
	)
	(gr_poly
		(pts
			(xy 142.907512 -221.356174) (xy 142.907512 -221.165674) (xy 142.805912 -221.129606) (xy 142.755112 -221.129606)
			(xy 142.755112 -221.392496) (xy 142.805912 -221.392496)
		)
		(stroke
			(width 0)
			(type solid)
		)
		(fill yes)
		(layer "F.Cu")
		(net "M_E_CPU1_SB_DQ<26>")
	)
	(gr_poly
		(pts
			(xy 142.907512 -220.759274) (xy 142.907512 -220.568774) (xy 142.805912 -220.532706) (xy 142.755112 -220.532706)
			(xy 142.755112 -220.795596) (xy 142.805912 -220.795596)
		)
		(stroke
			(width 0)
			(type solid)
		)
		(fill yes)
		(layer "F.Cu")
		(net "M_E_CPU1_SB_DQ<26>")
	)
	(gr_poly
		(pts
			(xy 142.907512 -220.162374) (xy 142.907512 -219.971874) (xy 142.805912 -219.935806) (xy 142.755112 -219.935806)
			(xy 142.755112 -220.198696) (xy 142.805912 -220.198696)
		)
		(stroke
			(width 0)
			(type solid)
		)
		(fill yes)
		(layer "F.Cu")
		(net "M_E_CPU1_SB_DQ<26>")
	)
	(gr_poly
		(pts
			(xy 142.907512 -219.565474) (xy 142.907512 -219.374974) (xy 142.805912 -219.338906) (xy 142.755112 -219.338906)
			(xy 142.755112 -219.601796) (xy 142.805912 -219.601796)
		)
		(stroke
			(width 0)
			(type solid)
		)
		(fill yes)
		(layer "F.Cu")
		(net "M_E_CPU1_SB_DQ<26>")
	)
	(gr_poly
		(pts
			(xy 142.907512 -218.968574) (xy 142.907512 -218.778074) (xy 142.805912 -218.742006) (xy 142.755112 -218.742006)
			(xy 142.755112 -219.004896) (xy 142.805912 -219.004896)
		)
		(stroke
			(width 0)
			(type solid)
		)
		(fill yes)
		(layer "F.Cu")
		(net "M_E_CPU1_SB_DQ<26>")
	)
	(gr_poly
		(pts
			(xy 142.907512 -218.371674) (xy 142.907512 -218.181174) (xy 142.805912 -218.145106) (xy 142.755112 -218.145106)
			(xy 142.755112 -218.407996) (xy 142.805912 -218.407996)
		)
		(stroke
			(width 0)
			(type solid)
		)
		(fill yes)
		(layer "F.Cu")
		(net "M_E_CPU1_SB_DQ<26>")
	)
	(gr_poly
		(pts
			(xy 142.907512 -217.774774) (xy 142.907512 -217.584274) (xy 142.805912 -217.548206) (xy 142.755112 -217.548206)
			(xy 142.755112 -217.811096) (xy 142.805912 -217.811096)
		)
		(stroke
			(width 0)
			(type solid)
		)
		(fill yes)
		(layer "F.Cu")
		(net "M_E_CPU1_SB_DQ<26>")
	)
	(gr_poly
		(pts
			(xy 142.907512 -217.177874) (xy 142.907512 -216.987374) (xy 142.805912 -216.951306) (xy 142.755112 -216.951306)
			(xy 142.755112 -217.214196) (xy 142.805912 -217.214196)
		)
		(stroke
			(width 0)
			(type solid)
		)
		(fill yes)
		(layer "F.Cu")
		(net "M_E_CPU1_SB_DQ<26>")
	)
	(gr_poly
		(pts
			(xy 142.907512 -216.580974) (xy 142.907512 -216.390474) (xy 142.805912 -216.354406) (xy 142.755112 -216.354406)
			(xy 142.755112 -216.617296) (xy 142.805912 -216.617296)
		)
		(stroke
			(width 0)
			(type solid)
		)
		(fill yes)
		(layer "F.Cu")
		(net "M_E_CPU1_SB_DQ<26>")
	)
	(gr_poly
		(pts
			(xy 142.907512 -215.984074) (xy 142.907512 -215.793574) (xy 142.805912 -215.757506) (xy 142.755112 -215.757506)
			(xy 142.755112 -216.020396) (xy 142.805912 -216.020396)
		)
		(stroke
			(width 0)
			(type solid)
		)
		(fill yes)
		(layer "F.Cu")
		(net "M_E_CPU1_SB_DQ<26>")
	)
	(gr_poly
		(pts
			(xy 142.910814 -265.603482) (xy 142.946628 -265.567668) (xy 142.7607 -265.38174) (xy 142.724886 -265.417554)
			(xy 142.678658 -265.51509) (xy 142.813278 -265.64971)
		)
		(stroke
			(width 0)
			(type solid)
		)
		(fill yes)
		(layer "F.Cu")
		(net "M_E_CPU1_SA_CB<0>")
	)
	(gr_poly
		(pts
			(xy 142.9131 -257.993134) (xy 142.949168 -257.95732) (xy 142.76324 -257.771392) (xy 142.727172 -257.807206)
			(xy 142.680944 -257.904742) (xy 142.815818 -258.039362)
		)
		(stroke
			(width 0)
			(type solid)
		)
		(fill yes)
		(layer "F.Cu")
		(net "M_E_CPU1_SA_CS_N<3>")
	)
	(gr_poly
		(pts
			(xy 142.919958 -264.750296) (xy 142.955772 -264.714228) (xy 142.769844 -264.5283) (xy 142.73403 -264.564368)
			(xy 142.687802 -264.66165) (xy 142.822422 -264.796524)
		)
		(stroke
			(width 0)
			(type solid)
		)
		(fill yes)
		(layer "F.Cu")
		(net "M_E_CPU1_SA_CB<1>")
	)
	(gr_poly
		(pts
			(xy 142.92199 -275.312632) (xy 142.968218 -275.215096) (xy 142.833598 -275.080476) (xy 142.736062 -275.126704)
			(xy 142.700248 -275.162772) (xy 142.885922 -275.348446)
		)
		(stroke
			(width 0)
			(type solid)
		)
		(fill yes)
		(layer "F.Cu")
		(net "M_E_CPU1_SA_DQ<19>")
	)
	(gr_poly
		(pts
			(xy 142.922244 -257.139694) (xy 142.958312 -257.10388) (xy 142.772384 -256.917952) (xy 142.73657 -256.953766)
			(xy 142.690088 -257.051302) (xy 142.824962 -257.185922)
		)
		(stroke
			(width 0)
			(type solid)
		)
		(fill yes)
		(layer "F.Cu")
		(net "M_E_CPU1_SA_CA<1>")
	)
	(gr_poly
		(pts
			(xy 142.925292 -277.88616) (xy 143.017748 -277.830788) (xy 142.98041 -277.643844) (xy 142.87373 -277.62835)
			(xy 142.823946 -277.638256) (xy 142.875508 -277.896066)
		)
		(stroke
			(width 0)
			(type solid)
		)
		(fill yes)
		(layer "F.Cu")
		(net "M_E_CPU1_SA_DQ<18>")
	)
	(gr_poly
		(pts
			(xy 142.92834 -228.951536) (xy 142.882112 -228.854) (xy 142.846298 -228.818186) (xy 142.66037 -229.004114)
			(xy 142.696184 -229.039928) (xy 142.79372 -229.086156)
		)
		(stroke
			(width 0)
			(type solid)
		)
		(fill yes)
		(layer "F.Cu")
		(net "M_E_CPU1_SB_DQ<21>")
	)
	(gr_poly
		(pts
			(xy 142.929864 -237.772956) (xy 142.89405 -237.737142) (xy 142.796514 -237.690914) (xy 142.661894 -237.825534)
			(xy 142.708122 -237.92307) (xy 142.743936 -237.958884)
		)
		(stroke
			(width 0)
			(type solid)
		)
		(fill yes)
		(layer "F.Cu")
		(net "M_E_CPU1_SB_DQ<9>")
	)
	(gr_poly
		(pts
			(xy 142.931642 -256.286508) (xy 142.967456 -256.25044) (xy 142.781528 -256.064512) (xy 142.745714 -256.10058)
			(xy 142.699486 -256.197862) (xy 142.834106 -256.332736)
		)
		(stroke
			(width 0)
			(type solid)
		)
		(fill yes)
		(layer "F.Cu")
		(net "M_E_CPU1_SA_CA<3>")
	)
	(gr_poly
		(pts
			(xy 142.933928 -278.188674) (xy 142.882366 -277.930864) (xy 142.832582 -277.941024) (xy 142.740126 -277.996396)
			(xy 142.777464 -278.183086) (xy 142.884144 -278.19858)
		)
		(stroke
			(width 0)
			(type solid)
		)
		(fill yes)
		(layer "F.Cu")
		(net "M_E_CPU1_SA_DQ<18>")
	)
	(gr_poly
		(pts
			(xy 142.937738 -229.804976) (xy 142.89151 -229.70744) (xy 142.855442 -229.671626) (xy 142.669514 -229.857554)
			(xy 142.705582 -229.893368) (xy 142.802864 -229.939596)
		)
		(stroke
			(width 0)
			(type solid)
		)
		(fill yes)
		(layer "F.Cu")
		(net "M_E_CPU1_SB_DQ<20>")
	)
	(gr_poly
		(pts
			(xy 142.940786 -255.433068) (xy 142.9766 -255.397) (xy 142.790926 -255.211326) (xy 142.754858 -255.24714)
			(xy 142.70863 -255.344676) (xy 142.84325 -255.479296)
		)
		(stroke
			(width 0)
			(type solid)
		)
		(fill yes)
		(layer "F.Cu")
		(net "M_E_CPU1_SA_CA<5>")
	)
	(gr_poly
		(pts
			(xy 142.944088 -267.258546) (xy 142.979902 -267.222478) (xy 142.793974 -267.03655) (xy 142.75816 -267.072618)
			(xy 142.711932 -267.1699) (xy 142.846552 -267.304774)
		)
		(stroke
			(width 0)
			(type solid)
		)
		(fill yes)
		(layer "F.Cu")
		(net "M_E_CPU1_SA_DQ<30>")
	)
	(gr_poly
		(pts
			(xy 142.94993 -254.579628) (xy 142.985998 -254.543814) (xy 142.80007 -254.357886) (xy 142.764002 -254.3937)
			(xy 142.717774 -254.491236) (xy 142.852648 -254.625856)
		)
		(stroke
			(width 0)
			(type solid)
		)
		(fill yes)
		(layer "F.Cu")
		(net "M_E_CPU1_SA_PAR")
	)
	(gr_poly
		(pts
			(xy 142.953486 -266.404852) (xy 142.989554 -266.369038) (xy 142.803626 -266.18311) (xy 142.767558 -266.218924)
			(xy 142.72133 -266.31646) (xy 142.856204 -266.45108)
		)
		(stroke
			(width 0)
			(type solid)
		)
		(fill yes)
		(layer "F.Cu")
		(net "M_E_CPU1_SA_DQ<31>")
	)
	(gr_poly
		(pts
			(xy 142.958312 -240.26114) (xy 142.958312 -240.21034) (xy 142.695422 -240.21034) (xy 142.695422 -240.26114)
			(xy 142.731744 -240.36274) (xy 142.922244 -240.36274)
		)
		(stroke
			(width 0)
			(type solid)
		)
		(fill yes)
		(layer "F.Cu")
		(net "M_E_CPU1_SB_CB<0>")
	)
	(gr_poly
		(pts
			(xy 142.958312 -239.95634) (xy 142.958312 -239.90554) (xy 142.695422 -239.90554) (xy 142.695422 -239.95634)
			(xy 142.731744 -240.05794) (xy 142.922244 -240.05794)
		)
		(stroke
			(width 0)
			(type solid)
		)
		(fill yes)
		(layer "F.Cu")
		(net "M_E_CPU1_SB_CB<2>")
	)
	(gr_poly
		(pts
			(xy 142.958312 -239.65154) (xy 142.958312 -239.60074) (xy 142.695422 -239.60074) (xy 142.695422 -239.65154)
			(xy 142.731744 -239.75314) (xy 142.922244 -239.75314)
		)
		(stroke
			(width 0)
			(type solid)
		)
		(fill yes)
		(layer "F.Cu")
		(net "M_E_CPU1_SB_CB<1>")
	)
	(gr_poly
		(pts
			(xy 142.958312 -239.34674) (xy 142.958312 -239.29594) (xy 142.695422 -239.29594) (xy 142.695422 -239.34674)
			(xy 142.731744 -239.44834) (xy 142.922244 -239.44834)
		)
		(stroke
			(width 0)
			(type solid)
		)
		(fill yes)
		(layer "F.Cu")
		(net "M_E_CPU1_SB_CB<3>")
	)
	(gr_poly
		(pts
			(xy 142.964662 -232.366312) (xy 142.91818 -232.268776) (xy 142.882366 -232.232962) (xy 142.696438 -232.41889)
			(xy 142.732506 -232.454704) (xy 142.829788 -232.500932)
		)
		(stroke
			(width 0)
			(type solid)
		)
		(fill yes)
		(layer "F.Cu")
		(net "M_E_CPU1_SB_DQ<17>")
	)
	(gr_poly
		(pts
			(xy 142.966694 -272.906236) (xy 143.002508 -272.870168) (xy 142.81658 -272.68424) (xy 142.780766 -272.720308)
			(xy 142.734538 -272.81759) (xy 142.869158 -272.952464)
		)
		(stroke
			(width 0)
			(type solid)
		)
		(fill yes)
		(layer "F.Cu")
		(net "M_E_CPU1_SA_DQ<22>")
	)
	(gr_poly
		(pts
			(xy 142.967964 -262.209788) (xy 143.003778 -262.17372) (xy 142.818104 -261.988046) (xy 142.782036 -262.02386)
			(xy 142.735808 -262.121396) (xy 142.870428 -262.256016)
		)
		(stroke
			(width 0)
			(type solid)
		)
		(fill yes)
		(layer "F.Cu")
		(net "M_E_CPU1_SA_CB<4>")
	)
	(gr_poly
		(pts
			(xy 142.971012 -259.201412) (xy 143.01724 -259.10413) (xy 142.88262 -258.969256) (xy 142.785084 -259.015484)
			(xy 142.74927 -259.051552) (xy 142.935198 -259.23748)
		)
		(stroke
			(width 0)
			(type solid)
		)
		(fill yes)
		(layer "F.Cu")
		(net "M_E_CPU1_SA_CS_N<0>")
	)
	(gr_poly
		(pts
			(xy 142.973298 -234.063286) (xy 142.92707 -233.966004) (xy 142.891256 -233.929936) (xy 142.705328 -234.115864)
			(xy 142.741142 -234.151932) (xy 142.838678 -234.19816)
		)
		(stroke
			(width 0)
			(type solid)
		)
		(fill yes)
		(layer "F.Cu")
		(net "M_E_CPU1_SB_DQ<15>")
	)
	(gr_poly
		(pts
			(xy 142.973806 -233.219752) (xy 142.927578 -233.122216) (xy 142.89151 -233.086402) (xy 142.705582 -233.27233)
			(xy 142.74165 -233.308144) (xy 142.838932 -233.354372)
		)
		(stroke
			(width 0)
			(type solid)
		)
		(fill yes)
		(layer "F.Cu")
		(net "M_E_CPU1_SB_DQ<16>")
	)
	(gr_poly
		(pts
			(xy 142.975584 -271.208754) (xy 143.011398 -271.172686) (xy 142.82547 -270.986758) (xy 142.789656 -271.022826)
			(xy 142.743428 -271.120362) (xy 142.878048 -271.254982)
		)
		(stroke
			(width 0)
			(type solid)
		)
		(fill yes)
		(layer "F.Cu")
		(net "M_E_CPU1_SA_DQ<24>")
	)
	(gr_poly
		(pts
			(xy 142.975838 -272.052542) (xy 143.011906 -272.016728) (xy 142.825978 -271.8308) (xy 142.790164 -271.866614)
			(xy 142.743682 -271.96415) (xy 142.878556 -272.09877)
		)
		(stroke
			(width 0)
			(type solid)
		)
		(fill yes)
		(layer "F.Cu")
		(net "M_E_CPU1_SA_DQ<23>")
	)
	(gr_poly
		(pts
			(xy 142.976092 -279.702006) (xy 143.068802 -279.646634) (xy 143.031464 -279.45969) (xy 142.92453 -279.444196)
			(xy 142.874746 -279.454102) (xy 142.926308 -279.711912)
		)
		(stroke
			(width 0)
			(type solid)
		)
		(fill yes)
		(layer "F.Cu")
		(net "M_E_CPU1_SA_DQ<16>")
	)
	(gr_poly
		(pts
			(xy 142.977108 -261.356348) (xy 143.013176 -261.320534) (xy 142.827248 -261.134606) (xy 142.79118 -261.17042)
			(xy 142.744952 -261.267956) (xy 142.879826 -261.402576)
		)
		(stroke
			(width 0)
			(type solid)
		)
		(fill yes)
		(layer "F.Cu")
		(net "M_E_CPU1_SA_CB<5>")
	)
	(gr_poly
		(pts
			(xy 142.98041 -258.347972) (xy 143.026638 -258.250436) (xy 142.892018 -258.115816) (xy 142.794482 -258.162044)
			(xy 142.758668 -258.198112) (xy 142.944342 -258.383786)
		)
		(stroke
			(width 0)
			(type solid)
		)
		(fill yes)
		(layer "F.Cu")
		(net "M_E_CPU1_SA_CS_N<1>")
	)
	(gr_poly
		(pts
			(xy 142.982442 -234.916726) (xy 142.936214 -234.81919) (xy 142.9004 -234.783376) (xy 142.714472 -234.969304)
			(xy 142.750286 -235.005118) (xy 142.847822 -235.051346)
		)
		(stroke
			(width 0)
			(type solid)
		)
		(fill yes)
		(layer "F.Cu")
		(net "M_E_CPU1_SB_DQ<14>")
	)
	(gr_poly
		(pts
			(xy 142.984728 -280.00452) (xy 142.933166 -279.74671) (xy 142.883382 -279.75687) (xy 142.790926 -279.812242)
			(xy 142.828264 -279.998932) (xy 142.934944 -280.01468)
		)
		(stroke
			(width 0)
			(type solid)
		)
		(fill yes)
		(layer "F.Cu")
		(net "M_E_CPU1_SA_DQ<16>")
	)
	(gr_poly
		(pts
			(xy 142.984728 -270.355314) (xy 143.020542 -270.319246) (xy 142.834868 -270.133572) (xy 142.7988 -270.169386)
			(xy 142.752572 -270.266922) (xy 142.887192 -270.401542)
		)
		(stroke
			(width 0)
			(type solid)
		)
		(fill yes)
		(layer "F.Cu")
		(net "M_E_CPU1_SA_DQ<25>")
	)
	(gr_poly
		(pts
			(xy 142.987014 -265.105134) (xy 143.033496 -265.007598) (xy 142.898622 -264.872978) (xy 142.80134 -264.919206)
			(xy 142.765272 -264.95502) (xy 142.9512 -265.140948)
		)
		(stroke
			(width 0)
			(type solid)
		)
		(fill yes)
		(layer "F.Cu")
		(net "M_E_CPU1_SA_CB<2>")
	)
	(gr_poly
		(pts
			(xy 142.987014 -242.598956) (xy 142.950692 -242.497356) (xy 142.760192 -242.497356) (xy 142.724124 -242.598956)
			(xy 142.724124 -242.649756) (xy 142.987014 -242.649756)
		)
		(stroke
			(width 0)
			(type solid)
		)
		(fill yes)
		(layer "F.Cu")
		(net "M_E_CPU1_SB_CB<4>")
	)
	(gr_poly
		(pts
			(xy 142.987014 -242.294156) (xy 142.950692 -242.192556) (xy 142.760192 -242.192556) (xy 142.724124 -242.294156)
			(xy 142.724124 -242.344956) (xy 142.987014 -242.344956)
		)
		(stroke
			(width 0)
			(type solid)
		)
		(fill yes)
		(layer "F.Cu")
		(net "M_E_CPU1_SB_CB<6>")
	)
	(gr_poly
		(pts
			(xy 142.987014 -241.989356) (xy 142.950692 -241.887756) (xy 142.760192 -241.887756) (xy 142.724124 -241.989356)
			(xy 142.724124 -242.040156) (xy 142.987014 -242.040156)
		)
		(stroke
			(width 0)
			(type solid)
		)
		(fill yes)
		(layer "F.Cu")
		(net "M_E_CPU1_SB_CB<5>")
	)
	(gr_poly
		(pts
			(xy 142.987014 -241.684556) (xy 142.950692 -241.582956) (xy 142.760192 -241.582956) (xy 142.724124 -241.684556)
			(xy 142.724124 -241.735356) (xy 142.987014 -241.735356)
		)
		(stroke
			(width 0)
			(type solid)
		)
		(fill yes)
		(layer "F.Cu")
		(net "M_E_CPU1_SB_CB<7>")
	)
	(gr_poly
		(pts
			(xy 142.989554 -257.494532) (xy 143.035782 -257.39725) (xy 142.901162 -257.262376) (xy 142.803626 -257.308604)
			(xy 142.767812 -257.344672) (xy 142.95374 -257.5306)
		)
		(stroke
			(width 0)
			(type solid)
		)
		(fill yes)
		(layer "F.Cu")
		(net "M_E_CPU1_SA_CA<0>")
	)
	(gr_poly
		(pts
			(xy 142.99057 -276.655784) (xy 143.083026 -276.600412) (xy 143.045688 -276.413468) (xy 142.939008 -276.397974)
			(xy 142.889224 -276.40788) (xy 142.940786 -276.66569)
		)
		(stroke
			(width 0)
			(type solid)
		)
		(fill yes)
		(layer "F.Cu")
		(net "M_E_CPU1_SA_DQ<17>")
	)
	(gr_poly
		(pts
			(xy 142.996412 -264.251694) (xy 143.04264 -264.154158) (xy 142.90802 -264.019538) (xy 142.810484 -264.065766)
			(xy 142.77467 -264.101834) (xy 142.960344 -264.287508)
		)
		(stroke
			(width 0)
			(type solid)
		)
		(fill yes)
		(layer "F.Cu")
		(net "M_E_CPU1_SA_CB<3>")
	)
	(gr_poly
		(pts
			(xy 142.998698 -256.641346) (xy 143.044926 -256.54381) (xy 142.910306 -256.40919) (xy 142.813024 -256.455418)
			(xy 142.776956 -256.491232) (xy 142.962884 -256.67716)
		)
		(stroke
			(width 0)
			(type solid)
		)
		(fill yes)
		(layer "F.Cu")
		(net "M_E_CPU1_SA_CA<2>")
	)
	(gr_poly
		(pts
			(xy 142.999206 -276.958298) (xy 142.947644 -276.700488) (xy 142.89786 -276.710394) (xy 142.805404 -276.765766)
			(xy 142.842742 -276.95271) (xy 142.949422 -276.968204)
		)
		(stroke
			(width 0)
			(type solid)
		)
		(fill yes)
		(layer "F.Cu")
		(net "M_E_CPU1_SA_DQ<17>")
	)
	(gr_poly
		(pts
			(xy 143.007334 -237.479586) (xy 142.961106 -237.382304) (xy 142.925292 -237.346236) (xy 142.739364 -237.532164)
			(xy 142.775178 -237.567978) (xy 142.872714 -237.61446)
		)
		(stroke
			(width 0)
			(type solid)
		)
		(fill yes)
		(layer "F.Cu")
		(net "M_E_CPU1_SB_DQ<11>")
	)
	(gr_poly
		(pts
			(xy 143.008096 -255.787906) (xy 143.054324 -255.69037) (xy 142.91945 -255.55575) (xy 142.822168 -255.601978)
			(xy 142.7861 -255.637792) (xy 142.972028 -255.82372)
		)
		(stroke
			(width 0)
			(type solid)
		)
		(fill yes)
		(layer "F.Cu")
		(net "M_E_CPU1_SA_CA<4>")
	)
	(gr_poly
		(pts
			(xy 143.011398 -267.613384) (xy 143.057626 -267.515848) (xy 142.922752 -267.381228) (xy 142.82547 -267.427456)
			(xy 142.789402 -267.46327) (xy 142.97533 -267.649198)
		)
		(stroke
			(width 0)
			(type solid)
		)
		(fill yes)
		(layer "F.Cu")
		(net "M_E_CPU1_SA_DQ<28>")
	)
	(gr_poly
		(pts
			(xy 143.01724 -254.934466) (xy 143.063468 -254.837184) (xy 142.928848 -254.70231) (xy 142.831312 -254.748538)
			(xy 142.795498 -254.784606) (xy 142.981426 -254.970534)
		)
		(stroke
			(width 0)
			(type solid)
		)
		(fill yes)
		(layer "F.Cu")
		(net "M_E_CPU1_SA_CA<6>")
	)
	(gr_poly
		(pts
			(xy 143.020542 -266.759944) (xy 143.06677 -266.662408) (xy 142.93215 -266.527788) (xy 142.834868 -266.574016)
			(xy 142.7988 -266.60983) (xy 142.984728 -266.795758)
		)
		(stroke
			(width 0)
			(type solid)
		)
		(fill yes)
		(layer "F.Cu")
		(net "M_E_CPU1_SA_DQ<29>")
	)
	(gr_poly
		(pts
			(xy 143.03375 -273.261328) (xy 143.079978 -273.163792) (xy 142.945104 -273.029172) (xy 142.847822 -273.0754)
			(xy 142.811754 -273.111214) (xy 142.997682 -273.297142)
		)
		(stroke
			(width 0)
			(type solid)
		)
		(fill yes)
		(layer "F.Cu")
		(net "M_E_CPU1_SA_DQ<20>")
	)
	(gr_poly
		(pts
			(xy 143.042386 -278.471376) (xy 143.134842 -278.416004) (xy 143.097504 -278.229314) (xy 142.990824 -278.213566)
			(xy 142.94104 -278.223472) (xy 142.992602 -278.481282)
		)
		(stroke
			(width 0)
			(type solid)
		)
		(fill yes)
		(layer "F.Cu")
		(net "M_E_CPU1_SA_DQ<18>")
	)
	(gr_poly
		(pts
			(xy 143.043148 -272.407634) (xy 143.089376 -272.310098) (xy 142.954502 -272.175478) (xy 142.85722 -272.221706)
			(xy 142.821152 -272.25752) (xy 143.00708 -272.443448)
		)
		(stroke
			(width 0)
			(type solid)
		)
		(fill yes)
		(layer "F.Cu")
		(net "M_E_CPU1_SA_DQ<21>")
	)
	(gr_poly
		(pts
			(xy 143.044418 -261.711186) (xy 143.090646 -261.613904) (xy 142.956026 -261.47903) (xy 142.85849 -261.525258)
			(xy 142.822676 -261.561326) (xy 143.008604 -261.747254)
		)
		(stroke
			(width 0)
			(type solid)
		)
		(fill yes)
		(layer "F.Cu")
		(net "M_E_CPU1_SA_CB<6>")
	)
	(gr_poly
		(pts
			(xy 143.051022 -278.774144) (xy 142.99946 -278.516334) (xy 142.949676 -278.52624) (xy 142.85722 -278.581612)
			(xy 142.894558 -278.768302) (xy 143.001238 -278.78405)
		)
		(stroke
			(width 0)
			(type solid)
		)
		(fill yes)
		(layer "F.Cu")
		(net "M_E_CPU1_SA_DQ<18>")
	)
	(gr_poly
		(pts
			(xy 143.052038 -270.710152) (xy 143.098266 -270.612616) (xy 142.963646 -270.477996) (xy 142.86611 -270.524224)
			(xy 142.830296 -270.560292) (xy 143.01597 -270.745966)
		)
		(stroke
			(width 0)
			(type solid)
		)
		(fill yes)
		(layer "F.Cu")
		(net "M_E_CPU1_SA_DQ<26>")
	)
	(gr_poly
		(pts
			(xy 143.053562 -260.857746) (xy 143.09979 -260.760464) (xy 142.96517 -260.625844) (xy 142.867634 -260.672072)
			(xy 142.83182 -260.707886) (xy 143.017748 -260.893814)
		)
		(stroke
			(width 0)
			(type solid)
		)
		(fill yes)
		(layer "F.Cu")
		(net "M_E_CPU1_SA_CB<7>")
	)
	(gr_poly
		(pts
			(xy 143.057372 -228.607112) (xy 143.021304 -228.571298) (xy 142.924022 -228.52507) (xy 142.789148 -228.65969)
			(xy 142.83563 -228.757226) (xy 142.871444 -228.79304)
		)
		(stroke
			(width 0)
			(type solid)
		)
		(fill yes)
		(layer "F.Cu")
		(net "M_E_CPU1_SB_DQ<21>")
	)
	(gr_poly
		(pts
			(xy 143.059912 -225.009456) (xy 143.009112 -225.009456) (xy 142.907512 -225.045778) (xy 142.907512 -225.236278)
			(xy 143.009112 -225.272346) (xy 143.059912 -225.272346)
		)
		(stroke
			(width 0)
			(type solid)
		)
		(fill yes)
		(layer "F.Cu")
		(net "M_E_CPU1_SB_DQ<24>")
	)
	(gr_poly
		(pts
			(xy 143.059912 -224.412556) (xy 143.009112 -224.412556) (xy 142.907512 -224.448878) (xy 142.907512 -224.639378)
			(xy 143.009112 -224.675446) (xy 143.059912 -224.675446)
		)
		(stroke
			(width 0)
			(type solid)
		)
		(fill yes)
		(layer "F.Cu")
		(net "M_E_CPU1_SB_DQ<24>")
	)
	(gr_poly
		(pts
			(xy 143.059912 -223.815656) (xy 143.009112 -223.815656) (xy 142.907512 -223.851978) (xy 142.907512 -224.042478)
			(xy 143.009112 -224.078546) (xy 143.059912 -224.078546)
		)
		(stroke
			(width 0)
			(type solid)
		)
		(fill yes)
		(layer "F.Cu")
		(net "M_E_CPU1_SB_DQ<24>")
	)
	(gr_poly
		(pts
			(xy 143.059912 -223.218756) (xy 143.009112 -223.218756) (xy 142.907512 -223.255078) (xy 142.907512 -223.445578)
			(xy 143.009112 -223.481646) (xy 143.059912 -223.481646)
		)
		(stroke
			(width 0)
			(type solid)
		)
		(fill yes)
		(layer "F.Cu")
		(net "M_E_CPU1_SB_DQ<24>")
	)
	(gr_poly
		(pts
			(xy 143.059912 -222.621856) (xy 143.009112 -222.621856) (xy 142.907512 -222.658178) (xy 142.907512 -222.848678)
			(xy 143.009112 -222.884746) (xy 143.059912 -222.884746)
		)
		(stroke
			(width 0)
			(type solid)
		)
		(fill yes)
		(layer "F.Cu")
		(net "M_E_CPU1_SB_DQ<24>")
	)
	(gr_poly
		(pts
			(xy 143.059912 -222.024956) (xy 143.009112 -222.024956) (xy 142.907512 -222.061278) (xy 142.907512 -222.251778)
			(xy 143.009112 -222.287846) (xy 143.059912 -222.287846)
		)
		(stroke
			(width 0)
			(type solid)
		)
		(fill yes)
		(layer "F.Cu")
		(net "M_E_CPU1_SB_DQ<24>")
	)
	(gr_poly
		(pts
			(xy 143.059912 -221.428056) (xy 143.009112 -221.428056) (xy 142.907512 -221.464378) (xy 142.907512 -221.654878)
			(xy 143.009112 -221.690946) (xy 143.059912 -221.690946)
		)
		(stroke
			(width 0)
			(type solid)
		)
		(fill yes)
		(layer "F.Cu")
		(net "M_E_CPU1_SB_DQ<24>")
	)
	(gr_poly
		(pts
			(xy 143.059912 -220.831156) (xy 143.009112 -220.831156) (xy 142.907512 -220.867478) (xy 142.907512 -221.057978)
			(xy 143.009112 -221.094046) (xy 143.059912 -221.094046)
		)
		(stroke
			(width 0)
			(type solid)
		)
		(fill yes)
		(layer "F.Cu")
		(net "M_E_CPU1_SB_DQ<24>")
	)
	(gr_poly
		(pts
			(xy 143.059912 -220.234256) (xy 143.009112 -220.234256) (xy 142.907512 -220.270578) (xy 142.907512 -220.461078)
			(xy 143.009112 -220.497146) (xy 143.059912 -220.497146)
		)
		(stroke
			(width 0)
			(type solid)
		)
		(fill yes)
		(layer "F.Cu")
		(net "M_E_CPU1_SB_DQ<24>")
	)
	(gr_poly
		(pts
			(xy 143.059912 -219.637356) (xy 143.009112 -219.637356) (xy 142.907512 -219.673678) (xy 142.907512 -219.864178)
			(xy 143.009112 -219.900246) (xy 143.059912 -219.900246)
		)
		(stroke
			(width 0)
			(type solid)
		)
		(fill yes)
		(layer "F.Cu")
		(net "M_E_CPU1_SB_DQ<24>")
	)
	(gr_poly
		(pts
			(xy 143.059912 -219.040456) (xy 143.009112 -219.040456) (xy 142.907512 -219.076778) (xy 142.907512 -219.267278)
			(xy 143.009112 -219.303346) (xy 143.059912 -219.303346)
		)
		(stroke
			(width 0)
			(type solid)
		)
		(fill yes)
		(layer "F.Cu")
		(net "M_E_CPU1_SB_DQ<24>")
	)
	(gr_poly
		(pts
			(xy 143.059912 -218.443556) (xy 143.009112 -218.443556) (xy 142.907512 -218.479878) (xy 142.907512 -218.670378)
			(xy 143.009112 -218.706446) (xy 143.059912 -218.706446)
		)
		(stroke
			(width 0)
			(type solid)
		)
		(fill yes)
		(layer "F.Cu")
		(net "M_E_CPU1_SB_DQ<24>")
	)
	(gr_poly
		(pts
			(xy 143.059912 -217.846656) (xy 143.009112 -217.846656) (xy 142.907512 -217.882978) (xy 142.907512 -218.073478)
			(xy 143.009112 -218.109546) (xy 143.059912 -218.109546)
		)
		(stroke
			(width 0)
			(type solid)
		)
		(fill yes)
		(layer "F.Cu")
		(net "M_E_CPU1_SB_DQ<24>")
	)
	(gr_poly
		(pts
			(xy 143.059912 -217.249756) (xy 143.009112 -217.249756) (xy 142.907512 -217.286078) (xy 142.907512 -217.476578)
			(xy 143.009112 -217.512646) (xy 143.059912 -217.512646)
		)
		(stroke
			(width 0)
			(type solid)
		)
		(fill yes)
		(layer "F.Cu")
		(net "M_E_CPU1_SB_DQ<24>")
	)
	(gr_poly
		(pts
			(xy 143.059912 -216.652856) (xy 143.009112 -216.652856) (xy 142.907512 -216.689178) (xy 142.907512 -216.879678)
			(xy 143.009112 -216.915746) (xy 143.059912 -216.915746)
		)
		(stroke
			(width 0)
			(type solid)
		)
		(fill yes)
		(layer "F.Cu")
		(net "M_E_CPU1_SB_DQ<24>")
	)
	(gr_poly
		(pts
			(xy 143.059912 -216.055956) (xy 143.009112 -216.055956) (xy 142.907512 -216.092278) (xy 142.907512 -216.282778)
			(xy 143.009112 -216.318846) (xy 143.059912 -216.318846)
		)
		(stroke
			(width 0)
			(type solid)
		)
		(fill yes)
		(layer "F.Cu")
		(net "M_E_CPU1_SB_DQ<24>")
	)
	(gr_poly
		(pts
			(xy 143.061182 -269.856712) (xy 143.10741 -269.759176) (xy 142.97279 -269.624556) (xy 142.875254 -269.670784)
			(xy 142.83944 -269.706852) (xy 143.025114 -269.892526)
		)
		(stroke
			(width 0)
			(type solid)
		)
		(fill yes)
		(layer "F.Cu")
		(net "M_E_CPU1_SA_DQ<27>")
	)
	(gr_poly
		(pts
			(xy 143.066516 -229.460552) (xy 143.030702 -229.424738) (xy 142.933166 -229.378256) (xy 142.798546 -229.51313)
			(xy 142.844774 -229.610412) (xy 142.880588 -229.64648)
		)
		(stroke
			(width 0)
			(type solid)
		)
		(fill yes)
		(layer "F.Cu")
		(net "M_E_CPU1_SB_DQ<20>")
	)
	(gr_poly
		(pts
			(xy 143.08455 -289.844226) (xy 143.03375 -289.844226) (xy 142.93215 -289.880548) (xy 142.93215 -290.071048)
			(xy 143.03375 -290.10737) (xy 143.08455 -290.10737)
		)
		(stroke
			(width 0)
			(type solid)
		)
		(fill yes)
		(layer "F.Cu")
		(net "M_E_CPU1_SA_DQ<16>")
	)
	(gr_poly
		(pts
			(xy 143.08455 -289.247326) (xy 143.03375 -289.247326) (xy 142.93215 -289.283648) (xy 142.93215 -289.474148)
			(xy 143.03375 -289.51047) (xy 143.08455 -289.51047)
		)
		(stroke
			(width 0)
			(type solid)
		)
		(fill yes)
		(layer "F.Cu")
		(net "M_E_CPU1_SA_DQ<16>")
	)
	(gr_poly
		(pts
			(xy 143.08455 -288.650426) (xy 143.03375 -288.650426) (xy 142.93215 -288.686748) (xy 142.93215 -288.877248)
			(xy 143.03375 -288.91357) (xy 143.08455 -288.91357)
		)
		(stroke
			(width 0)
			(type solid)
		)
		(fill yes)
		(layer "F.Cu")
		(net "M_E_CPU1_SA_DQ<16>")
	)
	(gr_poly
		(pts
			(xy 143.08455 -288.053526) (xy 143.03375 -288.053526) (xy 142.93215 -288.089848) (xy 142.93215 -288.280348)
			(xy 143.03375 -288.31667) (xy 143.08455 -288.31667)
		)
		(stroke
			(width 0)
			(type solid)
		)
		(fill yes)
		(layer "F.Cu")
		(net "M_E_CPU1_SA_DQ<16>")
	)
	(gr_poly
		(pts
			(xy 143.08455 -287.456626) (xy 143.03375 -287.456626) (xy 142.93215 -287.492948) (xy 142.93215 -287.683448)
			(xy 143.03375 -287.71977) (xy 143.08455 -287.71977)
		)
		(stroke
			(width 0)
			(type solid)
		)
		(fill yes)
		(layer "F.Cu")
		(net "M_E_CPU1_SA_DQ<16>")
	)
	(gr_poly
		(pts
			(xy 143.08455 -286.859726) (xy 143.03375 -286.859726) (xy 142.93215 -286.896048) (xy 142.93215 -287.086548)
			(xy 143.03375 -287.12287) (xy 143.08455 -287.12287)
		)
		(stroke
			(width 0)
			(type solid)
		)
		(fill yes)
		(layer "F.Cu")
		(net "M_E_CPU1_SA_DQ<16>")
	)
	(gr_poly
		(pts
			(xy 143.08455 -286.262826) (xy 143.03375 -286.262826) (xy 142.93215 -286.299148) (xy 142.93215 -286.489648)
			(xy 143.03375 -286.52597) (xy 143.08455 -286.52597)
		)
		(stroke
			(width 0)
			(type solid)
		)
		(fill yes)
		(layer "F.Cu")
		(net "M_E_CPU1_SA_DQ<16>")
	)
	(gr_poly
		(pts
			(xy 143.08455 -285.665926) (xy 143.03375 -285.665926) (xy 142.93215 -285.702248) (xy 142.93215 -285.892748)
			(xy 143.03375 -285.92907) (xy 143.08455 -285.92907)
		)
		(stroke
			(width 0)
			(type solid)
		)
		(fill yes)
		(layer "F.Cu")
		(net "M_E_CPU1_SA_DQ<16>")
	)
	(gr_poly
		(pts
			(xy 143.08455 -285.069026) (xy 143.03375 -285.069026) (xy 142.93215 -285.105348) (xy 142.93215 -285.295848)
			(xy 143.03375 -285.33217) (xy 143.08455 -285.33217)
		)
		(stroke
			(width 0)
			(type solid)
		)
		(fill yes)
		(layer "F.Cu")
		(net "M_E_CPU1_SA_DQ<16>")
	)
	(gr_poly
		(pts
			(xy 143.08455 -284.472126) (xy 143.03375 -284.472126) (xy 142.93215 -284.508448) (xy 142.93215 -284.698948)
			(xy 143.03375 -284.73527) (xy 143.08455 -284.73527)
		)
		(stroke
			(width 0)
			(type solid)
		)
		(fill yes)
		(layer "F.Cu")
		(net "M_E_CPU1_SA_DQ<16>")
	)
	(gr_poly
		(pts
			(xy 143.08455 -283.875226) (xy 143.03375 -283.875226) (xy 142.93215 -283.911548) (xy 142.93215 -284.102048)
			(xy 143.03375 -284.13837) (xy 143.08455 -284.13837)
		)
		(stroke
			(width 0)
			(type solid)
		)
		(fill yes)
		(layer "F.Cu")
		(net "M_E_CPU1_SA_DQ<16>")
	)
	(gr_poly
		(pts
			(xy 143.08455 -283.278326) (xy 143.03375 -283.278326) (xy 142.93215 -283.314648) (xy 142.93215 -283.505148)
			(xy 143.03375 -283.54147) (xy 143.08455 -283.54147)
		)
		(stroke
			(width 0)
			(type solid)
		)
		(fill yes)
		(layer "F.Cu")
		(net "M_E_CPU1_SA_DQ<16>")
	)
	(gr_poly
		(pts
			(xy 143.08455 -282.681426) (xy 143.03375 -282.681426) (xy 142.93215 -282.717748) (xy 142.93215 -282.908248)
			(xy 143.03375 -282.94457) (xy 143.08455 -282.94457)
		)
		(stroke
			(width 0)
			(type solid)
		)
		(fill yes)
		(layer "F.Cu")
		(net "M_E_CPU1_SA_DQ<16>")
	)
	(gr_poly
		(pts
			(xy 143.08455 -282.084526) (xy 143.03375 -282.084526) (xy 142.93215 -282.120848) (xy 142.93215 -282.311348)
			(xy 143.03375 -282.34767) (xy 143.08455 -282.34767)
		)
		(stroke
			(width 0)
			(type solid)
		)
		(fill yes)
		(layer "F.Cu")
		(net "M_E_CPU1_SA_DQ<16>")
	)
	(gr_poly
		(pts
			(xy 143.08455 -281.487626) (xy 143.03375 -281.487626) (xy 142.93215 -281.523948) (xy 142.93215 -281.714448)
			(xy 143.03375 -281.75077) (xy 143.08455 -281.75077)
		)
		(stroke
			(width 0)
			(type solid)
		)
		(fill yes)
		(layer "F.Cu")
		(net "M_E_CPU1_SA_DQ<16>")
	)
	(gr_poly
		(pts
			(xy 143.08455 -280.890726) (xy 143.03375 -280.890726) (xy 142.93215 -280.927048) (xy 142.93215 -281.117548)
			(xy 143.03375 -281.15387) (xy 143.08455 -281.15387)
		)
		(stroke
			(width 0)
			(type solid)
		)
		(fill yes)
		(layer "F.Cu")
		(net "M_E_CPU1_SA_DQ<16>")
	)
	(gr_poly
		(pts
			(xy 143.093186 -280.287222) (xy 143.185642 -280.23185) (xy 143.148304 -280.04516) (xy 143.041624 -280.029666)
			(xy 142.99184 -280.039572) (xy 143.043402 -280.297382)
		)
		(stroke
			(width 0)
			(type solid)
		)
		(fill yes)
		(layer "F.Cu")
		(net "M_E_CPU1_SA_DQ<16>")
	)
	(gr_poly
		(pts
			(xy 143.09344 -232.021888) (xy 143.057372 -231.986074) (xy 142.96009 -231.939846) (xy 142.82547 -232.074466)
			(xy 142.871698 -232.172002) (xy 142.907512 -232.207816)
		)
		(stroke
			(width 0)
			(type solid)
		)
		(fill yes)
		(layer "F.Cu")
		(net "M_E_CPU1_SB_DQ<17>")
	)
	(gr_poly
		(pts
			(xy 143.102076 -233.719116) (xy 143.066262 -233.683048) (xy 142.968726 -233.63682) (xy 142.834106 -233.77144)
			(xy 142.880334 -233.868976) (xy 142.916402 -233.90479)
		)
		(stroke
			(width 0)
			(type solid)
		)
		(fill yes)
		(layer "F.Cu")
		(net "M_E_CPU1_SB_DQ<15>")
	)
	(gr_poly
		(pts
			(xy 143.102584 -232.875328) (xy 143.06677 -232.83926) (xy 142.969234 -232.793032) (xy 142.834614 -232.927906)
			(xy 142.880842 -233.025188) (xy 142.916656 -233.061256)
		)
		(stroke
			(width 0)
			(type solid)
		)
		(fill yes)
		(layer "F.Cu")
		(net "M_E_CPU1_SB_DQ<16>")
	)
	(gr_poly
		(pts
			(xy 143.107664 -277.241) (xy 143.20012 -277.185628) (xy 143.162782 -276.998938) (xy 143.056102 -276.98319)
			(xy 143.006318 -276.993096) (xy 143.05788 -277.250906)
		)
		(stroke
			(width 0)
			(type solid)
		)
		(fill yes)
		(layer "F.Cu")
		(net "M_E_CPU1_SA_DQ<17>")
	)
	(gr_poly
		(pts
			(xy 143.110204 -259.484368) (xy 143.146018 -259.4483) (xy 142.960344 -259.262626) (xy 142.924276 -259.29844)
			(xy 142.878048 -259.395976) (xy 143.012668 -259.530596)
		)
		(stroke
			(width 0)
			(type solid)
		)
		(fill yes)
		(layer "F.Cu")
		(net "M_E_CPU1_SA_CS_N<0>")
	)
	(gr_poly
		(pts
			(xy 143.111474 -234.572302) (xy 143.075406 -234.536488) (xy 142.978124 -234.49026) (xy 142.84325 -234.62488)
			(xy 142.889478 -234.722416) (xy 142.925546 -234.75823)
		)
		(stroke
			(width 0)
			(type solid)
		)
		(fill yes)
		(layer "F.Cu")
		(net "M_E_CPU1_SB_DQ<14>")
	)
	(gr_poly
		(pts
			(xy 143.1163 -277.543514) (xy 143.064738 -277.285958) (xy 143.014954 -277.295864) (xy 142.922498 -277.351236)
			(xy 142.959836 -277.537926) (xy 143.066516 -277.553674)
		)
		(stroke
			(width 0)
			(type solid)
		)
		(fill yes)
		(layer "F.Cu")
		(net "M_E_CPU1_SA_DQ<17>")
	)
	(gr_poly
		(pts
			(xy 143.119602 -258.630928) (xy 143.155416 -258.59486) (xy 142.969488 -258.408932) (xy 142.933674 -258.445)
			(xy 142.887446 -258.542282) (xy 143.022066 -258.677156)
		)
		(stroke
			(width 0)
			(type solid)
		)
		(fill yes)
		(layer "F.Cu")
		(net "M_E_CPU1_SA_CS_N<1>")
	)
	(gr_poly
		(pts
			(xy 143.12646 -265.387836) (xy 143.162274 -265.352022) (xy 142.976346 -265.166094) (xy 142.940532 -265.201908)
			(xy 142.894304 -265.299444) (xy 143.028924 -265.434064)
		)
		(stroke
			(width 0)
			(type solid)
		)
		(fill yes)
		(layer "F.Cu")
		(net "M_E_CPU1_SA_CB<2>")
	)
	(gr_poly
		(pts
			(xy 143.128746 -257.777488) (xy 143.164814 -257.741674) (xy 142.978886 -257.555746) (xy 142.942818 -257.59156)
			(xy 142.89659 -257.689096) (xy 143.031464 -257.823716)
		)
		(stroke
			(width 0)
			(type solid)
		)
		(fill yes)
		(layer "F.Cu")
		(net "M_E_CPU1_SA_CA<0>")
	)
	(gr_poly
		(pts
			(xy 143.134842 -228.313742) (xy 143.088614 -228.21646) (xy 143.0528 -228.180392) (xy 142.866872 -228.36632)
			(xy 142.902686 -228.402388) (xy 143.000222 -228.448616)
		)
		(stroke
			(width 0)
			(type solid)
		)
		(fill yes)
		(layer "F.Cu")
		(net "M_E_CPU1_SB_DQ<23>")
	)
	(gr_poly
		(pts
			(xy 143.135604 -264.53465) (xy 143.171418 -264.498582) (xy 142.98549 -264.312654) (xy 142.949676 -264.348722)
			(xy 142.903448 -264.446004) (xy 143.038068 -264.580878)
		)
		(stroke
			(width 0)
			(type solid)
		)
		(fill yes)
		(layer "F.Cu")
		(net "M_E_CPU1_SA_CB<3>")
	)
	(gr_poly
		(pts
			(xy 143.136366 -237.135162) (xy 143.100298 -237.099348) (xy 143.003016 -237.05312) (xy 142.868142 -237.18774)
			(xy 142.91437 -237.285276) (xy 142.950438 -237.32109)
		)
		(stroke
			(width 0)
			(type solid)
		)
		(fill yes)
		(layer "F.Cu")
		(net "M_E_CPU1_SB_DQ<11>")
	)
	(gr_poly
		(pts
			(xy 143.13789 -256.924048) (xy 143.173958 -256.888234) (xy 142.98803 -256.702306) (xy 142.952216 -256.73812)
			(xy 142.905734 -256.835656) (xy 143.040608 -256.970276)
		)
		(stroke
			(width 0)
			(type solid)
		)
		(fill yes)
		(layer "F.Cu")
		(net "M_E_CPU1_SA_CA<2>")
	)
	(gr_poly
		(pts
			(xy 143.143986 -229.167182) (xy 143.097758 -229.069646) (xy 143.061944 -229.033832) (xy 142.876016 -229.21976)
			(xy 142.91183 -229.255574) (xy 143.009366 -229.301802)
		)
		(stroke
			(width 0)
			(type solid)
		)
		(fill yes)
		(layer "F.Cu")
		(net "M_E_CPU1_SB_DQ<22>")
	)
	(gr_poly
		(pts
			(xy 143.146272 -237.989364) (xy 143.110458 -237.95355) (xy 143.012922 -237.907322) (xy 142.878302 -238.041942)
			(xy 142.92453 -238.139224) (xy 142.960344 -238.175292)
		)
		(stroke
			(width 0)
			(type solid)
		)
		(fill yes)
		(layer "F.Cu")
		(net "M_E_CPU1_SB_DQ<10>")
	)
	(gr_poly
		(pts
			(xy 143.147288 -256.070862) (xy 143.183102 -256.034794) (xy 142.997174 -255.848866) (xy 142.96136 -255.884934)
			(xy 142.915132 -255.982216) (xy 143.049752 -256.11709)
		)
		(stroke
			(width 0)
			(type solid)
		)
		(fill yes)
		(layer "F.Cu")
		(net "M_E_CPU1_SA_CA<4>")
	)
	(gr_poly
		(pts
			(xy 143.15059 -267.896086) (xy 143.186404 -267.860272) (xy 143.000476 -267.674344) (xy 142.964662 -267.710412)
			(xy 142.918434 -267.807694) (xy 143.053054 -267.942568)
		)
		(stroke
			(width 0)
			(type solid)
		)
		(fill yes)
		(layer "F.Cu")
		(net "M_E_CPU1_SA_DQ<28>")
	)
	(gr_poly
		(pts
			(xy 143.156432 -255.217422) (xy 143.192246 -255.181354) (xy 143.006572 -254.99568) (xy 142.970504 -255.031494)
			(xy 142.924276 -255.12903) (xy 143.058896 -255.26365)
		)
		(stroke
			(width 0)
			(type solid)
		)
		(fill yes)
		(layer "F.Cu")
		(net "M_E_CPU1_SA_CA<6>")
	)
	(gr_poly
		(pts
			(xy 143.157448 -248.967752) (xy 143.12138 -248.866152) (xy 142.93088 -248.866152) (xy 142.894812 -248.967752)
			(xy 142.894812 -249.018552) (xy 143.157448 -249.018552)
		)
		(stroke
			(width 0)
			(type solid)
		)
		(fill yes)
		(layer "F.Cu")
		(net "M_E_CPU1_SB_CA<0>")
	)
	(gr_poly
		(pts
			(xy 143.157448 -248.662952) (xy 143.12138 -248.561352) (xy 142.93088 -248.561352) (xy 142.894812 -248.662952)
			(xy 142.894812 -248.713752) (xy 143.157448 -248.713752)
		)
		(stroke
			(width 0)
			(type solid)
		)
		(fill yes)
		(layer "F.Cu")
		(net "M_E_CPU1_SB_CA<1>")
	)
	(gr_poly
		(pts
			(xy 143.157448 -248.358152) (xy 143.12138 -248.256552) (xy 142.93088 -248.256552) (xy 142.894812 -248.358152)
			(xy 142.894812 -248.408952) (xy 143.157448 -248.408952)
		)
		(stroke
			(width 0)
			(type solid)
		)
		(fill yes)
		(layer "F.Cu")
		(net "M_E_CPU1_SB_CA<2>")
	)
	(gr_poly
		(pts
			(xy 143.157448 -248.053352) (xy 143.12138 -247.951752) (xy 142.93088 -247.951752) (xy 142.894812 -248.053352)
			(xy 142.894812 -248.104152) (xy 143.157448 -248.104152)
		)
		(stroke
			(width 0)
			(type solid)
		)
		(fill yes)
		(layer "F.Cu")
		(net "M_E_CPU1_SB_CA<3>")
	)
	(gr_poly
		(pts
			(xy 143.157448 -247.748552) (xy 143.12138 -247.646952) (xy 142.93088 -247.646952) (xy 142.894812 -247.748552)
			(xy 142.894812 -247.799352) (xy 143.157448 -247.799352)
		)
		(stroke
			(width 0)
			(type solid)
		)
		(fill yes)
		(layer "F.Cu")
		(net "M_E_CPU1_SB_CA<4>")
	)
	(gr_poly
		(pts
			(xy 143.157448 -247.443752) (xy 143.12138 -247.342152) (xy 142.93088 -247.342152) (xy 142.894812 -247.443752)
			(xy 142.894812 -247.494552) (xy 143.157448 -247.494552)
		)
		(stroke
			(width 0)
			(type solid)
		)
		(fill yes)
		(layer "F.Cu")
		(net "M_E_CPU1_SB_CA<5>")
	)
	(gr_poly
		(pts
			(xy 143.157448 -247.138952) (xy 143.12138 -247.037352) (xy 142.93088 -247.037352) (xy 142.894812 -247.138952)
			(xy 142.894812 -247.189752) (xy 143.157448 -247.189752)
		)
		(stroke
			(width 0)
			(type solid)
		)
		(fill yes)
		(layer "F.Cu")
		(net "M_E_CPU1_SB_CA<6>")
	)
	(gr_poly
		(pts
			(xy 143.157448 -246.834152) (xy 143.12138 -246.732552) (xy 142.93088 -246.732552) (xy 142.894812 -246.834152)
			(xy 142.894812 -246.884952) (xy 143.157448 -246.884952)
		)
		(stroke
			(width 0)
			(type solid)
		)
		(fill yes)
		(layer "F.Cu")
		(net "M_E_CPU1_SB_PAR")
	)
	(gr_poly
		(pts
			(xy 143.157448 -246.529352) (xy 143.12138 -246.427752) (xy 142.93088 -246.427752) (xy 142.894812 -246.529352)
			(xy 142.894812 -246.580152) (xy 143.157448 -246.580152)
		)
		(stroke
			(width 0)
			(type solid)
		)
		(fill yes)
		(layer "F.Cu")
		(net "M_E_CPU1_SB_CS_N<0>")
	)
	(gr_poly
		(pts
			(xy 143.157448 -246.224552) (xy 143.12138 -246.122952) (xy 142.93088 -246.122952) (xy 142.894812 -246.224552)
			(xy 142.894812 -246.275352) (xy 143.157448 -246.275352)
		)
		(stroke
			(width 0)
			(type solid)
		)
		(fill yes)
		(layer "F.Cu")
		(net "M_E_CPU1_SB_CS_N<2>")
	)
	(gr_poly
		(pts
			(xy 143.15948 -279.056592) (xy 143.251936 -279.00122) (xy 143.214598 -278.81453) (xy 143.107918 -278.799036)
			(xy 143.058134 -278.808942) (xy 143.109696 -279.066752)
		)
		(stroke
			(width 0)
			(type solid)
		)
		(fill yes)
		(layer "F.Cu")
		(net "M_E_CPU1_SA_DQ<18>")
	)
	(gr_poly
		(pts
			(xy 143.159734 -267.042646) (xy 143.195802 -267.006832) (xy 143.009874 -266.820904) (xy 142.97406 -266.856718)
			(xy 142.927578 -266.954254) (xy 143.062452 -267.088874)
		)
		(stroke
			(width 0)
			(type solid)
		)
		(fill yes)
		(layer "F.Cu")
		(net "M_E_CPU1_SA_DQ<29>")
	)
	(gr_poly
		(pts
			(xy 143.168116 -279.35936) (xy 143.116554 -279.10155) (xy 143.06677 -279.111456) (xy 142.974314 -279.166828)
			(xy 143.011652 -279.353772) (xy 143.118332 -279.369266)
		)
		(stroke
			(width 0)
			(type solid)
		)
		(fill yes)
		(layer "F.Cu")
		(net "M_E_CPU1_SA_DQ<18>")
	)
	(gr_poly
		(pts
			(xy 143.17091 -231.728518) (xy 143.124682 -231.631236) (xy 143.088868 -231.595168) (xy 142.90294 -231.781096)
			(xy 142.938754 -231.817164) (xy 143.03629 -231.863392)
		)
		(stroke
			(width 0)
			(type solid)
		)
		(fill yes)
		(layer "F.Cu")
		(net "M_E_CPU1_SB_DQ<19>")
	)
	(gr_poly
		(pts
			(xy 143.172942 -273.54403) (xy 143.208756 -273.508216) (xy 143.022828 -273.322288) (xy 142.987014 -273.358356)
			(xy 142.940786 -273.455638) (xy 143.075406 -273.590258)
		)
		(stroke
			(width 0)
			(type solid)
		)
		(fill yes)
		(layer "F.Cu")
		(net "M_E_CPU1_SA_DQ<20>")
	)
	(gr_poly
		(pts
			(xy 143.173196 -276.010624) (xy 143.265906 -275.955252) (xy 143.228568 -275.768308) (xy 143.121634 -275.752814)
			(xy 143.07185 -275.76272) (xy 143.123412 -276.02053)
		)
		(stroke
			(width 0)
			(type solid)
		)
		(fill yes)
		(layer "F.Cu")
		(net "M_E_CPU1_SA_DQ<19>")
	)
	(gr_poly
		(pts
			(xy 143.180308 -232.581958) (xy 143.133826 -232.484422) (xy 143.098012 -232.448608) (xy 142.912084 -232.634536)
			(xy 142.948152 -232.67035) (xy 143.045434 -232.716578)
		)
		(stroke
			(width 0)
			(type solid)
		)
		(fill yes)
		(layer "F.Cu")
		(net "M_E_CPU1_SB_DQ<18>")
	)
	(gr_poly
		(pts
			(xy 143.181832 -276.313138) (xy 143.130524 -276.055328) (xy 143.080486 -276.065234) (xy 142.98803 -276.120606)
			(xy 143.025368 -276.30755) (xy 143.132048 -276.323044)
		)
		(stroke
			(width 0)
			(type solid)
		)
		(fill yes)
		(layer "F.Cu")
		(net "M_E_CPU1_SA_DQ<19>")
	)
	(gr_poly
		(pts
			(xy 143.18234 -272.69059) (xy 143.218154 -272.654522) (xy 143.032226 -272.468594) (xy 142.996412 -272.504662)
			(xy 142.950184 -272.601944) (xy 143.084804 -272.736818)
		)
		(stroke
			(width 0)
			(type solid)
		)
		(fill yes)
		(layer "F.Cu")
		(net "M_E_CPU1_SA_DQ<21>")
	)
	(gr_poly
		(pts
			(xy 143.18361 -261.994142) (xy 143.219424 -261.958074) (xy 143.03375 -261.7724) (xy 142.997682 -261.808214)
			(xy 142.951454 -261.90575) (xy 143.086074 -262.04037)
		)
		(stroke
			(width 0)
			(type solid)
		)
		(fill yes)
		(layer "F.Cu")
		(net "M_E_CPU1_SA_CB<6>")
	)
	(gr_poly
		(pts
			(xy 143.186912 -258.985766) (xy 143.23314 -258.88823) (xy 143.098266 -258.75361) (xy 143.000984 -258.799838)
			(xy 142.964916 -258.835652) (xy 143.150844 -259.02158)
		)
		(stroke
			(width 0)
			(type solid)
		)
		(fill yes)
		(layer "F.Cu")
		(net "M_E_CPU1_SA_CS_N<2>")
	)
	(gr_poly
		(pts
			(xy 143.188944 -234.278932) (xy 143.142716 -234.18165) (xy 143.106902 -234.145582) (xy 142.920974 -234.33151)
			(xy 142.956788 -234.367578) (xy 143.054324 -234.413806)
		)
		(stroke
			(width 0)
			(type solid)
		)
		(fill yes)
		(layer "F.Cu")
		(net "M_E_CPU1_SB_DQ<13>")
	)
	(gr_poly
		(pts
			(xy 143.19123 -270.993108) (xy 143.227044 -270.95704) (xy 143.041116 -270.771112) (xy 143.005302 -270.80718)
			(xy 142.959074 -270.904462) (xy 143.093694 -271.039336)
		)
		(stroke
			(width 0)
			(type solid)
		)
		(fill yes)
		(layer "F.Cu")
		(net "M_E_CPU1_SA_DQ<26>")
	)
	(gr_poly
		(pts
			(xy 143.192754 -261.140702) (xy 143.228822 -261.104888) (xy 143.042894 -260.91896) (xy 143.006826 -260.954774)
			(xy 142.960598 -261.05231) (xy 143.095472 -261.18693)
		)
		(stroke
			(width 0)
			(type solid)
		)
		(fill yes)
		(layer "F.Cu")
		(net "M_E_CPU1_SA_CB<7>")
	)
	(gr_poly
		(pts
			(xy 143.193516 -265.742674) (xy 143.239744 -265.645392) (xy 143.105124 -265.510518) (xy 143.007588 -265.556746)
			(xy 142.971774 -265.592814) (xy 143.157702 -265.778742)
		)
		(stroke
			(width 0)
			(type solid)
		)
		(fill yes)
		(layer "F.Cu")
		(net "M_E_CPU1_SA_CB<0>")
	)
	(gr_poly
		(pts
			(xy 143.196056 -258.132326) (xy 143.242284 -258.03479) (xy 143.107664 -257.90017) (xy 143.010128 -257.946398)
			(xy 142.974314 -257.982466) (xy 143.159988 -258.16814)
		)
		(stroke
			(width 0)
			(type solid)
		)
		(fill yes)
		(layer "F.Cu")
		(net "M_E_CPU1_SA_CS_N<3>")
	)
	(gr_poly
		(pts
			(xy 143.198088 -235.132372) (xy 143.15186 -235.034836) (xy 143.116046 -234.999022) (xy 142.930118 -235.18495)
			(xy 142.965932 -235.220764) (xy 143.063468 -235.266992)
		)
		(stroke
			(width 0)
			(type solid)
		)
		(fill yes)
		(layer "F.Cu")
		(net "M_E_CPU1_SB_DQ<12>")
	)
	(gr_poly
		(pts
			(xy 143.200374 -270.139668) (xy 143.236188 -270.1036) (xy 143.05026 -269.917672) (xy 143.014446 -269.95374)
			(xy 142.968218 -270.051022) (xy 143.102838 -270.185896)
		)
		(stroke
			(width 0)
			(type solid)
		)
		(fill yes)
		(layer "F.Cu")
		(net "M_E_CPU1_SA_DQ<27>")
	)
	(gr_poly
		(pts
			(xy 143.20266 -264.889488) (xy 143.249142 -264.791952) (xy 143.114268 -264.657332) (xy 143.016986 -264.70356)
			(xy 142.980918 -264.739374) (xy 143.166846 -264.925302)
		)
		(stroke
			(width 0)
			(type solid)
		)
		(fill yes)
		(layer "F.Cu")
		(net "M_E_CPU1_SA_CB<1>")
	)
	(gr_poly
		(pts
			(xy 143.2052 -257.278886) (xy 143.251428 -257.181604) (xy 143.116808 -257.04673) (xy 143.019272 -257.092958)
			(xy 142.983458 -257.129026) (xy 143.169386 -257.314954)
		)
		(stroke
			(width 0)
			(type solid)
		)
		(fill yes)
		(layer "F.Cu")
		(net "M_E_CPU1_SA_CA<1>")
	)
	(gr_poly
		(pts
			(xy 143.212312 -224.937574) (xy 143.212312 -224.747074) (xy 143.110712 -224.711006) (xy 143.059912 -224.711006)
			(xy 143.059912 -224.973896) (xy 143.110712 -224.973896)
		)
		(stroke
			(width 0)
			(type solid)
		)
		(fill yes)
		(layer "F.Cu")
		(net "M_E_CPU1_SB_DQ<24>")
	)
	(gr_poly
		(pts
			(xy 143.212312 -224.340674) (xy 143.212312 -224.150174) (xy 143.110712 -224.114106) (xy 143.059912 -224.114106)
			(xy 143.059912 -224.376996) (xy 143.110712 -224.376996)
		)
		(stroke
			(width 0)
			(type solid)
		)
		(fill yes)
		(layer "F.Cu")
		(net "M_E_CPU1_SB_DQ<24>")
	)
	(gr_poly
		(pts
			(xy 143.212312 -223.743774) (xy 143.212312 -223.553274) (xy 143.110712 -223.517206) (xy 143.059912 -223.517206)
			(xy 143.059912 -223.780096) (xy 143.110712 -223.780096)
		)
		(stroke
			(width 0)
			(type solid)
		)
		(fill yes)
		(layer "F.Cu")
		(net "M_E_CPU1_SB_DQ<24>")
	)
	(gr_poly
		(pts
			(xy 143.212312 -223.146874) (xy 143.212312 -222.956374) (xy 143.110712 -222.920306) (xy 143.059912 -222.920306)
			(xy 143.059912 -223.183196) (xy 143.110712 -223.183196)
		)
		(stroke
			(width 0)
			(type solid)
		)
		(fill yes)
		(layer "F.Cu")
		(net "M_E_CPU1_SB_DQ<24>")
	)
	(gr_poly
		(pts
			(xy 143.212312 -222.549974) (xy 143.212312 -222.359474) (xy 143.110712 -222.323406) (xy 143.059912 -222.323406)
			(xy 143.059912 -222.586296) (xy 143.110712 -222.586296)
		)
		(stroke
			(width 0)
			(type solid)
		)
		(fill yes)
		(layer "F.Cu")
		(net "M_E_CPU1_SB_DQ<24>")
	)
	(gr_poly
		(pts
			(xy 143.212312 -221.953074) (xy 143.212312 -221.762574) (xy 143.110712 -221.726506) (xy 143.059912 -221.726506)
			(xy 143.059912 -221.989396) (xy 143.110712 -221.989396)
		)
		(stroke
			(width 0)
			(type solid)
		)
		(fill yes)
		(layer "F.Cu")
		(net "M_E_CPU1_SB_DQ<24>")
	)
	(gr_poly
		(pts
			(xy 143.212312 -221.356174) (xy 143.212312 -221.165674) (xy 143.110712 -221.129606) (xy 143.059912 -221.129606)
			(xy 143.059912 -221.392496) (xy 143.110712 -221.392496)
		)
		(stroke
			(width 0)
			(type solid)
		)
		(fill yes)
		(layer "F.Cu")
		(net "M_E_CPU1_SB_DQ<24>")
	)
	(gr_poly
		(pts
			(xy 143.212312 -220.759274) (xy 143.212312 -220.568774) (xy 143.110712 -220.532706) (xy 143.059912 -220.532706)
			(xy 143.059912 -220.795596) (xy 143.110712 -220.795596)
		)
		(stroke
			(width 0)
			(type solid)
		)
		(fill yes)
		(layer "F.Cu")
		(net "M_E_CPU1_SB_DQ<24>")
	)
	(gr_poly
		(pts
			(xy 143.212312 -220.162374) (xy 143.212312 -219.971874) (xy 143.110712 -219.935806) (xy 143.059912 -219.935806)
			(xy 143.059912 -220.198696) (xy 143.110712 -220.198696)
		)
		(stroke
			(width 0)
			(type solid)
		)
		(fill yes)
		(layer "F.Cu")
		(net "M_E_CPU1_SB_DQ<24>")
	)
	(gr_poly
		(pts
			(xy 143.212312 -219.565474) (xy 143.212312 -219.374974) (xy 143.110712 -219.338906) (xy 143.059912 -219.338906)
			(xy 143.059912 -219.601796) (xy 143.110712 -219.601796)
		)
		(stroke
			(width 0)
			(type solid)
		)
		(fill yes)
		(layer "F.Cu")
		(net "M_E_CPU1_SB_DQ<24>")
	)
	(gr_poly
		(pts
			(xy 143.212312 -218.968574) (xy 143.212312 -218.778074) (xy 143.110712 -218.742006) (xy 143.059912 -218.742006)
			(xy 143.059912 -219.004896) (xy 143.110712 -219.004896)
		)
		(stroke
			(width 0)
			(type solid)
		)
		(fill yes)
		(layer "F.Cu")
		(net "M_E_CPU1_SB_DQ<24>")
	)
	(gr_poly
		(pts
			(xy 143.212312 -218.371674) (xy 143.212312 -218.181174) (xy 143.110712 -218.145106) (xy 143.059912 -218.145106)
			(xy 143.059912 -218.407996) (xy 143.110712 -218.407996)
		)
		(stroke
			(width 0)
			(type solid)
		)
		(fill yes)
		(layer "F.Cu")
		(net "M_E_CPU1_SB_DQ<24>")
	)
	(gr_poly
		(pts
			(xy 143.212312 -217.774774) (xy 143.212312 -217.584274) (xy 143.110712 -217.548206) (xy 143.059912 -217.548206)
			(xy 143.059912 -217.811096) (xy 143.110712 -217.811096)
		)
		(stroke
			(width 0)
			(type solid)
		)
		(fill yes)
		(layer "F.Cu")
		(net "M_E_CPU1_SB_DQ<24>")
	)
	(gr_poly
		(pts
			(xy 143.212312 -217.177874) (xy 143.212312 -216.987374) (xy 143.110712 -216.951306) (xy 143.059912 -216.951306)
			(xy 143.059912 -217.214196) (xy 143.110712 -217.214196)
		)
		(stroke
			(width 0)
			(type solid)
		)
		(fill yes)
		(layer "F.Cu")
		(net "M_E_CPU1_SB_DQ<24>")
	)
	(gr_poly
		(pts
			(xy 143.212312 -216.580974) (xy 143.212312 -216.390474) (xy 143.110712 -216.354406) (xy 143.059912 -216.354406)
			(xy 143.059912 -216.617296) (xy 143.110712 -216.617296)
		)
		(stroke
			(width 0)
			(type solid)
		)
		(fill yes)
		(layer "F.Cu")
		(net "M_E_CPU1_SB_DQ<24>")
	)
	(gr_poly
		(pts
			(xy 143.212312 -215.984074) (xy 143.212312 -215.793574) (xy 143.110712 -215.757506) (xy 143.059912 -215.757506)
			(xy 143.059912 -216.020396) (xy 143.110712 -216.020396)
		)
		(stroke
			(width 0)
			(type solid)
		)
		(fill yes)
		(layer "F.Cu")
		(net "M_E_CPU1_SB_DQ<24>")
	)
	(gr_poly
		(pts
			(xy 143.214344 -256.4257) (xy 143.260572 -256.328164) (xy 143.125952 -256.193544) (xy 143.02867 -256.239772)
			(xy 142.992602 -256.275586) (xy 143.17853 -256.461514)
		)
		(stroke
			(width 0)
			(type solid)
		)
		(fill yes)
		(layer "F.Cu")
		(net "M_E_CPU1_SA_CA<3>")
	)
	(gr_poly
		(pts
			(xy 143.22298 -237.695232) (xy 143.176752 -237.59795) (xy 143.140938 -237.561882) (xy 142.95501 -237.74781)
			(xy 142.991078 -237.783878) (xy 143.08836 -237.830106)
		)
		(stroke
			(width 0)
			(type solid)
		)
		(fill yes)
		(layer "F.Cu")
		(net "M_E_CPU1_SB_DQ<9>")
	)
	(gr_poly
		(pts
			(xy 143.223742 -255.57226) (xy 143.26997 -255.474724) (xy 143.135096 -255.340104) (xy 143.037814 -255.386332)
			(xy 143.001746 -255.422146) (xy 143.187674 -255.608074)
		)
		(stroke
			(width 0)
			(type solid)
		)
		(fill yes)
		(layer "F.Cu")
		(net "M_E_CPU1_SA_CA<5>")
	)
	(gr_poly
		(pts
			(xy 143.224504 -277.826216) (xy 143.317214 -277.770844) (xy 143.279876 -277.584154) (xy 143.173196 -277.56866)
			(xy 143.123158 -277.578566) (xy 143.17472 -277.836376)
		)
		(stroke
			(width 0)
			(type solid)
		)
		(fill yes)
		(layer "F.Cu")
		(net "M_E_CPU1_SA_DQ<17>")
	)
	(gr_poly
		(pts
			(xy 143.227044 -267.397738) (xy 143.273272 -267.300202) (xy 143.138398 -267.165582) (xy 143.041116 -267.21181)
			(xy 143.005048 -267.247624) (xy 143.190976 -267.433552)
		)
		(stroke
			(width 0)
			(type solid)
		)
		(fill yes)
		(layer "F.Cu")
		(net "M_E_CPU1_SA_DQ<30>")
	)
	(gr_poly
		(pts
			(xy 143.232886 -254.71882) (xy 143.279114 -254.621538) (xy 143.144494 -254.486664) (xy 143.046958 -254.532892)
			(xy 143.011144 -254.56896) (xy 143.197072 -254.754888)
		)
		(stroke
			(width 0)
			(type solid)
		)
		(fill yes)
		(layer "F.Cu")
		(net "M_E_CPU1_SA_PAR")
	)
	(gr_poly
		(pts
			(xy 143.23314 -238.549434) (xy 143.186912 -238.452152) (xy 143.151098 -238.416084) (xy 142.96517 -238.602012)
			(xy 143.000984 -238.63808) (xy 143.09852 -238.684308)
		)
		(stroke
			(width 0)
			(type solid)
		)
		(fill yes)
		(layer "F.Cu")
		(net "M_E_CPU1_SB_DQ<8>")
	)
	(gr_poly
		(pts
			(xy 143.233394 -278.128984) (xy 143.181832 -277.871174) (xy 143.132048 -277.88108) (xy 143.039338 -277.936452)
			(xy 143.076676 -278.123396) (xy 143.18361 -278.13889)
		)
		(stroke
			(width 0)
			(type solid)
		)
		(fill yes)
		(layer "F.Cu")
		(net "M_E_CPU1_SA_DQ<17>")
	)
	(gr_poly
		(pts
			(xy 143.236442 -266.544044) (xy 143.28267 -266.446508) (xy 143.14805 -266.311888) (xy 143.050514 -266.358116)
			(xy 143.0147 -266.394184) (xy 143.200374 -266.579858)
		)
		(stroke
			(width 0)
			(type solid)
		)
		(fill yes)
		(layer "F.Cu")
		(net "M_E_CPU1_SA_DQ<31>")
	)
	(gr_poly
		(pts
			(xy 143.23695 -289.772598) (xy 143.23695 -289.582098) (xy 143.13535 -289.54603) (xy 143.08455 -289.54603)
			(xy 143.08455 -289.80892) (xy 143.13535 -289.80892)
		)
		(stroke
			(width 0)
			(type solid)
		)
		(fill yes)
		(layer "F.Cu")
		(net "M_E_CPU1_SA_DQ<16>")
	)
	(gr_poly
		(pts
			(xy 143.23695 -289.175698) (xy 143.23695 -288.985198) (xy 143.13535 -288.94913) (xy 143.08455 -288.94913)
			(xy 143.08455 -289.21202) (xy 143.13535 -289.21202)
		)
		(stroke
			(width 0)
			(type solid)
		)
		(fill yes)
		(layer "F.Cu")
		(net "M_E_CPU1_SA_DQ<16>")
	)
	(gr_poly
		(pts
			(xy 143.23695 -288.578798) (xy 143.23695 -288.388298) (xy 143.13535 -288.35223) (xy 143.08455 -288.35223)
			(xy 143.08455 -288.61512) (xy 143.13535 -288.61512)
		)
		(stroke
			(width 0)
			(type solid)
		)
		(fill yes)
		(layer "F.Cu")
		(net "M_E_CPU1_SA_DQ<16>")
	)
	(gr_poly
		(pts
			(xy 143.23695 -287.981898) (xy 143.23695 -287.791398) (xy 143.13535 -287.75533) (xy 143.08455 -287.75533)
			(xy 143.08455 -288.01822) (xy 143.13535 -288.01822)
		)
		(stroke
			(width 0)
			(type solid)
		)
		(fill yes)
		(layer "F.Cu")
		(net "M_E_CPU1_SA_DQ<16>")
	)
	(gr_poly
		(pts
			(xy 143.23695 -287.384998) (xy 143.23695 -287.194498) (xy 143.13535 -287.15843) (xy 143.08455 -287.15843)
			(xy 143.08455 -287.42132) (xy 143.13535 -287.42132)
		)
		(stroke
			(width 0)
			(type solid)
		)
		(fill yes)
		(layer "F.Cu")
		(net "M_E_CPU1_SA_DQ<16>")
	)
	(gr_poly
		(pts
			(xy 143.23695 -286.788098) (xy 143.23695 -286.597598) (xy 143.13535 -286.56153) (xy 143.08455 -286.56153)
			(xy 143.08455 -286.82442) (xy 143.13535 -286.82442)
		)
		(stroke
			(width 0)
			(type solid)
		)
		(fill yes)
		(layer "F.Cu")
		(net "M_E_CPU1_SA_DQ<16>")
	)
	(gr_poly
		(pts
			(xy 143.23695 -286.191198) (xy 143.23695 -286.000698) (xy 143.13535 -285.96463) (xy 143.08455 -285.96463)
			(xy 143.08455 -286.22752) (xy 143.13535 -286.22752)
		)
		(stroke
			(width 0)
			(type solid)
		)
		(fill yes)
		(layer "F.Cu")
		(net "M_E_CPU1_SA_DQ<16>")
	)
	(gr_poly
		(pts
			(xy 143.23695 -285.594298) (xy 143.23695 -285.403798) (xy 143.13535 -285.36773) (xy 143.08455 -285.36773)
			(xy 143.08455 -285.63062) (xy 143.13535 -285.63062)
		)
		(stroke
			(width 0)
			(type solid)
		)
		(fill yes)
		(layer "F.Cu")
		(net "M_E_CPU1_SA_DQ<16>")
	)
	(gr_poly
		(pts
			(xy 143.23695 -284.997398) (xy 143.23695 -284.806898) (xy 143.13535 -284.77083) (xy 143.08455 -284.77083)
			(xy 143.08455 -285.03372) (xy 143.13535 -285.03372)
		)
		(stroke
			(width 0)
			(type solid)
		)
		(fill yes)
		(layer "F.Cu")
		(net "M_E_CPU1_SA_DQ<16>")
	)
	(gr_poly
		(pts
			(xy 143.23695 -284.400498) (xy 143.23695 -284.209998) (xy 143.13535 -284.17393) (xy 143.08455 -284.17393)
			(xy 143.08455 -284.43682) (xy 143.13535 -284.43682)
		)
		(stroke
			(width 0)
			(type solid)
		)
		(fill yes)
		(layer "F.Cu")
		(net "M_E_CPU1_SA_DQ<16>")
	)
	(gr_poly
		(pts
			(xy 143.23695 -283.803598) (xy 143.23695 -283.613098) (xy 143.13535 -283.57703) (xy 143.08455 -283.57703)
			(xy 143.08455 -283.83992) (xy 143.13535 -283.83992)
		)
		(stroke
			(width 0)
			(type solid)
		)
		(fill yes)
		(layer "F.Cu")
		(net "M_E_CPU1_SA_DQ<16>")
	)
	(gr_poly
		(pts
			(xy 143.23695 -283.206698) (xy 143.23695 -283.016198) (xy 143.13535 -282.98013) (xy 143.08455 -282.98013)
			(xy 143.08455 -283.24302) (xy 143.13535 -283.24302)
		)
		(stroke
			(width 0)
			(type solid)
		)
		(fill yes)
		(layer "F.Cu")
		(net "M_E_CPU1_SA_DQ<16>")
	)
	(gr_poly
		(pts
			(xy 143.23695 -282.609798) (xy 143.23695 -282.419298) (xy 143.13535 -282.38323) (xy 143.08455 -282.38323)
			(xy 143.08455 -282.64612) (xy 143.13535 -282.64612)
		)
		(stroke
			(width 0)
			(type solid)
		)
		(fill yes)
		(layer "F.Cu")
		(net "M_E_CPU1_SA_DQ<16>")
	)
	(gr_poly
		(pts
			(xy 143.23695 -282.012898) (xy 143.23695 -281.822398) (xy 143.13535 -281.78633) (xy 143.08455 -281.78633)
			(xy 143.08455 -282.04922) (xy 143.13535 -282.04922)
		)
		(stroke
			(width 0)
			(type solid)
		)
		(fill yes)
		(layer "F.Cu")
		(net "M_E_CPU1_SA_DQ<16>")
	)
	(gr_poly
		(pts
			(xy 143.23695 -281.415998) (xy 143.23695 -281.225498) (xy 143.13535 -281.18943) (xy 143.08455 -281.18943)
			(xy 143.08455 -281.45232) (xy 143.13535 -281.45232)
		)
		(stroke
			(width 0)
			(type solid)
		)
		(fill yes)
		(layer "F.Cu")
		(net "M_E_CPU1_SA_DQ<16>")
	)
	(gr_poly
		(pts
			(xy 143.24965 -273.045428) (xy 143.295878 -272.947892) (xy 143.161004 -272.813272) (xy 143.063722 -272.8595)
			(xy 143.027654 -272.895314) (xy 143.213582 -273.081242)
		)
		(stroke
			(width 0)
			(type solid)
		)
		(fill yes)
		(layer "F.Cu")
		(net "M_E_CPU1_SA_DQ<22>")
	)
	(gr_poly
		(pts
			(xy 143.25092 -262.34898) (xy 143.297148 -262.251444) (xy 143.162274 -262.116824) (xy 143.064992 -262.163052)
			(xy 143.028924 -262.198866) (xy 143.214852 -262.384794)
		)
		(stroke
			(width 0)
			(type solid)
		)
		(fill yes)
		(layer "F.Cu")
		(net "M_E_CPU1_SA_CB<4>")
	)
	(gr_poly
		(pts
			(xy 143.256762 -240.15954) (xy 143.22044 -240.05794) (xy 143.02994 -240.05794) (xy 142.993872 -240.15954)
			(xy 142.993872 -240.21034) (xy 143.256762 -240.21034)
		)
		(stroke
			(width 0)
			(type solid)
		)
		(fill yes)
		(layer "F.Cu")
		(net "M_E_CPU1_SB_CB<0>")
	)
	(gr_poly
		(pts
			(xy 143.25854 -271.347946) (xy 143.304768 -271.25041) (xy 143.169894 -271.11579) (xy 143.072612 -271.162018)
			(xy 143.036544 -271.197832) (xy 143.222472 -271.38376)
		)
		(stroke
			(width 0)
			(type solid)
		)
		(fill yes)
		(layer "F.Cu")
		(net "M_E_CPU1_SA_DQ<24>")
	)
	(gr_poly
		(pts
			(xy 143.258794 -272.191734) (xy 143.305022 -272.094452) (xy 143.170402 -271.959578) (xy 143.072866 -272.005806)
			(xy 143.037052 -272.041874) (xy 143.22298 -272.227802)
		)
		(stroke
			(width 0)
			(type solid)
		)
		(fill yes)
		(layer "F.Cu")
		(net "M_E_CPU1_SA_DQ<23>")
	)
	(gr_poly
		(pts
			(xy 143.260064 -261.49554) (xy 143.306292 -261.398258) (xy 143.171672 -261.263384) (xy 143.074136 -261.309612)
			(xy 143.038322 -261.34568) (xy 143.22425 -261.531608)
		)
		(stroke
			(width 0)
			(type solid)
		)
		(fill yes)
		(layer "F.Cu")
		(net "M_E_CPU1_SA_CB<5>")
	)
	(gr_poly
		(pts
			(xy 143.267684 -270.494506) (xy 143.313912 -270.39697) (xy 143.179038 -270.26235) (xy 143.081756 -270.308578)
			(xy 143.045688 -270.344392) (xy 143.231616 -270.53032)
		)
		(stroke
			(width 0)
			(type solid)
		)
		(fill yes)
		(layer "F.Cu")
		(net "M_E_CPU1_SA_DQ<25>")
	)
	(gr_poly
		(pts
			(xy 143.273018 -228.822758) (xy 143.23695 -228.786944) (xy 143.139668 -228.740716) (xy 143.004794 -228.875336)
			(xy 143.051276 -228.972872) (xy 143.08709 -229.008686)
		)
		(stroke
			(width 0)
			(type solid)
		)
		(fill yes)
		(layer "F.Cu")
		(net "M_E_CPU1_SB_DQ<22>")
	)
	(gr_poly
		(pts
			(xy 143.276574 -279.642062) (xy 143.36903 -279.58669) (xy 143.331692 -279.399746) (xy 143.225012 -279.384252)
			(xy 143.175228 -279.394158) (xy 143.22679 -279.651968)
		)
		(stroke
			(width 0)
			(type solid)
		)
		(fill yes)
		(layer "F.Cu")
		(net "M_E_CPU1_SA_DQ<18>")
	)
	(gr_poly
		(pts
			(xy 143.28521 -279.944576) (xy 143.233648 -279.686766) (xy 143.183864 -279.696926) (xy 143.091408 -279.752298)
			(xy 143.128746 -279.938988) (xy 143.235426 -279.954482)
		)
		(stroke
			(width 0)
			(type solid)
		)
		(fill yes)
		(layer "F.Cu")
		(net "M_E_CPU1_SA_DQ<18>")
	)
	(gr_poly
		(pts
			(xy 143.285464 -242.700556) (xy 143.285464 -242.649756) (xy 143.022574 -242.649756) (xy 143.022574 -242.700556)
			(xy 143.058896 -242.802156) (xy 143.249396 -242.802156)
		)
		(stroke
			(width 0)
			(type solid)
		)
		(fill yes)
		(layer "F.Cu")
		(net "M_E_CPU1_SB_CB<4>")
	)
	(gr_poly
		(pts
			(xy 143.285464 -242.395756) (xy 143.285464 -242.344956) (xy 143.022574 -242.344956) (xy 143.022574 -242.395756)
			(xy 143.058896 -242.497356) (xy 143.249396 -242.497356)
		)
		(stroke
			(width 0)
			(type solid)
		)
		(fill yes)
		(layer "F.Cu")
		(net "M_E_CPU1_SB_CB<6>")
	)
	(gr_poly
		(pts
			(xy 143.285464 -242.090956) (xy 143.285464 -242.040156) (xy 143.022574 -242.040156) (xy 143.022574 -242.090956)
			(xy 143.058896 -242.192556) (xy 143.249396 -242.192556)
		)
		(stroke
			(width 0)
			(type solid)
		)
		(fill yes)
		(layer "F.Cu")
		(net "M_E_CPU1_SB_CB<5>")
	)
	(gr_poly
		(pts
			(xy 143.285464 -241.786156) (xy 143.285464 -241.735356) (xy 143.022574 -241.735356) (xy 143.022574 -241.786156)
			(xy 143.058896 -241.887756) (xy 143.249396 -241.887756)
		)
		(stroke
			(width 0)
			(type solid)
		)
		(fill yes)
		(layer "F.Cu")
		(net "M_E_CPU1_SB_CB<7>")
	)
	(gr_poly
		(pts
			(xy 143.29029 -276.59584) (xy 143.382746 -276.540468) (xy 143.345408 -276.353778) (xy 143.238728 -276.33803)
			(xy 143.188944 -276.347936) (xy 143.240252 -276.605746)
		)
		(stroke
			(width 0)
			(type solid)
		)
		(fill yes)
		(layer "F.Cu")
		(net "M_E_CPU1_SA_DQ<19>")
	)
	(gr_poly
		(pts
			(xy 143.298926 -276.898608) (xy 143.247364 -276.640798) (xy 143.19758 -276.650704) (xy 143.10487 -276.706076)
			(xy 143.142208 -276.892766) (xy 143.249142 -276.908514)
		)
		(stroke
			(width 0)
			(type solid)
		)
		(fill yes)
		(layer "F.Cu")
		(net "M_E_CPU1_SA_DQ<19>")
	)
	(gr_poly
		(pts
			(xy 143.299942 -231.384094) (xy 143.263874 -231.34828) (xy 143.166592 -231.302052) (xy 143.031718 -231.436672)
			(xy 143.077946 -231.534208) (xy 143.114014 -231.570022)
		)
		(stroke
			(width 0)
			(type solid)
		)
		(fill yes)
		(layer "F.Cu")
		(net "M_E_CPU1_SB_DQ<19>")
	)
	(gr_poly
		(pts
			(xy 143.309086 -232.237534) (xy 143.273018 -232.20172) (xy 143.175736 -232.155492) (xy 143.041116 -232.290112)
			(xy 143.087344 -232.387648) (xy 143.123158 -232.423462)
		)
		(stroke
			(width 0)
			(type solid)
		)
		(fill yes)
		(layer "F.Cu")
		(net "M_E_CPU1_SB_DQ<18>")
	)
	(gr_poly
		(pts
			(xy 143.317722 -233.934762) (xy 143.281908 -233.898694) (xy 143.184372 -233.852466) (xy 143.049752 -233.987086)
			(xy 143.09598 -234.084622) (xy 143.132048 -234.120436)
		)
		(stroke
			(width 0)
			(type solid)
		)
		(fill yes)
		(layer "F.Cu")
		(net "M_E_CPU1_SB_DQ<13>")
	)
	(gr_poly
		(pts
			(xy 143.32712 -234.787948) (xy 143.291052 -234.752134) (xy 143.19377 -234.705906) (xy 143.058896 -234.840526)
			(xy 143.105124 -234.938062) (xy 143.141192 -234.973876)
		)
		(stroke
			(width 0)
			(type solid)
		)
		(fill yes)
		(layer "F.Cu")
		(net "M_E_CPU1_SB_DQ<12>")
	)
	(gr_poly
		(pts
			(xy 143.332708 -266.02563) (xy 143.368776 -265.989816) (xy 143.182848 -265.803888) (xy 143.14678 -265.839702)
			(xy 143.100552 -265.937238) (xy 143.235426 -266.071858)
		)
		(stroke
			(width 0)
			(type solid)
		)
		(fill yes)
		(layer "F.Cu")
		(net "M_E_CPU1_SA_CB<0>")
	)
	(gr_poly
		(pts
			(xy 143.335248 -258.415282) (xy 143.371062 -258.379214) (xy 143.185134 -258.193286) (xy 143.14932 -258.229354)
			(xy 143.103092 -258.326636) (xy 143.237712 -258.46151)
		)
		(stroke
			(width 0)
			(type solid)
		)
		(fill yes)
		(layer "F.Cu")
		(net "M_E_CPU1_SA_CS_N<3>")
	)
	(gr_poly
		(pts
			(xy 143.341598 -278.411686) (xy 143.434054 -278.356314) (xy 143.396716 -278.16937) (xy 143.290036 -278.153876)
			(xy 143.240252 -278.163782) (xy 143.291814 -278.421592)
		)
		(stroke
			(width 0)
			(type solid)
		)
		(fill yes)
		(layer "F.Cu")
		(net "M_E_CPU1_SA_DQ<17>")
	)
	(gr_poly
		(pts
			(xy 143.342106 -265.17219) (xy 143.37792 -265.136376) (xy 143.191992 -264.950448) (xy 143.156178 -264.986262)
			(xy 143.10995 -265.083798) (xy 143.24457 -265.218418)
		)
		(stroke
			(width 0)
			(type solid)
		)
		(fill yes)
		(layer "F.Cu")
		(net "M_E_CPU1_SA_CB<1>")
	)
	(gr_poly
		(pts
			(xy 143.344392 -257.561842) (xy 143.38046 -257.526028) (xy 143.194532 -257.3401) (xy 143.158464 -257.375914)
			(xy 143.112236 -257.47345) (xy 143.24711 -257.60807)
		)
		(stroke
			(width 0)
			(type solid)
		)
		(fill yes)
		(layer "F.Cu")
		(net "M_E_CPU1_SA_CA<1>")
	)
	(gr_poly
		(pts
			(xy 143.350234 -278.7142) (xy 143.298672 -278.45639) (xy 143.248888 -278.46655) (xy 143.156432 -278.521922)
			(xy 143.19377 -278.708612) (xy 143.30045 -278.724106)
		)
		(stroke
			(width 0)
			(type solid)
		)
		(fill yes)
		(layer "F.Cu")
		(net "M_E_CPU1_SA_DQ<17>")
	)
	(gr_poly
		(pts
			(xy 143.350488 -228.529388) (xy 143.30426 -228.432106) (xy 143.268446 -228.396038) (xy 143.082518 -228.581966)
			(xy 143.118332 -228.618034) (xy 143.215868 -228.664262)
		)
		(stroke
			(width 0)
			(type solid)
		)
		(fill yes)
		(layer "F.Cu")
		(net "M_E_CPU1_SB_DQ<21>")
	)
	(gr_poly
		(pts
			(xy 143.352012 -237.351062) (xy 143.316198 -237.314994) (xy 143.218662 -237.268766) (xy 143.084042 -237.403386)
			(xy 143.13027 -237.500922) (xy 143.166084 -237.536736)
		)
		(stroke
			(width 0)
			(type solid)
		)
		(fill yes)
		(layer "F.Cu")
		(net "M_E_CPU1_SB_DQ<9>")
	)
	(gr_poly
		(pts
			(xy 143.353536 -256.708402) (xy 143.389604 -256.672588) (xy 143.203676 -256.48666) (xy 143.167862 -256.522474)
			(xy 143.12138 -256.62001) (xy 143.256254 -256.75463)
		)
		(stroke
			(width 0)
			(type solid)
		)
		(fill yes)
		(layer "F.Cu")
		(net "M_E_CPU1_SA_CA<3>")
	)
	(gr_poly
		(pts
			(xy 143.359632 -229.382828) (xy 143.313404 -229.285292) (xy 143.27759 -229.249478) (xy 143.091662 -229.435406)
			(xy 143.127476 -229.47122) (xy 143.225012 -229.517448)
		)
		(stroke
			(width 0)
			(type solid)
		)
		(fill yes)
		(layer "F.Cu")
		(net "M_E_CPU1_SB_DQ<20>")
	)
	(gr_poly
		(pts
			(xy 143.361918 -238.205264) (xy 143.326104 -238.169196) (xy 143.228568 -238.122968) (xy 143.093948 -238.257588)
			(xy 143.140176 -238.355124) (xy 143.176244 -238.390938)
		)
		(stroke
			(width 0)
			(type solid)
		)
		(fill yes)
		(layer "F.Cu")
		(net "M_E_CPU1_SB_DQ<8>")
	)
	(gr_poly
		(pts
			(xy 143.362934 -255.855216) (xy 143.398748 -255.819148) (xy 143.21282 -255.63322) (xy 143.177006 -255.669288)
			(xy 143.130778 -255.76657) (xy 143.265398 -255.901444)
		)
		(stroke
			(width 0)
			(type solid)
		)
		(fill yes)
		(layer "F.Cu")
		(net "M_E_CPU1_SA_CA<5>")
	)
	(gr_poly
		(pts
			(xy 143.366236 -267.68044) (xy 143.40205 -267.644626) (xy 143.216122 -267.458698) (xy 143.180308 -267.494766)
			(xy 143.13408 -267.592048) (xy 143.2687 -267.726922)
		)
		(stroke
			(width 0)
			(type solid)
		)
		(fill yes)
		(layer "F.Cu")
		(net "M_E_CPU1_SA_DQ<30>")
	)
	(gr_poly
		(pts
			(xy 143.372078 -255.001776) (xy 143.407892 -254.965708) (xy 143.222218 -254.780034) (xy 143.18615 -254.815848)
			(xy 143.139922 -254.913384) (xy 143.274542 -255.048004)
		)
		(stroke
			(width 0)
			(type solid)
		)
		(fill yes)
		(layer "F.Cu")
		(net "M_E_CPU1_SA_PAR")
	)
	(gr_poly
		(pts
			(xy 143.375634 -266.827) (xy 143.411448 -266.790932) (xy 143.22552 -266.605004) (xy 143.189706 -266.641072)
			(xy 143.143478 -266.738354) (xy 143.278098 -266.873228)
		)
		(stroke
			(width 0)
			(type solid)
		)
		(fill yes)
		(layer "F.Cu")
		(net "M_E_CPU1_SA_DQ<31>")
	)
	(gr_poly
		(pts
			(xy 143.386556 -231.944164) (xy 143.340328 -231.846882) (xy 143.304514 -231.810814) (xy 143.118586 -231.996742)
			(xy 143.1544 -232.03281) (xy 143.251936 -232.079038)
		)
		(stroke
			(width 0)
			(type solid)
		)
		(fill yes)
		(layer "F.Cu")
		(net "M_E_CPU1_SB_DQ<17>")
	)
	(gr_poly
		(pts
			(xy 143.388842 -273.32813) (xy 143.424656 -273.292316) (xy 143.238728 -273.106388) (xy 143.202914 -273.142456)
			(xy 143.156686 -273.239738) (xy 143.291306 -273.374612)
		)
		(stroke
			(width 0)
			(type solid)
		)
		(fill yes)
		(layer "F.Cu")
		(net "M_E_CPU1_SA_DQ<22>")
	)
	(gr_poly
		(pts
			(xy 143.38935 -289.247326) (xy 143.33855 -289.247326) (xy 143.23695 -289.283648) (xy 143.23695 -289.474148)
			(xy 143.33855 -289.51047) (xy 143.38935 -289.51047)
		)
		(stroke
			(width 0)
			(type solid)
		)
		(fill yes)
		(layer "F.Cu")
		(net "M_E_CPU1_SA_DQ<18>")
	)
	(gr_poly
		(pts
			(xy 143.38935 -288.650426) (xy 143.33855 -288.650426) (xy 143.23695 -288.686748) (xy 143.23695 -288.877248)
			(xy 143.33855 -288.91357) (xy 143.38935 -288.91357)
		)
		(stroke
			(width 0)
			(type solid)
		)
		(fill yes)
		(layer "F.Cu")
		(net "M_E_CPU1_SA_DQ<18>")
	)
	(gr_poly
		(pts
			(xy 143.38935 -288.053526) (xy 143.33855 -288.053526) (xy 143.23695 -288.089848) (xy 143.23695 -288.280348)
			(xy 143.33855 -288.31667) (xy 143.38935 -288.31667)
		)
		(stroke
			(width 0)
			(type solid)
		)
		(fill yes)
		(layer "F.Cu")
		(net "M_E_CPU1_SA_DQ<18>")
	)
	(gr_poly
		(pts
			(xy 143.38935 -287.456626) (xy 143.33855 -287.456626) (xy 143.23695 -287.492948) (xy 143.23695 -287.683448)
			(xy 143.33855 -287.71977) (xy 143.38935 -287.71977)
		)
		(stroke
			(width 0)
			(type solid)
		)
		(fill yes)
		(layer "F.Cu")
		(net "M_E_CPU1_SA_DQ<18>")
	)
	(gr_poly
		(pts
			(xy 143.38935 -286.859726) (xy 143.33855 -286.859726) (xy 143.23695 -286.896048) (xy 143.23695 -287.086548)
			(xy 143.33855 -287.12287) (xy 143.38935 -287.12287)
		)
		(stroke
			(width 0)
			(type solid)
		)
		(fill yes)
		(layer "F.Cu")
		(net "M_E_CPU1_SA_DQ<18>")
	)
	(gr_poly
		(pts
			(xy 143.38935 -286.262826) (xy 143.33855 -286.262826) (xy 143.23695 -286.299148) (xy 143.23695 -286.489648)
			(xy 143.33855 -286.52597) (xy 143.38935 -286.52597)
		)
		(stroke
			(width 0)
			(type solid)
		)
		(fill yes)
		(layer "F.Cu")
		(net "M_E_CPU1_SA_DQ<18>")
	)
	(gr_poly
		(pts
			(xy 143.38935 -285.665926) (xy 143.33855 -285.665926) (xy 143.23695 -285.702248) (xy 143.23695 -285.892748)
			(xy 143.33855 -285.92907) (xy 143.38935 -285.92907)
		)
		(stroke
			(width 0)
			(type solid)
		)
		(fill yes)
		(layer "F.Cu")
		(net "M_E_CPU1_SA_DQ<18>")
	)
	(gr_poly
		(pts
			(xy 143.38935 -285.069026) (xy 143.33855 -285.069026) (xy 143.23695 -285.105348) (xy 143.23695 -285.295848)
			(xy 143.33855 -285.33217) (xy 143.38935 -285.33217)
		)
		(stroke
			(width 0)
			(type solid)
		)
		(fill yes)
		(layer "F.Cu")
		(net "M_E_CPU1_SA_DQ<18>")
	)
	(gr_poly
		(pts
			(xy 143.38935 -284.472126) (xy 143.33855 -284.472126) (xy 143.23695 -284.508448) (xy 143.23695 -284.698948)
			(xy 143.33855 -284.73527) (xy 143.38935 -284.73527)
		)
		(stroke
			(width 0)
			(type solid)
		)
		(fill yes)
		(layer "F.Cu")
		(net "M_E_CPU1_SA_DQ<18>")
	)
	(gr_poly
		(pts
			(xy 143.38935 -283.875226) (xy 143.33855 -283.875226) (xy 143.23695 -283.911548) (xy 143.23695 -284.102048)
			(xy 143.33855 -284.13837) (xy 143.38935 -284.13837)
		)
		(stroke
			(width 0)
			(type solid)
		)
		(fill yes)
		(layer "F.Cu")
		(net "M_E_CPU1_SA_DQ<18>")
	)
	(gr_poly
		(pts
			(xy 143.38935 -283.278326) (xy 143.33855 -283.278326) (xy 143.23695 -283.314648) (xy 143.23695 -283.505148)
			(xy 143.33855 -283.54147) (xy 143.38935 -283.54147)
		)
		(stroke
			(width 0)
			(type solid)
		)
		(fill yes)
		(layer "F.Cu")
		(net "M_E_CPU1_SA_DQ<18>")
	)
	(gr_poly
		(pts
			(xy 143.38935 -282.681426) (xy 143.33855 -282.681426) (xy 143.23695 -282.717748) (xy 143.23695 -282.908248)
			(xy 143.33855 -282.94457) (xy 143.38935 -282.94457)
		)
		(stroke
			(width 0)
			(type solid)
		)
		(fill yes)
		(layer "F.Cu")
		(net "M_E_CPU1_SA_DQ<18>")
	)
	(gr_poly
		(pts
			(xy 143.38935 -282.084526) (xy 143.33855 -282.084526) (xy 143.23695 -282.120848) (xy 143.23695 -282.311348)
			(xy 143.33855 -282.34767) (xy 143.38935 -282.34767)
		)
		(stroke
			(width 0)
			(type solid)
		)
		(fill yes)
		(layer "F.Cu")
		(net "M_E_CPU1_SA_DQ<18>")
	)
	(gr_poly
		(pts
			(xy 143.38935 -281.487626) (xy 143.33855 -281.487626) (xy 143.23695 -281.523948) (xy 143.23695 -281.714448)
			(xy 143.33855 -281.75077) (xy 143.38935 -281.75077)
		)
		(stroke
			(width 0)
			(type solid)
		)
		(fill yes)
		(layer "F.Cu")
		(net "M_E_CPU1_SA_DQ<18>")
	)
	(gr_poly
		(pts
			(xy 143.38935 -280.890726) (xy 143.33855 -280.890726) (xy 143.23695 -280.927048) (xy 143.23695 -281.117548)
			(xy 143.33855 -281.15387) (xy 143.38935 -281.15387)
		)
		(stroke
			(width 0)
			(type solid)
		)
		(fill yes)
		(layer "F.Cu")
		(net "M_E_CPU1_SA_DQ<18>")
	)
	(gr_poly
		(pts
			(xy 143.390112 -262.631936) (xy 143.425926 -262.595868) (xy 143.239998 -262.40994) (xy 143.204184 -262.446008)
			(xy 143.157956 -262.54329) (xy 143.292576 -262.678164)
		)
		(stroke
			(width 0)
			(type solid)
		)
		(fill yes)
		(layer "F.Cu")
		(net "M_E_CPU1_SA_CB<4>")
	)
	(gr_poly
		(pts
			(xy 143.393668 -280.227278) (xy 143.486124 -280.171906) (xy 143.448786 -279.985216) (xy 143.342106 -279.969468)
			(xy 143.292322 -279.979374) (xy 143.343884 -280.237184)
		)
		(stroke
			(width 0)
			(type solid)
		)
		(fill yes)
		(layer "F.Cu")
		(net "M_E_CPU1_SA_DQ<18>")
	)
	(gr_poly
		(pts
			(xy 143.395446 -233.641392) (xy 143.349218 -233.543856) (xy 143.31315 -233.508042) (xy 143.127222 -233.69397)
			(xy 143.16329 -233.729784) (xy 143.260572 -233.776012)
		)
		(stroke
			(width 0)
			(type solid)
		)
		(fill yes)
		(layer "F.Cu")
		(net "M_E_CPU1_SB_DQ<15>")
	)
	(gr_poly
		(pts
			(xy 143.395954 -232.797604) (xy 143.349472 -232.700068) (xy 143.313658 -232.664254) (xy 143.12773 -232.850182)
			(xy 143.163798 -232.885996) (xy 143.26108 -232.932224)
		)
		(stroke
			(width 0)
			(type solid)
		)
		(fill yes)
		(layer "F.Cu")
		(net "M_E_CPU1_SB_DQ<16>")
	)
	(gr_poly
		(pts
			(xy 143.397732 -271.630648) (xy 143.433546 -271.594834) (xy 143.247618 -271.408906) (xy 143.211804 -271.444974)
			(xy 143.165576 -271.542256) (xy 143.300196 -271.67713)
		)
		(stroke
			(width 0)
			(type solid)
		)
		(fill yes)
		(layer "F.Cu")
		(net "M_E_CPU1_SA_DQ<24>")
	)
	(gr_poly
		(pts
			(xy 143.397986 -272.47469) (xy 143.434054 -272.438876) (xy 143.248126 -272.252948) (xy 143.212058 -272.288762)
			(xy 143.16583 -272.386298) (xy 143.30045 -272.520918)
		)
		(stroke
			(width 0)
			(type solid)
		)
		(fill yes)
		(layer "F.Cu")
		(net "M_E_CPU1_SA_DQ<23>")
	)
	(gr_poly
		(pts
			(xy 143.399256 -261.778496) (xy 143.43507 -261.742428) (xy 143.249396 -261.556754) (xy 143.213328 -261.592568)
			(xy 143.1671 -261.690104) (xy 143.30172 -261.824724)
		)
		(stroke
			(width 0)
			(type solid)
		)
		(fill yes)
		(layer "F.Cu")
		(net "M_E_CPU1_SA_CB<5>")
	)
	(gr_poly
		(pts
			(xy 143.402558 -258.77012) (xy 143.448786 -258.672584) (xy 143.313912 -258.537964) (xy 143.21663 -258.584192)
			(xy 143.180562 -258.620006) (xy 143.36649 -258.805934)
		)
		(stroke
			(width 0)
			(type solid)
		)
		(fill yes)
		(layer "F.Cu")
		(net "M_E_CPU1_SA_CS_N<1>")
	)
	(gr_poly
		(pts
			(xy 143.40459 -234.494578) (xy 143.358362 -234.397296) (xy 143.322548 -234.361228) (xy 143.13662 -234.547156)
			(xy 143.172434 -234.583224) (xy 143.26997 -234.629452)
		)
		(stroke
			(width 0)
			(type solid)
		)
		(fill yes)
		(layer "F.Cu")
		(net "M_E_CPU1_SB_DQ<14>")
	)
	(gr_poly
		(pts
			(xy 143.406876 -270.777208) (xy 143.44269 -270.741394) (xy 143.256762 -270.555466) (xy 143.220948 -270.591534)
			(xy 143.17472 -270.688816) (xy 143.30934 -270.82369)
		)
		(stroke
			(width 0)
			(type solid)
		)
		(fill yes)
		(layer "F.Cu")
		(net "M_E_CPU1_SA_DQ<25>")
	)
	(gr_poly
		(pts
			(xy 143.40713 -277.18131) (xy 143.499586 -277.125684) (xy 143.462248 -276.938994) (xy 143.355568 -276.9235)
			(xy 143.305784 -276.933406) (xy 143.357346 -277.191216)
		)
		(stroke
			(width 0)
			(type solid)
		)
		(fill yes)
		(layer "F.Cu")
		(net "M_E_CPU1_SA_DQ<19>")
	)
	(gr_poly
		(pts
			(xy 143.409162 -265.527028) (xy 143.45539 -265.429746) (xy 143.32077 -265.294872) (xy 143.223234 -265.3411)
			(xy 143.18742 -265.377168) (xy 143.373348 -265.563096)
		)
		(stroke
			(width 0)
			(type solid)
		)
		(fill yes)
		(layer "F.Cu")
		(net "M_E_CPU1_SA_CB<2>")
	)
	(gr_poly
		(pts
			(xy 143.411702 -257.91668) (xy 143.45793 -257.819144) (xy 143.32331 -257.684524) (xy 143.225774 -257.730752)
			(xy 143.18996 -257.76682) (xy 143.375634 -257.952494)
		)
		(stroke
			(width 0)
			(type solid)
		)
		(fill yes)
		(layer "F.Cu")
		(net "M_E_CPU1_SA_CA<0>")
	)
	(gr_poly
		(pts
			(xy 143.415766 -277.483824) (xy 143.364204 -277.226014) (xy 143.31442 -277.23592) (xy 143.221964 -277.291292)
			(xy 143.259302 -277.478236) (xy 143.365982 -277.49373)
		)
		(stroke
			(width 0)
			(type solid)
		)
		(fill yes)
		(layer "F.Cu")
		(net "M_E_CPU1_SA_DQ<19>")
	)
	(gr_poly
		(pts
			(xy 143.418306 -264.673842) (xy 143.464788 -264.576306) (xy 143.329914 -264.441686) (xy 143.232632 -264.487914)
			(xy 143.196564 -264.523728) (xy 143.382492 -264.709656)
		)
		(stroke
			(width 0)
			(type solid)
		)
		(fill yes)
		(layer "F.Cu")
		(net "M_E_CPU1_SA_CB<3>")
	)
	(gr_poly
		(pts
			(xy 143.420846 -257.06324) (xy 143.467074 -256.965958) (xy 143.332454 -256.831084) (xy 143.234918 -256.877312)
			(xy 143.199104 -256.91338) (xy 143.385032 -257.099308)
		)
		(stroke
			(width 0)
			(type solid)
		)
		(fill yes)
		(layer "F.Cu")
		(net "M_E_CPU1_SA_CA<2>")
	)
	(gr_poly
		(pts
			(xy 143.429482 -237.057692) (xy 143.383254 -236.960156) (xy 143.34744 -236.924342) (xy 143.161512 -237.110016)
			(xy 143.197326 -237.146084) (xy 143.294862 -237.192312)
		)
		(stroke
			(width 0)
			(type solid)
		)
		(fill yes)
		(layer "F.Cu")
		(net "M_E_CPU1_SB_DQ<11>")
	)
	(gr_poly
		(pts
			(xy 143.42999 -256.210054) (xy 143.476218 -256.112518) (xy 143.341598 -255.977898) (xy 143.244316 -256.024126)
			(xy 143.208248 -256.05994) (xy 143.394176 -256.245868)
		)
		(stroke
			(width 0)
			(type solid)
		)
		(fill yes)
		(layer "F.Cu")
		(net "M_E_CPU1_SA_CA<4>")
	)
	(gr_poly
		(pts
			(xy 143.433292 -268.035278) (xy 143.47952 -267.937996) (xy 143.3449 -267.803376) (xy 143.247364 -267.849604)
			(xy 143.21155 -267.885418) (xy 143.397478 -268.071346)
		)
		(stroke
			(width 0)
			(type solid)
		)
		(fill yes)
		(layer "F.Cu")
		(net "M_E_CPU1_SA_DQ<28>")
	)
	(gr_poly
		(pts
			(xy 143.439388 -255.356614) (xy 143.485616 -255.259078) (xy 143.350742 -255.124458) (xy 143.25346 -255.170686)
			(xy 143.217392 -255.2065) (xy 143.40332 -255.392428)
		)
		(stroke
			(width 0)
			(type solid)
		)
		(fill yes)
		(layer "F.Cu")
		(net "M_E_CPU1_SA_CA<6>")
	)
	(gr_poly
		(pts
			(xy 143.439388 -237.91164) (xy 143.39316 -237.814358) (xy 143.357346 -237.77829) (xy 143.171418 -237.964218)
			(xy 143.207232 -238.000032) (xy 143.304768 -238.046514)
		)
		(stroke
			(width 0)
			(type solid)
		)
		(fill yes)
		(layer "F.Cu")
		(net "M_E_CPU1_SB_DQ<10>")
	)
	(gr_poly
		(pts
			(xy 143.44269 -267.181838) (xy 143.488918 -267.084556) (xy 143.354298 -266.949682) (xy 143.256762 -266.99591)
			(xy 143.220948 -267.031978) (xy 143.406876 -267.217906)
		)
		(stroke
			(width 0)
			(type solid)
		)
		(fill yes)
		(layer "F.Cu")
		(net "M_E_CPU1_SA_DQ<29>")
	)
	(gr_poly
		(pts
			(xy 143.455898 -273.683222) (xy 143.502126 -273.58594) (xy 143.367252 -273.451066) (xy 143.26997 -273.497294)
			(xy 143.233902 -273.533362) (xy 143.41983 -273.71929)
		)
		(stroke
			(width 0)
			(type solid)
		)
		(fill yes)
		(layer "F.Cu")
		(net "M_E_CPU1_SA_DQ<20>")
	)
	(gr_poly
		(pts
			(xy 143.456152 -249.069352) (xy 143.456152 -249.018552) (xy 143.193008 -249.018552) (xy 143.193008 -249.069352)
			(xy 143.22933 -249.170952) (xy 143.41983 -249.170952)
		)
		(stroke
			(width 0)
			(type solid)
		)
		(fill yes)
		(layer "F.Cu")
		(net "M_E_CPU1_SB_CA<0>")
	)
	(gr_poly
		(pts
			(xy 143.456152 -248.764552) (xy 143.456152 -248.713752) (xy 143.193008 -248.713752) (xy 143.193008 -248.764552)
			(xy 143.22933 -248.866152) (xy 143.41983 -248.866152)
		)
		(stroke
			(width 0)
			(type solid)
		)
		(fill yes)
		(layer "F.Cu")
		(net "M_E_CPU1_SB_CA<1>")
	)
	(gr_poly
		(pts
			(xy 143.456152 -248.459752) (xy 143.456152 -248.408952) (xy 143.193008 -248.408952) (xy 143.193008 -248.459752)
			(xy 143.22933 -248.561352) (xy 143.41983 -248.561352)
		)
		(stroke
			(width 0)
			(type solid)
		)
		(fill yes)
		(layer "F.Cu")
		(net "M_E_CPU1_SB_CA<2>")
	)
	(gr_poly
		(pts
			(xy 143.456152 -248.154952) (xy 143.456152 -248.104152) (xy 143.193008 -248.104152) (xy 143.193008 -248.154952)
			(xy 143.22933 -248.256552) (xy 143.41983 -248.256552)
		)
		(stroke
			(width 0)
			(type solid)
		)
		(fill yes)
		(layer "F.Cu")
		(net "M_E_CPU1_SB_CA<3>")
	)
	(gr_poly
		(pts
			(xy 143.456152 -247.850152) (xy 143.456152 -247.799352) (xy 143.193008 -247.799352) (xy 143.193008 -247.850152)
			(xy 143.22933 -247.951752) (xy 143.41983 -247.951752)
		)
		(stroke
			(width 0)
			(type solid)
		)
		(fill yes)
		(layer "F.Cu")
		(net "M_E_CPU1_SB_CA<4>")
	)
	(gr_poly
		(pts
			(xy 143.456152 -247.545352) (xy 143.456152 -247.494552) (xy 143.193008 -247.494552) (xy 143.193008 -247.545352)
			(xy 143.22933 -247.646952) (xy 143.41983 -247.646952)
		)
		(stroke
			(width 0)
			(type solid)
		)
		(fill yes)
		(layer "F.Cu")
		(net "M_E_CPU1_SB_CA<5>")
	)
	(gr_poly
		(pts
			(xy 143.456152 -247.240552) (xy 143.456152 -247.189752) (xy 143.193008 -247.189752) (xy 143.193008 -247.240552)
			(xy 143.22933 -247.342152) (xy 143.41983 -247.342152)
		)
		(stroke
			(width 0)
			(type solid)
		)
		(fill yes)
		(layer "F.Cu")
		(net "M_E_CPU1_SB_CA<6>")
	)
	(gr_poly
		(pts
			(xy 143.456152 -246.935752) (xy 143.456152 -246.884952) (xy 143.193008 -246.884952) (xy 143.193008 -246.935752)
			(xy 143.22933 -247.037352) (xy 143.41983 -247.037352)
		)
		(stroke
			(width 0)
			(type solid)
		)
		(fill yes)
		(layer "F.Cu")
		(net "M_E_CPU1_SB_PAR")
	)
	(gr_poly
		(pts
			(xy 143.456152 -246.630952) (xy 143.456152 -246.580152) (xy 143.193008 -246.580152) (xy 143.193008 -246.630952)
			(xy 143.22933 -246.732552) (xy 143.41983 -246.732552)
		)
		(stroke
			(width 0)
			(type solid)
		)
		(fill yes)
		(layer "F.Cu")
		(net "M_E_CPU1_SB_CS_N<0>")
	)
	(gr_poly
		(pts
			(xy 143.456152 -246.326152) (xy 143.456152 -246.275352) (xy 143.193008 -246.275352) (xy 143.193008 -246.326152)
			(xy 143.22933 -246.427752) (xy 143.41983 -246.427752)
		)
		(stroke
			(width 0)
			(type solid)
		)
		(fill yes)
		(layer "F.Cu")
		(net "M_E_CPU1_SB_CS_N<2>")
	)
	(gr_poly
		(pts
			(xy 143.458692 -278.996902) (xy 143.551148 -278.94153) (xy 143.51381 -278.75484) (xy 143.40713 -278.739092)
			(xy 143.357346 -278.749252) (xy 143.408908 -279.006808)
		)
		(stroke
			(width 0)
			(type solid)
		)
		(fill yes)
		(layer "F.Cu")
		(net "M_E_CPU1_SA_DQ<17>")
	)
	(gr_poly
		(pts
			(xy 143.465042 -272.829782) (xy 143.511524 -272.732246) (xy 143.37665 -272.597626) (xy 143.279368 -272.643854)
			(xy 143.2433 -272.679668) (xy 143.429228 -272.865596)
		)
		(stroke
			(width 0)
			(type solid)
		)
		(fill yes)
		(layer "F.Cu")
		(net "M_E_CPU1_SA_DQ<21>")
	)
	(gr_poly
		(pts
			(xy 143.466566 -262.133334) (xy 143.512794 -262.035798) (xy 143.37792 -261.901178) (xy 143.280638 -261.947406)
			(xy 143.24457 -261.98322) (xy 143.430498 -262.169148)
		)
		(stroke
			(width 0)
			(type solid)
		)
		(fill yes)
		(layer "F.Cu")
		(net "M_E_CPU1_SA_CB<6>")
	)
	(gr_poly
		(pts
			(xy 143.467328 -279.29967) (xy 143.415766 -279.04186) (xy 143.365982 -279.051766) (xy 143.273526 -279.107138)
			(xy 143.310864 -279.294082) (xy 143.417544 -279.309576)
		)
		(stroke
			(width 0)
			(type solid)
		)
		(fill yes)
		(layer "F.Cu")
		(net "M_E_CPU1_SA_DQ<17>")
	)
	(gr_poly
		(pts
			(xy 143.473932 -271.1323) (xy 143.520414 -271.034764) (xy 143.38554 -270.900144) (xy 143.288258 -270.946372)
			(xy 143.25219 -270.982186) (xy 143.438118 -271.168114)
		)
		(stroke
			(width 0)
			(type solid)
		)
		(fill yes)
		(layer "F.Cu")
		(net "M_E_CPU1_SA_DQ<26>")
	)
	(gr_poly
		(pts
			(xy 143.47571 -261.279894) (xy 143.521938 -261.182612) (xy 143.387318 -261.047738) (xy 143.289782 -261.093966)
			(xy 143.253968 -261.130034) (xy 143.439896 -261.315962)
		)
		(stroke
			(width 0)
			(type solid)
		)
		(fill yes)
		(layer "F.Cu")
		(net "M_E_CPU1_SA_CB<7>")
	)
	(gr_poly
		(pts
			(xy 143.479266 -228.185218) (xy 143.443452 -228.14915) (xy 143.345916 -228.102922) (xy 143.211296 -228.237542)
			(xy 143.257524 -228.335078) (xy 143.293592 -228.370892)
		)
		(stroke
			(width 0)
			(type solid)
		)
		(fill yes)
		(layer "F.Cu")
		(net "M_E_CPU1_SB_DQ<21>")
	)
	(gr_poly
		(pts
			(xy 143.483076 -270.27886) (xy 143.529558 -270.181324) (xy 143.394684 -270.046704) (xy 143.297402 -270.092932)
			(xy 143.261334 -270.128746) (xy 143.447262 -270.314674)
		)
		(stroke
			(width 0)
			(type solid)
		)
		(fill yes)
		(layer "F.Cu")
		(net "M_E_CPU1_SA_DQ<27>")
	)
	(gr_poly
		(pts
			(xy 143.488664 -229.038404) (xy 143.452596 -229.00259) (xy 143.355314 -228.956362) (xy 143.22044 -229.090982)
			(xy 143.266922 -229.188518) (xy 143.302736 -229.224332)
		)
		(stroke
			(width 0)
			(type solid)
		)
		(fill yes)
		(layer "F.Cu")
		(net "M_E_CPU1_SB_DQ<20>")
	)
	(gr_poly
		(pts
			(xy 143.515588 -231.59974) (xy 143.47952 -231.563926) (xy 143.382238 -231.517698) (xy 143.247364 -231.652318)
			(xy 143.293592 -231.749854) (xy 143.32966 -231.785668)
		)
		(stroke
			(width 0)
			(type solid)
		)
		(fill yes)
		(layer "F.Cu")
		(net "M_E_CPU1_SB_DQ<17>")
	)
	(gr_poly
		(pts
			(xy 143.52397 -277.766526) (xy 143.61668 -277.711154) (xy 143.579342 -277.52421) (xy 143.472662 -277.508716)
			(xy 143.422624 -277.518622) (xy 143.474186 -277.776432)
		)
		(stroke
			(width 0)
			(type solid)
		)
		(fill yes)
		(layer "F.Cu")
		(net "M_E_CPU1_SA_DQ<19>")
	)
	(gr_poly
		(pts
			(xy 143.524224 -233.296968) (xy 143.48841 -233.2609) (xy 143.390874 -233.214672) (xy 143.256254 -233.349546)
			(xy 143.302482 -233.446828) (xy 143.338296 -233.482896)
		)
		(stroke
			(width 0)
			(type solid)
		)
		(fill yes)
		(layer "F.Cu")
		(net "M_E_CPU1_SB_DQ<15>")
	)
	(gr_poly
		(pts
			(xy 143.524732 -232.45318) (xy 143.488664 -232.417366) (xy 143.391382 -232.371138) (xy 143.256762 -232.505758)
			(xy 143.30299 -232.603294) (xy 143.338804 -232.639108)
		)
		(stroke
			(width 0)
			(type solid)
		)
		(fill yes)
		(layer "F.Cu")
		(net "M_E_CPU1_SB_DQ<16>")
	)
	(gr_poly
		(pts
			(xy 143.532606 -278.06904) (xy 143.481298 -277.811484) (xy 143.43126 -277.82139) (xy 143.338804 -277.876762)
			(xy 143.376142 -278.063452) (xy 143.482822 -278.0792)
		)
		(stroke
			(width 0)
			(type solid)
		)
		(fill yes)
		(layer "F.Cu")
		(net "M_E_CPU1_SA_DQ<19>")
	)
	(gr_poly
		(pts
			(xy 143.533368 -234.150408) (xy 143.497554 -234.11434) (xy 143.400018 -234.068112) (xy 143.265398 -234.202732)
			(xy 143.311626 -234.300268) (xy 143.347694 -234.336082)
		)
		(stroke
			(width 0)
			(type solid)
		)
		(fill yes)
		(layer "F.Cu")
		(net "M_E_CPU1_SB_DQ<14>")
	)
	(gr_poly
		(pts
			(xy 143.54175 -289.175698) (xy 143.54175 -288.985198) (xy 143.44015 -288.94913) (xy 143.38935 -288.94913)
			(xy 143.38935 -289.21202) (xy 143.44015 -289.21202)
		)
		(stroke
			(width 0)
			(type solid)
		)
		(fill yes)
		(layer "F.Cu")
		(net "M_E_CPU1_SA_DQ<18>")
	)
	(gr_poly
		(pts
			(xy 143.54175 -288.578798) (xy 143.54175 -288.388298) (xy 143.44015 -288.35223) (xy 143.38935 -288.35223)
			(xy 143.38935 -288.61512) (xy 143.44015 -288.61512)
		)
		(stroke
			(width 0)
			(type solid)
		)
		(fill yes)
		(layer "F.Cu")
		(net "M_E_CPU1_SA_DQ<18>")
	)
	(gr_poly
		(pts
			(xy 143.54175 -287.981898) (xy 143.54175 -287.791398) (xy 143.44015 -287.75533) (xy 143.38935 -287.75533)
			(xy 143.38935 -288.01822) (xy 143.44015 -288.01822)
		)
		(stroke
			(width 0)
			(type solid)
		)
		(fill yes)
		(layer "F.Cu")
		(net "M_E_CPU1_SA_DQ<18>")
	)
	(gr_poly
		(pts
			(xy 143.54175 -287.384998) (xy 143.54175 -287.194498) (xy 143.44015 -287.15843) (xy 143.38935 -287.15843)
			(xy 143.38935 -287.42132) (xy 143.44015 -287.42132)
		)
		(stroke
			(width 0)
			(type solid)
		)
		(fill yes)
		(layer "F.Cu")
		(net "M_E_CPU1_SA_DQ<18>")
	)
	(gr_poly
		(pts
			(xy 143.54175 -286.788098) (xy 143.54175 -286.597598) (xy 143.44015 -286.56153) (xy 143.38935 -286.56153)
			(xy 143.38935 -286.82442) (xy 143.44015 -286.82442)
		)
		(stroke
			(width 0)
			(type solid)
		)
		(fill yes)
		(layer "F.Cu")
		(net "M_E_CPU1_SA_DQ<18>")
	)
	(gr_poly
		(pts
			(xy 143.54175 -286.191198) (xy 143.54175 -286.000698) (xy 143.44015 -285.96463) (xy 143.38935 -285.96463)
			(xy 143.38935 -286.22752) (xy 143.44015 -286.22752)
		)
		(stroke
			(width 0)
			(type solid)
		)
		(fill yes)
		(layer "F.Cu")
		(net "M_E_CPU1_SA_DQ<18>")
	)
	(gr_poly
		(pts
			(xy 143.54175 -285.594298) (xy 143.54175 -285.403798) (xy 143.44015 -285.36773) (xy 143.38935 -285.36773)
			(xy 143.38935 -285.63062) (xy 143.44015 -285.63062)
		)
		(stroke
			(width 0)
			(type solid)
		)
		(fill yes)
		(layer "F.Cu")
		(net "M_E_CPU1_SA_DQ<18>")
	)
	(gr_poly
		(pts
			(xy 143.54175 -284.997398) (xy 143.54175 -284.806898) (xy 143.44015 -284.77083) (xy 143.38935 -284.77083)
			(xy 143.38935 -285.03372) (xy 143.44015 -285.03372)
		)
		(stroke
			(width 0)
			(type solid)
		)
		(fill yes)
		(layer "F.Cu")
		(net "M_E_CPU1_SA_DQ<18>")
	)
	(gr_poly
		(pts
			(xy 143.54175 -284.400498) (xy 143.54175 -284.209998) (xy 143.44015 -284.17393) (xy 143.38935 -284.17393)
			(xy 143.38935 -284.43682) (xy 143.44015 -284.43682)
		)
		(stroke
			(width 0)
			(type solid)
		)
		(fill yes)
		(layer "F.Cu")
		(net "M_E_CPU1_SA_DQ<18>")
	)
	(gr_poly
		(pts
			(xy 143.54175 -283.803598) (xy 143.54175 -283.613098) (xy 143.44015 -283.57703) (xy 143.38935 -283.57703)
			(xy 143.38935 -283.83992) (xy 143.44015 -283.83992)
		)
		(stroke
			(width 0)
			(type solid)
		)
		(fill yes)
		(layer "F.Cu")
		(net "M_E_CPU1_SA_DQ<18>")
	)
	(gr_poly
		(pts
			(xy 143.54175 -283.206698) (xy 143.54175 -283.016198) (xy 143.44015 -282.98013) (xy 143.38935 -282.98013)
			(xy 143.38935 -283.24302) (xy 143.44015 -283.24302)
		)
		(stroke
			(width 0)
			(type solid)
		)
		(fill yes)
		(layer "F.Cu")
		(net "M_E_CPU1_SA_DQ<18>")
	)
	(gr_poly
		(pts
			(xy 143.54175 -282.609798) (xy 143.54175 -282.419298) (xy 143.44015 -282.38323) (xy 143.38935 -282.38323)
			(xy 143.38935 -282.64612) (xy 143.44015 -282.64612)
		)
		(stroke
			(width 0)
			(type solid)
		)
		(fill yes)
		(layer "F.Cu")
		(net "M_E_CPU1_SA_DQ<18>")
	)
	(gr_poly
		(pts
			(xy 143.54175 -282.012898) (xy 143.54175 -281.822398) (xy 143.44015 -281.78633) (xy 143.38935 -281.78633)
			(xy 143.38935 -282.04922) (xy 143.44015 -282.04922)
		)
		(stroke
			(width 0)
			(type solid)
		)
		(fill yes)
		(layer "F.Cu")
		(net "M_E_CPU1_SA_DQ<18>")
	)
	(gr_poly
		(pts
			(xy 143.54175 -281.415998) (xy 143.54175 -281.225498) (xy 143.44015 -281.18943) (xy 143.38935 -281.18943)
			(xy 143.38935 -281.45232) (xy 143.44015 -281.45232)
		)
		(stroke
			(width 0)
			(type solid)
		)
		(fill yes)
		(layer "F.Cu")
		(net "M_E_CPU1_SA_DQ<18>")
	)
	(gr_poly
		(pts
			(xy 143.548354 -265.809984) (xy 143.584422 -265.77417) (xy 143.398494 -265.588242) (xy 143.362426 -265.624056)
			(xy 143.316198 -265.721592) (xy 143.451072 -265.856212)
		)
		(stroke
			(width 0)
			(type solid)
		)
		(fill yes)
		(layer "F.Cu")
		(net "M_E_CPU1_SA_CB<2>")
	)
	(gr_poly
		(pts
			(xy 143.55699 -227.891848) (xy 143.510762 -227.794312) (xy 143.474694 -227.758498) (xy 143.288766 -227.944426)
			(xy 143.324834 -227.98024) (xy 143.42237 -228.026468)
		)
		(stroke
			(width 0)
			(type solid)
		)
		(fill yes)
		(layer "F.Cu")
		(net "M_E_CPU1_SB_DQ<23>")
	)
	(gr_poly
		(pts
			(xy 143.557752 -264.956544) (xy 143.593566 -264.92073) (xy 143.407638 -264.734802) (xy 143.371824 -264.770616)
			(xy 143.325596 -264.868152) (xy 143.460216 -265.002772)
		)
		(stroke
			(width 0)
			(type solid)
		)
		(fill yes)
		(layer "F.Cu")
		(net "M_E_CPU1_SA_CB<3>")
	)
	(gr_poly
		(pts
			(xy 143.55826 -236.713268) (xy 143.522446 -236.6772) (xy 143.42491 -236.630972) (xy 143.29029 -236.765592)
			(xy 143.336518 -236.863128) (xy 143.372332 -236.898942)
		)
		(stroke
			(width 0)
			(type solid)
		)
		(fill yes)
		(layer "F.Cu")
		(net "M_E_CPU1_SB_DQ<11>")
	)
	(gr_poly
		(pts
			(xy 143.560038 -257.346196) (xy 143.596106 -257.310382) (xy 143.410178 -257.124454) (xy 143.37411 -257.160268)
			(xy 143.327882 -257.257804) (xy 143.462756 -257.392424)
		)
		(stroke
			(width 0)
			(type solid)
		)
		(fill yes)
		(layer "F.Cu")
		(net "M_E_CPU1_SA_CA<2>")
	)
	(gr_poly
		(pts
			(xy 143.566134 -228.745034) (xy 143.519906 -228.647752) (xy 143.484092 -228.611684) (xy 143.298164 -228.797612)
			(xy 143.333978 -228.83368) (xy 143.431514 -228.879908)
		)
		(stroke
			(width 0)
			(type solid)
		)
		(fill yes)
		(layer "F.Cu")
		(net "M_E_CPU1_SB_DQ<22>")
	)
	(gr_poly
		(pts
			(xy 143.56842 -237.567216) (xy 143.532352 -237.531402) (xy 143.43507 -237.485174) (xy 143.300196 -237.619794)
			(xy 143.346424 -237.71733) (xy 143.382492 -237.753144)
		)
		(stroke
			(width 0)
			(type solid)
		)
		(fill yes)
		(layer "F.Cu")
		(net "M_E_CPU1_SB_DQ<10>")
	)
	(gr_poly
		(pts
			(xy 143.569182 -256.492756) (xy 143.60525 -256.456942) (xy 143.419322 -256.271014) (xy 143.383508 -256.306828)
			(xy 143.337026 -256.404364) (xy 143.4719 -256.538984)
		)
		(stroke
			(width 0)
			(type solid)
		)
		(fill yes)
		(layer "F.Cu")
		(net "M_E_CPU1_SA_CA<4>")
	)
	(gr_poly
		(pts
			(xy 143.572484 -268.318234) (xy 143.608552 -268.28242) (xy 143.422624 -268.096492) (xy 143.386556 -268.132306)
			(xy 143.340328 -268.229842) (xy 143.475202 -268.364462)
		)
		(stroke
			(width 0)
			(type solid)
		)
		(fill yes)
		(layer "F.Cu")
		(net "M_E_CPU1_SA_DQ<28>")
	)
	(gr_poly
		(pts
			(xy 143.575532 -279.582372) (xy 143.668242 -279.527) (xy 143.630904 -279.340056) (xy 143.524224 -279.324562)
			(xy 143.474186 -279.334468) (xy 143.525748 -279.592278)
		)
		(stroke
			(width 0)
			(type solid)
		)
		(fill yes)
		(layer "F.Cu")
		(net "M_E_CPU1_SA_DQ<17>")
	)
	(gr_poly
		(pts
			(xy 143.576548 -239.263682) (xy 143.54048 -239.227868) (xy 143.443198 -239.18164) (xy 143.308324 -239.31626)
			(xy 143.354552 -239.413796) (xy 143.39062 -239.44961)
		)
		(stroke
			(width 0)
			(type solid)
		)
		(fill yes)
		(layer "F.Cu")
		(net "M_E_CPU1_SB_CB<1>")
	)
	(gr_poly
		(pts
			(xy 143.57858 -255.63957) (xy 143.614394 -255.603502) (xy 143.428466 -255.417574) (xy 143.392652 -255.453642)
			(xy 143.346424 -255.550924) (xy 143.481044 -255.685798)
		)
		(stroke
			(width 0)
			(type solid)
		)
		(fill yes)
		(layer "F.Cu")
		(net "M_E_CPU1_SA_CA<6>")
	)
	(gr_poly
		(pts
			(xy 143.581882 -267.464794) (xy 143.61795 -267.42898) (xy 143.432022 -267.243052) (xy 143.395954 -267.278866)
			(xy 143.349726 -267.376402) (xy 143.484346 -267.511022)
		)
		(stroke
			(width 0)
			(type solid)
		)
		(fill yes)
		(layer "F.Cu")
		(net "M_E_CPU1_SA_DQ<29>")
	)
	(gr_poly
		(pts
			(xy 143.583914 -242.598956) (xy 143.547592 -242.497356) (xy 143.357092 -242.497356) (xy 143.321024 -242.598956)
			(xy 143.321024 -242.649756) (xy 143.583914 -242.649756)
		)
		(stroke
			(width 0)
			(type solid)
		)
		(fill yes)
		(layer "F.Cu")
		(net "M_E_CPU1_SB_CB<4>")
	)
	(gr_poly
		(pts
			(xy 143.583914 -242.294156) (xy 143.547592 -242.192556) (xy 143.357092 -242.192556) (xy 143.321024 -242.294156)
			(xy 143.321024 -242.344956) (xy 143.583914 -242.344956)
		)
		(stroke
			(width 0)
			(type solid)
		)
		(fill yes)
		(layer "F.Cu")
		(net "M_E_CPU1_SB_CB<6>")
	)
	(gr_poly
		(pts
			(xy 143.583914 -241.989356) (xy 143.547592 -241.887756) (xy 143.357092 -241.887756) (xy 143.321024 -241.989356)
			(xy 143.321024 -242.040156) (xy 143.583914 -242.040156)
		)
		(stroke
			(width 0)
			(type solid)
		)
		(fill yes)
		(layer "F.Cu")
		(net "M_E_CPU1_SB_CB<5>")
	)
	(gr_poly
		(pts
			(xy 143.583914 -241.684556) (xy 143.547592 -241.582956) (xy 143.357092 -241.582956) (xy 143.321024 -241.684556)
			(xy 143.321024 -241.735356) (xy 143.583914 -241.735356)
		)
		(stroke
			(width 0)
			(type solid)
		)
		(fill yes)
		(layer "F.Cu")
		(net "M_E_CPU1_SB_CB<7>")
	)
	(gr_poly
		(pts
			(xy 143.584422 -279.884886) (xy 143.53286 -279.627076) (xy 143.483076 -279.636982) (xy 143.390366 -279.692608)
			(xy 143.427704 -279.879298) (xy 143.534638 -279.894792)
		)
		(stroke
			(width 0)
			(type solid)
		)
		(fill yes)
		(layer "F.Cu")
		(net "M_E_CPU1_SA_DQ<17>")
	)
	(gr_poly
		(pts
			(xy 143.593058 -231.306624) (xy 143.54683 -231.209088) (xy 143.510762 -231.173274) (xy 143.325088 -231.358948)
			(xy 143.360902 -231.395016) (xy 143.458438 -231.441244)
		)
		(stroke
			(width 0)
			(type solid)
		)
		(fill yes)
		(layer "F.Cu")
		(net "M_E_CPU1_SB_DQ<19>")
	)
	(gr_poly
		(pts
			(xy 143.59509 -273.966178) (xy 143.630904 -273.93011) (xy 143.444976 -273.744436) (xy 143.409162 -273.78025)
			(xy 143.362934 -273.877786) (xy 143.497554 -274.012406)
		)
		(stroke
			(width 0)
			(type solid)
		)
		(fill yes)
		(layer "F.Cu")
		(net "M_E_CPU1_SA_DQ<20>")
	)
	(gr_poly
		(pts
			(xy 143.602202 -232.15981) (xy 143.555974 -232.062528) (xy 143.52016 -232.02646) (xy 143.334232 -232.212388)
			(xy 143.370046 -232.248456) (xy 143.467582 -232.294684)
		)
		(stroke
			(width 0)
			(type solid)
		)
		(fill yes)
		(layer "F.Cu")
		(net "M_E_CPU1_SB_DQ<18>")
	)
	(gr_poly
		(pts
			(xy 143.604234 -273.112484) (xy 143.640302 -273.07667) (xy 143.454374 -272.890742) (xy 143.41856 -272.926556)
			(xy 143.372332 -273.024092) (xy 143.506952 -273.158712)
		)
		(stroke
			(width 0)
			(type solid)
		)
		(fill yes)
		(layer "F.Cu")
		(net "M_E_CPU1_SA_DQ<21>")
	)
	(gr_poly
		(pts
			(xy 143.605758 -262.41629) (xy 143.641572 -262.380222) (xy 143.455644 -262.194294) (xy 143.41983 -262.230362)
			(xy 143.373602 -262.327644) (xy 143.508222 -262.462518)
		)
		(stroke
			(width 0)
			(type solid)
		)
		(fill yes)
		(layer "F.Cu")
		(net "M_E_CPU1_SA_CB<6>")
	)
	(gr_poly
		(pts
			(xy 143.611092 -233.857038) (xy 143.564864 -233.759502) (xy 143.528796 -233.723688) (xy 143.342868 -233.909616)
			(xy 143.378936 -233.94543) (xy 143.476218 -233.991658)
		)
		(stroke
			(width 0)
			(type solid)
		)
		(fill yes)
		(layer "F.Cu")
		(net "M_E_CPU1_SB_DQ<13>")
	)
	(gr_poly
		(pts
			(xy 143.613124 -271.415002) (xy 143.649192 -271.379188) (xy 143.463264 -271.19326) (xy 143.42745 -271.229074)
			(xy 143.381222 -271.32661) (xy 143.515842 -271.46123)
		)
		(stroke
			(width 0)
			(type solid)
		)
		(fill yes)
		(layer "F.Cu")
		(net "M_E_CPU1_SA_DQ<26>")
	)
	(gr_poly
		(pts
			(xy 143.614902 -261.56285) (xy 143.650716 -261.526782) (xy 143.465042 -261.341108) (xy 143.428974 -261.376922)
			(xy 143.382746 -261.474458) (xy 143.517366 -261.609078)
		)
		(stroke
			(width 0)
			(type solid)
		)
		(fill yes)
		(layer "F.Cu")
		(net "M_E_CPU1_SA_CB<7>")
	)
	(gr_poly
		(pts
			(xy 143.615664 -266.164822) (xy 143.661892 -266.067286) (xy 143.527272 -265.932666) (xy 143.429736 -265.978894)
			(xy 143.393922 -266.014962) (xy 143.579596 -266.200636)
		)
		(stroke
			(width 0)
			(type solid)
		)
		(fill yes)
		(layer "F.Cu")
		(net "M_E_CPU1_SA_CB<0>")
	)
	(gr_poly
		(pts
			(xy 143.618712 -226.800156) (xy 143.567912 -226.800156) (xy 143.466312 -226.836478) (xy 143.466312 -227.026978)
			(xy 143.567912 -227.063046) (xy 143.618712 -227.063046)
		)
		(stroke
			(width 0)
			(type solid)
		)
		(fill yes)
		(layer "F.Cu")
		(net "M_E_CPU1_SB_DQ<23>")
	)
	(gr_poly
		(pts
			(xy 143.618712 -226.203256) (xy 143.567912 -226.203256) (xy 143.466312 -226.239578) (xy 143.466312 -226.430078)
			(xy 143.567912 -226.466146) (xy 143.618712 -226.466146)
		)
		(stroke
			(width 0)
			(type solid)
		)
		(fill yes)
		(layer "F.Cu")
		(net "M_E_CPU1_SB_DQ<23>")
	)
	(gr_poly
		(pts
			(xy 143.618712 -225.606356) (xy 143.567912 -225.606356) (xy 143.466312 -225.642678) (xy 143.466312 -225.833178)
			(xy 143.567912 -225.869246) (xy 143.618712 -225.869246)
		)
		(stroke
			(width 0)
			(type solid)
		)
		(fill yes)
		(layer "F.Cu")
		(net "M_E_CPU1_SB_DQ<23>")
	)
	(gr_poly
		(pts
			(xy 143.618712 -225.009456) (xy 143.567912 -225.009456) (xy 143.466312 -225.045778) (xy 143.466312 -225.236278)
			(xy 143.567912 -225.272346) (xy 143.618712 -225.272346)
		)
		(stroke
			(width 0)
			(type solid)
		)
		(fill yes)
		(layer "F.Cu")
		(net "M_E_CPU1_SB_DQ<23>")
	)
	(gr_poly
		(pts
			(xy 143.618712 -224.412556) (xy 143.567912 -224.412556) (xy 143.466312 -224.448878) (xy 143.466312 -224.639378)
			(xy 143.567912 -224.675446) (xy 143.618712 -224.675446)
		)
		(stroke
			(width 0)
			(type solid)
		)
		(fill yes)
		(layer "F.Cu")
		(net "M_E_CPU1_SB_DQ<23>")
	)
	(gr_poly
		(pts
			(xy 143.618712 -223.815656) (xy 143.567912 -223.815656) (xy 143.466312 -223.851978) (xy 143.466312 -224.042478)
			(xy 143.567912 -224.078546) (xy 143.618712 -224.078546)
		)
		(stroke
			(width 0)
			(type solid)
		)
		(fill yes)
		(layer "F.Cu")
		(net "M_E_CPU1_SB_DQ<23>")
	)
	(gr_poly
		(pts
			(xy 143.618712 -223.218756) (xy 143.567912 -223.218756) (xy 143.466312 -223.255078) (xy 143.466312 -223.445578)
			(xy 143.567912 -223.481646) (xy 143.618712 -223.481646)
		)
		(stroke
			(width 0)
			(type solid)
		)
		(fill yes)
		(layer "F.Cu")
		(net "M_E_CPU1_SB_DQ<23>")
	)
	(gr_poly
		(pts
			(xy 143.618712 -222.621856) (xy 143.567912 -222.621856) (xy 143.466312 -222.658178) (xy 143.466312 -222.848678)
			(xy 143.567912 -222.884746) (xy 143.618712 -222.884746)
		)
		(stroke
			(width 0)
			(type solid)
		)
		(fill yes)
		(layer "F.Cu")
		(net "M_E_CPU1_SB_DQ<23>")
	)
	(gr_poly
		(pts
			(xy 143.618712 -222.024956) (xy 143.567912 -222.024956) (xy 143.466312 -222.061278) (xy 143.466312 -222.251778)
			(xy 143.567912 -222.287846) (xy 143.618712 -222.287846)
		)
		(stroke
			(width 0)
			(type solid)
		)
		(fill yes)
		(layer "F.Cu")
		(net "M_E_CPU1_SB_DQ<23>")
	)
	(gr_poly
		(pts
			(xy 143.618712 -221.428056) (xy 143.567912 -221.428056) (xy 143.466312 -221.464378) (xy 143.466312 -221.654878)
			(xy 143.567912 -221.690946) (xy 143.618712 -221.690946)
		)
		(stroke
			(width 0)
			(type solid)
		)
		(fill yes)
		(layer "F.Cu")
		(net "M_E_CPU1_SB_DQ<23>")
	)
	(gr_poly
		(pts
			(xy 143.618712 -220.831156) (xy 143.567912 -220.831156) (xy 143.466312 -220.867478) (xy 143.466312 -221.057978)
			(xy 143.567912 -221.094046) (xy 143.618712 -221.094046)
		)
		(stroke
			(width 0)
			(type solid)
		)
		(fill yes)
		(layer "F.Cu")
		(net "M_E_CPU1_SB_DQ<23>")
	)
	(gr_poly
		(pts
			(xy 143.618712 -220.234256) (xy 143.567912 -220.234256) (xy 143.466312 -220.270578) (xy 143.466312 -220.461078)
			(xy 143.567912 -220.497146) (xy 143.618712 -220.497146)
		)
		(stroke
			(width 0)
			(type solid)
		)
		(fill yes)
		(layer "F.Cu")
		(net "M_E_CPU1_SB_DQ<23>")
	)
	(gr_poly
		(pts
			(xy 143.618712 -219.637356) (xy 143.567912 -219.637356) (xy 143.466312 -219.673678) (xy 143.466312 -219.864178)
			(xy 143.567912 -219.900246) (xy 143.618712 -219.900246)
		)
		(stroke
			(width 0)
			(type solid)
		)
		(fill yes)
		(layer "F.Cu")
		(net "M_E_CPU1_SB_DQ<23>")
	)
	(gr_poly
		(pts
			(xy 143.618712 -219.040456) (xy 143.567912 -219.040456) (xy 143.466312 -219.076778) (xy 143.466312 -219.267278)
			(xy 143.567912 -219.303346) (xy 143.618712 -219.303346)
		)
		(stroke
			(width 0)
			(type solid)
		)
		(fill yes)
		(layer "F.Cu")
		(net "M_E_CPU1_SB_DQ<23>")
	)
	(gr_poly
		(pts
			(xy 143.618712 -218.443556) (xy 143.567912 -218.443556) (xy 143.466312 -218.479878) (xy 143.466312 -218.670378)
			(xy 143.567912 -218.706446) (xy 143.618712 -218.706446)
		)
		(stroke
			(width 0)
			(type solid)
		)
		(fill yes)
		(layer "F.Cu")
		(net "M_E_CPU1_SB_DQ<23>")
	)
	(gr_poly
		(pts
			(xy 143.618712 -217.846656) (xy 143.567912 -217.846656) (xy 143.466312 -217.882978) (xy 143.466312 -218.073478)
			(xy 143.567912 -218.109546) (xy 143.618712 -218.109546)
		)
		(stroke
			(width 0)
			(type solid)
		)
		(fill yes)
		(layer "F.Cu")
		(net "M_E_CPU1_SB_DQ<23>")
	)
	(gr_poly
		(pts
			(xy 143.618712 -217.249756) (xy 143.567912 -217.249756) (xy 143.466312 -217.286078) (xy 143.466312 -217.476578)
			(xy 143.567912 -217.512646) (xy 143.618712 -217.512646)
		)
		(stroke
			(width 0)
			(type solid)
		)
		(fill yes)
		(layer "F.Cu")
		(net "M_E_CPU1_SB_DQ<23>")
	)
	(gr_poly
		(pts
			(xy 143.618712 -216.652856) (xy 143.567912 -216.652856) (xy 143.466312 -216.689178) (xy 143.466312 -216.879678)
			(xy 143.567912 -216.915746) (xy 143.618712 -216.915746)
		)
		(stroke
			(width 0)
			(type solid)
		)
		(fill yes)
		(layer "F.Cu")
		(net "M_E_CPU1_SB_DQ<23>")
	)
	(gr_poly
		(pts
			(xy 143.618712 -216.055956) (xy 143.567912 -216.055956) (xy 143.466312 -216.092278) (xy 143.466312 -216.282778)
			(xy 143.567912 -216.318846) (xy 143.618712 -216.318846)
		)
		(stroke
			(width 0)
			(type solid)
		)
		(fill yes)
		(layer "F.Cu")
		(net "M_E_CPU1_SB_DQ<23>")
	)
	(gr_poly
		(pts
			(xy 143.618712 -215.459056) (xy 143.567912 -215.459056) (xy 143.466312 -215.495378) (xy 143.466312 -215.685878)
			(xy 143.567912 -215.721946) (xy 143.618712 -215.721946)
		)
		(stroke
			(width 0)
			(type solid)
		)
		(fill yes)
		(layer "F.Cu")
		(net "M_E_CPU1_SB_DQ<23>")
	)
	(gr_poly
		(pts
			(xy 143.618712 -214.862156) (xy 143.567912 -214.862156) (xy 143.466312 -214.898478) (xy 143.466312 -215.088978)
			(xy 143.567912 -215.125046) (xy 143.618712 -215.125046)
		)
		(stroke
			(width 0)
			(type solid)
		)
		(fill yes)
		(layer "F.Cu")
		(net "M_E_CPU1_SB_DQ<23>")
	)
	(gr_poly
		(pts
			(xy 143.620236 -234.710224) (xy 143.574008 -234.612942) (xy 143.538194 -234.576874) (xy 143.352266 -234.762802)
			(xy 143.38808 -234.79887) (xy 143.485616 -234.845098)
		)
		(stroke
			(width 0)
			(type solid)
		)
		(fill yes)
		(layer "F.Cu")
		(net "M_E_CPU1_SB_DQ<12>")
	)
	(gr_poly
		(pts
			(xy 143.622522 -270.561562) (xy 143.658336 -270.525748) (xy 143.472408 -270.33982) (xy 143.436594 -270.375634)
			(xy 143.390366 -270.47317) (xy 143.524986 -270.60779)
		)
		(stroke
			(width 0)
			(type solid)
		)
		(fill yes)
		(layer "F.Cu")
		(net "M_E_CPU1_SA_DQ<27>")
	)
	(gr_poly
		(pts
			(xy 143.624808 -265.311382) (xy 143.671036 -265.2141) (xy 143.536416 -265.079226) (xy 143.43888 -265.125454)
			(xy 143.403066 -265.161522) (xy 143.588994 -265.34745)
		)
		(stroke
			(width 0)
			(type solid)
		)
		(fill yes)
		(layer "F.Cu")
		(net "M_E_CPU1_SA_CB<1>")
	)
	(gr_poly
		(pts
			(xy 143.627348 -257.701034) (xy 143.673576 -257.603498) (xy 143.538956 -257.468878) (xy 143.44142 -257.515106)
			(xy 143.405606 -257.551174) (xy 143.59128 -257.736848)
		)
		(stroke
			(width 0)
			(type solid)
		)
		(fill yes)
		(layer "F.Cu")
		(net "M_E_CPU1_SA_CA<1>")
	)
	(gr_poly
		(pts
			(xy 143.636492 -256.847594) (xy 143.68272 -256.750312) (xy 143.5481 -256.615438) (xy 143.450564 -256.661666)
			(xy 143.41475 -256.697734) (xy 143.600678 -256.883662)
		)
		(stroke
			(width 0)
			(type solid)
		)
		(fill yes)
		(layer "F.Cu")
		(net "M_E_CPU1_SA_CA<3>")
	)
	(gr_poly
		(pts
			(xy 143.641064 -278.351996) (xy 143.73352 -278.29637) (xy 143.696182 -278.10968) (xy 143.589502 -278.094186)
			(xy 143.539718 -278.104092) (xy 143.59128 -278.361902)
		)
		(stroke
			(width 0)
			(type solid)
		)
		(fill yes)
		(layer "F.Cu")
		(net "M_E_CPU1_SA_DQ<19>")
	)
	(gr_poly
		(pts
			(xy 143.645128 -237.273338) (xy 143.5989 -237.175802) (xy 143.563086 -237.139988) (xy 143.377158 -237.325916)
			(xy 143.412972 -237.36173) (xy 143.510508 -237.407958)
		)
		(stroke
			(width 0)
			(type solid)
		)
		(fill yes)
		(layer "F.Cu")
		(net "M_E_CPU1_SB_DQ<9>")
	)
	(gr_poly
		(pts
			(xy 143.645636 -255.994408) (xy 143.691864 -255.896872) (xy 143.557244 -255.762252) (xy 143.459962 -255.80848)
			(xy 143.423894 -255.844294) (xy 143.609822 -256.030222)
		)
		(stroke
			(width 0)
			(type solid)
		)
		(fill yes)
		(layer "F.Cu")
		(net "M_E_CPU1_SA_CA<5>")
	)
	(gr_poly
		(pts
			(xy 143.648938 -267.819632) (xy 143.695166 -267.72235) (xy 143.560546 -267.58773) (xy 143.46301 -267.633958)
			(xy 143.427196 -267.669772) (xy 143.613124 -267.8557)
		)
		(stroke
			(width 0)
			(type solid)
		)
		(fill yes)
		(layer "F.Cu")
		(net "M_E_CPU1_SA_DQ<30>")
	)
	(gr_poly
		(pts
			(xy 143.6497 -278.65451) (xy 143.598138 -278.3967) (xy 143.548354 -278.406606) (xy 143.455898 -278.461978)
			(xy 143.492982 -278.648922) (xy 143.599916 -278.664416)
		)
		(stroke
			(width 0)
			(type solid)
		)
		(fill yes)
		(layer "F.Cu")
		(net "M_E_CPU1_SA_DQ<19>")
	)
	(gr_poly
		(pts
			(xy 143.654018 -238.970312) (xy 143.60779 -238.87303) (xy 143.571976 -238.836962) (xy 143.386048 -239.02289)
			(xy 143.421862 -239.058958) (xy 143.519398 -239.105186)
		)
		(stroke
			(width 0)
			(type solid)
		)
		(fill yes)
		(layer "F.Cu")
		(net "M_E_CPU1_SB_CB<3>")
	)
	(gr_poly
		(pts
			(xy 143.655034 -255.140968) (xy 143.701262 -255.043432) (xy 143.566388 -254.908812) (xy 143.469106 -254.95504)
			(xy 143.433038 -254.990854) (xy 143.618966 -255.176782)
		)
		(stroke
			(width 0)
			(type solid)
		)
		(fill yes)
		(layer "F.Cu")
		(net "M_E_CPU1_SA_PAR")
	)
	(gr_poly
		(pts
			(xy 143.655288 -238.12754) (xy 143.60906 -238.030004) (xy 143.572992 -237.99419) (xy 143.387064 -238.180118)
			(xy 143.423132 -238.215932) (xy 143.520414 -238.26216)
		)
		(stroke
			(width 0)
			(type solid)
		)
		(fill yes)
		(layer "F.Cu")
		(net "M_E_CPU1_SB_DQ<8>")
	)
	(gr_poly
		(pts
			(xy 143.65859 -266.966192) (xy 143.704818 -266.868656) (xy 143.569944 -266.734036) (xy 143.472662 -266.780264)
			(xy 143.436594 -266.816078) (xy 143.622522 -267.002006)
		)
		(stroke
			(width 0)
			(type solid)
		)
		(fill yes)
		(layer "F.Cu")
		(net "M_E_CPU1_SA_DQ<31>")
	)
	(gr_poly
		(pts
			(xy 143.671544 -273.467322) (xy 143.717772 -273.37004) (xy 143.583152 -273.235166) (xy 143.485616 -273.281648)
			(xy 143.449802 -273.317462) (xy 143.63573 -273.50339)
		)
		(stroke
			(width 0)
			(type solid)
		)
		(fill yes)
		(layer "F.Cu")
		(net "M_E_CPU1_SA_DQ<22>")
	)
	(gr_poly
		(pts
			(xy 143.672814 -262.771128) (xy 143.719296 -262.673592) (xy 143.584422 -262.538972) (xy 143.48714 -262.5852)
			(xy 143.451072 -262.621014) (xy 143.637 -262.806942)
		)
		(stroke
			(width 0)
			(type solid)
		)
		(fill yes)
		(layer "F.Cu")
		(net "M_E_CPU1_SA_CB<4>")
	)
	(gr_poly
		(pts
			(xy 143.680434 -271.76984) (xy 143.726662 -271.672558) (xy 143.592042 -271.537938) (xy 143.494506 -271.584166)
			(xy 143.458692 -271.61998) (xy 143.64462 -271.805908)
		)
		(stroke
			(width 0)
			(type solid)
		)
		(fill yes)
		(layer "F.Cu")
		(net "M_E_CPU1_SA_DQ<24>")
	)
	(gr_poly
		(pts
			(xy 143.680942 -272.613882) (xy 143.72717 -272.516346) (xy 143.59255 -272.381726) (xy 143.495014 -272.427954)
			(xy 143.4592 -272.464022) (xy 143.644874 -272.649696)
		)
		(stroke
			(width 0)
			(type solid)
		)
		(fill yes)
		(layer "F.Cu")
		(net "M_E_CPU1_SA_DQ<23>")
	)
	(gr_poly
		(pts
			(xy 143.682212 -261.917688) (xy 143.72844 -261.820152) (xy 143.593566 -261.685532) (xy 143.496284 -261.73176)
			(xy 143.460216 -261.767574) (xy 143.646144 -261.953502)
		)
		(stroke
			(width 0)
			(type solid)
		)
		(fill yes)
		(layer "F.Cu")
		(net "M_E_CPU1_SA_CB<5>")
	)
	(gr_poly
		(pts
			(xy 143.689578 -270.9164) (xy 143.735806 -270.819118) (xy 143.601186 -270.684498) (xy 143.50365 -270.730726)
			(xy 143.467836 -270.76654) (xy 143.653764 -270.952468)
		)
		(stroke
			(width 0)
			(type solid)
		)
		(fill yes)
		(layer "F.Cu")
		(net "M_E_CPU1_SA_DQ<25>")
	)
	(gr_poly
		(pts
			(xy 143.692626 -280.167588) (xy 143.785082 -280.112216) (xy 143.747744 -279.925526) (xy 143.641064 -279.909778)
			(xy 143.59128 -279.919684) (xy 143.642842 -280.177494)
		)
		(stroke
			(width 0)
			(type solid)
		)
		(fill yes)
		(layer "F.Cu")
		(net "M_E_CPU1_SA_DQ<17>")
	)
	(gr_poly
		(pts
			(xy 143.69415 -289.247326) (xy 143.64335 -289.247326) (xy 143.54175 -289.283648) (xy 143.54175 -289.474148)
			(xy 143.64335 -289.51047) (xy 143.69415 -289.51047)
		)
		(stroke
			(width 0)
			(type solid)
		)
		(fill yes)
		(layer "F.Cu")
		(net "M_E_CPU1_SA_DQ<17>")
	)
	(gr_poly
		(pts
			(xy 143.69415 -288.650426) (xy 143.64335 -288.650426) (xy 143.54175 -288.686748) (xy 143.54175 -288.877248)
			(xy 143.64335 -288.91357) (xy 143.69415 -288.91357)
		)
		(stroke
			(width 0)
			(type solid)
		)
		(fill yes)
		(layer "F.Cu")
		(net "M_E_CPU1_SA_DQ<17>")
	)
	(gr_poly
		(pts
			(xy 143.69415 -288.053526) (xy 143.64335 -288.053526) (xy 143.54175 -288.089848) (xy 143.54175 -288.280348)
			(xy 143.64335 -288.31667) (xy 143.69415 -288.31667)
		)
		(stroke
			(width 0)
			(type solid)
		)
		(fill yes)
		(layer "F.Cu")
		(net "M_E_CPU1_SA_DQ<17>")
	)
	(gr_poly
		(pts
			(xy 143.69415 -287.456626) (xy 143.64335 -287.456626) (xy 143.54175 -287.492948) (xy 143.54175 -287.683448)
			(xy 143.64335 -287.71977) (xy 143.69415 -287.71977)
		)
		(stroke
			(width 0)
			(type solid)
		)
		(fill yes)
		(layer "F.Cu")
		(net "M_E_CPU1_SA_DQ<17>")
	)
	(gr_poly
		(pts
			(xy 143.69415 -286.859726) (xy 143.64335 -286.859726) (xy 143.54175 -286.896048) (xy 143.54175 -287.086548)
			(xy 143.64335 -287.12287) (xy 143.69415 -287.12287)
		)
		(stroke
			(width 0)
			(type solid)
		)
		(fill yes)
		(layer "F.Cu")
		(net "M_E_CPU1_SA_DQ<17>")
	)
	(gr_poly
		(pts
			(xy 143.69415 -286.262826) (xy 143.64335 -286.262826) (xy 143.54175 -286.299148) (xy 143.54175 -286.489648)
			(xy 143.64335 -286.52597) (xy 143.69415 -286.52597)
		)
		(stroke
			(width 0)
			(type solid)
		)
		(fill yes)
		(layer "F.Cu")
		(net "M_E_CPU1_SA_DQ<17>")
	)
	(gr_poly
		(pts
			(xy 143.69415 -285.665926) (xy 143.64335 -285.665926) (xy 143.54175 -285.702248) (xy 143.54175 -285.892748)
			(xy 143.64335 -285.92907) (xy 143.69415 -285.92907)
		)
		(stroke
			(width 0)
			(type solid)
		)
		(fill yes)
		(layer "F.Cu")
		(net "M_E_CPU1_SA_DQ<17>")
	)
	(gr_poly
		(pts
			(xy 143.69415 -285.069026) (xy 143.64335 -285.069026) (xy 143.54175 -285.105348) (xy 143.54175 -285.295848)
			(xy 143.64335 -285.33217) (xy 143.69415 -285.33217)
		)
		(stroke
			(width 0)
			(type solid)
		)
		(fill yes)
		(layer "F.Cu")
		(net "M_E_CPU1_SA_DQ<17>")
	)
	(gr_poly
		(pts
			(xy 143.69415 -284.472126) (xy 143.64335 -284.472126) (xy 143.54175 -284.508448) (xy 143.54175 -284.698948)
			(xy 143.64335 -284.73527) (xy 143.69415 -284.73527)
		)
		(stroke
			(width 0)
			(type solid)
		)
		(fill yes)
		(layer "F.Cu")
		(net "M_E_CPU1_SA_DQ<17>")
	)
	(gr_poly
		(pts
			(xy 143.69415 -283.875226) (xy 143.64335 -283.875226) (xy 143.54175 -283.911548) (xy 143.54175 -284.102048)
			(xy 143.64335 -284.13837) (xy 143.69415 -284.13837)
		)
		(stroke
			(width 0)
			(type solid)
		)
		(fill yes)
		(layer "F.Cu")
		(net "M_E_CPU1_SA_DQ<17>")
	)
	(gr_poly
		(pts
			(xy 143.69415 -283.278326) (xy 143.64335 -283.278326) (xy 143.54175 -283.314648) (xy 143.54175 -283.505148)
			(xy 143.64335 -283.54147) (xy 143.69415 -283.54147)
		)
		(stroke
			(width 0)
			(type solid)
		)
		(fill yes)
		(layer "F.Cu")
		(net "M_E_CPU1_SA_DQ<17>")
	)
	(gr_poly
		(pts
			(xy 143.69415 -282.681426) (xy 143.64335 -282.681426) (xy 143.54175 -282.717748) (xy 143.54175 -282.908248)
			(xy 143.64335 -282.94457) (xy 143.69415 -282.94457)
		)
		(stroke
			(width 0)
			(type solid)
		)
		(fill yes)
		(layer "F.Cu")
		(net "M_E_CPU1_SA_DQ<17>")
	)
	(gr_poly
		(pts
			(xy 143.69415 -282.084526) (xy 143.64335 -282.084526) (xy 143.54175 -282.120848) (xy 143.54175 -282.311348)
			(xy 143.64335 -282.34767) (xy 143.69415 -282.34767)
		)
		(stroke
			(width 0)
			(type solid)
		)
		(fill yes)
		(layer "F.Cu")
		(net "M_E_CPU1_SA_DQ<17>")
	)
	(gr_poly
		(pts
			(xy 143.69415 -281.487626) (xy 143.64335 -281.487626) (xy 143.54175 -281.523948) (xy 143.54175 -281.714448)
			(xy 143.64335 -281.75077) (xy 143.69415 -281.75077)
		)
		(stroke
			(width 0)
			(type solid)
		)
		(fill yes)
		(layer "F.Cu")
		(net "M_E_CPU1_SA_DQ<17>")
	)
	(gr_poly
		(pts
			(xy 143.69415 -280.890726) (xy 143.64335 -280.890726) (xy 143.54175 -280.927048) (xy 143.54175 -281.117548)
			(xy 143.64335 -281.15387) (xy 143.69415 -281.15387)
		)
		(stroke
			(width 0)
			(type solid)
		)
		(fill yes)
		(layer "F.Cu")
		(net "M_E_CPU1_SA_DQ<17>")
	)
	(gr_poly
		(pts
			(xy 143.694912 -228.400864) (xy 143.659098 -228.364796) (xy 143.561562 -228.318568) (xy 143.426942 -228.453188)
			(xy 143.47317 -228.550724) (xy 143.509238 -228.586538)
		)
		(stroke
			(width 0)
			(type solid)
		)
		(fill yes)
		(layer "F.Cu")
		(net "M_E_CPU1_SB_DQ<22>")
	)
	(gr_poly
		(pts
			(xy 143.721836 -230.9622) (xy 143.686022 -230.926132) (xy 143.588486 -230.879904) (xy 143.453866 -231.014778)
			(xy 143.500094 -231.11206) (xy 143.535908 -231.148128)
		)
		(stroke
			(width 0)
			(type solid)
		)
		(fill yes)
		(layer "F.Cu")
		(net "M_E_CPU1_SB_DQ<19>")
	)
	(gr_poly
		(pts
			(xy 143.731234 -231.815386) (xy 143.695166 -231.779572) (xy 143.597884 -231.733344) (xy 143.46301 -231.867964)
			(xy 143.509238 -231.9655) (xy 143.545306 -232.001314)
		)
		(stroke
			(width 0)
			(type solid)
		)
		(fill yes)
		(layer "F.Cu")
		(net "M_E_CPU1_SB_DQ<18>")
	)
	(gr_poly
		(pts
			(xy 143.73987 -233.512614) (xy 143.704056 -233.476546) (xy 143.60652 -233.430318) (xy 143.4719 -233.565192)
			(xy 143.518128 -233.662474) (xy 143.553942 -233.698542)
		)
		(stroke
			(width 0)
			(type solid)
		)
		(fill yes)
		(layer "F.Cu")
		(net "M_E_CPU1_SB_DQ<13>")
	)
	(gr_poly
		(pts
			(xy 143.749014 -234.366054) (xy 143.7132 -234.329986) (xy 143.615664 -234.283758) (xy 143.481044 -234.418378)
			(xy 143.527272 -234.515914) (xy 143.56334 -234.551728)
		)
		(stroke
			(width 0)
			(type solid)
		)
		(fill yes)
		(layer "F.Cu")
		(net "M_E_CPU1_SB_DQ<12>")
	)
	(gr_poly
		(pts
			(xy 143.754348 -248.967752) (xy 143.71828 -248.866152) (xy 143.52778 -248.866152) (xy 143.491712 -248.967752)
			(xy 143.491712 -249.018552) (xy 143.754348 -249.018552)
		)
		(stroke
			(width 0)
			(type solid)
		)
		(fill yes)
		(layer "F.Cu")
		(net "M_E_CPU1_SB_CA<0>")
	)
	(gr_poly
		(pts
			(xy 143.754348 -248.662952) (xy 143.71828 -248.561352) (xy 143.52778 -248.561352) (xy 143.491712 -248.662952)
			(xy 143.491712 -248.713752) (xy 143.754348 -248.713752)
		)
		(stroke
			(width 0)
			(type solid)
		)
		(fill yes)
		(layer "F.Cu")
		(net "M_E_CPU1_SB_CA<1>")
	)
	(gr_poly
		(pts
			(xy 143.754348 -248.358152) (xy 143.71828 -248.256552) (xy 143.52778 -248.256552) (xy 143.491712 -248.358152)
			(xy 143.491712 -248.408952) (xy 143.754348 -248.408952)
		)
		(stroke
			(width 0)
			(type solid)
		)
		(fill yes)
		(layer "F.Cu")
		(net "M_E_CPU1_SB_CA<2>")
	)
	(gr_poly
		(pts
			(xy 143.754348 -248.053352) (xy 143.71828 -247.951752) (xy 143.52778 -247.951752) (xy 143.491712 -248.053352)
			(xy 143.491712 -248.104152) (xy 143.754348 -248.104152)
		)
		(stroke
			(width 0)
			(type solid)
		)
		(fill yes)
		(layer "F.Cu")
		(net "M_E_CPU1_SB_CA<3>")
	)
	(gr_poly
		(pts
			(xy 143.754348 -247.748552) (xy 143.71828 -247.646952) (xy 143.52778 -247.646952) (xy 143.491712 -247.748552)
			(xy 143.491712 -247.799352) (xy 143.754348 -247.799352)
		)
		(stroke
			(width 0)
			(type solid)
		)
		(fill yes)
		(layer "F.Cu")
		(net "M_E_CPU1_SB_CA<4>")
	)
	(gr_poly
		(pts
			(xy 143.754348 -247.443752) (xy 143.71828 -247.342152) (xy 143.52778 -247.342152) (xy 143.491712 -247.443752)
			(xy 143.491712 -247.494552) (xy 143.754348 -247.494552)
		)
		(stroke
			(width 0)
			(type solid)
		)
		(fill yes)
		(layer "F.Cu")
		(net "M_E_CPU1_SB_CA<5>")
	)
	(gr_poly
		(pts
			(xy 143.754348 -247.138952) (xy 143.71828 -247.037352) (xy 143.52778 -247.037352) (xy 143.491712 -247.138952)
			(xy 143.491712 -247.189752) (xy 143.754348 -247.189752)
		)
		(stroke
			(width 0)
			(type solid)
		)
		(fill yes)
		(layer "F.Cu")
		(net "M_E_CPU1_SB_CA<6>")
	)
	(gr_poly
		(pts
			(xy 143.754348 -246.834152) (xy 143.71828 -246.732552) (xy 143.52778 -246.732552) (xy 143.491712 -246.834152)
			(xy 143.491712 -246.884952) (xy 143.754348 -246.884952)
		)
		(stroke
			(width 0)
			(type solid)
		)
		(fill yes)
		(layer "F.Cu")
		(net "M_E_CPU1_SB_PAR")
	)
	(gr_poly
		(pts
			(xy 143.754348 -246.529352) (xy 143.71828 -246.427752) (xy 143.52778 -246.427752) (xy 143.491712 -246.529352)
			(xy 143.491712 -246.580152) (xy 143.754348 -246.580152)
		)
		(stroke
			(width 0)
			(type solid)
		)
		(fill yes)
		(layer "F.Cu")
		(net "M_E_CPU1_SB_CS_N<0>")
	)
	(gr_poly
		(pts
			(xy 143.754856 -266.447778) (xy 143.79067 -266.41171) (xy 143.604742 -266.225782) (xy 143.568928 -266.26185)
			(xy 143.5227 -266.359132) (xy 143.65732 -266.494006)
		)
		(stroke
			(width 0)
			(type solid)
		)
		(fill yes)
		(layer "F.Cu")
		(net "M_E_CPU1_SA_CB<0>")
	)
	(gr_poly
		(pts
			(xy 143.757904 -278.937212) (xy 143.85036 -278.88184) (xy 143.813022 -278.694896) (xy 143.706342 -278.679402)
			(xy 143.656558 -278.689308) (xy 143.70812 -278.947118)
		)
		(stroke
			(width 0)
			(type solid)
		)
		(fill yes)
		(layer "F.Cu")
		(net "M_E_CPU1_SA_DQ<19>")
	)
	(gr_poly
		(pts
			(xy 143.764 -265.594338) (xy 143.800068 -265.558524) (xy 143.61414 -265.372596) (xy 143.578072 -265.40841)
			(xy 143.531844 -265.505946) (xy 143.666718 -265.640566)
		)
		(stroke
			(width 0)
			(type solid)
		)
		(fill yes)
		(layer "F.Cu")
		(net "M_E_CPU1_SA_CB<1>")
	)
	(gr_poly
		(pts
			(xy 143.76654 -279.239726) (xy 143.714978 -278.981916) (xy 143.665194 -278.992076) (xy 143.572738 -279.047448)
			(xy 143.610076 -279.234138) (xy 143.716756 -279.249886)
		)
		(stroke
			(width 0)
			(type solid)
		)
		(fill yes)
		(layer "F.Cu")
		(net "M_E_CPU1_SA_DQ<19>")
	)
	(gr_poly
		(pts
			(xy 143.771112 -227.325174) (xy 143.771112 -227.134674) (xy 143.669512 -227.098606) (xy 143.618712 -227.098606)
			(xy 143.618712 -227.361496) (xy 143.669512 -227.361496)
		)
		(stroke
			(width 0)
			(type solid)
		)
		(fill yes)
		(layer "F.Cu")
		(net "M_E_CPU1_SB_DQ<23>")
	)
	(gr_poly
		(pts
			(xy 143.771112 -226.728274) (xy 143.771112 -226.537774) (xy 143.669512 -226.501706) (xy 143.618712 -226.501706)
			(xy 143.618712 -226.764596) (xy 143.669512 -226.764596)
		)
		(stroke
			(width 0)
			(type solid)
		)
		(fill yes)
		(layer "F.Cu")
		(net "M_E_CPU1_SB_DQ<23>")
	)
	(gr_poly
		(pts
			(xy 143.771112 -226.131374) (xy 143.771112 -225.940874) (xy 143.669512 -225.904806) (xy 143.618712 -225.904806)
			(xy 143.618712 -226.167696) (xy 143.669512 -226.167696)
		)
		(stroke
			(width 0)
			(type solid)
		)
		(fill yes)
		(layer "F.Cu")
		(net "M_E_CPU1_SB_DQ<23>")
	)
	(gr_poly
		(pts
			(xy 143.771112 -225.534474) (xy 143.771112 -225.343974) (xy 143.669512 -225.307906) (xy 143.618712 -225.307906)
			(xy 143.618712 -225.570796) (xy 143.669512 -225.570796)
		)
		(stroke
			(width 0)
			(type solid)
		)
		(fill yes)
		(layer "F.Cu")
		(net "M_E_CPU1_SB_DQ<23>")
	)
	(gr_poly
		(pts
			(xy 143.771112 -224.937574) (xy 143.771112 -224.747074) (xy 143.669512 -224.711006) (xy 143.618712 -224.711006)
			(xy 143.618712 -224.973896) (xy 143.669512 -224.973896)
		)
		(stroke
			(width 0)
			(type solid)
		)
		(fill yes)
		(layer "F.Cu")
		(net "M_E_CPU1_SB_DQ<23>")
	)
	(gr_poly
		(pts
			(xy 143.771112 -224.340674) (xy 143.771112 -224.150174) (xy 143.669512 -224.114106) (xy 143.618712 -224.114106)
			(xy 143.618712 -224.376996) (xy 143.669512 -224.376996)
		)
		(stroke
			(width 0)
			(type solid)
		)
		(fill yes)
		(layer "F.Cu")
		(net "M_E_CPU1_SB_DQ<23>")
	)
	(gr_poly
		(pts
			(xy 143.771112 -223.743774) (xy 143.771112 -223.553274) (xy 143.669512 -223.517206) (xy 143.618712 -223.517206)
			(xy 143.618712 -223.780096) (xy 143.669512 -223.780096)
		)
		(stroke
			(width 0)
			(type solid)
		)
		(fill yes)
		(layer "F.Cu")
		(net "M_E_CPU1_SB_DQ<23>")
	)
	(gr_poly
		(pts
			(xy 143.771112 -223.146874) (xy 143.771112 -222.956374) (xy 143.669512 -222.920306) (xy 143.618712 -222.920306)
			(xy 143.618712 -223.183196) (xy 143.669512 -223.183196)
		)
		(stroke
			(width 0)
			(type solid)
		)
		(fill yes)
		(layer "F.Cu")
		(net "M_E_CPU1_SB_DQ<23>")
	)
	(gr_poly
		(pts
			(xy 143.771112 -222.549974) (xy 143.771112 -222.359474) (xy 143.669512 -222.323406) (xy 143.618712 -222.323406)
			(xy 143.618712 -222.586296) (xy 143.669512 -222.586296)
		)
		(stroke
			(width 0)
			(type solid)
		)
		(fill yes)
		(layer "F.Cu")
		(net "M_E_CPU1_SB_DQ<23>")
	)
	(gr_poly
		(pts
			(xy 143.771112 -221.953074) (xy 143.771112 -221.762574) (xy 143.669512 -221.726506) (xy 143.618712 -221.726506)
			(xy 143.618712 -221.989396) (xy 143.669512 -221.989396)
		)
		(stroke
			(width 0)
			(type solid)
		)
		(fill yes)
		(layer "F.Cu")
		(net "M_E_CPU1_SB_DQ<23>")
	)
	(gr_poly
		(pts
			(xy 143.771112 -221.356174) (xy 143.771112 -221.165674) (xy 143.669512 -221.129606) (xy 143.618712 -221.129606)
			(xy 143.618712 -221.392496) (xy 143.669512 -221.392496)
		)
		(stroke
			(width 0)
			(type solid)
		)
		(fill yes)
		(layer "F.Cu")
		(net "M_E_CPU1_SB_DQ<23>")
	)
	(gr_poly
		(pts
			(xy 143.771112 -220.759274) (xy 143.771112 -220.568774) (xy 143.669512 -220.532706) (xy 143.618712 -220.532706)
			(xy 143.618712 -220.795596) (xy 143.669512 -220.795596)
		)
		(stroke
			(width 0)
			(type solid)
		)
		(fill yes)
		(layer "F.Cu")
		(net "M_E_CPU1_SB_DQ<23>")
	)
	(gr_poly
		(pts
			(xy 143.771112 -220.162374) (xy 143.771112 -219.971874) (xy 143.669512 -219.935806) (xy 143.618712 -219.935806)
			(xy 143.618712 -220.198696) (xy 143.669512 -220.198696)
		)
		(stroke
			(width 0)
			(type solid)
		)
		(fill yes)
		(layer "F.Cu")
		(net "M_E_CPU1_SB_DQ<23>")
	)
	(gr_poly
		(pts
			(xy 143.771112 -219.565474) (xy 143.771112 -219.374974) (xy 143.669512 -219.338906) (xy 143.618712 -219.338906)
			(xy 143.618712 -219.601796) (xy 143.669512 -219.601796)
		)
		(stroke
			(width 0)
			(type solid)
		)
		(fill yes)
		(layer "F.Cu")
		(net "M_E_CPU1_SB_DQ<23>")
	)
	(gr_poly
		(pts
			(xy 143.771112 -218.968574) (xy 143.771112 -218.778074) (xy 143.669512 -218.742006) (xy 143.618712 -218.742006)
			(xy 143.618712 -219.004896) (xy 143.669512 -219.004896)
		)
		(stroke
			(width 0)
			(type solid)
		)
		(fill yes)
		(layer "F.Cu")
		(net "M_E_CPU1_SB_DQ<23>")
	)
	(gr_poly
		(pts
			(xy 143.771112 -218.371674) (xy 143.771112 -218.181174) (xy 143.669512 -218.145106) (xy 143.618712 -218.145106)
			(xy 143.618712 -218.407996) (xy 143.669512 -218.407996)
		)
		(stroke
			(width 0)
			(type solid)
		)
		(fill yes)
		(layer "F.Cu")
		(net "M_E_CPU1_SB_DQ<23>")
	)
	(gr_poly
		(pts
			(xy 143.771112 -217.774774) (xy 143.771112 -217.584274) (xy 143.669512 -217.548206) (xy 143.618712 -217.548206)
			(xy 143.618712 -217.811096) (xy 143.669512 -217.811096)
		)
		(stroke
			(width 0)
			(type solid)
		)
		(fill yes)
		(layer "F.Cu")
		(net "M_E_CPU1_SB_DQ<23>")
	)
	(gr_poly
		(pts
			(xy 143.771112 -217.177874) (xy 143.771112 -216.987374) (xy 143.669512 -216.951306) (xy 143.618712 -216.951306)
			(xy 143.618712 -217.214196) (xy 143.669512 -217.214196)
		)
		(stroke
			(width 0)
			(type solid)
		)
		(fill yes)
		(layer "F.Cu")
		(net "M_E_CPU1_SB_DQ<23>")
	)
	(gr_poly
		(pts
			(xy 143.771112 -216.580974) (xy 143.771112 -216.390474) (xy 143.669512 -216.354406) (xy 143.618712 -216.354406)
			(xy 143.618712 -216.617296) (xy 143.669512 -216.617296)
		)
		(stroke
			(width 0)
			(type solid)
		)
		(fill yes)
		(layer "F.Cu")
		(net "M_E_CPU1_SB_DQ<23>")
	)
	(gr_poly
		(pts
			(xy 143.771112 -215.984074) (xy 143.771112 -215.793574) (xy 143.669512 -215.757506) (xy 143.618712 -215.757506)
			(xy 143.618712 -216.020396) (xy 143.669512 -216.020396)
		)
		(stroke
			(width 0)
			(type solid)
		)
		(fill yes)
		(layer "F.Cu")
		(net "M_E_CPU1_SB_DQ<23>")
	)
	(gr_poly
		(pts
			(xy 143.771112 -215.387174) (xy 143.771112 -215.196674) (xy 143.669512 -215.160606) (xy 143.618712 -215.160606)
			(xy 143.618712 -215.423496) (xy 143.669512 -215.423496)
		)
		(stroke
			(width 0)
			(type solid)
		)
		(fill yes)
		(layer "F.Cu")
		(net "M_E_CPU1_SB_DQ<23>")
	)
	(gr_poly
		(pts
			(xy 143.772636 -228.107494) (xy 143.726408 -228.009958) (xy 143.69034 -227.974144) (xy 143.504412 -228.160072)
			(xy 143.54048 -228.195886) (xy 143.638016 -228.242114)
		)
		(stroke
			(width 0)
			(type solid)
		)
		(fill yes)
		(layer "F.Cu")
		(net "M_E_CPU1_SB_DQ<21>")
	)
	(gr_poly
		(pts
			(xy 143.77416 -236.928914) (xy 143.738092 -236.8931) (xy 143.64081 -236.846618) (xy 143.505936 -236.981492)
			(xy 143.552164 -237.078774) (xy 143.588232 -237.114842)
		)
		(stroke
			(width 0)
			(type solid)
		)
		(fill yes)
		(layer "F.Cu")
		(net "M_E_CPU1_SB_DQ<9>")
	)
	(gr_poly
		(pts
			(xy 143.775684 -257.13055) (xy 143.811752 -257.094736) (xy 143.625824 -256.908808) (xy 143.589756 -256.944622)
			(xy 143.543528 -257.042158) (xy 143.678402 -257.176778)
		)
		(stroke
			(width 0)
			(type solid)
		)
		(fill yes)
		(layer "F.Cu")
		(net "M_E_CPU1_SA_CA<3>")
	)
	(gr_poly
		(pts
			(xy 143.78178 -228.96068) (xy 143.735552 -228.863398) (xy 143.699738 -228.82733) (xy 143.51381 -229.013258)
			(xy 143.549624 -229.049326) (xy 143.64716 -229.095554)
		)
		(stroke
			(width 0)
			(type solid)
		)
		(fill yes)
		(layer "F.Cu")
		(net "M_E_CPU1_SB_DQ<20>")
	)
	(gr_poly
		(pts
			(xy 143.782796 -238.626142) (xy 143.746982 -238.590074) (xy 143.649446 -238.543846) (xy 143.514826 -238.678466)
			(xy 143.561054 -238.776002) (xy 143.597122 -238.811816)
		)
		(stroke
			(width 0)
			(type solid)
		)
		(fill yes)
		(layer "F.Cu")
		(net "M_E_CPU1_SB_CB<3>")
	)
	(gr_poly
		(pts
			(xy 143.784066 -237.783116) (xy 143.748252 -237.747048) (xy 143.650716 -237.70082) (xy 143.516096 -237.835694)
			(xy 143.562324 -237.932976) (xy 143.598138 -237.969044)
		)
		(stroke
			(width 0)
			(type solid)
		)
		(fill yes)
		(layer "F.Cu")
		(net "M_E_CPU1_SB_DQ<8>")
	)
	(gr_poly
		(pts
			(xy 143.784828 -256.27711) (xy 143.820896 -256.241296) (xy 143.634968 -256.055368) (xy 143.599154 -256.091182)
			(xy 143.552672 -256.188718) (xy 143.687546 -256.323338)
		)
		(stroke
			(width 0)
			(type solid)
		)
		(fill yes)
		(layer "F.Cu")
		(net "M_E_CPU1_SA_CA<5>")
	)
	(gr_poly
		(pts
			(xy 143.78813 -268.102588) (xy 143.824198 -268.066774) (xy 143.63827 -267.880846) (xy 143.602202 -267.91666)
			(xy 143.555974 -268.014196) (xy 143.690848 -268.148816)
		)
		(stroke
			(width 0)
			(type solid)
		)
		(fill yes)
		(layer "F.Cu")
		(net "M_E_CPU1_SA_DQ<30>")
	)
	(gr_poly
		(pts
			(xy 143.792194 -239.479328) (xy 143.756126 -239.443514) (xy 143.658844 -239.397286) (xy 143.52397 -239.531906)
			(xy 143.570198 -239.629442) (xy 143.606266 -239.665256)
		)
		(stroke
			(width 0)
			(type solid)
		)
		(fill yes)
		(layer "F.Cu")
		(net "M_E_CPU1_SB_CB<2>")
	)
	(gr_poly
		(pts
			(xy 143.794226 -255.423924) (xy 143.83004 -255.387856) (xy 143.644112 -255.201928) (xy 143.608298 -255.237996)
			(xy 143.56207 -255.335278) (xy 143.69669 -255.470152)
		)
		(stroke
			(width 0)
			(type solid)
		)
		(fill yes)
		(layer "F.Cu")
		(net "M_E_CPU1_SA_PAR")
	)
	(gr_poly
		(pts
			(xy 143.797782 -267.248894) (xy 143.833596 -267.21308) (xy 143.647668 -267.027152) (xy 143.611854 -267.06322)
			(xy 143.565626 -267.160502) (xy 143.700246 -267.295376)
		)
		(stroke
			(width 0)
			(type solid)
		)
		(fill yes)
		(layer "F.Cu")
		(net "M_E_CPU1_SA_DQ<31>")
	)
	(gr_poly
		(pts
			(xy 143.808704 -231.52227) (xy 143.762476 -231.424734) (xy 143.726408 -231.38892) (xy 143.540734 -231.574594)
			(xy 143.576548 -231.610662) (xy 143.674084 -231.65689)
		)
		(stroke
			(width 0)
			(type solid)
		)
		(fill yes)
		(layer "F.Cu")
		(net "M_E_CPU1_SB_DQ<17>")
	)
	(gr_poly
		(pts
			(xy 143.810736 -273.750278) (xy 143.846804 -273.714464) (xy 143.660876 -273.528536) (xy 143.624808 -273.56435)
			(xy 143.57858 -273.661886) (xy 143.713454 -273.796506)
		)
		(stroke
			(width 0)
			(type solid)
		)
		(fill yes)
		(layer "F.Cu")
		(net "M_E_CPU1_SA_DQ<22>")
	)
	(gr_poly
		(pts
			(xy 143.812006 -263.05383) (xy 143.848074 -263.018016) (xy 143.662146 -262.832088) (xy 143.626332 -262.867902)
			(xy 143.580104 -262.965438) (xy 143.714724 -263.100058)
		)
		(stroke
			(width 0)
			(type solid)
		)
		(fill yes)
		(layer "F.Cu")
		(net "M_E_CPU1_SA_CB<4>")
	)
	(gr_poly
		(pts
			(xy 143.817594 -233.219244) (xy 143.771112 -233.121708) (xy 143.735298 -233.085894) (xy 143.54937 -233.271822)
			(xy 143.585438 -233.307636) (xy 143.68272 -233.353864)
		)
		(stroke
			(width 0)
			(type solid)
		)
		(fill yes)
		(layer "F.Cu")
		(net "M_E_CPU1_SB_DQ<15>")
	)
	(gr_poly
		(pts
			(xy 143.817848 -232.375456) (xy 143.77162 -232.278174) (xy 143.735806 -232.242106) (xy 143.549878 -232.428034)
			(xy 143.585692 -232.464102) (xy 143.683228 -232.51033)
		)
		(stroke
			(width 0)
			(type solid)
		)
		(fill yes)
		(layer "F.Cu")
		(net "M_E_CPU1_SB_DQ<16>")
	)
	(gr_poly
		(pts
			(xy 143.819626 -272.052796) (xy 143.855694 -272.016982) (xy 143.669766 -271.831054) (xy 143.633698 -271.866868)
			(xy 143.58747 -271.964404) (xy 143.722344 -272.099024)
		)
		(stroke
			(width 0)
			(type solid)
		)
		(fill yes)
		(layer "F.Cu")
		(net "M_E_CPU1_SA_DQ<24>")
	)
	(gr_poly
		(pts
			(xy 143.820134 -272.896838) (xy 143.855948 -272.86077) (xy 143.67002 -272.674842) (xy 143.634206 -272.71091)
			(xy 143.587978 -272.808192) (xy 143.722598 -272.943066)
		)
		(stroke
			(width 0)
			(type solid)
		)
		(fill yes)
		(layer "F.Cu")
		(net "M_E_CPU1_SA_DQ<23>")
	)
	(gr_poly
		(pts
			(xy 143.821404 -262.200644) (xy 143.857218 -262.164576) (xy 143.67129 -261.978648) (xy 143.635476 -262.014716)
			(xy 143.589248 -262.111998) (xy 143.723868 -262.246872)
		)
		(stroke
			(width 0)
			(type solid)
		)
		(fill yes)
		(layer "F.Cu")
		(net "M_E_CPU1_SA_CB<5>")
	)
	(gr_poly
		(pts
			(xy 143.826738 -234.072684) (xy 143.78051 -233.975148) (xy 143.744442 -233.939334) (xy 143.558514 -234.125262)
			(xy 143.594582 -234.161076) (xy 143.691864 -234.207304)
		)
		(stroke
			(width 0)
			(type solid)
		)
		(fill yes)
		(layer "F.Cu")
		(net "M_E_CPU1_SB_DQ<14>")
	)
	(gr_poly
		(pts
			(xy 143.82877 -271.199356) (xy 143.864838 -271.163542) (xy 143.67891 -270.977614) (xy 143.642842 -271.013428)
			(xy 143.596614 -271.110964) (xy 143.731488 -271.245584)
		)
		(stroke
			(width 0)
			(type solid)
		)
		(fill yes)
		(layer "F.Cu")
		(net "M_E_CPU1_SA_DQ<25>")
	)
	(gr_poly
		(pts
			(xy 143.83131 -265.949176) (xy 143.877538 -265.85164) (xy 143.742918 -265.71702) (xy 143.645382 -265.763248)
			(xy 143.609568 -265.799316) (xy 143.795242 -265.98499)
		)
		(stroke
			(width 0)
			(type solid)
		)
		(fill yes)
		(layer "F.Cu")
		(net "M_E_CPU1_SA_CB<2>")
	)
	(gr_poly
		(pts
			(xy 143.840454 -265.095736) (xy 143.886682 -264.998454) (xy 143.752062 -264.86358) (xy 143.654526 -264.909808)
			(xy 143.618712 -264.945876) (xy 143.80464 -265.131804)
		)
		(stroke
			(width 0)
			(type solid)
		)
		(fill yes)
		(layer "F.Cu")
		(net "M_E_CPU1_SA_CB<3>")
	)
	(gr_poly
		(pts
			(xy 143.84655 -289.175698) (xy 143.84655 -288.985198) (xy 143.74495 -288.94913) (xy 143.69415 -288.94913)
			(xy 143.69415 -289.21202) (xy 143.74495 -289.21202)
		)
		(stroke
			(width 0)
			(type solid)
		)
		(fill yes)
		(layer "F.Cu")
		(net "M_E_CPU1_SA_DQ<17>")
	)
	(gr_poly
		(pts
			(xy 143.84655 -288.578798) (xy 143.84655 -288.388298) (xy 143.74495 -288.35223) (xy 143.69415 -288.35223)
			(xy 143.69415 -288.61512) (xy 143.74495 -288.61512)
		)
		(stroke
			(width 0)
			(type solid)
		)
		(fill yes)
		(layer "F.Cu")
		(net "M_E_CPU1_SA_DQ<17>")
	)
	(gr_poly
		(pts
			(xy 143.84655 -287.981898) (xy 143.84655 -287.791398) (xy 143.74495 -287.75533) (xy 143.69415 -287.75533)
			(xy 143.69415 -288.01822) (xy 143.74495 -288.01822)
		)
		(stroke
			(width 0)
			(type solid)
		)
		(fill yes)
		(layer "F.Cu")
		(net "M_E_CPU1_SA_DQ<17>")
	)
	(gr_poly
		(pts
			(xy 143.84655 -287.384998) (xy 143.84655 -287.194498) (xy 143.74495 -287.15843) (xy 143.69415 -287.15843)
			(xy 143.69415 -287.42132) (xy 143.74495 -287.42132)
		)
		(stroke
			(width 0)
			(type solid)
		)
		(fill yes)
		(layer "F.Cu")
		(net "M_E_CPU1_SA_DQ<17>")
	)
	(gr_poly
		(pts
			(xy 143.84655 -286.788098) (xy 143.84655 -286.597598) (xy 143.74495 -286.56153) (xy 143.69415 -286.56153)
			(xy 143.69415 -286.82442) (xy 143.74495 -286.82442)
		)
		(stroke
			(width 0)
			(type solid)
		)
		(fill yes)
		(layer "F.Cu")
		(net "M_E_CPU1_SA_DQ<17>")
	)
	(gr_poly
		(pts
			(xy 143.84655 -286.191198) (xy 143.84655 -286.000698) (xy 143.74495 -285.96463) (xy 143.69415 -285.96463)
			(xy 143.69415 -286.22752) (xy 143.74495 -286.22752)
		)
		(stroke
			(width 0)
			(type solid)
		)
		(fill yes)
		(layer "F.Cu")
		(net "M_E_CPU1_SA_DQ<17>")
	)
	(gr_poly
		(pts
			(xy 143.84655 -285.594298) (xy 143.84655 -285.403798) (xy 143.74495 -285.36773) (xy 143.69415 -285.36773)
			(xy 143.69415 -285.63062) (xy 143.74495 -285.63062)
		)
		(stroke
			(width 0)
			(type solid)
		)
		(fill yes)
		(layer "F.Cu")
		(net "M_E_CPU1_SA_DQ<17>")
	)
	(gr_poly
		(pts
			(xy 143.84655 -284.997398) (xy 143.84655 -284.806898) (xy 143.74495 -284.77083) (xy 143.69415 -284.77083)
			(xy 143.69415 -285.03372) (xy 143.74495 -285.03372)
		)
		(stroke
			(width 0)
			(type solid)
		)
		(fill yes)
		(layer "F.Cu")
		(net "M_E_CPU1_SA_DQ<17>")
	)
	(gr_poly
		(pts
			(xy 143.84655 -284.400498) (xy 143.84655 -284.209998) (xy 143.74495 -284.17393) (xy 143.69415 -284.17393)
			(xy 143.69415 -284.43682) (xy 143.74495 -284.43682)
		)
		(stroke
			(width 0)
			(type solid)
		)
		(fill yes)
		(layer "F.Cu")
		(net "M_E_CPU1_SA_DQ<17>")
	)
	(gr_poly
		(pts
			(xy 143.84655 -283.803598) (xy 143.84655 -283.613098) (xy 143.74495 -283.57703) (xy 143.69415 -283.57703)
			(xy 143.69415 -283.83992) (xy 143.74495 -283.83992)
		)
		(stroke
			(width 0)
			(type solid)
		)
		(fill yes)
		(layer "F.Cu")
		(net "M_E_CPU1_SA_DQ<17>")
	)
	(gr_poly
		(pts
			(xy 143.84655 -283.206698) (xy 143.84655 -283.016198) (xy 143.74495 -282.98013) (xy 143.69415 -282.98013)
			(xy 143.69415 -283.24302) (xy 143.74495 -283.24302)
		)
		(stroke
			(width 0)
			(type solid)
		)
		(fill yes)
		(layer "F.Cu")
		(net "M_E_CPU1_SA_DQ<17>")
	)
	(gr_poly
		(pts
			(xy 143.84655 -282.609798) (xy 143.84655 -282.419298) (xy 143.74495 -282.38323) (xy 143.69415 -282.38323)
			(xy 143.69415 -282.64612) (xy 143.74495 -282.64612)
		)
		(stroke
			(width 0)
			(type solid)
		)
		(fill yes)
		(layer "F.Cu")
		(net "M_E_CPU1_SA_DQ<17>")
	)
	(gr_poly
		(pts
			(xy 143.84655 -282.012898) (xy 143.84655 -281.822398) (xy 143.74495 -281.78633) (xy 143.69415 -281.78633)
			(xy 143.69415 -282.04922) (xy 143.74495 -282.04922)
		)
		(stroke
			(width 0)
			(type solid)
		)
		(fill yes)
		(layer "F.Cu")
		(net "M_E_CPU1_SA_DQ<17>")
	)
	(gr_poly
		(pts
			(xy 143.84655 -281.415998) (xy 143.84655 -281.225498) (xy 143.74495 -281.18943) (xy 143.69415 -281.18943)
			(xy 143.69415 -281.45232) (xy 143.74495 -281.45232)
		)
		(stroke
			(width 0)
			(type solid)
		)
		(fill yes)
		(layer "F.Cu")
		(net "M_E_CPU1_SA_DQ<17>")
	)
	(gr_poly
		(pts
			(xy 143.85163 -236.635544) (xy 143.805402 -236.538008) (xy 143.769334 -236.502194) (xy 143.583406 -236.688122)
			(xy 143.619474 -236.723936) (xy 143.716756 -236.770164)
		)
		(stroke
			(width 0)
			(type solid)
		)
		(fill yes)
		(layer "F.Cu")
		(net "M_E_CPU1_SB_DQ<11>")
	)
	(gr_poly
		(pts
			(xy 143.852138 -256.631948) (xy 143.898366 -256.534666) (xy 143.763746 -256.399792) (xy 143.66621 -256.44602)
			(xy 143.630396 -256.482088) (xy 143.816324 -256.668016)
		)
		(stroke
			(width 0)
			(type solid)
		)
		(fill yes)
		(layer "F.Cu")
		(net "M_E_CPU1_SA_CA<4>")
	)
	(gr_poly
		(pts
			(xy 143.85544 -268.457426) (xy 143.901668 -268.360144) (xy 143.767048 -268.22527) (xy 143.669512 -268.271498)
			(xy 143.633698 -268.307566) (xy 143.819626 -268.493494)
		)
		(stroke
			(width 0)
			(type solid)
		)
		(fill yes)
		(layer "F.Cu")
		(net "M_E_CPU1_SA_DQ<28>")
	)
	(gr_poly
		(pts
			(xy 143.861282 -255.778762) (xy 143.90751 -255.681226) (xy 143.77289 -255.546606) (xy 143.675608 -255.592834)
			(xy 143.63954 -255.628648) (xy 143.825468 -255.814576)
		)
		(stroke
			(width 0)
			(type solid)
		)
		(fill yes)
		(layer "F.Cu")
		(net "M_E_CPU1_SA_CA<6>")
	)
	(gr_poly
		(pts
			(xy 143.861536 -237.489746) (xy 143.815308 -237.39221) (xy 143.779494 -237.356142) (xy 143.593566 -237.54207)
			(xy 143.62938 -237.578138) (xy 143.726916 -237.624366)
		)
		(stroke
			(width 0)
			(type solid)
		)
		(fill yes)
		(layer "F.Cu")
		(net "M_E_CPU1_SB_DQ<10>")
	)
	(gr_poly
		(pts
			(xy 143.864838 -267.603986) (xy 143.911066 -267.50645) (xy 143.776446 -267.37183) (xy 143.67891 -267.418058)
			(xy 143.643096 -267.454126) (xy 143.82877 -267.6398)
		)
		(stroke
			(width 0)
			(type solid)
		)
		(fill yes)
		(layer "F.Cu")
		(net "M_E_CPU1_SA_DQ<29>")
	)
	(gr_poly
		(pts
			(xy 143.869664 -239.185958) (xy 143.823436 -239.088676) (xy 143.787622 -239.052608) (xy 143.601694 -239.238536)
			(xy 143.637508 -239.274604) (xy 143.735044 -239.320832)
		)
		(stroke
			(width 0)
			(type solid)
		)
		(fill yes)
		(layer "F.Cu")
		(net "M_E_CPU1_SB_CB<1>")
	)
	(gr_poly
		(pts
			(xy 143.874744 -279.522428) (xy 143.967454 -279.467056) (xy 143.930116 -279.280366) (xy 143.823436 -279.264872)
			(xy 143.773652 -279.274778) (xy 143.82496 -279.532588)
		)
		(stroke
			(width 0)
			(type solid)
		)
		(fill yes)
		(layer "F.Cu")
		(net "M_E_CPU1_SA_DQ<19>")
	)
	(gr_poly
		(pts
			(xy 143.878046 -274.10537) (xy 143.924274 -274.007834) (xy 143.7894 -273.873214) (xy 143.692118 -273.919442)
			(xy 143.65605 -273.955256) (xy 143.841978 -274.141184)
		)
		(stroke
			(width 0)
			(type solid)
		)
		(fill yes)
		(layer "F.Cu")
		(net "M_E_CPU1_SA_DQ<20>")
	)
	(gr_poly
		(pts
			(xy 143.878808 -240.039398) (xy 143.83258 -239.942116) (xy 143.796766 -239.906048) (xy 143.610838 -240.091976)
			(xy 143.646652 -240.12779) (xy 143.744188 -240.174018)
		)
		(stroke
			(width 0)
			(type solid)
		)
		(fill yes)
		(layer "F.Cu")
		(net "M_E_CPU1_SB_CB<0>")
	)
	(gr_poly
		(pts
			(xy 143.882364 -242.700556) (xy 143.882364 -242.649756) (xy 143.619474 -242.649756) (xy 143.619474 -242.700556)
			(xy 143.655796 -242.802156) (xy 143.846296 -242.802156)
		)
		(stroke
			(width 0)
			(type solid)
		)
		(fill yes)
		(layer "F.Cu")
		(net "M_E_CPU1_SB_CB<4>")
	)
	(gr_poly
		(pts
			(xy 143.882364 -242.395756) (xy 143.882364 -242.344956) (xy 143.619474 -242.344956) (xy 143.619474 -242.395756)
			(xy 143.655796 -242.497356) (xy 143.846296 -242.497356)
		)
		(stroke
			(width 0)
			(type solid)
		)
		(fill yes)
		(layer "F.Cu")
		(net "M_E_CPU1_SB_CB<6>")
	)
	(gr_poly
		(pts
			(xy 143.882364 -242.090956) (xy 143.882364 -242.040156) (xy 143.619474 -242.040156) (xy 143.619474 -242.090956)
			(xy 143.655796 -242.192556) (xy 143.846296 -242.192556)
		)
		(stroke
			(width 0)
			(type solid)
		)
		(fill yes)
		(layer "F.Cu")
		(net "M_E_CPU1_SB_CB<5>")
	)
	(gr_poly
		(pts
			(xy 143.882364 -241.786156) (xy 143.882364 -241.735356) (xy 143.619474 -241.735356) (xy 143.619474 -241.786156)
			(xy 143.655796 -241.887756) (xy 143.846296 -241.887756)
		)
		(stroke
			(width 0)
			(type solid)
		)
		(fill yes)
		(layer "F.Cu")
		(net "M_E_CPU1_SB_CB<7>")
	)
	(gr_poly
		(pts
			(xy 143.88338 -279.825196) (xy 143.832072 -279.567386) (xy 143.782288 -279.577292) (xy 143.689578 -279.632664)
			(xy 143.726916 -279.819608) (xy 143.833596 -279.835102)
		)
		(stroke
			(width 0)
			(type solid)
		)
		(fill yes)
		(layer "F.Cu")
		(net "M_E_CPU1_SA_DQ<19>")
	)
	(gr_poly
		(pts
			(xy 143.88719 -273.251676) (xy 143.933418 -273.154394) (xy 143.798798 -273.01952) (xy 143.701262 -273.065748)
			(xy 143.665448 -273.101816) (xy 143.851376 -273.287744)
		)
		(stroke
			(width 0)
			(type solid)
		)
		(fill yes)
		(layer "F.Cu")
		(net "M_E_CPU1_SA_DQ<21>")
	)
	(gr_poly
		(pts
			(xy 143.88846 -262.555482) (xy 143.934942 -262.457946) (xy 143.800068 -262.323326) (xy 143.702786 -262.369554)
			(xy 143.666718 -262.405368) (xy 143.852646 -262.591296)
		)
		(stroke
			(width 0)
			(type solid)
		)
		(fill yes)
		(layer "F.Cu")
		(net "M_E_CPU1_SA_CB<6>")
	)
	(gr_poly
		(pts
			(xy 143.89608 -271.554194) (xy 143.942308 -271.456912) (xy 143.807688 -271.322038) (xy 143.710152 -271.368266)
			(xy 143.674338 -271.404334) (xy 143.860266 -271.590262)
		)
		(stroke
			(width 0)
			(type solid)
		)
		(fill yes)
		(layer "F.Cu")
		(net "M_E_CPU1_SA_DQ<26>")
	)
	(gr_poly
		(pts
			(xy 143.897858 -261.702042) (xy 143.944086 -261.604506) (xy 143.809212 -261.469886) (xy 143.71193 -261.516114)
			(xy 143.675862 -261.551928) (xy 143.86179 -261.737856)
		)
		(stroke
			(width 0)
			(type solid)
		)
		(fill yes)
		(layer "F.Cu")
		(net "M_E_CPU1_SA_CB<7>")
	)
	(gr_poly
		(pts
			(xy 143.905224 -270.700754) (xy 143.951452 -270.603472) (xy 143.816832 -270.468598) (xy 143.719296 -270.51508)
			(xy 143.683482 -270.550894) (xy 143.86941 -270.736822)
		)
		(stroke
			(width 0)
			(type solid)
		)
		(fill yes)
		(layer "F.Cu")
		(net "M_E_CPU1_SA_DQ<27>")
	)
	(gr_poly
		(pts
			(xy 143.910558 -228.61651) (xy 143.874744 -228.580442) (xy 143.777208 -228.534214) (xy 143.642588 -228.668834)
			(xy 143.688816 -228.76637) (xy 143.724884 -228.802184)
		)
		(stroke
			(width 0)
			(type solid)
		)
		(fill yes)
		(layer "F.Cu")
		(net "M_E_CPU1_SB_DQ<20>")
	)
	(gr_poly
		(pts
			(xy 143.923512 -226.800156) (xy 143.872712 -226.800156) (xy 143.771112 -226.836478) (xy 143.771112 -227.026978)
			(xy 143.872712 -227.063046) (xy 143.923512 -227.063046)
		)
		(stroke
			(width 0)
			(type solid)
		)
		(fill yes)
		(layer "F.Cu")
		(net "M_E_CPU1_SB_DQ<21>")
	)
	(gr_poly
		(pts
			(xy 143.923512 -226.203256) (xy 143.872712 -226.203256) (xy 143.771112 -226.239578) (xy 143.771112 -226.430078)
			(xy 143.872712 -226.466146) (xy 143.923512 -226.466146)
		)
		(stroke
			(width 0)
			(type solid)
		)
		(fill yes)
		(layer "F.Cu")
		(net "M_E_CPU1_SB_DQ<21>")
	)
	(gr_poly
		(pts
			(xy 143.923512 -225.606356) (xy 143.872712 -225.606356) (xy 143.771112 -225.642678) (xy 143.771112 -225.833178)
			(xy 143.872712 -225.869246) (xy 143.923512 -225.869246)
		)
		(stroke
			(width 0)
			(type solid)
		)
		(fill yes)
		(layer "F.Cu")
		(net "M_E_CPU1_SB_DQ<21>")
	)
	(gr_poly
		(pts
			(xy 143.923512 -225.009456) (xy 143.872712 -225.009456) (xy 143.771112 -225.045778) (xy 143.771112 -225.236278)
			(xy 143.872712 -225.272346) (xy 143.923512 -225.272346)
		)
		(stroke
			(width 0)
			(type solid)
		)
		(fill yes)
		(layer "F.Cu")
		(net "M_E_CPU1_SB_DQ<21>")
	)
	(gr_poly
		(pts
			(xy 143.923512 -224.412556) (xy 143.872712 -224.412556) (xy 143.771112 -224.448878) (xy 143.771112 -224.639378)
			(xy 143.872712 -224.675446) (xy 143.923512 -224.675446)
		)
		(stroke
			(width 0)
			(type solid)
		)
		(fill yes)
		(layer "F.Cu")
		(net "M_E_CPU1_SB_DQ<21>")
	)
	(gr_poly
		(pts
			(xy 143.923512 -223.815656) (xy 143.872712 -223.815656) (xy 143.771112 -223.851978) (xy 143.771112 -224.042478)
			(xy 143.872712 -224.078546) (xy 143.923512 -224.078546)
		)
		(stroke
			(width 0)
			(type solid)
		)
		(fill yes)
		(layer "F.Cu")
		(net "M_E_CPU1_SB_DQ<21>")
	)
	(gr_poly
		(pts
			(xy 143.923512 -223.218756) (xy 143.872712 -223.218756) (xy 143.771112 -223.255078) (xy 143.771112 -223.445578)
			(xy 143.872712 -223.481646) (xy 143.923512 -223.481646)
		)
		(stroke
			(width 0)
			(type solid)
		)
		(fill yes)
		(layer "F.Cu")
		(net "M_E_CPU1_SB_DQ<21>")
	)
	(gr_poly
		(pts
			(xy 143.923512 -222.621856) (xy 143.872712 -222.621856) (xy 143.771112 -222.658178) (xy 143.771112 -222.848678)
			(xy 143.872712 -222.884746) (xy 143.923512 -222.884746)
		)
		(stroke
			(width 0)
			(type solid)
		)
		(fill yes)
		(layer "F.Cu")
		(net "M_E_CPU1_SB_DQ<21>")
	)
	(gr_poly
		(pts
			(xy 143.923512 -222.024956) (xy 143.872712 -222.024956) (xy 143.771112 -222.061278) (xy 143.771112 -222.251778)
			(xy 143.872712 -222.287846) (xy 143.923512 -222.287846)
		)
		(stroke
			(width 0)
			(type solid)
		)
		(fill yes)
		(layer "F.Cu")
		(net "M_E_CPU1_SB_DQ<21>")
	)
	(gr_poly
		(pts
			(xy 143.923512 -221.428056) (xy 143.872712 -221.428056) (xy 143.771112 -221.464378) (xy 143.771112 -221.654878)
			(xy 143.872712 -221.690946) (xy 143.923512 -221.690946)
		)
		(stroke
			(width 0)
			(type solid)
		)
		(fill yes)
		(layer "F.Cu")
		(net "M_E_CPU1_SB_DQ<21>")
	)
	(gr_poly
		(pts
			(xy 143.923512 -220.831156) (xy 143.872712 -220.831156) (xy 143.771112 -220.867478) (xy 143.771112 -221.057978)
			(xy 143.872712 -221.094046) (xy 143.923512 -221.094046)
		)
		(stroke
			(width 0)
			(type solid)
		)
		(fill yes)
		(layer "F.Cu")
		(net "M_E_CPU1_SB_DQ<21>")
	)
	(gr_poly
		(pts
			(xy 143.923512 -220.234256) (xy 143.872712 -220.234256) (xy 143.771112 -220.270578) (xy 143.771112 -220.461078)
			(xy 143.872712 -220.497146) (xy 143.923512 -220.497146)
		)
		(stroke
			(width 0)
			(type solid)
		)
		(fill yes)
		(layer "F.Cu")
		(net "M_E_CPU1_SB_DQ<21>")
	)
	(gr_poly
		(pts
			(xy 143.923512 -219.637356) (xy 143.872712 -219.637356) (xy 143.771112 -219.673678) (xy 143.771112 -219.864178)
			(xy 143.872712 -219.900246) (xy 143.923512 -219.900246)
		)
		(stroke
			(width 0)
			(type solid)
		)
		(fill yes)
		(layer "F.Cu")
		(net "M_E_CPU1_SB_DQ<21>")
	)
	(gr_poly
		(pts
			(xy 143.923512 -219.040456) (xy 143.872712 -219.040456) (xy 143.771112 -219.076778) (xy 143.771112 -219.267278)
			(xy 143.872712 -219.303346) (xy 143.923512 -219.303346)
		)
		(stroke
			(width 0)
			(type solid)
		)
		(fill yes)
		(layer "F.Cu")
		(net "M_E_CPU1_SB_DQ<21>")
	)
	(gr_poly
		(pts
			(xy 143.923512 -218.443556) (xy 143.872712 -218.443556) (xy 143.771112 -218.479878) (xy 143.771112 -218.670378)
			(xy 143.872712 -218.706446) (xy 143.923512 -218.706446)
		)
		(stroke
			(width 0)
			(type solid)
		)
		(fill yes)
		(layer "F.Cu")
		(net "M_E_CPU1_SB_DQ<21>")
	)
	(gr_poly
		(pts
			(xy 143.923512 -217.846656) (xy 143.872712 -217.846656) (xy 143.771112 -217.882978) (xy 143.771112 -218.073478)
			(xy 143.872712 -218.109546) (xy 143.923512 -218.109546)
		)
		(stroke
			(width 0)
			(type solid)
		)
		(fill yes)
		(layer "F.Cu")
		(net "M_E_CPU1_SB_DQ<21>")
	)
	(gr_poly
		(pts
			(xy 143.923512 -217.249756) (xy 143.872712 -217.249756) (xy 143.771112 -217.286078) (xy 143.771112 -217.476578)
			(xy 143.872712 -217.512646) (xy 143.923512 -217.512646)
		)
		(stroke
			(width 0)
			(type solid)
		)
		(fill yes)
		(layer "F.Cu")
		(net "M_E_CPU1_SB_DQ<21>")
	)
	(gr_poly
		(pts
			(xy 143.923512 -216.652856) (xy 143.872712 -216.652856) (xy 143.771112 -216.689178) (xy 143.771112 -216.879678)
			(xy 143.872712 -216.915746) (xy 143.923512 -216.915746)
		)
		(stroke
			(width 0)
			(type solid)
		)
		(fill yes)
		(layer "F.Cu")
		(net "M_E_CPU1_SB_DQ<21>")
	)
	(gr_poly
		(pts
			(xy 143.923512 -216.055956) (xy 143.872712 -216.055956) (xy 143.771112 -216.092278) (xy 143.771112 -216.282778)
			(xy 143.872712 -216.318846) (xy 143.923512 -216.318846)
		)
		(stroke
			(width 0)
			(type solid)
		)
		(fill yes)
		(layer "F.Cu")
		(net "M_E_CPU1_SB_DQ<21>")
	)
	(gr_poly
		(pts
			(xy 143.923512 -215.459056) (xy 143.872712 -215.459056) (xy 143.771112 -215.495378) (xy 143.771112 -215.685878)
			(xy 143.872712 -215.721946) (xy 143.923512 -215.721946)
		)
		(stroke
			(width 0)
			(type solid)
		)
		(fill yes)
		(layer "F.Cu")
		(net "M_E_CPU1_SB_DQ<21>")
	)
	(gr_poly
		(pts
			(xy 143.937482 -231.177846) (xy 143.901668 -231.141778) (xy 143.804132 -231.09555) (xy 143.669512 -231.230424)
			(xy 143.71574 -231.327706) (xy 143.751554 -231.363774)
		)
		(stroke
			(width 0)
			(type solid)
		)
		(fill yes)
		(layer "F.Cu")
		(net "M_E_CPU1_SB_DQ<17>")
	)
	(gr_poly
		(pts
			(xy 143.946372 -232.87482) (xy 143.910304 -232.839006) (xy 143.813022 -232.792778) (xy 143.678402 -232.927398)
			(xy 143.72463 -233.024934) (xy 143.760444 -233.060748)
		)
		(stroke
			(width 0)
			(type solid)
		)
		(fill yes)
		(layer "F.Cu")
		(net "M_E_CPU1_SB_DQ<15>")
	)
	(gr_poly
		(pts
			(xy 143.94688 -232.031032) (xy 143.910812 -231.995218) (xy 143.81353 -231.94899) (xy 143.678656 -232.08361)
			(xy 143.724884 -232.181146) (xy 143.760952 -232.21696)
		)
		(stroke
			(width 0)
			(type solid)
		)
		(fill yes)
		(layer "F.Cu")
		(net "M_E_CPU1_SB_DQ<16>")
	)
	(gr_poly
		(pts
			(xy 143.955516 -233.72826) (xy 143.919702 -233.692192) (xy 143.822166 -233.645964) (xy 143.687546 -233.780838)
			(xy 143.733774 -233.87812) (xy 143.769588 -233.914188)
		)
		(stroke
			(width 0)
			(type solid)
		)
		(fill yes)
		(layer "F.Cu")
		(net "M_E_CPU1_SB_DQ<14>")
	)
	(gr_poly
		(pts
			(xy 143.970502 -266.232132) (xy 144.006316 -266.196064) (xy 143.820388 -266.010136) (xy 143.784574 -266.046204)
			(xy 143.738346 -266.143486) (xy 143.872966 -266.27836)
		)
		(stroke
			(width 0)
			(type solid)
		)
		(fill yes)
		(layer "F.Cu")
		(net "M_E_CPU1_SA_CB<2>")
	)
	(gr_poly
		(pts
			(xy 143.979646 -265.378692) (xy 144.015714 -265.342878) (xy 143.829786 -265.15695) (xy 143.793718 -265.192764)
			(xy 143.74749 -265.2903) (xy 143.882364 -265.42492)
		)
		(stroke
			(width 0)
			(type solid)
		)
		(fill yes)
		(layer "F.Cu")
		(net "M_E_CPU1_SA_CB<3>")
	)
	(gr_poly
		(pts
			(xy 143.980408 -236.29112) (xy 143.944594 -236.255306) (xy 143.847058 -236.208824) (xy 143.712438 -236.343698)
			(xy 143.758666 -236.44098) (xy 143.79448 -236.477048)
		)
		(stroke
			(width 0)
			(type solid)
		)
		(fill yes)
		(layer "F.Cu")
		(net "M_E_CPU1_SB_DQ<11>")
	)
	(gr_poly
		(pts
			(xy 143.988282 -228.32314) (xy 143.942054 -228.225604) (xy 143.905986 -228.18979) (xy 143.720058 -228.375718)
			(xy 143.756126 -228.411532) (xy 143.853662 -228.45776)
		)
		(stroke
			(width 0)
			(type solid)
		)
		(fill yes)
		(layer "F.Cu")
		(net "M_E_CPU1_SB_DQ<22>")
	)
	(gr_poly
		(pts
			(xy 143.990314 -237.145322) (xy 143.9545 -237.109254) (xy 143.856964 -237.063026) (xy 143.722344 -237.197646)
			(xy 143.768572 -237.295182) (xy 143.80464 -237.330996)
		)
		(stroke
			(width 0)
			(type solid)
		)
		(fill yes)
		(layer "F.Cu")
		(net "M_E_CPU1_SB_DQ<10>")
	)
	(gr_poly
		(pts
			(xy 143.991838 -280.107898) (xy 144.084294 -280.052526) (xy 144.046956 -279.865582) (xy 143.940276 -279.850088)
			(xy 143.890492 -279.859994) (xy 143.942054 -280.117804)
		)
		(stroke
			(width 0)
			(type solid)
		)
		(fill yes)
		(layer "F.Cu")
		(net "M_E_CPU1_SA_DQ<19>")
	)
	(gr_poly
		(pts
			(xy 143.994632 -268.740382) (xy 144.030446 -268.704314) (xy 143.844772 -268.51864) (xy 143.808704 -268.554454)
			(xy 143.762476 -268.65199) (xy 143.897096 -268.78661)
		)
		(stroke
			(width 0)
			(type solid)
		)
		(fill yes)
		(layer "F.Cu")
		(net "M_E_CPU1_SA_DQ<28>")
	)
	(gr_poly
		(pts
			(xy 143.998442 -238.841788) (xy 143.962628 -238.80572) (xy 143.865092 -238.759492) (xy 143.730472 -238.894112)
			(xy 143.7767 -238.991648) (xy 143.812768 -239.027462)
		)
		(stroke
			(width 0)
			(type solid)
		)
		(fill yes)
		(layer "F.Cu")
		(net "M_E_CPU1_SB_CB<1>")
	)
	(gr_poly
		(pts
			(xy 143.99895 -288.650426) (xy 143.94815 -288.650426) (xy 143.84655 -288.686748) (xy 143.84655 -288.877248)
			(xy 143.94815 -288.91357) (xy 143.99895 -288.91357)
		)
		(stroke
			(width 0)
			(type solid)
		)
		(fill yes)
		(layer "F.Cu")
		(net "M_E_CPU1_SA_DQ<19>")
	)
	(gr_poly
		(pts
			(xy 143.99895 -288.053526) (xy 143.94815 -288.053526) (xy 143.84655 -288.089848) (xy 143.84655 -288.280348)
			(xy 143.94815 -288.31667) (xy 143.99895 -288.31667)
		)
		(stroke
			(width 0)
			(type solid)
		)
		(fill yes)
		(layer "F.Cu")
		(net "M_E_CPU1_SA_DQ<19>")
	)
	(gr_poly
		(pts
			(xy 143.99895 -287.456626) (xy 143.94815 -287.456626) (xy 143.84655 -287.492948) (xy 143.84655 -287.683448)
			(xy 143.94815 -287.71977) (xy 143.99895 -287.71977)
		)
		(stroke
			(width 0)
			(type solid)
		)
		(fill yes)
		(layer "F.Cu")
		(net "M_E_CPU1_SA_DQ<19>")
	)
	(gr_poly
		(pts
			(xy 143.99895 -286.859726) (xy 143.94815 -286.859726) (xy 143.84655 -286.896048) (xy 143.84655 -287.086548)
			(xy 143.94815 -287.12287) (xy 143.99895 -287.12287)
		)
		(stroke
			(width 0)
			(type solid)
		)
		(fill yes)
		(layer "F.Cu")
		(net "M_E_CPU1_SA_DQ<19>")
	)
	(gr_poly
		(pts
			(xy 143.99895 -286.262826) (xy 143.94815 -286.262826) (xy 143.84655 -286.299148) (xy 143.84655 -286.489648)
			(xy 143.94815 -286.52597) (xy 143.99895 -286.52597)
		)
		(stroke
			(width 0)
			(type solid)
		)
		(fill yes)
		(layer "F.Cu")
		(net "M_E_CPU1_SA_DQ<19>")
	)
	(gr_poly
		(pts
			(xy 143.99895 -285.665926) (xy 143.94815 -285.665926) (xy 143.84655 -285.702248) (xy 143.84655 -285.892748)
			(xy 143.94815 -285.92907) (xy 143.99895 -285.92907)
		)
		(stroke
			(width 0)
			(type solid)
		)
		(fill yes)
		(layer "F.Cu")
		(net "M_E_CPU1_SA_DQ<19>")
	)
	(gr_poly
		(pts
			(xy 143.99895 -285.069026) (xy 143.94815 -285.069026) (xy 143.84655 -285.105348) (xy 143.84655 -285.295848)
			(xy 143.94815 -285.33217) (xy 143.99895 -285.33217)
		)
		(stroke
			(width 0)
			(type solid)
		)
		(fill yes)
		(layer "F.Cu")
		(net "M_E_CPU1_SA_DQ<19>")
	)
	(gr_poly
		(pts
			(xy 143.99895 -284.472126) (xy 143.94815 -284.472126) (xy 143.84655 -284.508448) (xy 143.84655 -284.698948)
			(xy 143.94815 -284.73527) (xy 143.99895 -284.73527)
		)
		(stroke
			(width 0)
			(type solid)
		)
		(fill yes)
		(layer "F.Cu")
		(net "M_E_CPU1_SA_DQ<19>")
	)
	(gr_poly
		(pts
			(xy 143.99895 -283.875226) (xy 143.94815 -283.875226) (xy 143.84655 -283.911548) (xy 143.84655 -284.102048)
			(xy 143.94815 -284.13837) (xy 143.99895 -284.13837)
		)
		(stroke
			(width 0)
			(type solid)
		)
		(fill yes)
		(layer "F.Cu")
		(net "M_E_CPU1_SA_DQ<19>")
	)
	(gr_poly
		(pts
			(xy 143.99895 -283.278326) (xy 143.94815 -283.278326) (xy 143.84655 -283.314648) (xy 143.84655 -283.505148)
			(xy 143.94815 -283.54147) (xy 143.99895 -283.54147)
		)
		(stroke
			(width 0)
			(type solid)
		)
		(fill yes)
		(layer "F.Cu")
		(net "M_E_CPU1_SA_DQ<19>")
	)
	(gr_poly
		(pts
			(xy 143.99895 -282.681426) (xy 143.94815 -282.681426) (xy 143.84655 -282.717748) (xy 143.84655 -282.908248)
			(xy 143.94815 -282.94457) (xy 143.99895 -282.94457)
		)
		(stroke
			(width 0)
			(type solid)
		)
		(fill yes)
		(layer "F.Cu")
		(net "M_E_CPU1_SA_DQ<19>")
	)
	(gr_poly
		(pts
			(xy 143.99895 -282.084526) (xy 143.94815 -282.084526) (xy 143.84655 -282.120848) (xy 143.84655 -282.311348)
			(xy 143.94815 -282.34767) (xy 143.99895 -282.34767)
		)
		(stroke
			(width 0)
			(type solid)
		)
		(fill yes)
		(layer "F.Cu")
		(net "M_E_CPU1_SA_DQ<19>")
	)
	(gr_poly
		(pts
			(xy 143.99895 -281.487626) (xy 143.94815 -281.487626) (xy 143.84655 -281.523948) (xy 143.84655 -281.714448)
			(xy 143.94815 -281.75077) (xy 143.99895 -281.75077)
		)
		(stroke
			(width 0)
			(type solid)
		)
		(fill yes)
		(layer "F.Cu")
		(net "M_E_CPU1_SA_DQ<19>")
	)
	(gr_poly
		(pts
			(xy 143.99895 -280.890726) (xy 143.94815 -280.890726) (xy 143.84655 -280.927048) (xy 143.84655 -281.117548)
			(xy 143.94815 -281.15387) (xy 143.99895 -281.15387)
		)
		(stroke
			(width 0)
			(type solid)
		)
		(fill yes)
		(layer "F.Cu")
		(net "M_E_CPU1_SA_DQ<19>")
	)
	(gr_poly
		(pts
			(xy 144.000474 -256.061464) (xy 144.036542 -256.02565) (xy 143.850614 -255.839722) (xy 143.8148 -255.875536)
			(xy 143.768318 -255.973072) (xy 143.903192 -256.107692)
		)
		(stroke
			(width 0)
			(type solid)
		)
		(fill yes)
		(layer "F.Cu")
		(net "M_E_CPU1_SA_CA<6>")
	)
	(gr_poly
		(pts
			(xy 144.00403 -267.886942) (xy 144.039844 -267.850874) (xy 143.853916 -267.664946) (xy 143.818102 -267.701014)
			(xy 143.771874 -267.798296) (xy 143.906494 -267.93317)
		)
		(stroke
			(width 0)
			(type solid)
		)
		(fill yes)
		(layer "F.Cu")
		(net "M_E_CPU1_SA_DQ<29>")
	)
	(gr_poly
		(pts
			(xy 144.00784 -239.694974) (xy 143.971772 -239.65916) (xy 143.87449 -239.612932) (xy 143.739616 -239.747552)
			(xy 143.785844 -239.845088) (xy 143.821912 -239.880902)
		)
		(stroke
			(width 0)
			(type solid)
		)
		(fill yes)
		(layer "F.Cu")
		(net "M_E_CPU1_SB_CB<0>")
	)
	(gr_poly
		(pts
			(xy 144.015206 -230.884476) (xy 143.968978 -230.78694) (xy 143.93291 -230.751126) (xy 143.746982 -230.937054)
			(xy 143.78305 -230.972868) (xy 143.880332 -231.019096)
		)
		(stroke
			(width 0)
			(type solid)
		)
		(fill yes)
		(layer "F.Cu")
		(net "M_E_CPU1_SB_DQ<19>")
	)
	(gr_poly
		(pts
			(xy 144.017238 -274.388072) (xy 144.053052 -274.352258) (xy 143.867124 -274.16633) (xy 143.83131 -274.202144)
			(xy 143.785082 -274.29968) (xy 143.919702 -274.4343)
		)
		(stroke
			(width 0)
			(type solid)
		)
		(fill yes)
		(layer "F.Cu")
		(net "M_E_CPU1_SA_DQ<20>")
	)
	(gr_poly
		(pts
			(xy 144.02435 -231.737916) (xy 143.978122 -231.64038) (xy 143.942054 -231.604566) (xy 143.75638 -231.79024)
			(xy 143.792194 -231.826308) (xy 143.88973 -231.872536)
		)
		(stroke
			(width 0)
			(type solid)
		)
		(fill yes)
		(layer "F.Cu")
		(net "M_E_CPU1_SB_DQ<18>")
	)
	(gr_poly
		(pts
			(xy 144.026382 -273.534632) (xy 144.06245 -273.498818) (xy 143.876522 -273.31289) (xy 143.840454 -273.348704)
			(xy 143.794226 -273.44624) (xy 143.9291 -273.58086)
		)
		(stroke
			(width 0)
			(type solid)
		)
		(fill yes)
		(layer "F.Cu")
		(net "M_E_CPU1_SA_DQ<21>")
	)
	(gr_poly
		(pts
			(xy 144.027652 -262.838184) (xy 144.06372 -262.80237) (xy 143.877792 -262.616442) (xy 143.841978 -262.652256)
			(xy 143.79575 -262.749792) (xy 143.93037 -262.884412)
		)
		(stroke
			(width 0)
			(type solid)
		)
		(fill yes)
		(layer "F.Cu")
		(net "M_E_CPU1_SA_CB<6>")
	)
	(gr_poly
		(pts
			(xy 144.03324 -233.43489) (xy 143.986758 -233.337354) (xy 143.950944 -233.30154) (xy 143.765016 -233.487468)
			(xy 143.801084 -233.523282) (xy 143.898366 -233.56951)
		)
		(stroke
			(width 0)
			(type solid)
		)
		(fill yes)
		(layer "F.Cu")
		(net "M_E_CPU1_SB_DQ<13>")
	)
	(gr_poly
		(pts
			(xy 144.035272 -271.83715) (xy 144.07134 -271.801336) (xy 143.885412 -271.615408) (xy 143.849344 -271.651222)
			(xy 143.803116 -271.748758) (xy 143.93799 -271.883378)
		)
		(stroke
			(width 0)
			(type solid)
		)
		(fill yes)
		(layer "F.Cu")
		(net "M_E_CPU1_SA_DQ<26>")
	)
	(gr_poly
		(pts
			(xy 144.03705 -261.984998) (xy 144.072864 -261.94893) (xy 143.886936 -261.763002) (xy 143.851122 -261.79907)
			(xy 143.804894 -261.896352) (xy 143.939514 -262.031226)
		)
		(stroke
			(width 0)
			(type solid)
		)
		(fill yes)
		(layer "F.Cu")
		(net "M_E_CPU1_SA_CB<7>")
	)
	(gr_poly
		(pts
			(xy 144.037812 -266.58697) (xy 144.08404 -266.489434) (xy 143.949166 -266.354814) (xy 143.851884 -266.401042)
			(xy 143.815816 -266.436856) (xy 144.001744 -266.622784)
		)
		(stroke
			(width 0)
			(type solid)
		)
		(fill yes)
		(layer "F.Cu")
		(net "M_E_CPU1_SA_CB<0>")
	)
	(gr_poly
		(pts
			(xy 144.042384 -234.28833) (xy 143.996156 -234.190794) (xy 143.960088 -234.15498) (xy 143.77416 -234.340908)
			(xy 143.810228 -234.376722) (xy 143.90751 -234.42295)
		)
		(stroke
			(width 0)
			(type solid)
		)
		(fill yes)
		(layer "F.Cu")
		(net "M_E_CPU1_SB_DQ<12>")
	)
	(gr_poly
		(pts
			(xy 144.044416 -270.98371) (xy 144.080484 -270.947896) (xy 143.894556 -270.761968) (xy 143.858488 -270.797782)
			(xy 143.81226 -270.895318) (xy 143.947134 -271.029938)
		)
		(stroke
			(width 0)
			(type solid)
		)
		(fill yes)
		(layer "F.Cu")
		(net "M_E_CPU1_SA_DQ<27>")
	)
	(gr_poly
		(pts
			(xy 144.046956 -265.73353) (xy 144.093184 -265.635994) (xy 143.958564 -265.501374) (xy 143.861028 -265.547602)
			(xy 143.825214 -265.58367) (xy 144.010888 -265.769344)
		)
		(stroke
			(width 0)
			(type solid)
		)
		(fill yes)
		(layer "F.Cu")
		(net "M_E_CPU1_SA_CB<1>")
	)
	(gr_poly
		(pts
			(xy 144.053052 -249.069352) (xy 144.053052 -249.018552) (xy 143.789908 -249.018552) (xy 143.789908 -249.069352)
			(xy 143.82623 -249.170952) (xy 144.01673 -249.170952)
		)
		(stroke
			(width 0)
			(type solid)
		)
		(fill yes)
		(layer "F.Cu")
		(net "M_E_CPU1_SB_CA<0>")
	)
	(gr_poly
		(pts
			(xy 144.053052 -248.764552) (xy 144.053052 -248.713752) (xy 143.789908 -248.713752) (xy 143.789908 -248.764552)
			(xy 143.82623 -248.866152) (xy 144.01673 -248.866152)
		)
		(stroke
			(width 0)
			(type solid)
		)
		(fill yes)
		(layer "F.Cu")
		(net "M_E_CPU1_SB_CA<1>")
	)
	(gr_poly
		(pts
			(xy 144.053052 -248.459752) (xy 144.053052 -248.408952) (xy 143.789908 -248.408952) (xy 143.789908 -248.459752)
			(xy 143.82623 -248.561352) (xy 144.01673 -248.561352)
		)
		(stroke
			(width 0)
			(type solid)
		)
		(fill yes)
		(layer "F.Cu")
		(net "M_E_CPU1_SB_CA<2>")
	)
	(gr_poly
		(pts
			(xy 144.053052 -248.154952) (xy 144.053052 -248.104152) (xy 143.789908 -248.104152) (xy 143.789908 -248.154952)
			(xy 143.82623 -248.256552) (xy 144.01673 -248.256552)
		)
		(stroke
			(width 0)
			(type solid)
		)
		(fill yes)
		(layer "F.Cu")
		(net "M_E_CPU1_SB_CA<3>")
	)
	(gr_poly
		(pts
			(xy 144.053052 -247.850152) (xy 144.053052 -247.799352) (xy 143.789908 -247.799352) (xy 143.789908 -247.850152)
			(xy 143.82623 -247.951752) (xy 144.01673 -247.951752)
		)
		(stroke
			(width 0)
			(type solid)
		)
		(fill yes)
		(layer "F.Cu")
		(net "M_E_CPU1_SB_CA<4>")
	)
	(gr_poly
		(pts
			(xy 144.053052 -247.545352) (xy 144.053052 -247.494552) (xy 143.789908 -247.494552) (xy 143.789908 -247.545352)
			(xy 143.82623 -247.646952) (xy 144.01673 -247.646952)
		)
		(stroke
			(width 0)
			(type solid)
		)
		(fill yes)
		(layer "F.Cu")
		(net "M_E_CPU1_SB_CA<5>")
	)
	(gr_poly
		(pts
			(xy 144.053052 -247.240552) (xy 144.053052 -247.189752) (xy 143.789908 -247.189752) (xy 143.789908 -247.240552)
			(xy 143.82623 -247.342152) (xy 144.01673 -247.342152)
		)
		(stroke
			(width 0)
			(type solid)
		)
		(fill yes)
		(layer "F.Cu")
		(net "M_E_CPU1_SB_CA<6>")
	)
	(gr_poly
		(pts
			(xy 144.053052 -246.935752) (xy 144.053052 -246.884952) (xy 143.789908 -246.884952) (xy 143.789908 -246.935752)
			(xy 143.82623 -247.037352) (xy 144.01673 -247.037352)
		)
		(stroke
			(width 0)
			(type solid)
		)
		(fill yes)
		(layer "F.Cu")
		(net "M_E_CPU1_SB_PAR")
	)
	(gr_poly
		(pts
			(xy 144.067276 -236.85119) (xy 144.021048 -236.753908) (xy 143.985234 -236.71784) (xy 143.799306 -236.903768)
			(xy 143.83512 -236.939582) (xy 143.932656 -236.986064)
		)
		(stroke
			(width 0)
			(type solid)
		)
		(fill yes)
		(layer "F.Cu")
		(net "M_E_CPU1_SB_DQ<9>")
	)
	(gr_poly
		(pts
			(xy 144.067784 -256.416302) (xy 144.114012 -256.31902) (xy 143.979392 -256.184146) (xy 143.881856 -256.230374)
			(xy 143.846042 -256.266442) (xy 144.03197 -256.45237)
		)
		(stroke
			(width 0)
			(type solid)
		)
		(fill yes)
		(layer "F.Cu")
		(net "M_E_CPU1_SA_CA<5>")
	)
	(gr_poly
		(pts
			(xy 144.071086 -268.24178) (xy 144.117314 -268.144498) (xy 143.982694 -268.009624) (xy 143.885158 -268.055852)
			(xy 143.849344 -268.09192) (xy 144.035272 -268.277848)
		)
		(stroke
			(width 0)
			(type solid)
		)
		(fill yes)
		(layer "F.Cu")
		(net "M_E_CPU1_SA_DQ<30>")
	)
	(gr_poly
		(pts
			(xy 144.075912 -227.325174) (xy 144.075912 -227.134674) (xy 143.974312 -227.098606) (xy 143.923512 -227.098606)
			(xy 143.923512 -227.361496) (xy 143.974312 -227.361496)
		)
		(stroke
			(width 0)
			(type solid)
		)
		(fill yes)
		(layer "F.Cu")
		(net "M_E_CPU1_SB_DQ<21>")
	)
	(gr_poly
		(pts
			(xy 144.075912 -226.728274) (xy 144.075912 -226.537774) (xy 143.974312 -226.501706) (xy 143.923512 -226.501706)
			(xy 143.923512 -226.764596) (xy 143.974312 -226.764596)
		)
		(stroke
			(width 0)
			(type solid)
		)
		(fill yes)
		(layer "F.Cu")
		(net "M_E_CPU1_SB_DQ<21>")
	)
	(gr_poly
		(pts
			(xy 144.075912 -226.131374) (xy 144.075912 -225.940874) (xy 143.974312 -225.904806) (xy 143.923512 -225.904806)
			(xy 143.923512 -226.167696) (xy 143.974312 -226.167696)
		)
		(stroke
			(width 0)
			(type solid)
		)
		(fill yes)
		(layer "F.Cu")
		(net "M_E_CPU1_SB_DQ<21>")
	)
	(gr_poly
		(pts
			(xy 144.075912 -225.534474) (xy 144.075912 -225.343974) (xy 143.974312 -225.307906) (xy 143.923512 -225.307906)
			(xy 143.923512 -225.570796) (xy 143.974312 -225.570796)
		)
		(stroke
			(width 0)
			(type solid)
		)
		(fill yes)
		(layer "F.Cu")
		(net "M_E_CPU1_SB_DQ<21>")
	)
	(gr_poly
		(pts
			(xy 144.075912 -224.937574) (xy 144.075912 -224.747074) (xy 143.974312 -224.711006) (xy 143.923512 -224.711006)
			(xy 143.923512 -224.973896) (xy 143.974312 -224.973896)
		)
		(stroke
			(width 0)
			(type solid)
		)
		(fill yes)
		(layer "F.Cu")
		(net "M_E_CPU1_SB_DQ<21>")
	)
	(gr_poly
		(pts
			(xy 144.075912 -224.340674) (xy 144.075912 -224.150174) (xy 143.974312 -224.114106) (xy 143.923512 -224.114106)
			(xy 143.923512 -224.376996) (xy 143.974312 -224.376996)
		)
		(stroke
			(width 0)
			(type solid)
		)
		(fill yes)
		(layer "F.Cu")
		(net "M_E_CPU1_SB_DQ<21>")
	)
	(gr_poly
		(pts
			(xy 144.075912 -223.743774) (xy 144.075912 -223.553274) (xy 143.974312 -223.517206) (xy 143.923512 -223.517206)
			(xy 143.923512 -223.780096) (xy 143.974312 -223.780096)
		)
		(stroke
			(width 0)
			(type solid)
		)
		(fill yes)
		(layer "F.Cu")
		(net "M_E_CPU1_SB_DQ<21>")
	)
	(gr_poly
		(pts
			(xy 144.075912 -223.146874) (xy 144.075912 -222.956374) (xy 143.974312 -222.920306) (xy 143.923512 -222.920306)
			(xy 143.923512 -223.183196) (xy 143.974312 -223.183196)
		)
		(stroke
			(width 0)
			(type solid)
		)
		(fill yes)
		(layer "F.Cu")
		(net "M_E_CPU1_SB_DQ<21>")
	)
	(gr_poly
		(pts
			(xy 144.075912 -222.549974) (xy 144.075912 -222.359474) (xy 143.974312 -222.323406) (xy 143.923512 -222.323406)
			(xy 143.923512 -222.586296) (xy 143.974312 -222.586296)
		)
		(stroke
			(width 0)
			(type solid)
		)
		(fill yes)
		(layer "F.Cu")
		(net "M_E_CPU1_SB_DQ<21>")
	)
	(gr_poly
		(pts
			(xy 144.075912 -221.953074) (xy 144.075912 -221.762574) (xy 143.974312 -221.726506) (xy 143.923512 -221.726506)
			(xy 143.923512 -221.989396) (xy 143.974312 -221.989396)
		)
		(stroke
			(width 0)
			(type solid)
		)
		(fill yes)
		(layer "F.Cu")
		(net "M_E_CPU1_SB_DQ<21>")
	)
	(gr_poly
		(pts
			(xy 144.075912 -221.356174) (xy 144.075912 -221.165674) (xy 143.974312 -221.129606) (xy 143.923512 -221.129606)
			(xy 143.923512 -221.392496) (xy 143.974312 -221.392496)
		)
		(stroke
			(width 0)
			(type solid)
		)
		(fill yes)
		(layer "F.Cu")
		(net "M_E_CPU1_SB_DQ<21>")
	)
	(gr_poly
		(pts
			(xy 144.075912 -220.759274) (xy 144.075912 -220.568774) (xy 143.974312 -220.532706) (xy 143.923512 -220.532706)
			(xy 143.923512 -220.795596) (xy 143.974312 -220.795596)
		)
		(stroke
			(width 0)
			(type solid)
		)
		(fill yes)
		(layer "F.Cu")
		(net "M_E_CPU1_SB_DQ<21>")
	)
	(gr_poly
		(pts
			(xy 144.075912 -220.162374) (xy 144.075912 -219.971874) (xy 143.974312 -219.935806) (xy 143.923512 -219.935806)
			(xy 143.923512 -220.198696) (xy 143.974312 -220.198696)
		)
		(stroke
			(width 0)
			(type solid)
		)
		(fill yes)
		(layer "F.Cu")
		(net "M_E_CPU1_SB_DQ<21>")
	)
	(gr_poly
		(pts
			(xy 144.075912 -219.565474) (xy 144.075912 -219.374974) (xy 143.974312 -219.338906) (xy 143.923512 -219.338906)
			(xy 143.923512 -219.601796) (xy 143.974312 -219.601796)
		)
		(stroke
			(width 0)
			(type solid)
		)
		(fill yes)
		(layer "F.Cu")
		(net "M_E_CPU1_SB_DQ<21>")
	)
	(gr_poly
		(pts
			(xy 144.075912 -218.968574) (xy 144.075912 -218.778074) (xy 143.974312 -218.742006) (xy 143.923512 -218.742006)
			(xy 143.923512 -219.004896) (xy 143.974312 -219.004896)
		)
		(stroke
			(width 0)
			(type solid)
		)
		(fill yes)
		(layer "F.Cu")
		(net "M_E_CPU1_SB_DQ<21>")
	)
	(gr_poly
		(pts
			(xy 144.075912 -218.371674) (xy 144.075912 -218.181174) (xy 143.974312 -218.145106) (xy 143.923512 -218.145106)
			(xy 143.923512 -218.407996) (xy 143.974312 -218.407996)
		)
		(stroke
			(width 0)
			(type solid)
		)
		(fill yes)
		(layer "F.Cu")
		(net "M_E_CPU1_SB_DQ<21>")
	)
	(gr_poly
		(pts
			(xy 144.075912 -217.774774) (xy 144.075912 -217.584274) (xy 143.974312 -217.548206) (xy 143.923512 -217.548206)
			(xy 143.923512 -217.811096) (xy 143.974312 -217.811096)
		)
		(stroke
			(width 0)
			(type solid)
		)
		(fill yes)
		(layer "F.Cu")
		(net "M_E_CPU1_SB_DQ<21>")
	)
	(gr_poly
		(pts
			(xy 144.075912 -217.177874) (xy 144.075912 -216.987374) (xy 143.974312 -216.951306) (xy 143.923512 -216.951306)
			(xy 143.923512 -217.214196) (xy 143.974312 -217.214196)
		)
		(stroke
			(width 0)
			(type solid)
		)
		(fill yes)
		(layer "F.Cu")
		(net "M_E_CPU1_SB_DQ<21>")
	)
	(gr_poly
		(pts
			(xy 144.075912 -216.580974) (xy 144.075912 -216.390474) (xy 143.974312 -216.354406) (xy 143.923512 -216.354406)
			(xy 143.923512 -216.617296) (xy 143.974312 -216.617296)
		)
		(stroke
			(width 0)
			(type solid)
		)
		(fill yes)
		(layer "F.Cu")
		(net "M_E_CPU1_SB_DQ<21>")
	)
	(gr_poly
		(pts
			(xy 144.075912 -215.984074) (xy 144.075912 -215.793574) (xy 143.974312 -215.757506) (xy 143.923512 -215.757506)
			(xy 143.923512 -216.020396) (xy 143.974312 -216.020396)
		)
		(stroke
			(width 0)
			(type solid)
		)
		(fill yes)
		(layer "F.Cu")
		(net "M_E_CPU1_SB_DQ<21>")
	)
	(gr_poly
		(pts
			(xy 144.076166 -238.548418) (xy 144.029938 -238.450882) (xy 143.99387 -238.415068) (xy 143.807942 -238.600996)
			(xy 143.84401 -238.63681) (xy 143.941292 -238.683038)
		)
		(stroke
			(width 0)
			(type solid)
		)
		(fill yes)
		(layer "F.Cu")
		(net "M_E_CPU1_SB_CB<3>")
	)
	(gr_poly
		(pts
			(xy 144.076928 -255.563116) (xy 144.123156 -255.46558) (xy 143.988536 -255.33096) (xy 143.891254 -255.377188)
			(xy 143.855186 -255.413002) (xy 144.041114 -255.59893)
		)
		(stroke
			(width 0)
			(type solid)
		)
		(fill yes)
		(layer "F.Cu")
		(net "M_E_CPU1_SA_PAR")
	)
	(gr_poly
		(pts
			(xy 144.077436 -237.705392) (xy 144.030954 -237.607856) (xy 143.99514 -237.572042) (xy 143.809212 -237.75797)
			(xy 143.84528 -237.793784) (xy 143.942562 -237.840012)
		)
		(stroke
			(width 0)
			(type solid)
		)
		(fill yes)
		(layer "F.Cu")
		(net "M_E_CPU1_SB_DQ<8>")
	)
	(gr_poly
		(pts
			(xy 144.080484 -267.388086) (xy 144.126712 -267.290804) (xy 143.992092 -267.156184) (xy 143.894556 -267.202412)
			(xy 143.858742 -267.238226) (xy 144.04467 -267.424154)
		)
		(stroke
			(width 0)
			(type solid)
		)
		(fill yes)
		(layer "F.Cu")
		(net "M_E_CPU1_SA_DQ<31>")
	)
	(gr_poly
		(pts
			(xy 144.08531 -239.401604) (xy 144.039082 -239.304322) (xy 144.003268 -239.268254) (xy 143.81734 -239.454182)
			(xy 143.853154 -239.49025) (xy 143.95069 -239.536478)
		)
		(stroke
			(width 0)
			(type solid)
		)
		(fill yes)
		(layer "F.Cu")
		(net "M_E_CPU1_SB_CB<2>")
	)
	(gr_poly
		(pts
			(xy 144.093692 -273.88947) (xy 144.13992 -273.792188) (xy 144.0053 -273.657314) (xy 143.907764 -273.703542)
			(xy 143.87195 -273.73961) (xy 144.057878 -273.925538)
		)
		(stroke
			(width 0)
			(type solid)
		)
		(fill yes)
		(layer "F.Cu")
		(net "M_E_CPU1_SA_DQ<22>")
	)
	(gr_poly
		(pts
			(xy 144.094962 -263.193022) (xy 144.14119 -263.09574) (xy 144.00657 -262.960866) (xy 143.909034 -263.007094)
			(xy 143.87322 -263.043162) (xy 144.059148 -263.22909)
		)
		(stroke
			(width 0)
			(type solid)
		)
		(fill yes)
		(layer "F.Cu")
		(net "M_E_CPU1_SA_CB<4>")
	)
	(gr_poly
		(pts
			(xy 144.102582 -272.191988) (xy 144.14881 -272.094706) (xy 144.01419 -271.959832) (xy 143.916654 -272.00606)
			(xy 143.88084 -272.042128) (xy 144.066768 -272.228056)
		)
		(stroke
			(width 0)
			(type solid)
		)
		(fill yes)
		(layer "F.Cu")
		(net "M_E_CPU1_SA_DQ<24>")
	)
	(gr_poly
		(pts
			(xy 144.102836 -273.03603) (xy 144.149318 -272.938494) (xy 144.014444 -272.803874) (xy 143.917162 -272.850102)
			(xy 143.881094 -272.885916) (xy 144.067022 -273.071844)
		)
		(stroke
			(width 0)
			(type solid)
		)
		(fill yes)
		(layer "F.Cu")
		(net "M_E_CPU1_SA_DQ<23>")
	)
	(gr_poly
		(pts
			(xy 144.104106 -262.339836) (xy 144.150588 -262.2423) (xy 144.015714 -262.10768) (xy 143.918432 -262.153908)
			(xy 143.882364 -262.189722) (xy 144.068292 -262.37565)
		)
		(stroke
			(width 0)
			(type solid)
		)
		(fill yes)
		(layer "F.Cu")
		(net "M_E_CPU1_SA_CB<5>")
	)
	(gr_poly
		(pts
			(xy 144.111726 -271.338548) (xy 144.157954 -271.241266) (xy 144.023334 -271.106392) (xy 143.925798 -271.15262)
			(xy 143.889984 -271.188688) (xy 144.075912 -271.374616)
		)
		(stroke
			(width 0)
			(type solid)
		)
		(fill yes)
		(layer "F.Cu")
		(net "M_E_CPU1_SA_DQ<25>")
	)
	(gr_poly
		(pts
			(xy 144.11706 -227.978716) (xy 144.081246 -227.942648) (xy 143.98371 -227.89642) (xy 143.84909 -228.031294)
			(xy 143.895318 -228.128576) (xy 143.931132 -228.164644)
		)
		(stroke
			(width 0)
			(type solid)
		)
		(fill yes)
		(layer "F.Cu")
		(net "M_E_CPU1_SB_DQ<22>")
	)
	(gr_poly
		(pts
			(xy 144.143984 -230.540052) (xy 144.10817 -230.504238) (xy 144.010634 -230.45801) (xy 143.876014 -230.59263)
			(xy 143.922242 -230.689912) (xy 143.958056 -230.72598)
		)
		(stroke
			(width 0)
			(type solid)
		)
		(fill yes)
		(layer "F.Cu")
		(net "M_E_CPU1_SB_DQ<19>")
	)
	(gr_poly
		(pts
			(xy 144.15135 -289.175698) (xy 144.15135 -288.985198) (xy 144.04975 -288.94913) (xy 143.99895 -288.94913)
			(xy 143.99895 -289.21202) (xy 144.04975 -289.21202)
		)
		(stroke
			(width 0)
			(type solid)
		)
		(fill yes)
		(layer "F.Cu")
		(net "M_E_CPU1_SA_DQ<19>")
	)
	(gr_poly
		(pts
			(xy 144.15135 -288.578798) (xy 144.15135 -288.388298) (xy 144.04975 -288.35223) (xy 143.99895 -288.35223)
			(xy 143.99895 -288.61512) (xy 144.04975 -288.61512)
		)
		(stroke
			(width 0)
			(type solid)
		)
		(fill yes)
		(layer "F.Cu")
		(net "M_E_CPU1_SA_DQ<19>")
	)
	(gr_poly
		(pts
			(xy 144.15135 -287.981898) (xy 144.15135 -287.791398) (xy 144.04975 -287.75533) (xy 143.99895 -287.75533)
			(xy 143.99895 -288.01822) (xy 144.04975 -288.01822)
		)
		(stroke
			(width 0)
			(type solid)
		)
		(fill yes)
		(layer "F.Cu")
		(net "M_E_CPU1_SA_DQ<19>")
	)
	(gr_poly
		(pts
			(xy 144.15135 -287.384998) (xy 144.15135 -287.194498) (xy 144.04975 -287.15843) (xy 143.99895 -287.15843)
			(xy 143.99895 -287.42132) (xy 144.04975 -287.42132)
		)
		(stroke
			(width 0)
			(type solid)
		)
		(fill yes)
		(layer "F.Cu")
		(net "M_E_CPU1_SA_DQ<19>")
	)
	(gr_poly
		(pts
			(xy 144.15135 -286.788098) (xy 144.15135 -286.597598) (xy 144.04975 -286.56153) (xy 143.99895 -286.56153)
			(xy 143.99895 -286.82442) (xy 144.04975 -286.82442)
		)
		(stroke
			(width 0)
			(type solid)
		)
		(fill yes)
		(layer "F.Cu")
		(net "M_E_CPU1_SA_DQ<19>")
	)
	(gr_poly
		(pts
			(xy 144.15135 -286.191198) (xy 144.15135 -286.000698) (xy 144.04975 -285.96463) (xy 143.99895 -285.96463)
			(xy 143.99895 -286.22752) (xy 144.04975 -286.22752)
		)
		(stroke
			(width 0)
			(type solid)
		)
		(fill yes)
		(layer "F.Cu")
		(net "M_E_CPU1_SA_DQ<19>")
	)
	(gr_poly
		(pts
			(xy 144.15135 -285.594298) (xy 144.15135 -285.403798) (xy 144.04975 -285.36773) (xy 143.99895 -285.36773)
			(xy 143.99895 -285.63062) (xy 144.04975 -285.63062)
		)
		(stroke
			(width 0)
			(type solid)
		)
		(fill yes)
		(layer "F.Cu")
		(net "M_E_CPU1_SA_DQ<19>")
	)
	(gr_poly
		(pts
			(xy 144.15135 -284.997398) (xy 144.15135 -284.806898) (xy 144.04975 -284.77083) (xy 143.99895 -284.77083)
			(xy 143.99895 -285.03372) (xy 144.04975 -285.03372)
		)
		(stroke
			(width 0)
			(type solid)
		)
		(fill yes)
		(layer "F.Cu")
		(net "M_E_CPU1_SA_DQ<19>")
	)
	(gr_poly
		(pts
			(xy 144.15135 -284.400498) (xy 144.15135 -284.209998) (xy 144.04975 -284.17393) (xy 143.99895 -284.17393)
			(xy 143.99895 -284.43682) (xy 144.04975 -284.43682)
		)
		(stroke
			(width 0)
			(type solid)
		)
		(fill yes)
		(layer "F.Cu")
		(net "M_E_CPU1_SA_DQ<19>")
	)
	(gr_poly
		(pts
			(xy 144.15135 -283.803598) (xy 144.15135 -283.613098) (xy 144.04975 -283.57703) (xy 143.99895 -283.57703)
			(xy 143.99895 -283.83992) (xy 144.04975 -283.83992)
		)
		(stroke
			(width 0)
			(type solid)
		)
		(fill yes)
		(layer "F.Cu")
		(net "M_E_CPU1_SA_DQ<19>")
	)
	(gr_poly
		(pts
			(xy 144.15135 -283.206698) (xy 144.15135 -283.016198) (xy 144.04975 -282.98013) (xy 143.99895 -282.98013)
			(xy 143.99895 -283.24302) (xy 144.04975 -283.24302)
		)
		(stroke
			(width 0)
			(type solid)
		)
		(fill yes)
		(layer "F.Cu")
		(net "M_E_CPU1_SA_DQ<19>")
	)
	(gr_poly
		(pts
			(xy 144.15135 -282.609798) (xy 144.15135 -282.419298) (xy 144.04975 -282.38323) (xy 143.99895 -282.38323)
			(xy 143.99895 -282.64612) (xy 144.04975 -282.64612)
		)
		(stroke
			(width 0)
			(type solid)
		)
		(fill yes)
		(layer "F.Cu")
		(net "M_E_CPU1_SA_DQ<19>")
	)
	(gr_poly
		(pts
			(xy 144.15135 -282.012898) (xy 144.15135 -281.822398) (xy 144.04975 -281.78633) (xy 143.99895 -281.78633)
			(xy 143.99895 -282.04922) (xy 144.04975 -282.04922)
		)
		(stroke
			(width 0)
			(type solid)
		)
		(fill yes)
		(layer "F.Cu")
		(net "M_E_CPU1_SA_DQ<19>")
	)
	(gr_poly
		(pts
			(xy 144.15135 -281.415998) (xy 144.15135 -281.225498) (xy 144.04975 -281.18943) (xy 143.99895 -281.18943)
			(xy 143.99895 -281.45232) (xy 144.04975 -281.45232)
		)
		(stroke
			(width 0)
			(type solid)
		)
		(fill yes)
		(layer "F.Cu")
		(net "M_E_CPU1_SA_DQ<19>")
	)
	(gr_poly
		(pts
			(xy 144.153128 -231.393492) (xy 144.117314 -231.357424) (xy 144.019778 -231.311196) (xy 143.885158 -231.44607)
			(xy 143.931386 -231.543352) (xy 143.9672 -231.57942)
		)
		(stroke
			(width 0)
			(type solid)
		)
		(fill yes)
		(layer "F.Cu")
		(net "M_E_CPU1_SB_DQ<18>")
	)
	(gr_poly
		(pts
			(xy 144.162018 -233.090466) (xy 144.12595 -233.054652) (xy 144.028668 -233.008424) (xy 143.894048 -233.143044)
			(xy 143.940276 -233.24058) (xy 143.97609 -233.276394)
		)
		(stroke
			(width 0)
			(type solid)
		)
		(fill yes)
		(layer "F.Cu")
		(net "M_E_CPU1_SB_DQ<13>")
	)
	(gr_poly
		(pts
			(xy 144.171162 -233.943906) (xy 144.135348 -233.907838) (xy 144.037812 -233.86161) (xy 143.903192 -233.996484)
			(xy 143.94942 -234.093766) (xy 143.985234 -234.129834)
		)
		(stroke
			(width 0)
			(type solid)
		)
		(fill yes)
		(layer "F.Cu")
		(net "M_E_CPU1_SB_DQ<12>")
	)
	(gr_poly
		(pts
			(xy 144.177004 -266.869672) (xy 144.212818 -266.833858) (xy 144.02689 -266.64793) (xy 143.991076 -266.683998)
			(xy 143.944848 -266.78128) (xy 144.079468 -266.916154)
		)
		(stroke
			(width 0)
			(type solid)
		)
		(fill yes)
		(layer "F.Cu")
		(net "M_E_CPU1_SA_CB<0>")
	)
	(gr_poly
		(pts
			(xy 144.180814 -242.598956) (xy 144.144492 -242.497356) (xy 143.953992 -242.497356) (xy 143.917924 -242.598956)
			(xy 143.917924 -242.649756) (xy 144.180814 -242.649756)
		)
		(stroke
			(width 0)
			(type solid)
		)
		(fill yes)
		(layer "F.Cu")
		(net "M_E_CPU1_SB_CB<4>")
	)
	(gr_poly
		(pts
			(xy 144.180814 -242.294156) (xy 144.144492 -242.192556) (xy 143.953992 -242.192556) (xy 143.917924 -242.294156)
			(xy 143.917924 -242.344956) (xy 144.180814 -242.344956)
		)
		(stroke
			(width 0)
			(type solid)
		)
		(fill yes)
		(layer "F.Cu")
		(net "M_E_CPU1_SB_CB<6>")
	)
	(gr_poly
		(pts
			(xy 144.186148 -266.016486) (xy 144.221962 -265.980418) (xy 144.036034 -265.79449) (xy 144.00022 -265.830558)
			(xy 143.953992 -265.92784) (xy 144.088612 -266.062714)
		)
		(stroke
			(width 0)
			(type solid)
		)
		(fill yes)
		(layer "F.Cu")
		(net "M_E_CPU1_SA_CB<1>")
	)
	(gr_poly
		(pts
			(xy 144.196308 -236.506766) (xy 144.16024 -236.470952) (xy 144.062958 -236.424724) (xy 143.928084 -236.559344)
			(xy 143.974312 -236.65688) (xy 144.01038 -236.692694)
		)
		(stroke
			(width 0)
			(type solid)
		)
		(fill yes)
		(layer "F.Cu")
		(net "M_E_CPU1_SB_DQ<9>")
	)
	(gr_poly
		(pts
			(xy 144.203928 -228.538786) (xy 144.1577 -228.44125) (xy 144.121632 -228.405436) (xy 143.935704 -228.591364)
			(xy 143.971772 -228.627178) (xy 144.069308 -228.673406)
		)
		(stroke
			(width 0)
			(type solid)
		)
		(fill yes)
		(layer "F.Cu")
		(net "M_E_CPU1_SB_DQ<20>")
	)
	(gr_poly
		(pts
			(xy 144.204944 -238.203994) (xy 144.16913 -238.167926) (xy 144.071594 -238.121698) (xy 143.936974 -238.256572)
			(xy 143.983202 -238.353854) (xy 144.019016 -238.389922)
		)
		(stroke
			(width 0)
			(type solid)
		)
		(fill yes)
		(layer "F.Cu")
		(net "M_E_CPU1_SB_CB<3>")
	)
	(gr_poly
		(pts
			(xy 144.206214 -237.360968) (xy 144.170146 -237.325154) (xy 144.072864 -237.278926) (xy 143.938244 -237.413546)
			(xy 143.984472 -237.511082) (xy 144.020286 -237.546896)
		)
		(stroke
			(width 0)
			(type solid)
		)
		(fill yes)
		(layer "F.Cu")
		(net "M_E_CPU1_SB_DQ<8>")
	)
	(gr_poly
		(pts
			(xy 144.210278 -268.524736) (xy 144.246092 -268.488668) (xy 144.060418 -268.302994) (xy 144.02435 -268.338808)
			(xy 143.978122 -268.436344) (xy 144.112742 -268.570964)
		)
		(stroke
			(width 0)
			(type solid)
		)
		(fill yes)
		(layer "F.Cu")
		(net "M_E_CPU1_SA_DQ<30>")
	)
	(gr_poly
		(pts
			(xy 144.214088 -239.057434) (xy 144.178274 -239.021366) (xy 144.080738 -238.975138) (xy 143.946118 -239.109758)
			(xy 143.992346 -239.207294) (xy 144.028414 -239.243108)
		)
		(stroke
			(width 0)
			(type solid)
		)
		(fill yes)
		(layer "F.Cu")
		(net "M_E_CPU1_SB_CB<2>")
	)
	(gr_poly
		(pts
			(xy 144.21612 -255.845818) (xy 144.252188 -255.810004) (xy 144.06626 -255.624076) (xy 144.030446 -255.65989)
			(xy 143.983964 -255.757426) (xy 144.118838 -255.892046)
		)
		(stroke
			(width 0)
			(type solid)
		)
		(fill yes)
		(layer "F.Cu")
		(net "M_E_CPU1_SA_PAR")
	)
	(gr_poly
		(pts
			(xy 144.219676 -267.671042) (xy 144.255744 -267.635228) (xy 144.069816 -267.4493) (xy 144.033748 -267.485114)
			(xy 143.98752 -267.58265) (xy 144.122394 -267.71727)
		)
		(stroke
			(width 0)
			(type solid)
		)
		(fill yes)
		(layer "F.Cu")
		(net "M_E_CPU1_SA_DQ<31>")
	)
	(gr_poly
		(pts
			(xy 144.228312 -227.397056) (xy 144.177512 -227.397056) (xy 144.075912 -227.433378) (xy 144.075912 -227.623878)
			(xy 144.177512 -227.659946) (xy 144.228312 -227.659946)
		)
		(stroke
			(width 0)
			(type solid)
		)
		(fill yes)
		(layer "F.Cu")
		(net "M_E_CPU1_SB_DQ<22>")
	)
	(gr_poly
		(pts
			(xy 144.228312 -226.800156) (xy 144.177512 -226.800156) (xy 144.075912 -226.836478) (xy 144.075912 -227.026978)
			(xy 144.177512 -227.063046) (xy 144.228312 -227.063046)
		)
		(stroke
			(width 0)
			(type solid)
		)
		(fill yes)
		(layer "F.Cu")
		(net "M_E_CPU1_SB_DQ<22>")
	)
	(gr_poly
		(pts
			(xy 144.228312 -226.203256) (xy 144.177512 -226.203256) (xy 144.075912 -226.239578) (xy 144.075912 -226.430078)
			(xy 144.177512 -226.466146) (xy 144.228312 -226.466146)
		)
		(stroke
			(width 0)
			(type solid)
		)
		(fill yes)
		(layer "F.Cu")
		(net "M_E_CPU1_SB_DQ<22>")
	)
	(gr_poly
		(pts
			(xy 144.228312 -225.606356) (xy 144.177512 -225.606356) (xy 144.075912 -225.642678) (xy 144.075912 -225.833178)
			(xy 144.177512 -225.869246) (xy 144.228312 -225.869246)
		)
		(stroke
			(width 0)
			(type solid)
		)
		(fill yes)
		(layer "F.Cu")
		(net "M_E_CPU1_SB_DQ<22>")
	)
	(gr_poly
		(pts
			(xy 144.228312 -225.009456) (xy 144.177512 -225.009456) (xy 144.075912 -225.045778) (xy 144.075912 -225.236278)
			(xy 144.177512 -225.272346) (xy 144.228312 -225.272346)
		)
		(stroke
			(width 0)
			(type solid)
		)
		(fill yes)
		(layer "F.Cu")
		(net "M_E_CPU1_SB_DQ<22>")
	)
	(gr_poly
		(pts
			(xy 144.228312 -224.412556) (xy 144.177512 -224.412556) (xy 144.075912 -224.448878) (xy 144.075912 -224.639378)
			(xy 144.177512 -224.675446) (xy 144.228312 -224.675446)
		)
		(stroke
			(width 0)
			(type solid)
		)
		(fill yes)
		(layer "F.Cu")
		(net "M_E_CPU1_SB_DQ<22>")
	)
	(gr_poly
		(pts
			(xy 144.228312 -223.815656) (xy 144.177512 -223.815656) (xy 144.075912 -223.851978) (xy 144.075912 -224.042478)
			(xy 144.177512 -224.078546) (xy 144.228312 -224.078546)
		)
		(stroke
			(width 0)
			(type solid)
		)
		(fill yes)
		(layer "F.Cu")
		(net "M_E_CPU1_SB_DQ<22>")
	)
	(gr_poly
		(pts
			(xy 144.228312 -223.218756) (xy 144.177512 -223.218756) (xy 144.075912 -223.255078) (xy 144.075912 -223.445578)
			(xy 144.177512 -223.481646) (xy 144.228312 -223.481646)
		)
		(stroke
			(width 0)
			(type solid)
		)
		(fill yes)
		(layer "F.Cu")
		(net "M_E_CPU1_SB_DQ<22>")
	)
	(gr_poly
		(pts
			(xy 144.228312 -222.621856) (xy 144.177512 -222.621856) (xy 144.075912 -222.658178) (xy 144.075912 -222.848678)
			(xy 144.177512 -222.884746) (xy 144.228312 -222.884746)
		)
		(stroke
			(width 0)
			(type solid)
		)
		(fill yes)
		(layer "F.Cu")
		(net "M_E_CPU1_SB_DQ<22>")
	)
	(gr_poly
		(pts
			(xy 144.228312 -222.024956) (xy 144.177512 -222.024956) (xy 144.075912 -222.061278) (xy 144.075912 -222.251778)
			(xy 144.177512 -222.287846) (xy 144.228312 -222.287846)
		)
		(stroke
			(width 0)
			(type solid)
		)
		(fill yes)
		(layer "F.Cu")
		(net "M_E_CPU1_SB_DQ<22>")
	)
	(gr_poly
		(pts
			(xy 144.228312 -221.428056) (xy 144.177512 -221.428056) (xy 144.075912 -221.464378) (xy 144.075912 -221.654878)
			(xy 144.177512 -221.690946) (xy 144.228312 -221.690946)
		)
		(stroke
			(width 0)
			(type solid)
		)
		(fill yes)
		(layer "F.Cu")
		(net "M_E_CPU1_SB_DQ<22>")
	)
	(gr_poly
		(pts
			(xy 144.228312 -220.831156) (xy 144.177512 -220.831156) (xy 144.075912 -220.867478) (xy 144.075912 -221.057978)
			(xy 144.177512 -221.094046) (xy 144.228312 -221.094046)
		)
		(stroke
			(width 0)
			(type solid)
		)
		(fill yes)
		(layer "F.Cu")
		(net "M_E_CPU1_SB_DQ<22>")
	)
	(gr_poly
		(pts
			(xy 144.228312 -220.234256) (xy 144.177512 -220.234256) (xy 144.075912 -220.270578) (xy 144.075912 -220.461078)
			(xy 144.177512 -220.497146) (xy 144.228312 -220.497146)
		)
		(stroke
			(width 0)
			(type solid)
		)
		(fill yes)
		(layer "F.Cu")
		(net "M_E_CPU1_SB_DQ<22>")
	)
	(gr_poly
		(pts
			(xy 144.228312 -219.637356) (xy 144.177512 -219.637356) (xy 144.075912 -219.673678) (xy 144.075912 -219.864178)
			(xy 144.177512 -219.900246) (xy 144.228312 -219.900246)
		)
		(stroke
			(width 0)
			(type solid)
		)
		(fill yes)
		(layer "F.Cu")
		(net "M_E_CPU1_SB_DQ<22>")
	)
	(gr_poly
		(pts
			(xy 144.228312 -219.040456) (xy 144.177512 -219.040456) (xy 144.075912 -219.076778) (xy 144.075912 -219.267278)
			(xy 144.177512 -219.303346) (xy 144.228312 -219.303346)
		)
		(stroke
			(width 0)
			(type solid)
		)
		(fill yes)
		(layer "F.Cu")
		(net "M_E_CPU1_SB_DQ<22>")
	)
	(gr_poly
		(pts
			(xy 144.228312 -218.443556) (xy 144.177512 -218.443556) (xy 144.075912 -218.479878) (xy 144.075912 -218.670378)
			(xy 144.177512 -218.706446) (xy 144.228312 -218.706446)
		)
		(stroke
			(width 0)
			(type solid)
		)
		(fill yes)
		(layer "F.Cu")
		(net "M_E_CPU1_SB_DQ<22>")
	)
	(gr_poly
		(pts
			(xy 144.228312 -217.846656) (xy 144.177512 -217.846656) (xy 144.075912 -217.882978) (xy 144.075912 -218.073478)
			(xy 144.177512 -218.109546) (xy 144.228312 -218.109546)
		)
		(stroke
			(width 0)
			(type solid)
		)
		(fill yes)
		(layer "F.Cu")
		(net "M_E_CPU1_SB_DQ<22>")
	)
	(gr_poly
		(pts
			(xy 144.228312 -217.249756) (xy 144.177512 -217.249756) (xy 144.075912 -217.286078) (xy 144.075912 -217.476578)
			(xy 144.177512 -217.512646) (xy 144.228312 -217.512646)
		)
		(stroke
			(width 0)
			(type solid)
		)
		(fill yes)
		(layer "F.Cu")
		(net "M_E_CPU1_SB_DQ<22>")
	)
	(gr_poly
		(pts
			(xy 144.228312 -216.652856) (xy 144.177512 -216.652856) (xy 144.075912 -216.689178) (xy 144.075912 -216.879678)
			(xy 144.177512 -216.915746) (xy 144.228312 -216.915746)
		)
		(stroke
			(width 0)
			(type solid)
		)
		(fill yes)
		(layer "F.Cu")
		(net "M_E_CPU1_SB_DQ<22>")
	)
	(gr_poly
		(pts
			(xy 144.228312 -216.055956) (xy 144.177512 -216.055956) (xy 144.075912 -216.092278) (xy 144.075912 -216.282778)
			(xy 144.177512 -216.318846) (xy 144.228312 -216.318846)
		)
		(stroke
			(width 0)
			(type solid)
		)
		(fill yes)
		(layer "F.Cu")
		(net "M_E_CPU1_SB_DQ<22>")
	)
	(gr_poly
		(pts
			(xy 144.230852 -231.100122) (xy 144.184624 -231.002586) (xy 144.148556 -230.966772) (xy 143.962628 -231.1527)
			(xy 143.998696 -231.188514) (xy 144.095978 -231.234742)
		)
		(stroke
			(width 0)
			(type solid)
		)
		(fill yes)
		(layer "F.Cu")
		(net "M_E_CPU1_SB_DQ<17>")
	)
	(gr_poly
		(pts
			(xy 144.232884 -274.172426) (xy 144.268698 -274.136358) (xy 144.083024 -273.950684) (xy 144.046956 -273.986498)
			(xy 144.000728 -274.084034) (xy 144.135348 -274.218654)
		)
		(stroke
			(width 0)
			(type solid)
		)
		(fill yes)
		(layer "F.Cu")
		(net "M_E_CPU1_SA_DQ<22>")
	)
	(gr_poly
		(pts
			(xy 144.234154 -263.475978) (xy 144.270222 -263.440164) (xy 144.084294 -263.254236) (xy 144.048226 -263.29005)
			(xy 144.001998 -263.387586) (xy 144.136872 -263.522206)
		)
		(stroke
			(width 0)
			(type solid)
		)
		(fill yes)
		(layer "F.Cu")
		(net "M_E_CPU1_SA_CB<4>")
	)
	(gr_poly
		(pts
			(xy 144.239488 -232.797096) (xy 144.19326 -232.699814) (xy 144.157446 -232.663746) (xy 143.971518 -232.849674)
			(xy 144.007332 -232.885742) (xy 144.104868 -232.93197)
		)
		(stroke
			(width 0)
			(type solid)
		)
		(fill yes)
		(layer "F.Cu")
		(net "M_E_CPU1_SB_DQ<15>")
	)
	(gr_poly
		(pts
			(xy 144.239996 -231.953562) (xy 144.193768 -231.856026) (xy 144.1577 -231.820212) (xy 143.972026 -232.005886)
			(xy 144.00784 -232.041954) (xy 144.105376 -232.088182)
		)
		(stroke
			(width 0)
			(type solid)
		)
		(fill yes)
		(layer "F.Cu")
		(net "M_E_CPU1_SB_DQ<16>")
	)
	(gr_poly
		(pts
			(xy 144.241774 -272.474944) (xy 144.277588 -272.438876) (xy 144.091914 -272.253202) (xy 144.055846 -272.289016)
			(xy 144.009618 -272.386552) (xy 144.144238 -272.521172)
		)
		(stroke
			(width 0)
			(type solid)
		)
		(fill yes)
		(layer "F.Cu")
		(net "M_E_CPU1_SA_DQ<24>")
	)
	(gr_poly
		(pts
			(xy 144.242282 -273.318732) (xy 144.278096 -273.282918) (xy 144.092168 -273.09699) (xy 144.056354 -273.132804)
			(xy 144.010126 -273.23034) (xy 144.144746 -273.36496)
		)
		(stroke
			(width 0)
			(type solid)
		)
		(fill yes)
		(layer "F.Cu")
		(net "M_E_CPU1_SA_DQ<23>")
	)
	(gr_poly
		(pts
			(xy 144.243298 -262.622538) (xy 144.279366 -262.586724) (xy 144.093438 -262.400796) (xy 144.057624 -262.43661)
			(xy 144.011396 -262.534146) (xy 144.146016 -262.668766)
		)
		(stroke
			(width 0)
			(type solid)
		)
		(fill yes)
		(layer "F.Cu")
		(net "M_E_CPU1_SA_CB<5>")
	)
	(gr_poly
		(pts
			(xy 144.248886 -233.650536) (xy 144.202404 -233.553) (xy 144.16659 -233.517186) (xy 143.980662 -233.703114)
			(xy 144.01673 -233.738928) (xy 144.114012 -233.785156)
		)
		(stroke
			(width 0)
			(type solid)
		)
		(fill yes)
		(layer "F.Cu")
		(net "M_E_CPU1_SB_DQ<14>")
	)
	(gr_poly
		(pts
			(xy 144.250918 -271.621504) (xy 144.286732 -271.585436) (xy 144.101058 -271.399762) (xy 144.06499 -271.435576)
			(xy 144.018762 -271.533112) (xy 144.153382 -271.667732)
		)
		(stroke
			(width 0)
			(type solid)
		)
		(fill yes)
		(layer "F.Cu")
		(net "M_E_CPU1_SA_DQ<25>")
	)
	(gr_poly
		(pts
			(xy 144.253458 -266.371324) (xy 144.299686 -266.273788) (xy 144.164812 -266.139168) (xy 144.06753 -266.185396)
			(xy 144.031462 -266.22121) (xy 144.21739 -266.407138)
		)
		(stroke
			(width 0)
			(type solid)
		)
		(fill yes)
		(layer "F.Cu")
		(net "M_E_CPU1_SA_CB<2>")
	)
	(gr_poly
		(pts
			(xy 144.262602 -265.517884) (xy 144.30883 -265.420348) (xy 144.17421 -265.285728) (xy 144.076674 -265.331956)
			(xy 144.04086 -265.368024) (xy 144.226534 -265.553698)
		)
		(stroke
			(width 0)
			(type solid)
		)
		(fill yes)
		(layer "F.Cu")
		(net "M_E_CPU1_SA_CB<3>")
	)
	(gr_poly
		(pts
			(xy 144.273524 -236.213396) (xy 144.227296 -236.116114) (xy 144.191482 -236.080046) (xy 144.005554 -236.265974)
			(xy 144.041368 -236.301788) (xy 144.138904 -236.348016)
		)
		(stroke
			(width 0)
			(type solid)
		)
		(fill yes)
		(layer "F.Cu")
		(net "M_E_CPU1_SB_DQ<11>")
	)
	(gr_poly
		(pts
			(xy 144.277588 -268.879574) (xy 144.323816 -268.782038) (xy 144.188942 -268.647418) (xy 144.09166 -268.693646)
			(xy 144.055592 -268.72946) (xy 144.24152 -268.915388)
		)
		(stroke
			(width 0)
			(type solid)
		)
		(fill yes)
		(layer "F.Cu")
		(net "M_E_CPU1_SA_DQ<28>")
	)
	(gr_poly
		(pts
			(xy 144.28343 -256.200656) (xy 144.329658 -256.103374) (xy 144.195038 -255.9685) (xy 144.097502 -256.014728)
			(xy 144.061688 -256.050796) (xy 144.247616 -256.236724)
		)
		(stroke
			(width 0)
			(type solid)
		)
		(fill yes)
		(layer "F.Cu")
		(net "M_E_CPU1_SA_CA<6>")
	)
	(gr_poly
		(pts
			(xy 144.283684 -237.067598) (xy 144.237456 -236.970062) (xy 144.201388 -236.934248) (xy 144.01546 -237.120176)
			(xy 144.051528 -237.15599) (xy 144.14881 -237.202218)
		)
		(stroke
			(width 0)
			(type solid)
		)
		(fill yes)
		(layer "F.Cu")
		(net "M_E_CPU1_SB_DQ<10>")
	)
	(gr_poly
		(pts
			(xy 144.286732 -268.026134) (xy 144.333214 -267.928598) (xy 144.19834 -267.793978) (xy 144.101058 -267.840206)
			(xy 144.06499 -267.87602) (xy 144.250918 -268.061948)
		)
		(stroke
			(width 0)
			(type solid)
		)
		(fill yes)
		(layer "F.Cu")
		(net "M_E_CPU1_SA_DQ<29>")
	)
	(gr_poly
		(pts
			(xy 144.291812 -238.764064) (xy 144.245584 -238.666528) (xy 144.209516 -238.630714) (xy 144.023588 -238.816642)
			(xy 144.059656 -238.852456) (xy 144.156938 -238.898684)
		)
		(stroke
			(width 0)
			(type solid)
		)
		(fill yes)
		(layer "F.Cu")
		(net "M_E_CPU1_SB_CB<1>")
	)
	(gr_poly
		(pts
			(xy 144.300194 -274.527264) (xy 144.346422 -274.429982) (xy 144.211548 -274.295108) (xy 144.114266 -274.341336)
			(xy 144.078198 -274.377404) (xy 144.264126 -274.563332)
		)
		(stroke
			(width 0)
			(type solid)
		)
		(fill yes)
		(layer "F.Cu")
		(net "M_E_CPU1_SA_DQ<20>")
	)
	(gr_poly
		(pts
			(xy 144.300956 -239.61725) (xy 144.254728 -239.519968) (xy 144.218914 -239.4839) (xy 144.032986 -239.669828)
			(xy 144.0688 -239.705896) (xy 144.166336 -239.752124)
		)
		(stroke
			(width 0)
			(type solid)
		)
		(fill yes)
		(layer "F.Cu")
		(net "M_E_CPU1_SB_CB<0>")
	)
	(gr_poly
		(pts
			(xy 144.309338 -273.673824) (xy 144.355566 -273.576288) (xy 144.220946 -273.441668) (xy 144.12341 -273.487896)
			(xy 144.087596 -273.523964) (xy 144.27327 -273.709638)
		)
		(stroke
			(width 0)
			(type solid)
		)
		(fill yes)
		(layer "F.Cu")
		(net "M_E_CPU1_SA_DQ<21>")
	)
	(gr_poly
		(pts
			(xy 144.310608 -262.977376) (xy 144.356836 -262.880094) (xy 144.222216 -262.74522) (xy 144.12468 -262.791448)
			(xy 144.088866 -262.827516) (xy 144.274794 -263.013444)
		)
		(stroke
			(width 0)
			(type solid)
		)
		(fill yes)
		(layer "F.Cu")
		(net "M_E_CPU1_SA_CB<6>")
	)
	(gr_poly
		(pts
			(xy 144.318228 -271.976342) (xy 144.364456 -271.878806) (xy 144.229836 -271.744186) (xy 144.1323 -271.790414)
			(xy 144.096486 -271.826482) (xy 144.28216 -272.012156)
		)
		(stroke
			(width 0)
			(type solid)
		)
		(fill yes)
		(layer "F.Cu")
		(net "M_E_CPU1_SA_DQ<26>")
	)
	(gr_poly
		(pts
			(xy 144.319752 -262.12419) (xy 144.366234 -262.026654) (xy 144.23136 -261.892034) (xy 144.134078 -261.938262)
			(xy 144.09801 -261.974076) (xy 144.283938 -262.160004)
		)
		(stroke
			(width 0)
			(type solid)
		)
		(fill yes)
		(layer "F.Cu")
		(net "M_E_CPU1_SA_CB<7>")
	)
	(gr_poly
		(pts
			(xy 144.327372 -271.122902) (xy 144.3736 -271.025366) (xy 144.23898 -270.890746) (xy 144.141444 -270.936974)
			(xy 144.10563 -270.973042) (xy 144.291304 -271.158716)
		)
		(stroke
			(width 0)
			(type solid)
		)
		(fill yes)
		(layer "F.Cu")
		(net "M_E_CPU1_SA_DQ<27>")
	)
	(gr_poly
		(pts
			(xy 144.332706 -228.194362) (xy 144.296892 -228.158294) (xy 144.199356 -228.112066) (xy 144.064736 -228.24694)
			(xy 144.110964 -228.344222) (xy 144.146778 -228.38029)
		)
		(stroke
			(width 0)
			(type solid)
		)
		(fill yes)
		(layer "F.Cu")
		(net "M_E_CPU1_SB_DQ<20>")
	)
	(gr_poly
		(pts
			(xy 144.351248 -248.967752) (xy 144.31518 -248.866152) (xy 144.12468 -248.866152) (xy 144.088612 -248.967752)
			(xy 144.088612 -249.018552) (xy 144.351248 -249.018552)
		)
		(stroke
			(width 0)
			(type solid)
		)
		(fill yes)
		(layer "F.Cu")
		(net "M_E_CPU1_SB_CA<0>")
	)
	(gr_poly
		(pts
			(xy 144.351248 -248.662952) (xy 144.31518 -248.561352) (xy 144.12468 -248.561352) (xy 144.088612 -248.662952)
			(xy 144.088612 -248.713752) (xy 144.351248 -248.713752)
		)
		(stroke
			(width 0)
			(type solid)
		)
		(fill yes)
		(layer "F.Cu")
		(net "M_E_CPU1_SB_CA<1>")
	)
	(gr_poly
		(pts
			(xy 144.351248 -248.358152) (xy 144.31518 -248.256552) (xy 144.12468 -248.256552) (xy 144.088612 -248.358152)
			(xy 144.088612 -248.408952) (xy 144.351248 -248.408952)
		)
		(stroke
			(width 0)
			(type solid)
		)
		(fill yes)
		(layer "F.Cu")
		(net "M_E_CPU1_SB_CA<2>")
	)
	(gr_poly
		(pts
			(xy 144.351248 -248.053352) (xy 144.31518 -247.951752) (xy 144.12468 -247.951752) (xy 144.088612 -248.053352)
			(xy 144.088612 -248.104152) (xy 144.351248 -248.104152)
		)
		(stroke
			(width 0)
			(type solid)
		)
		(fill yes)
		(layer "F.Cu")
		(net "M_E_CPU1_SB_CA<3>")
	)
	(gr_poly
		(pts
			(xy 144.351248 -247.748552) (xy 144.31518 -247.646952) (xy 144.12468 -247.646952) (xy 144.088612 -247.748552)
			(xy 144.088612 -247.799352) (xy 144.351248 -247.799352)
		)
		(stroke
			(width 0)
			(type solid)
		)
		(fill yes)
		(layer "F.Cu")
		(net "M_E_CPU1_SB_CA<4>")
	)
	(gr_poly
		(pts
			(xy 144.351248 -247.443752) (xy 144.31518 -247.342152) (xy 144.12468 -247.342152) (xy 144.088612 -247.443752)
			(xy 144.088612 -247.494552) (xy 144.351248 -247.494552)
		)
		(stroke
			(width 0)
			(type solid)
		)
		(fill yes)
		(layer "F.Cu")
		(net "M_E_CPU1_SB_CA<5>")
	)
	(gr_poly
		(pts
			(xy 144.35963 -230.755698) (xy 144.323816 -230.719884) (xy 144.22628 -230.673656) (xy 144.09166 -230.808276)
			(xy 144.137888 -230.905558) (xy 144.173702 -230.941626)
		)
		(stroke
			(width 0)
			(type solid)
		)
		(fill yes)
		(layer "F.Cu")
		(net "M_E_CPU1_SB_DQ<17>")
	)
	(gr_poly
		(pts
			(xy 144.36852 -232.452672) (xy 144.332452 -232.416858) (xy 144.23517 -232.37063) (xy 144.100296 -232.50525)
			(xy 144.146524 -232.602786) (xy 144.182592 -232.6386)
		)
		(stroke
			(width 0)
			(type solid)
		)
		(fill yes)
		(layer "F.Cu")
		(net "M_E_CPU1_SB_DQ<15>")
	)
	(gr_poly
		(pts
			(xy 144.368774 -231.609138) (xy 144.33296 -231.57307) (xy 144.235424 -231.526842) (xy 144.100804 -231.661716)
			(xy 144.147032 -231.758998) (xy 144.182846 -231.795066)
		)
		(stroke
			(width 0)
			(type solid)
		)
		(fill yes)
		(layer "F.Cu")
		(net "M_E_CPU1_SB_DQ<16>")
	)
	(gr_poly
		(pts
			(xy 144.377664 -233.306112) (xy 144.341596 -233.270298) (xy 144.244314 -233.22407) (xy 144.109694 -233.35869)
			(xy 144.155922 -233.456226) (xy 144.191736 -233.49204)
		)
		(stroke
			(width 0)
			(type solid)
		)
		(fill yes)
		(layer "F.Cu")
		(net "M_E_CPU1_SB_DQ<14>")
	)
	(gr_poly
		(pts
			(xy 144.380712 -227.325174) (xy 144.380712 -227.134674) (xy 144.279112 -227.098606) (xy 144.228312 -227.098606)
			(xy 144.228312 -227.361496) (xy 144.279112 -227.361496)
		)
		(stroke
			(width 0)
			(type solid)
		)
		(fill yes)
		(layer "F.Cu")
		(net "M_E_CPU1_SB_DQ<22>")
	)
	(gr_poly
		(pts
			(xy 144.380712 -226.728274) (xy 144.380712 -226.537774) (xy 144.279112 -226.501706) (xy 144.228312 -226.501706)
			(xy 144.228312 -226.764596) (xy 144.279112 -226.764596)
		)
		(stroke
			(width 0)
			(type solid)
		)
		(fill yes)
		(layer "F.Cu")
		(net "M_E_CPU1_SB_DQ<22>")
	)
	(gr_poly
		(pts
			(xy 144.380712 -226.131374) (xy 144.380712 -225.940874) (xy 144.279112 -225.904806) (xy 144.228312 -225.904806)
			(xy 144.228312 -226.167696) (xy 144.279112 -226.167696)
		)
		(stroke
			(width 0)
			(type solid)
		)
		(fill yes)
		(layer "F.Cu")
		(net "M_E_CPU1_SB_DQ<22>")
	)
	(gr_poly
		(pts
			(xy 144.380712 -225.534474) (xy 144.380712 -225.343974) (xy 144.279112 -225.307906) (xy 144.228312 -225.307906)
			(xy 144.228312 -225.570796) (xy 144.279112 -225.570796)
		)
		(stroke
			(width 0)
			(type solid)
		)
		(fill yes)
		(layer "F.Cu")
		(net "M_E_CPU1_SB_DQ<22>")
	)
	(gr_poly
		(pts
			(xy 144.380712 -224.937574) (xy 144.380712 -224.747074) (xy 144.279112 -224.711006) (xy 144.228312 -224.711006)
			(xy 144.228312 -224.973896) (xy 144.279112 -224.973896)
		)
		(stroke
			(width 0)
			(type solid)
		)
		(fill yes)
		(layer "F.Cu")
		(net "M_E_CPU1_SB_DQ<22>")
	)
	(gr_poly
		(pts
			(xy 144.380712 -224.340674) (xy 144.380712 -224.150174) (xy 144.279112 -224.114106) (xy 144.228312 -224.114106)
			(xy 144.228312 -224.376996) (xy 144.279112 -224.376996)
		)
		(stroke
			(width 0)
			(type solid)
		)
		(fill yes)
		(layer "F.Cu")
		(net "M_E_CPU1_SB_DQ<22>")
	)
	(gr_poly
		(pts
			(xy 144.380712 -223.743774) (xy 144.380712 -223.553274) (xy 144.279112 -223.517206) (xy 144.228312 -223.517206)
			(xy 144.228312 -223.780096) (xy 144.279112 -223.780096)
		)
		(stroke
			(width 0)
			(type solid)
		)
		(fill yes)
		(layer "F.Cu")
		(net "M_E_CPU1_SB_DQ<22>")
	)
	(gr_poly
		(pts
			(xy 144.380712 -223.146874) (xy 144.380712 -222.956374) (xy 144.279112 -222.920306) (xy 144.228312 -222.920306)
			(xy 144.228312 -223.183196) (xy 144.279112 -223.183196)
		)
		(stroke
			(width 0)
			(type solid)
		)
		(fill yes)
		(layer "F.Cu")
		(net "M_E_CPU1_SB_DQ<22>")
	)
	(gr_poly
		(pts
			(xy 144.380712 -222.549974) (xy 144.380712 -222.359474) (xy 144.279112 -222.323406) (xy 144.228312 -222.323406)
			(xy 144.228312 -222.586296) (xy 144.279112 -222.586296)
		)
		(stroke
			(width 0)
			(type solid)
		)
		(fill yes)
		(layer "F.Cu")
		(net "M_E_CPU1_SB_DQ<22>")
	)
	(gr_poly
		(pts
			(xy 144.380712 -221.953074) (xy 144.380712 -221.762574) (xy 144.279112 -221.726506) (xy 144.228312 -221.726506)
			(xy 144.228312 -221.989396) (xy 144.279112 -221.989396)
		)
		(stroke
			(width 0)
			(type solid)
		)
		(fill yes)
		(layer "F.Cu")
		(net "M_E_CPU1_SB_DQ<22>")
	)
	(gr_poly
		(pts
			(xy 144.380712 -221.356174) (xy 144.380712 -221.165674) (xy 144.279112 -221.129606) (xy 144.228312 -221.129606)
			(xy 144.228312 -221.392496) (xy 144.279112 -221.392496)
		)
		(stroke
			(width 0)
			(type solid)
		)
		(fill yes)
		(layer "F.Cu")
		(net "M_E_CPU1_SB_DQ<22>")
	)
	(gr_poly
		(pts
			(xy 144.380712 -220.759274) (xy 144.380712 -220.568774) (xy 144.279112 -220.532706) (xy 144.228312 -220.532706)
			(xy 144.228312 -220.795596) (xy 144.279112 -220.795596)
		)
		(stroke
			(width 0)
			(type solid)
		)
		(fill yes)
		(layer "F.Cu")
		(net "M_E_CPU1_SB_DQ<22>")
	)
	(gr_poly
		(pts
			(xy 144.380712 -220.162374) (xy 144.380712 -219.971874) (xy 144.279112 -219.935806) (xy 144.228312 -219.935806)
			(xy 144.228312 -220.198696) (xy 144.279112 -220.198696)
		)
		(stroke
			(width 0)
			(type solid)
		)
		(fill yes)
		(layer "F.Cu")
		(net "M_E_CPU1_SB_DQ<22>")
	)
	(gr_poly
		(pts
			(xy 144.380712 -219.565474) (xy 144.380712 -219.374974) (xy 144.279112 -219.338906) (xy 144.228312 -219.338906)
			(xy 144.228312 -219.601796) (xy 144.279112 -219.601796)
		)
		(stroke
			(width 0)
			(type solid)
		)
		(fill yes)
		(layer "F.Cu")
		(net "M_E_CPU1_SB_DQ<22>")
	)
	(gr_poly
		(pts
			(xy 144.380712 -218.968574) (xy 144.380712 -218.778074) (xy 144.279112 -218.742006) (xy 144.228312 -218.742006)
			(xy 144.228312 -219.004896) (xy 144.279112 -219.004896)
		)
		(stroke
			(width 0)
			(type solid)
		)
		(fill yes)
		(layer "F.Cu")
		(net "M_E_CPU1_SB_DQ<22>")
	)
	(gr_poly
		(pts
			(xy 144.380712 -218.371674) (xy 144.380712 -218.181174) (xy 144.279112 -218.145106) (xy 144.228312 -218.145106)
			(xy 144.228312 -218.407996) (xy 144.279112 -218.407996)
		)
		(stroke
			(width 0)
			(type solid)
		)
		(fill yes)
		(layer "F.Cu")
		(net "M_E_CPU1_SB_DQ<22>")
	)
	(gr_poly
		(pts
			(xy 144.380712 -217.774774) (xy 144.380712 -217.584274) (xy 144.279112 -217.548206) (xy 144.228312 -217.548206)
			(xy 144.228312 -217.811096) (xy 144.279112 -217.811096)
		)
		(stroke
			(width 0)
			(type solid)
		)
		(fill yes)
		(layer "F.Cu")
		(net "M_E_CPU1_SB_DQ<22>")
	)
	(gr_poly
		(pts
			(xy 144.380712 -217.177874) (xy 144.380712 -216.987374) (xy 144.279112 -216.951306) (xy 144.228312 -216.951306)
			(xy 144.228312 -217.214196) (xy 144.279112 -217.214196)
		)
		(stroke
			(width 0)
			(type solid)
		)
		(fill yes)
		(layer "F.Cu")
		(net "M_E_CPU1_SB_DQ<22>")
	)
	(gr_poly
		(pts
			(xy 144.380712 -216.580974) (xy 144.380712 -216.390474) (xy 144.279112 -216.354406) (xy 144.228312 -216.354406)
			(xy 144.228312 -216.617296) (xy 144.279112 -216.617296)
		)
		(stroke
			(width 0)
			(type solid)
		)
		(fill yes)
		(layer "F.Cu")
		(net "M_E_CPU1_SB_DQ<22>")
	)
	(gr_poly
		(pts
			(xy 144.39265 -266.654026) (xy 144.428464 -266.618212) (xy 144.242536 -266.432284) (xy 144.206722 -266.468352)
			(xy 144.160494 -266.565634) (xy 144.295114 -266.700508)
		)
		(stroke
			(width 0)
			(type solid)
		)
		(fill yes)
		(layer "F.Cu")
		(net "M_E_CPU1_SA_CB<2>")
	)
	(gr_poly
		(pts
			(xy 144.401794 -265.80084) (xy 144.437608 -265.764772) (xy 144.25168 -265.578844) (xy 144.215866 -265.614912)
			(xy 144.169638 -265.712194) (xy 144.304258 -265.847068)
		)
		(stroke
			(width 0)
			(type solid)
		)
		(fill yes)
		(layer "F.Cu")
		(net "M_E_CPU1_SA_CB<3>")
	)
	(gr_poly
		(pts
			(xy 144.402556 -235.868972) (xy 144.366488 -235.833158) (xy 144.269206 -235.78693) (xy 144.134332 -235.92155)
			(xy 144.18056 -236.019086) (xy 144.216628 -236.0549)
		)
		(stroke
			(width 0)
			(type solid)
		)
		(fill yes)
		(layer "F.Cu")
		(net "M_E_CPU1_SB_DQ<11>")
	)
	(gr_poly
		(pts
			(xy 144.412462 -236.723174) (xy 144.376648 -236.68736) (xy 144.279112 -236.640878) (xy 144.144492 -236.775752)
			(xy 144.19072 -236.873034) (xy 144.226534 -236.909102)
		)
		(stroke
			(width 0)
			(type solid)
		)
		(fill yes)
		(layer "F.Cu")
		(net "M_E_CPU1_SB_DQ<10>")
	)
	(gr_poly
		(pts
			(xy 144.41678 -269.16253) (xy 144.452594 -269.126462) (xy 144.266666 -268.940534) (xy 144.230852 -268.976602)
			(xy 144.184624 -269.073884) (xy 144.319244 -269.208758)
		)
		(stroke
			(width 0)
			(type solid)
		)
		(fill yes)
		(layer "F.Cu")
		(net "M_E_CPU1_SA_DQ<28>")
	)
	(gr_poly
		(pts
			(xy 144.42059 -238.41964) (xy 144.384776 -238.383572) (xy 144.28724 -238.337344) (xy 144.15262 -238.472218)
			(xy 144.198848 -238.5695) (xy 144.234662 -238.605568)
		)
		(stroke
			(width 0)
			(type solid)
		)
		(fill yes)
		(layer "F.Cu")
		(net "M_E_CPU1_SB_CB<1>")
	)
	(gr_poly
		(pts
			(xy 144.426178 -268.308836) (xy 144.461992 -268.273022) (xy 144.276064 -268.087094) (xy 144.24025 -268.122908)
			(xy 144.194022 -268.220444) (xy 144.328642 -268.355064)
		)
		(stroke
			(width 0)
			(type solid)
		)
		(fill yes)
		(layer "F.Cu")
		(net "M_E_CPU1_SA_DQ<29>")
	)
	(gr_poly
		(pts
			(xy 144.429734 -239.27308) (xy 144.39392 -239.237012) (xy 144.296384 -239.190784) (xy 144.161764 -239.325404)
			(xy 144.207992 -239.42294) (xy 144.24406 -239.458754)
		)
		(stroke
			(width 0)
			(type solid)
		)
		(fill yes)
		(layer "F.Cu")
		(net "M_E_CPU1_SB_CB<0>")
	)
	(gr_poly
		(pts
			(xy 144.4371 -230.462328) (xy 144.390872 -230.365046) (xy 144.355058 -230.328978) (xy 144.16913 -230.514906)
			(xy 144.204944 -230.55072) (xy 144.30248 -230.597202)
		)
		(stroke
			(width 0)
			(type solid)
		)
		(fill yes)
		(layer "F.Cu")
		(net "M_E_CPU1_SB_DQ<19>")
	)
	(gr_poly
		(pts
			(xy 144.446498 -231.315768) (xy 144.40027 -231.218232) (xy 144.364202 -231.182418) (xy 144.178274 -231.368346)
			(xy 144.214342 -231.40416) (xy 144.311624 -231.450388)
		)
		(stroke
			(width 0)
			(type solid)
		)
		(fill yes)
		(layer "F.Cu")
		(net "M_E_CPU1_SB_DQ<18>")
	)
	(gr_poly
		(pts
			(xy 144.44853 -273.95678) (xy 144.484344 -273.920712) (xy 144.298416 -273.734784) (xy 144.262602 -273.770852)
			(xy 144.216374 -273.868134) (xy 144.350994 -274.003008)
		)
		(stroke
			(width 0)
			(type solid)
		)
		(fill yes)
		(layer "F.Cu")
		(net "M_E_CPU1_SA_DQ<21>")
	)
	(gr_poly
		(pts
			(xy 144.4498 -263.260332) (xy 144.485868 -263.224518) (xy 144.29994 -263.03859) (xy 144.263872 -263.074404)
			(xy 144.217644 -263.17194) (xy 144.352518 -263.30656)
		)
		(stroke
			(width 0)
			(type solid)
		)
		(fill yes)
		(layer "F.Cu")
		(net "M_E_CPU1_SA_CB<6>")
	)
	(gr_poly
		(pts
			(xy 144.455134 -233.012742) (xy 144.408906 -232.91546) (xy 144.373092 -232.879392) (xy 144.187164 -233.06532)
			(xy 144.222978 -233.101388) (xy 144.320514 -233.147616)
		)
		(stroke
			(width 0)
			(type solid)
		)
		(fill yes)
		(layer "F.Cu")
		(net "M_E_CPU1_SB_DQ<13>")
	)
	(gr_poly
		(pts
			(xy 144.45742 -272.259298) (xy 144.493234 -272.22323) (xy 144.307306 -272.037302) (xy 144.271492 -272.07337)
			(xy 144.225264 -272.170652) (xy 144.359884 -272.305526)
		)
		(stroke
			(width 0)
			(type solid)
		)
		(fill yes)
		(layer "F.Cu")
		(net "M_E_CPU1_SA_DQ<26>")
	)
	(gr_poly
		(pts
			(xy 144.458944 -262.406892) (xy 144.495012 -262.371078) (xy 144.309084 -262.18515) (xy 144.27327 -262.220964)
			(xy 144.227042 -262.3185) (xy 144.361662 -262.45312)
		)
		(stroke
			(width 0)
			(type solid)
		)
		(fill yes)
		(layer "F.Cu")
		(net "M_E_CPU1_SA_CB<7>")
	)
	(gr_poly
		(pts
			(xy 144.459706 -267.008864) (xy 144.505934 -266.911582) (xy 144.371314 -266.776962) (xy 144.273778 -266.82319)
			(xy 144.237964 -266.859004) (xy 144.423892 -267.044932)
		)
		(stroke
			(width 0)
			(type solid)
		)
		(fill yes)
		(layer "F.Cu")
		(net "M_E_CPU1_SA_CB<0>")
	)
	(gr_poly
		(pts
			(xy 144.464532 -233.866182) (xy 144.41805 -233.768646) (xy 144.382236 -233.732832) (xy 144.196308 -233.91876)
			(xy 144.232376 -233.954574) (xy 144.329658 -234.000802)
		)
		(stroke
			(width 0)
			(type solid)
		)
		(fill yes)
		(layer "F.Cu")
		(net "M_E_CPU1_SB_DQ<12>")
	)
	(gr_poly
		(pts
			(xy 144.466564 -271.405858) (xy 144.502378 -271.36979) (xy 144.31645 -271.183862) (xy 144.280636 -271.21993)
			(xy 144.234408 -271.317466) (xy 144.369028 -271.452086)
		)
		(stroke
			(width 0)
			(type solid)
		)
		(fill yes)
		(layer "F.Cu")
		(net "M_E_CPU1_SA_DQ<27>")
	)
	(gr_poly
		(pts
			(xy 144.469104 -266.155678) (xy 144.515332 -266.058142) (xy 144.380458 -265.923522) (xy 144.283176 -265.96975)
			(xy 144.247108 -266.005564) (xy 144.433036 -266.191492)
		)
		(stroke
			(width 0)
			(type solid)
		)
		(fill yes)
		(layer "F.Cu")
		(net "M_E_CPU1_SA_CB<1>")
	)
	(gr_poly
		(pts
			(xy 144.489424 -236.429296) (xy 144.443196 -236.33176) (xy 144.407128 -236.295946) (xy 144.221454 -236.48162)
			(xy 144.257268 -236.517688) (xy 144.354804 -236.563916)
		)
		(stroke
			(width 0)
			(type solid)
		)
		(fill yes)
		(layer "F.Cu")
		(net "M_E_CPU1_SB_DQ<9>")
	)
	(gr_poly
		(pts
			(xy 144.493234 -268.663928) (xy 144.539462 -268.566392) (xy 144.404588 -268.431772) (xy 144.307306 -268.478)
			(xy 144.271238 -268.513814) (xy 144.457166 -268.699742)
		)
		(stroke
			(width 0)
			(type solid)
		)
		(fill yes)
		(layer "F.Cu")
		(net "M_E_CPU1_SA_DQ<30>")
	)
	(gr_poly
		(pts
			(xy 144.498314 -238.12627) (xy 144.451832 -238.028734) (xy 144.416018 -237.99292) (xy 144.23009 -238.178848)
			(xy 144.266158 -238.214662) (xy 144.36344 -238.26089)
		)
		(stroke
			(width 0)
			(type solid)
		)
		(fill yes)
		(layer "F.Cu")
		(net "M_E_CPU1_SB_CB<3>")
	)
	(gr_poly
		(pts
			(xy 144.49933 -237.283244) (xy 144.453102 -237.185962) (xy 144.417288 -237.149894) (xy 144.23136 -237.335822)
			(xy 144.267174 -237.37189) (xy 144.36471 -237.418118)
		)
		(stroke
			(width 0)
			(type solid)
		)
		(fill yes)
		(layer "F.Cu")
		(net "M_E_CPU1_SB_DQ<8>")
	)
	(gr_poly
		(pts
			(xy 144.502632 -267.810234) (xy 144.54886 -267.712952) (xy 144.41424 -267.578078) (xy 144.316704 -267.624306)
			(xy 144.28089 -267.660374) (xy 144.466818 -267.846302)
		)
		(stroke
			(width 0)
			(type solid)
		)
		(fill yes)
		(layer "F.Cu")
		(net "M_E_CPU1_SA_DQ<31>")
	)
	(gr_poly
		(pts
			(xy 144.507458 -238.97971) (xy 144.46123 -238.882174) (xy 144.425162 -238.84636) (xy 144.239234 -239.032288)
			(xy 144.275302 -239.068102) (xy 144.372584 -239.11433)
		)
		(stroke
			(width 0)
			(type solid)
		)
		(fill yes)
		(layer "F.Cu")
		(net "M_E_CPU1_SB_CB<2>")
	)
	(gr_poly
		(pts
			(xy 144.51584 -274.311618) (xy 144.562068 -274.214082) (xy 144.427194 -274.079462) (xy 144.329912 -274.12569)
			(xy 144.293844 -274.161504) (xy 144.479772 -274.347432)
		)
		(stroke
			(width 0)
			(type solid)
		)
		(fill yes)
		(layer "F.Cu")
		(net "M_E_CPU1_SA_DQ<22>")
	)
	(gr_poly
		(pts
			(xy 144.51711 -263.61517) (xy 144.563338 -263.517634) (xy 144.428718 -263.383014) (xy 144.331182 -263.429242)
			(xy 144.295368 -263.46531) (xy 144.481042 -263.650984)
		)
		(stroke
			(width 0)
			(type solid)
		)
		(fill yes)
		(layer "F.Cu")
		(net "M_E_CPU1_SA_CB<4>")
	)
	(gr_poly
		(pts
			(xy 144.52473 -272.614136) (xy 144.570958 -272.5166) (xy 144.436084 -272.38198) (xy 144.338802 -272.428208)
			(xy 144.302734 -272.464022) (xy 144.488662 -272.64995)
		)
		(stroke
			(width 0)
			(type solid)
		)
		(fill yes)
		(layer "F.Cu")
		(net "M_E_CPU1_SA_DQ<24>")
	)
	(gr_poly
		(pts
			(xy 144.524984 -273.457924) (xy 144.571212 -273.360642) (xy 144.436592 -273.225768) (xy 144.339056 -273.271996)
			(xy 144.303242 -273.308064) (xy 144.48917 -273.493992)
		)
		(stroke
			(width 0)
			(type solid)
		)
		(fill yes)
		(layer "F.Cu")
		(net "M_E_CPU1_SA_DQ<23>")
	)
	(gr_poly
		(pts
			(xy 144.526254 -262.76173) (xy 144.572482 -262.664448) (xy 144.437862 -262.529574) (xy 144.340326 -262.575802)
			(xy 144.304512 -262.61187) (xy 144.49044 -262.797798)
		)
		(stroke
			(width 0)
			(type solid)
		)
		(fill yes)
		(layer "F.Cu")
		(net "M_E_CPU1_SA_CB<5>")
	)
	(gr_poly
		(pts
			(xy 144.533112 -227.397056) (xy 144.482312 -227.397056) (xy 144.380712 -227.433378) (xy 144.380712 -227.623878)
			(xy 144.482312 -227.659946) (xy 144.533112 -227.659946)
		)
		(stroke
			(width 0)
			(type solid)
		)
		(fill yes)
		(layer "F.Cu")
		(net "M_E_CPU1_SB_DQ<20>")
	)
	(gr_poly
		(pts
			(xy 144.533112 -226.800156) (xy 144.482312 -226.800156) (xy 144.380712 -226.836478) (xy 144.380712 -227.026978)
			(xy 144.482312 -227.063046) (xy 144.533112 -227.063046)
		)
		(stroke
			(width 0)
			(type solid)
		)
		(fill yes)
		(layer "F.Cu")
		(net "M_E_CPU1_SB_DQ<20>")
	)
	(gr_poly
		(pts
			(xy 144.533112 -226.203256) (xy 144.482312 -226.203256) (xy 144.380712 -226.239578) (xy 144.380712 -226.430078)
			(xy 144.482312 -226.466146) (xy 144.533112 -226.466146)
		)
		(stroke
			(width 0)
			(type solid)
		)
		(fill yes)
		(layer "F.Cu")
		(net "M_E_CPU1_SB_DQ<20>")
	)
	(gr_poly
		(pts
			(xy 144.533112 -225.606356) (xy 144.482312 -225.606356) (xy 144.380712 -225.642678) (xy 144.380712 -225.833178)
			(xy 144.482312 -225.869246) (xy 144.533112 -225.869246)
		)
		(stroke
			(width 0)
			(type solid)
		)
		(fill yes)
		(layer "F.Cu")
		(net "M_E_CPU1_SB_DQ<20>")
	)
	(gr_poly
		(pts
			(xy 144.533112 -225.009456) (xy 144.482312 -225.009456) (xy 144.380712 -225.045778) (xy 144.380712 -225.236278)
			(xy 144.482312 -225.272346) (xy 144.533112 -225.272346)
		)
		(stroke
			(width 0)
			(type solid)
		)
		(fill yes)
		(layer "F.Cu")
		(net "M_E_CPU1_SB_DQ<20>")
	)
	(gr_poly
		(pts
			(xy 144.533112 -224.412556) (xy 144.482312 -224.412556) (xy 144.380712 -224.448878) (xy 144.380712 -224.639378)
			(xy 144.482312 -224.675446) (xy 144.533112 -224.675446)
		)
		(stroke
			(width 0)
			(type solid)
		)
		(fill yes)
		(layer "F.Cu")
		(net "M_E_CPU1_SB_DQ<20>")
	)
	(gr_poly
		(pts
			(xy 144.533112 -223.815656) (xy 144.482312 -223.815656) (xy 144.380712 -223.851978) (xy 144.380712 -224.042478)
			(xy 144.482312 -224.078546) (xy 144.533112 -224.078546)
		)
		(stroke
			(width 0)
			(type solid)
		)
		(fill yes)
		(layer "F.Cu")
		(net "M_E_CPU1_SB_DQ<20>")
	)
	(gr_poly
		(pts
			(xy 144.533112 -223.218756) (xy 144.482312 -223.218756) (xy 144.380712 -223.255078) (xy 144.380712 -223.445578)
			(xy 144.482312 -223.481646) (xy 144.533112 -223.481646)
		)
		(stroke
			(width 0)
			(type solid)
		)
		(fill yes)
		(layer "F.Cu")
		(net "M_E_CPU1_SB_DQ<20>")
	)
	(gr_poly
		(pts
			(xy 144.533112 -222.621856) (xy 144.482312 -222.621856) (xy 144.380712 -222.658178) (xy 144.380712 -222.848678)
			(xy 144.482312 -222.884746) (xy 144.533112 -222.884746)
		)
		(stroke
			(width 0)
			(type solid)
		)
		(fill yes)
		(layer "F.Cu")
		(net "M_E_CPU1_SB_DQ<20>")
	)
	(gr_poly
		(pts
			(xy 144.533112 -222.024956) (xy 144.482312 -222.024956) (xy 144.380712 -222.061278) (xy 144.380712 -222.251778)
			(xy 144.482312 -222.287846) (xy 144.533112 -222.287846)
		)
		(stroke
			(width 0)
			(type solid)
		)
		(fill yes)
		(layer "F.Cu")
		(net "M_E_CPU1_SB_DQ<20>")
	)
	(gr_poly
		(pts
			(xy 144.533112 -221.428056) (xy 144.482312 -221.428056) (xy 144.380712 -221.464378) (xy 144.380712 -221.654878)
			(xy 144.482312 -221.690946) (xy 144.533112 -221.690946)
		)
		(stroke
			(width 0)
			(type solid)
		)
		(fill yes)
		(layer "F.Cu")
		(net "M_E_CPU1_SB_DQ<20>")
	)
	(gr_poly
		(pts
			(xy 144.533112 -220.831156) (xy 144.482312 -220.831156) (xy 144.380712 -220.867478) (xy 144.380712 -221.057978)
			(xy 144.482312 -221.094046) (xy 144.533112 -221.094046)
		)
		(stroke
			(width 0)
			(type solid)
		)
		(fill yes)
		(layer "F.Cu")
		(net "M_E_CPU1_SB_DQ<20>")
	)
	(gr_poly
		(pts
			(xy 144.533112 -220.234256) (xy 144.482312 -220.234256) (xy 144.380712 -220.270578) (xy 144.380712 -220.461078)
			(xy 144.482312 -220.497146) (xy 144.533112 -220.497146)
		)
		(stroke
			(width 0)
			(type solid)
		)
		(fill yes)
		(layer "F.Cu")
		(net "M_E_CPU1_SB_DQ<20>")
	)
	(gr_poly
		(pts
			(xy 144.533112 -219.637356) (xy 144.482312 -219.637356) (xy 144.380712 -219.673678) (xy 144.380712 -219.864178)
			(xy 144.482312 -219.900246) (xy 144.533112 -219.900246)
		)
		(stroke
			(width 0)
			(type solid)
		)
		(fill yes)
		(layer "F.Cu")
		(net "M_E_CPU1_SB_DQ<20>")
	)
	(gr_poly
		(pts
			(xy 144.533112 -219.040456) (xy 144.482312 -219.040456) (xy 144.380712 -219.076778) (xy 144.380712 -219.267278)
			(xy 144.482312 -219.303346) (xy 144.533112 -219.303346)
		)
		(stroke
			(width 0)
			(type solid)
		)
		(fill yes)
		(layer "F.Cu")
		(net "M_E_CPU1_SB_DQ<20>")
	)
	(gr_poly
		(pts
			(xy 144.533112 -218.443556) (xy 144.482312 -218.443556) (xy 144.380712 -218.479878) (xy 144.380712 -218.670378)
			(xy 144.482312 -218.706446) (xy 144.533112 -218.706446)
		)
		(stroke
			(width 0)
			(type solid)
		)
		(fill yes)
		(layer "F.Cu")
		(net "M_E_CPU1_SB_DQ<20>")
	)
	(gr_poly
		(pts
			(xy 144.533112 -217.846656) (xy 144.482312 -217.846656) (xy 144.380712 -217.882978) (xy 144.380712 -218.073478)
			(xy 144.482312 -218.109546) (xy 144.533112 -218.109546)
		)
		(stroke
			(width 0)
			(type solid)
		)
		(fill yes)
		(layer "F.Cu")
		(net "M_E_CPU1_SB_DQ<20>")
	)
	(gr_poly
		(pts
			(xy 144.533112 -217.249756) (xy 144.482312 -217.249756) (xy 144.380712 -217.286078) (xy 144.380712 -217.476578)
			(xy 144.482312 -217.512646) (xy 144.533112 -217.512646)
		)
		(stroke
			(width 0)
			(type solid)
		)
		(fill yes)
		(layer "F.Cu")
		(net "M_E_CPU1_SB_DQ<20>")
	)
	(gr_poly
		(pts
			(xy 144.533112 -216.652856) (xy 144.482312 -216.652856) (xy 144.380712 -216.689178) (xy 144.380712 -216.879678)
			(xy 144.482312 -216.915746) (xy 144.533112 -216.915746)
		)
		(stroke
			(width 0)
			(type solid)
		)
		(fill yes)
		(layer "F.Cu")
		(net "M_E_CPU1_SB_DQ<20>")
	)
	(gr_poly
		(pts
			(xy 144.533874 -271.760696) (xy 144.580102 -271.66316) (xy 144.445228 -271.52854) (xy 144.347946 -271.574768)
			(xy 144.311878 -271.610582) (xy 144.497806 -271.79651)
		)
		(stroke
			(width 0)
			(type solid)
		)
		(fill yes)
		(layer "F.Cu")
		(net "M_E_CPU1_SA_DQ<25>")
	)
	(gr_poly
		(pts
			(xy 144.566132 -230.117904) (xy 144.530064 -230.08209) (xy 144.432782 -230.035862) (xy 144.297908 -230.170482)
			(xy 144.344136 -230.268018) (xy 144.380204 -230.303832)
		)
		(stroke
			(width 0)
			(type solid)
		)
		(fill yes)
		(layer "F.Cu")
		(net "M_E_CPU1_SB_DQ<19>")
	)
	(gr_poly
		(pts
			(xy 144.575276 -230.971344) (xy 144.539462 -230.93553) (xy 144.441926 -230.889302) (xy 144.307306 -231.023922)
			(xy 144.353534 -231.121204) (xy 144.389348 -231.157272)
		)
		(stroke
			(width 0)
			(type solid)
		)
		(fill yes)
		(layer "F.Cu")
		(net "M_E_CPU1_SB_DQ<18>")
	)
	(gr_poly
		(pts
			(xy 144.576546 -241.49939) (xy 144.530064 -241.401854) (xy 144.49425 -241.36604) (xy 144.308322 -241.551968)
			(xy 144.34439 -241.587782) (xy 144.441672 -241.63401)
		)
		(stroke
			(width 0)
			(type solid)
		)
		(fill yes)
		(layer "F.Cu")
		(net "M_E_CPU1_SB_CB<7>")
	)
	(gr_poly
		(pts
			(xy 144.584166 -232.668318) (xy 144.548098 -232.632504) (xy 144.450816 -232.586276) (xy 144.315942 -232.720896)
			(xy 144.36217 -232.818432) (xy 144.398238 -232.854246)
		)
		(stroke
			(width 0)
			(type solid)
		)
		(fill yes)
		(layer "F.Cu")
		(net "M_E_CPU1_SB_DQ<13>")
	)
	(gr_poly
		(pts
			(xy 144.590262 -275.23821) (xy 144.682718 -275.182838) (xy 144.64538 -274.995894) (xy 144.5387 -274.9804)
			(xy 144.488916 -274.990306) (xy 144.540478 -275.248116)
		)
		(stroke
			(width 0)
			(type solid)
		)
		(fill yes)
		(layer "F.Cu")
		(net "M_E_CPU1_SA_DQ<20>")
	)
	(gr_poly
		(pts
			(xy 144.59331 -233.521758) (xy 144.557242 -233.485944) (xy 144.45996 -233.439716) (xy 144.32534 -233.574336)
			(xy 144.371568 -233.671872) (xy 144.407382 -233.707686)
		)
		(stroke
			(width 0)
			(type solid)
		)
		(fill yes)
		(layer "F.Cu")
		(net "M_E_CPU1_SB_DQ<12>")
	)
	(gr_poly
		(pts
			(xy 144.598898 -275.540724) (xy 144.547336 -275.283168) (xy 144.497552 -275.293074) (xy 144.405096 -275.348446)
			(xy 144.442434 -275.535136) (xy 144.549114 -275.550884)
		)
		(stroke
			(width 0)
			(type solid)
		)
		(fill yes)
		(layer "F.Cu")
		(net "M_E_CPU1_SA_DQ<20>")
	)
	(gr_poly
		(pts
			(xy 144.598898 -267.29182) (xy 144.634966 -267.256006) (xy 144.449038 -267.070078) (xy 144.41297 -267.105892)
			(xy 144.366742 -267.203428) (xy 144.501616 -267.338048)
		)
		(stroke
			(width 0)
			(type solid)
		)
		(fill yes)
		(layer "F.Cu")
		(net "M_E_CPU1_SA_CB<0>")
	)
	(gr_poly
		(pts
			(xy 144.608296 -266.43838) (xy 144.64411 -266.402566) (xy 144.458182 -266.216638) (xy 144.422368 -266.252706)
			(xy 144.37614 -266.349988) (xy 144.51076 -266.484862)
		)
		(stroke
			(width 0)
			(type solid)
		)
		(fill yes)
		(layer "F.Cu")
		(net "M_E_CPU1_SA_CB<1>")
	)
	(gr_poly
		(pts
			(xy 144.618202 -236.084872) (xy 144.582388 -236.048804) (xy 144.484852 -236.002576) (xy 144.350232 -236.13745)
			(xy 144.39646 -236.234732) (xy 144.432528 -236.2708)
		)
		(stroke
			(width 0)
			(type solid)
		)
		(fill yes)
		(layer "F.Cu")
		(net "M_E_CPU1_SB_DQ<9>")
	)
	(gr_poly
		(pts
			(xy 144.627092 -237.781846) (xy 144.591024 -237.746032) (xy 144.493742 -237.699804) (xy 144.359122 -237.834424)
			(xy 144.40535 -237.93196) (xy 144.441164 -237.967774)
		)
		(stroke
			(width 0)
			(type solid)
		)
		(fill yes)
		(layer "F.Cu")
		(net "M_E_CPU1_SB_CB<3>")
	)
	(gr_poly
		(pts
			(xy 144.628362 -236.93882) (xy 144.592294 -236.903006) (xy 144.495012 -236.856778) (xy 144.360138 -236.991398)
			(xy 144.406366 -237.088934) (xy 144.442434 -237.124748)
		)
		(stroke
			(width 0)
			(type solid)
		)
		(fill yes)
		(layer "F.Cu")
		(net "M_E_CPU1_SB_DQ<8>")
	)
	(gr_poly
		(pts
			(xy 144.632426 -268.946884) (xy 144.66824 -268.910816) (xy 144.482312 -268.724888) (xy 144.446498 -268.760956)
			(xy 144.40027 -268.858238) (xy 144.53489 -268.993112)
		)
		(stroke
			(width 0)
			(type solid)
		)
		(fill yes)
		(layer "F.Cu")
		(net "M_E_CPU1_SA_DQ<30>")
	)
	(gr_poly
		(pts
			(xy 144.636236 -238.635286) (xy 144.600422 -238.599218) (xy 144.502886 -238.55299) (xy 144.368266 -238.687864)
			(xy 144.414494 -238.785146) (xy 144.450308 -238.821214)
		)
		(stroke
			(width 0)
			(type solid)
		)
		(fill yes)
		(layer "F.Cu")
		(net "M_E_CPU1_SB_CB<2>")
	)
	(gr_poly
		(pts
			(xy 144.641824 -268.09319) (xy 144.677638 -268.057122) (xy 144.491964 -267.871448) (xy 144.455896 -267.907262)
			(xy 144.409668 -268.004798) (xy 144.544288 -268.139418)
		)
		(stroke
			(width 0)
			(type solid)
		)
		(fill yes)
		(layer "F.Cu")
		(net "M_E_CPU1_SA_DQ<31>")
	)
	(gr_poly
		(pts
			(xy 144.649952 -249.069352) (xy 144.649952 -249.018552) (xy 144.386808 -249.018552) (xy 144.386808 -249.069352)
			(xy 144.42313 -249.170952) (xy 144.61363 -249.170952)
		)
		(stroke
			(width 0)
			(type solid)
		)
		(fill yes)
		(layer "F.Cu")
		(net "M_E_CPU1_SB_CA<0>")
	)
	(gr_poly
		(pts
			(xy 144.649952 -248.764552) (xy 144.649952 -248.713752) (xy 144.386808 -248.713752) (xy 144.386808 -248.764552)
			(xy 144.42313 -248.866152) (xy 144.61363 -248.866152)
		)
		(stroke
			(width 0)
			(type solid)
		)
		(fill yes)
		(layer "F.Cu")
		(net "M_E_CPU1_SB_CA<1>")
	)
	(gr_poly
		(pts
			(xy 144.649952 -248.459752) (xy 144.649952 -248.408952) (xy 144.386808 -248.408952) (xy 144.386808 -248.459752)
			(xy 144.42313 -248.561352) (xy 144.61363 -248.561352)
		)
		(stroke
			(width 0)
			(type solid)
		)
		(fill yes)
		(layer "F.Cu")
		(net "M_E_CPU1_SB_CA<2>")
	)
	(gr_poly
		(pts
			(xy 144.649952 -248.154952) (xy 144.649952 -248.104152) (xy 144.386808 -248.104152) (xy 144.386808 -248.154952)
			(xy 144.42313 -248.256552) (xy 144.61363 -248.256552)
		)
		(stroke
			(width 0)
			(type solid)
		)
		(fill yes)
		(layer "F.Cu")
		(net "M_E_CPU1_SB_CA<3>")
	)
	(gr_poly
		(pts
			(xy 144.652746 -230.677974) (xy 144.606518 -230.580692) (xy 144.570704 -230.544624) (xy 144.384776 -230.730552)
			(xy 144.42059 -230.766366) (xy 144.518126 -230.812848)
		)
		(stroke
			(width 0)
			(type solid)
		)
		(fill yes)
		(layer "F.Cu")
		(net "M_E_CPU1_SB_DQ<17>")
	)
	(gr_poly
		(pts
			(xy 144.656302 -263.898126) (xy 144.692116 -263.862058) (xy 144.506188 -263.67613) (xy 144.470374 -263.712198)
			(xy 144.424146 -263.80948) (xy 144.558766 -263.944354)
		)
		(stroke
			(width 0)
			(type solid)
		)
		(fill yes)
		(layer "F.Cu")
		(net "M_E_CPU1_SA_CB<4>")
	)
	(gr_poly
		(pts
			(xy 144.661636 -232.375202) (xy 144.615408 -232.277666) (xy 144.57934 -232.241852) (xy 144.393666 -232.427526)
			(xy 144.42948 -232.463594) (xy 144.527016 -232.509822)
		)
		(stroke
			(width 0)
			(type solid)
		)
		(fill yes)
		(layer "F.Cu")
		(net "M_E_CPU1_SB_DQ<15>")
	)
	(gr_poly
		(pts
			(xy 144.662144 -231.531414) (xy 144.615916 -231.433878) (xy 144.579848 -231.398064) (xy 144.39392 -231.583992)
			(xy 144.429988 -231.619806) (xy 144.52727 -231.666034)
		)
		(stroke
			(width 0)
			(type solid)
		)
		(fill yes)
		(layer "F.Cu")
		(net "M_E_CPU1_SB_DQ<16>")
	)
	(gr_poly
		(pts
			(xy 144.663922 -272.897092) (xy 144.699736 -272.861024) (xy 144.513808 -272.675096) (xy 144.477994 -272.711164)
			(xy 144.431766 -272.808446) (xy 144.566386 -272.94332)
		)
		(stroke
			(width 0)
			(type solid)
		)
		(fill yes)
		(layer "F.Cu")
		(net "M_E_CPU1_SA_DQ<24>")
	)
	(gr_poly
		(pts
			(xy 144.664176 -273.74088) (xy 144.700244 -273.705066) (xy 144.514316 -273.519138) (xy 144.478248 -273.554952)
			(xy 144.43202 -273.652488) (xy 144.566894 -273.787108)
		)
		(stroke
			(width 0)
			(type solid)
		)
		(fill yes)
		(layer "F.Cu")
		(net "M_E_CPU1_SA_DQ<23>")
	)
	(gr_poly
		(pts
			(xy 144.665446 -263.044686) (xy 144.701514 -263.008872) (xy 144.515586 -262.822944) (xy 144.479518 -262.858758)
			(xy 144.43329 -262.956294) (xy 144.568164 -263.090914)
		)
		(stroke
			(width 0)
			(type solid)
		)
		(fill yes)
		(layer "F.Cu")
		(net "M_E_CPU1_SA_CB<5>")
	)
	(gr_poly
		(pts
			(xy 144.67078 -233.228388) (xy 144.624552 -233.131106) (xy 144.588738 -233.095038) (xy 144.40281 -233.280966)
			(xy 144.438624 -233.317034) (xy 144.53616 -233.363262)
		)
		(stroke
			(width 0)
			(type solid)
		)
		(fill yes)
		(layer "F.Cu")
		(net "M_E_CPU1_SB_DQ<14>")
	)
	(gr_poly
		(pts
			(xy 144.673066 -272.043652) (xy 144.70888 -272.007584) (xy 144.522952 -271.821656) (xy 144.487138 -271.857724)
			(xy 144.44091 -271.955006) (xy 144.57553 -272.08988)
		)
		(stroke
			(width 0)
			(type solid)
		)
		(fill yes)
		(layer "F.Cu")
		(net "M_E_CPU1_SA_DQ<25>")
	)
	(gr_poly
		(pts
			(xy 144.675352 -266.793218) (xy 144.72158 -266.695936) (xy 144.58696 -266.561316) (xy 144.489424 -266.607544)
			(xy 144.45361 -266.643358) (xy 144.639538 -266.829286)
		)
		(stroke
			(width 0)
			(type solid)
		)
		(fill yes)
		(layer "F.Cu")
		(net "M_E_CPU1_SA_CB<2>")
	)
	(gr_poly
		(pts
			(xy 144.68475 -265.940032) (xy 144.730978 -265.842496) (xy 144.596104 -265.707876) (xy 144.498822 -265.754104)
			(xy 144.462754 -265.789918) (xy 144.648682 -265.975846)
		)
		(stroke
			(width 0)
			(type solid)
		)
		(fill yes)
		(layer "F.Cu")
		(net "M_E_CPU1_SA_CB<3>")
	)
	(gr_poly
		(pts
			(xy 144.685512 -227.325174) (xy 144.685512 -227.134674) (xy 144.583912 -227.098606) (xy 144.533112 -227.098606)
			(xy 144.533112 -227.361496) (xy 144.583912 -227.361496)
		)
		(stroke
			(width 0)
			(type solid)
		)
		(fill yes)
		(layer "F.Cu")
		(net "M_E_CPU1_SB_DQ<20>")
	)
	(gr_poly
		(pts
			(xy 144.685512 -226.728274) (xy 144.685512 -226.537774) (xy 144.583912 -226.501706) (xy 144.533112 -226.501706)
			(xy 144.533112 -226.764596) (xy 144.583912 -226.764596)
		)
		(stroke
			(width 0)
			(type solid)
		)
		(fill yes)
		(layer "F.Cu")
		(net "M_E_CPU1_SB_DQ<20>")
	)
	(gr_poly
		(pts
			(xy 144.685512 -226.131374) (xy 144.685512 -225.940874) (xy 144.583912 -225.904806) (xy 144.533112 -225.904806)
			(xy 144.533112 -226.167696) (xy 144.583912 -226.167696)
		)
		(stroke
			(width 0)
			(type solid)
		)
		(fill yes)
		(layer "F.Cu")
		(net "M_E_CPU1_SB_DQ<20>")
	)
	(gr_poly
		(pts
			(xy 144.685512 -225.534474) (xy 144.685512 -225.343974) (xy 144.583912 -225.307906) (xy 144.533112 -225.307906)
			(xy 144.533112 -225.570796) (xy 144.583912 -225.570796)
		)
		(stroke
			(width 0)
			(type solid)
		)
		(fill yes)
		(layer "F.Cu")
		(net "M_E_CPU1_SB_DQ<20>")
	)
	(gr_poly
		(pts
			(xy 144.685512 -224.937574) (xy 144.685512 -224.747074) (xy 144.583912 -224.711006) (xy 144.533112 -224.711006)
			(xy 144.533112 -224.973896) (xy 144.583912 -224.973896)
		)
		(stroke
			(width 0)
			(type solid)
		)
		(fill yes)
		(layer "F.Cu")
		(net "M_E_CPU1_SB_DQ<20>")
	)
	(gr_poly
		(pts
			(xy 144.685512 -224.340674) (xy 144.685512 -224.150174) (xy 144.583912 -224.114106) (xy 144.533112 -224.114106)
			(xy 144.533112 -224.376996) (xy 144.583912 -224.376996)
		)
		(stroke
			(width 0)
			(type solid)
		)
		(fill yes)
		(layer "F.Cu")
		(net "M_E_CPU1_SB_DQ<20>")
	)
	(gr_poly
		(pts
			(xy 144.685512 -223.743774) (xy 144.685512 -223.553274) (xy 144.583912 -223.517206) (xy 144.533112 -223.517206)
			(xy 144.533112 -223.780096) (xy 144.583912 -223.780096)
		)
		(stroke
			(width 0)
			(type solid)
		)
		(fill yes)
		(layer "F.Cu")
		(net "M_E_CPU1_SB_DQ<20>")
	)
	(gr_poly
		(pts
			(xy 144.685512 -223.146874) (xy 144.685512 -222.956374) (xy 144.583912 -222.920306) (xy 144.533112 -222.920306)
			(xy 144.533112 -223.183196) (xy 144.583912 -223.183196)
		)
		(stroke
			(width 0)
			(type solid)
		)
		(fill yes)
		(layer "F.Cu")
		(net "M_E_CPU1_SB_DQ<20>")
	)
	(gr_poly
		(pts
			(xy 144.685512 -222.549974) (xy 144.685512 -222.359474) (xy 144.583912 -222.323406) (xy 144.533112 -222.323406)
			(xy 144.533112 -222.586296) (xy 144.583912 -222.586296)
		)
		(stroke
			(width 0)
			(type solid)
		)
		(fill yes)
		(layer "F.Cu")
		(net "M_E_CPU1_SB_DQ<20>")
	)
	(gr_poly
		(pts
			(xy 144.685512 -221.953074) (xy 144.685512 -221.762574) (xy 144.583912 -221.726506) (xy 144.533112 -221.726506)
			(xy 144.533112 -221.989396) (xy 144.583912 -221.989396)
		)
		(stroke
			(width 0)
			(type solid)
		)
		(fill yes)
		(layer "F.Cu")
		(net "M_E_CPU1_SB_DQ<20>")
	)
	(gr_poly
		(pts
			(xy 144.685512 -221.356174) (xy 144.685512 -221.165674) (xy 144.583912 -221.129606) (xy 144.533112 -221.129606)
			(xy 144.533112 -221.392496) (xy 144.583912 -221.392496)
		)
		(stroke
			(width 0)
			(type solid)
		)
		(fill yes)
		(layer "F.Cu")
		(net "M_E_CPU1_SB_DQ<20>")
	)
	(gr_poly
		(pts
			(xy 144.685512 -220.759274) (xy 144.685512 -220.568774) (xy 144.583912 -220.532706) (xy 144.533112 -220.532706)
			(xy 144.533112 -220.795596) (xy 144.583912 -220.795596)
		)
		(stroke
			(width 0)
			(type solid)
		)
		(fill yes)
		(layer "F.Cu")
		(net "M_E_CPU1_SB_DQ<20>")
	)
	(gr_poly
		(pts
			(xy 144.685512 -220.162374) (xy 144.685512 -219.971874) (xy 144.583912 -219.935806) (xy 144.533112 -219.935806)
			(xy 144.533112 -220.198696) (xy 144.583912 -220.198696)
		)
		(stroke
			(width 0)
			(type solid)
		)
		(fill yes)
		(layer "F.Cu")
		(net "M_E_CPU1_SB_DQ<20>")
	)
	(gr_poly
		(pts
			(xy 144.685512 -219.565474) (xy 144.685512 -219.374974) (xy 144.583912 -219.338906) (xy 144.533112 -219.338906)
			(xy 144.533112 -219.601796) (xy 144.583912 -219.601796)
		)
		(stroke
			(width 0)
			(type solid)
		)
		(fill yes)
		(layer "F.Cu")
		(net "M_E_CPU1_SB_DQ<20>")
	)
	(gr_poly
		(pts
			(xy 144.685512 -218.968574) (xy 144.685512 -218.778074) (xy 144.583912 -218.742006) (xy 144.533112 -218.742006)
			(xy 144.533112 -219.004896) (xy 144.583912 -219.004896)
		)
		(stroke
			(width 0)
			(type solid)
		)
		(fill yes)
		(layer "F.Cu")
		(net "M_E_CPU1_SB_DQ<20>")
	)
	(gr_poly
		(pts
			(xy 144.685512 -218.371674) (xy 144.685512 -218.181174) (xy 144.583912 -218.145106) (xy 144.533112 -218.145106)
			(xy 144.533112 -218.407996) (xy 144.583912 -218.407996)
		)
		(stroke
			(width 0)
			(type solid)
		)
		(fill yes)
		(layer "F.Cu")
		(net "M_E_CPU1_SB_DQ<20>")
	)
	(gr_poly
		(pts
			(xy 144.685512 -217.774774) (xy 144.685512 -217.584274) (xy 144.583912 -217.548206) (xy 144.533112 -217.548206)
			(xy 144.533112 -217.811096) (xy 144.583912 -217.811096)
		)
		(stroke
			(width 0)
			(type solid)
		)
		(fill yes)
		(layer "F.Cu")
		(net "M_E_CPU1_SB_DQ<20>")
	)
	(gr_poly
		(pts
			(xy 144.685512 -217.177874) (xy 144.685512 -216.987374) (xy 144.583912 -216.951306) (xy 144.533112 -216.951306)
			(xy 144.533112 -217.214196) (xy 144.583912 -217.214196)
		)
		(stroke
			(width 0)
			(type solid)
		)
		(fill yes)
		(layer "F.Cu")
		(net "M_E_CPU1_SB_DQ<20>")
	)
	(gr_poly
		(pts
			(xy 144.685512 -216.580974) (xy 144.685512 -216.390474) (xy 144.583912 -216.354406) (xy 144.533112 -216.354406)
			(xy 144.533112 -216.617296) (xy 144.583912 -216.617296)
		)
		(stroke
			(width 0)
			(type solid)
		)
		(fill yes)
		(layer "F.Cu")
		(net "M_E_CPU1_SB_DQ<20>")
	)
	(gr_poly
		(pts
			(xy 144.695672 -235.791248) (xy 144.649444 -235.693966) (xy 144.61363 -235.657898) (xy 144.427702 -235.843826)
			(xy 144.463516 -235.879894) (xy 144.561052 -235.926122)
		)
		(stroke
			(width 0)
			(type solid)
		)
		(fill yes)
		(layer "F.Cu")
		(net "M_E_CPU1_SB_DQ<11>")
	)
	(gr_poly
		(pts
			(xy 144.699482 -269.301722) (xy 144.74571 -269.204186) (xy 144.61109 -269.069566) (xy 144.513808 -269.115794)
			(xy 144.47774 -269.151608) (xy 144.663668 -269.337536)
		)
		(stroke
			(width 0)
			(type solid)
		)
		(fill yes)
		(layer "F.Cu")
		(net "M_E_CPU1_SA_DQ<28>")
	)
	(gr_poly
		(pts
			(xy 144.705324 -241.154966) (xy 144.66951 -241.119152) (xy 144.571974 -241.072924) (xy 144.437354 -241.207544)
			(xy 144.483582 -241.30508) (xy 144.519396 -241.340894)
		)
		(stroke
			(width 0)
			(type solid)
		)
		(fill yes)
		(layer "F.Cu")
		(net "M_E_CPU1_SB_CB<7>")
	)
	(gr_poly
		(pts
			(xy 144.705578 -236.64545) (xy 144.65935 -236.547914) (xy 144.623536 -236.5121) (xy 144.437608 -236.698028)
			(xy 144.473422 -236.733842) (xy 144.570958 -236.78007)
		)
		(stroke
			(width 0)
			(type solid)
		)
		(fill yes)
		(layer "F.Cu")
		(net "M_E_CPU1_SB_DQ<10>")
	)
	(gr_poly
		(pts
			(xy 144.707356 -275.823426) (xy 144.799812 -275.768054) (xy 144.762474 -275.581364) (xy 144.655794 -275.56587)
			(xy 144.60601 -275.575776) (xy 144.657318 -275.833586)
		)
		(stroke
			(width 0)
			(type solid)
		)
		(fill yes)
		(layer "F.Cu")
		(net "M_E_CPU1_SA_DQ<20>")
	)
	(gr_poly
		(pts
			(xy 144.70888 -268.448028) (xy 144.755108 -268.350746) (xy 144.620488 -268.215872) (xy 144.522952 -268.262354)
			(xy 144.487138 -268.298168) (xy 144.673066 -268.484096)
		)
		(stroke
			(width 0)
			(type solid)
		)
		(fill yes)
		(layer "F.Cu")
		(net "M_E_CPU1_SA_DQ<29>")
	)
	(gr_poly
		(pts
			(xy 144.71396 -238.341916) (xy 144.667478 -238.24438) (xy 144.631664 -238.208566) (xy 144.445736 -238.394494)
			(xy 144.481804 -238.430308) (xy 144.579086 -238.476536)
		)
		(stroke
			(width 0)
			(type solid)
		)
		(fill yes)
		(layer "F.Cu")
		(net "M_E_CPU1_SB_CB<1>")
	)
	(gr_poly
		(pts
			(xy 144.714468 -242.008406) (xy 144.678654 -241.972338) (xy 144.581118 -241.92611) (xy 144.446498 -242.060984)
			(xy 144.492726 -242.158266) (xy 144.52854 -242.194334)
		)
		(stroke
			(width 0)
			(type solid)
		)
		(fill yes)
		(layer "F.Cu")
		(net "M_E_CPU1_SB_CB<6>")
	)
	(gr_poly
		(pts
			(xy 144.715992 -276.126194) (xy 144.66443 -275.868384) (xy 144.614646 -275.87829) (xy 144.521936 -275.933662)
			(xy 144.559274 -276.120606) (xy 144.666208 -276.1361)
		)
		(stroke
			(width 0)
			(type solid)
		)
		(fill yes)
		(layer "F.Cu")
		(net "M_E_CPU1_SA_DQ<20>")
	)
	(gr_poly
		(pts
			(xy 144.723104 -239.195356) (xy 144.676876 -239.09782) (xy 144.640808 -239.062006) (xy 144.45488 -239.247934)
			(xy 144.490948 -239.283748) (xy 144.58823 -239.329976)
		)
		(stroke
			(width 0)
			(type solid)
		)
		(fill yes)
		(layer "F.Cu")
		(net "M_E_CPU1_SB_CB<0>")
	)
	(gr_poly
		(pts
			(xy 144.731486 -274.095972) (xy 144.777714 -273.998436) (xy 144.64284 -273.863816) (xy 144.545558 -273.910044)
			(xy 144.50949 -273.945858) (xy 144.695418 -274.131786)
		)
		(stroke
			(width 0)
			(type solid)
		)
		(fill yes)
		(layer "F.Cu")
		(net "M_E_CPU1_SA_DQ<21>")
	)
	(gr_poly
		(pts
			(xy 144.732756 -263.399524) (xy 144.778984 -263.301988) (xy 144.644364 -263.167368) (xy 144.546828 -263.213596)
			(xy 144.511014 -263.249664) (xy 144.696688 -263.435338)
		)
		(stroke
			(width 0)
			(type solid)
		)
		(fill yes)
		(layer "F.Cu")
		(net "M_E_CPU1_SA_CB<6>")
	)
	(gr_poly
		(pts
			(xy 144.740376 -272.39849) (xy 144.786604 -272.300954) (xy 144.65173 -272.166334) (xy 144.554448 -272.212562)
			(xy 144.51838 -272.248376) (xy 144.704308 -272.434304)
		)
		(stroke
			(width 0)
			(type solid)
		)
		(fill yes)
		(layer "F.Cu")
		(net "M_E_CPU1_SA_DQ<26>")
	)
	(gr_poly
		(pts
			(xy 144.7419 -262.546084) (xy 144.788128 -262.448802) (xy 144.653508 -262.313928) (xy 144.555972 -262.360156)
			(xy 144.520158 -262.396224) (xy 144.706086 -262.582152)
		)
		(stroke
			(width 0)
			(type solid)
		)
		(fill yes)
		(layer "F.Cu")
		(net "M_E_CPU1_SA_CB<7>")
	)
	(gr_poly
		(pts
			(xy 144.74952 -271.54505) (xy 144.795748 -271.447514) (xy 144.660874 -271.312894) (xy 144.563592 -271.359122)
			(xy 144.527524 -271.394936) (xy 144.713452 -271.580864)
		)
		(stroke
			(width 0)
			(type solid)
		)
		(fill yes)
		(layer "F.Cu")
		(net "M_E_CPU1_SA_DQ<27>")
	)
	(gr_poly
		(pts
			(xy 144.781778 -230.33355) (xy 144.74571 -230.297736) (xy 144.648428 -230.251508) (xy 144.513554 -230.386128)
			(xy 144.559782 -230.483664) (xy 144.59585 -230.519478)
		)
		(stroke
			(width 0)
			(type solid)
		)
		(fill yes)
		(layer "F.Cu")
		(net "M_E_CPU1_SB_DQ<17>")
	)
	(gr_poly
		(pts
			(xy 144.790414 -232.030778) (xy 144.7546 -231.99471) (xy 144.657064 -231.948482) (xy 144.522444 -232.083356)
			(xy 144.568672 -232.180638) (xy 144.604486 -232.216706)
		)
		(stroke
			(width 0)
			(type solid)
		)
		(fill yes)
		(layer "F.Cu")
		(net "M_E_CPU1_SB_DQ<15>")
	)
	(gr_poly
		(pts
			(xy 144.790922 -231.18699) (xy 144.755108 -231.151176) (xy 144.657572 -231.104948) (xy 144.522952 -231.239568)
			(xy 144.56918 -231.33685) (xy 144.604994 -231.372918)
		)
		(stroke
			(width 0)
			(type solid)
		)
		(fill yes)
		(layer "F.Cu")
		(net "M_E_CPU1_SB_DQ<16>")
	)
	(gr_poly
		(pts
			(xy 144.792192 -241.715036) (xy 144.74571 -241.6175) (xy 144.709896 -241.581686) (xy 144.523968 -241.767614)
			(xy 144.560036 -241.803428) (xy 144.657318 -241.849656)
		)
		(stroke
			(width 0)
			(type solid)
		)
		(fill yes)
		(layer "F.Cu")
		(net "M_E_CPU1_SB_CB<5>")
	)
	(gr_poly
		(pts
			(xy 144.799812 -232.883964) (xy 144.763744 -232.84815) (xy 144.666462 -232.801922) (xy 144.531588 -232.936542)
			(xy 144.577816 -233.034078) (xy 144.613884 -233.069892)
		)
		(stroke
			(width 0)
			(type solid)
		)
		(fill yes)
		(layer "F.Cu")
		(net "M_E_CPU1_SB_DQ<14>")
	)
	(gr_poly
		(pts
			(xy 144.814544 -267.076174) (xy 144.850612 -267.04036) (xy 144.664684 -266.854432) (xy 144.628616 -266.890246)
			(xy 144.582388 -266.987782) (xy 144.717262 -267.122402)
		)
		(stroke
			(width 0)
			(type solid)
		)
		(fill yes)
		(layer "F.Cu")
		(net "M_E_CPU1_SA_CB<2>")
	)
	(gr_poly
		(pts
			(xy 144.823942 -266.222734) (xy 144.859756 -266.18692) (xy 144.673828 -266.000992) (xy 144.638014 -266.03706)
			(xy 144.591786 -266.134342) (xy 144.726406 -266.269216)
		)
		(stroke
			(width 0)
			(type solid)
		)
		(fill yes)
		(layer "F.Cu")
		(net "M_E_CPU1_SA_CB<3>")
	)
	(gr_poly
		(pts
			(xy 144.824196 -276.408896) (xy 144.916652 -276.353524) (xy 144.879314 -276.16658) (xy 144.772634 -276.151086)
			(xy 144.72285 -276.160992) (xy 144.774412 -276.418802)
		)
		(stroke
			(width 0)
			(type solid)
		)
		(fill yes)
		(layer "F.Cu")
		(net "M_E_CPU1_SA_DQ<20>")
	)
	(gr_poly
		(pts
			(xy 144.824704 -235.447078) (xy 144.788636 -235.41101) (xy 144.691354 -235.364782) (xy 144.55648 -235.499402)
			(xy 144.602708 -235.596938) (xy 144.638776 -235.632752)
		)
		(stroke
			(width 0)
			(type solid)
		)
		(fill yes)
		(layer "F.Cu")
		(net "M_E_CPU1_SB_DQ<11>")
	)
	(gr_poly
		(pts
			(xy 144.832832 -276.71141) (xy 144.78127 -276.4536) (xy 144.731486 -276.46376) (xy 144.63903 -276.519132)
			(xy 144.676368 -276.705822) (xy 144.783048 -276.72157)
		)
		(stroke
			(width 0)
			(type solid)
		)
		(fill yes)
		(layer "F.Cu")
		(net "M_E_CPU1_SA_DQ<20>")
	)
	(gr_poly
		(pts
			(xy 144.83461 -236.301026) (xy 144.798542 -236.265212) (xy 144.70126 -236.218984) (xy 144.566386 -236.353604)
			(xy 144.612614 -236.45114) (xy 144.648682 -236.486954)
		)
		(stroke
			(width 0)
			(type solid)
		)
		(fill yes)
		(layer "F.Cu")
		(net "M_E_CPU1_SB_DQ<10>")
	)
	(gr_poly
		(pts
			(xy 144.838674 -269.584424) (xy 144.874742 -269.54861) (xy 144.688814 -269.362682) (xy 144.653 -269.398496)
			(xy 144.606518 -269.496032) (xy 144.741392 -269.630652)
		)
		(stroke
			(width 0)
			(type solid)
		)
		(fill yes)
		(layer "F.Cu")
		(net "M_E_CPU1_SA_DQ<28>")
	)
	(gr_poly
		(pts
			(xy 144.842738 -237.997492) (xy 144.80667 -237.961678) (xy 144.709388 -237.91545) (xy 144.574768 -238.05007)
			(xy 144.620996 -238.147606) (xy 144.65681 -238.18342)
		)
		(stroke
			(width 0)
			(type solid)
		)
		(fill yes)
		(layer "F.Cu")
		(net "M_E_CPU1_SB_CB<1>")
	)
	(gr_poly
		(pts
			(xy 144.848072 -268.730984) (xy 144.88414 -268.69517) (xy 144.698212 -268.509242) (xy 144.662144 -268.545056)
			(xy 144.615916 -268.642592) (xy 144.75079 -268.777212)
		)
		(stroke
			(width 0)
			(type solid)
		)
		(fill yes)
		(layer "F.Cu")
		(net "M_E_CPU1_SA_DQ<29>")
	)
	(gr_poly
		(pts
			(xy 144.851882 -238.850932) (xy 144.816068 -238.814864) (xy 144.718532 -238.768636) (xy 144.583912 -238.90351)
			(xy 144.63014 -239.000792) (xy 144.665954 -239.03686)
		)
		(stroke
			(width 0)
			(type solid)
		)
		(fill yes)
		(layer "F.Cu")
		(net "M_E_CPU1_SB_CB<0>")
	)
	(gr_poly
		(pts
			(xy 144.859248 -230.04018) (xy 144.81302 -229.942898) (xy 144.777206 -229.90683) (xy 144.591278 -230.092758)
			(xy 144.627092 -230.128826) (xy 144.724628 -230.175054)
		)
		(stroke
			(width 0)
			(type solid)
		)
		(fill yes)
		(layer "F.Cu")
		(net "M_E_CPU1_SB_DQ<19>")
	)
	(gr_poly
		(pts
			(xy 144.868392 -230.89362) (xy 144.822164 -230.796338) (xy 144.78635 -230.76027) (xy 144.600422 -230.946198)
			(xy 144.636236 -230.982012) (xy 144.733772 -231.028494)
		)
		(stroke
			(width 0)
			(type solid)
		)
		(fill yes)
		(layer "F.Cu")
		(net "M_E_CPU1_SB_DQ<18>")
	)
	(gr_poly
		(pts
			(xy 144.871948 -263.68248) (xy 144.907762 -263.646412) (xy 144.721834 -263.460484) (xy 144.68602 -263.496552)
			(xy 144.639792 -263.593834) (xy 144.774412 -263.728708)
		)
		(stroke
			(width 0)
			(type solid)
		)
		(fill yes)
		(layer "F.Cu")
		(net "M_E_CPU1_SA_CB<6>")
	)
	(gr_poly
		(pts
			(xy 144.877282 -232.590848) (xy 144.831054 -232.493312) (xy 144.794986 -232.457498) (xy 144.609312 -232.643172)
			(xy 144.645126 -232.67924) (xy 144.742662 -232.725468)
		)
		(stroke
			(width 0)
			(type solid)
		)
		(fill yes)
		(layer "F.Cu")
		(net "M_E_CPU1_SB_DQ<13>")
	)
	(gr_poly
		(pts
			(xy 144.879568 -272.681192) (xy 144.915382 -272.645378) (xy 144.729454 -272.45945) (xy 144.69364 -272.495518)
			(xy 144.647412 -272.5928) (xy 144.782032 -272.727674)
		)
		(stroke
			(width 0)
			(type solid)
		)
		(fill yes)
		(layer "F.Cu")
		(net "M_E_CPU1_SA_DQ<26>")
	)
	(gr_poly
		(pts
			(xy 144.881092 -262.82904) (xy 144.91716 -262.793226) (xy 144.731232 -262.607298) (xy 144.695164 -262.643112)
			(xy 144.648936 -262.740648) (xy 144.78381 -262.875268)
		)
		(stroke
			(width 0)
			(type solid)
		)
		(fill yes)
		(layer "F.Cu")
		(net "M_E_CPU1_SA_CB<7>")
	)
	(gr_poly
		(pts
			(xy 144.881854 -267.431012) (xy 144.928082 -267.33373) (xy 144.793462 -267.198856) (xy 144.695926 -267.245084)
			(xy 144.660112 -267.281152) (xy 144.84604 -267.46708)
		)
		(stroke
			(width 0)
			(type solid)
		)
		(fill yes)
		(layer "F.Cu")
		(net "M_E_CPU1_SA_CB<0>")
	)
	(gr_poly
		(pts
			(xy 144.886426 -233.444034) (xy 144.840198 -233.346752) (xy 144.804384 -233.310684) (xy 144.618456 -233.496612)
			(xy 144.65427 -233.53268) (xy 144.751806 -233.578908)
		)
		(stroke
			(width 0)
			(type solid)
		)
		(fill yes)
		(layer "F.Cu")
		(net "M_E_CPU1_SB_DQ<12>")
	)
	(gr_poly
		(pts
			(xy 144.888712 -271.827752) (xy 144.924526 -271.791938) (xy 144.738598 -271.60601) (xy 144.702784 -271.642078)
			(xy 144.656556 -271.73936) (xy 144.791176 -271.874234)
		)
		(stroke
			(width 0)
			(type solid)
		)
		(fill yes)
		(layer "F.Cu")
		(net "M_E_CPU1_SA_DQ<27>")
	)
	(gr_poly
		(pts
			(xy 144.889474 -275.178266) (xy 144.98193 -275.122894) (xy 144.944592 -274.936204) (xy 144.837912 -274.92071)
			(xy 144.788128 -274.930616) (xy 144.83969 -275.188426)
		)
		(stroke
			(width 0)
			(type solid)
		)
		(fill yes)
		(layer "F.Cu")
		(net "M_E_CPU1_SA_DQ<22>")
	)
	(gr_poly
		(pts
			(xy 144.890998 -266.577572) (xy 144.937226 -266.48029) (xy 144.802606 -266.34567) (xy 144.70507 -266.391898)
			(xy 144.669256 -266.427712) (xy 144.855184 -266.61364)
		)
		(stroke
			(width 0)
			(type solid)
		)
		(fill yes)
		(layer "F.Cu")
		(net "M_E_CPU1_SA_CB<1>")
	)
	(gr_poly
		(pts
			(xy 144.89811 -275.481034) (xy 144.846548 -275.223224) (xy 144.796764 -275.23313) (xy 144.704308 -275.288502)
			(xy 144.741646 -275.475446) (xy 144.848326 -275.49094)
		)
		(stroke
			(width 0)
			(type solid)
		)
		(fill yes)
		(layer "F.Cu")
		(net "M_E_CPU1_SA_DQ<22>")
	)
	(gr_poly
		(pts
			(xy 144.911572 -236.007148) (xy 144.865344 -235.909612) (xy 144.829276 -235.873798) (xy 144.643348 -236.059726)
			(xy 144.679416 -236.09554) (xy 144.776698 -236.141768)
		)
		(stroke
			(width 0)
			(type solid)
		)
		(fill yes)
		(layer "F.Cu")
		(net "M_E_CPU1_SB_DQ<9>")
	)
	(gr_poly
		(pts
			(xy 144.915128 -269.086076) (xy 144.961356 -268.98854) (xy 144.826736 -268.85392) (xy 144.729454 -268.900148)
			(xy 144.693386 -268.935962) (xy 144.879314 -269.12189)
		)
		(stroke
			(width 0)
			(type solid)
		)
		(fill yes)
		(layer "F.Cu")
		(net "M_E_CPU1_SA_DQ<30>")
	)
	(gr_poly
		(pts
			(xy 144.920208 -237.704122) (xy 144.87398 -237.60684) (xy 144.838166 -237.570772) (xy 144.652238 -237.7567)
			(xy 144.688052 -237.792768) (xy 144.785588 -237.838996)
		)
		(stroke
			(width 0)
			(type solid)
		)
		(fill yes)
		(layer "F.Cu")
		(net "M_E_CPU1_SB_CB<3>")
	)
	(gr_poly
		(pts
			(xy 144.92097 -241.370612) (xy 144.885156 -241.334798) (xy 144.78762 -241.28857) (xy 144.653 -241.42319)
			(xy 144.699228 -241.520726) (xy 144.735042 -241.55654)
		)
		(stroke
			(width 0)
			(type solid)
		)
		(fill yes)
		(layer "F.Cu")
		(net "M_E_CPU1_SB_CB<5>")
	)
	(gr_poly
		(pts
			(xy 144.921478 -236.86135) (xy 144.87525 -236.763814) (xy 144.839182 -236.728) (xy 144.653508 -236.913674)
			(xy 144.689322 -236.949742) (xy 144.786858 -236.99597)
		)
		(stroke
			(width 0)
			(type solid)
		)
		(fill yes)
		(layer "F.Cu")
		(net "M_E_CPU1_SB_DQ<8>")
	)
	(gr_poly
		(pts
			(xy 144.92478 -268.232382) (xy 144.971008 -268.134846) (xy 144.836134 -268.000226) (xy 144.738852 -268.046454)
			(xy 144.702784 -268.082268) (xy 144.888712 -268.268196)
		)
		(stroke
			(width 0)
			(type solid)
		)
		(fill yes)
		(layer "F.Cu")
		(net "M_E_CPU1_SA_DQ<31>")
	)
	(gr_poly
		(pts
			(xy 144.929606 -238.557562) (xy 144.883124 -238.460026) (xy 144.84731 -238.424212) (xy 144.661382 -238.61014)
			(xy 144.69745 -238.645954) (xy 144.794732 -238.692182)
		)
		(stroke
			(width 0)
			(type solid)
		)
		(fill yes)
		(layer "F.Cu")
		(net "M_E_CPU1_SB_CB<2>")
	)
	(gr_poly
		(pts
			(xy 144.930114 -242.224052) (xy 144.8943 -242.187984) (xy 144.796764 -242.141756) (xy 144.662144 -242.27663)
			(xy 144.708372 -242.373912) (xy 144.744186 -242.40998)
		)
		(stroke
			(width 0)
			(type solid)
		)
		(fill yes)
		(layer "F.Cu")
		(net "M_E_CPU1_SB_CB<4>")
	)
	(gr_poly
		(pts
			(xy 144.939258 -264.037318) (xy 144.985486 -263.939782) (xy 144.850612 -263.805162) (xy 144.75333 -263.85139)
			(xy 144.717262 -263.887204) (xy 144.90319 -264.073132)
		)
		(stroke
			(width 0)
			(type solid)
		)
		(fill yes)
		(layer "F.Cu")
		(net "M_E_CPU1_SA_CB<4>")
	)
	(gr_poly
		(pts
			(xy 144.94129 -276.994112) (xy 145.033746 -276.93874) (xy 144.996408 -276.75205) (xy 144.889728 -276.736302)
			(xy 144.839944 -276.746462) (xy 144.891252 -277.004272)
		)
		(stroke
			(width 0)
			(type solid)
		)
		(fill yes)
		(layer "F.Cu")
		(net "M_E_CPU1_SA_DQ<20>")
	)
	(gr_poly
		(pts
			(xy 144.946624 -273.036284) (xy 144.993106 -272.938748) (xy 144.858232 -272.804128) (xy 144.76095 -272.850356)
			(xy 144.724882 -272.88617) (xy 144.91081 -273.072098)
		)
		(stroke
			(width 0)
			(type solid)
		)
		(fill yes)
		(layer "F.Cu")
		(net "M_E_CPU1_SA_DQ<24>")
	)
	(gr_poly
		(pts
			(xy 144.947132 -273.880072) (xy 144.99336 -273.782536) (xy 144.85874 -273.647916) (xy 144.761204 -273.694144)
			(xy 144.72539 -273.730212) (xy 144.911064 -273.915886)
		)
		(stroke
			(width 0)
			(type solid)
		)
		(fill yes)
		(layer "F.Cu")
		(net "M_E_CPU1_SA_DQ<23>")
	)
	(gr_poly
		(pts
			(xy 144.948148 -248.967752) (xy 144.91208 -248.866152) (xy 144.72158 -248.866152) (xy 144.685512 -248.967752)
			(xy 144.685512 -249.018552) (xy 144.948148 -249.018552)
		)
		(stroke
			(width 0)
			(type solid)
		)
		(fill yes)
		(layer "F.Cu")
		(net "M_E_CPU1_SB_CA<0>")
	)
	(gr_poly
		(pts
			(xy 144.948402 -263.183878) (xy 144.99463 -263.086342) (xy 144.86001 -262.951722) (xy 144.762474 -262.99795)
			(xy 144.72666 -263.034018) (xy 144.912334 -263.219692)
		)
		(stroke
			(width 0)
			(type solid)
		)
		(fill yes)
		(layer "F.Cu")
		(net "M_E_CPU1_SA_CB<5>")
	)
	(gr_poly
		(pts
			(xy 144.949926 -277.29688) (xy 144.898364 -277.03907) (xy 144.84858 -277.048976) (xy 144.75587 -277.104348)
			(xy 144.793208 -277.291292) (xy 144.900142 -277.306786)
		)
		(stroke
			(width 0)
			(type solid)
		)
		(fill yes)
		(layer "F.Cu")
		(net "M_E_CPU1_SA_DQ<20>")
	)
	(gr_poly
		(pts
			(xy 144.955768 -272.182844) (xy 145.00225 -272.085308) (xy 144.867376 -271.950688) (xy 144.770094 -271.996916)
			(xy 144.734026 -272.03273) (xy 144.919954 -272.218658)
		)
		(stroke
			(width 0)
			(type solid)
		)
		(fill yes)
		(layer "F.Cu")
		(net "M_E_CPU1_SA_DQ<25>")
	)
	(gr_poly
		(pts
			(xy 144.988026 -229.69601) (xy 144.952212 -229.659942) (xy 144.854676 -229.613714) (xy 144.720056 -229.748334)
			(xy 144.766284 -229.84587) (xy 144.802352 -229.881684)
		)
		(stroke
			(width 0)
			(type solid)
		)
		(fill yes)
		(layer "F.Cu")
		(net "M_E_CPU1_SB_DQ<19>")
	)
	(gr_poly
		(pts
			(xy 144.997424 -230.549196) (xy 144.961356 -230.513382) (xy 144.864074 -230.467154) (xy 144.7292 -230.601774)
			(xy 144.775428 -230.69931) (xy 144.811496 -230.735124)
		)
		(stroke
			(width 0)
			(type solid)
		)
		(fill yes)
		(layer "F.Cu")
		(net "M_E_CPU1_SB_DQ<18>")
	)
	(gr_poly
		(pts
			(xy 144.99844 -241.077242) (xy 144.952212 -240.97996) (xy 144.916398 -240.943892) (xy 144.73047 -241.12982)
			(xy 144.766284 -241.165634) (xy 144.86382 -241.212116)
		)
		(stroke
			(width 0)
			(type solid)
		)
		(fill yes)
		(layer "F.Cu")
		(net "M_E_CPU1_SB_CB<7>")
	)
	(gr_poly
		(pts
			(xy 145.00606 -232.246424) (xy 144.970246 -232.210356) (xy 144.87271 -232.164128) (xy 144.73809 -232.299002)
			(xy 144.784318 -232.396284) (xy 144.820132 -232.432352)
		)
		(stroke
			(width 0)
			(type solid)
		)
		(fill yes)
		(layer "F.Cu")
		(net "M_E_CPU1_SB_DQ<13>")
	)
	(gr_poly
		(pts
			(xy 145.006568 -275.763736) (xy 145.099024 -275.708364) (xy 145.061686 -275.52142) (xy 144.954752 -275.505926)
			(xy 144.904968 -275.515832) (xy 144.95653 -275.773642)
		)
		(stroke
			(width 0)
			(type solid)
		)
		(fill yes)
		(layer "F.Cu")
		(net "M_E_CPU1_SA_DQ<22>")
	)
	(gr_poly
		(pts
			(xy 145.007838 -241.930682) (xy 144.961356 -241.833146) (xy 144.925542 -241.797332) (xy 144.739614 -241.98326)
			(xy 144.775682 -242.019074) (xy 144.872964 -242.065302)
		)
		(stroke
			(width 0)
			(type solid)
		)
		(fill yes)
		(layer "F.Cu")
		(net "M_E_CPU1_SB_CB<6>")
	)
	(gr_poly
		(pts
			(xy 145.015204 -276.06625) (xy 144.963642 -275.80844) (xy 144.913858 -275.8186) (xy 144.821148 -275.873972)
			(xy 144.858486 -276.060662) (xy 144.96542 -276.076156)
		)
		(stroke
			(width 0)
			(type solid)
		)
		(fill yes)
		(layer "F.Cu")
		(net "M_E_CPU1_SA_DQ<22>")
	)
	(gr_poly
		(pts
			(xy 145.015458 -233.09961) (xy 144.97939 -233.063796) (xy 144.882108 -233.017568) (xy 144.747234 -233.152188)
			(xy 144.793462 -233.249724) (xy 144.82953 -233.285538)
		)
		(stroke
			(width 0)
			(type solid)
		)
		(fill yes)
		(layer "F.Cu")
		(net "M_E_CPU1_SB_DQ<12>")
	)
	(gr_poly
		(pts
			(xy 145.021046 -267.713968) (xy 145.05686 -267.6779) (xy 144.871186 -267.492226) (xy 144.835118 -267.52804)
			(xy 144.78889 -267.625576) (xy 144.92351 -267.760196)
		)
		(stroke
			(width 0)
			(type solid)
		)
		(fill yes)
		(layer "F.Cu")
		(net "M_E_CPU1_SA_CB<0>")
	)
	(gr_poly
		(pts
			(xy 145.03019 -266.860528) (xy 145.066258 -266.824714) (xy 144.88033 -266.638786) (xy 144.844262 -266.6746)
			(xy 144.798034 -266.772136) (xy 144.932908 -266.906756)
		)
		(stroke
			(width 0)
			(type solid)
		)
		(fill yes)
		(layer "F.Cu")
		(net "M_E_CPU1_SA_CB<1>")
	)
	(gr_poly
		(pts
			(xy 145.04035 -235.662724) (xy 145.004536 -235.62691) (xy 144.907 -235.580682) (xy 144.77238 -235.715302)
			(xy 144.818608 -235.812838) (xy 144.854422 -235.848652)
		)
		(stroke
			(width 0)
			(type solid)
		)
		(fill yes)
		(layer "F.Cu")
		(net "M_E_CPU1_SB_DQ<9>")
	)
	(gr_poly
		(pts
			(xy 145.04924 -237.359698) (xy 145.013172 -237.323884) (xy 144.91589 -237.277656) (xy 144.781016 -237.412276)
			(xy 144.827244 -237.509812) (xy 144.863312 -237.545626)
		)
		(stroke
			(width 0)
			(type solid)
		)
		(fill yes)
		(layer "F.Cu")
		(net "M_E_CPU1_SB_CB<3>")
	)
	(gr_poly
		(pts
			(xy 145.050256 -236.516926) (xy 145.014442 -236.480858) (xy 144.916906 -236.43463) (xy 144.782286 -236.569504)
			(xy 144.828514 -236.666786) (xy 144.864328 -236.702854)
		)
		(stroke
			(width 0)
			(type solid)
		)
		(fill yes)
		(layer "F.Cu")
		(net "M_E_CPU1_SB_DQ<8>")
	)
	(gr_poly
		(pts
			(xy 145.05432 -269.368778) (xy 145.090388 -269.332964) (xy 144.90446 -269.147036) (xy 144.868646 -269.18285)
			(xy 144.822164 -269.280386) (xy 144.957038 -269.415006)
		)
		(stroke
			(width 0)
			(type solid)
		)
		(fill yes)
		(layer "F.Cu")
		(net "M_E_CPU1_SA_DQ<30>")
	)
	(gr_poly
		(pts
			(xy 145.05813 -277.579582) (xy 145.150586 -277.52421) (xy 145.113248 -277.337266) (xy 145.006568 -277.321772)
			(xy 144.956784 -277.331678) (xy 145.008346 -277.589488)
		)
		(stroke
			(width 0)
			(type solid)
		)
		(fill yes)
		(layer "F.Cu")
		(net "M_E_CPU1_SA_DQ<20>")
	)
	(gr_poly
		(pts
			(xy 145.058384 -238.213138) (xy 145.022316 -238.177324) (xy 144.925034 -238.131096) (xy 144.790414 -238.265716)
			(xy 144.836642 -238.363252) (xy 144.872456 -238.399066)
		)
		(stroke
			(width 0)
			(type solid)
		)
		(fill yes)
		(layer "F.Cu")
		(net "M_E_CPU1_SB_CB<2>")
	)
	(gr_poly
		(pts
			(xy 145.063972 -268.515338) (xy 145.099786 -268.47927) (xy 144.913858 -268.293342) (xy 144.878044 -268.32941)
			(xy 144.831816 -268.426692) (xy 144.966436 -268.561566)
		)
		(stroke
			(width 0)
			(type solid)
		)
		(fill yes)
		(layer "F.Cu")
		(net "M_E_CPU1_SA_DQ<31>")
	)
	(gr_poly
		(pts
			(xy 145.066766 -277.882096) (xy 145.015204 -277.624286) (xy 144.96542 -277.634192) (xy 144.872964 -277.689818)
			(xy 144.910302 -277.876508) (xy 145.016982 -277.892002)
		)
		(stroke
			(width 0)
			(type solid)
		)
		(fill yes)
		(layer "F.Cu")
		(net "M_E_CPU1_SA_DQ<20>")
	)
	(gr_poly
		(pts
			(xy 145.074894 -230.255826) (xy 145.028666 -230.158544) (xy 144.992852 -230.122476) (xy 144.806924 -230.308404)
			(xy 144.842738 -230.344472) (xy 144.940274 -230.3907)
		)
		(stroke
			(width 0)
			(type solid)
		)
		(fill yes)
		(layer "F.Cu")
		(net "M_E_CPU1_SB_DQ<17>")
	)
	(gr_poly
		(pts
			(xy 145.07845 -264.32002) (xy 145.114264 -264.284206) (xy 144.928336 -264.098278) (xy 144.892522 -264.134346)
			(xy 144.846294 -264.231628) (xy 144.980914 -264.366248)
		)
		(stroke
			(width 0)
			(type solid)
		)
		(fill yes)
		(layer "F.Cu")
		(net "M_E_CPU1_SA_CB<4>")
	)
	(gr_poly
		(pts
			(xy 145.080228 -274.835874) (xy 145.028666 -274.578064) (xy 144.978882 -274.58797) (xy 144.886426 -274.643342)
			(xy 144.923764 -274.830286) (xy 145.030444 -274.84578)
		)
		(stroke
			(width 0)
			(type solid)
		)
		(fill yes)
		(layer "F.Cu")
		(net "M_E_CPU1_SA_DQ<21>")
	)
	(gr_poly
		(pts
			(xy 145.083784 -231.953054) (xy 145.037556 -231.855518) (xy 145.001488 -231.819704) (xy 144.81556 -232.005632)
			(xy 144.851628 -232.041446) (xy 144.94891 -232.087674)
		)
		(stroke
			(width 0)
			(type solid)
		)
		(fill yes)
		(layer "F.Cu")
		(net "M_E_CPU1_SB_DQ<15>")
	)
	(gr_poly
		(pts
			(xy 145.084038 -231.109266) (xy 145.03781 -231.011984) (xy 145.001996 -230.975916) (xy 144.816068 -231.161844)
			(xy 144.851882 -231.197658) (xy 144.949418 -231.24414)
		)
		(stroke
			(width 0)
			(type solid)
		)
		(fill yes)
		(layer "F.Cu")
		(net "M_E_CPU1_SB_DQ<16>")
	)
	(gr_poly
		(pts
			(xy 145.085816 -273.318986) (xy 145.121884 -273.283172) (xy 144.935956 -273.097244) (xy 144.900142 -273.133058)
			(xy 144.85366 -273.230594) (xy 144.988534 -273.365214)
		)
		(stroke
			(width 0)
			(type solid)
		)
		(fill yes)
		(layer "F.Cu")
		(net "M_E_CPU1_SA_DQ<24>")
	)
	(gr_poly
		(pts
			(xy 145.086324 -274.163028) (xy 145.122138 -274.12696) (xy 144.93621 -273.941032) (xy 144.900396 -273.9771)
			(xy 144.854168 -274.074382) (xy 144.988788 -274.209256)
		)
		(stroke
			(width 0)
			(type solid)
		)
		(fill yes)
		(layer "F.Cu")
		(net "M_E_CPU1_SA_DQ<23>")
	)
	(gr_poly
		(pts
			(xy 145.087594 -263.466834) (xy 145.123408 -263.430766) (xy 144.93748 -263.244838) (xy 144.901666 -263.280906)
			(xy 144.855438 -263.378188) (xy 144.990058 -263.513062)
		)
		(stroke
			(width 0)
			(type solid)
		)
		(fill yes)
		(layer "F.Cu")
		(net "M_E_CPU1_SA_CB<5>")
	)
	(gr_poly
		(pts
			(xy 145.092928 -232.806494) (xy 145.0467 -232.708958) (xy 145.010632 -232.673144) (xy 144.824958 -232.858818)
			(xy 144.860772 -232.894886) (xy 144.958308 -232.941114)
		)
		(stroke
			(width 0)
			(type solid)
		)
		(fill yes)
		(layer "F.Cu")
		(net "M_E_CPU1_SB_DQ<14>")
	)
	(gr_poly
		(pts
			(xy 145.09496 -272.465546) (xy 145.131028 -272.429732) (xy 144.9451 -272.243804) (xy 144.909286 -272.279618)
			(xy 144.863058 -272.377154) (xy 144.997678 -272.511774)
		)
		(stroke
			(width 0)
			(type solid)
		)
		(fill yes)
		(layer "F.Cu")
		(net "M_E_CPU1_SA_DQ<25>")
	)
	(gr_poly
		(pts
			(xy 145.0975 -267.215366) (xy 145.143728 -267.118084) (xy 145.009108 -266.98321) (xy 144.911572 -267.029438)
			(xy 144.875758 -267.065506) (xy 145.061686 -267.251434)
		)
		(stroke
			(width 0)
			(type solid)
		)
		(fill yes)
		(layer "F.Cu")
		(net "M_E_CPU1_SA_CB<2>")
	)
	(gr_poly
		(pts
			(xy 145.106644 -266.361926) (xy 145.152872 -266.264644) (xy 145.018252 -266.130024) (xy 144.920716 -266.176252)
			(xy 144.884902 -266.212066) (xy 145.07083 -266.397994)
		)
		(stroke
			(width 0)
			(type solid)
		)
		(fill yes)
		(layer "F.Cu")
		(net "M_E_CPU1_SA_CB<3>")
	)
	(gr_poly
		(pts
			(xy 145.11782 -235.369354) (xy 145.071592 -235.271818) (xy 145.035524 -235.236004) (xy 144.849596 -235.421678)
			(xy 144.885664 -235.457746) (xy 144.982946 -235.503974)
		)
		(stroke
			(width 0)
			(type solid)
		)
		(fill yes)
		(layer "F.Cu")
		(net "M_E_CPU1_SB_DQ<11>")
	)
	(gr_poly
		(pts
			(xy 145.12163 -269.723616) (xy 145.167858 -269.626334) (xy 145.033238 -269.49146) (xy 144.935702 -269.537688)
			(xy 144.899888 -269.573756) (xy 145.085816 -269.759684)
		)
		(stroke
			(width 0)
			(type solid)
		)
		(fill yes)
		(layer "F.Cu")
		(net "M_E_CPU1_SA_DQ<28>")
	)
	(gr_poly
		(pts
			(xy 145.123408 -276.348952) (xy 145.216118 -276.29358) (xy 145.17878 -276.10689) (xy 145.071846 -276.091142)
			(xy 145.022062 -276.101302) (xy 145.073624 -276.358858)
		)
		(stroke
			(width 0)
			(type solid)
		)
		(fill yes)
		(layer "F.Cu")
		(net "M_E_CPU1_SA_DQ<22>")
	)
	(gr_poly
		(pts
			(xy 145.127472 -240.732818) (xy 145.091404 -240.697004) (xy 144.994122 -240.650776) (xy 144.859248 -240.785396)
			(xy 144.905476 -240.882932) (xy 144.941544 -240.918746)
		)
		(stroke
			(width 0)
			(type solid)
		)
		(fill yes)
		(layer "F.Cu")
		(net "M_E_CPU1_SB_CB<7>")
	)
	(gr_poly
		(pts
			(xy 145.127726 -236.223302) (xy 145.081498 -236.12602) (xy 145.045684 -236.089952) (xy 144.859756 -236.27588)
			(xy 144.89557 -236.311948) (xy 144.993106 -236.358176)
		)
		(stroke
			(width 0)
			(type solid)
		)
		(fill yes)
		(layer "F.Cu")
		(net "M_E_CPU1_SB_DQ<10>")
	)
	(gr_poly
		(pts
			(xy 145.131028 -268.870176) (xy 145.177256 -268.77264) (xy 145.042636 -268.63802) (xy 144.9451 -268.684248)
			(xy 144.909286 -268.720316) (xy 145.09496 -268.90599)
		)
		(stroke
			(width 0)
			(type solid)
		)
		(fill yes)
		(layer "F.Cu")
		(net "M_E_CPU1_SA_DQ<29>")
	)
	(gr_poly
		(pts
			(xy 145.132298 -276.65172) (xy 145.080736 -276.39391) (xy 145.030952 -276.403816) (xy 144.938242 -276.459188)
			(xy 144.97558 -276.646132) (xy 145.082514 -276.661626)
		)
		(stroke
			(width 0)
			(type solid)
		)
		(fill yes)
		(layer "F.Cu")
		(net "M_E_CPU1_SA_DQ<22>")
	)
	(gr_poly
		(pts
			(xy 145.135854 -237.919768) (xy 145.089626 -237.822486) (xy 145.053812 -237.786418) (xy 144.867884 -237.972346)
			(xy 144.903698 -238.008414) (xy 145.001234 -238.054642)
		)
		(stroke
			(width 0)
			(type solid)
		)
		(fill yes)
		(layer "F.Cu")
		(net "M_E_CPU1_SB_CB<1>")
	)
	(gr_poly
		(pts
			(xy 145.136616 -241.586258) (xy 145.100802 -241.550444) (xy 145.003266 -241.504216) (xy 144.868646 -241.638836)
			(xy 144.914874 -241.736372) (xy 144.950688 -241.772186)
		)
		(stroke
			(width 0)
			(type solid)
		)
		(fill yes)
		(layer "F.Cu")
		(net "M_E_CPU1_SB_CB<6>")
	)
	(gr_poly
		(pts
			(xy 145.145252 -238.773208) (xy 145.09877 -238.675672) (xy 145.062956 -238.639858) (xy 144.877028 -238.825786)
			(xy 144.913096 -238.8616) (xy 145.010378 -238.907828)
		)
		(stroke
			(width 0)
			(type solid)
		)
		(fill yes)
		(layer "F.Cu")
		(net "M_E_CPU1_SB_CB<0>")
	)
	(gr_poly
		(pts
			(xy 145.154904 -263.821672) (xy 145.201132 -263.724136) (xy 145.066258 -263.589516) (xy 144.968976 -263.635744)
			(xy 144.932908 -263.671558) (xy 145.118836 -263.857486)
		)
		(stroke
			(width 0)
			(type solid)
		)
		(fill yes)
		(layer "F.Cu")
		(net "M_E_CPU1_SA_CB<6>")
	)
	(gr_poly
		(pts
			(xy 145.16227 -272.820384) (xy 145.208498 -272.723102) (xy 145.073878 -272.588482) (xy 144.976342 -272.63471)
			(xy 144.940528 -272.670524) (xy 145.126456 -272.856452)
		)
		(stroke
			(width 0)
			(type solid)
		)
		(fill yes)
		(layer "F.Cu")
		(net "M_E_CPU1_SA_DQ<26>")
	)
	(gr_poly
		(pts
			(xy 145.164048 -262.968232) (xy 145.210276 -262.870696) (xy 145.075656 -262.736076) (xy 144.97812 -262.782304)
			(xy 144.942306 -262.818372) (xy 145.12798 -263.004046)
		)
		(stroke
			(width 0)
			(type solid)
		)
		(fill yes)
		(layer "F.Cu")
		(net "M_E_CPU1_SA_CB<7>")
	)
	(gr_poly
		(pts
			(xy 145.171414 -271.966944) (xy 145.217642 -271.869662) (xy 145.083022 -271.735042) (xy 144.985486 -271.78127)
			(xy 144.949672 -271.817084) (xy 145.1356 -272.003012)
		)
		(stroke
			(width 0)
			(type solid)
		)
		(fill yes)
		(layer "F.Cu")
		(net "M_E_CPU1_SA_DQ<27>")
	)
	(gr_poly
		(pts
			(xy 145.175224 -278.164798) (xy 145.26768 -278.109426) (xy 145.230342 -277.922736) (xy 145.123662 -277.906988)
			(xy 145.073878 -277.916894) (xy 145.125186 -278.174704)
		)
		(stroke
			(width 0)
			(type solid)
		)
		(fill yes)
		(layer "F.Cu")
		(net "M_E_CPU1_SA_DQ<20>")
	)
	(gr_poly
		(pts
			(xy 145.18386 -278.467566) (xy 145.132298 -278.209756) (xy 145.082514 -278.219662) (xy 144.989804 -278.275034)
			(xy 145.027142 -278.461978) (xy 145.134076 -278.477472)
		)
		(stroke
			(width 0)
			(type solid)
		)
		(fill yes)
		(layer "F.Cu")
		(net "M_E_CPU1_SA_DQ<20>")
	)
	(gr_poly
		(pts
			(xy 145.188686 -275.118576) (xy 145.281142 -275.063204) (xy 145.243804 -274.87626) (xy 145.137124 -274.860766)
			(xy 145.08734 -274.870672) (xy 145.138902 -275.128482)
		)
		(stroke
			(width 0)
			(type solid)
		)
		(fill yes)
		(layer "F.Cu")
		(net "M_E_CPU1_SA_DQ<21>")
	)
	(gr_poly
		(pts
			(xy 145.197322 -275.42109) (xy 145.14576 -275.16328) (xy 145.095976 -275.17344) (xy 145.00352 -275.228812)
			(xy 145.040858 -275.415502) (xy 145.147538 -275.430996)
		)
		(stroke
			(width 0)
			(type solid)
		)
		(fill yes)
		(layer "F.Cu")
		(net "M_E_CPU1_SA_DQ<21>")
	)
	(gr_poly
		(pts
			(xy 145.203672 -229.911656) (xy 145.167858 -229.875588) (xy 145.070322 -229.82936) (xy 144.935702 -229.96398)
			(xy 144.98193 -230.061516) (xy 145.017998 -230.09733)
		)
		(stroke
			(width 0)
			(type solid)
		)
		(fill yes)
		(layer "F.Cu")
		(net "M_E_CPU1_SB_DQ<17>")
	)
	(gr_poly
		(pts
			(xy 145.212562 -231.60863) (xy 145.176748 -231.572816) (xy 145.079212 -231.526588) (xy 144.944592 -231.661208)
			(xy 144.99082 -231.75849) (xy 145.026634 -231.794558)
		)
		(stroke
			(width 0)
			(type solid)
		)
		(fill yes)
		(layer "F.Cu")
		(net "M_E_CPU1_SB_DQ<15>")
	)
	(gr_poly
		(pts
			(xy 145.21307 -230.764842) (xy 145.177002 -230.729028) (xy 145.07972 -230.6828) (xy 144.944846 -230.81742)
			(xy 144.991074 -230.914956) (xy 145.027142 -230.95077)
		)
		(stroke
			(width 0)
			(type solid)
		)
		(fill yes)
		(layer "F.Cu")
		(net "M_E_CPU1_SB_DQ<16>")
	)
	(gr_poly
		(pts
			(xy 145.214086 -241.292888) (xy 145.167858 -241.195606) (xy 145.132044 -241.159538) (xy 144.946116 -241.345466)
			(xy 144.98193 -241.38128) (xy 145.079466 -241.427762)
		)
		(stroke
			(width 0)
			(type solid)
		)
		(fill yes)
		(layer "F.Cu")
		(net "M_E_CPU1_SB_CB<5>")
	)
	(gr_poly
		(pts
			(xy 145.221706 -232.46207) (xy 145.185892 -232.426002) (xy 145.088356 -232.379774) (xy 144.953736 -232.514648)
			(xy 144.999964 -232.61193) (xy 145.035778 -232.647998)
		)
		(stroke
			(width 0)
			(type solid)
		)
		(fill yes)
		(layer "F.Cu")
		(net "M_E_CPU1_SB_DQ<14>")
	)
	(gr_poly
		(pts
			(xy 145.223484 -242.146328) (xy 145.177002 -242.048792) (xy 145.141188 -242.012978) (xy 144.95526 -242.198906)
			(xy 144.991328 -242.23472) (xy 145.08861 -242.280948)
		)
		(stroke
			(width 0)
			(type solid)
		)
		(fill yes)
		(layer "F.Cu")
		(net "M_E_CPU1_SB_CB<4>")
	)
	(gr_poly
		(pts
			(xy 145.236692 -267.498322) (xy 145.272506 -267.462254) (xy 145.086832 -267.27658) (xy 145.050764 -267.312394)
			(xy 145.004536 -267.40993) (xy 145.139156 -267.54455)
		)
		(stroke
			(width 0)
			(type solid)
		)
		(fill yes)
		(layer "F.Cu")
		(net "M_E_CPU1_SA_CB<2>")
	)
	(gr_poly
		(pts
			(xy 145.240502 -276.934422) (xy 145.332958 -276.878796) (xy 145.29562 -276.692106) (xy 145.18894 -276.676612)
			(xy 145.139156 -276.686518) (xy 145.190718 -276.944328)
		)
		(stroke
			(width 0)
			(type solid)
		)
		(fill yes)
		(layer "F.Cu")
		(net "M_E_CPU1_SA_DQ<22>")
	)
	(gr_poly
		(pts
			(xy 145.245836 -266.644882) (xy 145.281904 -266.609068) (xy 145.095976 -266.42314) (xy 145.059908 -266.458954)
			(xy 145.01368 -266.55649) (xy 145.148554 -266.69111)
		)
		(stroke
			(width 0)
			(type solid)
		)
		(fill yes)
		(layer "F.Cu")
		(net "M_E_CPU1_SA_CB<3>")
	)
	(gr_poly
		(pts
			(xy 145.246598 -235.02493) (xy 145.210784 -234.988862) (xy 145.113248 -234.942634) (xy 144.978628 -235.077508)
			(xy 145.024856 -235.17479) (xy 145.06067 -235.210858)
		)
		(stroke
			(width 0)
			(type solid)
		)
		(fill yes)
		(layer "F.Cu")
		(net "M_E_CPU1_SB_DQ<11>")
	)
	(gr_poly
		(pts
			(xy 145.249138 -277.236936) (xy 145.19783 -276.979126) (xy 145.147792 -276.989032) (xy 145.055336 -277.044404)
			(xy 145.092674 -277.231348) (xy 145.199354 -277.246842)
		)
		(stroke
			(width 0)
			(type solid)
		)
		(fill yes)
		(layer "F.Cu")
		(net "M_E_CPU1_SA_DQ<22>")
	)
	(gr_poly
		(pts
			(xy 145.256504 -235.879132) (xy 145.22069 -235.843064) (xy 145.123154 -235.796836) (xy 144.988534 -235.931456)
			(xy 145.034762 -236.028992) (xy 145.07083 -236.064806)
		)
		(stroke
			(width 0)
			(type solid)
		)
		(fill yes)
		(layer "F.Cu")
		(net "M_E_CPU1_SB_DQ<10>")
	)
	(gr_poly
		(pts
			(xy 145.260822 -270.006572) (xy 145.29689 -269.970758) (xy 145.110962 -269.78483) (xy 145.074894 -269.820644)
			(xy 145.028666 -269.91818) (xy 145.16354 -270.0528)
		)
		(stroke
			(width 0)
			(type solid)
		)
		(fill yes)
		(layer "F.Cu")
		(net "M_E_CPU1_SA_DQ<28>")
	)
	(gr_poly
		(pts
			(xy 145.264886 -237.575344) (xy 145.228818 -237.53953) (xy 145.131536 -237.493302) (xy 144.996662 -237.627922)
			(xy 145.04289 -237.725458) (xy 145.078958 -237.761272)
		)
		(stroke
			(width 0)
			(type solid)
		)
		(fill yes)
		(layer "F.Cu")
		(net "M_E_CPU1_SB_CB<1>")
	)
	(gr_poly
		(pts
			(xy 145.27022 -269.153132) (xy 145.306034 -269.117064) (xy 145.120106 -268.931136) (xy 145.084292 -268.967204)
			(xy 145.038064 -269.06474) (xy 145.172684 -269.19936)
		)
		(stroke
			(width 0)
			(type solid)
		)
		(fill yes)
		(layer "F.Cu")
		(net "M_E_CPU1_SA_DQ<29>")
	)
	(gr_poly
		(pts
			(xy 145.27403 -238.428784) (xy 145.237962 -238.39297) (xy 145.14068 -238.346742) (xy 145.00606 -238.481362)
			(xy 145.052288 -238.578898) (xy 145.088102 -238.614712)
		)
		(stroke
			(width 0)
			(type solid)
		)
		(fill yes)
		(layer "F.Cu")
		(net "M_E_CPU1_SB_CB<0>")
	)
	(gr_poly
		(pts
			(xy 145.281396 -229.618286) (xy 145.235168 -229.52075) (xy 145.1991 -229.484936) (xy 145.013172 -229.670864)
			(xy 145.04924 -229.706678) (xy 145.146522 -229.752906)
		)
		(stroke
			(width 0)
			(type solid)
		)
		(fill yes)
		(layer "F.Cu")
		(net "M_E_CPU1_SB_DQ<19>")
	)
	(gr_poly
		(pts
			(xy 145.29054 -230.471472) (xy 145.244312 -230.37419) (xy 145.208498 -230.338122) (xy 145.02257 -230.52405)
			(xy 145.058384 -230.560118) (xy 145.15592 -230.606346)
		)
		(stroke
			(width 0)
			(type solid)
		)
		(fill yes)
		(layer "F.Cu")
		(net "M_E_CPU1_SB_DQ<18>")
	)
	(gr_poly
		(pts
			(xy 145.292064 -278.750268) (xy 145.38452 -278.694642) (xy 145.347182 -278.507952) (xy 145.240502 -278.492458)
			(xy 145.190718 -278.502364) (xy 145.24228 -278.760174)
		)
		(stroke
			(width 0)
			(type solid)
		)
		(fill yes)
		(layer "F.Cu")
		(net "M_E_CPU1_SA_DQ<20>")
	)
	(gr_poly
		(pts
			(xy 145.294096 -264.104374) (xy 145.32991 -264.06856) (xy 145.143982 -263.882632) (xy 145.108168 -263.9187)
			(xy 145.06194 -264.015982) (xy 145.19656 -264.150602)
		)
		(stroke
			(width 0)
			(type solid)
		)
		(fill yes)
		(layer "F.Cu")
		(net "M_E_CPU1_SA_CB<6>")
	)
	(gr_poly
		(pts
			(xy 145.29943 -232.1687) (xy 145.253202 -232.071164) (xy 145.217134 -232.03535) (xy 145.031206 -232.221278)
			(xy 145.067274 -232.257092) (xy 145.164556 -232.30332)
		)
		(stroke
			(width 0)
			(type solid)
		)
		(fill yes)
		(layer "F.Cu")
		(net "M_E_CPU1_SB_DQ<13>")
	)
	(gr_poly
		(pts
			(xy 145.3007 -279.052782) (xy 145.249138 -278.794972) (xy 145.199354 -278.804878) (xy 145.106898 -278.860504)
			(xy 145.144236 -279.047194) (xy 145.250916 -279.062688)
		)
		(stroke
			(width 0)
			(type solid)
		)
		(fill yes)
		(layer "F.Cu")
		(net "M_E_CPU1_SA_DQ<20>")
	)
	(gr_poly
		(pts
			(xy 145.301462 -273.10334) (xy 145.33753 -273.067526) (xy 145.151602 -272.881598) (xy 145.115534 -272.917412)
			(xy 145.069306 -273.014948) (xy 145.20418 -273.149568)
		)
		(stroke
			(width 0)
			(type solid)
		)
		(fill yes)
		(layer "F.Cu")
		(net "M_E_CPU1_SA_DQ<26>")
	)
	(gr_poly
		(pts
			(xy 145.30324 -263.251188) (xy 145.339054 -263.21512) (xy 145.153126 -263.029192) (xy 145.117312 -263.06526)
			(xy 145.071084 -263.162542) (xy 145.205704 -263.297416)
		)
		(stroke
			(width 0)
			(type solid)
		)
		(fill yes)
		(layer "F.Cu")
		(net "M_E_CPU1_SA_CB<7>")
	)
	(gr_poly
		(pts
			(xy 145.304002 -267.85316) (xy 145.35023 -267.755624) (xy 145.215356 -267.621004) (xy 145.118074 -267.667232)
			(xy 145.082006 -267.703046) (xy 145.267934 -267.888974)
		)
		(stroke
			(width 0)
			(type solid)
		)
		(fill yes)
		(layer "F.Cu")
		(net "M_E_CPU1_SA_CB<0>")
	)
	(gr_poly
		(pts
			(xy 145.30578 -275.703792) (xy 145.398236 -275.64842) (xy 145.360898 -275.461476) (xy 145.254218 -275.445982)
			(xy 145.204434 -275.455888) (xy 145.255996 -275.713698)
		)
		(stroke
			(width 0)
			(type solid)
		)
		(fill yes)
		(layer "F.Cu")
		(net "M_E_CPU1_SA_DQ<21>")
	)
	(gr_poly
		(pts
			(xy 145.308574 -233.02214) (xy 145.262346 -232.924604) (xy 145.226278 -232.88879) (xy 145.040604 -233.074464)
			(xy 145.076418 -233.110532) (xy 145.173954 -233.15676)
		)
		(stroke
			(width 0)
			(type solid)
		)
		(fill yes)
		(layer "F.Cu")
		(net "M_E_CPU1_SB_DQ<12>")
	)
	(gr_poly
		(pts
			(xy 145.310606 -272.2499) (xy 145.346674 -272.214086) (xy 145.160746 -272.028158) (xy 145.124678 -272.063972)
			(xy 145.07845 -272.161508) (xy 145.213324 -272.296128)
		)
		(stroke
			(width 0)
			(type solid)
		)
		(fill yes)
		(layer "F.Cu")
		(net "M_E_CPU1_SA_DQ<27>")
	)
	(gr_poly
		(pts
			(xy 145.313146 -266.99972) (xy 145.359374 -266.902438) (xy 145.224754 -266.767564) (xy 145.127218 -266.813792)
			(xy 145.091404 -266.84986) (xy 145.277332 -267.035788)
		)
		(stroke
			(width 0)
			(type solid)
		)
		(fill yes)
		(layer "F.Cu")
		(net "M_E_CPU1_SA_CB<1>")
	)
	(gr_poly
		(pts
			(xy 145.314416 -276.00656) (xy 145.262854 -275.74875) (xy 145.21307 -275.758656) (xy 145.120614 -275.814028)
			(xy 145.157952 -276.000718) (xy 145.264632 -276.016466)
		)
		(stroke
			(width 0)
			(type solid)
		)
		(fill yes)
		(layer "F.Cu")
		(net "M_E_CPU1_SA_DQ<21>")
	)
	(gr_poly
		(pts
			(xy 145.33372 -235.585254) (xy 145.287492 -235.487718) (xy 145.251424 -235.451904) (xy 145.065496 -235.637578)
			(xy 145.101564 -235.673646) (xy 145.198846 -235.719874)
		)
		(stroke
			(width 0)
			(type solid)
		)
		(fill yes)
		(layer "F.Cu")
		(net "M_E_CPU1_SB_DQ<9>")
	)
	(gr_poly
		(pts
			(xy 145.337276 -269.50797) (xy 145.383504 -269.410688) (xy 145.248884 -269.275814) (xy 145.151348 -269.322042)
			(xy 145.115534 -269.35811) (xy 145.301462 -269.544038)
		)
		(stroke
			(width 0)
			(type solid)
		)
		(fill yes)
		(layer "F.Cu")
		(net "M_E_CPU1_SA_DQ<30>")
	)
	(gr_poly
		(pts
			(xy 145.342356 -237.282228) (xy 145.296128 -237.184692) (xy 145.26006 -237.148878) (xy 145.074386 -237.334552)
			(xy 145.1102 -237.37062) (xy 145.207736 -237.416848)
		)
		(stroke
			(width 0)
			(type solid)
		)
		(fill yes)
		(layer "F.Cu")
		(net "M_E_CPU1_SB_CB<3>")
	)
	(gr_poly
		(pts
			(xy 145.343118 -240.948464) (xy 145.30705 -240.91265) (xy 145.209768 -240.866422) (xy 145.074894 -241.001042)
			(xy 145.121122 -241.098578) (xy 145.15719 -241.134392)
		)
		(stroke
			(width 0)
			(type solid)
		)
		(fill yes)
		(layer "F.Cu")
		(net "M_E_CPU1_SB_CB<5>")
	)
	(gr_poly
		(pts
			(xy 145.343626 -236.439202) (xy 145.297398 -236.341666) (xy 145.26133 -236.305852) (xy 145.075402 -236.49178)
			(xy 145.11147 -236.527594) (xy 145.208752 -236.573822)
		)
		(stroke
			(width 0)
			(type solid)
		)
		(fill yes)
		(layer "F.Cu")
		(net "M_E_CPU1_SB_DQ<8>")
	)
	(gr_poly
		(pts
			(xy 145.346674 -268.65453) (xy 145.392902 -268.556994) (xy 145.258282 -268.422374) (xy 145.161 -268.468602)
			(xy 145.124932 -268.504416) (xy 145.31086 -268.690344)
		)
		(stroke
			(width 0)
			(type solid)
		)
		(fill yes)
		(layer "F.Cu")
		(net "M_E_CPU1_SA_DQ<31>")
	)
	(gr_poly
		(pts
			(xy 145.3515 -238.135414) (xy 145.305272 -238.038132) (xy 145.269458 -238.002064) (xy 145.08353 -238.187992)
			(xy 145.119344 -238.22406) (xy 145.21688 -238.270288)
		)
		(stroke
			(width 0)
			(type solid)
		)
		(fill yes)
		(layer "F.Cu")
		(net "M_E_CPU1_SB_CB<2>")
	)
	(gr_poly
		(pts
			(xy 145.352262 -241.801904) (xy 145.316448 -241.76609) (xy 145.218912 -241.719862) (xy 145.084292 -241.854482)
			(xy 145.13052 -241.952018) (xy 145.166334 -241.987832)
		)
		(stroke
			(width 0)
			(type solid)
		)
		(fill yes)
		(layer "F.Cu")
		(net "M_E_CPU1_SB_CB<4>")
	)
	(gr_poly
		(pts
			(xy 145.357596 -277.519638) (xy 145.450052 -277.464266) (xy 145.412714 -277.277322) (xy 145.306034 -277.261828)
			(xy 145.25625 -277.271734) (xy 145.307812 -277.529544)
		)
		(stroke
			(width 0)
			(type solid)
		)
		(fill yes)
		(layer "F.Cu")
		(net "M_E_CPU1_SA_DQ<22>")
	)
	(gr_poly
		(pts
			(xy 145.361152 -264.459212) (xy 145.40738 -264.36193) (xy 145.27276 -264.227056) (xy 145.175224 -264.273538)
			(xy 145.13941 -264.309352) (xy 145.325338 -264.49528)
		)
		(stroke
			(width 0)
			(type solid)
		)
		(fill yes)
		(layer "F.Cu")
		(net "M_E_CPU1_SA_CB<4>")
	)
	(gr_poly
		(pts
			(xy 145.366232 -277.822152) (xy 145.31467 -277.564342) (xy 145.264886 -277.574502) (xy 145.17243 -277.629874)
			(xy 145.209768 -277.816564) (xy 145.316448 -277.832312)
		)
		(stroke
			(width 0)
			(type solid)
		)
		(fill yes)
		(layer "F.Cu")
		(net "M_E_CPU1_SA_DQ<22>")
	)
	(gr_poly
		(pts
			(xy 145.368772 -273.458178) (xy 145.415 -273.360896) (xy 145.28038 -273.226022) (xy 145.182844 -273.27225)
			(xy 145.14703 -273.308318) (xy 145.332958 -273.494246)
		)
		(stroke
			(width 0)
			(type solid)
		)
		(fill yes)
		(layer "F.Cu")
		(net "M_E_CPU1_SA_DQ<24>")
	)
	(gr_poly
		(pts
			(xy 145.37055 -263.606026) (xy 145.416778 -263.50849) (xy 145.281904 -263.37387) (xy 145.184622 -263.420098)
			(xy 145.148554 -263.455912) (xy 145.334482 -263.64184)
		)
		(stroke
			(width 0)
			(type solid)
		)
		(fill yes)
		(layer "F.Cu")
		(net "M_E_CPU1_SA_CB<5>")
	)
	(gr_poly
		(pts
			(xy 145.377916 -272.604738) (xy 145.424144 -272.507456) (xy 145.289524 -272.372582) (xy 145.191988 -272.41881)
			(xy 145.156174 -272.454878) (xy 145.342102 -272.640806)
		)
		(stroke
			(width 0)
			(type solid)
		)
		(fill yes)
		(layer "F.Cu")
		(net "M_E_CPU1_SA_DQ<25>")
	)
	(gr_poly
		(pts
			(xy 145.37944 -274.77593) (xy 145.327878 -274.51812) (xy 145.278094 -274.528026) (xy 145.185638 -274.583652)
			(xy 145.222976 -274.770342) (xy 145.329656 -274.785836)
		)
		(stroke
			(width 0)
			(type solid)
		)
		(fill yes)
		(layer "F.Cu")
		(net "M_E_CPU1_SA_DQ<23>")
	)
	(gr_poly
		(pts
			(xy 145.409158 -279.335484) (xy 145.501614 -279.280112) (xy 145.464276 -279.093168) (xy 145.357596 -279.077674)
			(xy 145.307812 -279.08758) (xy 145.35912 -279.34539)
		)
		(stroke
			(width 0)
			(type solid)
		)
		(fill yes)
		(layer "F.Cu")
		(net "M_E_CPU1_SA_DQ<20>")
	)
	(gr_poly
		(pts
			(xy 145.410174 -229.273862) (xy 145.37436 -229.237794) (xy 145.276824 -229.191566) (xy 145.142204 -229.32644)
			(xy 145.188432 -229.423722) (xy 145.224246 -229.45979)
		)
		(stroke
			(width 0)
			(type solid)
		)
		(fill yes)
		(layer "F.Cu")
		(net "M_E_CPU1_SB_DQ<19>")
	)
	(gr_poly
		(pts
			(xy 145.417794 -279.637998) (xy 145.366232 -279.380442) (xy 145.316448 -279.390348) (xy 145.223738 -279.44572)
			(xy 145.261076 -279.63241) (xy 145.36801 -279.648158)
		)
		(stroke
			(width 0)
			(type solid)
		)
		(fill yes)
		(layer "F.Cu")
		(net "M_E_CPU1_SA_DQ<20>")
	)
	(gr_poly
		(pts
			(xy 145.419318 -230.127302) (xy 145.383504 -230.091234) (xy 145.285968 -230.045006) (xy 145.151348 -230.179626)
			(xy 145.197576 -230.277162) (xy 145.233644 -230.312976)
		)
		(stroke
			(width 0)
			(type solid)
		)
		(fill yes)
		(layer "F.Cu")
		(net "M_E_CPU1_SB_DQ<18>")
	)
	(gr_poly
		(pts
			(xy 145.420588 -240.655348) (xy 145.37436 -240.557812) (xy 145.338292 -240.521998) (xy 145.152618 -240.707672)
			(xy 145.188432 -240.74374) (xy 145.285968 -240.789968)
		)
		(stroke
			(width 0)
			(type solid)
		)
		(fill yes)
		(layer "F.Cu")
		(net "M_E_CPU1_SB_CB<7>")
	)
	(gr_poly
		(pts
			(xy 145.422874 -276.289008) (xy 145.51533 -276.233636) (xy 145.477992 -276.046946) (xy 145.371312 -276.031452)
			(xy 145.321528 -276.041358) (xy 145.37309 -276.299168)
		)
		(stroke
			(width 0)
			(type solid)
		)
		(fill yes)
		(layer "F.Cu")
		(net "M_E_CPU1_SA_DQ<21>")
	)
	(gr_poly
		(pts
			(xy 145.428208 -231.824276) (xy 145.392394 -231.788462) (xy 145.294858 -231.742234) (xy 145.160238 -231.876854)
			(xy 145.206466 -231.974136) (xy 145.24228 -232.010204)
		)
		(stroke
			(width 0)
			(type solid)
		)
		(fill yes)
		(layer "F.Cu")
		(net "M_E_CPU1_SB_DQ<13>")
	)
	(gr_poly
		(pts
			(xy 145.429732 -241.508534) (xy 145.383504 -241.411252) (xy 145.34769 -241.375184) (xy 145.161762 -241.561112)
			(xy 145.197576 -241.596926) (xy 145.295112 -241.643408)
		)
		(stroke
			(width 0)
			(type solid)
		)
		(fill yes)
		(layer "F.Cu")
		(net "M_E_CPU1_SB_CB<6>")
	)
	(gr_poly
		(pts
			(xy 145.43151 -276.591776) (xy 145.379948 -276.333966) (xy 145.330164 -276.343872) (xy 145.237708 -276.399244)
			(xy 145.275046 -276.586188) (xy 145.381726 -276.601682)
		)
		(stroke
			(width 0)
			(type solid)
		)
		(fill yes)
		(layer "F.Cu")
		(net "M_E_CPU1_SA_DQ<21>")
	)
	(gr_poly
		(pts
			(xy 145.437352 -232.677716) (xy 145.401538 -232.641648) (xy 145.304002 -232.59542) (xy 145.169382 -232.730294)
			(xy 145.21561 -232.827576) (xy 145.251424 -232.863644)
		)
		(stroke
			(width 0)
			(type solid)
		)
		(fill yes)
		(layer "F.Cu")
		(net "M_E_CPU1_SB_DQ<12>")
	)
	(gr_poly
		(pts
			(xy 145.443194 -268.136116) (xy 145.479008 -268.100048) (xy 145.29308 -267.91412) (xy 145.257266 -267.950188)
			(xy 145.211038 -268.04747) (xy 145.345658 -268.182344)
		)
		(stroke
			(width 0)
			(type solid)
		)
		(fill yes)
		(layer "F.Cu")
		(net "M_E_CPU1_SA_CB<0>")
	)
	(gr_poly
		(pts
			(xy 145.452338 -267.282676) (xy 145.488152 -267.246608) (xy 145.302478 -267.060934) (xy 145.26641 -267.096748)
			(xy 145.220182 -267.194284) (xy 145.354802 -267.328904)
		)
		(stroke
			(width 0)
			(type solid)
		)
		(fill yes)
		(layer "F.Cu")
		(net "M_E_CPU1_SA_CB<1>")
	)
	(gr_poly
		(pts
			(xy 145.462498 -235.24083) (xy 145.426684 -235.204762) (xy 145.329148 -235.158534) (xy 145.194528 -235.293408)
			(xy 145.240756 -235.39069) (xy 145.27657 -235.426758)
		)
		(stroke
			(width 0)
			(type solid)
		)
		(fill yes)
		(layer "F.Cu")
		(net "M_E_CPU1_SB_DQ<9>")
	)
	(gr_poly
		(pts
			(xy 145.471134 -236.937804) (xy 145.43532 -236.901736) (xy 145.337784 -236.855508) (xy 145.203164 -236.990382)
			(xy 145.249392 -237.087664) (xy 145.285206 -237.123732)
		)
		(stroke
			(width 0)
			(type solid)
		)
		(fill yes)
		(layer "F.Cu")
		(net "M_E_CPU1_SB_CB<3>")
	)
	(gr_poly
		(pts
			(xy 145.472404 -236.094778) (xy 145.43659 -236.058964) (xy 145.339054 -236.012736) (xy 145.204434 -236.147356)
			(xy 145.250662 -236.244638) (xy 145.286476 -236.280706)
		)
		(stroke
			(width 0)
			(type solid)
		)
		(fill yes)
		(layer "F.Cu")
		(net "M_E_CPU1_SB_DQ<8>")
	)
	(gr_poly
		(pts
			(xy 145.47469 -278.104854) (xy 145.567146 -278.049482) (xy 145.529808 -277.862792) (xy 145.423128 -277.847044)
			(xy 145.373344 -277.857204) (xy 145.424906 -278.115014)
		)
		(stroke
			(width 0)
			(type solid)
		)
		(fill yes)
		(layer "F.Cu")
		(net "M_E_CPU1_SA_DQ<22>")
	)
	(gr_poly
		(pts
			(xy 145.476468 -269.790926) (xy 145.512536 -269.755112) (xy 145.326608 -269.569184) (xy 145.29054 -269.604998)
			(xy 145.244312 -269.702534) (xy 145.379186 -269.837154)
		)
		(stroke
			(width 0)
			(type solid)
		)
		(fill yes)
		(layer "F.Cu")
		(net "M_E_CPU1_SA_DQ<30>")
	)
	(gr_poly
		(pts
			(xy 145.480532 -237.79099) (xy 145.444464 -237.755176) (xy 145.347182 -237.708948) (xy 145.212308 -237.843568)
			(xy 145.258536 -237.941104) (xy 145.294604 -237.976918)
		)
		(stroke
			(width 0)
			(type solid)
		)
		(fill yes)
		(layer "F.Cu")
		(net "M_E_CPU1_SB_CB<2>")
	)
	(gr_poly
		(pts
			(xy 145.483326 -278.407622) (xy 145.431764 -278.149812) (xy 145.38198 -278.159718) (xy 145.289524 -278.21509)
			(xy 145.326862 -278.402034) (xy 145.433542 -278.417528)
		)
		(stroke
			(width 0)
			(type solid)
		)
		(fill yes)
		(layer "F.Cu")
		(net "M_E_CPU1_SA_DQ<22>")
	)
	(gr_poly
		(pts
			(xy 145.485866 -268.937232) (xy 145.521934 -268.901418) (xy 145.336006 -268.71549) (xy 145.300192 -268.751304)
			(xy 145.25371 -268.84884) (xy 145.388584 -268.98346)
		)
		(stroke
			(width 0)
			(type solid)
		)
		(fill yes)
		(layer "F.Cu")
		(net "M_E_CPU1_SA_DQ<31>")
	)
	(gr_poly
		(pts
			(xy 145.487898 -275.058632) (xy 145.580354 -275.00326) (xy 145.543016 -274.816316) (xy 145.436336 -274.800822)
			(xy 145.386552 -274.810728) (xy 145.438114 -275.068538)
		)
		(stroke
			(width 0)
			(type solid)
		)
		(fill yes)
		(layer "F.Cu")
		(net "M_E_CPU1_SA_DQ<23>")
	)
	(gr_poly
		(pts
			(xy 145.496534 -275.3614) (xy 145.444972 -275.10359) (xy 145.395188 -275.113496) (xy 145.302732 -275.168868)
			(xy 145.34007 -275.355558) (xy 145.44675 -275.371306)
		)
		(stroke
			(width 0)
			(type solid)
		)
		(fill yes)
		(layer "F.Cu")
		(net "M_E_CPU1_SA_DQ<23>")
	)
	(gr_poly
		(pts
			(xy 145.497042 -229.833932) (xy 145.450814 -229.736396) (xy 145.414746 -229.700582) (xy 145.228818 -229.88651)
			(xy 145.264886 -229.922324) (xy 145.362168 -229.968552)
		)
		(stroke
			(width 0)
			(type solid)
		)
		(fill yes)
		(layer "F.Cu")
		(net "M_E_CPU1_SB_DQ<17>")
	)
	(gr_poly
		(pts
			(xy 145.500344 -264.742168) (xy 145.536412 -264.706354) (xy 145.350484 -264.520426) (xy 145.314416 -264.55624)
			(xy 145.268188 -264.653776) (xy 145.403062 -264.788396)
		)
		(stroke
			(width 0)
			(type solid)
		)
		(fill yes)
		(layer "F.Cu")
		(net "M_E_CPU1_SA_CB<4>")
	)
	(gr_poly
		(pts
			(xy 145.505678 -231.530906) (xy 145.45945 -231.433624) (xy 145.423636 -231.397556) (xy 145.237708 -231.583484)
			(xy 145.273522 -231.619298) (xy 145.371058 -231.66578)
		)
		(stroke
			(width 0)
			(type solid)
		)
		(fill yes)
		(layer "F.Cu")
		(net "M_E_CPU1_SB_DQ<15>")
	)
	(gr_poly
		(pts
			(xy 145.506186 -230.687118) (xy 145.459958 -230.589836) (xy 145.424144 -230.553768) (xy 145.238216 -230.739696)
			(xy 145.27403 -230.775764) (xy 145.371566 -230.821992)
		)
		(stroke
			(width 0)
			(type solid)
		)
		(fill yes)
		(layer "F.Cu")
		(net "M_E_CPU1_SB_DQ<16>")
	)
	(gr_poly
		(pts
			(xy 145.507964 -273.741134) (xy 145.544032 -273.70532) (xy 145.358104 -273.519392) (xy 145.322036 -273.555206)
			(xy 145.275808 -273.652742) (xy 145.410682 -273.787362)
		)
		(stroke
			(width 0)
			(type solid)
		)
		(fill yes)
		(layer "F.Cu")
		(net "M_E_CPU1_SA_DQ<24>")
	)
	(gr_poly
		(pts
			(xy 145.509742 -263.888728) (xy 145.545556 -263.852914) (xy 145.359628 -263.666986) (xy 145.323814 -263.703054)
			(xy 145.277586 -263.800336) (xy 145.412206 -263.934956)
		)
		(stroke
			(width 0)
			(type solid)
		)
		(fill yes)
		(layer "F.Cu")
		(net "M_E_CPU1_SA_CB<5>")
	)
	(gr_poly
		(pts
			(xy 145.515076 -232.384346) (xy 145.468848 -232.28681) (xy 145.43278 -232.250996) (xy 145.246852 -232.436924)
			(xy 145.28292 -232.472738) (xy 145.380202 -232.518966)
		)
		(stroke
			(width 0)
			(type solid)
		)
		(fill yes)
		(layer "F.Cu")
		(net "M_E_CPU1_SB_DQ<14>")
	)
	(gr_poly
		(pts
			(xy 145.517108 -272.887694) (xy 145.553176 -272.85188) (xy 145.367248 -272.665952) (xy 145.33118 -272.701766)
			(xy 145.284952 -272.799302) (xy 145.419826 -272.933922)
		)
		(stroke
			(width 0)
			(type solid)
		)
		(fill yes)
		(layer "F.Cu")
		(net "M_E_CPU1_SA_DQ<25>")
	)
	(gr_poly
		(pts
			(xy 145.519648 -267.637514) (xy 145.565876 -267.539978) (xy 145.431002 -267.405358) (xy 145.33372 -267.451586)
			(xy 145.297652 -267.4874) (xy 145.48358 -267.673328)
		)
		(stroke
			(width 0)
			(type solid)
		)
		(fill yes)
		(layer "F.Cu")
		(net "M_E_CPU1_SA_CB<2>")
	)
	(gr_poly
		(pts
			(xy 145.525998 -279.9207) (xy 145.618454 -279.865328) (xy 145.581116 -279.678638) (xy 145.474436 -279.663144)
			(xy 145.424652 -279.67305) (xy 145.476214 -279.93086)
		)
		(stroke
			(width 0)
			(type solid)
		)
		(fill yes)
		(layer "F.Cu")
		(net "M_E_CPU1_SA_DQ<20>")
	)
	(gr_poly
		(pts
			(xy 145.52676 -285.143448) (xy 145.47596 -285.143448) (xy 145.37436 -285.17977) (xy 145.37436 -285.37027)
			(xy 145.47596 -285.406338) (xy 145.52676 -285.406338)
		)
		(stroke
			(width 0)
			(type solid)
		)
		(fill yes)
		(layer "F.Cu")
		(net "M_E_CPU1_SA_DQ<20>")
	)
	(gr_poly
		(pts
			(xy 145.52676 -284.546548) (xy 145.47596 -284.546548) (xy 145.37436 -284.58287) (xy 145.37436 -284.77337)
			(xy 145.47596 -284.809438) (xy 145.52676 -284.809438)
		)
		(stroke
			(width 0)
			(type solid)
		)
		(fill yes)
		(layer "F.Cu")
		(net "M_E_CPU1_SA_DQ<20>")
	)
	(gr_poly
		(pts
			(xy 145.52676 -283.949648) (xy 145.47596 -283.949648) (xy 145.37436 -283.98597) (xy 145.37436 -284.17647)
			(xy 145.47596 -284.212538) (xy 145.52676 -284.212538)
		)
		(stroke
			(width 0)
			(type solid)
		)
		(fill yes)
		(layer "F.Cu")
		(net "M_E_CPU1_SA_DQ<20>")
	)
	(gr_poly
		(pts
			(xy 145.52676 -283.352748) (xy 145.47596 -283.352748) (xy 145.37436 -283.38907) (xy 145.37436 -283.57957)
			(xy 145.47596 -283.615638) (xy 145.52676 -283.615638)
		)
		(stroke
			(width 0)
			(type solid)
		)
		(fill yes)
		(layer "F.Cu")
		(net "M_E_CPU1_SA_DQ<20>")
	)
	(gr_poly
		(pts
			(xy 145.52676 -282.755848) (xy 145.47596 -282.755848) (xy 145.37436 -282.79217) (xy 145.37436 -282.98267)
			(xy 145.47596 -283.018738) (xy 145.52676 -283.018738)
		)
		(stroke
			(width 0)
			(type solid)
		)
		(fill yes)
		(layer "F.Cu")
		(net "M_E_CPU1_SA_DQ<20>")
	)
	(gr_poly
		(pts
			(xy 145.52676 -282.158948) (xy 145.47596 -282.158948) (xy 145.37436 -282.19527) (xy 145.37436 -282.38577)
			(xy 145.47596 -282.421838) (xy 145.52676 -282.421838)
		)
		(stroke
			(width 0)
			(type solid)
		)
		(fill yes)
		(layer "F.Cu")
		(net "M_E_CPU1_SA_DQ<20>")
	)
	(gr_poly
		(pts
			(xy 145.52676 -281.562048) (xy 145.47596 -281.562048) (xy 145.37436 -281.59837) (xy 145.37436 -281.78887)
			(xy 145.47596 -281.824938) (xy 145.52676 -281.824938)
		)
		(stroke
			(width 0)
			(type solid)
		)
		(fill yes)
		(layer "F.Cu")
		(net "M_E_CPU1_SA_DQ<20>")
	)
	(gr_poly
		(pts
			(xy 145.52676 -280.965148) (xy 145.47596 -280.965148) (xy 145.37436 -281.00147) (xy 145.37436 -281.19197)
			(xy 145.47596 -281.228038) (xy 145.52676 -281.228038)
		)
		(stroke
			(width 0)
			(type solid)
		)
		(fill yes)
		(layer "F.Cu")
		(net "M_E_CPU1_SA_DQ<20>")
	)
	(gr_poly
		(pts
			(xy 145.528792 -266.784074) (xy 145.57502 -266.686792) (xy 145.4404 -266.551918) (xy 145.342864 -266.598146)
			(xy 145.30705 -266.634214) (xy 145.492978 -266.820142)
		)
		(stroke
			(width 0)
			(type solid)
		)
		(fill yes)
		(layer "F.Cu")
		(net "M_E_CPU1_SA_CB<3>")
	)
	(gr_poly
		(pts
			(xy 145.539968 -276.874478) (xy 145.632424 -276.819106) (xy 145.595086 -276.632162) (xy 145.488406 -276.616668)
			(xy 145.438622 -276.626574) (xy 145.490184 -276.884384)
		)
		(stroke
			(width 0)
			(type solid)
		)
		(fill yes)
		(layer "F.Cu")
		(net "M_E_CPU1_SA_DQ<21>")
	)
	(gr_poly
		(pts
			(xy 145.539968 -234.947206) (xy 145.493486 -234.84967) (xy 145.457672 -234.813856) (xy 145.271744 -234.999784)
			(xy 145.307812 -235.035598) (xy 145.405094 -235.081826)
		)
		(stroke
			(width 0)
			(type solid)
		)
		(fill yes)
		(layer "F.Cu")
		(net "M_E_CPU1_SB_DQ<11>")
	)
	(gr_poly
		(pts
			(xy 145.543778 -270.145764) (xy 145.590006 -270.048228) (xy 145.455386 -269.913608) (xy 145.35785 -269.959836)
			(xy 145.322036 -269.995904) (xy 145.50771 -270.181578)
		)
		(stroke
			(width 0)
			(type solid)
		)
		(fill yes)
		(layer "F.Cu")
		(net "M_E_CPU1_SA_DQ<28>")
	)
	(gr_poly
		(pts
			(xy 145.548604 -277.176992) (xy 145.497042 -276.919182) (xy 145.447258 -276.929342) (xy 145.354802 -276.984714)
			(xy 145.39214 -277.171404) (xy 145.49882 -277.186898)
		)
		(stroke
			(width 0)
			(type solid)
		)
		(fill yes)
		(layer "F.Cu")
		(net "M_E_CPU1_SA_DQ<21>")
	)
	(gr_poly
		(pts
			(xy 145.549366 -240.310924) (xy 145.513552 -240.274856) (xy 145.416016 -240.228628) (xy 145.281396 -240.363248)
			(xy 145.327624 -240.460784) (xy 145.363438 -240.496852)
		)
		(stroke
			(width 0)
			(type solid)
		)
		(fill yes)
		(layer "F.Cu")
		(net "M_E_CPU1_SB_CB<7>")
	)
	(gr_poly
		(pts
			(xy 145.549874 -235.801408) (xy 145.503646 -235.703872) (xy 145.467578 -235.668058) (xy 145.28165 -235.853986)
			(xy 145.317718 -235.8898) (xy 145.415 -235.936028)
		)
		(stroke
			(width 0)
			(type solid)
		)
		(fill yes)
		(layer "F.Cu")
		(net "M_E_CPU1_SB_DQ<10>")
	)
	(gr_poly
		(pts
			(xy 145.553176 -269.292324) (xy 145.599404 -269.194788) (xy 145.46453 -269.060168) (xy 145.367248 -269.106396)
			(xy 145.33118 -269.14221) (xy 145.517108 -269.328138)
		)
		(stroke
			(width 0)
			(type solid)
		)
		(fill yes)
		(layer "F.Cu")
		(net "M_E_CPU1_SA_DQ<29>")
	)
	(gr_poly
		(pts
			(xy 145.558002 -237.497874) (xy 145.511774 -237.400338) (xy 145.475706 -237.364524) (xy 145.290032 -237.550198)
			(xy 145.325846 -237.586266) (xy 145.423382 -237.632494)
		)
		(stroke
			(width 0)
			(type solid)
		)
		(fill yes)
		(layer "F.Cu")
		(net "M_E_CPU1_SB_CB<1>")
	)
	(gr_poly
		(pts
			(xy 145.558764 -241.16411) (xy 145.522696 -241.128296) (xy 145.425414 -241.082068) (xy 145.29054 -241.216688)
			(xy 145.336768 -241.314224) (xy 145.372836 -241.350038)
		)
		(stroke
			(width 0)
			(type solid)
		)
		(fill yes)
		(layer "F.Cu")
		(net "M_E_CPU1_SB_CB<6>")
	)
	(gr_poly
		(pts
			(xy 145.567146 -238.35106) (xy 145.520918 -238.253778) (xy 145.485104 -238.21771) (xy 145.299176 -238.403638)
			(xy 145.33499 -238.439706) (xy 145.432526 -238.485934)
		)
		(stroke
			(width 0)
			(type solid)
		)
		(fill yes)
		(layer "F.Cu")
		(net "M_E_CPU1_SB_CB<0>")
	)
	(gr_poly
		(pts
			(xy 145.576798 -264.243566) (xy 145.623026 -264.146284) (xy 145.488406 -264.01141) (xy 145.39087 -264.057892)
			(xy 145.355056 -264.093706) (xy 145.540984 -264.279634)
		)
		(stroke
			(width 0)
			(type solid)
		)
		(fill yes)
		(layer "F.Cu")
		(net "M_E_CPU1_SA_CB<6>")
	)
	(gr_poly
		(pts
			(xy 145.584418 -273.242532) (xy 145.630646 -273.14525) (xy 145.496026 -273.010376) (xy 145.39849 -273.056604)
			(xy 145.362676 -273.092672) (xy 145.548604 -273.2786)
		)
		(stroke
			(width 0)
			(type solid)
		)
		(fill yes)
		(layer "F.Cu")
		(net "M_E_CPU1_SA_DQ<26>")
	)
	(gr_poly
		(pts
			(xy 145.586196 -263.39038) (xy 145.632424 -263.292844) (xy 145.49755 -263.158224) (xy 145.400268 -263.204452)
			(xy 145.3642 -263.240266) (xy 145.550128 -263.426194)
		)
		(stroke
			(width 0)
			(type solid)
		)
		(fill yes)
		(layer "F.Cu")
		(net "M_E_CPU1_SA_CB<7>")
	)
	(gr_poly
		(pts
			(xy 145.591784 -278.690324) (xy 145.68424 -278.634698) (xy 145.646902 -278.448008) (xy 145.540222 -278.432514)
			(xy 145.490438 -278.44242) (xy 145.542 -278.70023)
		)
		(stroke
			(width 0)
			(type solid)
		)
		(fill yes)
		(layer "F.Cu")
		(net "M_E_CPU1_SA_DQ<22>")
	)
	(gr_poly
		(pts
			(xy 145.593562 -272.389092) (xy 145.63979 -272.29181) (xy 145.50517 -272.156936) (xy 145.407634 -272.203164)
			(xy 145.37182 -272.239232) (xy 145.557748 -272.42516)
		)
		(stroke
			(width 0)
			(type solid)
		)
		(fill yes)
		(layer "F.Cu")
		(net "M_E_CPU1_SA_DQ<27>")
	)
	(gr_poly
		(pts
			(xy 145.60042 -278.992838) (xy 145.548858 -278.735028) (xy 145.499074 -278.744934) (xy 145.406618 -278.80056)
			(xy 145.443956 -278.98725) (xy 145.550636 -279.002744)
		)
		(stroke
			(width 0)
			(type solid)
		)
		(fill yes)
		(layer "F.Cu")
		(net "M_E_CPU1_SA_DQ<22>")
	)
	(gr_poly
		(pts
			(xy 145.604992 -275.643848) (xy 145.697448 -275.588476) (xy 145.66011 -275.401786) (xy 145.55343 -275.386292)
			(xy 145.503646 -275.396198) (xy 145.555208 -275.654008)
		)
		(stroke
			(width 0)
			(type solid)
		)
		(fill yes)
		(layer "F.Cu")
		(net "M_E_CPU1_SA_DQ<23>")
	)
	(gr_poly
		(pts
			(xy 145.613628 -275.946616) (xy 145.562066 -275.688806) (xy 145.512282 -275.698712) (xy 145.419826 -275.754084)
			(xy 145.457164 -275.941028) (xy 145.563844 -275.956522)
		)
		(stroke
			(width 0)
			(type solid)
		)
		(fill yes)
		(layer "F.Cu")
		(net "M_E_CPU1_SA_DQ<23>")
	)
	(gr_poly
		(pts
			(xy 145.62582 -229.489508) (xy 145.590006 -229.45344) (xy 145.49247 -229.407212) (xy 145.35785 -229.542086)
			(xy 145.404078 -229.639368) (xy 145.439892 -229.675436)
		)
		(stroke
			(width 0)
			(type solid)
		)
		(fill yes)
		(layer "F.Cu")
		(net "M_E_CPU1_SB_DQ<17>")
	)
	(gr_poly
		(pts
			(xy 145.63471 -231.186482) (xy 145.598642 -231.150668) (xy 145.50136 -231.10444) (xy 145.366486 -231.23906)
			(xy 145.412714 -231.336596) (xy 145.448782 -231.37241)
		)
		(stroke
			(width 0)
			(type solid)
		)
		(fill yes)
		(layer "F.Cu")
		(net "M_E_CPU1_SB_DQ<15>")
	)
	(gr_poly
		(pts
			(xy 145.634964 -230.342948) (xy 145.59915 -230.30688) (xy 145.501614 -230.260652) (xy 145.366994 -230.395272)
			(xy 145.413222 -230.492808) (xy 145.44929 -230.528622)
		)
		(stroke
			(width 0)
			(type solid)
		)
		(fill yes)
		(layer "F.Cu")
		(net "M_E_CPU1_SB_DQ<16>")
	)
	(gr_poly
		(pts
			(xy 145.636234 -240.870994) (xy 145.590006 -240.773458) (xy 145.553938 -240.737644) (xy 145.368264 -240.923318)
			(xy 145.404078 -240.959386) (xy 145.501614 -241.005614)
		)
		(stroke
			(width 0)
			(type solid)
		)
		(fill yes)
		(layer "F.Cu")
		(net "M_E_CPU1_SB_CB<5>")
	)
	(gr_poly
		(pts
			(xy 145.643854 -232.039922) (xy 145.60804 -232.004108) (xy 145.510504 -231.95788) (xy 145.375884 -232.0925)
			(xy 145.422112 -232.189782) (xy 145.457926 -232.22585)
		)
		(stroke
			(width 0)
			(type solid)
		)
		(fill yes)
		(layer "F.Cu")
		(net "M_E_CPU1_SB_DQ<14>")
	)
	(gr_poly
		(pts
			(xy 145.645378 -241.72418) (xy 145.59915 -241.626898) (xy 145.563336 -241.59083) (xy 145.377408 -241.776758)
			(xy 145.413222 -241.812572) (xy 145.510758 -241.859054)
		)
		(stroke
			(width 0)
			(type solid)
		)
		(fill yes)
		(layer "F.Cu")
		(net "M_E_CPU1_SB_CB<4>")
	)
	(gr_poly
		(pts
			(xy 145.657062 -277.459694) (xy 145.749518 -277.404322) (xy 145.71218 -277.217632) (xy 145.6055 -277.201884)
			(xy 145.555716 -277.21179) (xy 145.607278 -277.4696)
		)
		(stroke
			(width 0)
			(type solid)
		)
		(fill yes)
		(layer "F.Cu")
		(net "M_E_CPU1_SA_DQ<21>")
	)
	(gr_poly
		(pts
			(xy 145.65884 -267.92047) (xy 145.694654 -267.884402) (xy 145.508726 -267.698474) (xy 145.472912 -267.734542)
			(xy 145.426684 -267.831824) (xy 145.561304 -267.966698)
		)
		(stroke
			(width 0)
			(type solid)
		)
		(fill yes)
		(layer "F.Cu")
		(net "M_E_CPU1_SA_CB<2>")
	)
	(gr_poly
		(pts
			(xy 145.665698 -277.762462) (xy 145.614136 -277.504652) (xy 145.564352 -277.514558) (xy 145.471896 -277.56993)
			(xy 145.509234 -277.75662) (xy 145.615914 -277.772368)
		)
		(stroke
			(width 0)
			(type solid)
		)
		(fill yes)
		(layer "F.Cu")
		(net "M_E_CPU1_SA_DQ<21>")
	)
	(gr_poly
		(pts
			(xy 145.667984 -267.06703) (xy 145.703798 -267.030962) (xy 145.518124 -266.845288) (xy 145.482056 -266.881102)
			(xy 145.435828 -266.978638) (xy 145.570448 -267.113258)
		)
		(stroke
			(width 0)
			(type solid)
		)
		(fill yes)
		(layer "F.Cu")
		(net "M_E_CPU1_SA_CB<3>")
	)
	(gr_poly
		(pts
			(xy 145.668746 -234.602782) (xy 145.632678 -234.566968) (xy 145.535396 -234.52074) (xy 145.400776 -234.65536)
			(xy 145.447004 -234.752896) (xy 145.482818 -234.78871)
		)
		(stroke
			(width 0)
			(type solid)
		)
		(fill yes)
		(layer "F.Cu")
		(net "M_E_CPU1_SB_DQ<11>")
	)
	(gr_poly
		(pts
			(xy 145.678652 -235.456984) (xy 145.642838 -235.420916) (xy 145.545302 -235.374688) (xy 145.410682 -235.509562)
			(xy 145.45691 -235.606844) (xy 145.492724 -235.642912)
		)
		(stroke
			(width 0)
			(type solid)
		)
		(fill yes)
		(layer "F.Cu")
		(net "M_E_CPU1_SB_DQ<10>")
	)
	(gr_poly
		(pts
			(xy 145.67916 -285.07182) (xy 145.67916 -284.88132) (xy 145.57756 -284.844998) (xy 145.52676 -284.844998)
			(xy 145.52676 -285.108142) (xy 145.57756 -285.108142)
		)
		(stroke
			(width 0)
			(type solid)
		)
		(fill yes)
		(layer "F.Cu")
		(net "M_E_CPU1_SA_DQ<20>")
	)
	(gr_poly
		(pts
			(xy 145.67916 -284.47492) (xy 145.67916 -284.28442) (xy 145.57756 -284.248098) (xy 145.52676 -284.248098)
			(xy 145.52676 -284.511242) (xy 145.57756 -284.511242)
		)
		(stroke
			(width 0)
			(type solid)
		)
		(fill yes)
		(layer "F.Cu")
		(net "M_E_CPU1_SA_DQ<20>")
	)
	(gr_poly
		(pts
			(xy 145.67916 -283.87802) (xy 145.67916 -283.68752) (xy 145.57756 -283.651198) (xy 145.52676 -283.651198)
			(xy 145.52676 -283.914342) (xy 145.57756 -283.914342)
		)
		(stroke
			(width 0)
			(type solid)
		)
		(fill yes)
		(layer "F.Cu")
		(net "M_E_CPU1_SA_DQ<20>")
	)
	(gr_poly
		(pts
			(xy 145.67916 -283.28112) (xy 145.67916 -283.09062) (xy 145.57756 -283.054298) (xy 145.52676 -283.054298)
			(xy 145.52676 -283.317442) (xy 145.57756 -283.317442)
		)
		(stroke
			(width 0)
			(type solid)
		)
		(fill yes)
		(layer "F.Cu")
		(net "M_E_CPU1_SA_DQ<20>")
	)
	(gr_poly
		(pts
			(xy 145.67916 -282.68422) (xy 145.67916 -282.49372) (xy 145.57756 -282.457398) (xy 145.52676 -282.457398)
			(xy 145.52676 -282.720542) (xy 145.57756 -282.720542)
		)
		(stroke
			(width 0)
			(type solid)
		)
		(fill yes)
		(layer "F.Cu")
		(net "M_E_CPU1_SA_DQ<20>")
	)
	(gr_poly
		(pts
			(xy 145.67916 -282.08732) (xy 145.67916 -281.89682) (xy 145.57756 -281.860498) (xy 145.52676 -281.860498)
			(xy 145.52676 -282.123642) (xy 145.57756 -282.123642)
		)
		(stroke
			(width 0)
			(type solid)
		)
		(fill yes)
		(layer "F.Cu")
		(net "M_E_CPU1_SA_DQ<20>")
	)
	(gr_poly
		(pts
			(xy 145.67916 -281.49042) (xy 145.67916 -281.29992) (xy 145.57756 -281.263598) (xy 145.52676 -281.263598)
			(xy 145.52676 -281.526742) (xy 145.57756 -281.526742)
		)
		(stroke
			(width 0)
			(type solid)
		)
		(fill yes)
		(layer "F.Cu")
		(net "M_E_CPU1_SA_DQ<20>")
	)
	(gr_poly
		(pts
			(xy 145.67916 -280.89352) (xy 145.67916 -280.70302) (xy 145.57756 -280.666698) (xy 145.52676 -280.666698)
			(xy 145.52676 -280.929842) (xy 145.57756 -280.929842)
		)
		(stroke
			(width 0)
			(type solid)
		)
		(fill yes)
		(layer "F.Cu")
		(net "M_E_CPU1_SA_DQ<20>")
	)
	(gr_poly
		(pts
			(xy 145.68297 -270.42872) (xy 145.718784 -270.392652) (xy 145.532856 -270.206724) (xy 145.497042 -270.242792)
			(xy 145.450814 -270.340074) (xy 145.585434 -270.474948)
		)
		(stroke
			(width 0)
			(type solid)
		)
		(fill yes)
		(layer "F.Cu")
		(net "M_E_CPU1_SA_DQ<28>")
	)
	(gr_poly
		(pts
			(xy 145.68678 -237.15345) (xy 145.650966 -237.117382) (xy 145.55343 -237.071154) (xy 145.41881 -237.206028)
			(xy 145.465038 -237.30331) (xy 145.500852 -237.339378)
		)
		(stroke
			(width 0)
			(type solid)
		)
		(fill yes)
		(layer "F.Cu")
		(net "M_E_CPU1_SB_CB<1>")
	)
	(gr_poly
		(pts
			(xy 145.692368 -269.575026) (xy 145.728182 -269.539212) (xy 145.542254 -269.353284) (xy 145.50644 -269.389352)
			(xy 145.460212 -269.486634) (xy 145.594832 -269.621508)
		)
		(stroke
			(width 0)
			(type solid)
		)
		(fill yes)
		(layer "F.Cu")
		(net "M_E_CPU1_SA_DQ<29>")
	)
	(gr_poly
		(pts
			(xy 145.696178 -238.006636) (xy 145.66011 -237.970822) (xy 145.562828 -237.924594) (xy 145.427954 -238.059214)
			(xy 145.474182 -238.15675) (xy 145.51025 -238.192564)
		)
		(stroke
			(width 0)
			(type solid)
		)
		(fill yes)
		(layer "F.Cu")
		(net "M_E_CPU1_SB_CB<0>")
	)
	(gr_poly
		(pts
			(xy 145.70329 -229.196138) (xy 145.657062 -229.098602) (xy 145.621248 -229.062788) (xy 145.43532 -229.248716)
			(xy 145.471134 -229.28453) (xy 145.56867 -229.330758)
		)
		(stroke
			(width 0)
			(type solid)
		)
		(fill yes)
		(layer "F.Cu")
		(net "M_E_CPU1_SB_DQ<19>")
	)
	(gr_poly
		(pts
			(xy 145.708878 -279.27554) (xy 145.801334 -279.220168) (xy 145.763996 -279.033224) (xy 145.657316 -279.01773)
			(xy 145.607278 -279.027636) (xy 145.659094 -279.285446)
		)
		(stroke
			(width 0)
			(type solid)
		)
		(fill yes)
		(layer "F.Cu")
		(net "M_E_CPU1_SA_DQ<22>")
	)
	(gr_poly
		(pts
			(xy 145.712688 -230.049578) (xy 145.66646 -229.952042) (xy 145.630392 -229.916228) (xy 145.444464 -230.102156)
			(xy 145.480532 -230.13797) (xy 145.577814 -230.184198)
		)
		(stroke
			(width 0)
			(type solid)
		)
		(fill yes)
		(layer "F.Cu")
		(net "M_E_CPU1_SB_DQ<18>")
	)
	(gr_poly
		(pts
			(xy 145.71599 -264.526522) (xy 145.752058 -264.490708) (xy 145.56613 -264.30478) (xy 145.530062 -264.340594)
			(xy 145.483834 -264.43813) (xy 145.618708 -264.57275)
		)
		(stroke
			(width 0)
			(type solid)
		)
		(fill yes)
		(layer "F.Cu")
		(net "M_E_CPU1_SA_CB<6>")
	)
	(gr_poly
		(pts
			(xy 145.717514 -279.578054) (xy 145.665952 -279.320498) (xy 145.616168 -279.330404) (xy 145.523712 -279.385776)
			(xy 145.56105 -279.572466) (xy 145.66773 -279.588214)
		)
		(stroke
			(width 0)
			(type solid)
		)
		(fill yes)
		(layer "F.Cu")
		(net "M_E_CPU1_SA_DQ<22>")
	)
	(gr_poly
		(pts
			(xy 145.721324 -231.746552) (xy 145.675096 -231.64927) (xy 145.639282 -231.613202) (xy 145.453354 -231.79913)
			(xy 145.489168 -231.834944) (xy 145.586704 -231.881426)
		)
		(stroke
			(width 0)
			(type solid)
		)
		(fill yes)
		(layer "F.Cu")
		(net "M_E_CPU1_SB_DQ<13>")
	)
	(gr_poly
		(pts
			(xy 145.722086 -276.229318) (xy 145.814542 -276.173946) (xy 145.777204 -275.987002) (xy 145.670524 -275.971508)
			(xy 145.62074 -275.981414) (xy 145.672302 -276.239224)
		)
		(stroke
			(width 0)
			(type solid)
		)
		(fill yes)
		(layer "F.Cu")
		(net "M_E_CPU1_SA_DQ<23>")
	)
	(gr_poly
		(pts
			(xy 145.72361 -273.525488) (xy 145.759424 -273.48942) (xy 145.57375 -273.303746) (xy 145.537682 -273.33956)
			(xy 145.491454 -273.437096) (xy 145.626074 -273.571716)
		)
		(stroke
			(width 0)
			(type solid)
		)
		(fill yes)
		(layer "F.Cu")
		(net "M_E_CPU1_SA_DQ<26>")
	)
	(gr_poly
		(pts
			(xy 145.725388 -263.673082) (xy 145.761202 -263.637268) (xy 145.575274 -263.45134) (xy 145.53946 -263.487408)
			(xy 145.493232 -263.58469) (xy 145.627852 -263.71931)
		)
		(stroke
			(width 0)
			(type solid)
		)
		(fill yes)
		(layer "F.Cu")
		(net "M_E_CPU1_SA_CB<7>")
	)
	(gr_poly
		(pts
			(xy 145.725896 -268.275308) (xy 145.772124 -268.177772) (xy 145.637504 -268.043152) (xy 145.540222 -268.08938)
			(xy 145.504154 -268.125194) (xy 145.690082 -268.311122)
		)
		(stroke
			(width 0)
			(type solid)
		)
		(fill yes)
		(layer "F.Cu")
		(net "M_E_CPU1_SA_CB<0>")
	)
	(gr_poly
		(pts
			(xy 145.730722 -276.531832) (xy 145.67916 -276.274022) (xy 145.629376 -276.284182) (xy 145.53692 -276.339554)
			(xy 145.574258 -276.526244) (xy 145.680938 -276.541738)
		)
		(stroke
			(width 0)
			(type solid)
		)
		(fill yes)
		(layer "F.Cu")
		(net "M_E_CPU1_SA_DQ<23>")
	)
	(gr_poly
		(pts
			(xy 145.730722 -232.599992) (xy 145.684494 -232.502456) (xy 145.648426 -232.466642) (xy 145.462498 -232.65257)
			(xy 145.498566 -232.688384) (xy 145.595848 -232.734612)
		)
		(stroke
			(width 0)
			(type solid)
		)
		(fill yes)
		(layer "F.Cu")
		(net "M_E_CPU1_SB_DQ<12>")
	)
	(gr_poly
		(pts
			(xy 145.732754 -272.672048) (xy 145.768568 -272.63598) (xy 145.582894 -272.450306) (xy 145.546826 -272.48612)
			(xy 145.500598 -272.583656) (xy 145.635218 -272.718276)
		)
		(stroke
			(width 0)
			(type solid)
		)
		(fill yes)
		(layer "F.Cu")
		(net "M_E_CPU1_SA_DQ<27>")
	)
	(gr_poly
		(pts
			(xy 145.735294 -267.421868) (xy 145.781522 -267.324332) (xy 145.646648 -267.189712) (xy 145.549366 -267.23594)
			(xy 145.513298 -267.271754) (xy 145.699226 -267.457682)
		)
		(stroke
			(width 0)
			(type solid)
		)
		(fill yes)
		(layer "F.Cu")
		(net "M_E_CPU1_SA_CB<1>")
	)
	(gr_poly
		(pts
			(xy 145.755868 -235.163106) (xy 145.709386 -235.06557) (xy 145.673572 -235.029756) (xy 145.487644 -235.215684)
			(xy 145.523712 -235.251498) (xy 145.620994 -235.297726)
		)
		(stroke
			(width 0)
			(type solid)
		)
		(fill yes)
		(layer "F.Cu")
		(net "M_E_CPU1_SB_DQ<9>")
	)
	(gr_poly
		(pts
			(xy 145.759424 -269.930118) (xy 145.805652 -269.832582) (xy 145.671032 -269.697962) (xy 145.573496 -269.74419)
			(xy 145.537682 -269.780258) (xy 145.723356 -269.965932)
		)
		(stroke
			(width 0)
			(type solid)
		)
		(fill yes)
		(layer "F.Cu")
		(net "M_E_CPU1_SA_DQ<30>")
	)
	(gr_poly
		(pts
			(xy 145.764504 -236.86008) (xy 145.718276 -236.762544) (xy 145.682208 -236.72673) (xy 145.49628 -236.912658)
			(xy 145.532348 -236.948472) (xy 145.62963 -236.9947)
		)
		(stroke
			(width 0)
			(type solid)
		)
		(fill yes)
		(layer "F.Cu")
		(net "M_E_CPU1_SB_CB<3>")
	)
	(gr_poly
		(pts
			(xy 145.765012 -240.52657) (xy 145.729198 -240.490502) (xy 145.631662 -240.444274) (xy 145.497042 -240.578894)
			(xy 145.54327 -240.67643) (xy 145.579084 -240.712498)
		)
		(stroke
			(width 0)
			(type solid)
		)
		(fill yes)
		(layer "F.Cu")
		(net "M_E_CPU1_SB_CB<5>")
	)
	(gr_poly
		(pts
			(xy 145.76552 -236.017054) (xy 145.719292 -235.919772) (xy 145.683478 -235.883704) (xy 145.49755 -236.069632)
			(xy 145.533364 -236.105446) (xy 145.6309 -236.151928)
		)
		(stroke
			(width 0)
			(type solid)
		)
		(fill yes)
		(layer "F.Cu")
		(net "M_E_CPU1_SB_DQ<8>")
	)
	(gr_poly
		(pts
			(xy 145.768822 -269.076424) (xy 145.81505 -268.979142) (xy 145.68043 -268.844268) (xy 145.582894 -268.890496)
			(xy 145.54708 -268.926564) (xy 145.733008 -269.112492)
		)
		(stroke
			(width 0)
			(type solid)
		)
		(fill yes)
		(layer "F.Cu")
		(net "M_E_CPU1_SA_DQ<31>")
	)
	(gr_poly
		(pts
			(xy 145.773648 -237.71352) (xy 145.72742 -237.615984) (xy 145.691352 -237.58017) (xy 145.505678 -237.765844)
			(xy 145.541492 -237.801912) (xy 145.639028 -237.84814)
		)
		(stroke
			(width 0)
			(type solid)
		)
		(fill yes)
		(layer "F.Cu")
		(net "M_E_CPU1_SB_CB<2>")
	)
	(gr_poly
		(pts
			(xy 145.774156 -278.04491) (xy 145.866612 -277.989538) (xy 145.829274 -277.802848) (xy 145.722594 -277.787354)
			(xy 145.67281 -277.79726) (xy 145.724372 -278.05507)
		)
		(stroke
			(width 0)
			(type solid)
		)
		(fill yes)
		(layer "F.Cu")
		(net "M_E_CPU1_SA_DQ<21>")
	)
	(gr_poly
		(pts
			(xy 145.77441 -241.379756) (xy 145.738342 -241.343942) (xy 145.64106 -241.297714) (xy 145.506186 -241.432334)
			(xy 145.552414 -241.52987) (xy 145.588482 -241.565684)
		)
		(stroke
			(width 0)
			(type solid)
		)
		(fill yes)
		(layer "F.Cu")
		(net "M_E_CPU1_SB_CB<4>")
	)
	(gr_poly
		(pts
			(xy 145.782792 -278.347678) (xy 145.73123 -278.089868) (xy 145.681446 -278.099774) (xy 145.58899 -278.155146)
			(xy 145.626328 -278.34209) (xy 145.733008 -278.357584)
		)
		(stroke
			(width 0)
			(type solid)
		)
		(fill yes)
		(layer "F.Cu")
		(net "M_E_CPU1_SA_DQ<21>")
	)
	(gr_poly
		(pts
			(xy 145.7833 -264.88136) (xy 145.829528 -264.783824) (xy 145.694908 -264.649204) (xy 145.597372 -264.695432)
			(xy 145.561558 -264.7315) (xy 145.747486 -264.917428)
		)
		(stroke
			(width 0)
			(type solid)
		)
		(fill yes)
		(layer "F.Cu")
		(net "M_E_CPU1_SA_CB<4>")
	)
	(gr_poly
		(pts
			(xy 145.792444 -264.02792) (xy 145.838672 -263.930638) (xy 145.704052 -263.795764) (xy 145.606516 -263.842246)
			(xy 145.570702 -263.87806) (xy 145.75663 -264.063988)
		)
		(stroke
			(width 0)
			(type solid)
		)
		(fill yes)
		(layer "F.Cu")
		(net "M_E_CPU1_SA_CB<5>")
	)
	(gr_poly
		(pts
			(xy 145.800064 -273.026886) (xy 145.846292 -272.92935) (xy 145.711672 -272.79473) (xy 145.614136 -272.840958)
			(xy 145.578322 -272.877026) (xy 145.763996 -273.0627)
		)
		(stroke
			(width 0)
			(type solid)
		)
		(fill yes)
		(layer "F.Cu")
		(net "M_E_CPU1_SA_DQ<25>")
	)
	(gr_poly
		(pts
			(xy 145.825718 -279.860756) (xy 145.918428 -279.805384) (xy 145.88109 -279.618694) (xy 145.774156 -279.602946)
			(xy 145.724372 -279.613106) (xy 145.775934 -279.870916)
		)
		(stroke
			(width 0)
			(type solid)
		)
		(fill yes)
		(layer "F.Cu")
		(net "M_E_CPU1_SA_DQ<22>")
	)
	(gr_poly
		(pts
			(xy 145.83156 -285.143448) (xy 145.78076 -285.143448) (xy 145.67916 -285.17977) (xy 145.67916 -285.37027)
			(xy 145.78076 -285.406338) (xy 145.83156 -285.406338)
		)
		(stroke
			(width 0)
			(type solid)
		)
		(fill yes)
		(layer "F.Cu")
		(net "M_E_CPU1_SA_DQ<22>")
	)
	(gr_poly
		(pts
			(xy 145.83156 -284.546548) (xy 145.78076 -284.546548) (xy 145.67916 -284.58287) (xy 145.67916 -284.77337)
			(xy 145.78076 -284.809438) (xy 145.83156 -284.809438)
		)
		(stroke
			(width 0)
			(type solid)
		)
		(fill yes)
		(layer "F.Cu")
		(net "M_E_CPU1_SA_DQ<22>")
	)
	(gr_poly
		(pts
			(xy 145.83156 -283.949648) (xy 145.78076 -283.949648) (xy 145.67916 -283.98597) (xy 145.67916 -284.17647)
			(xy 145.78076 -284.212538) (xy 145.83156 -284.212538)
		)
		(stroke
			(width 0)
			(type solid)
		)
		(fill yes)
		(layer "F.Cu")
		(net "M_E_CPU1_SA_DQ<22>")
	)
	(gr_poly
		(pts
			(xy 145.83156 -283.352748) (xy 145.78076 -283.352748) (xy 145.67916 -283.38907) (xy 145.67916 -283.57957)
			(xy 145.78076 -283.615638) (xy 145.83156 -283.615638)
		)
		(stroke
			(width 0)
			(type solid)
		)
		(fill yes)
		(layer "F.Cu")
		(net "M_E_CPU1_SA_DQ<22>")
	)
	(gr_poly
		(pts
			(xy 145.83156 -282.755848) (xy 145.78076 -282.755848) (xy 145.67916 -282.79217) (xy 145.67916 -282.98267)
			(xy 145.78076 -283.018738) (xy 145.83156 -283.018738)
		)
		(stroke
			(width 0)
			(type solid)
		)
		(fill yes)
		(layer "F.Cu")
		(net "M_E_CPU1_SA_DQ<22>")
	)
	(gr_poly
		(pts
			(xy 145.83156 -282.158948) (xy 145.78076 -282.158948) (xy 145.67916 -282.19527) (xy 145.67916 -282.38577)
			(xy 145.78076 -282.421838) (xy 145.83156 -282.421838)
		)
		(stroke
			(width 0)
			(type solid)
		)
		(fill yes)
		(layer "F.Cu")
		(net "M_E_CPU1_SA_DQ<22>")
	)
	(gr_poly
		(pts
			(xy 145.83156 -281.562048) (xy 145.78076 -281.562048) (xy 145.67916 -281.59837) (xy 145.67916 -281.78887)
			(xy 145.78076 -281.824938) (xy 145.83156 -281.824938)
		)
		(stroke
			(width 0)
			(type solid)
		)
		(fill yes)
		(layer "F.Cu")
		(net "M_E_CPU1_SA_DQ<22>")
	)
	(gr_poly
		(pts
			(xy 145.83156 -280.965148) (xy 145.78076 -280.965148) (xy 145.67916 -281.00147) (xy 145.67916 -281.19197)
			(xy 145.78076 -281.228038) (xy 145.83156 -281.228038)
		)
		(stroke
			(width 0)
			(type solid)
		)
		(fill yes)
		(layer "F.Cu")
		(net "M_E_CPU1_SA_DQ<22>")
	)
	(gr_poly
		(pts
			(xy 145.832322 -228.851714) (xy 145.796254 -228.8159) (xy 145.698972 -228.769672) (xy 145.564098 -228.904292)
			(xy 145.61058 -229.001828) (xy 145.646394 -229.037642)
		)
		(stroke
			(width 0)
			(type solid)
		)
		(fill yes)
		(layer "F.Cu")
		(net "M_E_CPU1_SB_DQ<19>")
	)
	(gr_poly
		(pts
			(xy 145.83918 -276.814534) (xy 145.931636 -276.759162) (xy 145.894298 -276.572472) (xy 145.787618 -276.556724)
			(xy 145.737834 -276.566884) (xy 145.789396 -276.82444)
		)
		(stroke
			(width 0)
			(type solid)
		)
		(fill yes)
		(layer "F.Cu")
		(net "M_E_CPU1_SA_DQ<23>")
	)
	(gr_poly
		(pts
			(xy 145.841466 -229.705154) (xy 145.805652 -229.669086) (xy 145.708116 -229.622858) (xy 145.573496 -229.757732)
			(xy 145.619724 -229.855014) (xy 145.655538 -229.891082)
		)
		(stroke
			(width 0)
			(type solid)
		)
		(fill yes)
		(layer "F.Cu")
		(net "M_E_CPU1_SB_DQ<18>")
	)
	(gr_poly
		(pts
			(xy 145.842736 -240.2332) (xy 145.796508 -240.135664) (xy 145.76044 -240.09985) (xy 145.574512 -240.285778)
			(xy 145.61058 -240.321592) (xy 145.707862 -240.36782)
		)
		(stroke
			(width 0)
			(type solid)
		)
		(fill yes)
		(layer "F.Cu")
		(net "M_E_CPU1_SB_CB<7>")
	)
	(gr_poly
		(pts
			(xy 145.847816 -277.117302) (xy 145.796254 -276.859492) (xy 145.74647 -276.869398) (xy 145.654014 -276.92477)
			(xy 145.691352 -277.111714) (xy 145.798032 -277.127208)
		)
		(stroke
			(width 0)
			(type solid)
		)
		(fill yes)
		(layer "F.Cu")
		(net "M_E_CPU1_SA_DQ<23>")
	)
	(gr_poly
		(pts
			(xy 145.850356 -231.402128) (xy 145.814288 -231.366314) (xy 145.717006 -231.320086) (xy 145.582132 -231.454706)
			(xy 145.62836 -231.552242) (xy 145.664428 -231.588056)
		)
		(stroke
			(width 0)
			(type solid)
		)
		(fill yes)
		(layer "F.Cu")
		(net "M_E_CPU1_SB_DQ<13>")
	)
	(gr_poly
		(pts
			(xy 145.85188 -241.08664) (xy 145.805652 -240.989104) (xy 145.769584 -240.95329) (xy 145.58391 -241.138964)
			(xy 145.619724 -241.175032) (xy 145.71726 -241.22126)
		)
		(stroke
			(width 0)
			(type solid)
		)
		(fill yes)
		(layer "F.Cu")
		(net "M_E_CPU1_SB_CB<6>")
	)
	(gr_poly
		(pts
			(xy 145.8595 -232.255568) (xy 145.823686 -232.219754) (xy 145.72615 -232.173526) (xy 145.59153 -232.308146)
			(xy 145.637758 -232.405428) (xy 145.673572 -232.441496)
		)
		(stroke
			(width 0)
			(type solid)
		)
		(fill yes)
		(layer "F.Cu")
		(net "M_E_CPU1_SB_DQ<12>")
	)
	(gr_poly
		(pts
			(xy 145.865088 -268.55801) (xy 145.901156 -268.522196) (xy 145.715228 -268.336268) (xy 145.679414 -268.372082)
			(xy 145.632932 -268.469618) (xy 145.767806 -268.604238)
		)
		(stroke
			(width 0)
			(type solid)
		)
		(fill yes)
		(layer "F.Cu")
		(net "M_E_CPU1_SA_CB<0>")
	)
	(gr_poly
		(pts
			(xy 145.874486 -267.704824) (xy 145.9103 -267.668756) (xy 145.724372 -267.482828) (xy 145.688558 -267.518896)
			(xy 145.64233 -267.616178) (xy 145.77695 -267.751052)
		)
		(stroke
			(width 0)
			(type solid)
		)
		(fill yes)
		(layer "F.Cu")
		(net "M_E_CPU1_SA_CB<1>")
	)
	(gr_poly
		(pts
			(xy 145.884646 -234.818682) (xy 145.848832 -234.782868) (xy 145.751296 -234.73664) (xy 145.616676 -234.87126)
			(xy 145.662904 -234.968796) (xy 145.698718 -235.00461)
		)
		(stroke
			(width 0)
			(type solid)
		)
		(fill yes)
		(layer "F.Cu")
		(net "M_E_CPU1_SB_DQ<9>")
	)
	(gr_poly
		(pts
			(xy 145.89125 -278.63038) (xy 145.983706 -278.575008) (xy 145.946368 -278.388064) (xy 145.839688 -278.37257)
			(xy 145.789904 -278.382476) (xy 145.841466 -278.640286)
		)
		(stroke
			(width 0)
			(type solid)
		)
		(fill yes)
		(layer "F.Cu")
		(net "M_E_CPU1_SA_DQ<21>")
	)
	(gr_poly
		(pts
			(xy 145.893282 -236.515656) (xy 145.857468 -236.479842) (xy 145.759932 -236.433614) (xy 145.625312 -236.568234)
			(xy 145.67154 -236.665516) (xy 145.707354 -236.701584)
		)
		(stroke
			(width 0)
			(type solid)
		)
		(fill yes)
		(layer "F.Cu")
		(net "M_E_CPU1_SB_CB<3>")
	)
	(gr_poly
		(pts
			(xy 145.894552 -235.67263) (xy 145.858484 -235.636816) (xy 145.761202 -235.590588) (xy 145.626328 -235.725208)
			(xy 145.672556 -235.822744) (xy 145.708624 -235.858558)
		)
		(stroke
			(width 0)
			(type solid)
		)
		(fill yes)
		(layer "F.Cu")
		(net "M_E_CPU1_SB_DQ<8>")
	)
	(gr_poly
		(pts
			(xy 145.898616 -270.213074) (xy 145.93443 -270.177006) (xy 145.748502 -269.991078) (xy 145.712688 -270.027146)
			(xy 145.66646 -270.124428) (xy 145.80108 -270.259302)
		)
		(stroke
			(width 0)
			(type solid)
		)
		(fill yes)
		(layer "F.Cu")
		(net "M_E_CPU1_SA_DQ<30>")
	)
	(gr_poly
		(pts
			(xy 145.899886 -278.932894) (xy 145.848324 -278.675084) (xy 145.79854 -278.685244) (xy 145.706084 -278.740616)
			(xy 145.743422 -278.927306) (xy 145.850102 -278.9428)
		)
		(stroke
			(width 0)
			(type solid)
		)
		(fill yes)
		(layer "F.Cu")
		(net "M_E_CPU1_SA_DQ<21>")
	)
	(gr_poly
		(pts
			(xy 145.902426 -237.369096) (xy 145.866612 -237.333028) (xy 145.769076 -237.2868) (xy 145.634456 -237.421674)
			(xy 145.680684 -237.518956) (xy 145.716498 -237.555024)
		)
		(stroke
			(width 0)
			(type solid)
		)
		(fill yes)
		(layer "F.Cu")
		(net "M_E_CPU1_SB_CB<2>")
	)
	(gr_poly
		(pts
			(xy 145.908014 -269.35938) (xy 145.944082 -269.323566) (xy 145.758154 -269.137638) (xy 145.722086 -269.173452)
			(xy 145.675858 -269.270988) (xy 145.810732 -269.405608)
		)
		(stroke
			(width 0)
			(type solid)
		)
		(fill yes)
		(layer "F.Cu")
		(net "M_E_CPU1_SA_DQ<31>")
	)
	(gr_poly
		(pts
			(xy 145.918936 -229.411784) (xy 145.872708 -229.314248) (xy 145.836894 -229.278434) (xy 145.650966 -229.464362)
			(xy 145.68678 -229.500176) (xy 145.784316 -229.546404)
		)
		(stroke
			(width 0)
			(type solid)
		)
		(fill yes)
		(layer "F.Cu")
		(net "M_E_CPU1_SB_DQ<17>")
	)
	(gr_poly
		(pts
			(xy 145.91919 -274.330414) (xy 146.011646 -274.275042) (xy 145.974308 -274.088098) (xy 145.867628 -274.072604)
			(xy 145.817844 -274.08251) (xy 145.869406 -274.34032)
		)
		(stroke
			(width 0)
			(type solid)
		)
		(fill yes)
		(layer "F.Cu")
		(net "M_E_CPU1_SA_DQ<24>")
	)
	(gr_poly
		(pts
			(xy 145.922492 -265.164316) (xy 145.958306 -265.128248) (xy 145.772632 -264.942574) (xy 145.736564 -264.978388)
			(xy 145.690336 -265.075924) (xy 145.824956 -265.210544)
		)
		(stroke
			(width 0)
			(type solid)
		)
		(fill yes)
		(layer "F.Cu")
		(net "M_E_CPU1_SA_CB<4>")
	)
	(gr_poly
		(pts
			(xy 145.927826 -274.632928) (xy 145.876264 -274.375118) (xy 145.82648 -274.385278) (xy 145.734024 -274.44065)
			(xy 145.771362 -274.62734) (xy 145.878042 -274.642834)
		)
		(stroke
			(width 0)
			(type solid)
		)
		(fill yes)
		(layer "F.Cu")
		(net "M_E_CPU1_SA_DQ<24>")
	)
	(gr_poly
		(pts
			(xy 145.927826 -231.108758) (xy 145.881598 -231.011476) (xy 145.845784 -230.975408) (xy 145.659856 -231.161336)
			(xy 145.69567 -231.197404) (xy 145.793206 -231.243632)
		)
		(stroke
			(width 0)
			(type solid)
		)
		(fill yes)
		(layer "F.Cu")
		(net "M_E_CPU1_SB_DQ<15>")
	)
	(gr_poly
		(pts
			(xy 145.928334 -230.265224) (xy 145.882106 -230.167688) (xy 145.846038 -230.131874) (xy 145.66011 -230.317802)
			(xy 145.696178 -230.353616) (xy 145.79346 -230.399844)
		)
		(stroke
			(width 0)
			(type solid)
		)
		(fill yes)
		(layer "F.Cu")
		(net "M_E_CPU1_SB_DQ<16>")
	)
	(gr_poly
		(pts
			(xy 145.931636 -264.310876) (xy 145.967704 -264.275062) (xy 145.781776 -264.089134) (xy 145.745708 -264.124948)
			(xy 145.69948 -264.222484) (xy 145.834354 -264.357104)
		)
		(stroke
			(width 0)
			(type solid)
		)
		(fill yes)
		(layer "F.Cu")
		(net "M_E_CPU1_SA_CB<5>")
	)
	(gr_poly
		(pts
			(xy 145.93697 -231.962198) (xy 145.890742 -231.864916) (xy 145.854928 -231.828848) (xy 145.669 -232.014776)
			(xy 145.704814 -232.05059) (xy 145.80235 -232.097072)
		)
		(stroke
			(width 0)
			(type solid)
		)
		(fill yes)
		(layer "F.Cu")
		(net "M_E_CPU1_SB_DQ<14>")
	)
	(gr_poly
		(pts
			(xy 145.939256 -273.309842) (xy 145.97507 -273.273774) (xy 145.789142 -273.087846) (xy 145.753328 -273.123914)
			(xy 145.7071 -273.221196) (xy 145.84172 -273.35607)
		)
		(stroke
			(width 0)
			(type solid)
		)
		(fill yes)
		(layer "F.Cu")
		(net "M_E_CPU1_SA_DQ<25>")
	)
	(gr_poly
		(pts
			(xy 145.941542 -268.059662) (xy 145.98777 -267.962126) (xy 145.85315 -267.827506) (xy 145.755868 -267.873734)
			(xy 145.7198 -267.909548) (xy 145.905728 -268.095476)
		)
		(stroke
			(width 0)
			(type solid)
		)
		(fill yes)
		(layer "F.Cu")
		(net "M_E_CPU1_SA_CB<2>")
	)
	(gr_poly
		(pts
			(xy 145.95094 -267.206222) (xy 145.997168 -267.108686) (xy 145.862294 -266.974066) (xy 145.765012 -267.020294)
			(xy 145.728944 -267.056108) (xy 145.914872 -267.242036)
		)
		(stroke
			(width 0)
			(type solid)
		)
		(fill yes)
		(layer "F.Cu")
		(net "M_E_CPU1_SA_CB<3>")
	)
	(gr_poly
		(pts
			(xy 145.956274 -277.400004) (xy 146.04873 -277.344378) (xy 146.011392 -277.157688) (xy 145.904712 -277.142194)
			(xy 145.854928 -277.1521) (xy 145.90649 -277.40991)
		)
		(stroke
			(width 0)
			(type solid)
		)
		(fill yes)
		(layer "F.Cu")
		(net "M_E_CPU1_SA_DQ<23>")
	)
	(gr_poly
		(pts
			(xy 145.961862 -234.525058) (xy 145.915634 -234.427776) (xy 145.87982 -234.391708) (xy 145.693892 -234.577636)
			(xy 145.729706 -234.613704) (xy 145.827242 -234.659932)
		)
		(stroke
			(width 0)
			(type solid)
		)
		(fill yes)
		(layer "F.Cu")
		(net "M_E_CPU1_SB_DQ<11>")
	)
	(gr_poly
		(pts
			(xy 145.96491 -277.702518) (xy 145.913348 -277.444708) (xy 145.863564 -277.454614) (xy 145.771108 -277.509986)
			(xy 145.808446 -277.69693) (xy 145.915126 -277.712424)
		)
		(stroke
			(width 0)
			(type solid)
		)
		(fill yes)
		(layer "F.Cu")
		(net "M_E_CPU1_SA_DQ<23>")
	)
	(gr_poly
		(pts
			(xy 145.965926 -270.567912) (xy 146.012154 -270.470376) (xy 145.87728 -270.335756) (xy 145.779998 -270.381984)
			(xy 145.74393 -270.417798) (xy 145.929858 -270.603726)
		)
		(stroke
			(width 0)
			(type solid)
		)
		(fill yes)
		(layer "F.Cu")
		(net "M_E_CPU1_SA_DQ<28>")
	)
	(gr_poly
		(pts
			(xy 145.971514 -239.888776) (xy 145.9357 -239.852962) (xy 145.838164 -239.80648) (xy 145.703544 -239.941354)
			(xy 145.749772 -240.038636) (xy 145.785586 -240.074704)
		)
		(stroke
			(width 0)
			(type solid)
		)
		(fill yes)
		(layer "F.Cu")
		(net "M_E_CPU1_SB_CB<7>")
	)
	(gr_poly
		(pts
			(xy 145.972022 -235.37926) (xy 145.92554 -235.281724) (xy 145.889726 -235.24591) (xy 145.703798 -235.431838)
			(xy 145.739866 -235.467652) (xy 145.837148 -235.51388)
		)
		(stroke
			(width 0)
			(type solid)
		)
		(fill yes)
		(layer "F.Cu")
		(net "M_E_CPU1_SB_DQ<10>")
	)
	(gr_poly
		(pts
			(xy 145.97507 -269.714218) (xy 146.021298 -269.616936) (xy 145.886678 -269.482316) (xy 145.789142 -269.528544)
			(xy 145.753328 -269.564358) (xy 145.939256 -269.750286)
		)
		(stroke
			(width 0)
			(type solid)
		)
		(fill yes)
		(layer "F.Cu")
		(net "M_E_CPU1_SA_DQ<29>")
	)
	(gr_poly
		(pts
			(xy 145.98015 -237.075726) (xy 145.933922 -236.97819) (xy 145.897854 -236.942376) (xy 145.711926 -237.128304)
			(xy 145.747994 -237.164118) (xy 145.845276 -237.210346)
		)
		(stroke
			(width 0)
			(type solid)
		)
		(fill yes)
		(layer "F.Cu")
		(net "M_E_CPU1_SB_CB<1>")
	)
	(gr_poly
		(pts
			(xy 145.980658 -240.742216) (xy 145.944844 -240.706148) (xy 145.847308 -240.65992) (xy 145.712688 -240.79454)
			(xy 145.758916 -240.892076) (xy 145.79473 -240.928144)
		)
		(stroke
			(width 0)
			(type solid)
		)
		(fill yes)
		(layer "F.Cu")
		(net "M_E_CPU1_SB_CB<6>")
	)
	(gr_poly
		(pts
			(xy 145.98396 -285.07182) (xy 145.98396 -284.88132) (xy 145.88236 -284.844998) (xy 145.83156 -284.844998)
			(xy 145.83156 -285.108142) (xy 145.88236 -285.108142)
		)
		(stroke
			(width 0)
			(type solid)
		)
		(fill yes)
		(layer "F.Cu")
		(net "M_E_CPU1_SA_DQ<22>")
	)
	(gr_poly
		(pts
			(xy 145.98396 -284.47492) (xy 145.98396 -284.28442) (xy 145.88236 -284.248098) (xy 145.83156 -284.248098)
			(xy 145.83156 -284.511242) (xy 145.88236 -284.511242)
		)
		(stroke
			(width 0)
			(type solid)
		)
		(fill yes)
		(layer "F.Cu")
		(net "M_E_CPU1_SA_DQ<22>")
	)
	(gr_poly
		(pts
			(xy 145.98396 -283.87802) (xy 145.98396 -283.68752) (xy 145.88236 -283.651198) (xy 145.83156 -283.651198)
			(xy 145.83156 -283.914342) (xy 145.88236 -283.914342)
		)
		(stroke
			(width 0)
			(type solid)
		)
		(fill yes)
		(layer "F.Cu")
		(net "M_E_CPU1_SA_DQ<22>")
	)
	(gr_poly
		(pts
			(xy 145.98396 -283.28112) (xy 145.98396 -283.09062) (xy 145.88236 -283.054298) (xy 145.83156 -283.054298)
			(xy 145.83156 -283.317442) (xy 145.88236 -283.317442)
		)
		(stroke
			(width 0)
			(type solid)
		)
		(fill yes)
		(layer "F.Cu")
		(net "M_E_CPU1_SA_DQ<22>")
	)
	(gr_poly
		(pts
			(xy 145.98396 -282.68422) (xy 145.98396 -282.49372) (xy 145.88236 -282.457398) (xy 145.83156 -282.457398)
			(xy 145.83156 -282.720542) (xy 145.88236 -282.720542)
		)
		(stroke
			(width 0)
			(type solid)
		)
		(fill yes)
		(layer "F.Cu")
		(net "M_E_CPU1_SA_DQ<22>")
	)
	(gr_poly
		(pts
			(xy 145.98396 -282.08732) (xy 145.98396 -281.89682) (xy 145.88236 -281.860498) (xy 145.83156 -281.860498)
			(xy 145.83156 -282.123642) (xy 145.88236 -282.123642)
		)
		(stroke
			(width 0)
			(type solid)
		)
		(fill yes)
		(layer "F.Cu")
		(net "M_E_CPU1_SA_DQ<22>")
	)
	(gr_poly
		(pts
			(xy 145.98396 -281.49042) (xy 145.98396 -281.29992) (xy 145.88236 -281.263598) (xy 145.83156 -281.263598)
			(xy 145.83156 -281.526742) (xy 145.88236 -281.526742)
		)
		(stroke
			(width 0)
			(type solid)
		)
		(fill yes)
		(layer "F.Cu")
		(net "M_E_CPU1_SA_DQ<22>")
	)
	(gr_poly
		(pts
			(xy 145.98396 -280.89352) (xy 145.98396 -280.70302) (xy 145.88236 -280.666698) (xy 145.83156 -280.666698)
			(xy 145.83156 -280.929842) (xy 145.88236 -280.929842)
		)
		(stroke
			(width 0)
			(type solid)
		)
		(fill yes)
		(layer "F.Cu")
		(net "M_E_CPU1_SA_DQ<22>")
	)
	(gr_poly
		(pts
			(xy 145.989294 -237.929166) (xy 145.943066 -237.83163) (xy 145.906998 -237.795816) (xy 145.721324 -237.98149)
			(xy 145.757138 -238.017558) (xy 145.854674 -238.063786)
		)
		(stroke
			(width 0)
			(type solid)
		)
		(fill yes)
		(layer "F.Cu")
		(net "M_E_CPU1_SB_CB<0>")
	)
	(gr_poly
		(pts
			(xy 145.998946 -264.665714) (xy 146.045174 -264.568178) (xy 145.910554 -264.433558) (xy 145.813018 -264.479786)
			(xy 145.777204 -264.515854) (xy 145.963132 -264.701782)
		)
		(stroke
			(width 0)
			(type solid)
		)
		(fill yes)
		(layer "F.Cu")
		(net "M_E_CPU1_SA_CB<6>")
	)
	(gr_poly
		(pts
			(xy 146.006566 -273.66468) (xy 146.052794 -273.567144) (xy 145.91792 -273.432524) (xy 145.820638 -273.478752)
			(xy 145.78457 -273.514566) (xy 145.970498 -273.700494)
		)
		(stroke
			(width 0)
			(type solid)
		)
		(fill yes)
		(layer "F.Cu")
		(net "M_E_CPU1_SA_DQ<26>")
	)
	(gr_poly
		(pts
			(xy 146.00809 -263.812274) (xy 146.054318 -263.714992) (xy 145.919698 -263.580118) (xy 145.822162 -263.6266)
			(xy 145.786348 -263.662414) (xy 145.972276 -263.848342)
		)
		(stroke
			(width 0)
			(type solid)
		)
		(fill yes)
		(layer "F.Cu")
		(net "M_E_CPU1_SA_CB<7>")
	)
	(gr_poly
		(pts
			(xy 146.008344 -279.215596) (xy 146.1008 -279.160224) (xy 146.063462 -278.973534) (xy 145.956782 -278.957786)
			(xy 145.906998 -278.967692) (xy 145.95856 -279.225502)
		)
		(stroke
			(width 0)
			(type solid)
		)
		(fill yes)
		(layer "F.Cu")
		(net "M_E_CPU1_SA_DQ<21>")
	)
	(gr_poly
		(pts
			(xy 146.01571 -272.81124) (xy 146.061938 -272.713704) (xy 145.927064 -272.579084) (xy 145.829782 -272.625312)
			(xy 145.793714 -272.661126) (xy 145.979642 -272.847054)
		)
		(stroke
			(width 0)
			(type solid)
		)
		(fill yes)
		(layer "F.Cu")
		(net "M_E_CPU1_SA_DQ<27>")
	)
	(gr_poly
		(pts
			(xy 146.01698 -279.518364) (xy 145.965418 -279.260554) (xy 145.915634 -279.27046) (xy 145.823178 -279.325832)
			(xy 145.860516 -279.512522) (xy 145.967196 -279.52827)
		)
		(stroke
			(width 0)
			(type solid)
		)
		(fill yes)
		(layer "F.Cu")
		(net "M_E_CPU1_SA_DQ<21>")
	)
	(gr_poly
		(pts
			(xy 146.036284 -274.91563) (xy 146.12874 -274.860258) (xy 146.091402 -274.673568) (xy 145.984722 -274.65782)
			(xy 145.934938 -274.66798) (xy 145.9865 -274.925536)
		)
		(stroke
			(width 0)
			(type solid)
		)
		(fill yes)
		(layer "F.Cu")
		(net "M_E_CPU1_SA_DQ<24>")
	)
	(gr_poly
		(pts
			(xy 146.04492 -275.218398) (xy 145.993358 -274.960588) (xy 145.943574 -274.970494) (xy 145.851118 -275.025866)
			(xy 145.888456 -275.21281) (xy 145.995136 -275.228304)
		)
		(stroke
			(width 0)
			(type solid)
		)
		(fill yes)
		(layer "F.Cu")
		(net "M_E_CPU1_SA_DQ<24>")
	)
	(gr_poly
		(pts
			(xy 146.047968 -229.06736) (xy 146.0119 -229.031546) (xy 145.914618 -228.985318) (xy 145.779744 -229.119938)
			(xy 145.826226 -229.217474) (xy 145.86204 -229.253288)
		)
		(stroke
			(width 0)
			(type solid)
		)
		(fill yes)
		(layer "F.Cu")
		(net "M_E_CPU1_SB_DQ<17>")
	)
	(gr_poly
		(pts
			(xy 146.056604 -230.764588) (xy 146.02079 -230.72852) (xy 145.923254 -230.682292) (xy 145.788634 -230.816912)
			(xy 145.834862 -230.914448) (xy 145.87093 -230.950262)
		)
		(stroke
			(width 0)
			(type solid)
		)
		(fill yes)
		(layer "F.Cu")
		(net "M_E_CPU1_SB_DQ<15>")
	)
	(gr_poly
		(pts
			(xy 146.057112 -229.9208) (xy 146.021298 -229.884732) (xy 145.923762 -229.838504) (xy 145.789142 -229.973378)
			(xy 145.83537 -230.07066) (xy 145.871184 -230.106728)
		)
		(stroke
			(width 0)
			(type solid)
		)
		(fill yes)
		(layer "F.Cu")
		(net "M_E_CPU1_SB_DQ<16>")
	)
	(gr_poly
		(pts
			(xy 146.057112 -227.922074) (xy 146.006312 -227.922074) (xy 145.904712 -227.958142) (xy 145.904712 -228.148642)
			(xy 146.006312 -228.184964) (xy 146.057112 -228.184964)
		)
		(stroke
			(width 0)
			(type solid)
		)
		(fill yes)
		(layer "F.Cu")
		(net "M_E_CPU1_SB_DQ<19>")
	)
	(gr_poly
		(pts
			(xy 146.057112 -227.325174) (xy 146.006312 -227.325174) (xy 145.904712 -227.361242) (xy 145.904712 -227.551742)
			(xy 146.006312 -227.588064) (xy 146.057112 -227.588064)
		)
		(stroke
			(width 0)
			(type solid)
		)
		(fill yes)
		(layer "F.Cu")
		(net "M_E_CPU1_SB_DQ<19>")
	)
	(gr_poly
		(pts
			(xy 146.057112 -226.728274) (xy 146.006312 -226.728274) (xy 145.904712 -226.764342) (xy 145.904712 -226.954842)
			(xy 146.006312 -226.991164) (xy 146.057112 -226.991164)
		)
		(stroke
			(width 0)
			(type solid)
		)
		(fill yes)
		(layer "F.Cu")
		(net "M_E_CPU1_SB_DQ<19>")
	)
	(gr_poly
		(pts
			(xy 146.057112 -226.131374) (xy 146.006312 -226.131374) (xy 145.904712 -226.167442) (xy 145.904712 -226.357942)
			(xy 146.006312 -226.394264) (xy 146.057112 -226.394264)
		)
		(stroke
			(width 0)
			(type solid)
		)
		(fill yes)
		(layer "F.Cu")
		(net "M_E_CPU1_SB_DQ<19>")
	)
	(gr_poly
		(pts
			(xy 146.057112 -225.534474) (xy 146.006312 -225.534474) (xy 145.904712 -225.570542) (xy 145.904712 -225.761042)
			(xy 146.006312 -225.797364) (xy 146.057112 -225.797364)
		)
		(stroke
			(width 0)
			(type solid)
		)
		(fill yes)
		(layer "F.Cu")
		(net "M_E_CPU1_SB_DQ<19>")
	)
	(gr_poly
		(pts
			(xy 146.057112 -224.937574) (xy 146.006312 -224.937574) (xy 145.904712 -224.973642) (xy 145.904712 -225.164142)
			(xy 146.006312 -225.200464) (xy 146.057112 -225.200464)
		)
		(stroke
			(width 0)
			(type solid)
		)
		(fill yes)
		(layer "F.Cu")
		(net "M_E_CPU1_SB_DQ<19>")
	)
	(gr_poly
		(pts
			(xy 146.057112 -224.340674) (xy 146.006312 -224.340674) (xy 145.904712 -224.376742) (xy 145.904712 -224.567242)
			(xy 146.006312 -224.603564) (xy 146.057112 -224.603564)
		)
		(stroke
			(width 0)
			(type solid)
		)
		(fill yes)
		(layer "F.Cu")
		(net "M_E_CPU1_SB_DQ<19>")
	)
	(gr_poly
		(pts
			(xy 146.057112 -223.743774) (xy 146.006312 -223.743774) (xy 145.904712 -223.779842) (xy 145.904712 -223.970342)
			(xy 146.006312 -224.006664) (xy 146.057112 -224.006664)
		)
		(stroke
			(width 0)
			(type solid)
		)
		(fill yes)
		(layer "F.Cu")
		(net "M_E_CPU1_SB_DQ<19>")
	)
	(gr_poly
		(pts
			(xy 146.057112 -223.146874) (xy 146.006312 -223.146874) (xy 145.904712 -223.182942) (xy 145.904712 -223.373442)
			(xy 146.006312 -223.409764) (xy 146.057112 -223.409764)
		)
		(stroke
			(width 0)
			(type solid)
		)
		(fill yes)
		(layer "F.Cu")
		(net "M_E_CPU1_SB_DQ<19>")
	)
	(gr_poly
		(pts
			(xy 146.057112 -222.549974) (xy 146.006312 -222.549974) (xy 145.904712 -222.586042) (xy 145.904712 -222.776542)
			(xy 146.006312 -222.812864) (xy 146.057112 -222.812864)
		)
		(stroke
			(width 0)
			(type solid)
		)
		(fill yes)
		(layer "F.Cu")
		(net "M_E_CPU1_SB_DQ<19>")
	)
	(gr_poly
		(pts
			(xy 146.057112 -221.953074) (xy 146.006312 -221.953074) (xy 145.904712 -221.989142) (xy 145.904712 -222.179642)
			(xy 146.006312 -222.215964) (xy 146.057112 -222.215964)
		)
		(stroke
			(width 0)
			(type solid)
		)
		(fill yes)
		(layer "F.Cu")
		(net "M_E_CPU1_SB_DQ<19>")
	)
	(gr_poly
		(pts
			(xy 146.057112 -221.356174) (xy 146.006312 -221.356174) (xy 145.904712 -221.392242) (xy 145.904712 -221.582742)
			(xy 146.006312 -221.619064) (xy 146.057112 -221.619064)
		)
		(stroke
			(width 0)
			(type solid)
		)
		(fill yes)
		(layer "F.Cu")
		(net "M_E_CPU1_SB_DQ<19>")
	)
	(gr_poly
		(pts
			(xy 146.057112 -220.759274) (xy 146.006312 -220.759274) (xy 145.904712 -220.795342) (xy 145.904712 -220.985842)
			(xy 146.006312 -221.022164) (xy 146.057112 -221.022164)
		)
		(stroke
			(width 0)
			(type solid)
		)
		(fill yes)
		(layer "F.Cu")
		(net "M_E_CPU1_SB_DQ<19>")
	)
	(gr_poly
		(pts
			(xy 146.057112 -220.162374) (xy 146.006312 -220.162374) (xy 145.904712 -220.198442) (xy 145.904712 -220.388942)
			(xy 146.006312 -220.425264) (xy 146.057112 -220.425264)
		)
		(stroke
			(width 0)
			(type solid)
		)
		(fill yes)
		(layer "F.Cu")
		(net "M_E_CPU1_SB_DQ<19>")
	)
	(gr_poly
		(pts
			(xy 146.057112 -219.565474) (xy 146.006312 -219.565474) (xy 145.904712 -219.601542) (xy 145.904712 -219.792042)
			(xy 146.006312 -219.828364) (xy 146.057112 -219.828364)
		)
		(stroke
			(width 0)
			(type solid)
		)
		(fill yes)
		(layer "F.Cu")
		(net "M_E_CPU1_SB_DQ<19>")
	)
	(gr_poly
		(pts
			(xy 146.058382 -240.448846) (xy 146.012154 -240.35131) (xy 145.976086 -240.315496) (xy 145.790158 -240.501424)
			(xy 145.826226 -240.537238) (xy 145.923508 -240.583466)
		)
		(stroke
			(width 0)
			(type solid)
		)
		(fill yes)
		(layer "F.Cu")
		(net "M_E_CPU1_SB_CB<5>")
	)
	(gr_poly
		(pts
			(xy 146.066002 -231.617774) (xy 146.029934 -231.58196) (xy 145.932652 -231.535732) (xy 145.797778 -231.670352)
			(xy 145.844006 -231.767888) (xy 145.880074 -231.803702)
		)
		(stroke
			(width 0)
			(type solid)
		)
		(fill yes)
		(layer "F.Cu")
		(net "M_E_CPU1_SB_DQ<14>")
	)
	(gr_poly
		(pts
			(xy 146.073368 -277.98522) (xy 146.165824 -277.929848) (xy 146.128486 -277.742904) (xy 146.021806 -277.72741)
			(xy 145.971768 -277.737316) (xy 146.02333 -277.995126)
		)
		(stroke
			(width 0)
			(type solid)
		)
		(fill yes)
		(layer "F.Cu")
		(net "M_E_CPU1_SA_DQ<23>")
	)
	(gr_poly
		(pts
			(xy 146.080734 -268.342364) (xy 146.116802 -268.30655) (xy 145.930874 -268.120622) (xy 145.89506 -268.156436)
			(xy 145.848578 -268.253972) (xy 145.983452 -268.388592)
		)
		(stroke
			(width 0)
			(type solid)
		)
		(fill yes)
		(layer "F.Cu")
		(net "M_E_CPU1_SA_CB<2>")
	)
	(gr_poly
		(pts
			(xy 146.082004 -278.287734) (xy 146.030442 -278.029924) (xy 145.980658 -278.040084) (xy 145.888202 -278.095456)
			(xy 145.92554 -278.282146) (xy 146.03222 -278.297894)
		)
		(stroke
			(width 0)
			(type solid)
		)
		(fill yes)
		(layer "F.Cu")
		(net "M_E_CPU1_SA_DQ<23>")
	)
	(gr_poly
		(pts
			(xy 146.090132 -267.489178) (xy 146.125946 -267.45311) (xy 145.940018 -267.267182) (xy 145.904204 -267.30325)
			(xy 145.857976 -267.400532) (xy 145.992596 -267.535406)
		)
		(stroke
			(width 0)
			(type solid)
		)
		(fill yes)
		(layer "F.Cu")
		(net "M_E_CPU1_SA_CB<3>")
	)
	(gr_poly
		(pts
			(xy 146.090894 -234.180634) (xy 146.054826 -234.14482) (xy 145.957544 -234.098592) (xy 145.82267 -234.233212)
			(xy 145.868898 -234.330748) (xy 145.904966 -234.366562)
		)
		(stroke
			(width 0)
			(type solid)
		)
		(fill yes)
		(layer "F.Cu")
		(net "M_E_CPU1_SB_DQ<11>")
	)
	(gr_poly
		(pts
			(xy 146.1008 -235.034836) (xy 146.064732 -234.999022) (xy 145.96745 -234.952794) (xy 145.83283 -235.087414)
			(xy 145.879058 -235.18495) (xy 145.914872 -235.220764)
		)
		(stroke
			(width 0)
			(type solid)
		)
		(fill yes)
		(layer "F.Cu")
		(net "M_E_CPU1_SB_DQ<10>")
	)
	(gr_poly
		(pts
			(xy 146.105118 -270.850614) (xy 146.140932 -270.8148) (xy 145.955004 -270.628872) (xy 145.91919 -270.664686)
			(xy 145.872962 -270.762222) (xy 146.007582 -270.896842)
		)
		(stroke
			(width 0)
			(type solid)
		)
		(fill yes)
		(layer "F.Cu")
		(net "M_E_CPU1_SA_DQ<28>")
	)
	(gr_poly
		(pts
			(xy 146.108928 -236.731302) (xy 146.073114 -236.695488) (xy 145.975578 -236.64926) (xy 145.840958 -236.78388)
			(xy 145.887186 -236.881162) (xy 145.923 -236.91723)
		)
		(stroke
			(width 0)
			(type solid)
		)
		(fill yes)
		(layer "F.Cu")
		(net "M_E_CPU1_SB_CB<1>")
	)
	(gr_poly
		(pts
			(xy 146.114262 -269.997174) (xy 146.15033 -269.96136) (xy 145.964402 -269.775432) (xy 145.928334 -269.811246)
			(xy 145.882106 -269.908782) (xy 146.01698 -270.043402)
		)
		(stroke
			(width 0)
			(type solid)
		)
		(fill yes)
		(layer "F.Cu")
		(net "M_E_CPU1_SA_DQ<29>")
	)
	(gr_poly
		(pts
			(xy 146.118072 -237.584742) (xy 146.082258 -237.548674) (xy 145.984722 -237.502446) (xy 145.850102 -237.63732)
			(xy 145.89633 -237.734602) (xy 145.932144 -237.77067)
		)
		(stroke
			(width 0)
			(type solid)
		)
		(fill yes)
		(layer "F.Cu")
		(net "M_E_CPU1_SB_CB<0>")
	)
	(gr_poly
		(pts
			(xy 146.125438 -279.800812) (xy 146.217894 -279.74544) (xy 146.180556 -279.55875) (xy 146.073876 -279.543256)
			(xy 146.024092 -279.553162) (xy 146.075654 -279.810972)
		)
		(stroke
			(width 0)
			(type solid)
		)
		(fill yes)
		(layer "F.Cu")
		(net "M_E_CPU1_SA_DQ<21>")
	)
	(gr_poly
		(pts
			(xy 146.134582 -229.62743) (xy 146.088354 -229.529894) (xy 146.05254 -229.49408) (xy 145.866612 -229.680008)
			(xy 145.902426 -229.715822) (xy 145.999962 -229.76205)
		)
		(stroke
			(width 0)
			(type solid)
		)
		(fill yes)
		(layer "F.Cu")
		(net "M_E_CPU1_SB_DQ<18>")
	)
	(gr_poly
		(pts
			(xy 146.13636 -283.949648) (xy 146.08556 -283.949648) (xy 145.98396 -283.98597) (xy 145.98396 -284.17647)
			(xy 146.08556 -284.212538) (xy 146.13636 -284.212538)
		)
		(stroke
			(width 0)
			(type solid)
		)
		(fill yes)
		(layer "F.Cu")
		(net "M_E_CPU1_SA_DQ<21>")
	)
	(gr_poly
		(pts
			(xy 146.13636 -283.352748) (xy 146.08556 -283.352748) (xy 145.98396 -283.38907) (xy 145.98396 -283.57957)
			(xy 146.08556 -283.615638) (xy 146.13636 -283.615638)
		)
		(stroke
			(width 0)
			(type solid)
		)
		(fill yes)
		(layer "F.Cu")
		(net "M_E_CPU1_SA_DQ<21>")
	)
	(gr_poly
		(pts
			(xy 146.13636 -282.755848) (xy 146.08556 -282.755848) (xy 145.98396 -282.79217) (xy 145.98396 -282.98267)
			(xy 146.08556 -283.018738) (xy 146.13636 -283.018738)
		)
		(stroke
			(width 0)
			(type solid)
		)
		(fill yes)
		(layer "F.Cu")
		(net "M_E_CPU1_SA_DQ<21>")
	)
	(gr_poly
		(pts
			(xy 146.13636 -282.158948) (xy 146.08556 -282.158948) (xy 145.98396 -282.19527) (xy 145.98396 -282.38577)
			(xy 146.08556 -282.421838) (xy 146.13636 -282.421838)
		)
		(stroke
			(width 0)
			(type solid)
		)
		(fill yes)
		(layer "F.Cu")
		(net "M_E_CPU1_SA_DQ<21>")
	)
	(gr_poly
		(pts
			(xy 146.13636 -281.562048) (xy 146.08556 -281.562048) (xy 145.98396 -281.59837) (xy 145.98396 -281.78887)
			(xy 146.08556 -281.824938) (xy 146.13636 -281.824938)
		)
		(stroke
			(width 0)
			(type solid)
		)
		(fill yes)
		(layer "F.Cu")
		(net "M_E_CPU1_SA_DQ<21>")
	)
	(gr_poly
		(pts
			(xy 146.13636 -280.965148) (xy 146.08556 -280.965148) (xy 145.98396 -281.00147) (xy 145.98396 -281.19197)
			(xy 146.08556 -281.228038) (xy 146.13636 -281.228038)
		)
		(stroke
			(width 0)
			(type solid)
		)
		(fill yes)
		(layer "F.Cu")
		(net "M_E_CPU1_SA_DQ<21>")
	)
	(gr_poly
		(pts
			(xy 146.13636 -280.368248) (xy 146.08556 -280.368248) (xy 145.98396 -280.40457) (xy 145.98396 -280.59507)
			(xy 146.08556 -280.631138) (xy 146.13636 -280.631138)
		)
		(stroke
			(width 0)
			(type solid)
		)
		(fill yes)
		(layer "F.Cu")
		(net "M_E_CPU1_SA_DQ<21>")
	)
	(gr_poly
		(pts
			(xy 146.138138 -264.94867) (xy 146.173952 -264.912602) (xy 145.988278 -264.726928) (xy 145.95221 -264.762742)
			(xy 145.905982 -264.860278) (xy 146.040602 -264.994898)
		)
		(stroke
			(width 0)
			(type solid)
		)
		(fill yes)
		(layer "F.Cu")
		(net "M_E_CPU1_SA_CB<6>")
	)
	(gr_poly
		(pts
			(xy 146.143472 -231.324404) (xy 146.097244 -231.227122) (xy 146.06143 -231.191054) (xy 145.875502 -231.376982)
			(xy 145.911316 -231.41305) (xy 146.008852 -231.459278)
		)
		(stroke
			(width 0)
			(type solid)
		)
		(fill yes)
		(layer "F.Cu")
		(net "M_E_CPU1_SB_DQ<13>")
	)
	(gr_poly
		(pts
			(xy 146.147282 -264.09523) (xy 146.18335 -264.059416) (xy 145.997422 -263.873488) (xy 145.961354 -263.909302)
			(xy 145.915126 -264.006838) (xy 146.05 -264.141458)
		)
		(stroke
			(width 0)
			(type solid)
		)
		(fill yes)
		(layer "F.Cu")
		(net "M_E_CPU1_SA_CB<7>")
	)
	(gr_poly
		(pts
			(xy 146.148044 -268.697202) (xy 146.194272 -268.59992) (xy 146.059652 -268.465046) (xy 145.962116 -268.511274)
			(xy 145.926302 -268.547342) (xy 146.11223 -268.73327)
		)
		(stroke
			(width 0)
			(type solid)
		)
		(fill yes)
		(layer "F.Cu")
		(net "M_E_CPU1_SA_CB<0>")
	)
	(gr_poly
		(pts
			(xy 146.152616 -232.177844) (xy 146.106388 -232.080562) (xy 146.070574 -232.044494) (xy 145.884646 -232.230422)
			(xy 145.92046 -232.266236) (xy 146.017996 -232.312718)
		)
		(stroke
			(width 0)
			(type solid)
		)
		(fill yes)
		(layer "F.Cu")
		(net "M_E_CPU1_SB_DQ<12>")
	)
	(gr_poly
		(pts
			(xy 146.153378 -275.5011) (xy 146.245834 -275.445474) (xy 146.208496 -275.258784) (xy 146.101816 -275.24329)
			(xy 146.052032 -275.253196) (xy 146.103594 -275.511006)
		)
		(stroke
			(width 0)
			(type solid)
		)
		(fill yes)
		(layer "F.Cu")
		(net "M_E_CPU1_SA_DQ<24>")
	)
	(gr_poly
		(pts
			(xy 146.154902 -273.094196) (xy 146.190716 -273.058128) (xy 146.004788 -272.8722) (xy 145.968974 -272.908268)
			(xy 145.922746 -273.00555) (xy 146.057366 -273.140424)
		)
		(stroke
			(width 0)
			(type solid)
		)
		(fill yes)
		(layer "F.Cu")
		(net "M_E_CPU1_SA_DQ<27>")
	)
	(gr_poly
		(pts
			(xy 146.157188 -267.844016) (xy 146.203416 -267.74648) (xy 146.068796 -267.61186) (xy 145.971514 -267.658088)
			(xy 145.935446 -267.693902) (xy 146.121374 -267.87983)
		)
		(stroke
			(width 0)
			(type solid)
		)
		(fill yes)
		(layer "F.Cu")
		(net "M_E_CPU1_SA_CB<1>")
	)
	(gr_poly
		(pts
			(xy 146.162014 -275.803614) (xy 146.110452 -275.545804) (xy 146.060668 -275.55571) (xy 145.968212 -275.611082)
			(xy 146.00555 -275.798026) (xy 146.11223 -275.81352)
		)
		(stroke
			(width 0)
			(type solid)
		)
		(fill yes)
		(layer "F.Cu")
		(net "M_E_CPU1_SA_DQ<24>")
	)
	(gr_poly
		(pts
			(xy 146.177762 -234.740958) (xy 146.131534 -234.643676) (xy 146.09572 -234.607608) (xy 145.909792 -234.793536)
			(xy 145.945606 -234.829604) (xy 146.043142 -234.875832)
		)
		(stroke
			(width 0)
			(type solid)
		)
		(fill yes)
		(layer "F.Cu")
		(net "M_E_CPU1_SB_DQ<9>")
	)
	(gr_poly
		(pts
			(xy 146.181572 -270.352266) (xy 146.2278 -270.25473) (xy 146.092926 -270.12011) (xy 145.995644 -270.166338)
			(xy 145.959576 -270.202152) (xy 146.145504 -270.38808)
		)
		(stroke
			(width 0)
			(type solid)
		)
		(fill yes)
		(layer "F.Cu")
		(net "M_E_CPU1_SA_DQ<30>")
	)
	(gr_poly
		(pts
			(xy 146.186398 -236.437932) (xy 146.14017 -236.34065) (xy 146.104356 -236.304582) (xy 145.918428 -236.49051)
			(xy 145.954242 -236.526324) (xy 146.051778 -236.572806)
		)
		(stroke
			(width 0)
			(type solid)
		)
		(fill yes)
		(layer "F.Cu")
		(net "M_E_CPU1_SB_CB<3>")
	)
	(gr_poly
		(pts
			(xy 146.18716 -240.104422) (xy 146.151346 -240.068608) (xy 146.05381 -240.022126) (xy 145.91919 -240.157)
			(xy 145.965418 -240.254282) (xy 146.001232 -240.29035)
		)
		(stroke
			(width 0)
			(type solid)
		)
		(fill yes)
		(layer "F.Cu")
		(net "M_E_CPU1_SB_CB<5>")
	)
	(gr_poly
		(pts
			(xy 146.187668 -235.59516) (xy 146.14144 -235.497624) (xy 146.105626 -235.461556) (xy 145.919698 -235.647484)
			(xy 145.955512 -235.683552) (xy 146.053048 -235.72978)
		)
		(stroke
			(width 0)
			(type solid)
		)
		(fill yes)
		(layer "F.Cu")
		(net "M_E_CPU1_SB_DQ<8>")
	)
	(gr_poly
		(pts
			(xy 146.190462 -278.570436) (xy 146.282918 -278.515064) (xy 146.24558 -278.328374) (xy 146.1389 -278.312626)
			(xy 146.088862 -278.322786) (xy 146.140424 -278.580342)
		)
		(stroke
			(width 0)
			(type solid)
		)
		(fill yes)
		(layer "F.Cu")
		(net "M_E_CPU1_SA_DQ<23>")
	)
	(gr_poly
		(pts
			(xy 146.19097 -269.498572) (xy 146.237198 -269.401036) (xy 146.102578 -269.266416) (xy 146.005042 -269.312644)
			(xy 145.969228 -269.348712) (xy 146.154902 -269.534386)
		)
		(stroke
			(width 0)
			(type solid)
		)
		(fill yes)
		(layer "F.Cu")
		(net "M_E_CPU1_SA_DQ<31>")
	)
	(gr_poly
		(pts
			(xy 146.195796 -237.291372) (xy 146.149568 -237.193836) (xy 146.1135 -237.158022) (xy 145.927572 -237.34395)
			(xy 145.96364 -237.379764) (xy 146.060922 -237.425992)
		)
		(stroke
			(width 0)
			(type solid)
		)
		(fill yes)
		(layer "F.Cu")
		(net "M_E_CPU1_SB_CB<2>")
	)
	(gr_poly
		(pts
			(xy 146.199098 -278.873204) (xy 146.147536 -278.615394) (xy 146.097752 -278.6253) (xy 146.005042 -278.680672)
			(xy 146.042634 -278.867616) (xy 146.149314 -278.88311)
		)
		(stroke
			(width 0)
			(type solid)
		)
		(fill yes)
		(layer "F.Cu")
		(net "M_E_CPU1_SA_DQ<23>")
	)
	(gr_poly
		(pts
			(xy 146.205448 -265.303508) (xy 146.251676 -265.205972) (xy 146.116802 -265.071352) (xy 146.01952 -265.11758)
			(xy 145.983452 -265.153394) (xy 146.16938 -265.339322)
		)
		(stroke
			(width 0)
			(type solid)
		)
		(fill yes)
		(layer "F.Cu")
		(net "M_E_CPU1_SA_CB<4>")
	)
	(gr_poly
		(pts
			(xy 146.209512 -228.447092) (xy 146.209512 -228.256592) (xy 146.107912 -228.220524) (xy 146.057112 -228.220524)
			(xy 146.057112 -228.483414) (xy 146.107912 -228.483414)
		)
		(stroke
			(width 0)
			(type solid)
		)
		(fill yes)
		(layer "F.Cu")
		(net "M_E_CPU1_SB_DQ<19>")
	)
	(gr_poly
		(pts
			(xy 146.209512 -227.850192) (xy 146.209512 -227.659692) (xy 146.107912 -227.623624) (xy 146.057112 -227.623624)
			(xy 146.057112 -227.886514) (xy 146.107912 -227.886514)
		)
		(stroke
			(width 0)
			(type solid)
		)
		(fill yes)
		(layer "F.Cu")
		(net "M_E_CPU1_SB_DQ<19>")
	)
	(gr_poly
		(pts
			(xy 146.209512 -227.253292) (xy 146.209512 -227.062792) (xy 146.107912 -227.026724) (xy 146.057112 -227.026724)
			(xy 146.057112 -227.289614) (xy 146.107912 -227.289614)
		)
		(stroke
			(width 0)
			(type solid)
		)
		(fill yes)
		(layer "F.Cu")
		(net "M_E_CPU1_SB_DQ<19>")
	)
	(gr_poly
		(pts
			(xy 146.209512 -226.656392) (xy 146.209512 -226.465892) (xy 146.107912 -226.429824) (xy 146.057112 -226.429824)
			(xy 146.057112 -226.692714) (xy 146.107912 -226.692714)
		)
		(stroke
			(width 0)
			(type solid)
		)
		(fill yes)
		(layer "F.Cu")
		(net "M_E_CPU1_SB_DQ<19>")
	)
	(gr_poly
		(pts
			(xy 146.209512 -226.059492) (xy 146.209512 -225.868992) (xy 146.107912 -225.832924) (xy 146.057112 -225.832924)
			(xy 146.057112 -226.095814) (xy 146.107912 -226.095814)
		)
		(stroke
			(width 0)
			(type solid)
		)
		(fill yes)
		(layer "F.Cu")
		(net "M_E_CPU1_SB_DQ<19>")
	)
	(gr_poly
		(pts
			(xy 146.209512 -225.462592) (xy 146.209512 -225.272092) (xy 146.107912 -225.236024) (xy 146.057112 -225.236024)
			(xy 146.057112 -225.498914) (xy 146.107912 -225.498914)
		)
		(stroke
			(width 0)
			(type solid)
		)
		(fill yes)
		(layer "F.Cu")
		(net "M_E_CPU1_SB_DQ<19>")
	)
	(gr_poly
		(pts
			(xy 146.209512 -224.865692) (xy 146.209512 -224.675192) (xy 146.107912 -224.639124) (xy 146.057112 -224.639124)
			(xy 146.057112 -224.902014) (xy 146.107912 -224.902014)
		)
		(stroke
			(width 0)
			(type solid)
		)
		(fill yes)
		(layer "F.Cu")
		(net "M_E_CPU1_SB_DQ<19>")
	)
	(gr_poly
		(pts
			(xy 146.209512 -224.268792) (xy 146.209512 -224.078292) (xy 146.107912 -224.042224) (xy 146.057112 -224.042224)
			(xy 146.057112 -224.305114) (xy 146.107912 -224.305114)
		)
		(stroke
			(width 0)
			(type solid)
		)
		(fill yes)
		(layer "F.Cu")
		(net "M_E_CPU1_SB_DQ<19>")
	)
	(gr_poly
		(pts
			(xy 146.209512 -223.671892) (xy 146.209512 -223.481392) (xy 146.107912 -223.445324) (xy 146.057112 -223.445324)
			(xy 146.057112 -223.708214) (xy 146.107912 -223.708214)
		)
		(stroke
			(width 0)
			(type solid)
		)
		(fill yes)
		(layer "F.Cu")
		(net "M_E_CPU1_SB_DQ<19>")
	)
	(gr_poly
		(pts
			(xy 146.209512 -223.074992) (xy 146.209512 -222.884492) (xy 146.107912 -222.848424) (xy 146.057112 -222.848424)
			(xy 146.057112 -223.111314) (xy 146.107912 -223.111314)
		)
		(stroke
			(width 0)
			(type solid)
		)
		(fill yes)
		(layer "F.Cu")
		(net "M_E_CPU1_SB_DQ<19>")
	)
	(gr_poly
		(pts
			(xy 146.209512 -222.478092) (xy 146.209512 -222.287592) (xy 146.107912 -222.251524) (xy 146.057112 -222.251524)
			(xy 146.057112 -222.514414) (xy 146.107912 -222.514414)
		)
		(stroke
			(width 0)
			(type solid)
		)
		(fill yes)
		(layer "F.Cu")
		(net "M_E_CPU1_SB_DQ<19>")
	)
	(gr_poly
		(pts
			(xy 146.209512 -221.881192) (xy 146.209512 -221.690692) (xy 146.107912 -221.654624) (xy 146.057112 -221.654624)
			(xy 146.057112 -221.917514) (xy 146.107912 -221.917514)
		)
		(stroke
			(width 0)
			(type solid)
		)
		(fill yes)
		(layer "F.Cu")
		(net "M_E_CPU1_SB_DQ<19>")
	)
	(gr_poly
		(pts
			(xy 146.209512 -221.284292) (xy 146.209512 -221.093792) (xy 146.107912 -221.057724) (xy 146.057112 -221.057724)
			(xy 146.057112 -221.320614) (xy 146.107912 -221.320614)
		)
		(stroke
			(width 0)
			(type solid)
		)
		(fill yes)
		(layer "F.Cu")
		(net "M_E_CPU1_SB_DQ<19>")
	)
	(gr_poly
		(pts
			(xy 146.209512 -220.687392) (xy 146.209512 -220.496892) (xy 146.107912 -220.460824) (xy 146.057112 -220.460824)
			(xy 146.057112 -220.723714) (xy 146.107912 -220.723714)
		)
		(stroke
			(width 0)
			(type solid)
		)
		(fill yes)
		(layer "F.Cu")
		(net "M_E_CPU1_SB_DQ<19>")
	)
	(gr_poly
		(pts
			(xy 146.209512 -220.090492) (xy 146.209512 -219.899992) (xy 146.107912 -219.863924) (xy 146.057112 -219.863924)
			(xy 146.057112 -220.126814) (xy 146.107912 -220.126814)
		)
		(stroke
			(width 0)
			(type solid)
		)
		(fill yes)
		(layer "F.Cu")
		(net "M_E_CPU1_SB_DQ<19>")
	)
	(gr_poly
		(pts
			(xy 146.214592 -264.450068) (xy 146.26082 -264.352532) (xy 146.1262 -264.217912) (xy 146.028664 -264.26414)
			(xy 145.99285 -264.300208) (xy 146.178778 -264.486136)
		)
		(stroke
			(width 0)
			(type solid)
		)
		(fill yes)
		(layer "F.Cu")
		(net "M_E_CPU1_SA_CB<5>")
	)
	(gr_poly
		(pts
			(xy 146.218148 -274.27047) (xy 146.310858 -274.215098) (xy 146.273266 -274.028408) (xy 146.166586 -274.01266)
			(xy 146.116802 -274.02282) (xy 146.168364 -274.28063)
		)
		(stroke
			(width 0)
			(type solid)
		)
		(fill yes)
		(layer "F.Cu")
		(net "M_E_CPU1_SA_DQ<26>")
	)
	(gr_poly
		(pts
			(xy 146.222212 -273.449034) (xy 146.26844 -273.351498) (xy 146.133566 -273.216878) (xy 146.036284 -273.263106)
			(xy 146.000216 -273.29892) (xy 146.186144 -273.484848)
		)
		(stroke
			(width 0)
			(type solid)
		)
		(fill yes)
		(layer "F.Cu")
		(net "M_E_CPU1_SA_DQ<25>")
	)
	(gr_poly
		(pts
			(xy 146.227038 -274.573238) (xy 146.175476 -274.315428) (xy 146.125692 -274.325334) (xy 146.032982 -274.380706)
			(xy 146.07032 -274.56765) (xy 146.177254 -274.583144)
		)
		(stroke
			(width 0)
			(type solid)
		)
		(fill yes)
		(layer "F.Cu")
		(net "M_E_CPU1_SA_DQ<26>")
	)
	(gr_poly
		(pts
			(xy 146.263614 -229.283006) (xy 146.227546 -229.247192) (xy 146.130264 -229.200964) (xy 145.99539 -229.335584)
			(xy 146.041872 -229.43312) (xy 146.077686 -229.468934)
		)
		(stroke
			(width 0)
			(type solid)
		)
		(fill yes)
		(layer "F.Cu")
		(net "M_E_CPU1_SB_DQ<18>")
	)
	(gr_poly
		(pts
			(xy 146.270472 -276.086316) (xy 146.362928 -276.030944) (xy 146.32559 -275.844) (xy 146.21891 -275.828506)
			(xy 146.169126 -275.838412) (xy 146.220688 -276.096222)
		)
		(stroke
			(width 0)
			(type solid)
		)
		(fill yes)
		(layer "F.Cu")
		(net "M_E_CPU1_SA_DQ<24>")
	)
	(gr_poly
		(pts
			(xy 146.27225 -230.980234) (xy 146.236436 -230.944166) (xy 146.1389 -230.897938) (xy 146.00428 -231.032558)
			(xy 146.050508 -231.130094) (xy 146.086576 -231.165908)
		)
		(stroke
			(width 0)
			(type solid)
		)
		(fill yes)
		(layer "F.Cu")
		(net "M_E_CPU1_SB_DQ<13>")
	)
	(gr_poly
		(pts
			(xy 146.279108 -276.38883) (xy 146.227546 -276.13102) (xy 146.177762 -276.14118) (xy 146.085306 -276.196552)
			(xy 146.122644 -276.383242) (xy 146.229324 -276.39899)
		)
		(stroke
			(width 0)
			(type solid)
		)
		(fill yes)
		(layer "F.Cu")
		(net "M_E_CPU1_SA_DQ<24>")
	)
	(gr_poly
		(pts
			(xy 146.281648 -231.83342) (xy 146.24558 -231.797606) (xy 146.148298 -231.751378) (xy 146.013424 -231.885998)
			(xy 146.059652 -231.983534) (xy 146.09572 -232.019348)
		)
		(stroke
			(width 0)
			(type solid)
		)
		(fill yes)
		(layer "F.Cu")
		(net "M_E_CPU1_SB_DQ<12>")
	)
	(gr_poly
		(pts
			(xy 146.287236 -268.980158) (xy 146.323304 -268.944344) (xy 146.137376 -268.758416) (xy 146.101308 -268.79423)
			(xy 146.05508 -268.891766) (xy 146.189954 -269.026386)
		)
		(stroke
			(width 0)
			(type solid)
		)
		(fill yes)
		(layer "F.Cu")
		(net "M_E_CPU1_SA_CB<0>")
	)
	(gr_poly
		(pts
			(xy 146.28876 -284.47492) (xy 146.28876 -284.28442) (xy 146.18716 -284.248098) (xy 146.13636 -284.248098)
			(xy 146.13636 -284.511242) (xy 146.18716 -284.511242)
		)
		(stroke
			(width 0)
			(type solid)
		)
		(fill yes)
		(layer "F.Cu")
		(net "M_E_CPU1_SA_DQ<21>")
	)
	(gr_poly
		(pts
			(xy 146.28876 -283.87802) (xy 146.28876 -283.68752) (xy 146.18716 -283.651198) (xy 146.13636 -283.651198)
			(xy 146.13636 -283.914342) (xy 146.18716 -283.914342)
		)
		(stroke
			(width 0)
			(type solid)
		)
		(fill yes)
		(layer "F.Cu")
		(net "M_E_CPU1_SA_DQ<21>")
	)
	(gr_poly
		(pts
			(xy 146.28876 -283.28112) (xy 146.28876 -283.09062) (xy 146.18716 -283.054298) (xy 146.13636 -283.054298)
			(xy 146.13636 -283.317442) (xy 146.18716 -283.317442)
		)
		(stroke
			(width 0)
			(type solid)
		)
		(fill yes)
		(layer "F.Cu")
		(net "M_E_CPU1_SA_DQ<21>")
	)
	(gr_poly
		(pts
			(xy 146.28876 -282.68422) (xy 146.28876 -282.49372) (xy 146.18716 -282.457398) (xy 146.13636 -282.457398)
			(xy 146.13636 -282.720542) (xy 146.18716 -282.720542)
		)
		(stroke
			(width 0)
			(type solid)
		)
		(fill yes)
		(layer "F.Cu")
		(net "M_E_CPU1_SA_DQ<21>")
	)
	(gr_poly
		(pts
			(xy 146.28876 -282.08732) (xy 146.28876 -281.89682) (xy 146.18716 -281.860498) (xy 146.13636 -281.860498)
			(xy 146.13636 -282.123642) (xy 146.18716 -282.123642)
		)
		(stroke
			(width 0)
			(type solid)
		)
		(fill yes)
		(layer "F.Cu")
		(net "M_E_CPU1_SA_DQ<21>")
	)
	(gr_poly
		(pts
			(xy 146.28876 -281.49042) (xy 146.28876 -281.29992) (xy 146.18716 -281.263598) (xy 146.13636 -281.263598)
			(xy 146.13636 -281.526742) (xy 146.18716 -281.526742)
		)
		(stroke
			(width 0)
			(type solid)
		)
		(fill yes)
		(layer "F.Cu")
		(net "M_E_CPU1_SA_DQ<21>")
	)
	(gr_poly
		(pts
			(xy 146.28876 -280.89352) (xy 146.28876 -280.70302) (xy 146.18716 -280.666698) (xy 146.13636 -280.666698)
			(xy 146.13636 -280.929842) (xy 146.18716 -280.929842)
		)
		(stroke
			(width 0)
			(type solid)
		)
		(fill yes)
		(layer "F.Cu")
		(net "M_E_CPU1_SA_DQ<21>")
	)
	(gr_poly
		(pts
			(xy 146.29638 -268.126718) (xy 146.332448 -268.090904) (xy 146.14652 -267.904976) (xy 146.110706 -267.94079)
			(xy 146.064224 -268.038326) (xy 146.199098 -268.172946)
		)
		(stroke
			(width 0)
			(type solid)
		)
		(fill yes)
		(layer "F.Cu")
		(net "M_E_CPU1_SA_CB<1>")
	)
	(gr_poly
		(pts
			(xy 146.306794 -234.396788) (xy 146.270726 -234.36072) (xy 146.173444 -234.314492) (xy 146.03857 -234.449112)
			(xy 146.084798 -234.546648) (xy 146.120866 -234.582462)
		)
		(stroke
			(width 0)
			(type solid)
		)
		(fill yes)
		(layer "F.Cu")
		(net "M_E_CPU1_SB_DQ<9>")
	)
	(gr_poly
		(pts
			(xy 146.307302 -279.155906) (xy 146.400012 -279.10028) (xy 146.362674 -278.91359) (xy 146.25574 -278.898096)
			(xy 146.205956 -278.908002) (xy 146.257518 -279.165812)
		)
		(stroke
			(width 0)
			(type solid)
		)
		(fill yes)
		(layer "F.Cu")
		(net "M_E_CPU1_SA_DQ<23>")
	)
	(gr_poly
		(pts
			(xy 146.31543 -236.093508) (xy 146.279362 -236.057694) (xy 146.18208 -236.011466) (xy 146.047206 -236.146086)
			(xy 146.093434 -236.243622) (xy 146.129502 -236.279436)
		)
		(stroke
			(width 0)
			(type solid)
		)
		(fill yes)
		(layer "F.Cu")
		(net "M_E_CPU1_SB_CB<3>")
	)
	(gr_poly
		(pts
			(xy 146.316192 -279.45842) (xy 146.26463 -279.20061) (xy 146.214846 -279.210516) (xy 146.122136 -279.266142)
			(xy 146.159474 -279.452832) (xy 146.266408 -279.468326)
		)
		(stroke
			(width 0)
			(type solid)
		)
		(fill yes)
		(layer "F.Cu")
		(net "M_E_CPU1_SA_DQ<23>")
	)
	(gr_poly
		(pts
			(xy 146.316446 -235.250736) (xy 146.280632 -235.214668) (xy 146.183096 -235.16844) (xy 146.048476 -235.30306)
			(xy 146.094704 -235.400596) (xy 146.130772 -235.43641)
		)
		(stroke
			(width 0)
			(type solid)
		)
		(fill yes)
		(layer "F.Cu")
		(net "M_E_CPU1_SB_DQ<8>")
	)
	(gr_poly
		(pts
			(xy 146.320764 -270.634968) (xy 146.356578 -270.599154) (xy 146.17065 -270.413226) (xy 146.134836 -270.44904)
			(xy 146.088608 -270.546576) (xy 146.223228 -270.681196)
		)
		(stroke
			(width 0)
			(type solid)
		)
		(fill yes)
		(layer "F.Cu")
		(net "M_E_CPU1_SA_DQ<30>")
	)
	(gr_poly
		(pts
			(xy 146.324574 -236.946948) (xy 146.28876 -236.911134) (xy 146.191224 -236.864906) (xy 146.056604 -236.999526)
			(xy 146.102832 -237.096808) (xy 146.138646 -237.132876)
		)
		(stroke
			(width 0)
			(type solid)
		)
		(fill yes)
		(layer "F.Cu")
		(net "M_E_CPU1_SB_CB<2>")
	)
	(gr_poly
		(pts
			(xy 146.330162 -269.781528) (xy 146.365976 -269.74546) (xy 146.180048 -269.559532) (xy 146.144234 -269.5956)
			(xy 146.098006 -269.692882) (xy 146.232626 -269.827756)
		)
		(stroke
			(width 0)
			(type solid)
		)
		(fill yes)
		(layer "F.Cu")
		(net "M_E_CPU1_SA_DQ<31>")
	)
	(gr_poly
		(pts
			(xy 146.335242 -274.85594) (xy 146.427952 -274.800314) (xy 146.39036 -274.613624) (xy 146.28368 -274.59813)
			(xy 146.233896 -274.608036) (xy 146.285458 -274.865846)
		)
		(stroke
			(width 0)
			(type solid)
		)
		(fill yes)
		(layer "F.Cu")
		(net "M_E_CPU1_SA_DQ<26>")
	)
	(gr_poly
		(pts
			(xy 146.341084 -228.989636) (xy 146.294856 -228.892354) (xy 146.259042 -228.856286) (xy 146.073114 -229.042214)
			(xy 146.108928 -229.078282) (xy 146.206464 -229.12451)
		)
		(stroke
			(width 0)
			(type solid)
		)
		(fill yes)
		(layer "F.Cu")
		(net "M_E_CPU1_SB_DQ<17>")
	)
	(gr_poly
		(pts
			(xy 146.344132 -275.158454) (xy 146.29257 -274.900644) (xy 146.242532 -274.91055) (xy 146.150076 -274.966176)
			(xy 146.187414 -275.152866) (xy 146.294094 -275.16836)
		)
		(stroke
			(width 0)
			(type solid)
		)
		(fill yes)
		(layer "F.Cu")
		(net "M_E_CPU1_SA_DQ<26>")
	)
	(gr_poly
		(pts
			(xy 146.34464 -265.58621) (xy 146.380454 -265.550396) (xy 146.194526 -265.364468) (xy 146.158712 -265.400536)
			(xy 146.112484 -265.497818) (xy 146.247104 -265.632692)
		)
		(stroke
			(width 0)
			(type solid)
		)
		(fill yes)
		(layer "F.Cu")
		(net "M_E_CPU1_SA_CB<4>")
	)
	(gr_poly
		(pts
			(xy 146.349974 -230.686864) (xy 146.303746 -230.589328) (xy 146.267678 -230.553514) (xy 146.08175 -230.739442)
			(xy 146.117818 -230.775256) (xy 146.2151 -230.821484)
		)
		(stroke
			(width 0)
			(type solid)
		)
		(fill yes)
		(layer "F.Cu")
		(net "M_E_CPU1_SB_DQ<15>")
	)
	(gr_poly
		(pts
			(xy 146.350228 -229.843076) (xy 146.304 -229.74554) (xy 146.268186 -229.709726) (xy 146.082258 -229.895654)
			(xy 146.118072 -229.931468) (xy 146.215608 -229.977696)
		)
		(stroke
			(width 0)
			(type solid)
		)
		(fill yes)
		(layer "F.Cu")
		(net "M_E_CPU1_SB_DQ<16>")
	)
	(gr_poly
		(pts
			(xy 146.353784 -264.733024) (xy 146.389598 -264.696956) (xy 146.203924 -264.511282) (xy 146.167856 -264.547096)
			(xy 146.121628 -264.644632) (xy 146.256248 -264.779252)
		)
		(stroke
			(width 0)
			(type solid)
		)
		(fill yes)
		(layer "F.Cu")
		(net "M_E_CPU1_SA_CB<5>")
	)
	(gr_poly
		(pts
			(xy 146.359118 -231.54005) (xy 146.31289 -231.442768) (xy 146.277076 -231.4067) (xy 146.091148 -231.592628)
			(xy 146.126962 -231.628696) (xy 146.224498 -231.674924)
		)
		(stroke
			(width 0)
			(type solid)
		)
		(fill yes)
		(layer "F.Cu")
		(net "M_E_CPU1_SB_DQ<14>")
	)
	(gr_poly
		(pts
			(xy 146.361912 -227.922074) (xy 146.311112 -227.922074) (xy 146.209512 -227.958142) (xy 146.209512 -228.148642)
			(xy 146.311112 -228.184964) (xy 146.361912 -228.184964)
		)
		(stroke
			(width 0)
			(type solid)
		)
		(fill yes)
		(layer "F.Cu")
		(net "M_E_CPU1_SB_DQ<17>")
	)
	(gr_poly
		(pts
			(xy 146.361912 -227.325174) (xy 146.311112 -227.325174) (xy 146.209512 -227.361242) (xy 146.209512 -227.551742)
			(xy 146.311112 -227.588064) (xy 146.361912 -227.588064)
		)
		(stroke
			(width 0)
			(type solid)
		)
		(fill yes)
		(layer "F.Cu")
		(net "M_E_CPU1_SB_DQ<17>")
	)
	(gr_poly
		(pts
			(xy 146.361912 -226.728274) (xy 146.311112 -226.728274) (xy 146.209512 -226.764342) (xy 146.209512 -226.954842)
			(xy 146.311112 -226.991164) (xy 146.361912 -226.991164)
		)
		(stroke
			(width 0)
			(type solid)
		)
		(fill yes)
		(layer "F.Cu")
		(net "M_E_CPU1_SB_DQ<17>")
	)
	(gr_poly
		(pts
			(xy 146.361912 -226.131374) (xy 146.311112 -226.131374) (xy 146.209512 -226.167442) (xy 146.209512 -226.357942)
			(xy 146.311112 -226.394264) (xy 146.361912 -226.394264)
		)
		(stroke
			(width 0)
			(type solid)
		)
		(fill yes)
		(layer "F.Cu")
		(net "M_E_CPU1_SB_DQ<17>")
	)
	(gr_poly
		(pts
			(xy 146.361912 -225.534474) (xy 146.311112 -225.534474) (xy 146.209512 -225.570542) (xy 146.209512 -225.761042)
			(xy 146.311112 -225.797364) (xy 146.361912 -225.797364)
		)
		(stroke
			(width 0)
			(type solid)
		)
		(fill yes)
		(layer "F.Cu")
		(net "M_E_CPU1_SB_DQ<17>")
	)
	(gr_poly
		(pts
			(xy 146.361912 -224.937574) (xy 146.311112 -224.937574) (xy 146.209512 -224.973642) (xy 146.209512 -225.164142)
			(xy 146.311112 -225.200464) (xy 146.361912 -225.200464)
		)
		(stroke
			(width 0)
			(type solid)
		)
		(fill yes)
		(layer "F.Cu")
		(net "M_E_CPU1_SB_DQ<17>")
	)
	(gr_poly
		(pts
			(xy 146.361912 -224.340674) (xy 146.311112 -224.340674) (xy 146.209512 -224.376742) (xy 146.209512 -224.567242)
			(xy 146.311112 -224.603564) (xy 146.361912 -224.603564)
		)
		(stroke
			(width 0)
			(type solid)
		)
		(fill yes)
		(layer "F.Cu")
		(net "M_E_CPU1_SB_DQ<17>")
	)
	(gr_poly
		(pts
			(xy 146.361912 -223.743774) (xy 146.311112 -223.743774) (xy 146.209512 -223.779842) (xy 146.209512 -223.970342)
			(xy 146.311112 -224.006664) (xy 146.361912 -224.006664)
		)
		(stroke
			(width 0)
			(type solid)
		)
		(fill yes)
		(layer "F.Cu")
		(net "M_E_CPU1_SB_DQ<17>")
	)
	(gr_poly
		(pts
			(xy 146.361912 -223.146874) (xy 146.311112 -223.146874) (xy 146.209512 -223.182942) (xy 146.209512 -223.373442)
			(xy 146.311112 -223.409764) (xy 146.361912 -223.409764)
		)
		(stroke
			(width 0)
			(type solid)
		)
		(fill yes)
		(layer "F.Cu")
		(net "M_E_CPU1_SB_DQ<17>")
	)
	(gr_poly
		(pts
			(xy 146.361912 -222.549974) (xy 146.311112 -222.549974) (xy 146.209512 -222.586042) (xy 146.209512 -222.776542)
			(xy 146.311112 -222.812864) (xy 146.361912 -222.812864)
		)
		(stroke
			(width 0)
			(type solid)
		)
		(fill yes)
		(layer "F.Cu")
		(net "M_E_CPU1_SB_DQ<17>")
	)
	(gr_poly
		(pts
			(xy 146.361912 -221.953074) (xy 146.311112 -221.953074) (xy 146.209512 -221.989142) (xy 146.209512 -222.179642)
			(xy 146.311112 -222.215964) (xy 146.361912 -222.215964)
		)
		(stroke
			(width 0)
			(type solid)
		)
		(fill yes)
		(layer "F.Cu")
		(net "M_E_CPU1_SB_DQ<17>")
	)
	(gr_poly
		(pts
			(xy 146.361912 -221.356174) (xy 146.311112 -221.356174) (xy 146.209512 -221.392242) (xy 146.209512 -221.582742)
			(xy 146.311112 -221.619064) (xy 146.361912 -221.619064)
		)
		(stroke
			(width 0)
			(type solid)
		)
		(fill yes)
		(layer "F.Cu")
		(net "M_E_CPU1_SB_DQ<17>")
	)
	(gr_poly
		(pts
			(xy 146.361912 -220.759274) (xy 146.311112 -220.759274) (xy 146.209512 -220.795342) (xy 146.209512 -220.985842)
			(xy 146.311112 -221.022164) (xy 146.361912 -221.022164)
		)
		(stroke
			(width 0)
			(type solid)
		)
		(fill yes)
		(layer "F.Cu")
		(net "M_E_CPU1_SB_DQ<17>")
	)
	(gr_poly
		(pts
			(xy 146.361912 -220.162374) (xy 146.311112 -220.162374) (xy 146.209512 -220.198442) (xy 146.209512 -220.388942)
			(xy 146.311112 -220.425264) (xy 146.361912 -220.425264)
		)
		(stroke
			(width 0)
			(type solid)
		)
		(fill yes)
		(layer "F.Cu")
		(net "M_E_CPU1_SB_DQ<17>")
	)
	(gr_poly
		(pts
			(xy 146.36369 -268.481556) (xy 146.409918 -268.384274) (xy 146.275298 -268.2494) (xy 146.177762 -268.295628)
			(xy 146.141948 -268.331696) (xy 146.327876 -268.517624)
		)
		(stroke
			(width 0)
			(type solid)
		)
		(fill yes)
		(layer "F.Cu")
		(net "M_E_CPU1_SA_CB<2>")
	)
	(gr_poly
		(pts
			(xy 146.372834 -267.62837) (xy 146.419062 -267.530834) (xy 146.284442 -267.396214) (xy 146.18716 -267.442442)
			(xy 146.151092 -267.478256) (xy 146.33702 -267.664184)
		)
		(stroke
			(width 0)
			(type solid)
		)
		(fill yes)
		(layer "F.Cu")
		(net "M_E_CPU1_SA_CB<3>")
	)
	(gr_poly
		(pts
			(xy 146.38401 -234.103164) (xy 146.337782 -234.005628) (xy 146.301714 -233.969814) (xy 146.11604 -234.155488)
			(xy 146.151854 -234.191556) (xy 146.24939 -234.237784)
		)
		(stroke
			(width 0)
			(type solid)
		)
		(fill yes)
		(layer "F.Cu")
		(net "M_E_CPU1_SB_DQ<11>")
	)
	(gr_poly
		(pts
			(xy 146.387566 -276.671532) (xy 146.480022 -276.61616) (xy 146.442684 -276.42947) (xy 146.336004 -276.413722)
			(xy 146.28622 -276.423882) (xy 146.337782 -276.681438)
		)
		(stroke
			(width 0)
			(type solid)
		)
		(fill yes)
		(layer "F.Cu")
		(net "M_E_CPU1_SA_DQ<24>")
	)
	(gr_poly
		(pts
			(xy 146.38782 -270.989806) (xy 146.434048 -270.892524) (xy 146.299428 -270.75765) (xy 146.201892 -270.804132)
			(xy 146.166078 -270.839946) (xy 146.352006 -271.025874)
		)
		(stroke
			(width 0)
			(type solid)
		)
		(fill yes)
		(layer "F.Cu")
		(net "M_E_CPU1_SA_DQ<28>")
	)
	(gr_poly
		(pts
			(xy 146.393916 -234.957112) (xy 146.347688 -234.85983) (xy 146.311874 -234.823762) (xy 146.125946 -235.00969)
			(xy 146.16176 -235.045758) (xy 146.259296 -235.091986)
		)
		(stroke
			(width 0)
			(type solid)
		)
		(fill yes)
		(layer "F.Cu")
		(net "M_E_CPU1_SB_DQ<10>")
	)
	(gr_poly
		(pts
			(xy 146.396202 -276.9743) (xy 146.34464 -276.71649) (xy 146.294856 -276.726396) (xy 146.2024 -276.781768)
			(xy 146.239738 -276.968712) (xy 146.346418 -276.984206)
		)
		(stroke
			(width 0)
			(type solid)
		)
		(fill yes)
		(layer "F.Cu")
		(net "M_E_CPU1_SA_DQ<24>")
	)
	(gr_poly
		(pts
			(xy 146.397218 -270.136366) (xy 146.443446 -270.039084) (xy 146.308826 -269.90421) (xy 146.21129 -269.950438)
			(xy 146.175476 -269.986506) (xy 146.361404 -270.172434)
		)
		(stroke
			(width 0)
			(type solid)
		)
		(fill yes)
		(layer "F.Cu")
		(net "M_E_CPU1_SA_DQ<29>")
	)
	(gr_poly
		(pts
			(xy 146.402044 -236.653578) (xy 146.355816 -236.556296) (xy 146.320002 -236.520228) (xy 146.134074 -236.706156)
			(xy 146.169888 -236.74197) (xy 146.267424 -236.788452)
		)
		(stroke
			(width 0)
			(type solid)
		)
		(fill yes)
		(layer "F.Cu")
		(net "M_E_CPU1_SB_CB<1>")
	)
	(gr_poly
		(pts
			(xy 146.411442 -237.507018) (xy 146.365214 -237.409482) (xy 146.329146 -237.373668) (xy 146.143218 -237.559596)
			(xy 146.179286 -237.59541) (xy 146.276568 -237.641638)
		)
		(stroke
			(width 0)
			(type solid)
		)
		(fill yes)
		(layer "F.Cu")
		(net "M_E_CPU1_SB_CB<0>")
	)
	(gr_poly
		(pts
			(xy 146.421094 -265.087862) (xy 146.467322 -264.990326) (xy 146.332448 -264.855706) (xy 146.235166 -264.901934)
			(xy 146.199098 -264.937748) (xy 146.385026 -265.123676)
		)
		(stroke
			(width 0)
			(type solid)
		)
		(fill yes)
		(layer "F.Cu")
		(net "M_E_CPU1_SA_CB<6>")
	)
	(gr_poly
		(pts
			(xy 146.424396 -279.741122) (xy 146.517106 -279.68575) (xy 146.479768 -279.498806) (xy 146.372834 -279.483312)
			(xy 146.32305 -279.493218) (xy 146.374612 -279.751028)
		)
		(stroke
			(width 0)
			(type solid)
		)
		(fill yes)
		(layer "F.Cu")
		(net "M_E_CPU1_SA_DQ<23>")
	)
	(gr_poly
		(pts
			(xy 146.430238 -264.234422) (xy 146.476466 -264.136886) (xy 146.341846 -264.002266) (xy 146.24431 -264.048494)
			(xy 146.208496 -264.084562) (xy 146.394424 -264.27049)
		)
		(stroke
			(width 0)
			(type solid)
		)
		(fill yes)
		(layer "F.Cu")
		(net "M_E_CPU1_SA_CB<7>")
	)
	(gr_poly
		(pts
			(xy 146.437604 -273.233388) (xy 146.483832 -273.135852) (xy 146.349212 -273.001232) (xy 146.25193 -273.04746)
			(xy 146.215862 -273.083274) (xy 146.40179 -273.269202)
		)
		(stroke
			(width 0)
			(type solid)
		)
		(fill yes)
		(layer "F.Cu")
		(net "M_E_CPU1_SA_DQ<27>")
	)
	(gr_poly
		(pts
			(xy 146.44116 -283.949648) (xy 146.39036 -283.949648) (xy 146.28876 -283.98597) (xy 146.28876 -284.17647)
			(xy 146.39036 -284.212538) (xy 146.44116 -284.212538)
		)
		(stroke
			(width 0)
			(type solid)
		)
		(fill yes)
		(layer "F.Cu")
		(net "M_E_CPU1_SA_DQ<23>")
	)
	(gr_poly
		(pts
			(xy 146.44116 -283.352748) (xy 146.39036 -283.352748) (xy 146.28876 -283.38907) (xy 146.28876 -283.57957)
			(xy 146.39036 -283.615638) (xy 146.44116 -283.615638)
		)
		(stroke
			(width 0)
			(type solid)
		)
		(fill yes)
		(layer "F.Cu")
		(net "M_E_CPU1_SA_DQ<23>")
	)
	(gr_poly
		(pts
			(xy 146.44116 -282.755848) (xy 146.39036 -282.755848) (xy 146.28876 -282.79217) (xy 146.28876 -282.98267)
			(xy 146.39036 -283.018738) (xy 146.44116 -283.018738)
		)
		(stroke
			(width 0)
			(type solid)
		)
		(fill yes)
		(layer "F.Cu")
		(net "M_E_CPU1_SA_DQ<23>")
	)
	(gr_poly
		(pts
			(xy 146.44116 -282.158948) (xy 146.39036 -282.158948) (xy 146.28876 -282.19527) (xy 146.28876 -282.38577)
			(xy 146.39036 -282.421838) (xy 146.44116 -282.421838)
		)
		(stroke
			(width 0)
			(type solid)
		)
		(fill yes)
		(layer "F.Cu")
		(net "M_E_CPU1_SA_DQ<23>")
	)
	(gr_poly
		(pts
			(xy 146.44116 -281.562048) (xy 146.39036 -281.562048) (xy 146.28876 -281.59837) (xy 146.28876 -281.78887)
			(xy 146.39036 -281.824938) (xy 146.44116 -281.824938)
		)
		(stroke
			(width 0)
			(type solid)
		)
		(fill yes)
		(layer "F.Cu")
		(net "M_E_CPU1_SA_DQ<23>")
	)
	(gr_poly
		(pts
			(xy 146.44116 -280.965148) (xy 146.39036 -280.965148) (xy 146.28876 -281.00147) (xy 146.28876 -281.19197)
			(xy 146.39036 -281.228038) (xy 146.44116 -281.228038)
		)
		(stroke
			(width 0)
			(type solid)
		)
		(fill yes)
		(layer "F.Cu")
		(net "M_E_CPU1_SA_DQ<23>")
	)
	(gr_poly
		(pts
			(xy 146.44116 -280.368248) (xy 146.39036 -280.368248) (xy 146.28876 -280.40457) (xy 146.28876 -280.59507)
			(xy 146.39036 -280.631138) (xy 146.44116 -280.631138)
		)
		(stroke
			(width 0)
			(type solid)
		)
		(fill yes)
		(layer "F.Cu")
		(net "M_E_CPU1_SA_DQ<23>")
	)
	(gr_poly
		(pts
			(xy 146.452336 -275.441156) (xy 146.544792 -275.385784) (xy 146.507454 -275.19884) (xy 146.400774 -275.183346)
			(xy 146.35099 -275.193252) (xy 146.402552 -275.451062)
		)
		(stroke
			(width 0)
			(type solid)
		)
		(fill yes)
		(layer "F.Cu")
		(net "M_E_CPU1_SA_DQ<26>")
	)
	(gr_poly
		(pts
			(xy 146.461226 -275.74367) (xy 146.409664 -275.486114) (xy 146.359626 -275.49602) (xy 146.26717 -275.551392)
			(xy 146.304508 -275.738082) (xy 146.411188 -275.75383)
		)
		(stroke
			(width 0)
			(type solid)
		)
		(fill yes)
		(layer "F.Cu")
		(net "M_E_CPU1_SA_DQ<26>")
	)
	(gr_poly
		(pts
			(xy 146.478752 -230.34244) (xy 146.442938 -230.306372) (xy 146.345402 -230.260144) (xy 146.210782 -230.395018)
			(xy 146.25701 -230.4923) (xy 146.292824 -230.528368)
		)
		(stroke
			(width 0)
			(type solid)
		)
		(fill yes)
		(layer "F.Cu")
		(net "M_E_CPU1_SB_DQ<15>")
	)
	(gr_poly
		(pts
			(xy 146.47926 -229.498652) (xy 146.443192 -229.462838) (xy 146.34591 -229.41661) (xy 146.211036 -229.55123)
			(xy 146.257518 -229.648766) (xy 146.293332 -229.68458)
		)
		(stroke
			(width 0)
			(type solid)
		)
		(fill yes)
		(layer "F.Cu")
		(net "M_E_CPU1_SB_DQ<16>")
	)
	(gr_poly
		(pts
			(xy 146.487896 -231.19588) (xy 146.452082 -231.159812) (xy 146.354546 -231.113584) (xy 146.219926 -231.248204)
			(xy 146.266154 -231.34574) (xy 146.302222 -231.381554)
		)
		(stroke
			(width 0)
			(type solid)
		)
		(fill yes)
		(layer "F.Cu")
		(net "M_E_CPU1_SB_DQ<14>")
	)
	(gr_poly
		(pts
			(xy 146.502882 -268.764512) (xy 146.53895 -268.728698) (xy 146.353022 -268.54277) (xy 146.316954 -268.578584)
			(xy 146.270726 -268.67612) (xy 146.4056 -268.81074)
		)
		(stroke
			(width 0)
			(type solid)
		)
		(fill yes)
		(layer "F.Cu")
		(net "M_E_CPU1_SA_CB<2>")
	)
	(gr_poly
		(pts
			(xy 146.50466 -277.257002) (xy 146.597116 -277.201376) (xy 146.559778 -277.014686) (xy 146.453098 -276.999192)
			(xy 146.40306 -277.009098) (xy 146.454876 -277.266908)
		)
		(stroke
			(width 0)
			(type solid)
		)
		(fill yes)
		(layer "F.Cu")
		(net "M_E_CPU1_SA_DQ<24>")
	)
	(gr_poly
		(pts
			(xy 146.512026 -267.911072) (xy 146.548094 -267.875258) (xy 146.362166 -267.68933) (xy 146.326352 -267.725144)
			(xy 146.27987 -267.82268) (xy 146.414744 -267.9573)
		)
		(stroke
			(width 0)
			(type solid)
		)
		(fill yes)
		(layer "F.Cu")
		(net "M_E_CPU1_SA_CB<3>")
	)
	(gr_poly
		(pts
			(xy 146.512788 -233.75874) (xy 146.476974 -233.722672) (xy 146.379438 -233.676444) (xy 146.244818 -233.811064)
			(xy 146.291046 -233.9086) (xy 146.32686 -233.944668)
		)
		(stroke
			(width 0)
			(type solid)
		)
		(fill yes)
		(layer "F.Cu")
		(net "M_E_CPU1_SB_DQ<11>")
	)
	(gr_poly
		(pts
			(xy 146.513296 -277.559516) (xy 146.461734 -277.301706) (xy 146.41195 -277.311612) (xy 146.319494 -277.367238)
			(xy 146.356832 -277.553928) (xy 146.463512 -277.569422)
		)
		(stroke
			(width 0)
			(type solid)
		)
		(fill yes)
		(layer "F.Cu")
		(net "M_E_CPU1_SA_DQ<24>")
	)
	(gr_poly
		(pts
			(xy 146.514312 -228.447092) (xy 146.514312 -228.256592) (xy 146.412712 -228.220524) (xy 146.361912 -228.220524)
			(xy 146.361912 -228.483414) (xy 146.412712 -228.483414)
		)
		(stroke
			(width 0)
			(type solid)
		)
		(fill yes)
		(layer "F.Cu")
		(net "M_E_CPU1_SB_DQ<17>")
	)
	(gr_poly
		(pts
			(xy 146.514312 -227.850192) (xy 146.514312 -227.659692) (xy 146.412712 -227.623624) (xy 146.361912 -227.623624)
			(xy 146.361912 -227.886514) (xy 146.412712 -227.886514)
		)
		(stroke
			(width 0)
			(type solid)
		)
		(fill yes)
		(layer "F.Cu")
		(net "M_E_CPU1_SB_DQ<17>")
	)
	(gr_poly
		(pts
			(xy 146.514312 -227.253292) (xy 146.514312 -227.062792) (xy 146.412712 -227.026724) (xy 146.361912 -227.026724)
			(xy 146.361912 -227.289614) (xy 146.412712 -227.289614)
		)
		(stroke
			(width 0)
			(type solid)
		)
		(fill yes)
		(layer "F.Cu")
		(net "M_E_CPU1_SB_DQ<17>")
	)
	(gr_poly
		(pts
			(xy 146.514312 -226.656392) (xy 146.514312 -226.465892) (xy 146.412712 -226.429824) (xy 146.361912 -226.429824)
			(xy 146.361912 -226.692714) (xy 146.412712 -226.692714)
		)
		(stroke
			(width 0)
			(type solid)
		)
		(fill yes)
		(layer "F.Cu")
		(net "M_E_CPU1_SB_DQ<17>")
	)
	(gr_poly
		(pts
			(xy 146.514312 -226.059492) (xy 146.514312 -225.868992) (xy 146.412712 -225.832924) (xy 146.361912 -225.832924)
			(xy 146.361912 -226.095814) (xy 146.412712 -226.095814)
		)
		(stroke
			(width 0)
			(type solid)
		)
		(fill yes)
		(layer "F.Cu")
		(net "M_E_CPU1_SB_DQ<17>")
	)
	(gr_poly
		(pts
			(xy 146.514312 -225.462592) (xy 146.514312 -225.272092) (xy 146.412712 -225.236024) (xy 146.361912 -225.236024)
			(xy 146.361912 -225.498914) (xy 146.412712 -225.498914)
		)
		(stroke
			(width 0)
			(type solid)
		)
		(fill yes)
		(layer "F.Cu")
		(net "M_E_CPU1_SB_DQ<17>")
	)
	(gr_poly
		(pts
			(xy 146.514312 -224.865692) (xy 146.514312 -224.675192) (xy 146.412712 -224.639124) (xy 146.361912 -224.639124)
			(xy 146.361912 -224.902014) (xy 146.412712 -224.902014)
		)
		(stroke
			(width 0)
			(type solid)
		)
		(fill yes)
		(layer "F.Cu")
		(net "M_E_CPU1_SB_DQ<17>")
	)
	(gr_poly
		(pts
			(xy 146.514312 -224.268792) (xy 146.514312 -224.078292) (xy 146.412712 -224.042224) (xy 146.361912 -224.042224)
			(xy 146.361912 -224.305114) (xy 146.412712 -224.305114)
		)
		(stroke
			(width 0)
			(type solid)
		)
		(fill yes)
		(layer "F.Cu")
		(net "M_E_CPU1_SB_DQ<17>")
	)
	(gr_poly
		(pts
			(xy 146.514312 -223.671892) (xy 146.514312 -223.481392) (xy 146.412712 -223.445324) (xy 146.361912 -223.445324)
			(xy 146.361912 -223.708214) (xy 146.412712 -223.708214)
		)
		(stroke
			(width 0)
			(type solid)
		)
		(fill yes)
		(layer "F.Cu")
		(net "M_E_CPU1_SB_DQ<17>")
	)
	(gr_poly
		(pts
			(xy 146.514312 -223.074992) (xy 146.514312 -222.884492) (xy 146.412712 -222.848424) (xy 146.361912 -222.848424)
			(xy 146.361912 -223.111314) (xy 146.412712 -223.111314)
		)
		(stroke
			(width 0)
			(type solid)
		)
		(fill yes)
		(layer "F.Cu")
		(net "M_E_CPU1_SB_DQ<17>")
	)
	(gr_poly
		(pts
			(xy 146.514312 -222.478092) (xy 146.514312 -222.287592) (xy 146.412712 -222.251524) (xy 146.361912 -222.251524)
			(xy 146.361912 -222.514414) (xy 146.412712 -222.514414)
		)
		(stroke
			(width 0)
			(type solid)
		)
		(fill yes)
		(layer "F.Cu")
		(net "M_E_CPU1_SB_DQ<17>")
	)
	(gr_poly
		(pts
			(xy 146.514312 -221.881192) (xy 146.514312 -221.690692) (xy 146.412712 -221.654624) (xy 146.361912 -221.654624)
			(xy 146.361912 -221.917514) (xy 146.412712 -221.917514)
		)
		(stroke
			(width 0)
			(type solid)
		)
		(fill yes)
		(layer "F.Cu")
		(net "M_E_CPU1_SB_DQ<17>")
	)
	(gr_poly
		(pts
			(xy 146.514312 -221.284292) (xy 146.514312 -221.093792) (xy 146.412712 -221.057724) (xy 146.361912 -221.057724)
			(xy 146.361912 -221.320614) (xy 146.412712 -221.320614)
		)
		(stroke
			(width 0)
			(type solid)
		)
		(fill yes)
		(layer "F.Cu")
		(net "M_E_CPU1_SB_DQ<17>")
	)
	(gr_poly
		(pts
			(xy 146.514312 -220.687392) (xy 146.514312 -220.496892) (xy 146.412712 -220.460824) (xy 146.361912 -220.460824)
			(xy 146.361912 -220.723714) (xy 146.412712 -220.723714)
		)
		(stroke
			(width 0)
			(type solid)
		)
		(fill yes)
		(layer "F.Cu")
		(net "M_E_CPU1_SB_DQ<17>")
	)
	(gr_poly
		(pts
			(xy 146.51736 -274.21078) (xy 146.609816 -274.155408) (xy 146.572478 -273.968464) (xy 146.465798 -273.95297)
			(xy 146.416014 -273.962876) (xy 146.467576 -274.220686)
		)
		(stroke
			(width 0)
			(type solid)
		)
		(fill yes)
		(layer "F.Cu")
		(net "M_E_CPU1_SA_DQ<25>")
	)
	(gr_poly
		(pts
			(xy 146.522948 -234.612688) (xy 146.48688 -234.576874) (xy 146.389598 -234.530646) (xy 146.254724 -234.665266)
			(xy 146.300952 -234.762802) (xy 146.33702 -234.798616)
		)
		(stroke
			(width 0)
			(type solid)
		)
		(fill yes)
		(layer "F.Cu")
		(net "M_E_CPU1_SB_DQ<10>")
	)
	(gr_poly
		(pts
			(xy 146.525996 -274.513294) (xy 146.474434 -274.255484) (xy 146.42465 -274.265644) (xy 146.332194 -274.321016)
			(xy 146.369532 -274.507706) (xy 146.476212 -274.5232)
		)
		(stroke
			(width 0)
			(type solid)
		)
		(fill yes)
		(layer "F.Cu")
		(net "M_E_CPU1_SA_DQ<25>")
	)
	(gr_poly
		(pts
			(xy 146.527012 -271.272762) (xy 146.56308 -271.236948) (xy 146.377152 -271.05102) (xy 146.341084 -271.086834)
			(xy 146.294856 -271.18437) (xy 146.42973 -271.31899)
		)
		(stroke
			(width 0)
			(type solid)
		)
		(fill yes)
		(layer "F.Cu")
		(net "M_E_CPU1_SA_DQ<28>")
	)
	(gr_poly
		(pts
			(xy 146.531076 -236.309154) (xy 146.495008 -236.27334) (xy 146.397726 -236.227112) (xy 146.262852 -236.361732)
			(xy 146.30908 -236.459268) (xy 146.345148 -236.495082)
		)
		(stroke
			(width 0)
			(type solid)
		)
		(fill yes)
		(layer "F.Cu")
		(net "M_E_CPU1_SB_CB<1>")
	)
	(gr_poly
		(pts
			(xy 146.53641 -270.419322) (xy 146.572224 -270.383254) (xy 146.38655 -270.19758) (xy 146.350482 -270.233394)
			(xy 146.304254 -270.33093) (xy 146.438874 -270.46555)
		)
		(stroke
			(width 0)
			(type solid)
		)
		(fill yes)
		(layer "F.Cu")
		(net "M_E_CPU1_SA_DQ<29>")
	)
	(gr_poly
		(pts
			(xy 146.54022 -237.162594) (xy 146.504406 -237.12678) (xy 146.40687 -237.080552) (xy 146.27225 -237.215172)
			(xy 146.318478 -237.312454) (xy 146.354292 -237.348522)
		)
		(stroke
			(width 0)
			(type solid)
		)
		(fill yes)
		(layer "F.Cu")
		(net "M_E_CPU1_SB_CB<0>")
	)
	(gr_poly
		(pts
			(xy 146.55673 -229.205282) (xy 146.510502 -229.108) (xy 146.474688 -229.071932) (xy 146.28876 -229.25786)
			(xy 146.324574 -229.293928) (xy 146.42211 -229.340156)
		)
		(stroke
			(width 0)
			(type solid)
		)
		(fill yes)
		(layer "F.Cu")
		(net "M_E_CPU1_SB_DQ<18>")
	)
	(gr_poly
		(pts
			(xy 146.560286 -265.370564) (xy 146.5961 -265.33475) (xy 146.410172 -265.148822) (xy 146.374358 -265.18489)
			(xy 146.32813 -265.282172) (xy 146.46275 -265.417046)
		)
		(stroke
			(width 0)
			(type solid)
		)
		(fill yes)
		(layer "F.Cu")
		(net "M_E_CPU1_SA_CB<6>")
	)
	(gr_poly
		(pts
			(xy 146.56562 -230.90251) (xy 146.519392 -230.804974) (xy 146.483324 -230.76916) (xy 146.297396 -230.955088)
			(xy 146.333464 -230.990902) (xy 146.430746 -231.03713)
		)
		(stroke
			(width 0)
			(type solid)
		)
		(fill yes)
		(layer "F.Cu")
		(net "M_E_CPU1_SB_DQ<13>")
	)
	(gr_poly
		(pts
			(xy 146.56943 -276.026372) (xy 146.661886 -275.971) (xy 146.624548 -275.78431) (xy 146.517868 -275.768562)
			(xy 146.468084 -275.778722) (xy 146.519646 -276.036532)
		)
		(stroke
			(width 0)
			(type solid)
		)
		(fill yes)
		(layer "F.Cu")
		(net "M_E_CPU1_SA_DQ<26>")
	)
	(gr_poly
		(pts
			(xy 146.56943 -264.517378) (xy 146.605244 -264.48131) (xy 146.41957 -264.295636) (xy 146.383502 -264.33145)
			(xy 146.337274 -264.428986) (xy 146.471894 -264.563606)
		)
		(stroke
			(width 0)
			(type solid)
		)
		(fill yes)
		(layer "F.Cu")
		(net "M_E_CPU1_SA_CB<7>")
	)
	(gr_poly
		(pts
			(xy 146.570192 -269.11935) (xy 146.61642 -269.021814) (xy 146.4818 -268.887194) (xy 146.384264 -268.933422)
			(xy 146.34845 -268.96949) (xy 146.534124 -269.155164)
		)
		(stroke
			(width 0)
			(type solid)
		)
		(fill yes)
		(layer "F.Cu")
		(net "M_E_CPU1_SA_CB<0>")
	)
	(gr_poly
		(pts
			(xy 146.574764 -231.755696) (xy 146.528536 -231.658414) (xy 146.492722 -231.622346) (xy 146.306794 -231.808274)
			(xy 146.342608 -231.844342) (xy 146.440144 -231.89057)
		)
		(stroke
			(width 0)
			(type solid)
		)
		(fill yes)
		(layer "F.Cu")
		(net "M_E_CPU1_SB_DQ<12>")
	)
	(gr_poly
		(pts
			(xy 146.578066 -276.32914) (xy 146.526504 -276.07133) (xy 146.47672 -276.081236) (xy 146.384264 -276.136608)
			(xy 146.421602 -276.323552) (xy 146.528282 -276.339046)
		)
		(stroke
			(width 0)
			(type solid)
		)
		(fill yes)
		(layer "F.Cu")
		(net "M_E_CPU1_SA_DQ<26>")
	)
	(gr_poly
		(pts
			(xy 146.579336 -268.26591) (xy 146.625564 -268.168628) (xy 146.490944 -268.033754) (xy 146.393408 -268.079982)
			(xy 146.357594 -268.11605) (xy 146.543522 -268.301978)
		)
		(stroke
			(width 0)
			(type solid)
		)
		(fill yes)
		(layer "F.Cu")
		(net "M_E_CPU1_SA_CB<1>")
	)
	(gr_poly
		(pts
			(xy 146.59356 -283.87802) (xy 146.59356 -283.68752) (xy 146.49196 -283.651198) (xy 146.44116 -283.651198)
			(xy 146.44116 -283.914342) (xy 146.49196 -283.914342)
		)
		(stroke
			(width 0)
			(type solid)
		)
		(fill yes)
		(layer "F.Cu")
		(net "M_E_CPU1_SA_DQ<23>")
	)
	(gr_poly
		(pts
			(xy 146.59356 -283.28112) (xy 146.59356 -283.09062) (xy 146.49196 -283.054298) (xy 146.44116 -283.054298)
			(xy 146.44116 -283.317442) (xy 146.49196 -283.317442)
		)
		(stroke
			(width 0)
			(type solid)
		)
		(fill yes)
		(layer "F.Cu")
		(net "M_E_CPU1_SA_DQ<23>")
	)
	(gr_poly
		(pts
			(xy 146.59356 -282.68422) (xy 146.59356 -282.49372) (xy 146.49196 -282.457398) (xy 146.44116 -282.457398)
			(xy 146.44116 -282.720542) (xy 146.49196 -282.720542)
		)
		(stroke
			(width 0)
			(type solid)
		)
		(fill yes)
		(layer "F.Cu")
		(net "M_E_CPU1_SA_DQ<23>")
	)
	(gr_poly
		(pts
			(xy 146.59356 -282.08732) (xy 146.59356 -281.89682) (xy 146.49196 -281.860498) (xy 146.44116 -281.860498)
			(xy 146.44116 -282.123642) (xy 146.49196 -282.123642)
		)
		(stroke
			(width 0)
			(type solid)
		)
		(fill yes)
		(layer "F.Cu")
		(net "M_E_CPU1_SA_DQ<23>")
	)
	(gr_poly
		(pts
			(xy 146.59356 -281.49042) (xy 146.59356 -281.29992) (xy 146.49196 -281.263598) (xy 146.44116 -281.263598)
			(xy 146.44116 -281.526742) (xy 146.49196 -281.526742)
		)
		(stroke
			(width 0)
			(type solid)
		)
		(fill yes)
		(layer "F.Cu")
		(net "M_E_CPU1_SA_DQ<23>")
	)
	(gr_poly
		(pts
			(xy 146.59356 -280.89352) (xy 146.59356 -280.70302) (xy 146.49196 -280.666698) (xy 146.44116 -280.666698)
			(xy 146.44116 -280.929842) (xy 146.49196 -280.929842)
		)
		(stroke
			(width 0)
			(type solid)
		)
		(fill yes)
		(layer "F.Cu")
		(net "M_E_CPU1_SA_DQ<23>")
	)
	(gr_poly
		(pts
			(xy 146.59991 -234.319064) (xy 146.553682 -234.221528) (xy 146.517868 -234.185714) (xy 146.33194 -234.371642)
			(xy 146.367754 -234.407456) (xy 146.46529 -234.453684)
		)
		(stroke
			(width 0)
			(type solid)
		)
		(fill yes)
		(layer "F.Cu")
		(net "M_E_CPU1_SB_DQ<9>")
	)
	(gr_poly
		(pts
			(xy 146.603466 -270.77416) (xy 146.649694 -270.676878) (xy 146.515074 -270.542004) (xy 146.417538 -270.588486)
			(xy 146.381724 -270.6243) (xy 146.567652 -270.810228)
		)
		(stroke
			(width 0)
			(type solid)
		)
		(fill yes)
		(layer "F.Cu")
		(net "M_E_CPU1_SA_DQ<30>")
	)
	(gr_poly
		(pts
			(xy 146.608546 -236.016038) (xy 146.562318 -235.918502) (xy 146.526504 -235.882434) (xy 146.340576 -236.068362)
			(xy 146.37639 -236.10443) (xy 146.473926 -236.150658)
		)
		(stroke
			(width 0)
			(type solid)
		)
		(fill yes)
		(layer "F.Cu")
		(net "M_E_CPU1_SB_CB<3>")
	)
	(gr_poly
		(pts
			(xy 146.609816 -235.173012) (xy 146.563588 -235.075476) (xy 146.52752 -235.039662) (xy 146.341592 -235.22559)
			(xy 146.37766 -235.261404) (xy 146.474942 -235.307632)
		)
		(stroke
			(width 0)
			(type solid)
		)
		(fill yes)
		(layer "F.Cu")
		(net "M_E_CPU1_SB_DQ<8>")
	)
	(gr_poly
		(pts
			(xy 146.613118 -269.92072) (xy 146.659346 -269.823184) (xy 146.524472 -269.688564) (xy 146.42719 -269.734792)
			(xy 146.391122 -269.770606) (xy 146.57705 -269.956534)
		)
		(stroke
			(width 0)
			(type solid)
		)
		(fill yes)
		(layer "F.Cu")
		(net "M_E_CPU1_SA_DQ<31>")
	)
	(gr_poly
		(pts
			(xy 146.617944 -236.869224) (xy 146.571716 -236.771688) (xy 146.535648 -236.735874) (xy 146.34972 -236.921802)
			(xy 146.385788 -236.957616) (xy 146.48307 -237.003844)
		)
		(stroke
			(width 0)
			(type solid)
		)
		(fill yes)
		(layer "F.Cu")
		(net "M_E_CPU1_SB_CB<2>")
	)
	(gr_poly
		(pts
			(xy 146.621754 -277.842218) (xy 146.71421 -277.786846) (xy 146.676872 -277.599902) (xy 146.570192 -277.584408)
			(xy 146.520154 -277.594314) (xy 146.571716 -277.852124)
		)
		(stroke
			(width 0)
			(type solid)
		)
		(fill yes)
		(layer "F.Cu")
		(net "M_E_CPU1_SA_DQ<24>")
	)
	(gr_poly
		(pts
			(xy 146.627342 -265.725656) (xy 146.67357 -265.62812) (xy 146.53895 -265.4935) (xy 146.441414 -265.539728)
			(xy 146.4056 -265.575542) (xy 146.591528 -265.76147)
		)
		(stroke
			(width 0)
			(type solid)
		)
		(fill yes)
		(layer "F.Cu")
		(net "M_E_CPU1_SA_CB<4>")
	)
	(gr_poly
		(pts
			(xy 146.63039 -278.144732) (xy 146.578828 -277.886922) (xy 146.529044 -277.897082) (xy 146.436334 -277.952454)
			(xy 146.473926 -278.139144) (xy 146.580606 -278.154892)
		)
		(stroke
			(width 0)
			(type solid)
		)
		(fill yes)
		(layer "F.Cu")
		(net "M_E_CPU1_SA_DQ<24>")
	)
	(gr_poly
		(pts
			(xy 146.634454 -274.795996) (xy 146.72691 -274.740624) (xy 146.689572 -274.55368) (xy 146.582892 -274.538186)
			(xy 146.533108 -274.548092) (xy 146.58467 -274.805902)
		)
		(stroke
			(width 0)
			(type solid)
		)
		(fill yes)
		(layer "F.Cu")
		(net "M_E_CPU1_SA_DQ<25>")
	)
	(gr_poly
		(pts
			(xy 146.63674 -264.872216) (xy 146.682968 -264.77468) (xy 146.548094 -264.64006) (xy 146.450812 -264.686288)
			(xy 146.414744 -264.722102) (xy 146.600672 -264.90803)
		)
		(stroke
			(width 0)
			(type solid)
		)
		(fill yes)
		(layer "F.Cu")
		(net "M_E_CPU1_SA_CB<5>")
	)
	(gr_poly
		(pts
			(xy 146.64309 -275.098764) (xy 146.591528 -274.840954) (xy 146.541744 -274.85086) (xy 146.449288 -274.906232)
			(xy 146.486626 -275.093176) (xy 146.593306 -275.10867)
		)
		(stroke
			(width 0)
			(type solid)
		)
		(fill yes)
		(layer "F.Cu")
		(net "M_E_CPU1_SA_DQ<25>")
	)
	(gr_poly
		(pts
			(xy 146.666712 -227.922074) (xy 146.615912 -227.922074) (xy 146.514312 -227.958142) (xy 146.514312 -228.148642)
			(xy 146.615912 -228.184964) (xy 146.666712 -228.184964)
		)
		(stroke
			(width 0)
			(type solid)
		)
		(fill yes)
		(layer "F.Cu")
		(net "M_E_CPU1_SB_DQ<18>")
	)
	(gr_poly
		(pts
			(xy 146.666712 -227.325174) (xy 146.615912 -227.325174) (xy 146.514312 -227.361242) (xy 146.514312 -227.551742)
			(xy 146.615912 -227.588064) (xy 146.666712 -227.588064)
		)
		(stroke
			(width 0)
			(type solid)
		)
		(fill yes)
		(layer "F.Cu")
		(net "M_E_CPU1_SB_DQ<18>")
	)
	(gr_poly
		(pts
			(xy 146.666712 -226.728274) (xy 146.615912 -226.728274) (xy 146.514312 -226.764342) (xy 146.514312 -226.954842)
			(xy 146.615912 -226.991164) (xy 146.666712 -226.991164)
		)
		(stroke
			(width 0)
			(type solid)
		)
		(fill yes)
		(layer "F.Cu")
		(net "M_E_CPU1_SB_DQ<18>")
	)
	(gr_poly
		(pts
			(xy 146.666712 -226.131374) (xy 146.615912 -226.131374) (xy 146.514312 -226.167442) (xy 146.514312 -226.357942)
			(xy 146.615912 -226.394264) (xy 146.666712 -226.394264)
		)
		(stroke
			(width 0)
			(type solid)
		)
		(fill yes)
		(layer "F.Cu")
		(net "M_E_CPU1_SB_DQ<18>")
	)
	(gr_poly
		(pts
			(xy 146.666712 -225.534474) (xy 146.615912 -225.534474) (xy 146.514312 -225.570542) (xy 146.514312 -225.761042)
			(xy 146.615912 -225.797364) (xy 146.666712 -225.797364)
		)
		(stroke
			(width 0)
			(type solid)
		)
		(fill yes)
		(layer "F.Cu")
		(net "M_E_CPU1_SB_DQ<18>")
	)
	(gr_poly
		(pts
			(xy 146.666712 -224.937574) (xy 146.615912 -224.937574) (xy 146.514312 -224.973642) (xy 146.514312 -225.164142)
			(xy 146.615912 -225.200464) (xy 146.666712 -225.200464)
		)
		(stroke
			(width 0)
			(type solid)
		)
		(fill yes)
		(layer "F.Cu")
		(net "M_E_CPU1_SB_DQ<18>")
	)
	(gr_poly
		(pts
			(xy 146.666712 -224.340674) (xy 146.615912 -224.340674) (xy 146.514312 -224.376742) (xy 146.514312 -224.567242)
			(xy 146.615912 -224.603564) (xy 146.666712 -224.603564)
		)
		(stroke
			(width 0)
			(type solid)
		)
		(fill yes)
		(layer "F.Cu")
		(net "M_E_CPU1_SB_DQ<18>")
	)
	(gr_poly
		(pts
			(xy 146.666712 -223.743774) (xy 146.615912 -223.743774) (xy 146.514312 -223.779842) (xy 146.514312 -223.970342)
			(xy 146.615912 -224.006664) (xy 146.666712 -224.006664)
		)
		(stroke
			(width 0)
			(type solid)
		)
		(fill yes)
		(layer "F.Cu")
		(net "M_E_CPU1_SB_DQ<18>")
	)
	(gr_poly
		(pts
			(xy 146.666712 -223.146874) (xy 146.615912 -223.146874) (xy 146.514312 -223.182942) (xy 146.514312 -223.373442)
			(xy 146.615912 -223.409764) (xy 146.666712 -223.409764)
		)
		(stroke
			(width 0)
			(type solid)
		)
		(fill yes)
		(layer "F.Cu")
		(net "M_E_CPU1_SB_DQ<18>")
	)
	(gr_poly
		(pts
			(xy 146.666712 -222.549974) (xy 146.615912 -222.549974) (xy 146.514312 -222.586042) (xy 146.514312 -222.776542)
			(xy 146.615912 -222.812864) (xy 146.666712 -222.812864)
		)
		(stroke
			(width 0)
			(type solid)
		)
		(fill yes)
		(layer "F.Cu")
		(net "M_E_CPU1_SB_DQ<18>")
	)
	(gr_poly
		(pts
			(xy 146.666712 -221.953074) (xy 146.615912 -221.953074) (xy 146.514312 -221.989142) (xy 146.514312 -222.179642)
			(xy 146.615912 -222.215964) (xy 146.666712 -222.215964)
		)
		(stroke
			(width 0)
			(type solid)
		)
		(fill yes)
		(layer "F.Cu")
		(net "M_E_CPU1_SB_DQ<18>")
	)
	(gr_poly
		(pts
			(xy 146.666712 -221.356174) (xy 146.615912 -221.356174) (xy 146.514312 -221.392242) (xy 146.514312 -221.582742)
			(xy 146.615912 -221.619064) (xy 146.666712 -221.619064)
		)
		(stroke
			(width 0)
			(type solid)
		)
		(fill yes)
		(layer "F.Cu")
		(net "M_E_CPU1_SB_DQ<18>")
	)
	(gr_poly
		(pts
			(xy 146.666712 -220.759274) (xy 146.615912 -220.759274) (xy 146.514312 -220.795342) (xy 146.514312 -220.985842)
			(xy 146.615912 -221.022164) (xy 146.666712 -221.022164)
		)
		(stroke
			(width 0)
			(type solid)
		)
		(fill yes)
		(layer "F.Cu")
		(net "M_E_CPU1_SB_DQ<18>")
	)
	(gr_poly
		(pts
			(xy 146.666712 -220.162374) (xy 146.615912 -220.162374) (xy 146.514312 -220.198442) (xy 146.514312 -220.388942)
			(xy 146.615912 -220.425264) (xy 146.666712 -220.425264)
		)
		(stroke
			(width 0)
			(type solid)
		)
		(fill yes)
		(layer "F.Cu")
		(net "M_E_CPU1_SB_DQ<18>")
	)
	(gr_poly
		(pts
			(xy 146.686524 -276.611842) (xy 146.77898 -276.556216) (xy 146.741642 -276.369526) (xy 146.634962 -276.354032)
			(xy 146.585178 -276.363938) (xy 146.63674 -276.621748)
		)
		(stroke
			(width 0)
			(type solid)
		)
		(fill yes)
		(layer "F.Cu")
		(net "M_E_CPU1_SA_DQ<26>")
	)
	(gr_poly
		(pts
			(xy 146.694398 -230.558086) (xy 146.658584 -230.522018) (xy 146.561048 -230.47579) (xy 146.426428 -230.610664)
			(xy 146.472656 -230.707946) (xy 146.50847 -230.744014)
		)
		(stroke
			(width 0)
			(type solid)
		)
		(fill yes)
		(layer "F.Cu")
		(net "M_E_CPU1_SB_DQ<13>")
	)
	(gr_poly
		(pts
			(xy 146.69516 -276.914356) (xy 146.643598 -276.656546) (xy 146.593814 -276.666452) (xy 146.501358 -276.722078)
			(xy 146.538696 -276.908768) (xy 146.645376 -276.924262)
		)
		(stroke
			(width 0)
			(type solid)
		)
		(fill yes)
		(layer "F.Cu")
		(net "M_E_CPU1_SA_DQ<26>")
	)
	(gr_poly
		(pts
			(xy 146.703542 -231.411526) (xy 146.667728 -231.375458) (xy 146.570192 -231.32923) (xy 146.435572 -231.46385)
			(xy 146.4818 -231.561386) (xy 146.517868 -231.5972)
		)
		(stroke
			(width 0)
			(type solid)
		)
		(fill yes)
		(layer "F.Cu")
		(net "M_E_CPU1_SB_DQ<12>")
	)
	(gr_poly
		(pts
			(xy 146.709384 -269.402306) (xy 146.745198 -269.366238) (xy 146.55927 -269.18031) (xy 146.523456 -269.216378)
			(xy 146.477228 -269.31366) (xy 146.611848 -269.448534)
		)
		(stroke
			(width 0)
			(type solid)
		)
		(fill yes)
		(layer "F.Cu")
		(net "M_E_CPU1_SA_CB<0>")
	)
	(gr_poly
		(pts
			(xy 146.718528 -268.548866) (xy 146.754596 -268.513052) (xy 146.568668 -268.327124) (xy 146.5326 -268.362938)
			(xy 146.486372 -268.460474) (xy 146.621246 -268.595094)
		)
		(stroke
			(width 0)
			(type solid)
		)
		(fill yes)
		(layer "F.Cu")
		(net "M_E_CPU1_SA_CB<1>")
	)
	(gr_poly
		(pts
			(xy 146.728942 -233.97464) (xy 146.692874 -233.938826) (xy 146.595592 -233.892598) (xy 146.460718 -234.027218)
			(xy 146.506946 -234.1245) (xy 146.543014 -234.160568)
		)
		(stroke
			(width 0)
			(type solid)
		)
		(fill yes)
		(layer "F.Cu")
		(net "M_E_CPU1_SB_DQ<9>")
	)
	(gr_poly
		(pts
			(xy 146.738594 -278.427434) (xy 146.831304 -278.372062) (xy 146.793966 -278.185372) (xy 146.687032 -278.169624)
			(xy 146.637248 -278.179784) (xy 146.68881 -278.437594)
		)
		(stroke
			(width 0)
			(type solid)
		)
		(fill yes)
		(layer "F.Cu")
		(net "M_E_CPU1_SA_DQ<24>")
	)
	(gr_poly
		(pts
			(xy 146.738594 -234.828588) (xy 146.70278 -234.792774) (xy 146.605244 -234.746292) (xy 146.470624 -234.881166)
			(xy 146.516852 -234.978448) (xy 146.552666 -235.014516)
		)
		(stroke
			(width 0)
			(type solid)
		)
		(fill yes)
		(layer "F.Cu")
		(net "M_E_CPU1_SB_DQ<8>")
	)
	(gr_poly
		(pts
			(xy 146.742658 -271.057116) (xy 146.778726 -271.021302) (xy 146.592798 -270.835374) (xy 146.55673 -270.871188)
			(xy 146.510502 -270.968724) (xy 146.645376 -271.103344)
		)
		(stroke
			(width 0)
			(type solid)
		)
		(fill yes)
		(layer "F.Cu")
		(net "M_E_CPU1_SA_DQ<30>")
	)
	(gr_poly
		(pts
			(xy 146.746722 -236.5248) (xy 146.710908 -236.488986) (xy 146.613372 -236.442758) (xy 146.478752 -236.577378)
			(xy 146.52498 -236.67466) (xy 146.560794 -236.710728)
		)
		(stroke
			(width 0)
			(type solid)
		)
		(fill yes)
		(layer "F.Cu")
		(net "M_E_CPU1_SB_CB<2>")
	)
	(gr_poly
		(pts
			(xy 146.747484 -278.730202) (xy 146.695922 -278.472392) (xy 146.646138 -278.482298) (xy 146.553428 -278.53767)
			(xy 146.59102 -278.724614) (xy 146.6977 -278.740108)
		)
		(stroke
			(width 0)
			(type solid)
		)
		(fill yes)
		(layer "F.Cu")
		(net "M_E_CPU1_SA_DQ<24>")
	)
	(gr_poly
		(pts
			(xy 146.751548 -275.381212) (xy 146.844004 -275.32584) (xy 146.806666 -275.13915) (xy 146.699986 -275.123656)
			(xy 146.650202 -275.133562) (xy 146.701764 -275.391372)
		)
		(stroke
			(width 0)
			(type solid)
		)
		(fill yes)
		(layer "F.Cu")
		(net "M_E_CPU1_SA_DQ<25>")
	)
	(gr_poly
		(pts
			(xy 146.75231 -270.203422) (xy 146.788124 -270.167608) (xy 146.602196 -269.98168) (xy 146.566382 -270.017494)
			(xy 146.520154 -270.11503) (xy 146.654774 -270.24965)
		)
		(stroke
			(width 0)
			(type solid)
		)
		(fill yes)
		(layer "F.Cu")
		(net "M_E_CPU1_SA_DQ<31>")
	)
	(gr_poly
		(pts
			(xy 146.760438 -275.68398) (xy 146.708622 -275.42617) (xy 146.658838 -275.436076) (xy 146.566382 -275.491448)
			(xy 146.60372 -275.678392) (xy 146.7104 -275.693886)
		)
		(stroke
			(width 0)
			(type solid)
		)
		(fill yes)
		(layer "F.Cu")
		(net "M_E_CPU1_SA_DQ<25>")
	)
	(gr_poly
		(pts
			(xy 146.766534 -266.008358) (xy 146.802602 -265.972544) (xy 146.616674 -265.786616) (xy 146.58086 -265.82243)
			(xy 146.534378 -265.919966) (xy 146.669252 -266.054586)
		)
		(stroke
			(width 0)
			(type solid)
		)
		(fill yes)
		(layer "F.Cu")
		(net "M_E_CPU1_SA_CB<4>")
	)
	(gr_poly
		(pts
			(xy 146.771868 -230.264716) (xy 146.72564 -230.16718) (xy 146.689826 -230.131366) (xy 146.503898 -230.317294)
			(xy 146.539712 -230.353108) (xy 146.637248 -230.399336)
		)
		(stroke
			(width 0)
			(type solid)
		)
		(fill yes)
		(layer "F.Cu")
		(net "M_E_CPU1_SB_DQ<15>")
	)
	(gr_poly
		(pts
			(xy 146.772376 -229.420928) (xy 146.726148 -229.323646) (xy 146.690334 -229.287578) (xy 146.504406 -229.473506)
			(xy 146.54022 -229.509574) (xy 146.637756 -229.555802)
		)
		(stroke
			(width 0)
			(type solid)
		)
		(fill yes)
		(layer "F.Cu")
		(net "M_E_CPU1_SB_DQ<16>")
	)
	(gr_poly
		(pts
			(xy 146.775932 -265.154918) (xy 146.811746 -265.119104) (xy 146.625818 -264.933176) (xy 146.590004 -264.969244)
			(xy 146.543776 -265.066526) (xy 146.678396 -265.2014)
		)
		(stroke
			(width 0)
			(type solid)
		)
		(fill yes)
		(layer "F.Cu")
		(net "M_E_CPU1_SA_CB<5>")
	)
	(gr_poly
		(pts
			(xy 146.781266 -231.118156) (xy 146.735038 -231.02062) (xy 146.69897 -230.984806) (xy 146.513042 -231.170734)
			(xy 146.54911 -231.206548) (xy 146.646392 -231.252776)
		)
		(stroke
			(width 0)
			(type solid)
		)
		(fill yes)
		(layer "F.Cu")
		(net "M_E_CPU1_SB_DQ<14>")
	)
	(gr_poly
		(pts
			(xy 146.785838 -268.903704) (xy 146.832066 -268.806168) (xy 146.697446 -268.671548) (xy 146.59991 -268.717776)
			(xy 146.564096 -268.753844) (xy 146.74977 -268.939518)
		)
		(stroke
			(width 0)
			(type solid)
		)
		(fill yes)
		(layer "F.Cu")
		(net "M_E_CPU1_SA_CB<2>")
	)
	(gr_poly
		(pts
			(xy 146.794982 -268.050264) (xy 146.84121 -267.952982) (xy 146.70659 -267.818108) (xy 146.609054 -267.864336)
			(xy 146.57324 -267.900404) (xy 146.759168 -268.086332)
		)
		(stroke
			(width 0)
			(type solid)
		)
		(fill yes)
		(layer "F.Cu")
		(net "M_E_CPU1_SA_CB<3>")
	)
	(gr_poly
		(pts
			(xy 146.803618 -277.197058) (xy 146.896074 -277.141686) (xy 146.858736 -276.954742) (xy 146.752056 -276.939248)
			(xy 146.702272 -276.949154) (xy 146.753834 -277.206964)
		)
		(stroke
			(width 0)
			(type solid)
		)
		(fill yes)
		(layer "F.Cu")
		(net "M_E_CPU1_SA_DQ<26>")
	)
	(gr_poly
		(pts
			(xy 146.806158 -233.681016) (xy 146.75993 -233.58348) (xy 146.723862 -233.547666) (xy 146.537934 -233.733594)
			(xy 146.574002 -233.769408) (xy 146.671284 -233.815636)
		)
		(stroke
			(width 0)
			(type solid)
		)
		(fill yes)
		(layer "F.Cu")
		(net "M_E_CPU1_SB_DQ<11>")
	)
	(gr_poly
		(pts
			(xy 146.809968 -271.411954) (xy 146.856196 -271.314418) (xy 146.721576 -271.179798) (xy 146.62404 -271.226026)
			(xy 146.588226 -271.262094) (xy 146.7739 -271.447768)
		)
		(stroke
			(width 0)
			(type solid)
		)
		(fill yes)
		(layer "F.Cu")
		(net "M_E_CPU1_SA_DQ<28>")
	)
	(gr_poly
		(pts
			(xy 146.812254 -277.499572) (xy 146.760692 -277.242016) (xy 146.710908 -277.251922) (xy 146.618452 -277.307294)
			(xy 146.65579 -277.493984) (xy 146.76247 -277.509732)
		)
		(stroke
			(width 0)
			(type solid)
		)
		(fill yes)
		(layer "F.Cu")
		(net "M_E_CPU1_SA_DQ<26>")
	)
	(gr_poly
		(pts
			(xy 146.816064 -234.535218) (xy 146.769836 -234.437682) (xy 146.733768 -234.401868) (xy 146.548094 -234.587542)
			(xy 146.583908 -234.62361) (xy 146.681444 -234.669838)
		)
		(stroke
			(width 0)
			(type solid)
		)
		(fill yes)
		(layer "F.Cu")
		(net "M_E_CPU1_SB_DQ<10>")
	)
	(gr_poly
		(pts
			(xy 146.816826 -274.150836) (xy 146.909282 -274.095464) (xy 146.871944 -273.90852) (xy 146.76501 -273.893026)
			(xy 146.715226 -273.902932) (xy 146.766788 -274.160742)
		)
		(stroke
			(width 0)
			(type solid)
		)
		(fill yes)
		(layer "F.Cu")
		(net "M_E_CPU1_SA_DQ<27>")
	)
	(gr_poly
		(pts
			(xy 146.819112 -228.447092) (xy 146.819112 -228.256592) (xy 146.717512 -228.220524) (xy 146.666712 -228.220524)
			(xy 146.666712 -228.483414) (xy 146.717512 -228.483414)
		)
		(stroke
			(width 0)
			(type solid)
		)
		(fill yes)
		(layer "F.Cu")
		(net "M_E_CPU1_SB_DQ<18>")
	)
	(gr_poly
		(pts
			(xy 146.819112 -227.850192) (xy 146.819112 -227.659692) (xy 146.717512 -227.623624) (xy 146.666712 -227.623624)
			(xy 146.666712 -227.886514) (xy 146.717512 -227.886514)
		)
		(stroke
			(width 0)
			(type solid)
		)
		(fill yes)
		(layer "F.Cu")
		(net "M_E_CPU1_SB_DQ<18>")
	)
	(gr_poly
		(pts
			(xy 146.819112 -227.253292) (xy 146.819112 -227.062792) (xy 146.717512 -227.026724) (xy 146.666712 -227.026724)
			(xy 146.666712 -227.289614) (xy 146.717512 -227.289614)
		)
		(stroke
			(width 0)
			(type solid)
		)
		(fill yes)
		(layer "F.Cu")
		(net "M_E_CPU1_SB_DQ<18>")
	)
	(gr_poly
		(pts
			(xy 146.819112 -226.656392) (xy 146.819112 -226.465892) (xy 146.717512 -226.429824) (xy 146.666712 -226.429824)
			(xy 146.666712 -226.692714) (xy 146.717512 -226.692714)
		)
		(stroke
			(width 0)
			(type solid)
		)
		(fill yes)
		(layer "F.Cu")
		(net "M_E_CPU1_SB_DQ<18>")
	)
	(gr_poly
		(pts
			(xy 146.819112 -226.059492) (xy 146.819112 -225.868992) (xy 146.717512 -225.832924) (xy 146.666712 -225.832924)
			(xy 146.666712 -226.095814) (xy 146.717512 -226.095814)
		)
		(stroke
			(width 0)
			(type solid)
		)
		(fill yes)
		(layer "F.Cu")
		(net "M_E_CPU1_SB_DQ<18>")
	)
	(gr_poly
		(pts
			(xy 146.819112 -225.462592) (xy 146.819112 -225.272092) (xy 146.717512 -225.236024) (xy 146.666712 -225.236024)
			(xy 146.666712 -225.498914) (xy 146.717512 -225.498914)
		)
		(stroke
			(width 0)
			(type solid)
		)
		(fill yes)
		(layer "F.Cu")
		(net "M_E_CPU1_SB_DQ<18>")
	)
	(gr_poly
		(pts
			(xy 146.819112 -224.865692) (xy 146.819112 -224.675192) (xy 146.717512 -224.639124) (xy 146.666712 -224.639124)
			(xy 146.666712 -224.902014) (xy 146.717512 -224.902014)
		)
		(stroke
			(width 0)
			(type solid)
		)
		(fill yes)
		(layer "F.Cu")
		(net "M_E_CPU1_SB_DQ<18>")
	)
	(gr_poly
		(pts
			(xy 146.819112 -224.268792) (xy 146.819112 -224.078292) (xy 146.717512 -224.042224) (xy 146.666712 -224.042224)
			(xy 146.666712 -224.305114) (xy 146.717512 -224.305114)
		)
		(stroke
			(width 0)
			(type solid)
		)
		(fill yes)
		(layer "F.Cu")
		(net "M_E_CPU1_SB_DQ<18>")
	)
	(gr_poly
		(pts
			(xy 146.819112 -223.671892) (xy 146.819112 -223.481392) (xy 146.717512 -223.445324) (xy 146.666712 -223.445324)
			(xy 146.666712 -223.708214) (xy 146.717512 -223.708214)
		)
		(stroke
			(width 0)
			(type solid)
		)
		(fill yes)
		(layer "F.Cu")
		(net "M_E_CPU1_SB_DQ<18>")
	)
	(gr_poly
		(pts
			(xy 146.819112 -223.074992) (xy 146.819112 -222.884492) (xy 146.717512 -222.848424) (xy 146.666712 -222.848424)
			(xy 146.666712 -223.111314) (xy 146.717512 -223.111314)
		)
		(stroke
			(width 0)
			(type solid)
		)
		(fill yes)
		(layer "F.Cu")
		(net "M_E_CPU1_SB_DQ<18>")
	)
	(gr_poly
		(pts
			(xy 146.819112 -222.478092) (xy 146.819112 -222.287592) (xy 146.717512 -222.251524) (xy 146.666712 -222.251524)
			(xy 146.666712 -222.514414) (xy 146.717512 -222.514414)
		)
		(stroke
			(width 0)
			(type solid)
		)
		(fill yes)
		(layer "F.Cu")
		(net "M_E_CPU1_SB_DQ<18>")
	)
	(gr_poly
		(pts
			(xy 146.819112 -221.881192) (xy 146.819112 -221.690692) (xy 146.717512 -221.654624) (xy 146.666712 -221.654624)
			(xy 146.666712 -221.917514) (xy 146.717512 -221.917514)
		)
		(stroke
			(width 0)
			(type solid)
		)
		(fill yes)
		(layer "F.Cu")
		(net "M_E_CPU1_SB_DQ<18>")
	)
	(gr_poly
		(pts
			(xy 146.819112 -221.284292) (xy 146.819112 -221.093792) (xy 146.717512 -221.057724) (xy 146.666712 -221.057724)
			(xy 146.666712 -221.320614) (xy 146.717512 -221.320614)
		)
		(stroke
			(width 0)
			(type solid)
		)
		(fill yes)
		(layer "F.Cu")
		(net "M_E_CPU1_SB_DQ<18>")
	)
	(gr_poly
		(pts
			(xy 146.819112 -220.687392) (xy 146.819112 -220.496892) (xy 146.717512 -220.460824) (xy 146.666712 -220.460824)
			(xy 146.666712 -220.723714) (xy 146.717512 -220.723714)
		)
		(stroke
			(width 0)
			(type solid)
		)
		(fill yes)
		(layer "F.Cu")
		(net "M_E_CPU1_SB_DQ<18>")
	)
	(gr_poly
		(pts
			(xy 146.819366 -270.558514) (xy 146.865594 -270.460978) (xy 146.73072 -270.326358) (xy 146.633438 -270.372586)
			(xy 146.59737 -270.4084) (xy 146.783298 -270.594328)
		)
		(stroke
			(width 0)
			(type solid)
		)
		(fill yes)
		(layer "F.Cu")
		(net "M_E_CPU1_SA_DQ<29>")
	)
	(gr_poly
		(pts
			(xy 146.824192 -236.231684) (xy 146.777964 -236.134148) (xy 146.74215 -236.09808) (xy 146.556222 -236.284008)
			(xy 146.592036 -236.320076) (xy 146.689572 -236.366304)
		)
		(stroke
			(width 0)
			(type solid)
		)
		(fill yes)
		(layer "F.Cu")
		(net "M_E_CPU1_SB_CB<1>")
	)
	(gr_poly
		(pts
			(xy 146.825462 -274.45335) (xy 146.7739 -274.195794) (xy 146.724116 -274.2057) (xy 146.63166 -274.261072)
			(xy 146.668998 -274.447762) (xy 146.775678 -274.46351)
		)
		(stroke
			(width 0)
			(type solid)
		)
		(fill yes)
		(layer "F.Cu")
		(net "M_E_CPU1_SA_DQ<27>")
	)
	(gr_poly
		(pts
			(xy 146.833336 -237.08487) (xy 146.787108 -236.987588) (xy 146.751294 -236.95152) (xy 146.565366 -237.137448)
			(xy 146.60118 -237.173262) (xy 146.698716 -237.219744)
		)
		(stroke
			(width 0)
			(type solid)
		)
		(fill yes)
		(layer "F.Cu")
		(net "M_E_CPU1_SB_CB<0>")
	)
	(gr_poly
		(pts
			(xy 146.842988 -265.51001) (xy 146.889216 -265.412474) (xy 146.754596 -265.277854) (xy 146.65706 -265.324082)
			(xy 146.621246 -265.359896) (xy 146.807174 -265.545824)
		)
		(stroke
			(width 0)
			(type solid)
		)
		(fill yes)
		(layer "F.Cu")
		(net "M_E_CPU1_SA_CB<6>")
	)
	(gr_poly
		(pts
			(xy 146.852386 -264.65657) (xy 146.898614 -264.559034) (xy 146.76374 -264.424414) (xy 146.666458 -264.470642)
			(xy 146.63039 -264.506456) (xy 146.816318 -264.692384)
		)
		(stroke
			(width 0)
			(type solid)
		)
		(fill yes)
		(layer "F.Cu")
		(net "M_E_CPU1_SA_CB<7>")
	)
	(gr_poly
		(pts
			(xy 146.855688 -279.012904) (xy 146.948398 -278.957278) (xy 146.91106 -278.770588) (xy 146.804126 -278.755094)
			(xy 146.754342 -278.765) (xy 146.805904 -279.02281)
		)
		(stroke
			(width 0)
			(type solid)
		)
		(fill yes)
		(layer "F.Cu")
		(net "M_E_CPU1_SA_DQ<24>")
	)
	(gr_poly
		(pts
			(xy 146.864578 -279.315418) (xy 146.813016 -279.057608) (xy 146.763232 -279.067514) (xy 146.670522 -279.12314)
			(xy 146.70786 -279.30983) (xy 146.814794 -279.325324)
		)
		(stroke
			(width 0)
			(type solid)
		)
		(fill yes)
		(layer "F.Cu")
		(net "M_E_CPU1_SA_DQ<24>")
	)
	(gr_poly
		(pts
			(xy 146.868642 -275.966682) (xy 146.961098 -275.91131) (xy 146.92376 -275.724366) (xy 146.81708 -275.708872)
			(xy 146.767296 -275.718778) (xy 146.818858 -275.976588)
		)
		(stroke
			(width 0)
			(type solid)
		)
		(fill yes)
		(layer "F.Cu")
		(net "M_E_CPU1_SA_DQ<25>")
	)
	(gr_poly
		(pts
			(xy 146.877532 -276.269196) (xy 146.82597 -276.011386) (xy 146.776186 -276.021292) (xy 146.683476 -276.076918)
			(xy 146.720814 -276.263608) (xy 146.827748 -276.279102)
		)
		(stroke
			(width 0)
			(type solid)
		)
		(fill yes)
		(layer "F.Cu")
		(net "M_E_CPU1_SA_DQ<25>")
	)
	(gr_poly
		(pts
			(xy 146.9009 -229.920292) (xy 146.864832 -229.884478) (xy 146.76755 -229.83825) (xy 146.632676 -229.97287)
			(xy 146.679158 -230.070406) (xy 146.714972 -230.10622)
		)
		(stroke
			(width 0)
			(type solid)
		)
		(fill yes)
		(layer "F.Cu")
		(net "M_E_CPU1_SB_DQ<15>")
	)
	(gr_poly
		(pts
			(xy 146.910044 -230.773732) (xy 146.87423 -230.737664) (xy 146.776694 -230.691436) (xy 146.642074 -230.82631)
			(xy 146.688302 -230.923592) (xy 146.724116 -230.95966)
		)
		(stroke
			(width 0)
			(type solid)
		)
		(fill yes)
		(layer "F.Cu")
		(net "M_E_CPU1_SB_DQ<14>")
	)
	(gr_poly
		(pts
			(xy 146.920712 -277.782274) (xy 147.013168 -277.726902) (xy 146.97583 -277.540212) (xy 146.86915 -277.524718)
			(xy 146.819366 -277.534624) (xy 146.870928 -277.792434)
		)
		(stroke
			(width 0)
			(type solid)
		)
		(fill yes)
		(layer "F.Cu")
		(net "M_E_CPU1_SA_DQ<26>")
	)
	(gr_poly
		(pts
			(xy 146.92503 -269.18666) (xy 146.960844 -269.150592) (xy 146.774916 -268.964664) (xy 146.739102 -269.000732)
			(xy 146.692874 -269.098014) (xy 146.827494 -269.232888)
		)
		(stroke
			(width 0)
			(type solid)
		)
		(fill yes)
		(layer "F.Cu")
		(net "M_E_CPU1_SA_CB<2>")
	)
	(gr_poly
		(pts
			(xy 146.929348 -278.085042) (xy 146.877786 -277.827232) (xy 146.828002 -277.837138) (xy 146.735546 -277.89251)
			(xy 146.772884 -278.079454) (xy 146.879564 -278.094948)
		)
		(stroke
			(width 0)
			(type solid)
		)
		(fill yes)
		(layer "F.Cu")
		(net "M_E_CPU1_SA_DQ<26>")
	)
	(gr_poly
		(pts
			(xy 146.93392 -274.736052) (xy 147.026376 -274.68068) (xy 146.989038 -274.49399) (xy 146.882358 -274.478242)
			(xy 146.83232 -274.488402) (xy 146.883882 -274.746212)
		)
		(stroke
			(width 0)
			(type solid)
		)
		(fill yes)
		(layer "F.Cu")
		(net "M_E_CPU1_SA_DQ<27>")
	)
	(gr_poly
		(pts
			(xy 146.934174 -268.33322) (xy 146.970242 -268.297406) (xy 146.784314 -268.111478) (xy 146.748246 -268.147292)
			(xy 146.702018 -268.244828) (xy 146.836892 -268.379448)
		)
		(stroke
			(width 0)
			(type solid)
		)
		(fill yes)
		(layer "F.Cu")
		(net "M_E_CPU1_SA_CB<3>")
	)
	(gr_poly
		(pts
			(xy 146.934936 -233.336592) (xy 146.899122 -233.300778) (xy 146.801586 -233.25455) (xy 146.666966 -233.38917)
			(xy 146.713194 -233.486452) (xy 146.749008 -233.52252)
		)
		(stroke
			(width 0)
			(type solid)
		)
		(fill yes)
		(layer "F.Cu")
		(net "M_E_CPU1_SB_DQ<11>")
	)
	(gr_poly
		(pts
			(xy 146.942556 -275.03882) (xy 146.890994 -274.78101) (xy 146.84121 -274.790916) (xy 146.748754 -274.846288)
			(xy 146.786092 -275.033232) (xy 146.892772 -275.048726)
		)
		(stroke
			(width 0)
			(type solid)
		)
		(fill yes)
		(layer "F.Cu")
		(net "M_E_CPU1_SA_DQ<27>")
	)
	(gr_poly
		(pts
			(xy 146.944842 -234.190794) (xy 146.909028 -234.154726) (xy 146.811492 -234.108498) (xy 146.676872 -234.243372)
			(xy 146.7231 -234.340654) (xy 146.758914 -234.376722)
		)
		(stroke
			(width 0)
			(type solid)
		)
		(fill yes)
		(layer "F.Cu")
		(net "M_E_CPU1_SB_DQ<10>")
	)
	(gr_poly
		(pts
			(xy 146.94916 -271.69491) (xy 146.984974 -271.658842) (xy 146.799046 -271.472914) (xy 146.763232 -271.508982)
			(xy 146.717004 -271.606518) (xy 146.851624 -271.741138)
		)
		(stroke
			(width 0)
			(type solid)
		)
		(fill yes)
		(layer "F.Cu")
		(net "M_E_CPU1_SA_DQ<28>")
	)
	(gr_poly
		(pts
			(xy 146.958558 -270.84147) (xy 146.994372 -270.805402) (xy 146.808444 -270.619474) (xy 146.77263 -270.655542)
			(xy 146.726402 -270.752824) (xy 146.861022 -270.887698)
		)
		(stroke
			(width 0)
			(type solid)
		)
		(fill yes)
		(layer "F.Cu")
		(net "M_E_CPU1_SA_DQ<29>")
	)
	(gr_poly
		(pts
			(xy 146.962368 -236.740446) (xy 146.9263 -236.704632) (xy 146.829018 -236.658404) (xy 146.694144 -236.793024)
			(xy 146.740372 -236.89056) (xy 146.77644 -236.926374)
		)
		(stroke
			(width 0)
			(type solid)
		)
		(fill yes)
		(layer "F.Cu")
		(net "M_E_CPU1_SB_CB<0>")
	)
	(gr_poly
		(pts
			(xy 146.971512 -228.518974) (xy 146.920712 -228.518974) (xy 146.819112 -228.555042) (xy 146.819112 -228.745542)
			(xy 146.920712 -228.781864) (xy 146.971512 -228.781864)
		)
		(stroke
			(width 0)
			(type solid)
		)
		(fill yes)
		(layer "F.Cu")
		(net "M_E_CPU1_SB_DQ<16>")
	)
	(gr_poly
		(pts
			(xy 146.971512 -227.922074) (xy 146.920712 -227.922074) (xy 146.819112 -227.958142) (xy 146.819112 -228.148642)
			(xy 146.920712 -228.184964) (xy 146.971512 -228.184964)
		)
		(stroke
			(width 0)
			(type solid)
		)
		(fill yes)
		(layer "F.Cu")
		(net "M_E_CPU1_SB_DQ<16>")
	)
	(gr_poly
		(pts
			(xy 146.971512 -227.325174) (xy 146.920712 -227.325174) (xy 146.819112 -227.361242) (xy 146.819112 -227.551742)
			(xy 146.920712 -227.588064) (xy 146.971512 -227.588064)
		)
		(stroke
			(width 0)
			(type solid)
		)
		(fill yes)
		(layer "F.Cu")
		(net "M_E_CPU1_SB_DQ<16>")
	)
	(gr_poly
		(pts
			(xy 146.971512 -226.728274) (xy 146.920712 -226.728274) (xy 146.819112 -226.764342) (xy 146.819112 -226.954842)
			(xy 146.920712 -226.991164) (xy 146.971512 -226.991164)
		)
		(stroke
			(width 0)
			(type solid)
		)
		(fill yes)
		(layer "F.Cu")
		(net "M_E_CPU1_SB_DQ<16>")
	)
	(gr_poly
		(pts
			(xy 146.971512 -226.131374) (xy 146.920712 -226.131374) (xy 146.819112 -226.167442) (xy 146.819112 -226.357942)
			(xy 146.920712 -226.394264) (xy 146.971512 -226.394264)
		)
		(stroke
			(width 0)
			(type solid)
		)
		(fill yes)
		(layer "F.Cu")
		(net "M_E_CPU1_SB_DQ<16>")
	)
	(gr_poly
		(pts
			(xy 146.971512 -225.534474) (xy 146.920712 -225.534474) (xy 146.819112 -225.570542) (xy 146.819112 -225.761042)
			(xy 146.920712 -225.797364) (xy 146.971512 -225.797364)
		)
		(stroke
			(width 0)
			(type solid)
		)
		(fill yes)
		(layer "F.Cu")
		(net "M_E_CPU1_SB_DQ<16>")
	)
	(gr_poly
		(pts
			(xy 146.971512 -224.937574) (xy 146.920712 -224.937574) (xy 146.819112 -224.973642) (xy 146.819112 -225.164142)
			(xy 146.920712 -225.200464) (xy 146.971512 -225.200464)
		)
		(stroke
			(width 0)
			(type solid)
		)
		(fill yes)
		(layer "F.Cu")
		(net "M_E_CPU1_SB_DQ<16>")
	)
	(gr_poly
		(pts
			(xy 146.971512 -224.340674) (xy 146.920712 -224.340674) (xy 146.819112 -224.376742) (xy 146.819112 -224.567242)
			(xy 146.920712 -224.603564) (xy 146.971512 -224.603564)
		)
		(stroke
			(width 0)
			(type solid)
		)
		(fill yes)
		(layer "F.Cu")
		(net "M_E_CPU1_SB_DQ<16>")
	)
	(gr_poly
		(pts
			(xy 146.971512 -223.743774) (xy 146.920712 -223.743774) (xy 146.819112 -223.779842) (xy 146.819112 -223.970342)
			(xy 146.920712 -224.006664) (xy 146.971512 -224.006664)
		)
		(stroke
			(width 0)
			(type solid)
		)
		(fill yes)
		(layer "F.Cu")
		(net "M_E_CPU1_SB_DQ<16>")
	)
	(gr_poly
		(pts
			(xy 146.971512 -223.146874) (xy 146.920712 -223.146874) (xy 146.819112 -223.182942) (xy 146.819112 -223.373442)
			(xy 146.920712 -223.409764) (xy 146.971512 -223.409764)
		)
		(stroke
			(width 0)
			(type solid)
		)
		(fill yes)
		(layer "F.Cu")
		(net "M_E_CPU1_SB_DQ<16>")
	)
	(gr_poly
		(pts
			(xy 146.971512 -222.549974) (xy 146.920712 -222.549974) (xy 146.819112 -222.586042) (xy 146.819112 -222.776542)
			(xy 146.920712 -222.812864) (xy 146.971512 -222.812864)
		)
		(stroke
			(width 0)
			(type solid)
		)
		(fill yes)
		(layer "F.Cu")
		(net "M_E_CPU1_SB_DQ<16>")
	)
	(gr_poly
		(pts
			(xy 146.971512 -221.953074) (xy 146.920712 -221.953074) (xy 146.819112 -221.989142) (xy 146.819112 -222.179642)
			(xy 146.920712 -222.215964) (xy 146.971512 -222.215964)
		)
		(stroke
			(width 0)
			(type solid)
		)
		(fill yes)
		(layer "F.Cu")
		(net "M_E_CPU1_SB_DQ<16>")
	)
	(gr_poly
		(pts
			(xy 146.971512 -221.356174) (xy 146.920712 -221.356174) (xy 146.819112 -221.392242) (xy 146.819112 -221.582742)
			(xy 146.920712 -221.619064) (xy 146.971512 -221.619064)
		)
		(stroke
			(width 0)
			(type solid)
		)
		(fill yes)
		(layer "F.Cu")
		(net "M_E_CPU1_SB_DQ<16>")
	)
	(gr_poly
		(pts
			(xy 146.972782 -279.59812) (xy 147.065492 -279.542748) (xy 147.028154 -279.355804) (xy 146.92122 -279.34031)
			(xy 146.871436 -279.350216) (xy 146.922998 -279.608026)
		)
		(stroke
			(width 0)
			(type solid)
		)
		(fill yes)
		(layer "F.Cu")
		(net "M_E_CPU1_SA_DQ<24>")
	)
	(gr_poly
		(pts
			(xy 146.981672 -279.900634) (xy 146.93011 -279.643078) (xy 146.880326 -279.652984) (xy 146.787616 -279.708356)
			(xy 146.824954 -279.895046) (xy 146.931888 -279.910794)
		)
		(stroke
			(width 0)
			(type solid)
		)
		(fill yes)
		(layer "F.Cu")
		(net "M_E_CPU1_SA_DQ<24>")
	)
	(gr_poly
		(pts
			(xy 146.98218 -265.792712) (xy 147.018248 -265.756898) (xy 146.83232 -265.57097) (xy 146.796506 -265.606784)
			(xy 146.750024 -265.70432) (xy 146.884898 -265.83894)
		)
		(stroke
			(width 0)
			(type solid)
		)
		(fill yes)
		(layer "F.Cu")
		(net "M_E_CPU1_SA_CB<6>")
	)
	(gr_poly
		(pts
			(xy 146.985736 -276.551898) (xy 147.078446 -276.496526) (xy 147.041108 -276.309582) (xy 146.934174 -276.294088)
			(xy 146.88439 -276.303994) (xy 146.935952 -276.561804)
		)
		(stroke
			(width 0)
			(type solid)
		)
		(fill yes)
		(layer "F.Cu")
		(net "M_E_CPU1_SA_DQ<25>")
	)
	(gr_poly
		(pts
			(xy 146.987514 -230.480362) (xy 146.941286 -230.382826) (xy 146.905472 -230.347012) (xy 146.719544 -230.53294)
			(xy 146.755358 -230.568754) (xy 146.852894 -230.614982)
		)
		(stroke
			(width 0)
			(type solid)
		)
		(fill yes)
		(layer "F.Cu")
		(net "M_E_CPU1_SB_DQ<13>")
	)
	(gr_poly
		(pts
			(xy 146.991578 -264.939272) (xy 147.027392 -264.903458) (xy 146.841464 -264.71753) (xy 146.80565 -264.753598)
			(xy 146.759422 -264.85088) (xy 146.894042 -264.985754)
		)
		(stroke
			(width 0)
			(type solid)
		)
		(fill yes)
		(layer "F.Cu")
		(net "M_E_CPU1_SA_CB<7>")
	)
	(gr_poly
		(pts
			(xy 146.99234 -269.541498) (xy 147.038568 -269.443962) (xy 146.903694 -269.309342) (xy 146.806412 -269.35557)
			(xy 146.770344 -269.391384) (xy 146.956272 -269.577312)
		)
		(stroke
			(width 0)
			(type solid)
		)
		(fill yes)
		(layer "F.Cu")
		(net "M_E_CPU1_SA_CB<0>")
	)
	(gr_poly
		(pts
			(xy 146.994626 -276.854412) (xy 146.943064 -276.596856) (xy 146.89328 -276.606762) (xy 146.80057 -276.662134)
			(xy 146.838162 -276.848824) (xy 146.944842 -276.864572)
		)
		(stroke
			(width 0)
			(type solid)
		)
		(fill yes)
		(layer "F.Cu")
		(net "M_E_CPU1_SA_DQ<25>")
	)
	(gr_poly
		(pts
			(xy 146.996912 -231.333802) (xy 146.950684 -231.236266) (xy 146.914616 -231.200452) (xy 146.728688 -231.38638)
			(xy 146.764756 -231.422194) (xy 146.862038 -231.468422)
		)
		(stroke
			(width 0)
			(type solid)
		)
		(fill yes)
		(layer "F.Cu")
		(net "M_E_CPU1_SB_DQ<12>")
	)
	(gr_poly
		(pts
			(xy 147.001484 -268.688058) (xy 147.047712 -268.590522) (xy 146.913092 -268.455902) (xy 146.815556 -268.50213)
			(xy 146.779742 -268.538198) (xy 146.965416 -268.723872)
		)
		(stroke
			(width 0)
			(type solid)
		)
		(fill yes)
		(layer "F.Cu")
		(net "M_E_CPU1_SA_CB<1>")
	)
	(gr_poly
		(pts
			(xy 147.022058 -233.896916) (xy 146.97583 -233.799634) (xy 146.940016 -233.763566) (xy 146.754088 -233.949494)
			(xy 146.789902 -233.985562) (xy 146.887438 -234.03179)
		)
		(stroke
			(width 0)
			(type solid)
		)
		(fill yes)
		(layer "F.Cu")
		(net "M_E_CPU1_SB_DQ<9>")
	)
	(gr_poly
		(pts
			(xy 147.025614 -271.196308) (xy 147.071842 -271.098772) (xy 146.937222 -270.964152) (xy 146.839686 -271.01038)
			(xy 146.803872 -271.046448) (xy 146.989546 -271.232122)
		)
		(stroke
			(width 0)
			(type solid)
		)
		(fill yes)
		(layer "F.Cu")
		(net "M_E_CPU1_SA_DQ<30>")
	)
	(gr_poly
		(pts
			(xy 147.03171 -234.750864) (xy 146.985482 -234.653328) (xy 146.949668 -234.617514) (xy 146.76374 -234.803442)
			(xy 146.799554 -234.839256) (xy 146.89709 -234.885484)
		)
		(stroke
			(width 0)
			(type solid)
		)
		(fill yes)
		(layer "F.Cu")
		(net "M_E_CPU1_SB_DQ<8>")
	)
	(gr_poly
		(pts
			(xy 147.035012 -270.342614) (xy 147.08124 -270.245332) (xy 146.94662 -270.110458) (xy 146.849084 -270.15694)
			(xy 146.81327 -270.192754) (xy 146.999198 -270.378682)
		)
		(stroke
			(width 0)
			(type solid)
		)
		(fill yes)
		(layer "F.Cu")
		(net "M_E_CPU1_SA_DQ<31>")
	)
	(gr_poly
		(pts
			(xy 147.037806 -278.367744) (xy 147.130262 -278.312372) (xy 147.092924 -278.125428) (xy 146.986244 -278.109934)
			(xy 146.93646 -278.11984) (xy 146.988022 -278.37765)
		)
		(stroke
			(width 0)
			(type solid)
		)
		(fill yes)
		(layer "F.Cu")
		(net "M_E_CPU1_SA_DQ<26>")
	)
	(gr_poly
		(pts
			(xy 147.040092 -236.447076) (xy 146.993864 -236.34954) (xy 146.957796 -236.313726) (xy 146.771868 -236.499654)
			(xy 146.807936 -236.535468) (xy 146.905218 -236.581696)
		)
		(stroke
			(width 0)
			(type solid)
		)
		(fill yes)
		(layer "F.Cu")
		(net "M_E_CPU1_SB_CB<2>")
	)
	(gr_poly
		(pts
			(xy 147.046442 -278.670258) (xy 146.99488 -278.412448) (xy 146.945096 -278.422608) (xy 146.85264 -278.47798)
			(xy 146.889978 -278.66467) (xy 146.996658 -278.680164)
		)
		(stroke
			(width 0)
			(type solid)
		)
		(fill yes)
		(layer "F.Cu")
		(net "M_E_CPU1_SA_DQ<26>")
	)
	(gr_poly
		(pts
			(xy 147.04949 -266.14755) (xy 147.095718 -266.050268) (xy 146.961098 -265.915394) (xy 146.863562 -265.961622)
			(xy 146.827748 -265.99769) (xy 147.013676 -266.183618)
		)
		(stroke
			(width 0)
			(type solid)
		)
		(fill yes)
		(layer "F.Cu")
		(net "M_E_CPU1_SA_CB<4>")
	)
	(gr_poly
		(pts
			(xy 147.051014 -275.321522) (xy 147.14347 -275.26615) (xy 147.106132 -275.079206) (xy 146.999452 -275.063712)
			(xy 146.949414 -275.073618) (xy 147.000976 -275.331428)
		)
		(stroke
			(width 0)
			(type solid)
		)
		(fill yes)
		(layer "F.Cu")
		(net "M_E_CPU1_SA_DQ<27>")
	)
	(gr_poly
		(pts
			(xy 147.058634 -265.294364) (xy 147.104862 -265.196828) (xy 146.970242 -265.062208) (xy 146.872706 -265.108436)
			(xy 146.836892 -265.14425) (xy 147.02282 -265.330178)
		)
		(stroke
			(width 0)
			(type solid)
		)
		(fill yes)
		(layer "F.Cu")
		(net "M_E_CPU1_SA_CB<5>")
	)
	(gr_poly
		(pts
			(xy 147.05965 -275.624036) (xy 147.008088 -275.366226) (xy 146.958304 -275.376132) (xy 146.865848 -275.431758)
			(xy 146.903186 -275.618448) (xy 147.009866 -275.633942)
		)
		(stroke
			(width 0)
			(type solid)
		)
		(fill yes)
		(layer "F.Cu")
		(net "M_E_CPU1_SA_DQ<27>")
	)
	(gr_poly
		(pts
			(xy 147.089876 -280.183336) (xy 147.182586 -280.127964) (xy 147.144994 -279.941274) (xy 147.038314 -279.925526)
			(xy 146.98853 -279.935686) (xy 147.040092 -280.193496)
		)
		(stroke
			(width 0)
			(type solid)
		)
		(fill yes)
		(layer "F.Cu")
		(net "M_E_CPU1_SA_DQ<24>")
	)
	(gr_poly
		(pts
			(xy 147.098766 -280.486104) (xy 147.047204 -280.228294) (xy 146.997166 -280.2382) (xy 146.90471 -280.293572)
			(xy 146.942048 -280.480516) (xy 147.048982 -280.49601)
		)
		(stroke
			(width 0)
			(type solid)
		)
		(fill yes)
		(layer "F.Cu")
		(net "M_E_CPU1_SA_DQ<24>")
	)
	(gr_poly
		(pts
			(xy 147.103084 -277.137114) (xy 147.19554 -277.081742) (xy 147.158202 -276.895052) (xy 147.051268 -276.879304)
			(xy 147.001484 -276.889464) (xy 147.053046 -277.147274)
		)
		(stroke
			(width 0)
			(type solid)
		)
		(fill yes)
		(layer "F.Cu")
		(net "M_E_CPU1_SA_DQ<25>")
	)
	(gr_poly
		(pts
			(xy 147.11172 -277.439882) (xy 147.060158 -277.182072) (xy 147.010374 -277.191978) (xy 146.917918 -277.24735)
			(xy 146.955256 -277.434294) (xy 147.061936 -277.449788)
		)
		(stroke
			(width 0)
			(type solid)
		)
		(fill yes)
		(layer "F.Cu")
		(net "M_E_CPU1_SA_DQ<25>")
	)
	(gr_poly
		(pts
			(xy 147.116546 -230.135938) (xy 147.080478 -230.100124) (xy 146.983196 -230.053896) (xy 146.848322 -230.188516)
			(xy 146.894804 -230.286052) (xy 146.930618 -230.321866)
		)
		(stroke
			(width 0)
			(type solid)
		)
		(fill yes)
		(layer "F.Cu")
		(net "M_E_CPU1_SB_DQ<13>")
	)
	(gr_poly
		(pts
			(xy 147.123912 -228.447092) (xy 147.123912 -228.256592) (xy 147.022312 -228.220524) (xy 146.971512 -228.220524)
			(xy 146.971512 -228.483414) (xy 147.022312 -228.483414)
		)
		(stroke
			(width 0)
			(type solid)
		)
		(fill yes)
		(layer "F.Cu")
		(net "M_E_CPU1_SB_DQ<16>")
	)
	(gr_poly
		(pts
			(xy 147.123912 -227.850192) (xy 147.123912 -227.659692) (xy 147.022312 -227.623624) (xy 146.971512 -227.623624)
			(xy 146.971512 -227.886514) (xy 147.022312 -227.886514)
		)
		(stroke
			(width 0)
			(type solid)
		)
		(fill yes)
		(layer "F.Cu")
		(net "M_E_CPU1_SB_DQ<16>")
	)
	(gr_poly
		(pts
			(xy 147.123912 -227.253292) (xy 147.123912 -227.062792) (xy 147.022312 -227.026724) (xy 146.971512 -227.026724)
			(xy 146.971512 -227.289614) (xy 147.022312 -227.289614)
		)
		(stroke
			(width 0)
			(type solid)
		)
		(fill yes)
		(layer "F.Cu")
		(net "M_E_CPU1_SB_DQ<16>")
	)
	(gr_poly
		(pts
			(xy 147.123912 -226.656392) (xy 147.123912 -226.465892) (xy 147.022312 -226.429824) (xy 146.971512 -226.429824)
			(xy 146.971512 -226.692714) (xy 147.022312 -226.692714)
		)
		(stroke
			(width 0)
			(type solid)
		)
		(fill yes)
		(layer "F.Cu")
		(net "M_E_CPU1_SB_DQ<16>")
	)
	(gr_poly
		(pts
			(xy 147.123912 -226.059492) (xy 147.123912 -225.868992) (xy 147.022312 -225.832924) (xy 146.971512 -225.832924)
			(xy 146.971512 -226.095814) (xy 147.022312 -226.095814)
		)
		(stroke
			(width 0)
			(type solid)
		)
		(fill yes)
		(layer "F.Cu")
		(net "M_E_CPU1_SB_DQ<16>")
	)
	(gr_poly
		(pts
			(xy 147.123912 -225.462592) (xy 147.123912 -225.272092) (xy 147.022312 -225.236024) (xy 146.971512 -225.236024)
			(xy 146.971512 -225.498914) (xy 147.022312 -225.498914)
		)
		(stroke
			(width 0)
			(type solid)
		)
		(fill yes)
		(layer "F.Cu")
		(net "M_E_CPU1_SB_DQ<16>")
	)
	(gr_poly
		(pts
			(xy 147.123912 -224.865692) (xy 147.123912 -224.675192) (xy 147.022312 -224.639124) (xy 146.971512 -224.639124)
			(xy 146.971512 -224.902014) (xy 147.022312 -224.902014)
		)
		(stroke
			(width 0)
			(type solid)
		)
		(fill yes)
		(layer "F.Cu")
		(net "M_E_CPU1_SB_DQ<16>")
	)
	(gr_poly
		(pts
			(xy 147.123912 -224.268792) (xy 147.123912 -224.078292) (xy 147.022312 -224.042224) (xy 146.971512 -224.042224)
			(xy 146.971512 -224.305114) (xy 147.022312 -224.305114)
		)
		(stroke
			(width 0)
			(type solid)
		)
		(fill yes)
		(layer "F.Cu")
		(net "M_E_CPU1_SB_DQ<16>")
	)
	(gr_poly
		(pts
			(xy 147.123912 -223.671892) (xy 147.123912 -223.481392) (xy 147.022312 -223.445324) (xy 146.971512 -223.445324)
			(xy 146.971512 -223.708214) (xy 147.022312 -223.708214)
		)
		(stroke
			(width 0)
			(type solid)
		)
		(fill yes)
		(layer "F.Cu")
		(net "M_E_CPU1_SB_DQ<16>")
	)
	(gr_poly
		(pts
			(xy 147.123912 -223.074992) (xy 147.123912 -222.884492) (xy 147.022312 -222.848424) (xy 146.971512 -222.848424)
			(xy 146.971512 -223.111314) (xy 147.022312 -223.111314)
		)
		(stroke
			(width 0)
			(type solid)
		)
		(fill yes)
		(layer "F.Cu")
		(net "M_E_CPU1_SB_DQ<16>")
	)
	(gr_poly
		(pts
			(xy 147.123912 -222.478092) (xy 147.123912 -222.287592) (xy 147.022312 -222.251524) (xy 146.971512 -222.251524)
			(xy 146.971512 -222.514414) (xy 147.022312 -222.514414)
		)
		(stroke
			(width 0)
			(type solid)
		)
		(fill yes)
		(layer "F.Cu")
		(net "M_E_CPU1_SB_DQ<16>")
	)
	(gr_poly
		(pts
			(xy 147.123912 -221.881192) (xy 147.123912 -221.690692) (xy 147.022312 -221.654624) (xy 146.971512 -221.654624)
			(xy 146.971512 -221.917514) (xy 147.022312 -221.917514)
		)
		(stroke
			(width 0)
			(type solid)
		)
		(fill yes)
		(layer "F.Cu")
		(net "M_E_CPU1_SB_DQ<16>")
	)
	(gr_poly
		(pts
			(xy 147.12569 -230.989378) (xy 147.089876 -230.95331) (xy 146.99234 -230.907082) (xy 146.85772 -231.041956)
			(xy 146.903948 -231.139238) (xy 146.939762 -231.175306)
		)
		(stroke
			(width 0)
			(type solid)
		)
		(fill yes)
		(layer "F.Cu")
		(net "M_E_CPU1_SB_DQ<12>")
	)
	(gr_poly
		(pts
			(xy 147.131532 -269.8242) (xy 147.167346 -269.788386) (xy 146.981418 -269.602458) (xy 146.945604 -269.638272)
			(xy 146.899376 -269.735808) (xy 147.033996 -269.870428)
		)
		(stroke
			(width 0)
			(type solid)
		)
		(fill yes)
		(layer "F.Cu")
		(net "M_E_CPU1_SA_CB<0>")
	)
	(gr_poly
		(pts
			(xy 147.140676 -268.971014) (xy 147.17649 -268.934946) (xy 146.990562 -268.749018) (xy 146.954748 -268.785086)
			(xy 146.90852 -268.882368) (xy 147.04314 -269.017242)
		)
		(stroke
			(width 0)
			(type solid)
		)
		(fill yes)
		(layer "F.Cu")
		(net "M_E_CPU1_SA_CB<1>")
	)
	(gr_poly
		(pts
			(xy 147.150836 -233.552746) (xy 147.115022 -233.516678) (xy 147.017486 -233.47045) (xy 146.882866 -233.60507)
			(xy 146.929094 -233.702606) (xy 146.965162 -233.73842)
		)
		(stroke
			(width 0)
			(type solid)
		)
		(fill yes)
		(layer "F.Cu")
		(net "M_E_CPU1_SB_DQ<9>")
	)
	(gr_poly
		(pts
			(xy 147.1549 -278.95296) (xy 147.247356 -278.897588) (xy 147.210018 -278.710644) (xy 147.103338 -278.69515)
			(xy 147.053554 -278.705056) (xy 147.105116 -278.962866)
		)
		(stroke
			(width 0)
			(type solid)
		)
		(fill yes)
		(layer "F.Cu")
		(net "M_E_CPU1_SA_DQ<26>")
	)
	(gr_poly
		(pts
			(xy 147.160742 -234.40644) (xy 147.124674 -234.370626) (xy 147.027392 -234.324398) (xy 146.892518 -234.459018)
			(xy 146.939 -234.556554) (xy 146.974814 -234.592368)
		)
		(stroke
			(width 0)
			(type solid)
		)
		(fill yes)
		(layer "F.Cu")
		(net "M_E_CPU1_SB_DQ<8>")
	)
	(gr_poly
		(pts
			(xy 147.163536 -279.255728) (xy 147.111974 -278.997918) (xy 147.06219 -279.007824) (xy 146.969734 -279.063196)
			(xy 147.007072 -279.25014) (xy 147.113752 -279.265634)
		)
		(stroke
			(width 0)
			(type solid)
		)
		(fill yes)
		(layer "F.Cu")
		(net "M_E_CPU1_SA_DQ<26>")
	)
	(gr_poly
		(pts
			(xy 147.164806 -271.479264) (xy 147.20062 -271.443196) (xy 147.014692 -271.257268) (xy 146.978878 -271.293336)
			(xy 146.93265 -271.390872) (xy 147.06727 -271.525492)
		)
		(stroke
			(width 0)
			(type solid)
		)
		(fill yes)
		(layer "F.Cu")
		(net "M_E_CPU1_SA_DQ<30>")
	)
	(gr_poly
		(pts
			(xy 147.168108 -275.906738) (xy 147.260564 -275.851366) (xy 147.223226 -275.664422) (xy 147.116546 -275.648928)
			(xy 147.066508 -275.658834) (xy 147.11807 -275.916644)
		)
		(stroke
			(width 0)
			(type solid)
		)
		(fill yes)
		(layer "F.Cu")
		(net "M_E_CPU1_SA_DQ<27>")
	)
	(gr_poly
		(pts
			(xy 147.174204 -270.62557) (xy 147.210272 -270.589756) (xy 147.024344 -270.403828) (xy 146.988276 -270.439642)
			(xy 146.942048 -270.537178) (xy 147.076922 -270.671798)
		)
		(stroke
			(width 0)
			(type solid)
		)
		(fill yes)
		(layer "F.Cu")
		(net "M_E_CPU1_SA_DQ<31>")
	)
	(gr_poly
		(pts
			(xy 147.176744 -276.209252) (xy 147.125182 -275.951696) (xy 147.075398 -275.961602) (xy 146.982942 -276.016974)
			(xy 147.02028 -276.203664) (xy 147.12696 -276.219412)
		)
		(stroke
			(width 0)
			(type solid)
		)
		(fill yes)
		(layer "F.Cu")
		(net "M_E_CPU1_SA_DQ<27>")
	)
	(gr_poly
		(pts
			(xy 147.188682 -266.430506) (xy 147.224496 -266.394438) (xy 147.038822 -266.208764) (xy 147.002754 -266.244578)
			(xy 146.956526 -266.342114) (xy 147.091146 -266.476734)
		)
		(stroke
			(width 0)
			(type solid)
		)
		(fill yes)
		(layer "F.Cu")
		(net "M_E_CPU1_SA_CB<4>")
	)
	(gr_poly
		(pts
			(xy 147.194016 -229.842568) (xy 147.147788 -229.745286) (xy 147.111974 -229.709218) (xy 146.926046 -229.895146)
			(xy 146.96186 -229.931214) (xy 147.059396 -229.977442)
		)
		(stroke
			(width 0)
			(type solid)
		)
		(fill yes)
		(layer "F.Cu")
		(net "M_E_CPU1_SB_DQ<15>")
	)
	(gr_poly
		(pts
			(xy 147.197826 -265.577066) (xy 147.233894 -265.541252) (xy 147.047966 -265.355324) (xy 147.012152 -265.391138)
			(xy 146.96567 -265.488674) (xy 147.100544 -265.623294)
		)
		(stroke
			(width 0)
			(type solid)
		)
		(fill yes)
		(layer "F.Cu")
		(net "M_E_CPU1_SA_CB<5>")
	)
	(gr_poly
		(pts
			(xy 147.20316 -230.696008) (xy 147.156932 -230.598472) (xy 147.121118 -230.562658) (xy 146.93519 -230.748586)
			(xy 146.971004 -230.7844) (xy 147.06854 -230.830628)
		)
		(stroke
			(width 0)
			(type solid)
		)
		(fill yes)
		(layer "F.Cu")
		(net "M_E_CPU1_SB_DQ<14>")
	)
	(gr_poly
		(pts
			(xy 147.20697 -280.768806) (xy 147.299426 -280.713434) (xy 147.262088 -280.52649) (xy 147.155408 -280.510996)
			(xy 147.105624 -280.520902) (xy 147.157186 -280.778712)
		)
		(stroke
			(width 0)
			(type solid)
		)
		(fill yes)
		(layer "F.Cu")
		(net "M_E_CPU1_SA_DQ<24>")
	)
	(gr_poly
		(pts
			(xy 147.207986 -269.325852) (xy 147.254214 -269.228316) (xy 147.11934 -269.093696) (xy 147.022058 -269.139924)
			(xy 146.98599 -269.175738) (xy 147.171918 -269.361666)
		)
		(stroke
			(width 0)
			(type solid)
		)
		(fill yes)
		(layer "F.Cu")
		(net "M_E_CPU1_SA_CB<2>")
	)
	(gr_poly
		(pts
			(xy 147.21586 -281.07132) (xy 147.164298 -280.81351) (xy 147.11426 -280.823416) (xy 147.021804 -280.879042)
			(xy 147.059142 -281.065732) (xy 147.165822 -281.081226)
		)
		(stroke
			(width 0)
			(type solid)
		)
		(fill yes)
		(layer "F.Cu")
		(net "M_E_CPU1_SA_DQ<24>")
	)
	(gr_poly
		(pts
			(xy 147.21713 -268.472412) (xy 147.263358 -268.374876) (xy 147.128738 -268.240256) (xy 147.031202 -268.286484)
			(xy 146.995388 -268.322552) (xy 147.181062 -268.508226)
		)
		(stroke
			(width 0)
			(type solid)
		)
		(fill yes)
		(layer "F.Cu")
		(net "M_E_CPU1_SA_CB<3>")
	)
	(gr_poly
		(pts
			(xy 147.220178 -277.722584) (xy 147.312634 -277.666958) (xy 147.275296 -277.480268) (xy 147.168616 -277.464774)
			(xy 147.118832 -277.47468) (xy 147.170394 -277.73249)
		)
		(stroke
			(width 0)
			(type solid)
		)
		(fill yes)
		(layer "F.Cu")
		(net "M_E_CPU1_SA_DQ<25>")
	)
	(gr_poly
		(pts
			(xy 147.228052 -233.258868) (xy 147.181824 -233.161586) (xy 147.14601 -233.125518) (xy 146.960082 -233.311446)
			(xy 146.995896 -233.34726) (xy 147.093432 -233.393742)
		)
		(stroke
			(width 0)
			(type solid)
		)
		(fill yes)
		(layer "F.Cu")
		(net "M_E_CPU1_SB_DQ<11>")
	)
	(gr_poly
		(pts
			(xy 147.228814 -278.025098) (xy 147.177252 -277.767288) (xy 147.127468 -277.777194) (xy 147.035012 -277.83282)
			(xy 147.07235 -278.01951) (xy 147.17903 -278.035004)
		)
		(stroke
			(width 0)
			(type solid)
		)
		(fill yes)
		(layer "F.Cu")
		(net "M_E_CPU1_SA_DQ<25>")
	)
	(gr_poly
		(pts
			(xy 147.232116 -271.834102) (xy 147.278344 -271.736566) (xy 147.14347 -271.601946) (xy 147.046188 -271.648174)
			(xy 147.01012 -271.683988) (xy 147.196048 -271.869916)
		)
		(stroke
			(width 0)
			(type solid)
		)
		(fill yes)
		(layer "F.Cu")
		(net "M_E_CPU1_SA_DQ<28>")
	)
	(gr_poly
		(pts
			(xy 147.238212 -234.11307) (xy 147.191984 -234.015534) (xy 147.155916 -233.97972) (xy 146.969988 -234.165648)
			(xy 147.006056 -234.201462) (xy 147.103338 -234.24769)
		)
		(stroke
			(width 0)
			(type solid)
		)
		(fill yes)
		(layer "F.Cu")
		(net "M_E_CPU1_SB_DQ<10>")
	)
	(gr_poly
		(pts
			(xy 147.24126 -270.980662) (xy 147.287488 -270.883126) (xy 147.152868 -270.748506) (xy 147.055586 -270.794734)
			(xy 147.019518 -270.830548) (xy 147.205446 -271.016476)
		)
		(stroke
			(width 0)
			(type solid)
		)
		(fill yes)
		(layer "F.Cu")
		(net "M_E_CPU1_SA_DQ<29>")
	)
	(gr_poly
		(pts
			(xy 147.265136 -265.931904) (xy 147.311364 -265.834622) (xy 147.176744 -265.699748) (xy 147.079208 -265.745976)
			(xy 147.043394 -265.782044) (xy 147.229322 -265.967972)
		)
		(stroke
			(width 0)
			(type solid)
		)
		(fill yes)
		(layer "F.Cu")
		(net "M_E_CPU1_SA_CB<6>")
	)
	(gr_poly
		(pts
			(xy 147.271994 -279.538176) (xy 147.36445 -279.482804) (xy 147.327112 -279.296114) (xy 147.220432 -279.28062)
			(xy 147.170648 -279.290526) (xy 147.22221 -279.548336)
		)
		(stroke
			(width 0)
			(type solid)
		)
		(fill yes)
		(layer "F.Cu")
		(net "M_E_CPU1_SA_DQ<26>")
	)
	(gr_poly
		(pts
			(xy 147.27428 -265.078718) (xy 147.320508 -264.981182) (xy 147.185888 -264.846562) (xy 147.088352 -264.89279)
			(xy 147.052538 -264.928604) (xy 147.238466 -265.114532)
		)
		(stroke
			(width 0)
			(type solid)
		)
		(fill yes)
		(layer "F.Cu")
		(net "M_E_CPU1_SA_CB<7>")
	)
	(gr_poly
		(pts
			(xy 147.28063 -279.840944) (xy 147.229068 -279.583134) (xy 147.179284 -279.59304) (xy 147.086828 -279.648412)
			(xy 147.124166 -279.835356) (xy 147.230846 -279.85085)
		)
		(stroke
			(width 0)
			(type solid)
		)
		(fill yes)
		(layer "F.Cu")
		(net "M_E_CPU1_SA_DQ<26>")
	)
	(gr_poly
		(pts
			(xy 147.285202 -276.491954) (xy 147.377658 -276.436582) (xy 147.34032 -276.249892) (xy 147.23364 -276.234144)
			(xy 147.183602 -276.244304) (xy 147.235164 -276.502114)
		)
		(stroke
			(width 0)
			(type solid)
		)
		(fill yes)
		(layer "F.Cu")
		(net "M_E_CPU1_SA_DQ<27>")
	)
	(gr_poly
		(pts
			(xy 147.293838 -276.794722) (xy 147.242276 -276.536912) (xy 147.192492 -276.546818) (xy 147.100036 -276.60219)
			(xy 147.137374 -276.789134) (xy 147.244054 -276.804628)
		)
		(stroke
			(width 0)
			(type solid)
		)
		(fill yes)
		(layer "F.Cu")
		(net "M_E_CPU1_SA_DQ<27>")
	)
	(gr_poly
		(pts
			(xy 147.322794 -229.498398) (xy 147.28698 -229.46233) (xy 147.189444 -229.416102) (xy 147.054824 -229.550722)
			(xy 147.101052 -229.648258) (xy 147.13712 -229.684072)
		)
		(stroke
			(width 0)
			(type solid)
		)
		(fill yes)
		(layer "F.Cu")
		(net "M_E_CPU1_SB_DQ<15>")
	)
	(gr_poly
		(pts
			(xy 147.324064 -281.354022) (xy 147.41652 -281.29865) (xy 147.379182 -281.111706) (xy 147.272502 -281.096212)
			(xy 147.222718 -281.106118) (xy 147.27428 -281.363928)
		)
		(stroke
			(width 0)
			(type solid)
		)
		(fill yes)
		(layer "F.Cu")
		(net "M_E_CPU1_SA_DQ<24>")
	)
	(gr_poly
		(pts
			(xy 147.332192 -230.351584) (xy 147.296124 -230.31577) (xy 147.198842 -230.269542) (xy 147.063968 -230.404162)
			(xy 147.11045 -230.501698) (xy 147.146264 -230.537512)
		)
		(stroke
			(width 0)
			(type solid)
		)
		(fill yes)
		(layer "F.Cu")
		(net "M_E_CPU1_SB_DQ<14>")
	)
	(gr_poly
		(pts
			(xy 147.337272 -278.3078) (xy 147.429728 -278.252428) (xy 147.39239 -278.065484) (xy 147.28571 -278.04999)
			(xy 147.235926 -278.059896) (xy 147.287488 -278.317706)
		)
		(stroke
			(width 0)
			(type solid)
		)
		(fill yes)
		(layer "F.Cu")
		(net "M_E_CPU1_SA_DQ<25>")
	)
	(gr_poly
		(pts
			(xy 147.345908 -278.610314) (xy 147.294346 -278.352504) (xy 147.244562 -278.362664) (xy 147.152106 -278.418036)
			(xy 147.189444 -278.604726) (xy 147.296124 -278.620474)
		)
		(stroke
			(width 0)
			(type solid)
		)
		(fill yes)
		(layer "F.Cu")
		(net "M_E_CPU1_SA_DQ<25>")
	)
	(gr_poly
		(pts
			(xy 147.347178 -269.608554) (xy 147.382992 -269.57274) (xy 147.197064 -269.386812) (xy 147.16125 -269.422626)
			(xy 147.115022 -269.520162) (xy 147.249642 -269.654782)
		)
		(stroke
			(width 0)
			(type solid)
		)
		(fill yes)
		(layer "F.Cu")
		(net "M_E_CPU1_SA_CB<2>")
	)
	(gr_poly
		(pts
			(xy 147.356322 -268.755368) (xy 147.392136 -268.7193) (xy 147.206208 -268.533372) (xy 147.170394 -268.56944)
			(xy 147.124166 -268.666722) (xy 147.258786 -268.801596)
		)
		(stroke
			(width 0)
			(type solid)
		)
		(fill yes)
		(layer "F.Cu")
		(net "M_E_CPU1_SA_CB<3>")
	)
	(gr_poly
		(pts
			(xy 147.357084 -232.914444) (xy 147.321016 -232.87863) (xy 147.223734 -232.832402) (xy 147.08886 -232.967022)
			(xy 147.135088 -233.064558) (xy 147.171156 -233.100372)
		)
		(stroke
			(width 0)
			(type solid)
		)
		(fill yes)
		(layer "F.Cu")
		(net "M_E_CPU1_SB_DQ<11>")
	)
	(gr_poly
		(pts
			(xy 147.36699 -233.768646) (xy 147.331176 -233.732832) (xy 147.23364 -233.686604) (xy 147.09902 -233.821224)
			(xy 147.145248 -233.918506) (xy 147.181062 -233.954574)
		)
		(stroke
			(width 0)
			(type solid)
		)
		(fill yes)
		(layer "F.Cu")
		(net "M_E_CPU1_SB_DQ<10>")
	)
	(gr_poly
		(pts
			(xy 147.371308 -272.116804) (xy 147.407122 -272.08099) (xy 147.221194 -271.895062) (xy 147.18538 -271.93113)
			(xy 147.139152 -272.028412) (xy 147.273772 -272.163286)
		)
		(stroke
			(width 0)
			(type solid)
		)
		(fill yes)
		(layer "F.Cu")
		(net "M_E_CPU1_SA_DQ<28>")
	)
	(gr_poly
		(pts
			(xy 147.380452 -271.263364) (xy 147.41652 -271.22755) (xy 147.230592 -271.041622) (xy 147.194778 -271.077436)
			(xy 147.148296 -271.174972) (xy 147.28317 -271.309592)
		)
		(stroke
			(width 0)
			(type solid)
		)
		(fill yes)
		(layer "F.Cu")
		(net "M_E_CPU1_SA_DQ<29>")
	)
	(gr_poly
		(pts
			(xy 147.389088 -280.123646) (xy 147.481544 -280.068274) (xy 147.444206 -279.88133) (xy 147.337526 -279.865836)
			(xy 147.287742 -279.875742) (xy 147.339304 -280.133552)
		)
		(stroke
			(width 0)
			(type solid)
		)
		(fill yes)
		(layer "F.Cu")
		(net "M_E_CPU1_SA_DQ<26>")
	)
	(gr_poly
		(pts
			(xy 147.397724 -280.42616) (xy 147.346162 -280.16835) (xy 147.296378 -280.17851) (xy 147.203922 -280.233882)
			(xy 147.24126 -280.420572) (xy 147.34794 -280.436066)
		)
		(stroke
			(width 0)
			(type solid)
		)
		(fill yes)
		(layer "F.Cu")
		(net "M_E_CPU1_SA_DQ<26>")
	)
	(gr_poly
		(pts
			(xy 147.402296 -277.077424) (xy 147.494752 -277.022052) (xy 147.457414 -276.835108) (xy 147.350734 -276.819614)
			(xy 147.300696 -276.82952) (xy 147.352258 -277.08733)
		)
		(stroke
			(width 0)
			(type solid)
		)
		(fill yes)
		(layer "F.Cu")
		(net "M_E_CPU1_SA_DQ<27>")
	)
	(gr_poly
		(pts
			(xy 147.404328 -266.21486) (xy 147.440142 -266.178792) (xy 147.254468 -265.993118) (xy 147.2184 -266.028932)
			(xy 147.172172 -266.126468) (xy 147.306792 -266.261088)
		)
		(stroke
			(width 0)
			(type solid)
		)
		(fill yes)
		(layer "F.Cu")
		(net "M_E_CPU1_SA_CB<6>")
	)
	(gr_poly
		(pts
			(xy 147.409662 -230.058214) (xy 147.363434 -229.960932) (xy 147.32762 -229.924864) (xy 147.141692 -230.110792)
			(xy 147.177506 -230.14686) (xy 147.275042 -230.193088)
		)
		(stroke
			(width 0)
			(type solid)
		)
		(fill yes)
		(layer "F.Cu")
		(net "M_E_CPU1_SB_DQ<13>")
	)
	(gr_poly
		(pts
			(xy 147.410932 -277.379938) (xy 147.35937 -277.122128) (xy 147.309586 -277.132034) (xy 147.21713 -277.18766)
			(xy 147.254468 -277.37435) (xy 147.361148 -277.389844)
		)
		(stroke
			(width 0)
			(type solid)
		)
		(fill yes)
		(layer "F.Cu")
		(net "M_E_CPU1_SA_DQ<27>")
	)
	(gr_poly
		(pts
			(xy 147.413472 -265.36142) (xy 147.44954 -265.325606) (xy 147.263612 -265.139678) (xy 147.227798 -265.175492)
			(xy 147.181316 -265.273028) (xy 147.31619 -265.407648)
		)
		(stroke
			(width 0)
			(type solid)
		)
		(fill yes)
		(layer "F.Cu")
		(net "M_E_CPU1_SA_CB<7>")
	)
	(gr_poly
		(pts
			(xy 147.414234 -269.963392) (xy 147.460462 -269.86611) (xy 147.325842 -269.731236) (xy 147.228306 -269.777718)
			(xy 147.192492 -269.813532) (xy 147.37842 -269.99946)
		)
		(stroke
			(width 0)
			(type solid)
		)
		(fill yes)
		(layer "F.Cu")
		(net "M_E_CPU1_SA_CB<0>")
	)
	(gr_poly
		(pts
			(xy 147.418806 -230.911654) (xy 147.372578 -230.814118) (xy 147.336764 -230.778304) (xy 147.150836 -230.964232)
			(xy 147.18665 -231.000046) (xy 147.284186 -231.046274)
		)
		(stroke
			(width 0)
			(type solid)
		)
		(fill yes)
		(layer "F.Cu")
		(net "M_E_CPU1_SB_DQ<12>")
	)
	(gr_poly
		(pts
			(xy 147.423632 -269.110206) (xy 147.46986 -269.01267) (xy 147.334986 -268.87805) (xy 147.237704 -268.924278)
			(xy 147.201636 -268.960092) (xy 147.387564 -269.14602)
		)
		(stroke
			(width 0)
			(type solid)
		)
		(fill yes)
		(layer "F.Cu")
		(net "M_E_CPU1_SA_CB<1>")
	)
	(gr_poly
		(pts
			(xy 147.444206 -233.475022) (xy 147.397978 -233.377486) (xy 147.36191 -233.341672) (xy 147.175982 -233.5276)
			(xy 147.21205 -233.563414) (xy 147.309586 -233.609642)
		)
		(stroke
			(width 0)
			(type solid)
		)
		(fill yes)
		(layer "F.Cu")
		(net "M_E_CPU1_SB_DQ<9>")
	)
	(gr_poly
		(pts
			(xy 147.447762 -271.618456) (xy 147.49399 -271.52092) (xy 147.359116 -271.3863) (xy 147.261834 -271.432528)
			(xy 147.225766 -271.468342) (xy 147.411694 -271.65427)
		)
		(stroke
			(width 0)
			(type solid)
		)
		(fill yes)
		(layer "F.Cu")
		(net "M_E_CPU1_SA_DQ<30>")
	)
	(gr_poly
		(pts
			(xy 147.453858 -234.328716) (xy 147.40763 -234.231434) (xy 147.371816 -234.195366) (xy 147.185888 -234.381294)
			(xy 147.221702 -234.417362) (xy 147.319238 -234.46359)
		)
		(stroke
			(width 0)
			(type solid)
		)
		(fill yes)
		(layer "F.Cu")
		(net "M_E_CPU1_SB_DQ<8>")
	)
	(gr_poly
		(pts
			(xy 147.454366 -278.893016) (xy 147.546822 -278.837644) (xy 147.509484 -278.650954) (xy 147.402804 -278.635206)
			(xy 147.35302 -278.645366) (xy 147.404582 -278.903176)
		)
		(stroke
			(width 0)
			(type solid)
		)
		(fill yes)
		(layer "F.Cu")
		(net "M_E_CPU1_SA_DQ<25>")
	)
	(gr_poly
		(pts
			(xy 147.45716 -270.764762) (xy 147.503388 -270.667226) (xy 147.368768 -270.532606) (xy 147.271232 -270.578834)
			(xy 147.235418 -270.614902) (xy 147.421092 -270.800576)
		)
		(stroke
			(width 0)
			(type solid)
		)
		(fill yes)
		(layer "F.Cu")
		(net "M_E_CPU1_SA_DQ<31>")
	)
	(gr_poly
		(pts
			(xy 147.463002 -279.195784) (xy 147.41144 -278.937974) (xy 147.361656 -278.94788) (xy 147.2692 -279.003252)
			(xy 147.306538 -279.190196) (xy 147.413218 -279.20569)
		)
		(stroke
			(width 0)
			(type solid)
		)
		(fill yes)
		(layer "F.Cu")
		(net "M_E_CPU1_SA_DQ<25>")
	)
	(gr_poly
		(pts
			(xy 147.471638 -266.569698) (xy 147.517866 -266.472162) (xy 147.383246 -266.337542) (xy 147.28571 -266.38377)
			(xy 147.249642 -266.419584) (xy 147.43557 -266.605512)
		)
		(stroke
			(width 0)
			(type solid)
		)
		(fill yes)
		(layer "F.Cu")
		(net "M_E_CPU1_SA_CB<4>")
	)
	(gr_poly
		(pts
			(xy 147.480782 -265.716258) (xy 147.52701 -265.618976) (xy 147.39239 -265.484102) (xy 147.294854 -265.53033)
			(xy 147.25904 -265.566398) (xy 147.444968 -265.752326)
		)
		(stroke
			(width 0)
			(type solid)
		)
		(fill yes)
		(layer "F.Cu")
		(net "M_E_CPU1_SA_CB<5>")
	)
	(gr_poly
		(pts
			(xy 147.506182 -280.708862) (xy 147.598638 -280.65349) (xy 147.5613 -280.4668) (xy 147.45462 -280.451052)
			(xy 147.404582 -280.461212) (xy 147.456398 -280.718768)
		)
		(stroke
			(width 0)
			(type solid)
		)
		(fill yes)
		(layer "F.Cu")
		(net "M_E_CPU1_SA_DQ<26>")
	)
	(gr_poly
		(pts
			(xy 147.51939 -277.66264) (xy 147.611846 -277.607268) (xy 147.574508 -277.420324) (xy 147.467828 -277.40483)
			(xy 147.41779 -277.414736) (xy 147.469606 -277.672546)
		)
		(stroke
			(width 0)
			(type solid)
		)
		(fill yes)
		(layer "F.Cu")
		(net "M_E_CPU1_SA_DQ<27>")
	)
	(gr_poly
		(pts
			(xy 147.528026 -277.965154) (xy 147.476464 -277.707598) (xy 147.42668 -277.717504) (xy 147.334224 -277.772876)
			(xy 147.371562 -277.959566) (xy 147.478242 -277.975314)
		)
		(stroke
			(width 0)
			(type solid)
		)
		(fill yes)
		(layer "F.Cu")
		(net "M_E_CPU1_SA_DQ<27>")
	)
	(gr_poly
		(pts
			(xy 147.530312 -228.768148) (xy 147.479512 -228.768148) (xy 147.377912 -228.80447) (xy 147.377912 -228.99497)
			(xy 147.479512 -229.031038) (xy 147.530312 -229.031038)
		)
		(stroke
			(width 0)
			(type solid)
		)
		(fill yes)
		(layer "F.Cu")
		(net "M_E_CPU1_SB_DQ<15>")
	)
	(gr_poly
		(pts
			(xy 147.530312 -228.171248) (xy 147.479512 -228.171248) (xy 147.377912 -228.20757) (xy 147.377912 -228.39807)
			(xy 147.479512 -228.434138) (xy 147.530312 -228.434138)
		)
		(stroke
			(width 0)
			(type solid)
		)
		(fill yes)
		(layer "F.Cu")
		(net "M_E_CPU1_SB_DQ<15>")
	)
	(gr_poly
		(pts
			(xy 147.530312 -227.574348) (xy 147.479512 -227.574348) (xy 147.377912 -227.61067) (xy 147.377912 -227.80117)
			(xy 147.479512 -227.837238) (xy 147.530312 -227.837238)
		)
		(stroke
			(width 0)
			(type solid)
		)
		(fill yes)
		(layer "F.Cu")
		(net "M_E_CPU1_SB_DQ<15>")
	)
	(gr_poly
		(pts
			(xy 147.530312 -226.977448) (xy 147.479512 -226.977448) (xy 147.377912 -227.01377) (xy 147.377912 -227.20427)
			(xy 147.479512 -227.240338) (xy 147.530312 -227.240338)
		)
		(stroke
			(width 0)
			(type solid)
		)
		(fill yes)
		(layer "F.Cu")
		(net "M_E_CPU1_SB_DQ<15>")
	)
	(gr_poly
		(pts
			(xy 147.530312 -226.380548) (xy 147.479512 -226.380548) (xy 147.377912 -226.41687) (xy 147.377912 -226.60737)
			(xy 147.479512 -226.643438) (xy 147.530312 -226.643438)
		)
		(stroke
			(width 0)
			(type solid)
		)
		(fill yes)
		(layer "F.Cu")
		(net "M_E_CPU1_SB_DQ<15>")
	)
	(gr_poly
		(pts
			(xy 147.53844 -229.714044) (xy 147.502626 -229.677976) (xy 147.40509 -229.631748) (xy 147.27047 -229.766368)
			(xy 147.316698 -229.863904) (xy 147.352766 -229.899718)
		)
		(stroke
			(width 0)
			(type solid)
		)
		(fill yes)
		(layer "F.Cu")
		(net "M_E_CPU1_SB_DQ<13>")
	)
	(gr_poly
		(pts
			(xy 147.547838 -230.56723) (xy 147.51177 -230.531416) (xy 147.414488 -230.485188) (xy 147.279614 -230.619808)
			(xy 147.326096 -230.717344) (xy 147.36191 -230.753158)
		)
		(stroke
			(width 0)
			(type solid)
		)
		(fill yes)
		(layer "F.Cu")
		(net "M_E_CPU1_SB_DQ<12>")
	)
	(gr_poly
		(pts
			(xy 147.553426 -270.246348) (xy 147.589494 -270.210534) (xy 147.403566 -270.024606) (xy 147.367498 -270.06042)
			(xy 147.32127 -270.157956) (xy 147.456144 -270.292576)
		)
		(stroke
			(width 0)
			(type solid)
		)
		(fill yes)
		(layer "F.Cu")
		(net "M_E_CPU1_SA_CB<0>")
	)
	(gr_poly
		(pts
			(xy 147.562824 -269.392908) (xy 147.598638 -269.357094) (xy 147.41271 -269.171166) (xy 147.376896 -269.20698)
			(xy 147.330668 -269.304516) (xy 147.465288 -269.439136)
		)
		(stroke
			(width 0)
			(type solid)
		)
		(fill yes)
		(layer "F.Cu")
		(net "M_E_CPU1_SA_CB<1>")
	)
	(gr_poly
		(pts
			(xy 147.57146 -279.478486) (xy 147.663916 -279.42286) (xy 147.626578 -279.23617) (xy 147.519898 -279.220676)
			(xy 147.470114 -279.230582) (xy 147.521676 -279.488392)
		)
		(stroke
			(width 0)
			(type solid)
		)
		(fill yes)
		(layer "F.Cu")
		(net "M_E_CPU1_SA_DQ<25>")
	)
	(gr_poly
		(pts
			(xy 147.572984 -233.130598) (xy 147.53717 -233.094784) (xy 147.439634 -233.048302) (xy 147.305014 -233.183176)
			(xy 147.351242 -233.280458) (xy 147.387056 -233.316526)
		)
		(stroke
			(width 0)
			(type solid)
		)
		(fill yes)
		(layer "F.Cu")
		(net "M_E_CPU1_SB_DQ<9>")
	)
	(gr_poly
		(pts
			(xy 147.58035 -279.781) (xy 147.528788 -279.52319) (xy 147.47875 -279.533096) (xy 147.386294 -279.588722)
			(xy 147.423632 -279.775412) (xy 147.530566 -279.790906)
		)
		(stroke
			(width 0)
			(type solid)
		)
		(fill yes)
		(layer "F.Cu")
		(net "M_E_CPU1_SA_DQ<25>")
	)
	(gr_poly
		(pts
			(xy 147.582636 -233.984546) (xy 147.546822 -233.948478) (xy 147.449286 -233.90225) (xy 147.314666 -234.03687)
			(xy 147.360894 -234.134406) (xy 147.396962 -234.17022)
		)
		(stroke
			(width 0)
			(type solid)
		)
		(fill yes)
		(layer "F.Cu")
		(net "M_E_CPU1_SB_DQ<8>")
	)
	(gr_poly
		(pts
			(xy 147.586954 -271.901158) (xy 147.622768 -271.865344) (xy 147.43684 -271.679416) (xy 147.401026 -271.715484)
			(xy 147.354798 -271.812766) (xy 147.489418 -271.94764)
		)
		(stroke
			(width 0)
			(type solid)
		)
		(fill yes)
		(layer "F.Cu")
		(net "M_E_CPU1_SA_DQ<30>")
	)
	(gr_poly
		(pts
			(xy 147.596352 -271.047718) (xy 147.632166 -271.01165) (xy 147.446238 -270.825722) (xy 147.410424 -270.86179)
			(xy 147.364196 -270.959326) (xy 147.498816 -271.093946)
		)
		(stroke
			(width 0)
			(type solid)
		)
		(fill yes)
		(layer "F.Cu")
		(net "M_E_CPU1_SA_DQ<31>")
	)
	(gr_poly
		(pts
			(xy 147.61083 -266.852654) (xy 147.646644 -266.816586) (xy 147.460716 -266.630658) (xy 147.424902 -266.666726)
			(xy 147.378674 -266.764008) (xy 147.513294 -266.898882)
		)
		(stroke
			(width 0)
			(type solid)
		)
		(fill yes)
		(layer "F.Cu")
		(net "M_E_CPU1_SA_CB<4>")
	)
	(gr_poly
		(pts
			(xy 147.619974 -265.999214) (xy 147.655788 -265.963146) (xy 147.470114 -265.777472) (xy 147.434046 -265.813286)
			(xy 147.387818 -265.910822) (xy 147.522438 -266.045442)
		)
		(stroke
			(width 0)
			(type solid)
		)
		(fill yes)
		(layer "F.Cu")
		(net "M_E_CPU1_SA_CB<5>")
	)
	(gr_poly
		(pts
			(xy 147.625308 -230.27386) (xy 147.57908 -230.176578) (xy 147.543266 -230.14051) (xy 147.357338 -230.326438)
			(xy 147.393152 -230.362506) (xy 147.490688 -230.408734)
		)
		(stroke
			(width 0)
			(type solid)
		)
		(fill yes)
		(layer "F.Cu")
		(net "M_E_CPU1_SB_DQ<14>")
	)
	(gr_poly
		(pts
			(xy 147.62988 -269.747746) (xy 147.676108 -269.650464) (xy 147.541488 -269.51559) (xy 147.443952 -269.562072)
			(xy 147.408138 -269.597886) (xy 147.594066 -269.783814)
		)
		(stroke
			(width 0)
			(type solid)
		)
		(fill yes)
		(layer "F.Cu")
		(net "M_E_CPU1_SA_CB<2>")
	)
	(gr_poly
		(pts
			(xy 147.636484 -278.247856) (xy 147.72894 -278.192484) (xy 147.691602 -278.005794) (xy 147.584922 -277.990046)
			(xy 147.534884 -278.000206) (xy 147.5867 -278.258016)
		)
		(stroke
			(width 0)
			(type solid)
		)
		(fill yes)
		(layer "F.Cu")
		(net "M_E_CPU1_SA_DQ<27>")
	)
	(gr_poly
		(pts
			(xy 147.639278 -268.89456) (xy 147.685506 -268.797024) (xy 147.550632 -268.662404) (xy 147.45335 -268.708632)
			(xy 147.417282 -268.744446) (xy 147.60321 -268.930374)
		)
		(stroke
			(width 0)
			(type solid)
		)
		(fill yes)
		(layer "F.Cu")
		(net "M_E_CPU1_SA_CB<3>")
	)
	(gr_poly
		(pts
			(xy 147.64512 -278.550624) (xy 147.593558 -278.292814) (xy 147.543774 -278.30272) (xy 147.451318 -278.358092)
			(xy 147.488656 -278.545036) (xy 147.595336 -278.56053)
		)
		(stroke
			(width 0)
			(type solid)
		)
		(fill yes)
		(layer "F.Cu")
		(net "M_E_CPU1_SA_DQ<27>")
	)
	(gr_poly
		(pts
			(xy 147.6502 -232.836974) (xy 147.603972 -232.739438) (xy 147.568158 -232.703624) (xy 147.38223 -232.889298)
			(xy 147.418044 -232.925366) (xy 147.51558 -232.971594)
		)
		(stroke
			(width 0)
			(type solid)
		)
		(fill yes)
		(layer "F.Cu")
		(net "M_E_CPU1_SB_DQ<11>")
	)
	(gr_poly
		(pts
			(xy 147.65401 -272.255996) (xy 147.700238 -272.158714) (xy 147.565618 -272.024094) (xy 147.468082 -272.070322)
			(xy 147.432268 -272.106136) (xy 147.618196 -272.292064)
		)
		(stroke
			(width 0)
			(type solid)
		)
		(fill yes)
		(layer "F.Cu")
		(net "M_E_CPU1_SA_DQ<28>")
	)
	(gr_poly
		(pts
			(xy 147.660106 -233.690922) (xy 147.613878 -233.59364) (xy 147.578064 -233.557572) (xy 147.392136 -233.7435)
			(xy 147.42795 -233.779314) (xy 147.525486 -233.825796)
		)
		(stroke
			(width 0)
			(type solid)
		)
		(fill yes)
		(layer "F.Cu")
		(net "M_E_CPU1_SB_DQ<10>")
	)
	(gr_poly
		(pts
			(xy 147.663408 -271.402556) (xy 147.709636 -271.305274) (xy 147.575016 -271.1704) (xy 147.47748 -271.216628)
			(xy 147.441666 -271.252696) (xy 147.627594 -271.438624)
		)
		(stroke
			(width 0)
			(type solid)
		)
		(fill yes)
		(layer "F.Cu")
		(net "M_E_CPU1_SA_DQ<29>")
	)
	(gr_poly
		(pts
			(xy 147.682712 -228.696266) (xy 147.682712 -228.505766) (xy 147.581112 -228.469698) (xy 147.530312 -228.469698)
			(xy 147.530312 -228.732588) (xy 147.581112 -228.732588)
		)
		(stroke
			(width 0)
			(type solid)
		)
		(fill yes)
		(layer "F.Cu")
		(net "M_E_CPU1_SB_DQ<15>")
	)
	(gr_poly
		(pts
			(xy 147.682712 -228.099366) (xy 147.682712 -227.908866) (xy 147.581112 -227.872798) (xy 147.530312 -227.872798)
			(xy 147.530312 -228.135688) (xy 147.581112 -228.135688)
		)
		(stroke
			(width 0)
			(type solid)
		)
		(fill yes)
		(layer "F.Cu")
		(net "M_E_CPU1_SB_DQ<15>")
	)
	(gr_poly
		(pts
			(xy 147.682712 -227.502466) (xy 147.682712 -227.311966) (xy 147.581112 -227.275898) (xy 147.530312 -227.275898)
			(xy 147.530312 -227.538788) (xy 147.581112 -227.538788)
		)
		(stroke
			(width 0)
			(type solid)
		)
		(fill yes)
		(layer "F.Cu")
		(net "M_E_CPU1_SB_DQ<15>")
	)
	(gr_poly
		(pts
			(xy 147.682712 -226.905566) (xy 147.682712 -226.715066) (xy 147.581112 -226.678998) (xy 147.530312 -226.678998)
			(xy 147.530312 -226.941888) (xy 147.581112 -226.941888)
		)
		(stroke
			(width 0)
			(type solid)
		)
		(fill yes)
		(layer "F.Cu")
		(net "M_E_CPU1_SB_DQ<15>")
	)
	(gr_poly
		(pts
			(xy 147.687284 -266.354052) (xy 147.733512 -266.256516) (xy 147.598892 -266.121896) (xy 147.501356 -266.168124)
			(xy 147.465288 -266.203938) (xy 147.651216 -266.389866)
		)
		(stroke
			(width 0)
			(type solid)
		)
		(fill yes)
		(layer "F.Cu")
		(net "M_E_CPU1_SA_CB<6>")
	)
	(gr_poly
		(pts
			(xy 147.688554 -280.063702) (xy 147.781264 -280.00833) (xy 147.743672 -279.821386) (xy 147.636992 -279.805892)
			(xy 147.587208 -279.815798) (xy 147.63877 -280.073608)
		)
		(stroke
			(width 0)
			(type solid)
		)
		(fill yes)
		(layer "F.Cu")
		(net "M_E_CPU1_SA_DQ<25>")
	)
	(gr_poly
		(pts
			(xy 147.696428 -265.500612) (xy 147.742656 -265.40333) (xy 147.608036 -265.268456) (xy 147.5105 -265.314684)
			(xy 147.474686 -265.350752) (xy 147.660614 -265.53668)
		)
		(stroke
			(width 0)
			(type solid)
		)
		(fill yes)
		(layer "F.Cu")
		(net "M_E_CPU1_SA_CB<7>")
	)
	(gr_poly
		(pts
			(xy 147.697444 -280.366216) (xy 147.645882 -280.108406) (xy 147.596098 -280.118566) (xy 147.503388 -280.173938)
			(xy 147.540726 -280.360628) (xy 147.64766 -280.376376)
		)
		(stroke
			(width 0)
			(type solid)
		)
		(fill yes)
		(layer "F.Cu")
		(net "M_E_CPU1_SA_DQ<25>")
	)
	(gr_poly
		(pts
			(xy 147.753578 -278.833326) (xy 147.846034 -278.777954) (xy 147.808696 -278.59101) (xy 147.702016 -278.575516)
			(xy 147.652232 -278.585422) (xy 147.703794 -278.843232)
		)
		(stroke
			(width 0)
			(type solid)
		)
		(fill yes)
		(layer "F.Cu")
		(net "M_E_CPU1_SA_DQ<27>")
	)
	(gr_poly
		(pts
			(xy 147.754086 -229.92969) (xy 147.718272 -229.893622) (xy 147.620736 -229.847394) (xy 147.486116 -229.982014)
			(xy 147.532344 -230.07955) (xy 147.568412 -230.115364)
		)
		(stroke
			(width 0)
			(type solid)
		)
		(fill yes)
		(layer "F.Cu")
		(net "M_E_CPU1_SB_DQ<14>")
	)
	(gr_poly
		(pts
			(xy 147.762214 -279.13584) (xy 147.710652 -278.87803) (xy 147.660868 -278.887936) (xy 147.568412 -278.943562)
			(xy 147.60575 -279.130252) (xy 147.71243 -279.145746)
		)
		(stroke
			(width 0)
			(type solid)
		)
		(fill yes)
		(layer "F.Cu")
		(net "M_E_CPU1_SA_DQ<27>")
	)
	(gr_poly
		(pts
			(xy 147.769072 -270.030702) (xy 147.80514 -269.994888) (xy 147.619212 -269.80896) (xy 147.583144 -269.844774)
			(xy 147.536916 -269.94231) (xy 147.67179 -270.07693)
		)
		(stroke
			(width 0)
			(type solid)
		)
		(fill yes)
		(layer "F.Cu")
		(net "M_E_CPU1_SA_CB<2>")
	)
	(gr_poly
		(pts
			(xy 147.77847 -269.177262) (xy 147.814284 -269.141448) (xy 147.628356 -268.95552) (xy 147.592542 -268.991334)
			(xy 147.546314 -269.08887) (xy 147.680934 -269.22349)
		)
		(stroke
			(width 0)
			(type solid)
		)
		(fill yes)
		(layer "F.Cu")
		(net "M_E_CPU1_SA_CB<3>")
	)
	(gr_poly
		(pts
			(xy 147.778978 -232.49255) (xy 147.743164 -232.456482) (xy 147.645628 -232.410254) (xy 147.511008 -232.544874)
			(xy 147.557236 -232.64241) (xy 147.59305 -232.678224)
		)
		(stroke
			(width 0)
			(type solid)
		)
		(fill yes)
		(layer "F.Cu")
		(net "M_E_CPU1_SB_DQ<11>")
	)
	(gr_poly
		(pts
			(xy 147.789138 -233.346498) (xy 147.75307 -233.310684) (xy 147.655788 -233.264456) (xy 147.520914 -233.399076)
			(xy 147.567142 -233.496612) (xy 147.60321 -233.532426)
		)
		(stroke
			(width 0)
			(type solid)
		)
		(fill yes)
		(layer "F.Cu")
		(net "M_E_CPU1_SB_DQ<10>")
	)
	(gr_poly
		(pts
			(xy 147.793202 -272.538952) (xy 147.82927 -272.503138) (xy 147.643342 -272.31721) (xy 147.607274 -272.353024)
			(xy 147.561046 -272.45056) (xy 147.69592 -272.58518)
		)
		(stroke
			(width 0)
			(type solid)
		)
		(fill yes)
		(layer "F.Cu")
		(net "M_E_CPU1_SA_DQ<28>")
	)
	(gr_poly
		(pts
			(xy 147.8026 -271.685512) (xy 147.838668 -271.649698) (xy 147.65274 -271.46377) (xy 147.616672 -271.499584)
			(xy 147.570444 -271.59712) (xy 147.705318 -271.73174)
		)
		(stroke
			(width 0)
			(type solid)
		)
		(fill yes)
		(layer "F.Cu")
		(net "M_E_CPU1_SA_DQ<29>")
	)
	(gr_poly
		(pts
			(xy 147.826476 -266.637008) (xy 147.86229 -266.60094) (xy 147.676362 -266.415012) (xy 147.640548 -266.45108)
			(xy 147.59432 -266.548362) (xy 147.72894 -266.683236)
		)
		(stroke
			(width 0)
			(type solid)
		)
		(fill yes)
		(layer "F.Cu")
		(net "M_E_CPU1_SA_CB<6>")
	)
	(gr_poly
		(pts
			(xy 147.835112 -228.768148) (xy 147.784312 -228.768148) (xy 147.682712 -228.80447) (xy 147.682712 -228.99497)
			(xy 147.784312 -229.031038) (xy 147.835112 -229.031038)
		)
		(stroke
			(width 0)
			(type solid)
		)
		(fill yes)
		(layer "F.Cu")
		(net "M_E_CPU1_SB_DQ<13>")
	)
	(gr_poly
		(pts
			(xy 147.835112 -228.171248) (xy 147.784312 -228.171248) (xy 147.682712 -228.20757) (xy 147.682712 -228.39807)
			(xy 147.784312 -228.434138) (xy 147.835112 -228.434138)
		)
		(stroke
			(width 0)
			(type solid)
		)
		(fill yes)
		(layer "F.Cu")
		(net "M_E_CPU1_SB_DQ<13>")
	)
	(gr_poly
		(pts
			(xy 147.835112 -227.574348) (xy 147.784312 -227.574348) (xy 147.682712 -227.61067) (xy 147.682712 -227.80117)
			(xy 147.784312 -227.837238) (xy 147.835112 -227.837238)
		)
		(stroke
			(width 0)
			(type solid)
		)
		(fill yes)
		(layer "F.Cu")
		(net "M_E_CPU1_SB_DQ<13>")
	)
	(gr_poly
		(pts
			(xy 147.835112 -226.977448) (xy 147.784312 -226.977448) (xy 147.682712 -227.01377) (xy 147.682712 -227.20427)
			(xy 147.784312 -227.240338) (xy 147.835112 -227.240338)
		)
		(stroke
			(width 0)
			(type solid)
		)
		(fill yes)
		(layer "F.Cu")
		(net "M_E_CPU1_SB_DQ<13>")
	)
	(gr_poly
		(pts
			(xy 147.835112 -226.380548) (xy 147.784312 -226.380548) (xy 147.682712 -226.41687) (xy 147.682712 -226.60737)
			(xy 147.784312 -226.643438) (xy 147.835112 -226.643438)
		)
		(stroke
			(width 0)
			(type solid)
		)
		(fill yes)
		(layer "F.Cu")
		(net "M_E_CPU1_SB_DQ<13>")
	)
	(gr_poly
		(pts
			(xy 147.83562 -265.783568) (xy 147.871434 -265.7475) (xy 147.68576 -265.561826) (xy 147.649692 -265.59764)
			(xy 147.603464 -265.695176) (xy 147.738084 -265.829796)
		)
		(stroke
			(width 0)
			(type solid)
		)
		(fill yes)
		(layer "F.Cu")
		(net "M_E_CPU1_SA_CB<7>")
	)
	(gr_poly
		(pts
			(xy 147.836382 -270.38554) (xy 147.88261 -270.288004) (xy 147.74799 -270.153384) (xy 147.650454 -270.199612)
			(xy 147.61464 -270.23568) (xy 147.800314 -270.421354)
		)
		(stroke
			(width 0)
			(type solid)
		)
		(fill yes)
		(layer "F.Cu")
		(net "M_E_CPU1_SA_CB<0>")
	)
	(gr_poly
		(pts
			(xy 147.840954 -230.489506) (xy 147.794726 -230.392224) (xy 147.758912 -230.356156) (xy 147.572984 -230.542084)
			(xy 147.608798 -230.578152) (xy 147.706334 -230.62438)
		)
		(stroke
			(width 0)
			(type solid)
		)
		(fill yes)
		(layer "F.Cu")
		(net "M_E_CPU1_SB_DQ<12>")
	)
	(gr_poly
		(pts
			(xy 147.845526 -269.5321) (xy 147.891754 -269.434818) (xy 147.757134 -269.299944) (xy 147.659598 -269.346426)
			(xy 147.623784 -269.38224) (xy 147.809712 -269.568168)
		)
		(stroke
			(width 0)
			(type solid)
		)
		(fill yes)
		(layer "F.Cu")
		(net "M_E_CPU1_SA_CB<1>")
	)
	(gr_poly
		(pts
			(xy 147.866354 -233.052874) (xy 147.820126 -232.955592) (xy 147.784058 -232.919524) (xy 147.59813 -233.105452)
			(xy 147.634198 -233.141266) (xy 147.73148 -233.187494)
		)
		(stroke
			(width 0)
			(type solid)
		)
		(fill yes)
		(layer "F.Cu")
		(net "M_E_CPU1_SB_DQ<9>")
	)
	(gr_poly
		(pts
			(xy 147.869656 -272.04035) (xy 147.915884 -271.943068) (xy 147.781264 -271.808448) (xy 147.683728 -271.854676)
			(xy 147.647914 -271.89049) (xy 147.833842 -272.076418)
		)
		(stroke
			(width 0)
			(type solid)
		)
		(fill yes)
		(layer "F.Cu")
		(net "M_E_CPU1_SA_DQ<30>")
	)
	(gr_poly
		(pts
			(xy 147.870672 -279.418542) (xy 147.963128 -279.36317) (xy 147.92579 -279.176226) (xy 147.81911 -279.160732)
			(xy 147.769326 -279.170638) (xy 147.820888 -279.428448)
		)
		(stroke
			(width 0)
			(type solid)
		)
		(fill yes)
		(layer "F.Cu")
		(net "M_E_CPU1_SA_DQ<27>")
	)
	(gr_poly
		(pts
			(xy 147.876006 -233.906822) (xy 147.829778 -233.809286) (xy 147.79371 -233.773472) (xy 147.607782 -233.9594)
			(xy 147.64385 -233.995214) (xy 147.741386 -234.041442)
		)
		(stroke
			(width 0)
			(type solid)
		)
		(fill yes)
		(layer "F.Cu")
		(net "M_E_CPU1_SB_DQ<8>")
	)
	(gr_poly
		(pts
			(xy 147.879308 -279.721056) (xy 147.827746 -279.4635) (xy 147.777962 -279.473406) (xy 147.685506 -279.528778)
			(xy 147.722844 -279.715468) (xy 147.829524 -279.731216)
		)
		(stroke
			(width 0)
			(type solid)
		)
		(fill yes)
		(layer "F.Cu")
		(net "M_E_CPU1_SA_DQ<27>")
	)
	(gr_poly
		(pts
			(xy 147.879308 -271.18691) (xy 147.925536 -271.089374) (xy 147.790662 -270.954754) (xy 147.69338 -271.000982)
			(xy 147.657312 -271.036796) (xy 147.84324 -271.222724)
		)
		(stroke
			(width 0)
			(type solid)
		)
		(fill yes)
		(layer "F.Cu")
		(net "M_E_CPU1_SA_DQ<31>")
	)
	(gr_poly
		(pts
			(xy 147.893532 -266.991846) (xy 147.940014 -266.89431) (xy 147.80514 -266.75969) (xy 147.707858 -266.805918)
			(xy 147.67179 -266.841732) (xy 147.857718 -267.02766)
		)
		(stroke
			(width 0)
			(type solid)
		)
		(fill yes)
		(layer "F.Cu")
		(net "M_E_CPU1_SA_CB<4>")
	)
	(gr_poly
		(pts
			(xy 147.90293 -266.138406) (xy 147.949158 -266.04087) (xy 147.814538 -265.90625) (xy 147.717002 -265.952478)
			(xy 147.680934 -265.988292) (xy 147.866862 -266.17422)
		)
		(stroke
			(width 0)
			(type solid)
		)
		(fill yes)
		(layer "F.Cu")
		(net "M_E_CPU1_SA_CB<5>")
	)
	(gr_poly
		(pts
			(xy 147.969732 -230.145336) (xy 147.933918 -230.109268) (xy 147.836382 -230.06304) (xy 147.701762 -230.19766)
			(xy 147.74799 -230.295196) (xy 147.784058 -230.33101)
		)
		(stroke
			(width 0)
			(type solid)
		)
		(fill yes)
		(layer "F.Cu")
		(net "M_E_CPU1_SB_DQ<12>")
	)
	(gr_poly
		(pts
			(xy 147.975574 -270.668496) (xy 148.011388 -270.632428) (xy 147.82546 -270.4465) (xy 147.789646 -270.482568)
			(xy 147.743418 -270.580104) (xy 147.878038 -270.714724)
		)
		(stroke
			(width 0)
			(type solid)
		)
		(fill yes)
		(layer "F.Cu")
		(net "M_E_CPU1_SA_CB<0>")
	)
	(gr_poly
		(pts
			(xy 147.984718 -269.815056) (xy 148.020786 -269.779242) (xy 147.834858 -269.593314) (xy 147.79879 -269.629128)
			(xy 147.752562 -269.726664) (xy 147.887436 -269.861284)
		)
		(stroke
			(width 0)
			(type solid)
		)
		(fill yes)
		(layer "F.Cu")
		(net "M_E_CPU1_SA_CB<1>")
	)
	(gr_poly
		(pts
			(xy 147.987512 -228.696266) (xy 147.987512 -228.505766) (xy 147.885912 -228.469698) (xy 147.835112 -228.469698)
			(xy 147.835112 -228.732588) (xy 147.885912 -228.732588)
		)
		(stroke
			(width 0)
			(type solid)
		)
		(fill yes)
		(layer "F.Cu")
		(net "M_E_CPU1_SB_DQ<13>")
	)
	(gr_poly
		(pts
			(xy 147.987512 -228.099366) (xy 147.987512 -227.908866) (xy 147.885912 -227.872798) (xy 147.835112 -227.872798)
			(xy 147.835112 -228.135688) (xy 147.885912 -228.135688)
		)
		(stroke
			(width 0)
			(type solid)
		)
		(fill yes)
		(layer "F.Cu")
		(net "M_E_CPU1_SB_DQ<13>")
	)
	(gr_poly
		(pts
			(xy 147.987512 -227.502466) (xy 147.987512 -227.311966) (xy 147.885912 -227.275898) (xy 147.835112 -227.275898)
			(xy 147.835112 -227.538788) (xy 147.885912 -227.538788)
		)
		(stroke
			(width 0)
			(type solid)
		)
		(fill yes)
		(layer "F.Cu")
		(net "M_E_CPU1_SB_DQ<13>")
	)
	(gr_poly
		(pts
			(xy 147.987512 -226.905566) (xy 147.987512 -226.715066) (xy 147.885912 -226.678998) (xy 147.835112 -226.678998)
			(xy 147.835112 -226.941888) (xy 147.885912 -226.941888)
		)
		(stroke
			(width 0)
			(type solid)
		)
		(fill yes)
		(layer "F.Cu")
		(net "M_E_CPU1_SB_DQ<13>")
	)
	(gr_poly
		(pts
			(xy 147.987766 -280.003758) (xy 148.080222 -279.948386) (xy 148.042884 -279.761696) (xy 147.936204 -279.745948)
			(xy 147.88642 -279.756108) (xy 147.937982 -280.013918)
		)
		(stroke
			(width 0)
			(type solid)
		)
		(fill yes)
		(layer "F.Cu")
		(net "M_E_CPU1_SA_DQ<27>")
	)
	(gr_poly
		(pts
			(xy 147.995132 -232.70845) (xy 147.959318 -232.672636) (xy 147.861782 -232.626408) (xy 147.727162 -232.761028)
			(xy 147.77339 -232.858564) (xy 147.809204 -232.894378)
		)
		(stroke
			(width 0)
			(type solid)
		)
		(fill yes)
		(layer "F.Cu")
		(net "M_E_CPU1_SB_DQ<9>")
	)
	(gr_poly
		(pts
			(xy 147.996402 -280.306526) (xy 147.94484 -280.048716) (xy 147.895056 -280.058622) (xy 147.8026 -280.113994)
			(xy 147.839938 -280.300938) (xy 147.946618 -280.316432)
		)
		(stroke
			(width 0)
			(type solid)
		)
		(fill yes)
		(layer "F.Cu")
		(net "M_E_CPU1_SA_DQ<27>")
	)
	(gr_poly
		(pts
			(xy 148.004784 -233.562398) (xy 147.96897 -233.52633) (xy 147.871434 -233.480102) (xy 147.736814 -233.614976)
			(xy 147.783042 -233.712258) (xy 147.818856 -233.748326)
		)
		(stroke
			(width 0)
			(type solid)
		)
		(fill yes)
		(layer "F.Cu")
		(net "M_E_CPU1_SB_DQ<8>")
	)
	(gr_poly
		(pts
			(xy 148.008848 -272.323306) (xy 148.044916 -272.287492) (xy 147.858988 -272.101564) (xy 147.82292 -272.137378)
			(xy 147.776692 -272.234914) (xy 147.911566 -272.369534)
		)
		(stroke
			(width 0)
			(type solid)
		)
		(fill yes)
		(layer "F.Cu")
		(net "M_E_CPU1_SA_DQ<30>")
	)
	(gr_poly
		(pts
			(xy 148.0185 -271.469612) (xy 148.054314 -271.433798) (xy 147.868386 -271.24787) (xy 147.832572 -271.283938)
			(xy 147.786344 -271.38122) (xy 147.920964 -271.516094)
		)
		(stroke
			(width 0)
			(type solid)
		)
		(fill yes)
		(layer "F.Cu")
		(net "M_E_CPU1_SA_DQ<31>")
	)
	(gr_poly
		(pts
			(xy 148.032724 -267.274548) (xy 148.068792 -267.238734) (xy 147.882864 -267.052806) (xy 147.84705 -267.08862)
			(xy 147.800822 -267.186156) (xy 147.935442 -267.320776)
		)
		(stroke
			(width 0)
			(type solid)
		)
		(fill yes)
		(layer "F.Cu")
		(net "M_E_CPU1_SA_CB<4>")
	)
	(gr_poly
		(pts
			(xy 148.042122 -266.421362) (xy 148.077936 -266.385294) (xy 147.892008 -266.199366) (xy 147.856194 -266.235434)
			(xy 147.809966 -266.332716) (xy 147.944586 -266.46759)
		)
		(stroke
			(width 0)
			(type solid)
		)
		(fill yes)
		(layer "F.Cu")
		(net "M_E_CPU1_SA_CB<5>")
	)
	(gr_poly
		(pts
			(xy 148.047456 -229.851966) (xy 148.001228 -229.75443) (xy 147.96516 -229.718616) (xy 147.779232 -229.904544)
			(xy 147.8153 -229.940358) (xy 147.912836 -229.986586)
		)
		(stroke
			(width 0)
			(type solid)
		)
		(fill yes)
		(layer "F.Cu")
		(net "M_E_CPU1_SB_DQ<14>")
	)
	(gr_poly
		(pts
			(xy 148.052028 -270.169894) (xy 148.098256 -270.072358) (xy 147.963636 -269.937738) (xy 147.8661 -269.983966)
			(xy 147.830286 -270.020034) (xy 148.01596 -270.205708)
		)
		(stroke
			(width 0)
			(type solid)
		)
		(fill yes)
		(layer "F.Cu")
		(net "M_E_CPU1_SA_CB<2>")
	)
	(gr_poly
		(pts
			(xy 148.061172 -269.316454) (xy 148.1074 -269.219172) (xy 147.97278 -269.084298) (xy 147.875244 -269.13078)
			(xy 147.83943 -269.166594) (xy 148.025358 -269.352522)
		)
		(stroke
			(width 0)
			(type solid)
		)
		(fill yes)
		(layer "F.Cu")
		(net "M_E_CPU1_SA_CB<3>")
	)
	(gr_poly
		(pts
			(xy 148.072348 -232.414826) (xy 148.02612 -232.31729) (xy 147.990052 -232.281476) (xy 147.804124 -232.467404)
			(xy 147.840192 -232.503218) (xy 147.937474 -232.549446)
		)
		(stroke
			(width 0)
			(type solid)
		)
		(fill yes)
		(layer "F.Cu")
		(net "M_E_CPU1_SB_DQ<11>")
	)
	(gr_poly
		(pts
			(xy 148.082254 -233.268774) (xy 148.036026 -233.171492) (xy 148.000212 -233.135424) (xy 147.814284 -233.321352)
			(xy 147.850098 -233.35742) (xy 147.947634 -233.403648)
		)
		(stroke
			(width 0)
			(type solid)
		)
		(fill yes)
		(layer "F.Cu")
		(net "M_E_CPU1_SB_DQ<10>")
	)
	(gr_poly
		(pts
			(xy 148.085556 -271.824704) (xy 148.131784 -271.727168) (xy 147.997164 -271.592548) (xy 147.899628 -271.638776)
			(xy 147.863814 -271.674844) (xy 148.049488 -271.860518)
		)
		(stroke
			(width 0)
			(type solid)
		)
		(fill yes)
		(layer "F.Cu")
		(net "M_E_CPU1_SA_DQ<29>")
	)
	(gr_poly
		(pts
			(xy 148.10486 -280.589228) (xy 148.197316 -280.533856) (xy 148.159978 -280.346912) (xy 148.053298 -280.331418)
			(xy 148.003514 -280.341324) (xy 148.055076 -280.599134)
		)
		(stroke
			(width 0)
			(type solid)
		)
		(fill yes)
		(layer "F.Cu")
		(net "M_E_CPU1_SA_DQ<27>")
	)
	(gr_poly
		(pts
			(xy 148.109178 -266.7762) (xy 148.15566 -266.678664) (xy 148.020786 -266.544044) (xy 147.923504 -266.590272)
			(xy 147.887436 -266.626086) (xy 148.073364 -266.812014)
		)
		(stroke
			(width 0)
			(type solid)
		)
		(fill yes)
		(layer "F.Cu")
		(net "M_E_CPU1_SA_CB<6>")
	)
	(gr_poly
		(pts
			(xy 148.118576 -265.92276) (xy 148.164804 -265.825224) (xy 148.030184 -265.690604) (xy 147.932648 -265.736832)
			(xy 147.89658 -265.772646) (xy 148.082508 -265.958574)
		)
		(stroke
			(width 0)
			(type solid)
		)
		(fill yes)
		(layer "F.Cu")
		(net "M_E_CPU1_SA_CB<7>")
	)
	(gr_poly
		(pts
			(xy 148.139912 -228.768148) (xy 148.089112 -228.768148) (xy 147.987512 -228.80447) (xy 147.987512 -228.99497)
			(xy 148.089112 -229.031038) (xy 148.139912 -229.031038)
		)
		(stroke
			(width 0)
			(type solid)
		)
		(fill yes)
		(layer "F.Cu")
		(net "M_E_CPU1_SB_DQ<14>")
	)
	(gr_poly
		(pts
			(xy 148.139912 -228.171248) (xy 148.089112 -228.171248) (xy 147.987512 -228.20757) (xy 147.987512 -228.39807)
			(xy 148.089112 -228.434138) (xy 148.139912 -228.434138)
		)
		(stroke
			(width 0)
			(type solid)
		)
		(fill yes)
		(layer "F.Cu")
		(net "M_E_CPU1_SB_DQ<14>")
	)
	(gr_poly
		(pts
			(xy 148.139912 -227.574348) (xy 148.089112 -227.574348) (xy 147.987512 -227.61067) (xy 147.987512 -227.80117)
			(xy 148.089112 -227.837238) (xy 148.139912 -227.837238)
		)
		(stroke
			(width 0)
			(type solid)
		)
		(fill yes)
		(layer "F.Cu")
		(net "M_E_CPU1_SB_DQ<14>")
	)
	(gr_poly
		(pts
			(xy 148.179028 -273.376644) (xy 148.127466 -273.118834) (xy 148.077682 -273.12874) (xy 147.984972 -273.184112)
			(xy 148.02231 -273.371056) (xy 148.129244 -273.38655)
		)
		(stroke
			(width 0)
			(type solid)
		)
		(fill yes)
		(layer "F.Cu")
		(net "M_E_CPU1_SA_DQ<28>")
	)
	(gr_poly
		(pts
			(xy 148.19122 -270.45285) (xy 148.227034 -270.416782) (xy 148.041106 -270.230854) (xy 148.005292 -270.266922)
			(xy 147.959064 -270.364458) (xy 148.093684 -270.499078)
		)
		(stroke
			(width 0)
			(type solid)
		)
		(fill yes)
		(layer "F.Cu")
		(net "M_E_CPU1_SA_CB<2>")
	)
	(gr_poly
		(pts
			(xy 148.200364 -269.59941) (xy 148.236432 -269.563596) (xy 148.050504 -269.377668) (xy 148.014436 -269.413482)
			(xy 147.968208 -269.511018) (xy 148.103082 -269.645638)
		)
		(stroke
			(width 0)
			(type solid)
		)
		(fill yes)
		(layer "F.Cu")
		(net "M_E_CPU1_SA_CB<3>")
	)
	(gr_poly
		(pts
			(xy 148.201126 -232.070402) (xy 148.165312 -232.034588) (xy 148.067776 -231.988106) (xy 147.933156 -232.12298)
			(xy 147.979384 -232.220262) (xy 148.015198 -232.25633)
		)
		(stroke
			(width 0)
			(type solid)
		)
		(fill yes)
		(layer "F.Cu")
		(net "M_E_CPU1_SB_DQ<11>")
	)
	(gr_poly
		(pts
			(xy 148.211032 -232.924604) (xy 148.175218 -232.888536) (xy 148.077682 -232.842308) (xy 147.943062 -232.976928)
			(xy 147.98929 -233.074464) (xy 148.025358 -233.110278)
		)
		(stroke
			(width 0)
			(type solid)
		)
		(fill yes)
		(layer "F.Cu")
		(net "M_E_CPU1_SB_DQ<10>")
	)
	(gr_poly
		(pts
			(xy 148.224748 -272.10766) (xy 148.260562 -272.071592) (xy 148.074634 -271.885664) (xy 148.03882 -271.921732)
			(xy 147.992592 -272.019014) (xy 148.127212 -272.153888)
		)
		(stroke
			(width 0)
			(type solid)
		)
		(fill yes)
		(layer "F.Cu")
		(net "M_E_CPU1_SA_DQ<29>")
	)
	(gr_poly
		(pts
			(xy 148.24837 -267.058902) (xy 148.284438 -267.023088) (xy 148.09851 -266.83716) (xy 148.062696 -266.872974)
			(xy 148.016468 -266.97051) (xy 148.151088 -267.10513)
		)
		(stroke
			(width 0)
			(type solid)
		)
		(fill yes)
		(layer "F.Cu")
		(net "M_E_CPU1_SA_CB<6>")
	)
	(gr_poly
		(pts
			(xy 148.257768 -266.205716) (xy 148.293582 -266.169648) (xy 148.107654 -265.98372) (xy 148.07184 -266.019788)
			(xy 148.025612 -266.11707) (xy 148.160232 -266.251944)
		)
		(stroke
			(width 0)
			(type solid)
		)
		(fill yes)
		(layer "F.Cu")
		(net "M_E_CPU1_SA_CB<7>")
	)
	(gr_poly
		(pts
			(xy 148.25853 -270.807688) (xy 148.304758 -270.710152) (xy 148.169884 -270.575532) (xy 148.072602 -270.62176)
			(xy 148.036534 -270.657574) (xy 148.222462 -270.843502)
		)
		(stroke
			(width 0)
			(type solid)
		)
		(fill yes)
		(layer "F.Cu")
		(net "M_E_CPU1_SA_CB<0>")
	)
	(gr_poly
		(pts
			(xy 148.263102 -230.067612) (xy 148.216874 -229.970076) (xy 148.180806 -229.934262) (xy 147.994878 -230.12019)
			(xy 148.030946 -230.156004) (xy 148.128482 -230.202232)
		)
		(stroke
			(width 0)
			(type solid)
		)
		(fill yes)
		(layer "F.Cu")
		(net "M_E_CPU1_SB_DQ<12>")
	)
	(gr_poly
		(pts
			(xy 148.267674 -269.954248) (xy 148.313902 -269.856712) (xy 148.179282 -269.722092) (xy 148.081746 -269.76832)
			(xy 148.045932 -269.804388) (xy 148.231606 -269.990062)
		)
		(stroke
			(width 0)
			(type solid)
		)
		(fill yes)
		(layer "F.Cu")
		(net "M_E_CPU1_SA_CB<1>")
	)
	(gr_poly
		(pts
			(xy 148.287232 -273.659092) (xy 148.379942 -273.60372) (xy 148.342604 -273.41703) (xy 148.23567 -273.401536)
			(xy 148.185886 -273.411442) (xy 148.237448 -273.669252)
		)
		(stroke
			(width 0)
			(type solid)
		)
		(fill yes)
		(layer "F.Cu")
		(net "M_E_CPU1_SA_DQ<28>")
	)
	(gr_poly
		(pts
			(xy 148.288502 -232.63098) (xy 148.24202 -232.533444) (xy 148.206206 -232.49763) (xy 148.020278 -232.683304)
			(xy 148.056346 -232.719372) (xy 148.153628 -232.7656)
		)
		(stroke
			(width 0)
			(type solid)
		)
		(fill yes)
		(layer "F.Cu")
		(net "M_E_CPU1_SB_DQ<9>")
	)
	(gr_poly
		(pts
			(xy 148.292312 -229.293166) (xy 148.292312 -229.102666) (xy 148.190712 -229.066598) (xy 148.139912 -229.066598)
			(xy 148.139912 -229.329488) (xy 148.190712 -229.329488)
		)
		(stroke
			(width 0)
			(type solid)
		)
		(fill yes)
		(layer "F.Cu")
		(net "M_E_CPU1_SB_DQ<14>")
	)
	(gr_poly
		(pts
			(xy 148.292312 -228.696266) (xy 148.292312 -228.505766) (xy 148.190712 -228.469698) (xy 148.139912 -228.469698)
			(xy 148.139912 -228.732588) (xy 148.190712 -228.732588)
		)
		(stroke
			(width 0)
			(type solid)
		)
		(fill yes)
		(layer "F.Cu")
		(net "M_E_CPU1_SB_DQ<14>")
	)
	(gr_poly
		(pts
			(xy 148.292312 -228.099366) (xy 148.292312 -227.908866) (xy 148.190712 -227.872798) (xy 148.139912 -227.872798)
			(xy 148.139912 -228.135688) (xy 148.190712 -228.135688)
		)
		(stroke
			(width 0)
			(type solid)
		)
		(fill yes)
		(layer "F.Cu")
		(net "M_E_CPU1_SB_DQ<14>")
	)
	(gr_poly
		(pts
			(xy 148.292312 -227.502466) (xy 148.292312 -227.311966) (xy 148.190712 -227.275898) (xy 148.139912 -227.275898)
			(xy 148.139912 -227.538788) (xy 148.190712 -227.538788)
		)
		(stroke
			(width 0)
			(type solid)
		)
		(fill yes)
		(layer "F.Cu")
		(net "M_E_CPU1_SB_DQ<14>")
	)
	(gr_poly
		(pts
			(xy 148.296122 -273.96186) (xy 148.24456 -273.70405) (xy 148.194776 -273.713956) (xy 148.102066 -273.769328)
			(xy 148.139658 -273.956272) (xy 148.246338 -273.971766)
		)
		(stroke
			(width 0)
			(type solid)
		)
		(fill yes)
		(layer "F.Cu")
		(net "M_E_CPU1_SA_DQ<28>")
	)
	(gr_poly
		(pts
			(xy 148.298154 -233.484674) (xy 148.251672 -233.387138) (xy 148.215858 -233.351324) (xy 148.02993 -233.537252)
			(xy 148.065998 -233.573066) (xy 148.16328 -233.619294)
		)
		(stroke
			(width 0)
			(type solid)
		)
		(fill yes)
		(layer "F.Cu")
		(net "M_E_CPU1_SB_DQ<8>")
	)
	(gr_poly
		(pts
			(xy 148.301202 -271.608804) (xy 148.34743 -271.511522) (xy 148.21281 -271.376902) (xy 148.115274 -271.42313)
			(xy 148.07946 -271.458944) (xy 148.265388 -271.644872)
		)
		(stroke
			(width 0)
			(type solid)
		)
		(fill yes)
		(layer "F.Cu")
		(net "M_E_CPU1_SA_DQ<31>")
	)
	(gr_poly
		(pts
			(xy 148.31568 -267.41374) (xy 148.361908 -267.316458) (xy 148.227288 -267.181584) (xy 148.129752 -267.227812)
			(xy 148.093938 -267.26388) (xy 148.279866 -267.449808)
		)
		(stroke
			(width 0)
			(type solid)
		)
		(fill yes)
		(layer "F.Cu")
		(net "M_E_CPU1_SA_CB<4>")
	)
	(gr_poly
		(pts
			(xy 148.324824 -266.560554) (xy 148.371306 -266.463018) (xy 148.236432 -266.328398) (xy 148.13915 -266.374626)
			(xy 148.103082 -266.41044) (xy 148.28901 -266.596368)
		)
		(stroke
			(width 0)
			(type solid)
		)
		(fill yes)
		(layer "F.Cu")
		(net "M_E_CPU1_SA_CB<5>")
	)
	(gr_poly
		(pts
			(xy 148.397722 -271.09039) (xy 148.433536 -271.054576) (xy 148.247608 -270.868648) (xy 148.211794 -270.904716)
			(xy 148.165566 -271.001998) (xy 148.300186 -271.136872)
		)
		(stroke
			(width 0)
			(type solid)
		)
		(fill yes)
		(layer "F.Cu")
		(net "M_E_CPU1_SA_CB<0>")
	)
	(gr_poly
		(pts
			(xy 148.40458 -274.244562) (xy 148.497036 -274.18919) (xy 148.459698 -274.002246) (xy 148.353018 -273.986752)
			(xy 148.30298 -273.996658) (xy 148.354542 -274.254468)
		)
		(stroke
			(width 0)
			(type solid)
		)
		(fill yes)
		(layer "F.Cu")
		(net "M_E_CPU1_SA_DQ<28>")
	)
	(gr_poly
		(pts
			(xy 148.406866 -270.237204) (xy 148.44268 -270.201136) (xy 148.256752 -270.015208) (xy 148.220938 -270.051276)
			(xy 148.17471 -270.148812) (xy 148.30933 -270.283432)
		)
		(stroke
			(width 0)
			(type solid)
		)
		(fill yes)
		(layer "F.Cu")
		(net "M_E_CPU1_SA_CB<1>")
	)
	(gr_poly
		(pts
			(xy 148.413216 -274.547076) (xy 148.361654 -274.289266) (xy 148.31187 -274.299426) (xy 148.219414 -274.354798)
			(xy 148.256752 -274.541488) (xy 148.363432 -274.556982)
		)
		(stroke
			(width 0)
			(type solid)
		)
		(fill yes)
		(layer "F.Cu")
		(net "M_E_CPU1_SA_DQ<28>")
	)
	(gr_poly
		(pts
			(xy 148.41728 -232.286556) (xy 148.381466 -232.250488) (xy 148.28393 -232.20426) (xy 148.14931 -232.339134)
			(xy 148.195538 -232.436416) (xy 148.231352 -232.472484)
		)
		(stroke
			(width 0)
			(type solid)
		)
		(fill yes)
		(layer "F.Cu")
		(net "M_E_CPU1_SB_DQ<9>")
	)
	(gr_poly
		(pts
			(xy 148.426932 -233.14025) (xy 148.390864 -233.104436) (xy 148.293582 -233.058208) (xy 148.158962 -233.192828)
			(xy 148.20519 -233.290364) (xy 148.241004 -233.326178)
		)
		(stroke
			(width 0)
			(type solid)
		)
		(fill yes)
		(layer "F.Cu")
		(net "M_E_CPU1_SB_DQ<8>")
	)
	(gr_poly
		(pts
			(xy 148.440394 -271.89176) (xy 148.476462 -271.855946) (xy 148.290534 -271.670018) (xy 148.254466 -271.705832)
			(xy 148.208238 -271.803368) (xy 148.343112 -271.937988)
		)
		(stroke
			(width 0)
			(type solid)
		)
		(fill yes)
		(layer "F.Cu")
		(net "M_E_CPU1_SA_DQ<31>")
	)
	(gr_poly
		(pts
			(xy 148.444712 -228.768148) (xy 148.393912 -228.768148) (xy 148.292312 -228.80447) (xy 148.292312 -228.99497)
			(xy 148.393912 -229.031038) (xy 148.444712 -229.031038)
		)
		(stroke
			(width 0)
			(type solid)
		)
		(fill yes)
		(layer "F.Cu")
		(net "M_E_CPU1_SB_DQ<12>")
	)
	(gr_poly
		(pts
			(xy 148.444712 -228.171248) (xy 148.393912 -228.171248) (xy 148.292312 -228.20757) (xy 148.292312 -228.39807)
			(xy 148.393912 -228.434138) (xy 148.444712 -228.434138)
		)
		(stroke
			(width 0)
			(type solid)
		)
		(fill yes)
		(layer "F.Cu")
		(net "M_E_CPU1_SB_DQ<12>")
	)
	(gr_poly
		(pts
			(xy 148.444712 -227.574348) (xy 148.393912 -227.574348) (xy 148.292312 -227.61067) (xy 148.292312 -227.80117)
			(xy 148.393912 -227.837238) (xy 148.444712 -227.837238)
		)
		(stroke
			(width 0)
			(type solid)
		)
		(fill yes)
		(layer "F.Cu")
		(net "M_E_CPU1_SB_DQ<12>")
	)
	(gr_poly
		(pts
			(xy 148.444712 -226.977448) (xy 148.393912 -226.977448) (xy 148.292312 -227.01377) (xy 148.292312 -227.20427)
			(xy 148.393912 -227.240338) (xy 148.444712 -227.240338)
		)
		(stroke
			(width 0)
			(type solid)
		)
		(fill yes)
		(layer "F.Cu")
		(net "M_E_CPU1_SB_DQ<12>")
	)
	(gr_poly
		(pts
			(xy 148.454872 -267.696696) (xy 148.49094 -267.660882) (xy 148.305012 -267.474954) (xy 148.268944 -267.510768)
			(xy 148.222716 -267.608304) (xy 148.35759 -267.742924)
		)
		(stroke
			(width 0)
			(type solid)
		)
		(fill yes)
		(layer "F.Cu")
		(net "M_E_CPU1_SA_CB<4>")
	)
	(gr_poly
		(pts
			(xy 148.464016 -266.843256) (xy 148.500084 -266.807442) (xy 148.314156 -266.621514) (xy 148.278342 -266.657328)
			(xy 148.232114 -266.754864) (xy 148.366734 -266.889484)
		)
		(stroke
			(width 0)
			(type solid)
		)
		(fill yes)
		(layer "F.Cu")
		(net "M_E_CPU1_SA_CB<5>")
	)
	(gr_poly
		(pts
			(xy 148.46935 -273.013932) (xy 148.56206 -272.95856) (xy 148.524722 -272.77187) (xy 148.417788 -272.756376)
			(xy 148.368004 -272.766282) (xy 148.419566 -273.024092)
		)
		(stroke
			(width 0)
			(type solid)
		)
		(fill yes)
		(layer "F.Cu")
		(net "M_E_CPU1_SA_DQ<30>")
	)
	(gr_poly
		(pts
			(xy 148.474176 -270.592042) (xy 148.520404 -270.494506) (xy 148.38553 -270.359886) (xy 148.288248 -270.406114)
			(xy 148.25218 -270.441928) (xy 148.438108 -270.627856)
		)
		(stroke
			(width 0)
			(type solid)
		)
		(fill yes)
		(layer "F.Cu")
		(net "M_E_CPU1_SA_CB<2>")
	)
	(gr_poly
		(pts
			(xy 148.47824 -273.3167) (xy 148.426678 -273.05889) (xy 148.376894 -273.068796) (xy 148.284184 -273.124168)
			(xy 148.321776 -273.311112) (xy 148.428456 -273.326606)
		)
		(stroke
			(width 0)
			(type solid)
		)
		(fill yes)
		(layer "F.Cu")
		(net "M_E_CPU1_SA_DQ<30>")
	)
	(gr_poly
		(pts
			(xy 148.48332 -269.738602) (xy 148.529548 -269.641066) (xy 148.394928 -269.506446) (xy 148.297392 -269.552674)
			(xy 148.261578 -269.588742) (xy 148.447252 -269.774416)
		)
		(stroke
			(width 0)
			(type solid)
		)
		(fill yes)
		(layer "F.Cu")
		(net "M_E_CPU1_SA_CB<3>")
	)
	(gr_poly
		(pts
			(xy 148.494242 -231.992678) (xy 148.448014 -231.895396) (xy 148.4122 -231.859328) (xy 148.226272 -232.045256)
			(xy 148.262086 -232.08107) (xy 148.359622 -232.127298)
		)
		(stroke
			(width 0)
			(type solid)
		)
		(fill yes)
		(layer "F.Cu")
		(net "M_E_CPU1_SB_DQ<11>")
	)
	(gr_poly
		(pts
			(xy 148.504402 -232.84688) (xy 148.458174 -232.749344) (xy 148.422106 -232.71353) (xy 148.236178 -232.899458)
			(xy 148.272246 -232.935272) (xy 148.369528 -232.9815)
		)
		(stroke
			(width 0)
			(type solid)
		)
		(fill yes)
		(layer "F.Cu")
		(net "M_E_CPU1_SB_DQ<10>")
	)
	(gr_poly
		(pts
			(xy 148.507704 -272.246852) (xy 148.553932 -272.149316) (xy 148.419058 -272.014696) (xy 148.321776 -272.060924)
			(xy 148.285708 -272.096738) (xy 148.471636 -272.282666)
		)
		(stroke
			(width 0)
			(type solid)
		)
		(fill yes)
		(layer "F.Cu")
		(net "M_E_CPU1_SA_DQ<29>")
	)
	(gr_poly
		(pts
			(xy 148.521674 -274.829778) (xy 148.61413 -274.774406) (xy 148.576792 -274.587462) (xy 148.470112 -274.571968)
			(xy 148.420328 -274.581874) (xy 148.47189 -274.839684)
		)
		(stroke
			(width 0)
			(type solid)
		)
		(fill yes)
		(layer "F.Cu")
		(net "M_E_CPU1_SA_DQ<28>")
	)
	(gr_poly
		(pts
			(xy 148.53031 -275.132292) (xy 148.478748 -274.874736) (xy 148.428964 -274.884642) (xy 148.336508 -274.940014)
			(xy 148.373846 -275.126704) (xy 148.480526 -275.142452)
		)
		(stroke
			(width 0)
			(type solid)
		)
		(fill yes)
		(layer "F.Cu")
		(net "M_E_CPU1_SA_DQ<28>")
	)
	(gr_poly
		(pts
			(xy 148.531326 -267.198094) (xy 148.577554 -267.100812) (xy 148.442934 -266.965938) (xy 148.345398 -267.012166)
			(xy 148.309584 -267.048234) (xy 148.495512 -267.234162)
		)
		(stroke
			(width 0)
			(type solid)
		)
		(fill yes)
		(layer "F.Cu")
		(net "M_E_CPU1_SA_CB<6>")
	)
	(gr_poly
		(pts
			(xy 148.54047 -266.344908) (xy 148.586952 -266.247372) (xy 148.452078 -266.112752) (xy 148.354796 -266.15898)
			(xy 148.318728 -266.194794) (xy 148.504656 -266.380722)
		)
		(stroke
			(width 0)
			(type solid)
		)
		(fill yes)
		(layer "F.Cu")
		(net "M_E_CPU1_SA_CB<7>")
	)
	(gr_poly
		(pts
			(xy 148.586444 -273.599402) (xy 148.679154 -273.54403) (xy 148.641816 -273.357086) (xy 148.534882 -273.341592)
			(xy 148.485098 -273.351498) (xy 148.53666 -273.609308)
		)
		(stroke
			(width 0)
			(type solid)
		)
		(fill yes)
		(layer "F.Cu")
		(net "M_E_CPU1_SA_DQ<30>")
	)
	(gr_poly
		(pts
			(xy 148.595334 -273.901916) (xy 148.543772 -273.644106) (xy 148.493988 -273.654266) (xy 148.401278 -273.709638)
			(xy 148.43887 -273.896328) (xy 148.54555 -273.911822)
		)
		(stroke
			(width 0)
			(type solid)
		)
		(fill yes)
		(layer "F.Cu")
		(net "M_E_CPU1_SA_DQ<30>")
	)
	(gr_poly
		(pts
			(xy 148.597112 -229.293166) (xy 148.597112 -229.102666) (xy 148.495512 -229.066598) (xy 148.444712 -229.066598)
			(xy 148.444712 -229.329488) (xy 148.495512 -229.329488)
		)
		(stroke
			(width 0)
			(type solid)
		)
		(fill yes)
		(layer "F.Cu")
		(net "M_E_CPU1_SB_DQ<12>")
	)
	(gr_poly
		(pts
			(xy 148.597112 -228.696266) (xy 148.597112 -228.505766) (xy 148.495512 -228.469698) (xy 148.444712 -228.469698)
			(xy 148.444712 -228.732588) (xy 148.495512 -228.732588)
		)
		(stroke
			(width 0)
			(type solid)
		)
		(fill yes)
		(layer "F.Cu")
		(net "M_E_CPU1_SB_DQ<12>")
	)
	(gr_poly
		(pts
			(xy 148.597112 -228.099366) (xy 148.597112 -227.908866) (xy 148.495512 -227.872798) (xy 148.444712 -227.872798)
			(xy 148.444712 -228.135688) (xy 148.495512 -228.135688)
		)
		(stroke
			(width 0)
			(type solid)
		)
		(fill yes)
		(layer "F.Cu")
		(net "M_E_CPU1_SB_DQ<12>")
	)
	(gr_poly
		(pts
			(xy 148.597112 -227.502466) (xy 148.597112 -227.311966) (xy 148.495512 -227.275898) (xy 148.444712 -227.275898)
			(xy 148.444712 -227.538788) (xy 148.495512 -227.538788)
		)
		(stroke
			(width 0)
			(type solid)
		)
		(fill yes)
		(layer "F.Cu")
		(net "M_E_CPU1_SB_DQ<12>")
	)
	(gr_poly
		(pts
			(xy 148.613368 -270.874744) (xy 148.649182 -270.83893) (xy 148.463254 -270.653002) (xy 148.42744 -270.68907)
			(xy 148.381212 -270.786352) (xy 148.515832 -270.921226)
		)
		(stroke
			(width 0)
			(type solid)
		)
		(fill yes)
		(layer "F.Cu")
		(net "M_E_CPU1_SA_CB<2>")
	)
	(gr_poly
		(pts
			(xy 148.622512 -270.021558) (xy 148.658326 -269.98549) (xy 148.472398 -269.799562) (xy 148.436584 -269.83563)
			(xy 148.390356 -269.933166) (xy 148.524976 -270.067786)
		)
		(stroke
			(width 0)
			(type solid)
		)
		(fill yes)
		(layer "F.Cu")
		(net "M_E_CPU1_SA_CB<3>")
	)
	(gr_poly
		(pts
			(xy 148.623274 -231.648254) (xy 148.587206 -231.61244) (xy 148.489924 -231.566212) (xy 148.35505 -231.700832)
			(xy 148.401278 -231.798368) (xy 148.437346 -231.834182)
		)
		(stroke
			(width 0)
			(type solid)
		)
		(fill yes)
		(layer "F.Cu")
		(net "M_E_CPU1_SB_DQ<11>")
	)
	(gr_poly
		(pts
			(xy 148.63318 -232.502456) (xy 148.597366 -232.466388) (xy 148.49983 -232.42016) (xy 148.36521 -232.555034)
			(xy 148.411438 -232.652316) (xy 148.447252 -232.688384)
		)
		(stroke
			(width 0)
			(type solid)
		)
		(fill yes)
		(layer "F.Cu")
		(net "M_E_CPU1_SB_DQ<10>")
	)
	(gr_poly
		(pts
			(xy 148.638768 -275.414994) (xy 148.731224 -275.359622) (xy 148.693886 -275.172932) (xy 148.587206 -275.157438)
			(xy 148.537422 -275.167344) (xy 148.588984 -275.425154)
		)
		(stroke
			(width 0)
			(type solid)
		)
		(fill yes)
		(layer "F.Cu")
		(net "M_E_CPU1_SA_DQ<28>")
	)
	(gr_poly
		(pts
			(xy 148.647404 -275.717762) (xy 148.595842 -275.459952) (xy 148.546058 -275.469858) (xy 148.453602 -275.52523)
			(xy 148.49094 -275.712174) (xy 148.59762 -275.727668)
		)
		(stroke
			(width 0)
			(type solid)
		)
		(fill yes)
		(layer "F.Cu")
		(net "M_E_CPU1_SA_DQ<28>")
	)
	(gr_poly
		(pts
			(xy 148.670518 -267.48105) (xy 148.706586 -267.445236) (xy 148.520658 -267.259308) (xy 148.48459 -267.295122)
			(xy 148.438362 -267.392658) (xy 148.573236 -267.527278)
		)
		(stroke
			(width 0)
			(type solid)
		)
		(fill yes)
		(layer "F.Cu")
		(net "M_E_CPU1_SA_CB<6>")
	)
	(gr_poly
		(pts
			(xy 148.679662 -266.62761) (xy 148.71573 -266.591796) (xy 148.529802 -266.405868) (xy 148.493988 -266.441682)
			(xy 148.44776 -266.539218) (xy 148.58238 -266.673838)
		)
		(stroke
			(width 0)
			(type solid)
		)
		(fill yes)
		(layer "F.Cu")
		(net "M_E_CPU1_SA_CB<7>")
	)
	(gr_poly
		(pts
			(xy 148.680424 -271.229582) (xy 148.726652 -271.1323) (xy 148.592032 -270.99768) (xy 148.494496 -271.043908)
			(xy 148.458682 -271.079722) (xy 148.64461 -271.26565)
		)
		(stroke
			(width 0)
			(type solid)
		)
		(fill yes)
		(layer "F.Cu")
		(net "M_E_CPU1_SA_CB<0>")
	)
	(gr_poly
		(pts
			(xy 148.689822 -270.376396) (xy 148.73605 -270.27886) (xy 148.601176 -270.14424) (xy 148.503894 -270.190468)
			(xy 148.467826 -270.226282) (xy 148.653754 -270.41221)
		)
		(stroke
			(width 0)
			(type solid)
		)
		(fill yes)
		(layer "F.Cu")
		(net "M_E_CPU1_SA_CB<1>")
	)
	(gr_poly
		(pts
			(xy 148.703538 -274.184618) (xy 148.796248 -274.129246) (xy 148.75891 -273.942302) (xy 148.651976 -273.926808)
			(xy 148.602192 -273.936714) (xy 148.653754 -274.194524)
		)
		(stroke
			(width 0)
			(type solid)
		)
		(fill yes)
		(layer "F.Cu")
		(net "M_E_CPU1_SA_DQ<30>")
	)
	(gr_poly
		(pts
			(xy 148.710396 -232.208832) (xy 148.664168 -232.111296) (xy 148.628354 -232.075482) (xy 148.442426 -232.26141)
			(xy 148.47824 -232.297224) (xy 148.575776 -232.343452)
		)
		(stroke
			(width 0)
			(type solid)
		)
		(fill yes)
		(layer "F.Cu")
		(net "M_E_CPU1_SB_DQ<9>")
	)
	(gr_poly
		(pts
			(xy 148.712428 -274.487132) (xy 148.660866 -274.229576) (xy 148.611082 -274.239482) (xy 148.518372 -274.294854)
			(xy 148.555964 -274.481544) (xy 148.662644 -274.497292)
		)
		(stroke
			(width 0)
			(type solid)
		)
		(fill yes)
		(layer "F.Cu")
		(net "M_E_CPU1_SA_DQ<30>")
	)
	(gr_poly
		(pts
			(xy 148.720048 -233.062526) (xy 148.67382 -232.965244) (xy 148.638006 -232.929176) (xy 148.452078 -233.115104)
			(xy 148.487892 -233.151172) (xy 148.585428 -233.1974)
		)
		(stroke
			(width 0)
			(type solid)
		)
		(fill yes)
		(layer "F.Cu")
		(net "M_E_CPU1_SB_DQ<8>")
	)
	(gr_poly
		(pts
			(xy 148.72335 -272.030952) (xy 148.769578 -271.93367) (xy 148.634958 -271.798796) (xy 148.537422 -271.845024)
			(xy 148.501608 -271.881092) (xy 148.687536 -272.06702)
		)
		(stroke
			(width 0)
			(type solid)
		)
		(fill yes)
		(layer "F.Cu")
		(net "M_E_CPU1_SA_DQ<31>")
	)
	(gr_poly
		(pts
			(xy 148.737828 -267.835888) (xy 148.784056 -267.738352) (xy 148.649436 -267.603732) (xy 148.5519 -267.64996)
			(xy 148.516086 -267.686028) (xy 148.70176 -267.871702)
		)
		(stroke
			(width 0)
			(type solid)
		)
		(fill yes)
		(layer "F.Cu")
		(net "M_E_CPU1_SA_CB<4>")
	)
	(gr_poly
		(pts
			(xy 148.746972 -266.982448) (xy 148.7932 -266.885166) (xy 148.65858 -266.750292) (xy 148.561044 -266.79652)
			(xy 148.52523 -266.832588) (xy 148.711158 -267.018516)
		)
		(stroke
			(width 0)
			(type solid)
		)
		(fill yes)
		(layer "F.Cu")
		(net "M_E_CPU1_SA_CB<5>")
	)
	(gr_poly
		(pts
			(xy 148.755862 -276.000464) (xy 148.848318 -275.945092) (xy 148.81098 -275.758148) (xy 148.7043 -275.742654)
			(xy 148.654516 -275.75256) (xy 148.706078 -276.01037)
		)
		(stroke
			(width 0)
			(type solid)
		)
		(fill yes)
		(layer "F.Cu")
		(net "M_E_CPU1_SA_DQ<28>")
	)
	(gr_poly
		(pts
			(xy 148.764498 -276.302978) (xy 148.712936 -276.045168) (xy 148.663152 -276.055074) (xy 148.570696 -276.1107)
			(xy 148.608034 -276.29739) (xy 148.714714 -276.312884)
		)
		(stroke
			(width 0)
			(type solid)
		)
		(fill yes)
		(layer "F.Cu")
		(net "M_E_CPU1_SA_DQ<28>")
	)
	(gr_poly
		(pts
			(xy 148.768562 -272.954242) (xy 148.861018 -272.89887) (xy 148.82368 -272.711926) (xy 148.717 -272.696432)
			(xy 148.667216 -272.706338) (xy 148.718778 -272.964148)
		)
		(stroke
			(width 0)
			(type solid)
		)
		(fill yes)
		(layer "F.Cu")
		(net "M_E_CPU1_SA_DQ<29>")
	)
	(gr_poly
		(pts
			(xy 148.777198 -273.256756) (xy 148.725636 -272.998946) (xy 148.675852 -273.009106) (xy 148.583396 -273.064478)
			(xy 148.620734 -273.251168) (xy 148.727414 -273.266662)
		)
		(stroke
			(width 0)
			(type solid)
		)
		(fill yes)
		(layer "F.Cu")
		(net "M_E_CPU1_SA_DQ<29>")
	)
	(gr_poly
		(pts
			(xy 148.819616 -271.512538) (xy 148.855684 -271.476724) (xy 148.669756 -271.290796) (xy 148.633688 -271.32661)
			(xy 148.58746 -271.424146) (xy 148.722334 -271.558766)
		)
		(stroke
			(width 0)
			(type solid)
		)
		(fill yes)
		(layer "F.Cu")
		(net "M_E_CPU1_SA_CB<0>")
	)
	(gr_poly
		(pts
			(xy 148.820886 -274.769834) (xy 148.913342 -274.714462) (xy 148.876004 -274.527772) (xy 148.76907 -274.512278)
			(xy 148.719286 -274.522184) (xy 148.770848 -274.779994)
		)
		(stroke
			(width 0)
			(type solid)
		)
		(fill yes)
		(layer "F.Cu")
		(net "M_E_CPU1_SA_DQ<30>")
	)
	(gr_poly
		(pts
			(xy 148.829014 -270.659098) (xy 148.864828 -270.623284) (xy 148.6789 -270.437356) (xy 148.643086 -270.473424)
			(xy 148.596858 -270.570706) (xy 148.731478 -270.70558)
		)
		(stroke
			(width 0)
			(type solid)
		)
		(fill yes)
		(layer "F.Cu")
		(net "M_E_CPU1_SA_CB<1>")
	)
	(gr_poly
		(pts
			(xy 148.829522 -275.072602) (xy 148.77796 -274.814792) (xy 148.728176 -274.824698) (xy 148.63572 -274.88007)
			(xy 148.673058 -275.067014) (xy 148.779738 -275.082508)
		)
		(stroke
			(width 0)
			(type solid)
		)
		(fill yes)
		(layer "F.Cu")
		(net "M_E_CPU1_SA_DQ<30>")
	)
	(gr_poly
		(pts
			(xy 148.839428 -231.864408) (xy 148.80336 -231.828594) (xy 148.706078 -231.782366) (xy 148.571204 -231.916986)
			(xy 148.617432 -232.014522) (xy 148.6535 -232.050336)
		)
		(stroke
			(width 0)
			(type solid)
		)
		(fill yes)
		(layer "F.Cu")
		(net "M_E_CPU1_SB_DQ<9>")
	)
	(gr_poly
		(pts
			(xy 148.84908 -232.718102) (xy 148.813012 -232.682288) (xy 148.71573 -232.63606) (xy 148.580856 -232.77068)
			(xy 148.627084 -232.868216) (xy 148.663152 -232.90403)
		)
		(stroke
			(width 0)
			(type solid)
		)
		(fill yes)
		(layer "F.Cu")
		(net "M_E_CPU1_SB_DQ<8>")
	)
	(gr_poly
		(pts
			(xy 148.872956 -276.58568) (xy 148.965412 -276.530308) (xy 148.928074 -276.343364) (xy 148.821394 -276.32787)
			(xy 148.77161 -276.337776) (xy 148.823172 -276.595586)
		)
		(stroke
			(width 0)
			(type solid)
		)
		(fill yes)
		(layer "F.Cu")
		(net "M_E_CPU1_SA_DQ<28>")
	)
	(gr_poly
		(pts
			(xy 148.87702 -268.118844) (xy 148.912834 -268.082776) (xy 148.726906 -267.896848) (xy 148.691092 -267.932916)
			(xy 148.644864 -268.030198) (xy 148.779484 -268.165072)
		)
		(stroke
			(width 0)
			(type solid)
		)
		(fill yes)
		(layer "F.Cu")
		(net "M_E_CPU1_SA_CB<4>")
	)
	(gr_poly
		(pts
			(xy 148.881846 -276.888194) (xy 148.830284 -276.630638) (xy 148.780246 -276.640544) (xy 148.68779 -276.695916)
			(xy 148.725128 -276.882606) (xy 148.831808 -276.898354)
		)
		(stroke
			(width 0)
			(type solid)
		)
		(fill yes)
		(layer "F.Cu")
		(net "M_E_CPU1_SA_DQ<28>")
	)
	(gr_poly
		(pts
			(xy 148.885656 -273.539458) (xy 148.978112 -273.484086) (xy 148.940774 -273.297396) (xy 148.834094 -273.281648)
			(xy 148.78431 -273.291554) (xy 148.835872 -273.549364)
		)
		(stroke
			(width 0)
			(type solid)
		)
		(fill yes)
		(layer "F.Cu")
		(net "M_E_CPU1_SA_DQ<29>")
	)
	(gr_poly
		(pts
			(xy 148.886164 -267.265404) (xy 148.922232 -267.22959) (xy 148.736304 -267.043662) (xy 148.700236 -267.079476)
			(xy 148.654008 -267.177012) (xy 148.788882 -267.311632)
		)
		(stroke
			(width 0)
			(type solid)
		)
		(fill yes)
		(layer "F.Cu")
		(net "M_E_CPU1_SA_CB<5>")
	)
	(gr_poly
		(pts
			(xy 148.894292 -273.842226) (xy 148.84273 -273.584416) (xy 148.792946 -273.594322) (xy 148.70049 -273.649694)
			(xy 148.737828 -273.836638) (xy 148.844508 -273.852132)
		)
		(stroke
			(width 0)
			(type solid)
		)
		(fill yes)
		(layer "F.Cu")
		(net "M_E_CPU1_SA_DQ<29>")
	)
	(gr_poly
		(pts
			(xy 148.905468 -270.16075) (xy 148.951696 -270.063214) (xy 148.816822 -269.928594) (xy 148.71954 -269.974822)
			(xy 148.683472 -270.010636) (xy 148.8694 -270.196564)
		)
		(stroke
			(width 0)
			(type solid)
		)
		(fill yes)
		(layer "F.Cu")
		(net "M_E_CPU1_SA_CB<3>")
	)
	(gr_poly
		(pts
			(xy 148.91639 -231.57053) (xy 148.870162 -231.473248) (xy 148.834348 -231.43718) (xy 148.64842 -231.623108)
			(xy 148.684234 -231.659176) (xy 148.78177 -231.705404)
		)
		(stroke
			(width 0)
			(type solid)
		)
		(fill yes)
		(layer "F.Cu")
		(net "M_E_CPU1_SB_DQ<11>")
	)
	(gr_poly
		(pts
			(xy 148.926296 -232.424732) (xy 148.880068 -232.327196) (xy 148.844254 -232.291382) (xy 148.658326 -232.47731)
			(xy 148.69414 -232.513124) (xy 148.791676 -232.559352)
		)
		(stroke
			(width 0)
			(type solid)
		)
		(fill yes)
		(layer "F.Cu")
		(net "M_E_CPU1_SB_DQ<10>")
	)
	(gr_poly
		(pts
			(xy 148.93798 -275.355304) (xy 149.030436 -275.299932) (xy 148.993098 -275.112988) (xy 148.886418 -275.097494)
			(xy 148.83638 -275.1074) (xy 148.887942 -275.36521)
		)
		(stroke
			(width 0)
			(type solid)
		)
		(fill yes)
		(layer "F.Cu")
		(net "M_E_CPU1_SA_DQ<30>")
	)
	(gr_poly
		(pts
			(xy 148.946616 -275.657818) (xy 148.895054 -275.400008) (xy 148.84527 -275.409914) (xy 148.752814 -275.46554)
			(xy 148.790152 -275.65223) (xy 148.896832 -275.667724)
		)
		(stroke
			(width 0)
			(type solid)
		)
		(fill yes)
		(layer "F.Cu")
		(net "M_E_CPU1_SA_DQ<30>")
	)
	(gr_poly
		(pts
			(xy 148.953474 -267.620242) (xy 148.999702 -267.522706) (xy 148.865082 -267.388086) (xy 148.767546 -267.434314)
			(xy 148.731732 -267.470382) (xy 148.917406 -267.656056)
		)
		(stroke
			(width 0)
			(type solid)
		)
		(fill yes)
		(layer "F.Cu")
		(net "M_E_CPU1_SA_CB<6>")
	)
	(gr_poly
		(pts
			(xy 148.962618 -266.766802) (xy 149.008846 -266.66952) (xy 148.874226 -266.534646) (xy 148.77669 -266.580874)
			(xy 148.740876 -266.616942) (xy 148.926804 -266.80287)
		)
		(stroke
			(width 0)
			(type solid)
		)
		(fill yes)
		(layer "F.Cu")
		(net "M_E_CPU1_SA_CB<7>")
	)
	(gr_poly
		(pts
			(xy 148.99005 -277.170896) (xy 149.08276 -277.115524) (xy 149.045168 -276.928834) (xy 148.938488 -276.913086)
			(xy 148.888704 -276.923246) (xy 148.940266 -277.181056)
		)
		(stroke
			(width 0)
			(type solid)
		)
		(fill yes)
		(layer "F.Cu")
		(net "M_E_CPU1_SA_DQ<28>")
	)
	(gr_poly
		(pts
			(xy 148.99894 -277.473664) (xy 148.947378 -277.215854) (xy 148.897594 -277.22576) (xy 148.804884 -277.281132)
			(xy 148.842222 -277.468076) (xy 148.949156 -277.48357)
		)
		(stroke
			(width 0)
			(type solid)
		)
		(fill yes)
		(layer "F.Cu")
		(net "M_E_CPU1_SA_DQ<28>")
	)
	(gr_poly
		(pts
			(xy 149.00275 -274.124928) (xy 149.095206 -274.069302) (xy 149.057868 -273.882612) (xy 148.951188 -273.867118)
			(xy 148.901404 -273.877024) (xy 148.952966 -274.134834)
		)
		(stroke
			(width 0)
			(type solid)
		)
		(fill yes)
		(layer "F.Cu")
		(net "M_E_CPU1_SA_DQ<29>")
	)
	(gr_poly
		(pts
			(xy 149.011386 -274.427442) (xy 148.959824 -274.169632) (xy 148.91004 -274.179538) (xy 148.817584 -274.23491)
			(xy 148.854922 -274.421854) (xy 148.961602 -274.437348)
		)
		(stroke
			(width 0)
			(type solid)
		)
		(fill yes)
		(layer "F.Cu")
		(net "M_E_CPU1_SA_DQ<29>")
	)
	(gr_poly
		(pts
			(xy 149.04466 -270.443452) (xy 149.080474 -270.407638) (xy 148.894546 -270.22171) (xy 148.858732 -270.257778)
			(xy 148.812504 -270.35506) (xy 148.947124 -270.489934)
		)
		(stroke
			(width 0)
			(type solid)
		)
		(fill yes)
		(layer "F.Cu")
		(net "M_E_CPU1_SA_CB<3>")
	)
	(gr_poly
		(pts
			(xy 149.045422 -231.22636) (xy 149.009354 -231.190292) (xy 148.912072 -231.144064) (xy 148.777198 -231.278684)
			(xy 148.823426 -231.37622) (xy 148.859494 -231.412034)
		)
		(stroke
			(width 0)
			(type solid)
		)
		(fill yes)
		(layer "F.Cu")
		(net "M_E_CPU1_SB_DQ<11>")
	)
	(gr_poly
		(pts
			(xy 149.055074 -275.94052) (xy 149.14753 -275.885148) (xy 149.110192 -275.698204) (xy 149.003512 -275.68271)
			(xy 148.953474 -275.692616) (xy 149.00529 -275.950426)
		)
		(stroke
			(width 0)
			(type solid)
		)
		(fill yes)
		(layer "F.Cu")
		(net "M_E_CPU1_SA_DQ<30>")
	)
	(gr_poly
		(pts
			(xy 149.055328 -232.080308) (xy 149.01926 -232.044494) (xy 148.921978 -231.998266) (xy 148.787104 -232.132886)
			(xy 148.833586 -232.230422) (xy 148.8694 -232.266236)
		)
		(stroke
			(width 0)
			(type solid)
		)
		(fill yes)
		(layer "F.Cu")
		(net "M_E_CPU1_SB_DQ<10>")
	)
	(gr_poly
		(pts
			(xy 149.06371 -276.243034) (xy 149.012148 -275.985478) (xy 148.962364 -275.995384) (xy 148.869908 -276.050756)
			(xy 148.907246 -276.237446) (xy 149.013926 -276.253194)
		)
		(stroke
			(width 0)
			(type solid)
		)
		(fill yes)
		(layer "F.Cu")
		(net "M_E_CPU1_SA_DQ<30>")
	)
	(gr_poly
		(pts
			(xy 149.067774 -272.894298) (xy 149.16023 -272.838926) (xy 149.122892 -272.651982) (xy 149.016212 -272.636488)
			(xy 148.966428 -272.646394) (xy 149.01799 -272.904204)
		)
		(stroke
			(width 0)
			(type solid)
		)
		(fill yes)
		(layer "F.Cu")
		(net "M_E_CPU1_SA_DQ<31>")
	)
	(gr_poly
		(pts
			(xy 149.07641 -273.196812) (xy 149.024848 -272.939256) (xy 148.975064 -272.949162) (xy 148.882608 -273.004534)
			(xy 148.919946 -273.191224) (xy 149.026626 -273.206972)
		)
		(stroke
			(width 0)
			(type solid)
		)
		(fill yes)
		(layer "F.Cu")
		(net "M_E_CPU1_SA_DQ<31>")
	)
	(gr_poly
		(pts
			(xy 149.092666 -267.903198) (xy 149.12848 -267.86713) (xy 148.942552 -267.681202) (xy 148.906738 -267.71727)
			(xy 148.86051 -267.814552) (xy 148.99513 -267.949426)
		)
		(stroke
			(width 0)
			(type solid)
		)
		(fill yes)
		(layer "F.Cu")
		(net "M_E_CPU1_SA_CB<6>")
	)
	(gr_poly
		(pts
			(xy 149.10181 -267.049758) (xy 149.137878 -267.013944) (xy 148.95195 -266.828016) (xy 148.915882 -266.86383)
			(xy 148.869654 -266.961366) (xy 149.004528 -267.095986)
		)
		(stroke
			(width 0)
			(type solid)
		)
		(fill yes)
		(layer "F.Cu")
		(net "M_E_CPU1_SA_CB<7>")
	)
	(gr_poly
		(pts
			(xy 149.119844 -274.710144) (xy 149.2123 -274.654772) (xy 149.174962 -274.467828) (xy 149.068282 -274.452334)
			(xy 149.018498 -274.46224) (xy 149.07006 -274.72005)
		)
		(stroke
			(width 0)
			(type solid)
		)
		(fill yes)
		(layer "F.Cu")
		(net "M_E_CPU1_SA_DQ<29>")
	)
	(gr_poly
		(pts
			(xy 149.12848 -275.012658) (xy 149.076918 -274.754848) (xy 149.027134 -274.765008) (xy 148.934678 -274.82038)
			(xy 148.972016 -275.00707) (xy 149.078696 -275.022564)
		)
		(stroke
			(width 0)
			(type solid)
		)
		(fill yes)
		(layer "F.Cu")
		(net "M_E_CPU1_SA_DQ<29>")
	)
	(gr_poly
		(pts
			(xy 149.132544 -231.786684) (xy 149.086316 -231.689402) (xy 149.050502 -231.653334) (xy 148.864574 -231.839262)
			(xy 148.900388 -231.87533) (xy 148.997924 -231.921558)
		)
		(stroke
			(width 0)
			(type solid)
		)
		(fill yes)
		(layer "F.Cu")
		(net "M_E_CPU1_SB_DQ<9>")
	)
	(gr_poly
		(pts
			(xy 149.142196 -232.640632) (xy 149.095968 -232.543096) (xy 149.0599 -232.507282) (xy 148.874226 -232.692956)
			(xy 148.91004 -232.729024) (xy 149.007576 -232.775252)
		)
		(stroke
			(width 0)
			(type solid)
		)
		(fill yes)
		(layer "F.Cu")
		(net "M_E_CPU1_SB_DQ<8>")
	)
	(gr_poly
		(pts
			(xy 149.159976 -268.258036) (xy 149.206204 -268.1605) (xy 149.07133 -268.02588) (xy 148.974048 -268.072108)
			(xy 148.93798 -268.107922) (xy 149.123908 -268.29385)
		)
		(stroke
			(width 0)
			(type solid)
		)
		(fill yes)
		(layer "F.Cu")
		(net "M_E_CPU1_SA_CB<4>")
	)
	(gr_poly
		(pts
			(xy 149.16912 -267.404596) (xy 149.215348 -267.30706) (xy 149.080728 -267.17244) (xy 148.983192 -267.218668)
			(xy 148.947378 -267.254736) (xy 149.133052 -267.44041)
		)
		(stroke
			(width 0)
			(type solid)
		)
		(fill yes)
		(layer "F.Cu")
		(net "M_E_CPU1_SA_CB<5>")
	)
	(gr_poly
		(pts
			(xy 149.172168 -276.525736) (xy 149.264624 -276.470364) (xy 149.227286 -276.283674) (xy 149.120606 -276.26818)
			(xy 149.070822 -276.278086) (xy 149.122384 -276.535896)
		)
		(stroke
			(width 0)
			(type solid)
		)
		(fill yes)
		(layer "F.Cu")
		(net "M_E_CPU1_SA_DQ<30>")
	)
	(gr_poly
		(pts
			(xy 149.180804 -276.828504) (xy 149.129242 -276.570694) (xy 149.079458 -276.5806) (xy 148.987002 -276.635972)
			(xy 149.02434 -276.822916) (xy 149.13102 -276.83841)
		)
		(stroke
			(width 0)
			(type solid)
		)
		(fill yes)
		(layer "F.Cu")
		(net "M_E_CPU1_SA_DQ<30>")
	)
	(gr_poly
		(pts
			(xy 149.184868 -273.479514) (xy 149.277324 -273.424142) (xy 149.239986 -273.237452) (xy 149.133306 -273.221958)
			(xy 149.083522 -273.231864) (xy 149.135084 -273.489674)
		)
		(stroke
			(width 0)
			(type solid)
		)
		(fill yes)
		(layer "F.Cu")
		(net "M_E_CPU1_SA_DQ<31>")
	)
	(gr_poly
		(pts
			(xy 149.193504 -273.782282) (xy 149.141942 -273.524472) (xy 149.092158 -273.534378) (xy 148.999702 -273.58975)
			(xy 149.03704 -273.776694) (xy 149.14372 -273.792188)
		)
		(stroke
			(width 0)
			(type solid)
		)
		(fill yes)
		(layer "F.Cu")
		(net "M_E_CPU1_SA_DQ<31>")
	)
	(gr_poly
		(pts
			(xy 149.236938 -275.29536) (xy 149.329394 -275.239988) (xy 149.292056 -275.053298) (xy 149.185376 -275.03755)
			(xy 149.135592 -275.04771) (xy 149.187154 -275.305266)
		)
		(stroke
			(width 0)
			(type solid)
		)
		(fill yes)
		(layer "F.Cu")
		(net "M_E_CPU1_SA_DQ<29>")
	)
	(gr_poly
		(pts
			(xy 149.245574 -275.598128) (xy 149.194012 -275.340318) (xy 149.144228 -275.350224) (xy 149.051772 -275.405596)
			(xy 149.08911 -275.59254) (xy 149.19579 -275.608034)
		)
		(stroke
			(width 0)
			(type solid)
		)
		(fill yes)
		(layer "F.Cu")
		(net "M_E_CPU1_SA_DQ<29>")
	)
	(gr_poly
		(pts
			(xy 149.261576 -231.442514) (xy 149.225508 -231.406446) (xy 149.128226 -231.360218) (xy 148.993352 -231.494838)
			(xy 149.03958 -231.592374) (xy 149.075648 -231.628188)
		)
		(stroke
			(width 0)
			(type solid)
		)
		(fill yes)
		(layer "F.Cu")
		(net "M_E_CPU1_SB_DQ<9>")
	)
	(gr_poly
		(pts
			(xy 149.270974 -232.296208) (xy 149.23516 -232.26014) (xy 149.137624 -232.213912) (xy 149.003004 -232.348786)
			(xy 149.049232 -232.446068) (xy 149.085046 -232.482136)
		)
		(stroke
			(width 0)
			(type solid)
		)
		(fill yes)
		(layer "F.Cu")
		(net "M_E_CPU1_SB_DQ<8>")
	)
	(gr_poly
		(pts
			(xy 149.289262 -277.111206) (xy 149.381718 -277.055834) (xy 149.34438 -276.86889) (xy 149.2377 -276.853396)
			(xy 149.187916 -276.863302) (xy 149.239478 -277.121112)
		)
		(stroke
			(width 0)
			(type solid)
		)
		(fill yes)
		(layer "F.Cu")
		(net "M_E_CPU1_SA_DQ<30>")
	)
	(gr_poly
		(pts
			(xy 149.299168 -268.540738) (xy 149.334982 -268.504924) (xy 149.149054 -268.318996) (xy 149.11324 -268.355064)
			(xy 149.067012 -268.452346) (xy 149.201632 -268.586966)
		)
		(stroke
			(width 0)
			(type solid)
		)
		(fill yes)
		(layer "F.Cu")
		(net "M_E_CPU1_SA_CB<4>")
	)
	(gr_poly
		(pts
			(xy 149.301962 -274.064984) (xy 149.394418 -274.009612) (xy 149.35708 -273.822668) (xy 149.2504 -273.807174)
			(xy 149.200362 -273.81708) (xy 149.252178 -274.07489)
		)
		(stroke
			(width 0)
			(type solid)
		)
		(fill yes)
		(layer "F.Cu")
		(net "M_E_CPU1_SA_DQ<31>")
	)
	(gr_poly
		(pts
			(xy 149.308312 -267.687552) (xy 149.344126 -267.651484) (xy 149.158198 -267.465556) (xy 149.122384 -267.501624)
			(xy 149.076156 -267.598906) (xy 149.210776 -267.73378)
		)
		(stroke
			(width 0)
			(type solid)
		)
		(fill yes)
		(layer "F.Cu")
		(net "M_E_CPU1_SA_CB<5>")
	)
	(gr_poly
		(pts
			(xy 149.310598 -274.367498) (xy 149.259036 -274.109688) (xy 149.209252 -274.119848) (xy 149.116796 -274.17522)
			(xy 149.154134 -274.36191) (xy 149.260814 -274.377404)
		)
		(stroke
			(width 0)
			(type solid)
		)
		(fill yes)
		(layer "F.Cu")
		(net "M_E_CPU1_SA_DQ<31>")
	)
	(gr_poly
		(pts
			(xy 149.338538 -231.148636) (xy 149.29231 -231.0511) (xy 149.256242 -231.015286) (xy 149.070314 -231.20096)
			(xy 149.106382 -231.237028) (xy 149.203664 -231.283256)
		)
		(stroke
			(width 0)
			(type solid)
		)
		(fill yes)
		(layer "F.Cu")
		(net "M_E_CPU1_SB_DQ<11>")
	)
	(gr_poly
		(pts
			(xy 149.348444 -232.002584) (xy 149.302216 -231.905302) (xy 149.266402 -231.869234) (xy 149.080474 -232.055162)
			(xy 149.116288 -232.09123) (xy 149.213824 -232.137458)
		)
		(stroke
			(width 0)
			(type solid)
		)
		(fill yes)
		(layer "F.Cu")
		(net "M_E_CPU1_SB_DQ<10>")
	)
	(gr_poly
		(pts
			(xy 149.354032 -275.88083) (xy 149.446488 -275.825204) (xy 149.40915 -275.638514) (xy 149.30247 -275.62302)
			(xy 149.252686 -275.632926) (xy 149.304248 -275.890736)
		)
		(stroke
			(width 0)
			(type solid)
		)
		(fill yes)
		(layer "F.Cu")
		(net "M_E_CPU1_SA_DQ<29>")
	)
	(gr_poly
		(pts
			(xy 149.362668 -276.183344) (xy 149.311106 -275.925534) (xy 149.261322 -275.93544) (xy 149.168866 -275.990812)
			(xy 149.206204 -276.177756) (xy 149.312884 -276.19325)
		)
		(stroke
			(width 0)
			(type solid)
		)
		(fill yes)
		(layer "F.Cu")
		(net "M_E_CPU1_SA_DQ<29>")
	)
	(gr_poly
		(pts
			(xy 149.375622 -268.04239) (xy 149.42185 -267.944854) (xy 149.286976 -267.810234) (xy 149.189694 -267.856462)
			(xy 149.153626 -267.892276) (xy 149.339554 -268.078204)
		)
		(stroke
			(width 0)
			(type solid)
		)
		(fill yes)
		(layer "F.Cu")
		(net "M_E_CPU1_SA_CB<6>")
	)
	(gr_poly
		(pts
			(xy 149.384766 -267.18895) (xy 149.430994 -267.091414) (xy 149.296374 -266.956794) (xy 149.198838 -267.003022)
			(xy 149.163024 -267.03909) (xy 149.348698 -267.224764)
		)
		(stroke
			(width 0)
			(type solid)
		)
		(fill yes)
		(layer "F.Cu")
		(net "M_E_CPU1_SA_CB<7>")
	)
	(gr_poly
		(pts
			(xy 149.418802 -274.6502) (xy 149.511512 -274.594828) (xy 149.474174 -274.408138) (xy 149.36724 -274.39239)
			(xy 149.317456 -274.402296) (xy 149.369018 -274.660106)
		)
		(stroke
			(width 0)
			(type solid)
		)
		(fill yes)
		(layer "F.Cu")
		(net "M_E_CPU1_SA_DQ<31>")
	)
	(gr_poly
		(pts
			(xy 149.427692 -274.952968) (xy 149.37613 -274.695158) (xy 149.326346 -274.705064) (xy 149.233636 -274.760436)
			(xy 149.270974 -274.94738) (xy 149.377908 -274.962874)
		)
		(stroke
			(width 0)
			(type solid)
		)
		(fill yes)
		(layer "F.Cu")
		(net "M_E_CPU1_SA_DQ<31>")
	)
	(gr_poly
		(pts
			(xy 149.467316 -230.804212) (xy 149.431502 -230.768144) (xy 149.333966 -230.721916) (xy 149.199346 -230.85679)
			(xy 149.245574 -230.954072) (xy 149.281388 -230.99014)
		)
		(stroke
			(width 0)
			(type solid)
		)
		(fill yes)
		(layer "F.Cu")
		(net "M_E_CPU1_SB_DQ<11>")
	)
	(gr_poly
		(pts
			(xy 149.471126 -276.466046) (xy 149.563582 -276.410674) (xy 149.526244 -276.22373) (xy 149.419564 -276.208236)
			(xy 149.36978 -276.218142) (xy 149.421342 -276.475952)
		)
		(stroke
			(width 0)
			(type solid)
		)
		(fill yes)
		(layer "F.Cu")
		(net "M_E_CPU1_SA_DQ<29>")
	)
	(gr_poly
		(pts
			(xy 149.477222 -231.658414) (xy 149.441408 -231.622346) (xy 149.343872 -231.576118) (xy 149.209252 -231.710738)
			(xy 149.25548 -231.808274) (xy 149.291548 -231.844088)
		)
		(stroke
			(width 0)
			(type solid)
		)
		(fill yes)
		(layer "F.Cu")
		(net "M_E_CPU1_SB_DQ<10>")
	)
	(gr_poly
		(pts
			(xy 149.479762 -276.76856) (xy 149.4282 -276.51075) (xy 149.378416 -276.52091) (xy 149.28596 -276.576282)
			(xy 149.323298 -276.762972) (xy 149.429978 -276.778466)
		)
		(stroke
			(width 0)
			(type solid)
		)
		(fill yes)
		(layer "F.Cu")
		(net "M_E_CPU1_SA_DQ<29>")
	)
	(gr_poly
		(pts
			(xy 149.514814 -268.325092) (xy 149.550628 -268.289278) (xy 149.3647 -268.10335) (xy 149.328886 -268.139418)
			(xy 149.282658 -268.2367) (xy 149.417278 -268.37132)
		)
		(stroke
			(width 0)
			(type solid)
		)
		(fill yes)
		(layer "F.Cu")
		(net "M_E_CPU1_SA_CB<6>")
	)
	(gr_poly
		(pts
			(xy 149.523958 -267.471906) (xy 149.559772 -267.435838) (xy 149.373844 -267.24991) (xy 149.33803 -267.285978)
			(xy 149.291802 -267.38326) (xy 149.426422 -267.518134)
		)
		(stroke
			(width 0)
			(type solid)
		)
		(fill yes)
		(layer "F.Cu")
		(net "M_E_CPU1_SA_CB<7>")
	)
	(gr_poly
		(pts
			(xy 149.535896 -275.23567) (xy 149.628606 -275.180044) (xy 149.591014 -274.993354) (xy 149.484334 -274.97786)
			(xy 149.43455 -274.987766) (xy 149.486112 -275.245576)
		)
		(stroke
			(width 0)
			(type solid)
		)
		(fill yes)
		(layer "F.Cu")
		(net "M_E_CPU1_SA_DQ<31>")
	)
	(gr_poly
		(pts
			(xy 149.544786 -275.538184) (xy 149.493224 -275.280374) (xy 149.443186 -275.29028) (xy 149.35073 -275.345652)
			(xy 149.388068 -275.532596) (xy 149.494748 -275.54809)
		)
		(stroke
			(width 0)
			(type solid)
		)
		(fill yes)
		(layer "F.Cu")
		(net "M_E_CPU1_SA_DQ<31>")
	)
	(gr_poly
		(pts
			(xy 149.554692 -231.36479) (xy 149.508464 -231.267254) (xy 149.47265 -231.23144) (xy 149.286722 -231.417368)
			(xy 149.322536 -231.453182) (xy 149.420072 -231.49941)
		)
		(stroke
			(width 0)
			(type solid)
		)
		(fill yes)
		(layer "F.Cu")
		(net "M_E_CPU1_SB_DQ<9>")
	)
	(gr_poly
		(pts
			(xy 149.564344 -232.218484) (xy 149.518116 -232.120948) (xy 149.482048 -232.085134) (xy 149.29612 -232.271062)
			(xy 149.332188 -232.306876) (xy 149.42947 -232.353104)
		)
		(stroke
			(width 0)
			(type solid)
		)
		(fill yes)
		(layer "F.Cu")
		(net "M_E_CPU1_SB_DQ<8>")
	)
	(gr_poly
		(pts
			(xy 149.591268 -267.826744) (xy 149.637496 -267.729208) (xy 149.502622 -267.594588) (xy 149.40534 -267.640816)
			(xy 149.369272 -267.67663) (xy 149.5552 -267.862558)
		)
		(stroke
			(width 0)
			(type solid)
		)
		(fill yes)
		(layer "F.Cu")
		(net "M_E_CPU1_SA_CB<5>")
	)
	(gr_poly
		(pts
			(xy 149.65299 -275.820886) (xy 149.745446 -275.765514) (xy 149.708108 -275.57857) (xy 149.601428 -275.563076)
			(xy 149.551644 -275.572982) (xy 149.603206 -275.830792)
		)
		(stroke
			(width 0)
			(type solid)
		)
		(fill yes)
		(layer "F.Cu")
		(net "M_E_CPU1_SA_DQ<31>")
	)
	(gr_poly
		(pts
			(xy 149.661626 -276.1234) (xy 149.610064 -275.86559) (xy 149.56028 -275.87575) (xy 149.467824 -275.931122)
			(xy 149.505162 -276.117812) (xy 149.611842 -276.13356)
		)
		(stroke
			(width 0)
			(type solid)
		)
		(fill yes)
		(layer "F.Cu")
		(net "M_E_CPU1_SA_DQ<31>")
	)
	(gr_poly
		(pts
			(xy 149.68347 -231.020366) (xy 149.647656 -230.984552) (xy 149.55012 -230.938324) (xy 149.4155 -231.072944)
			(xy 149.461728 -231.170226) (xy 149.497796 -231.206294)
		)
		(stroke
			(width 0)
			(type solid)
		)
		(fill yes)
		(layer "F.Cu")
		(net "M_E_CPU1_SB_DQ<9>")
	)
	(gr_poly
		(pts
			(xy 149.73046 -268.109446) (xy 149.766274 -268.073632) (xy 149.580346 -267.887704) (xy 149.544532 -267.923772)
			(xy 149.498304 -268.021054) (xy 149.632924 -268.155674)
		)
		(stroke
			(width 0)
			(type solid)
		)
		(fill yes)
		(layer "F.Cu")
		(net "M_E_CPU1_SA_CB<5>")
	)
	(gr_poly
		(pts
			(xy 149.760686 -230.726488) (xy 149.714204 -230.628952) (xy 149.67839 -230.593138) (xy 149.492462 -230.779066)
			(xy 149.52853 -230.81488) (xy 149.625812 -230.861108)
		)
		(stroke
			(width 0)
			(type solid)
		)
		(fill yes)
		(layer "F.Cu")
		(net "M_E_CPU1_SB_DQ<11>")
	)
	(gr_poly
		(pts
			(xy 149.770084 -276.406102) (xy 149.86254 -276.35073) (xy 149.825202 -276.16404) (xy 149.718522 -276.148292)
			(xy 149.668738 -276.158452) (xy 149.7203 -276.416008)
		)
		(stroke
			(width 0)
			(type solid)
		)
		(fill yes)
		(layer "F.Cu")
		(net "M_E_CPU1_SA_DQ<31>")
	)
	(gr_poly
		(pts
			(xy 149.77872 -276.70887) (xy 149.727158 -276.45106) (xy 149.677374 -276.460966) (xy 149.584918 -276.516338)
			(xy 149.622256 -276.703282) (xy 149.728936 -276.718776)
		)
		(stroke
			(width 0)
			(type solid)
		)
		(fill yes)
		(layer "F.Cu")
		(net "M_E_CPU1_SA_DQ<31>")
	)
	(gr_poly
		(pts
			(xy 149.89937 -231.236266) (xy 149.863556 -231.200198) (xy 149.76602 -231.15397) (xy 149.6314 -231.288844)
			(xy 149.677628 -231.386126) (xy 149.713442 -231.422194)
		)
		(stroke
			(width 0)
			(type solid)
		)
		(fill yes)
		(layer "F.Cu")
		(net "M_E_CPU1_SB_DQ<10>")
	)
	(gr_poly
		(pts
			(xy 149.97684 -230.942642) (xy 149.930612 -230.84536) (xy 149.894544 -230.809292) (xy 149.70887 -230.99522)
			(xy 149.744684 -231.031288) (xy 149.84222 -231.077516)
		)
		(stroke
			(width 0)
			(type solid)
		)
		(fill yes)
		(layer "F.Cu")
		(net "M_E_CPU1_SB_DQ<9>")
	)
	(gr_poly
		(pts
			(xy 150.105618 -230.598472) (xy 150.069804 -230.562404) (xy 149.972268 -230.516176) (xy 149.837648 -230.650796)
			(xy 149.883876 -230.748332) (xy 149.91969 -230.784146)
		)
		(stroke
			(width 0)
			(type solid)
		)
		(fill yes)
		(layer "F.Cu")
		(net "M_E_CPU1_SB_DQ<9>")
	)
	(gr_poly
		(pts
			(xy 322.173346 -277.773384) (xy 322.123562 -277.763478) (xy 322.016628 -277.778972) (xy 321.979544 -277.965916)
			(xy 322.072254 -278.021288) (xy 322.122038 -278.031194)
		)
		(stroke
			(width 0)
			(type solid)
		)
		(fill yes)
		(layer "F.Cu")
		(net "M_A_CPU0_SA_DQ<31>")
	)
	(gr_poly
		(pts
			(xy 322.289678 -277.187914) (xy 322.239894 -277.178008) (xy 322.133214 -277.193502) (xy 322.09613 -277.380446)
			(xy 322.188586 -277.435818) (xy 322.23837 -277.445724)
		)
		(stroke
			(width 0)
			(type solid)
		)
		(fill yes)
		(layer "F.Cu")
		(net "M_A_CPU0_SA_DQ<31>")
	)
	(gr_poly
		(pts
			(xy 322.336668 -277.732744) (xy 322.374006 -277.5458) (xy 322.281296 -277.490428) (xy 322.231512 -277.480522)
			(xy 322.180204 -277.738332) (xy 322.229988 -277.748238)
		)
		(stroke
			(width 0)
			(type solid)
		)
		(fill yes)
		(layer "F.Cu")
		(net "M_A_CPU0_SA_DQ<31>")
	)
	(gr_poly
		(pts
			(xy 322.406264 -276.602444) (xy 322.35648 -276.592538) (xy 322.2498 -276.608286) (xy 322.212462 -276.794976)
			(xy 322.305172 -276.850348) (xy 322.354956 -276.860254)
		)
		(stroke
			(width 0)
			(type solid)
		)
		(fill yes)
		(layer "F.Cu")
		(net "M_A_CPU0_SA_DQ<31>")
	)
	(gr_poly
		(pts
			(xy 322.453254 -277.147274) (xy 322.490338 -276.96033) (xy 322.397882 -276.904958) (xy 322.348098 -276.895052)
			(xy 322.29679 -277.153116) (xy 322.346574 -277.163022)
		)
		(stroke
			(width 0)
			(type solid)
		)
		(fill yes)
		(layer "F.Cu")
		(net "M_A_CPU0_SA_DQ<31>")
	)
	(gr_poly
		(pts
			(xy 322.472558 -277.83282) (xy 322.422774 -277.822914) (xy 322.316094 -277.838662) (xy 322.278756 -278.025352)
			(xy 322.371466 -278.080724) (xy 322.42125 -278.09063)
		)
		(stroke
			(width 0)
			(type solid)
		)
		(fill yes)
		(layer "F.Cu")
		(net "M_A_CPU0_SA_DQ<29>")
	)
	(gr_poly
		(pts
			(xy 322.589144 -277.24735) (xy 322.539106 -277.237444) (xy 322.432426 -277.253192) (xy 322.395342 -277.440136)
			(xy 322.487798 -277.495254) (xy 322.537836 -277.50516)
		)
		(stroke
			(width 0)
			(type solid)
		)
		(fill yes)
		(layer "F.Cu")
		(net "M_A_CPU0_SA_DQ<29>")
	)
	(gr_poly
		(pts
			(xy 322.636134 -277.79218) (xy 322.673218 -277.605236) (xy 322.580508 -277.550118) (xy 322.530724 -277.540212)
			(xy 322.479416 -277.798022) (xy 322.529454 -277.807928)
		)
		(stroke
			(width 0)
			(type solid)
		)
		(fill yes)
		(layer "F.Cu")
		(net "M_A_CPU0_SA_DQ<29>")
	)
	(gr_poly
		(pts
			(xy 322.705476 -276.66188) (xy 322.655692 -276.651974) (xy 322.549012 -276.667722) (xy 322.511674 -276.854666)
			(xy 322.604384 -276.909784) (xy 322.654168 -276.919944)
		)
		(stroke
			(width 0)
			(type solid)
		)
		(fill yes)
		(layer "F.Cu")
		(net "M_A_CPU0_SA_DQ<29>")
	)
	(gr_poly
		(pts
			(xy 322.74256 -275.773642) (xy 322.697856 -275.749766) (xy 322.591176 -275.733764) (xy 322.50126 -275.901658)
			(xy 322.573904 -275.981668) (xy 322.618608 -276.005544)
		)
		(stroke
			(width 0)
			(type solid)
		)
		(fill yes)
		(layer "F.Cu")
		(net "M_A_CPU0_SA_DQ<31>")
	)
	(gr_poly
		(pts
			(xy 322.752466 -277.20671) (xy 322.78955 -277.02002) (xy 322.697094 -276.964648) (xy 322.64731 -276.954742)
			(xy 322.596002 -277.212552) (xy 322.645786 -277.222458)
		)
		(stroke
			(width 0)
			(type solid)
		)
		(fill yes)
		(layer "F.Cu")
		(net "M_A_CPU0_SA_DQ<29>")
	)
	(gr_poly
		(pts
			(xy 322.772024 -277.89251) (xy 322.72224 -277.882604) (xy 322.61556 -277.898098) (xy 322.578222 -278.085042)
			(xy 322.670932 -278.140414) (xy 322.720716 -278.15032)
		)
		(stroke
			(width 0)
			(type solid)
		)
		(fill yes)
		(layer "F.Cu")
		(net "M_A_CPU0_SA_DQ<30>")
	)
	(gr_poly
		(pts
			(xy 322.819014 -278.437086) (xy 322.856098 -278.250396) (xy 322.763642 -278.195024) (xy 322.713858 -278.185118)
			(xy 322.66255 -278.442928) (xy 322.712334 -278.452834)
		)
		(stroke
			(width 0)
			(type solid)
		)
		(fill yes)
		(layer "F.Cu")
		(net "M_A_CPU0_SA_DQ<30>")
	)
	(gr_poly
		(pts
			(xy 322.888356 -277.30704) (xy 322.838572 -277.297134) (xy 322.731892 -277.312628) (xy 322.694554 -277.499572)
			(xy 322.787264 -277.554944) (xy 322.837048 -277.56485)
		)
		(stroke
			(width 0)
			(type solid)
		)
		(fill yes)
		(layer "F.Cu")
		(net "M_A_CPU0_SA_DQ<30>")
	)
	(gr_poly
		(pts
			(xy 322.935346 -277.85187) (xy 322.972684 -277.664926) (xy 322.879974 -277.609554) (xy 322.83019 -277.599648)
			(xy 322.778882 -277.857458) (xy 322.828666 -277.867364)
		)
		(stroke
			(width 0)
			(type solid)
		)
		(fill yes)
		(layer "F.Cu")
		(net "M_A_CPU0_SA_DQ<30>")
	)
	(gr_poly
		(pts
			(xy 323.000624 -275.614384) (xy 322.92798 -275.534374) (xy 322.883276 -275.510498) (xy 322.759324 -275.7424)
			(xy 322.804028 -275.766276) (xy 322.910708 -275.782278)
		)
		(stroke
			(width 0)
			(type solid)
		)
		(fill yes)
		(layer "F.Cu")
		(net "M_A_CPU0_SA_DQ<31>")
	)
	(gr_poly
		(pts
			(xy 323.004688 -276.72157) (xy 322.954904 -276.711664) (xy 322.848224 -276.727412) (xy 322.81114 -276.914102)
			(xy 322.903596 -276.969474) (xy 322.95338 -276.97938)
		)
		(stroke
			(width 0)
			(type solid)
		)
		(fill yes)
		(layer "F.Cu")
		(net "M_A_CPU0_SA_DQ<30>")
	)
	(gr_poly
		(pts
			(xy 323.0118 -275.91766) (xy 322.966842 -275.89353) (xy 322.860162 -275.877782) (xy 322.7705 -276.045676)
			(xy 322.84289 -276.125432) (xy 322.887848 -276.149562)
		)
		(stroke
			(width 0)
			(type solid)
		)
		(fill yes)
		(layer "F.Cu")
		(net "M_A_CPU0_SA_DQ<29>")
	)
	(gr_poly
		(pts
			(xy 323.023992 -275.247354) (xy 322.979034 -275.223224) (xy 322.872354 -275.207476) (xy 322.782692 -275.37537)
			(xy 322.855082 -275.455126) (xy 322.90004 -275.479256)
		)
		(stroke
			(width 0)
			(type solid)
		)
		(fill yes)
		(layer "F.Cu")
		(net "M_A_CPU0_SA_DQ<31>")
	)
	(gr_poly
		(pts
			(xy 323.051678 -277.2664) (xy 323.089016 -277.079456) (xy 322.996306 -277.024084) (xy 322.946522 -277.014178)
			(xy 322.895214 -277.271988) (xy 322.944998 -277.281894)
		)
		(stroke
			(width 0)
			(type solid)
		)
		(fill yes)
		(layer "F.Cu")
		(net "M_A_CPU0_SA_DQ<30>")
	)
	(gr_poly
		(pts
			(xy 323.070982 -277.951946) (xy 323.021198 -277.94204) (xy 322.914518 -277.957788) (xy 322.877434 -278.144478)
			(xy 322.96989 -278.19985) (xy 323.019928 -278.209756)
		)
		(stroke
			(width 0)
			(type solid)
		)
		(fill yes)
		(layer "F.Cu")
		(net "M_A_CPU0_SA_DQ<28>")
	)
	(gr_poly
		(pts
			(xy 323.118226 -278.496776) (xy 323.15531 -278.309832) (xy 323.0626 -278.25446) (xy 323.012816 -278.244554)
			(xy 322.961508 -278.502618) (xy 323.011546 -278.51227)
		)
		(stroke
			(width 0)
			(type solid)
		)
		(fill yes)
		(layer "F.Cu")
		(net "M_A_CPU0_SA_DQ<28>")
	)
	(gr_poly
		(pts
			(xy 323.187568 -277.366476) (xy 323.137784 -277.35657) (xy 323.03085 -277.372318) (xy 322.993766 -277.559008)
			(xy 323.086476 -277.61438) (xy 323.13626 -277.624286)
		)
		(stroke
			(width 0)
			(type solid)
		)
		(fill yes)
		(layer "F.Cu")
		(net "M_A_CPU0_SA_DQ<28>")
	)
	(gr_poly
		(pts
			(xy 323.234558 -277.911306) (xy 323.271642 -277.724362) (xy 323.179186 -277.66899) (xy 323.129402 -277.659084)
			(xy 323.078094 -277.917148) (xy 323.127878 -277.927054)
		)
		(stroke
			(width 0)
			(type solid)
		)
		(fill yes)
		(layer "F.Cu")
		(net "M_A_CPU0_SA_DQ<28>")
	)
	(gr_poly
		(pts
			(xy 323.269864 -275.758148) (xy 323.19722 -275.678392) (xy 323.152516 -275.654262) (xy 323.028564 -275.886164)
			(xy 323.073268 -275.910294) (xy 323.179948 -275.926042)
		)
		(stroke
			(width 0)
			(type solid)
		)
		(fill yes)
		(layer "F.Cu")
		(net "M_A_CPU0_SA_DQ<29>")
	)
	(gr_poly
		(pts
			(xy 323.280786 -276.061424) (xy 323.236082 -276.037548) (xy 323.129402 -276.021546) (xy 323.039486 -276.18944)
			(xy 323.11213 -276.26945) (xy 323.156834 -276.293326)
		)
		(stroke
			(width 0)
			(type solid)
		)
		(fill yes)
		(layer "F.Cu")
		(net "M_A_CPU0_SA_DQ<30>")
	)
	(gr_poly
		(pts
			(xy 323.282056 -275.087842) (xy 323.209412 -275.008086) (xy 323.164708 -274.98421) (xy 323.040756 -275.215858)
			(xy 323.08546 -275.239988) (xy 323.19214 -275.255736)
		)
		(stroke
			(width 0)
			(type solid)
		)
		(fill yes)
		(layer "F.Cu")
		(net "M_A_CPU0_SA_DQ<31>")
	)
	(gr_poly
		(pts
			(xy 323.292978 -275.391118) (xy 323.248274 -275.367242) (xy 323.141594 -275.35124) (xy 323.051932 -275.519134)
			(xy 323.124322 -275.599144) (xy 323.16928 -275.62302)
		)
		(stroke
			(width 0)
			(type solid)
		)
		(fill yes)
		(layer "F.Cu")
		(net "M_A_CPU0_SA_DQ<29>")
	)
	(gr_poly
		(pts
			(xy 323.3039 -276.781006) (xy 323.254116 -276.7711) (xy 323.147436 -276.786848) (xy 323.110352 -276.973792)
			(xy 323.202808 -277.02891) (xy 323.252592 -277.038816)
		)
		(stroke
			(width 0)
			(type solid)
		)
		(fill yes)
		(layer "F.Cu")
		(net "M_A_CPU0_SA_DQ<28>")
	)
	(gr_poly
		(pts
			(xy 323.305424 -274.720812) (xy 323.260466 -274.696936) (xy 323.153786 -274.680934) (xy 323.064124 -274.849082)
			(xy 323.136514 -274.928838) (xy 323.181472 -274.952714)
		)
		(stroke
			(width 0)
			(type solid)
		)
		(fill yes)
		(layer "F.Cu")
		(net "M_A_CPU0_SA_DQ<31>")
	)
	(gr_poly
		(pts
			(xy 323.35089 -277.325836) (xy 323.388228 -277.138892) (xy 323.295518 -277.083774) (xy 323.245734 -277.073868)
			(xy 323.194426 -277.331678) (xy 323.24421 -277.341584)
		)
		(stroke
			(width 0)
			(type solid)
		)
		(fill yes)
		(layer "F.Cu")
		(net "M_A_CPU0_SA_DQ<28>")
	)
	(gr_poly
		(pts
			(xy 323.53885 -275.901912) (xy 323.466206 -275.822156) (xy 323.421502 -275.79828) (xy 323.29755 -276.030182)
			(xy 323.342508 -276.054058) (xy 323.448934 -276.07006)
		)
		(stroke
			(width 0)
			(type solid)
		)
		(fill yes)
		(layer "F.Cu")
		(net "M_A_CPU0_SA_DQ<30>")
	)
	(gr_poly
		(pts
			(xy 323.550026 -276.205442) (xy 323.505322 -276.181312) (xy 323.398642 -276.165564) (xy 323.308726 -276.333458)
			(xy 323.38137 -276.413214) (xy 323.426074 -276.437344)
		)
		(stroke
			(width 0)
			(type solid)
		)
		(fill yes)
		(layer "F.Cu")
		(net "M_A_CPU0_SA_DQ<28>")
	)
	(gr_poly
		(pts
			(xy 323.551042 -275.231606) (xy 323.478652 -275.15185) (xy 323.433694 -275.127974) (xy 323.309742 -275.359876)
			(xy 323.3547 -275.383752) (xy 323.46138 -275.399754)
		)
		(stroke
			(width 0)
			(type solid)
		)
		(fill yes)
		(layer "F.Cu")
		(net "M_A_CPU0_SA_DQ<29>")
	)
	(gr_poly
		(pts
			(xy 323.562218 -275.535136) (xy 323.517514 -275.511006) (xy 323.410834 -275.495004) (xy 323.320918 -275.663152)
			(xy 323.393562 -275.742908) (xy 323.438266 -275.766784)
		)
		(stroke
			(width 0)
			(type solid)
		)
		(fill yes)
		(layer "F.Cu")
		(net "M_A_CPU0_SA_DQ<30>")
	)
	(gr_poly
		(pts
			(xy 323.563488 -274.561554) (xy 323.490844 -274.481544) (xy 323.44614 -274.457668) (xy 323.322188 -274.68957)
			(xy 323.366892 -274.713446) (xy 323.473572 -274.729448)
		)
		(stroke
			(width 0)
			(type solid)
		)
		(fill yes)
		(layer "F.Cu")
		(net "M_A_CPU0_SA_DQ<31>")
	)
	(gr_poly
		(pts
			(xy 323.57441 -274.86483) (xy 323.529706 -274.8407) (xy 323.423026 -274.824952) (xy 323.33311 -274.992846)
			(xy 323.405754 -275.072602) (xy 323.450458 -275.096478)
		)
		(stroke
			(width 0)
			(type solid)
		)
		(fill yes)
		(layer "F.Cu")
		(net "M_A_CPU0_SA_DQ<29>")
	)
	(gr_poly
		(pts
			(xy 323.586856 -274.194524) (xy 323.541898 -274.170648) (xy 323.435218 -274.154646) (xy 323.345556 -274.32254)
			(xy 323.417946 -274.402296) (xy 323.462904 -274.426426)
		)
		(stroke
			(width 0)
			(type solid)
		)
		(fill yes)
		(layer "F.Cu")
		(net "M_A_CPU0_SA_DQ<31>")
	)
	(gr_poly
		(pts
			(xy 323.80809 -276.04593) (xy 323.7357 -275.966174) (xy 323.690742 -275.942298) (xy 323.56679 -276.173946)
			(xy 323.611748 -276.198076) (xy 323.718428 -276.214078)
		)
		(stroke
			(width 0)
			(type solid)
		)
		(fill yes)
		(layer "F.Cu")
		(net "M_A_CPU0_SA_DQ<28>")
	)
	(gr_poly
		(pts
			(xy 323.820282 -275.375624) (xy 323.747638 -275.295868) (xy 323.702934 -275.271738) (xy 323.578982 -275.50364)
			(xy 323.623686 -275.527516) (xy 323.730366 -275.543518)
		)
		(stroke
			(width 0)
			(type solid)
		)
		(fill yes)
		(layer "F.Cu")
		(net "M_A_CPU0_SA_DQ<30>")
	)
	(gr_poly
		(pts
			(xy 323.831458 -275.6789) (xy 323.786754 -275.655024) (xy 323.680074 -275.639022) (xy 323.590158 -275.80717)
			(xy 323.662802 -275.886926) (xy 323.707506 -275.910802)
		)
		(stroke
			(width 0)
			(type solid)
		)
		(fill yes)
		(layer "F.Cu")
		(net "M_A_CPU0_SA_DQ<28>")
	)
	(gr_poly
		(pts
			(xy 323.832474 -274.705318) (xy 323.75983 -274.625562) (xy 323.715126 -274.601432) (xy 323.591174 -274.833334)
			(xy 323.636132 -274.857464) (xy 323.742812 -274.873212)
		)
		(stroke
			(width 0)
			(type solid)
		)
		(fill yes)
		(layer "F.Cu")
		(net "M_A_CPU0_SA_DQ<29>")
	)
	(gr_poly
		(pts
			(xy 323.84365 -275.008594) (xy 323.798692 -274.984718) (xy 323.692012 -274.968716) (xy 323.60235 -275.13661)
			(xy 323.674994 -275.21662) (xy 323.719698 -275.240496)
		)
		(stroke
			(width 0)
			(type solid)
		)
		(fill yes)
		(layer "F.Cu")
		(net "M_A_CPU0_SA_DQ<30>")
	)
	(gr_poly
		(pts
			(xy 323.844666 -274.035012) (xy 323.772276 -273.955256) (xy 323.727318 -273.93138) (xy 323.60362 -274.163028)
			(xy 323.648324 -274.187158) (xy 323.755004 -274.20316)
		)
		(stroke
			(width 0)
			(type solid)
		)
		(fill yes)
		(layer "F.Cu")
		(net "M_A_CPU0_SA_DQ<31>")
	)
	(gr_poly
		(pts
			(xy 323.855842 -274.338288) (xy 323.811138 -274.314412) (xy 323.704458 -274.29841) (xy 323.614542 -274.466304)
			(xy 323.687186 -274.546314) (xy 323.73189 -274.57019)
		)
		(stroke
			(width 0)
			(type solid)
		)
		(fill yes)
		(layer "F.Cu")
		(net "M_A_CPU0_SA_DQ<29>")
	)
	(gr_poly
		(pts
			(xy 323.868034 -273.667982) (xy 323.82333 -273.644106) (xy 323.71665 -273.628104) (xy 323.626734 -273.796252)
			(xy 323.699378 -273.876008) (xy 323.744082 -273.899884)
		)
		(stroke
			(width 0)
			(type solid)
		)
		(fill yes)
		(layer "F.Cu")
		(net "M_A_CPU0_SA_DQ<31>")
	)
	(gr_poly
		(pts
			(xy 323.988938 -281.31262) (xy 323.939154 -281.302714) (xy 323.832474 -281.318208) (xy 323.79539 -281.505152)
			(xy 323.887846 -281.560524) (xy 323.93763 -281.57043)
		)
		(stroke
			(width 0)
			(type solid)
		)
		(fill yes)
		(layer "F.Cu")
		(net "M_A_CPU0_SA_DQ<27>")
	)
	(gr_poly
		(pts
			(xy 324.089522 -275.519642) (xy 324.017132 -275.439886) (xy 323.972174 -275.415756) (xy 323.848222 -275.647658)
			(xy 323.89318 -275.671534) (xy 323.99986 -275.687536)
		)
		(stroke
			(width 0)
			(type solid)
		)
		(fill yes)
		(layer "F.Cu")
		(net "M_A_CPU0_SA_DQ<28>")
	)
	(gr_poly
		(pts
			(xy 324.101714 -274.849082) (xy 324.02907 -274.769326) (xy 323.984366 -274.74545) (xy 323.860414 -274.977352)
			(xy 323.905118 -275.001228) (xy 324.011798 -275.01723)
		)
		(stroke
			(width 0)
			(type solid)
		)
		(fill yes)
		(layer "F.Cu")
		(net "M_A_CPU0_SA_DQ<30>")
	)
	(gr_poly
		(pts
			(xy 324.105524 -280.72715) (xy 324.05574 -280.717244) (xy 323.94906 -280.732992) (xy 323.911722 -280.919682)
			(xy 324.004432 -280.975054) (xy 324.054216 -280.98496)
		)
		(stroke
			(width 0)
			(type solid)
		)
		(fill yes)
		(layer "F.Cu")
		(net "M_A_CPU0_SA_DQ<27>")
	)
	(gr_poly
		(pts
			(xy 324.11289 -275.152612) (xy 324.068186 -275.128736) (xy 323.961506 -275.112734) (xy 323.871844 -275.280628)
			(xy 323.944234 -275.360638) (xy 323.989192 -275.384514)
		)
		(stroke
			(width 0)
			(type solid)
		)
		(fill yes)
		(layer "F.Cu")
		(net "M_A_CPU0_SA_DQ<28>")
	)
	(gr_poly
		(pts
			(xy 324.113906 -274.178776) (xy 324.041262 -274.09902) (xy 323.996558 -274.075144) (xy 323.872606 -274.307046)
			(xy 323.91731 -274.330922) (xy 324.02399 -274.346924)
		)
		(stroke
			(width 0)
			(type solid)
		)
		(fill yes)
		(layer "F.Cu")
		(net "M_A_CPU0_SA_DQ<29>")
	)
	(gr_poly
		(pts
			(xy 324.125082 -274.482306) (xy 324.080124 -274.458176) (xy 323.973444 -274.442174) (xy 323.883782 -274.610322)
			(xy 323.956172 -274.690078) (xy 324.00113 -274.713954)
		)
		(stroke
			(width 0)
			(type solid)
		)
		(fill yes)
		(layer "F.Cu")
		(net "M_A_CPU0_SA_DQ<30>")
	)
	(gr_poly
		(pts
			(xy 324.137274 -273.812) (xy 324.092316 -273.78787) (xy 323.985636 -273.771868) (xy 323.895974 -273.940016)
			(xy 323.968364 -274.019772) (xy 324.013322 -274.043648)
		)
		(stroke
			(width 0)
			(type solid)
		)
		(fill yes)
		(layer "F.Cu")
		(net "M_A_CPU0_SA_DQ<29>")
	)
	(gr_poly
		(pts
			(xy 324.152514 -281.27198) (xy 324.189598 -281.085036) (xy 324.097142 -281.029664) (xy 324.047358 -281.019758)
			(xy 323.99605 -281.277568) (xy 324.045834 -281.287728)
		)
		(stroke
			(width 0)
			(type solid)
		)
		(fill yes)
		(layer "F.Cu")
		(net "M_A_CPU0_SA_DQ<27>")
	)
	(gr_poly
		(pts
			(xy 324.22211 -280.14168) (xy 324.172072 -280.131774) (xy 324.065392 -280.147522) (xy 324.028308 -280.334212)
			(xy 324.120764 -280.389584) (xy 324.170802 -280.39949)
		)
		(stroke
			(width 0)
			(type solid)
		)
		(fill yes)
		(layer "F.Cu")
		(net "M_A_CPU0_SA_DQ<27>")
	)
	(gr_poly
		(pts
			(xy 324.2691 -280.68651) (xy 324.306184 -280.499566) (xy 324.213474 -280.444448) (xy 324.16369 -280.434542)
			(xy 324.112382 -280.692352) (xy 324.162166 -280.702258)
		)
		(stroke
			(width 0)
			(type solid)
		)
		(fill yes)
		(layer "F.Cu")
		(net "M_A_CPU0_SA_DQ<27>")
	)
	(gr_poly
		(pts
			(xy 324.338442 -279.55621) (xy 324.288658 -279.546304) (xy 324.181978 -279.562052) (xy 324.144894 -279.748996)
			(xy 324.23735 -279.804114) (xy 324.287134 -279.81402)
		)
		(stroke
			(width 0)
			(type solid)
		)
		(fill yes)
		(layer "F.Cu")
		(net "M_A_CPU0_SA_DQ<27>")
	)
	(gr_poly
		(pts
			(xy 324.371208 -274.9931) (xy 324.298564 -274.913344) (xy 324.25386 -274.889468) (xy 324.129908 -275.12137)
			(xy 324.174612 -275.145246) (xy 324.281292 -275.161248)
		)
		(stroke
			(width 0)
			(type solid)
		)
		(fill yes)
		(layer "F.Cu")
		(net "M_A_CPU0_SA_DQ<28>")
	)
	(gr_poly
		(pts
			(xy 324.383146 -274.322794) (xy 324.310502 -274.243038) (xy 324.265798 -274.218908) (xy 324.141846 -274.45081)
			(xy 324.18655 -274.474686) (xy 324.29323 -274.490688)
		)
		(stroke
			(width 0)
			(type solid)
		)
		(fill yes)
		(layer "F.Cu")
		(net "M_A_CPU0_SA_DQ<30>")
	)
	(gr_poly
		(pts
			(xy 324.385432 -280.10104) (xy 324.42277 -279.91435) (xy 324.33006 -279.858978) (xy 324.280276 -279.849072)
			(xy 324.228968 -280.106882) (xy 324.278752 -280.116788)
		)
		(stroke
			(width 0)
			(type solid)
		)
		(fill yes)
		(layer "F.Cu")
		(net "M_A_CPU0_SA_DQ<27>")
	)
	(gr_poly
		(pts
			(xy 324.394576 -274.626324) (xy 324.349618 -274.602448) (xy 324.242938 -274.586446) (xy 324.153276 -274.75434)
			(xy 324.225666 -274.834096) (xy 324.270624 -274.858226)
		)
		(stroke
			(width 0)
			(type solid)
		)
		(fill yes)
		(layer "F.Cu")
		(net "M_A_CPU0_SA_DQ<28>")
	)
	(gr_poly
		(pts
			(xy 324.404736 -280.786586) (xy 324.354952 -280.77668) (xy 324.248272 -280.792428) (xy 324.210934 -280.979372)
			(xy 324.303644 -281.03449) (xy 324.353428 -281.044396)
		)
		(stroke
			(width 0)
			(type solid)
		)
		(fill yes)
		(layer "F.Cu")
		(net "M_A_CPU0_SA_DQ<25>")
	)
	(gr_poly
		(pts
			(xy 324.40626 -273.955764) (xy 324.361556 -273.931888) (xy 324.254876 -273.915886) (xy 324.165214 -274.08378)
			(xy 324.237604 -274.16379) (xy 324.282562 -274.187666)
		)
		(stroke
			(width 0)
			(type solid)
		)
		(fill yes)
		(layer "F.Cu")
		(net "M_A_CPU0_SA_DQ<30>")
	)
	(gr_poly
		(pts
			(xy 324.422516 -273.199606) (xy 324.376288 -273.10207) (xy 324.34022 -273.066256) (xy 324.154292 -273.252184)
			(xy 324.19036 -273.287998) (xy 324.287642 -273.334226)
		)
		(stroke
			(width 0)
			(type solid)
		)
		(fill yes)
		(layer "F.Cu")
		(net "M_A_CPU0_SA_DQ<31>")
	)
	(gr_poly
		(pts
			(xy 324.451726 -281.331416) (xy 324.48881 -281.144726) (xy 324.396354 -281.089354) (xy 324.34657 -281.079448)
			(xy 324.295262 -281.337258) (xy 324.345046 -281.347164)
		)
		(stroke
			(width 0)
			(type solid)
		)
		(fill yes)
		(layer "F.Cu")
		(net "M_A_CPU0_SA_DQ<25>")
	)
	(gr_poly
		(pts
			(xy 324.455028 -278.970994) (xy 324.405244 -278.961088) (xy 324.298564 -278.976582) (xy 324.261226 -279.163526)
			(xy 324.353936 -279.218898) (xy 324.40372 -279.228804)
		)
		(stroke
			(width 0)
			(type solid)
		)
		(fill yes)
		(layer "F.Cu")
		(net "M_A_CPU0_SA_DQ<27>")
	)
	(gr_poly
		(pts
			(xy 324.465188 -266.2809) (xy 324.429374 -266.244832) (xy 324.331838 -266.198604) (xy 324.197218 -266.333224)
			(xy 324.243446 -266.43076) (xy 324.279514 -266.466574)
		)
		(stroke
			(width 0)
			(type solid)
		)
		(fill yes)
		(layer "F.Cu")
		(net "M_A_CPU0_SA_CB<5>")
	)
	(gr_poly
		(pts
			(xy 324.502018 -279.51557) (xy 324.539102 -279.32888) (xy 324.446646 -279.273508) (xy 324.396608 -279.263602)
			(xy 324.345554 -279.521412) (xy 324.395338 -279.531318)
		)
		(stroke
			(width 0)
			(type solid)
		)
		(fill yes)
		(layer "F.Cu")
		(net "M_A_CPU0_SA_DQ<27>")
	)
	(gr_poly
		(pts
			(xy 324.521322 -280.20137) (xy 324.471538 -280.191464) (xy 324.364604 -280.206958) (xy 324.32752 -280.393902)
			(xy 324.42023 -280.449274) (xy 324.470014 -280.45918)
		)
		(stroke
			(width 0)
			(type solid)
		)
		(fill yes)
		(layer "F.Cu")
		(net "M_A_CPU0_SA_DQ<25>")
	)
	(gr_poly
		(pts
			(xy 324.542658 -265.987276) (xy 324.49643 -265.889994) (xy 324.460616 -265.853926) (xy 324.274688 -266.039854)
			(xy 324.310502 -266.075922) (xy 324.408038 -266.12215)
		)
		(stroke
			(width 0)
			(type solid)
		)
		(fill yes)
		(layer "F.Cu")
		(net "M_A_CPU0_SA_CB<7>")
	)
	(gr_poly
		(pts
			(xy 324.551294 -272.855182) (xy 324.51548 -272.819368) (xy 324.417944 -272.772886) (xy 324.283324 -272.90776)
			(xy 324.329552 -273.005042) (xy 324.365366 -273.04111)
		)
		(stroke
			(width 0)
			(type solid)
		)
		(fill yes)
		(layer "F.Cu")
		(net "M_A_CPU0_SA_DQ<31>")
	)
	(gr_poly
		(pts
			(xy 324.568312 -280.745946) (xy 324.605396 -280.559256) (xy 324.51294 -280.503884) (xy 324.462902 -280.493978)
			(xy 324.411594 -280.751788) (xy 324.461632 -280.761694)
		)
		(stroke
			(width 0)
			(type solid)
		)
		(fill yes)
		(layer "F.Cu")
		(net "M_A_CPU0_SA_DQ<25>")
	)
	(gr_poly
		(pts
			(xy 324.57136 -278.385524) (xy 324.521576 -278.375618) (xy 324.414896 -278.391112) (xy 324.377812 -278.578056)
			(xy 324.470268 -278.633428) (xy 324.520052 -278.643334)
		)
		(stroke
			(width 0)
			(type solid)
		)
		(fill yes)
		(layer "F.Cu")
		(net "M_A_CPU0_SA_DQ<27>")
	)
	(gr_poly
		(pts
			(xy 324.587616 -281.431492) (xy 324.537832 -281.421586) (xy 324.430898 -281.437334) (xy 324.393814 -281.624278)
			(xy 324.486524 -281.679396) (xy 324.536308 -281.689556)
		)
		(stroke
			(width 0)
			(type solid)
		)
		(fill yes)
		(layer "F.Cu")
		(net "M_A_CPU0_SA_DQ<26>")
	)
	(gr_poly
		(pts
			(xy 324.61835 -278.930354) (xy 324.655688 -278.74341) (xy 324.562978 -278.688038) (xy 324.513194 -278.678132)
			(xy 324.461886 -278.935942) (xy 324.51167 -278.945848)
		)
		(stroke
			(width 0)
			(type solid)
		)
		(fill yes)
		(layer "F.Cu")
		(net "M_A_CPU0_SA_DQ<27>")
	)
	(gr_poly
		(pts
			(xy 324.637654 -279.6159) (xy 324.58787 -279.605994) (xy 324.48119 -279.621488) (xy 324.444106 -279.808432)
			(xy 324.536562 -279.863804) (xy 324.586346 -279.87371)
		)
		(stroke
			(width 0)
			(type solid)
		)
		(fill yes)
		(layer "F.Cu")
		(net "M_A_CPU0_SA_DQ<25>")
	)
	(gr_poly
		(pts
			(xy 324.638162 -273.415252) (xy 324.591934 -273.31797) (xy 324.55612 -273.281902) (xy 324.370192 -273.46783)
			(xy 324.406006 -273.503898) (xy 324.503542 -273.550126)
		)
		(stroke
			(width 0)
			(type solid)
		)
		(fill yes)
		(layer "F.Cu")
		(net "M_A_CPU0_SA_DQ<29>")
	)
	(gr_poly
		(pts
			(xy 324.65264 -274.466812) (xy 324.579996 -274.387056) (xy 324.535292 -274.36318) (xy 324.41134 -274.594828)
			(xy 324.456044 -274.618958) (xy 324.562724 -274.63496)
		)
		(stroke
			(width 0)
			(type solid)
		)
		(fill yes)
		(layer "F.Cu")
		(net "M_A_CPU0_SA_DQ<28>")
	)
	(gr_poly
		(pts
			(xy 324.67169 -265.642852) (xy 324.635622 -265.607038) (xy 324.53834 -265.56081) (xy 324.403466 -265.69543)
			(xy 324.449694 -265.792966) (xy 324.485762 -265.82878)
		)
		(stroke
			(width 0)
			(type solid)
		)
		(fill yes)
		(layer "F.Cu")
		(net "M_A_CPU0_SA_CB<7>")
	)
	(gr_poly
		(pts
			(xy 324.672452 -223.210374) (xy 324.621652 -223.210374) (xy 324.520052 -223.246696) (xy 324.520052 -223.437196)
			(xy 324.621652 -223.473518) (xy 324.672452 -223.473518)
		)
		(stroke
			(width 0)
			(type solid)
		)
		(fill yes)
		(layer "F.Cu")
		(net "M_A_CPU0_SB_DQ<16>")
	)
	(gr_poly
		(pts
			(xy 324.672452 -222.613474) (xy 324.621652 -222.613474) (xy 324.520052 -222.649796) (xy 324.520052 -222.840296)
			(xy 324.621652 -222.876618) (xy 324.672452 -222.876618)
		)
		(stroke
			(width 0)
			(type solid)
		)
		(fill yes)
		(layer "F.Cu")
		(net "M_A_CPU0_SB_DQ<16>")
	)
	(gr_poly
		(pts
			(xy 324.672452 -222.016574) (xy 324.621652 -222.016574) (xy 324.520052 -222.052896) (xy 324.520052 -222.243396)
			(xy 324.621652 -222.279718) (xy 324.672452 -222.279718)
		)
		(stroke
			(width 0)
			(type solid)
		)
		(fill yes)
		(layer "F.Cu")
		(net "M_A_CPU0_SB_DQ<16>")
	)
	(gr_poly
		(pts
			(xy 324.672452 -221.419674) (xy 324.621652 -221.419674) (xy 324.520052 -221.455996) (xy 324.520052 -221.646496)
			(xy 324.621652 -221.682818) (xy 324.672452 -221.682818)
		)
		(stroke
			(width 0)
			(type solid)
		)
		(fill yes)
		(layer "F.Cu")
		(net "M_A_CPU0_SB_DQ<16>")
	)
	(gr_poly
		(pts
			(xy 324.672452 -220.822774) (xy 324.621652 -220.822774) (xy 324.520052 -220.859096) (xy 324.520052 -221.049596)
			(xy 324.621652 -221.085918) (xy 324.672452 -221.085918)
		)
		(stroke
			(width 0)
			(type solid)
		)
		(fill yes)
		(layer "F.Cu")
		(net "M_A_CPU0_SB_DQ<16>")
	)
	(gr_poly
		(pts
			(xy 324.672452 -220.225874) (xy 324.621652 -220.225874) (xy 324.520052 -220.262196) (xy 324.520052 -220.452696)
			(xy 324.621652 -220.489018) (xy 324.672452 -220.489018)
		)
		(stroke
			(width 0)
			(type solid)
		)
		(fill yes)
		(layer "F.Cu")
		(net "M_A_CPU0_SB_DQ<16>")
	)
	(gr_poly
		(pts
			(xy 324.676008 -274.099782) (xy 324.63105 -274.075906) (xy 324.52437 -274.059904) (xy 324.434708 -274.228052)
			(xy 324.507098 -274.307808) (xy 324.552056 -274.331684)
		)
		(stroke
			(width 0)
			(type solid)
		)
		(fill yes)
		(layer "F.Cu")
		(net "M_A_CPU0_SA_DQ<28>")
	)
	(gr_poly
		(pts
			(xy 324.681088 -266.496546) (xy 324.64502 -266.460732) (xy 324.547738 -266.414504) (xy 324.413118 -266.549124)
			(xy 324.459346 -266.64666) (xy 324.49516 -266.682474)
		)
		(stroke
			(width 0)
			(type solid)
		)
		(fill yes)
		(layer "F.Cu")
		(net "M_A_CPU0_SA_CB<6>")
	)
	(gr_poly
		(pts
			(xy 324.68439 -280.16073) (xy 324.721728 -279.973786) (xy 324.629018 -279.918414) (xy 324.579234 -279.908508)
			(xy 324.527926 -280.166318) (xy 324.57771 -280.176224)
		)
		(stroke
			(width 0)
			(type solid)
		)
		(fill yes)
		(layer "F.Cu")
		(net "M_A_CPU0_SA_DQ<25>")
	)
	(gr_poly
		(pts
			(xy 324.687946 -277.800054) (xy 324.638162 -277.790148) (xy 324.531482 -277.805896) (xy 324.494144 -277.992586)
			(xy 324.586854 -278.047958) (xy 324.636638 -278.057864)
		)
		(stroke
			(width 0)
			(type solid)
		)
		(fill yes)
		(layer "F.Cu")
		(net "M_A_CPU0_SA_DQ<27>")
	)
	(gr_poly
		(pts
			(xy 324.703694 -280.846276) (xy 324.65391 -280.83637) (xy 324.54723 -280.851864) (xy 324.510146 -281.038808)
			(xy 324.602602 -281.09418) (xy 324.652386 -281.104086)
		)
		(stroke
			(width 0)
			(type solid)
		)
		(fill yes)
		(layer "F.Cu")
		(net "M_A_CPU0_SA_DQ<26>")
	)
	(gr_poly
		(pts
			(xy 324.734936 -278.344884) (xy 324.77202 -278.15794) (xy 324.679564 -278.102568) (xy 324.62978 -278.092662)
			(xy 324.578472 -278.350472) (xy 324.628256 -278.360378)
		)
		(stroke
			(width 0)
			(type solid)
		)
		(fill yes)
		(layer "F.Cu")
		(net "M_A_CPU0_SA_DQ<27>")
	)
	(gr_poly
		(pts
			(xy 324.750684 -281.390852) (xy 324.788022 -281.204162) (xy 324.695312 -281.14879) (xy 324.645528 -281.138884)
			(xy 324.59422 -281.396694) (xy 324.644004 -281.4066)
		)
		(stroke
			(width 0)
			(type solid)
		)
		(fill yes)
		(layer "F.Cu")
		(net "M_A_CPU0_SA_DQ<26>")
	)
	(gr_poly
		(pts
			(xy 324.75424 -279.03043) (xy 324.704456 -279.020524) (xy 324.597776 -279.036272) (xy 324.560438 -279.222962)
			(xy 324.653148 -279.278334) (xy 324.702932 -279.28824)
		)
		(stroke
			(width 0)
			(type solid)
		)
		(fill yes)
		(layer "F.Cu")
		(net "M_A_CPU0_SA_DQ<25>")
	)
	(gr_poly
		(pts
			(xy 324.758558 -266.203176) (xy 324.71233 -266.10564) (xy 324.676262 -266.069826) (xy 324.490334 -266.255754)
			(xy 324.526402 -266.291568) (xy 324.623684 -266.337796)
		)
		(stroke
			(width 0)
			(type solid)
		)
		(fill yes)
		(layer "F.Cu")
		(net "M_A_CPU0_SA_CB<5>")
	)
	(gr_poly
		(pts
			(xy 324.767194 -273.070828) (xy 324.731126 -273.035014) (xy 324.63359 -272.988786) (xy 324.49897 -273.123406)
			(xy 324.545198 -273.220942) (xy 324.581266 -273.256756)
		)
		(stroke
			(width 0)
			(type solid)
		)
		(fill yes)
		(layer "F.Cu")
		(net "M_A_CPU0_SA_DQ<29>")
	)
	(gr_poly
		(pts
			(xy 324.767956 -267.05687) (xy 324.721728 -266.959334) (xy 324.685914 -266.923266) (xy 324.499986 -267.109194)
			(xy 324.5358 -267.145262) (xy 324.633336 -267.19149)
		)
		(stroke
			(width 0)
			(type solid)
		)
		(fill yes)
		(layer "F.Cu")
		(net "M_A_CPU0_SA_CB<4>")
	)
	(gr_poly
		(pts
			(xy 324.80123 -279.57526) (xy 324.838314 -279.388316) (xy 324.745858 -279.332944) (xy 324.696074 -279.323038)
			(xy 324.644766 -279.580848) (xy 324.69455 -279.590754)
		)
		(stroke
			(width 0)
			(type solid)
		)
		(fill yes)
		(layer "F.Cu")
		(net "M_A_CPU0_SA_DQ<25>")
	)
	(gr_poly
		(pts
			(xy 324.804532 -277.214584) (xy 324.754748 -277.204678) (xy 324.647814 -277.220426) (xy 324.61073 -277.407116)
			(xy 324.70344 -277.462488) (xy 324.753224 -277.472394)
		)
		(stroke
			(width 0)
			(type solid)
		)
		(fill yes)
		(layer "F.Cu")
		(net "M_A_CPU0_SA_DQ<27>")
	)
	(gr_poly
		(pts
			(xy 324.820534 -280.260806) (xy 324.77075 -280.2509) (xy 324.66407 -280.266394) (xy 324.626732 -280.453338)
			(xy 324.719442 -280.50871) (xy 324.769226 -280.518616)
		)
		(stroke
			(width 0)
			(type solid)
		)
		(fill yes)
		(layer "F.Cu")
		(net "M_A_CPU0_SA_DQ<26>")
	)
	(gr_poly
		(pts
			(xy 324.824852 -223.138746) (xy 324.824852 -222.948246) (xy 324.723252 -222.912178) (xy 324.672452 -222.912178)
			(xy 324.672452 -223.174814) (xy 324.723252 -223.174814)
		)
		(stroke
			(width 0)
			(type solid)
		)
		(fill yes)
		(layer "F.Cu")
		(net "M_A_CPU0_SB_DQ<16>")
	)
	(gr_poly
		(pts
			(xy 324.824852 -222.541846) (xy 324.824852 -222.351346) (xy 324.723252 -222.315278) (xy 324.672452 -222.315278)
			(xy 324.672452 -222.577914) (xy 324.723252 -222.577914)
		)
		(stroke
			(width 0)
			(type solid)
		)
		(fill yes)
		(layer "F.Cu")
		(net "M_A_CPU0_SB_DQ<16>")
	)
	(gr_poly
		(pts
			(xy 324.824852 -221.944946) (xy 324.824852 -221.754446) (xy 324.723252 -221.718378) (xy 324.672452 -221.718378)
			(xy 324.672452 -221.981014) (xy 324.723252 -221.981014)
		)
		(stroke
			(width 0)
			(type solid)
		)
		(fill yes)
		(layer "F.Cu")
		(net "M_A_CPU0_SB_DQ<16>")
	)
	(gr_poly
		(pts
			(xy 324.824852 -221.348046) (xy 324.824852 -221.157546) (xy 324.723252 -221.121478) (xy 324.672452 -221.121478)
			(xy 324.672452 -221.384114) (xy 324.723252 -221.384114)
		)
		(stroke
			(width 0)
			(type solid)
		)
		(fill yes)
		(layer "F.Cu")
		(net "M_A_CPU0_SB_DQ<16>")
	)
	(gr_poly
		(pts
			(xy 324.824852 -220.751146) (xy 324.824852 -220.560646) (xy 324.723252 -220.524578) (xy 324.672452 -220.524578)
			(xy 324.672452 -220.787214) (xy 324.723252 -220.787214)
		)
		(stroke
			(width 0)
			(type solid)
		)
		(fill yes)
		(layer "F.Cu")
		(net "M_A_CPU0_SB_DQ<16>")
	)
	(gr_poly
		(pts
			(xy 324.84441 -272.777458) (xy 324.798182 -272.680176) (xy 324.762368 -272.644108) (xy 324.57644 -272.830036)
			(xy 324.612254 -272.86585) (xy 324.70979 -272.912078)
		)
		(stroke
			(width 0)
			(type solid)
		)
		(fill yes)
		(layer "F.Cu")
		(net "M_A_CPU0_SA_DQ<31>")
	)
	(gr_poly
		(pts
			(xy 324.851522 -277.759414) (xy 324.888606 -277.57247) (xy 324.79615 -277.517352) (xy 324.746112 -277.507446)
			(xy 324.694804 -277.765256) (xy 324.744842 -277.775162)
		)
		(stroke
			(width 0)
			(type solid)
		)
		(fill yes)
		(layer "F.Cu")
		(net "M_A_CPU0_SA_DQ<27>")
	)
	(gr_poly
		(pts
			(xy 324.86727 -280.805636) (xy 324.904354 -280.618692) (xy 324.811898 -280.56332) (xy 324.762114 -280.553414)
			(xy 324.710806 -280.811224) (xy 324.76059 -280.82113)
		)
		(stroke
			(width 0)
			(type solid)
		)
		(fill yes)
		(layer "F.Cu")
		(net "M_A_CPU0_SA_DQ<26>")
	)
	(gr_poly
		(pts
			(xy 324.870826 -278.44496) (xy 324.820788 -278.435054) (xy 324.714108 -278.450802) (xy 324.677024 -278.637492)
			(xy 324.76948 -278.692864) (xy 324.819518 -278.70277)
		)
		(stroke
			(width 0)
			(type solid)
		)
		(fill yes)
		(layer "F.Cu")
		(net "M_A_CPU0_SA_DQ<25>")
	)
	(gr_poly
		(pts
			(xy 324.886828 -281.491182) (xy 324.837044 -281.481276) (xy 324.73011 -281.497024) (xy 324.693026 -281.683714)
			(xy 324.785736 -281.739086) (xy 324.83552 -281.748992)
		)
		(stroke
			(width 0)
			(type solid)
		)
		(fill yes)
		(layer "F.Cu")
		(net "M_A_CPU0_SA_DQ<24>")
	)
	(gr_poly
		(pts
			(xy 324.887336 -265.858752) (xy 324.851522 -265.822938) (xy 324.753986 -265.776456) (xy 324.619366 -265.91133)
			(xy 324.665594 -266.008612) (xy 324.701408 -266.04468)
		)
		(stroke
			(width 0)
			(type solid)
		)
		(fill yes)
		(layer "F.Cu")
		(net "M_A_CPU0_SA_CB<5>")
	)
	(gr_poly
		(pts
			(xy 324.896734 -266.712446) (xy 324.86092 -266.676378) (xy 324.763384 -266.63015) (xy 324.628764 -266.76477)
			(xy 324.674992 -266.862306) (xy 324.71106 -266.89812)
		)
		(stroke
			(width 0)
			(type solid)
		)
		(fill yes)
		(layer "F.Cu")
		(net "M_A_CPU0_SA_CB<4>")
	)
	(gr_poly
		(pts
			(xy 324.917562 -278.98979) (xy 324.954646 -278.802846) (xy 324.861936 -278.747728) (xy 324.812152 -278.737822)
			(xy 324.760844 -278.995632) (xy 324.810628 -279.005538)
		)
		(stroke
			(width 0)
			(type solid)
		)
		(fill yes)
		(layer "F.Cu")
		(net "M_A_CPU0_SA_DQ<25>")
	)
	(gr_poly
		(pts
			(xy 324.936866 -279.675336) (xy 324.886828 -279.66543) (xy 324.780148 -279.681178) (xy 324.743064 -279.867868)
			(xy 324.83552 -279.92324) (xy 324.885558 -279.933146)
		)
		(stroke
			(width 0)
			(type solid)
		)
		(fill yes)
		(layer "F.Cu")
		(net "M_A_CPU0_SA_DQ<26>")
	)
	(gr_poly
		(pts
			(xy 324.964806 -265.565382) (xy 324.918578 -265.467846) (xy 324.88251 -265.432032) (xy 324.696836 -265.617706)
			(xy 324.73265 -265.653774) (xy 324.830186 -265.700002)
		)
		(stroke
			(width 0)
			(type solid)
		)
		(fill yes)
		(layer "F.Cu")
		(net "M_A_CPU0_SA_CB<7>")
	)
	(gr_poly
		(pts
			(xy 324.973442 -272.433034) (xy 324.937374 -272.39722) (xy 324.840092 -272.350992) (xy 324.705218 -272.485612)
			(xy 324.751446 -272.583148) (xy 324.787514 -272.618962)
		)
		(stroke
			(width 0)
			(type solid)
		)
		(fill yes)
		(layer "F.Cu")
		(net "M_A_CPU0_SA_DQ<31>")
	)
	(gr_poly
		(pts
			(xy 324.974204 -266.418822) (xy 324.927976 -266.32154) (xy 324.892162 -266.285472) (xy 324.706234 -266.4714)
			(xy 324.742048 -266.507468) (xy 324.839584 -266.553696)
		)
		(stroke
			(width 0)
			(type solid)
		)
		(fill yes)
		(layer "F.Cu")
		(net "M_A_CPU0_SA_CB<6>")
	)
	(gr_poly
		(pts
			(xy 324.977252 -223.210374) (xy 324.926452 -223.210374) (xy 324.824852 -223.246696) (xy 324.824852 -223.437196)
			(xy 324.926452 -223.473518) (xy 324.977252 -223.473518)
		)
		(stroke
			(width 0)
			(type solid)
		)
		(fill yes)
		(layer "F.Cu")
		(net "M_A_CPU0_SB_DQ<18>")
	)
	(gr_poly
		(pts
			(xy 324.977252 -222.613474) (xy 324.926452 -222.613474) (xy 324.824852 -222.649796) (xy 324.824852 -222.840296)
			(xy 324.926452 -222.876618) (xy 324.977252 -222.876618)
		)
		(stroke
			(width 0)
			(type solid)
		)
		(fill yes)
		(layer "F.Cu")
		(net "M_A_CPU0_SB_DQ<18>")
	)
	(gr_poly
		(pts
			(xy 324.977252 -222.016574) (xy 324.926452 -222.016574) (xy 324.824852 -222.052896) (xy 324.824852 -222.243396)
			(xy 324.926452 -222.279718) (xy 324.977252 -222.279718)
		)
		(stroke
			(width 0)
			(type solid)
		)
		(fill yes)
		(layer "F.Cu")
		(net "M_A_CPU0_SB_DQ<18>")
	)
	(gr_poly
		(pts
			(xy 324.977252 -221.419674) (xy 324.926452 -221.419674) (xy 324.824852 -221.455996) (xy 324.824852 -221.646496)
			(xy 324.926452 -221.682818) (xy 324.977252 -221.682818)
		)
		(stroke
			(width 0)
			(type solid)
		)
		(fill yes)
		(layer "F.Cu")
		(net "M_A_CPU0_SB_DQ<18>")
	)
	(gr_poly
		(pts
			(xy 324.977252 -220.822774) (xy 324.926452 -220.822774) (xy 324.824852 -220.859096) (xy 324.824852 -221.049596)
			(xy 324.926452 -221.085918) (xy 324.977252 -221.085918)
		)
		(stroke
			(width 0)
			(type solid)
		)
		(fill yes)
		(layer "F.Cu")
		(net "M_A_CPU0_SB_DQ<18>")
	)
	(gr_poly
		(pts
			(xy 324.977252 -220.225874) (xy 324.926452 -220.225874) (xy 324.824852 -220.262196) (xy 324.824852 -220.452696)
			(xy 324.926452 -220.489018) (xy 324.977252 -220.489018)
		)
		(stroke
			(width 0)
			(type solid)
		)
		(fill yes)
		(layer "F.Cu")
		(net "M_A_CPU0_SB_DQ<18>")
	)
	(gr_poly
		(pts
			(xy 324.983094 -273.286982) (xy 324.94728 -273.251168) (xy 324.849744 -273.204686) (xy 324.715124 -273.33956)
			(xy 324.761352 -273.436842) (xy 324.797166 -273.47291)
		)
		(stroke
			(width 0)
			(type solid)
		)
		(fill yes)
		(layer "F.Cu")
		(net "M_A_CPU0_SA_DQ<30>")
	)
	(gr_poly
		(pts
			(xy 324.983856 -280.220166) (xy 325.02094 -280.033222) (xy 324.92823 -279.97785) (xy 324.878446 -279.967944)
			(xy 324.827138 -280.225754) (xy 324.876922 -280.23566)
		)
		(stroke
			(width 0)
			(type solid)
		)
		(fill yes)
		(layer "F.Cu")
		(net "M_A_CPU0_SA_DQ<26>")
	)
	(gr_poly
		(pts
			(xy 324.987158 -277.85949) (xy 324.937374 -277.849584) (xy 324.830694 -277.865332) (xy 324.79361 -278.052276)
			(xy 324.886066 -278.107394) (xy 324.93585 -278.1173)
		)
		(stroke
			(width 0)
			(type solid)
		)
		(fill yes)
		(layer "F.Cu")
		(net "M_A_CPU0_SA_DQ<25>")
	)
	(gr_poly
		(pts
			(xy 325.00316 -280.905712) (xy 324.953376 -280.895806) (xy 324.846696 -280.911554) (xy 324.809612 -281.098244)
			(xy 324.902068 -281.153616) (xy 324.951852 -281.163522)
		)
		(stroke
			(width 0)
			(type solid)
		)
		(fill yes)
		(layer "F.Cu")
		(net "M_A_CPU0_SA_DQ<24>")
	)
	(gr_poly
		(pts
			(xy 325.033894 -278.40432) (xy 325.071232 -278.21763) (xy 324.978522 -278.162258) (xy 324.928738 -278.152352)
			(xy 324.87743 -278.410162) (xy 324.927214 -278.420068)
		)
		(stroke
			(width 0)
			(type solid)
		)
		(fill yes)
		(layer "F.Cu")
		(net "M_A_CPU0_SA_DQ<25>")
	)
	(gr_poly
		(pts
			(xy 325.05015 -281.450542) (xy 325.087488 -281.263598) (xy 324.994778 -281.20848) (xy 324.944994 -281.198574)
			(xy 324.893686 -281.456384) (xy 324.94347 -281.46629)
		)
		(stroke
			(width 0)
			(type solid)
		)
		(fill yes)
		(layer "F.Cu")
		(net "M_A_CPU0_SA_DQ<24>")
	)
	(gr_poly
		(pts
			(xy 325.053452 -279.089866) (xy 325.003668 -279.07996) (xy 324.896988 -279.095708) (xy 324.85965 -279.282398)
			(xy 324.95236 -279.33777) (xy 325.002144 -279.347676)
		)
		(stroke
			(width 0)
			(type solid)
		)
		(fill yes)
		(layer "F.Cu")
		(net "M_A_CPU0_SA_DQ<26>")
	)
	(gr_poly
		(pts
			(xy 325.06031 -272.993358) (xy 325.014082 -272.895822) (xy 324.978014 -272.860008) (xy 324.79234 -273.045682)
			(xy 324.828154 -273.08175) (xy 324.92569 -273.127978)
		)
		(stroke
			(width 0)
			(type solid)
		)
		(fill yes)
		(layer "F.Cu")
		(net "M_A_CPU0_SA_DQ<29>")
	)
	(gr_poly
		(pts
			(xy 325.07428 -276.62251) (xy 325.029322 -276.598634) (xy 324.922642 -276.582632) (xy 324.83298 -276.750526)
			(xy 324.90537 -276.830282) (xy 324.950328 -276.854412)
		)
		(stroke
			(width 0)
			(type solid)
		)
		(fill yes)
		(layer "F.Cu")
		(net "M_A_CPU0_SA_DQ<27>")
	)
	(gr_poly
		(pts
			(xy 325.093584 -265.220958) (xy 325.05777 -265.18489) (xy 324.960234 -265.138662) (xy 324.825614 -265.273536)
			(xy 324.871842 -265.370818) (xy 324.907656 -265.406886)
		)
		(stroke
			(width 0)
			(type solid)
		)
		(fill yes)
		(layer "F.Cu")
		(net "M_A_CPU0_SA_CB<7>")
	)
	(gr_poly
		(pts
			(xy 325.100188 -279.634696) (xy 325.137272 -279.447752) (xy 325.044816 -279.392634) (xy 324.995032 -279.382728)
			(xy 324.943724 -279.640538) (xy 324.993508 -279.650444)
		)
		(stroke
			(width 0)
			(type solid)
		)
		(fill yes)
		(layer "F.Cu")
		(net "M_A_CPU0_SA_DQ<26>")
	)
	(gr_poly
		(pts
			(xy 325.103236 -266.074398) (xy 325.067168 -266.038584) (xy 324.969886 -265.992356) (xy 324.835012 -266.126976)
			(xy 324.88124 -266.224512) (xy 324.917308 -266.260326)
		)
		(stroke
			(width 0)
			(type solid)
		)
		(fill yes)
		(layer "F.Cu")
		(net "M_A_CPU0_SA_CB<6>")
	)
	(gr_poly
		(pts
			(xy 325.11746 -269.511018) (xy 325.081646 -269.47495) (xy 324.98411 -269.428722) (xy 324.84949 -269.563596)
			(xy 324.895718 -269.660878) (xy 324.931532 -269.696946)
		)
		(stroke
			(width 0)
			(type solid)
		)
		(fill yes)
		(layer "F.Cu")
		(net "M_A_CPU0_SA_CB<2>")
	)
	(gr_poly
		(pts
			(xy 325.119746 -280.320242) (xy 325.069962 -280.310336) (xy 324.963282 -280.326084) (xy 324.925944 -280.513028)
			(xy 325.018654 -280.568146) (xy 325.068438 -280.578052)
		)
		(stroke
			(width 0)
			(type solid)
		)
		(fill yes)
		(layer "F.Cu")
		(net "M_A_CPU0_SA_DQ<24>")
	)
	(gr_poly
		(pts
			(xy 325.129652 -223.138746) (xy 325.129652 -222.948246) (xy 325.028052 -222.912178) (xy 324.977252 -222.912178)
			(xy 324.977252 -223.174814) (xy 325.028052 -223.174814)
		)
		(stroke
			(width 0)
			(type solid)
		)
		(fill yes)
		(layer "F.Cu")
		(net "M_A_CPU0_SB_DQ<18>")
	)
	(gr_poly
		(pts
			(xy 325.129652 -222.541846) (xy 325.129652 -222.351346) (xy 325.028052 -222.315278) (xy 324.977252 -222.315278)
			(xy 324.977252 -222.577914) (xy 325.028052 -222.577914)
		)
		(stroke
			(width 0)
			(type solid)
		)
		(fill yes)
		(layer "F.Cu")
		(net "M_A_CPU0_SB_DQ<18>")
	)
	(gr_poly
		(pts
			(xy 325.129652 -221.944946) (xy 325.129652 -221.754446) (xy 325.028052 -221.718378) (xy 324.977252 -221.718378)
			(xy 324.977252 -221.981014) (xy 325.028052 -221.981014)
		)
		(stroke
			(width 0)
			(type solid)
		)
		(fill yes)
		(layer "F.Cu")
		(net "M_A_CPU0_SB_DQ<18>")
	)
	(gr_poly
		(pts
			(xy 325.129652 -221.348046) (xy 325.129652 -221.157546) (xy 325.028052 -221.121478) (xy 324.977252 -221.121478)
			(xy 324.977252 -221.384114) (xy 325.028052 -221.384114)
		)
		(stroke
			(width 0)
			(type solid)
		)
		(fill yes)
		(layer "F.Cu")
		(net "M_A_CPU0_SB_DQ<18>")
	)
	(gr_poly
		(pts
			(xy 325.129652 -220.751146) (xy 325.129652 -220.560646) (xy 325.028052 -220.524578) (xy 324.977252 -220.524578)
			(xy 324.977252 -220.787214) (xy 325.028052 -220.787214)
		)
		(stroke
			(width 0)
			(type solid)
		)
		(fill yes)
		(layer "F.Cu")
		(net "M_A_CPU0_SB_DQ<18>")
	)
	(gr_poly
		(pts
			(xy 325.129652 -220.154246) (xy 325.129652 -219.963746) (xy 325.028052 -219.927678) (xy 324.977252 -219.927678)
			(xy 324.977252 -220.190314) (xy 325.028052 -220.190314)
		)
		(stroke
			(width 0)
			(type solid)
		)
		(fill yes)
		(layer "F.Cu")
		(net "M_A_CPU0_SB_DQ<18>")
	)
	(gr_poly
		(pts
			(xy 325.129652 -219.557346) (xy 325.129652 -219.366846) (xy 325.028052 -219.330778) (xy 324.977252 -219.330778)
			(xy 324.977252 -219.593414) (xy 325.028052 -219.593414)
		)
		(stroke
			(width 0)
			(type solid)
		)
		(fill yes)
		(layer "F.Cu")
		(net "M_A_CPU0_SB_DQ<18>")
	)
	(gr_poly
		(pts
			(xy 325.150734 -277.81885) (xy 325.187818 -277.63216) (xy 325.095362 -277.576788) (xy 325.045578 -277.566882)
			(xy 324.99427 -277.824692) (xy 325.044054 -277.834598)
		)
		(stroke
			(width 0)
			(type solid)
		)
		(fill yes)
		(layer "F.Cu")
		(net "M_A_CPU0_SA_DQ<25>")
	)
	(gr_poly
		(pts
			(xy 325.166736 -280.865072) (xy 325.20382 -280.678382) (xy 325.111364 -280.62301) (xy 325.06158 -280.613104)
			(xy 325.010272 -280.870914) (xy 325.060056 -280.88082)
		)
		(stroke
			(width 0)
			(type solid)
		)
		(fill yes)
		(layer "F.Cu")
		(net "M_A_CPU0_SA_DQ<24>")
	)
	(gr_poly
		(pts
			(xy 325.170038 -278.504396) (xy 325.120254 -278.49449) (xy 325.01332 -278.510238) (xy 324.976236 -278.697182)
			(xy 325.068946 -278.7523) (xy 325.11873 -278.762206)
		)
		(stroke
			(width 0)
			(type solid)
		)
		(fill yes)
		(layer "F.Cu")
		(net "M_A_CPU0_SA_DQ<26>")
	)
	(gr_poly
		(pts
			(xy 325.180452 -265.781028) (xy 325.134224 -265.683492) (xy 325.09841 -265.647678) (xy 324.912482 -265.833606)
			(xy 324.948296 -265.86942) (xy 325.045832 -265.915648)
		)
		(stroke
			(width 0)
			(type solid)
		)
		(fill yes)
		(layer "F.Cu")
		(net "M_A_CPU0_SA_CB<5>")
	)
	(gr_poly
		(pts
			(xy 325.181976 -224.3201) (xy 325.228204 -224.222564) (xy 325.09333 -224.087944) (xy 324.996048 -224.134172)
			(xy 324.95998 -224.169986) (xy 325.145908 -224.355914)
		)
		(stroke
			(width 0)
			(type solid)
		)
		(fill yes)
		(layer "F.Cu")
		(net "M_A_CPU0_SB_DQ<16>")
	)
	(gr_poly
		(pts
			(xy 325.189088 -272.648934) (xy 325.153274 -272.612866) (xy 325.055738 -272.566638) (xy 324.921118 -272.701512)
			(xy 324.967346 -272.798794) (xy 325.00316 -272.834862)
		)
		(stroke
			(width 0)
			(type solid)
		)
		(fill yes)
		(layer "F.Cu")
		(net "M_A_CPU0_SA_DQ<29>")
	)
	(gr_poly
		(pts
			(xy 325.190104 -266.634722) (xy 325.143876 -266.537186) (xy 325.107808 -266.501372) (xy 324.92188 -266.6873)
			(xy 324.957948 -266.723114) (xy 325.05523 -266.769342)
		)
		(stroke
			(width 0)
			(type solid)
		)
		(fill yes)
		(layer "F.Cu")
		(net "M_A_CPU0_SA_CB<4>")
	)
	(gr_poly
		(pts
			(xy 325.19493 -269.217394) (xy 325.148702 -269.120112) (xy 325.112888 -269.084044) (xy 324.92696 -269.269972)
			(xy 324.962774 -269.30604) (xy 325.06031 -269.352268)
		)
		(stroke
			(width 0)
			(type solid)
		)
		(fill yes)
		(layer "F.Cu")
		(net "M_A_CPU0_SA_CB<1>")
	)
	(gr_poly
		(pts
			(xy 325.19874 -273.502628) (xy 325.162926 -273.466814) (xy 325.06539 -273.420332) (xy 324.93077 -273.555206)
			(xy 324.976998 -273.652488) (xy 325.012812 -273.688556)
		)
		(stroke
			(width 0)
			(type solid)
		)
		(fill yes)
		(layer "F.Cu")
		(net "M_A_CPU0_SA_DQ<28>")
	)
	(gr_poly
		(pts
			(xy 325.216774 -279.049226) (xy 325.253858 -278.862536) (xy 325.161402 -278.807164) (xy 325.111364 -278.797258)
			(xy 325.060056 -279.055068) (xy 325.110094 -279.064974)
		)
		(stroke
			(width 0)
			(type solid)
		)
		(fill yes)
		(layer "F.Cu")
		(net "M_A_CPU0_SA_DQ<26>")
	)
	(gr_poly
		(pts
			(xy 325.236078 -279.734772) (xy 325.186294 -279.724866) (xy 325.079614 -279.740614) (xy 325.04253 -279.927558)
			(xy 325.134986 -279.98293) (xy 325.18477 -279.992836)
		)
		(stroke
			(width 0)
			(type solid)
		)
		(fill yes)
		(layer "F.Cu")
		(net "M_A_CPU0_SA_DQ<24>")
	)
	(gr_poly
		(pts
			(xy 325.266558 -272.35531) (xy 325.22033 -272.258028) (xy 325.184516 -272.22196) (xy 324.998588 -272.407888)
			(xy 325.034402 -272.443956) (xy 325.131938 -272.490184)
		)
		(stroke
			(width 0)
			(type solid)
		)
		(fill yes)
		(layer "F.Cu")
		(net "M_A_CPU0_SA_DQ<31>")
	)
	(gr_poly
		(pts
			(xy 325.27621 -273.209258) (xy 325.229982 -273.111976) (xy 325.194168 -273.075908) (xy 325.00824 -273.261836)
			(xy 325.044054 -273.29765) (xy 325.14159 -273.343878)
		)
		(stroke
			(width 0)
			(type solid)
		)
		(fill yes)
		(layer "F.Cu")
		(net "M_A_CPU0_SA_DQ<30>")
	)
	(gr_poly
		(pts
			(xy 325.282052 -223.210374) (xy 325.231252 -223.210374) (xy 325.129652 -223.246696) (xy 325.129652 -223.437196)
			(xy 325.231252 -223.473518) (xy 325.282052 -223.473518)
		)
		(stroke
			(width 0)
			(type solid)
		)
		(fill yes)
		(layer "F.Cu")
		(net "M_A_CPU0_SB_DQ<17>")
	)
	(gr_poly
		(pts
			(xy 325.282052 -222.613474) (xy 325.231252 -222.613474) (xy 325.129652 -222.649796) (xy 325.129652 -222.840296)
			(xy 325.231252 -222.876618) (xy 325.282052 -222.876618)
		)
		(stroke
			(width 0)
			(type solid)
		)
		(fill yes)
		(layer "F.Cu")
		(net "M_A_CPU0_SB_DQ<17>")
	)
	(gr_poly
		(pts
			(xy 325.282052 -222.016574) (xy 325.231252 -222.016574) (xy 325.129652 -222.052896) (xy 325.129652 -222.243396)
			(xy 325.231252 -222.279718) (xy 325.282052 -222.279718)
		)
		(stroke
			(width 0)
			(type solid)
		)
		(fill yes)
		(layer "F.Cu")
		(net "M_A_CPU0_SB_DQ<17>")
	)
	(gr_poly
		(pts
			(xy 325.282052 -221.419674) (xy 325.231252 -221.419674) (xy 325.129652 -221.455996) (xy 325.129652 -221.646496)
			(xy 325.231252 -221.682818) (xy 325.282052 -221.682818)
		)
		(stroke
			(width 0)
			(type solid)
		)
		(fill yes)
		(layer "F.Cu")
		(net "M_A_CPU0_SB_DQ<17>")
	)
	(gr_poly
		(pts
			(xy 325.282052 -220.822774) (xy 325.231252 -220.822774) (xy 325.129652 -220.859096) (xy 325.129652 -221.049596)
			(xy 325.231252 -221.085918) (xy 325.282052 -221.085918)
		)
		(stroke
			(width 0)
			(type solid)
		)
		(fill yes)
		(layer "F.Cu")
		(net "M_A_CPU0_SB_DQ<17>")
	)
	(gr_poly
		(pts
			(xy 325.282052 -220.225874) (xy 325.231252 -220.225874) (xy 325.129652 -220.262196) (xy 325.129652 -220.452696)
			(xy 325.231252 -220.489018) (xy 325.282052 -220.489018)
		)
		(stroke
			(width 0)
			(type solid)
		)
		(fill yes)
		(layer "F.Cu")
		(net "M_A_CPU0_SB_DQ<17>")
	)
	(gr_poly
		(pts
			(xy 325.282052 -219.628974) (xy 325.231252 -219.628974) (xy 325.129652 -219.665296) (xy 325.129652 -219.855796)
			(xy 325.231252 -219.892118) (xy 325.282052 -219.892118)
		)
		(stroke
			(width 0)
			(type solid)
		)
		(fill yes)
		(layer "F.Cu")
		(net "M_A_CPU0_SB_DQ<17>")
	)
	(gr_poly
		(pts
			(xy 325.283068 -280.279602) (xy 325.320406 -280.092912) (xy 325.227696 -280.03754) (xy 325.177912 -280.027634)
			(xy 325.126604 -280.285444) (xy 325.176388 -280.29535)
		)
		(stroke
			(width 0)
			(type solid)
		)
		(fill yes)
		(layer "F.Cu")
		(net "M_A_CPU0_SA_DQ<24>")
	)
	(gr_poly
		(pts
			(xy 325.286116 -277.918926) (xy 325.236332 -277.90902) (xy 325.129652 -277.924768) (xy 325.092568 -278.111712)
			(xy 325.185024 -278.167084) (xy 325.234808 -278.17699)
		)
		(stroke
			(width 0)
			(type solid)
		)
		(fill yes)
		(layer "F.Cu")
		(net "M_A_CPU0_SA_DQ<26>")
	)
	(gr_poly
		(pts
			(xy 325.309484 -265.436604) (xy 325.273416 -265.40079) (xy 325.176134 -265.354562) (xy 325.04126 -265.489182)
			(xy 325.087488 -265.586718) (xy 325.123556 -265.622532)
		)
		(stroke
			(width 0)
			(type solid)
		)
		(fill yes)
		(layer "F.Cu")
		(net "M_A_CPU0_SA_CB<5>")
	)
	(gr_poly
		(pts
			(xy 325.318882 -266.290298) (xy 325.283068 -266.254484) (xy 325.185532 -266.208002) (xy 325.050912 -266.342876)
			(xy 325.09714 -266.440158) (xy 325.132954 -266.476226)
		)
		(stroke
			(width 0)
			(type solid)
		)
		(fill yes)
		(layer "F.Cu")
		(net "M_A_CPU0_SA_CB<4>")
	)
	(gr_poly
		(pts
			(xy 325.321168 -224.602802) (xy 325.356982 -224.566988) (xy 325.171054 -224.38106) (xy 325.13524 -224.417128)
			(xy 325.089012 -224.51441) (xy 325.223632 -224.649284)
		)
		(stroke
			(width 0)
			(type solid)
		)
		(fill yes)
		(layer "F.Cu")
		(net "M_A_CPU0_SB_DQ<16>")
	)
	(gr_poly
		(pts
			(xy 325.323708 -268.873224) (xy 325.287894 -268.837156) (xy 325.190358 -268.790928) (xy 325.055738 -268.925548)
			(xy 325.101966 -269.023084) (xy 325.138034 -269.058898)
		)
		(stroke
			(width 0)
			(type solid)
		)
		(fill yes)
		(layer "F.Cu")
		(net "M_A_CPU0_SA_CB<1>")
	)
	(gr_poly
		(pts
			(xy 325.332344 -276.462998) (xy 325.2597 -276.383242) (xy 325.214996 -276.359366) (xy 325.091044 -276.591014)
			(xy 325.135748 -276.615144) (xy 325.242428 -276.631146)
		)
		(stroke
			(width 0)
			(type solid)
		)
		(fill yes)
		(layer "F.Cu")
		(net "M_A_CPU0_SA_DQ<27>")
	)
	(gr_poly
		(pts
			(xy 325.333106 -278.463756) (xy 325.370444 -278.277066) (xy 325.277734 -278.221694) (xy 325.22795 -278.211788)
			(xy 325.176642 -278.469598) (xy 325.226426 -278.479504)
		)
		(stroke
			(width 0)
			(type solid)
		)
		(fill yes)
		(layer "F.Cu")
		(net "M_A_CPU0_SA_DQ<26>")
	)
	(gr_poly
		(pts
			(xy 325.333106 -269.726664) (xy 325.297292 -269.690596) (xy 325.199756 -269.644368) (xy 325.065136 -269.779242)
			(xy 325.111364 -269.876524) (xy 325.147178 -269.912592)
		)
		(stroke
			(width 0)
			(type solid)
		)
		(fill yes)
		(layer "F.Cu")
		(net "M_A_CPU0_SA_CB<0>")
	)
	(gr_poly
		(pts
			(xy 325.343266 -276.766274) (xy 325.298562 -276.742398) (xy 325.191882 -276.726396) (xy 325.10222 -276.89429)
			(xy 325.17461 -276.9743) (xy 325.219568 -276.998176)
		)
		(stroke
			(width 0)
			(type solid)
		)
		(fill yes)
		(layer "F.Cu")
		(net "M_A_CPU0_SA_DQ<25>")
	)
	(gr_poly
		(pts
			(xy 325.352664 -279.149556) (xy 325.30288 -279.13965) (xy 325.1962 -279.155144) (xy 325.158862 -279.342088)
			(xy 325.251572 -279.39746) (xy 325.301356 -279.407366)
		)
		(stroke
			(width 0)
			(type solid)
		)
		(fill yes)
		(layer "F.Cu")
		(net "M_A_CPU0_SA_DQ<24>")
	)
	(gr_poly
		(pts
			(xy 325.355712 -276.095968) (xy 325.310754 -276.072092) (xy 325.204074 -276.05609) (xy 325.114412 -276.224238)
			(xy 325.186802 -276.303994) (xy 325.23176 -276.32787)
		)
		(stroke
			(width 0)
			(type solid)
		)
		(fill yes)
		(layer "F.Cu")
		(net "M_A_CPU0_SA_DQ<27>")
	)
	(gr_poly
		(pts
			(xy 325.386954 -265.143234) (xy 325.340726 -265.045698) (xy 325.304658 -265.009884) (xy 325.11873 -265.195812)
			(xy 325.154798 -265.231626) (xy 325.25208 -265.277854)
		)
		(stroke
			(width 0)
			(type solid)
		)
		(fill yes)
		(layer "F.Cu")
		(net "M_A_CPU0_SA_CB<7>")
	)
	(gr_poly
		(pts
			(xy 325.395336 -272.01114) (xy 325.359522 -271.975072) (xy 325.261986 -271.928844) (xy 325.127366 -272.063464)
			(xy 325.173594 -272.161) (xy 325.209662 -272.196814)
		)
		(stroke
			(width 0)
			(type solid)
		)
		(fill yes)
		(layer "F.Cu")
		(net "M_A_CPU0_SA_DQ<31>")
	)
	(gr_poly
		(pts
			(xy 325.396352 -265.996928) (xy 325.350124 -265.899392) (xy 325.314056 -265.863578) (xy 325.128382 -266.049252)
			(xy 325.164196 -266.08532) (xy 325.261732 -266.131548)
		)
		(stroke
			(width 0)
			(type solid)
		)
		(fill yes)
		(layer "F.Cu")
		(net "M_A_CPU0_SA_CB<6>")
	)
	(gr_poly
		(pts
			(xy 325.397622 -224.104454) (xy 325.44385 -224.006918) (xy 325.308976 -223.872298) (xy 325.211694 -223.918526)
			(xy 325.175626 -223.95434) (xy 325.361554 -224.140268)
		)
		(stroke
			(width 0)
			(type solid)
		)
		(fill yes)
		(layer "F.Cu")
		(net "M_A_CPU0_SB_DQ<18>")
	)
	(gr_poly
		(pts
			(xy 325.399654 -279.694386) (xy 325.436738 -279.507442) (xy 325.344282 -279.45207) (xy 325.294498 -279.442164)
			(xy 325.24319 -279.699974) (xy 325.292974 -279.70988)
		)
		(stroke
			(width 0)
			(type solid)
		)
		(fill yes)
		(layer "F.Cu")
		(net "M_A_CPU0_SA_DQ<24>")
	)
	(gr_poly
		(pts
			(xy 325.401432 -268.579854) (xy 325.355204 -268.482318) (xy 325.319136 -268.446504) (xy 325.133208 -268.632432)
			(xy 325.169276 -268.668246) (xy 325.266558 -268.714474)
		)
		(stroke
			(width 0)
			(type solid)
		)
		(fill yes)
		(layer "F.Cu")
		(net "M_A_CPU0_SA_CB<3>")
	)
	(gr_poly
		(pts
			(xy 325.405242 -272.864834) (xy 325.369174 -272.82902) (xy 325.271892 -272.782792) (xy 325.137018 -272.917412)
			(xy 325.183246 -273.014948) (xy 325.219314 -273.050762)
		)
		(stroke
			(width 0)
			(type solid)
		)
		(fill yes)
		(layer "F.Cu")
		(net "M_A_CPU0_SA_DQ<30>")
	)
	(gr_poly
		(pts
			(xy 325.406258 -246.323612) (xy 325.406258 -246.272812) (xy 325.143368 -246.272812) (xy 325.143368 -246.323612)
			(xy 325.179436 -246.425212) (xy 325.369936 -246.425212)
		)
		(stroke
			(width 0)
			(type solid)
		)
		(fill yes)
		(layer "F.Cu")
		(net "M_A_CPU0_SB_CS_N<3>")
	)
	(gr_poly
		(pts
			(xy 325.406258 -246.018812) (xy 325.406258 -245.968012) (xy 325.143368 -245.968012) (xy 325.143368 -246.018812)
			(xy 325.179436 -246.120412) (xy 325.369936 -246.120412)
		)
		(stroke
			(width 0)
			(type solid)
		)
		(fill yes)
		(layer "F.Cu")
		(net "M_A_CPU0_SB_CS_N<1>")
	)
	(gr_poly
		(pts
			(xy 325.41083 -269.433294) (xy 325.364348 -269.335758) (xy 325.328534 -269.299944) (xy 325.142606 -269.485872)
			(xy 325.178674 -269.521686) (xy 325.275956 -269.567914)
		)
		(stroke
			(width 0)
			(type solid)
		)
		(fill yes)
		(layer "F.Cu")
		(net "M_A_CPU0_SA_CB<2>")
	)
	(gr_poly
		(pts
			(xy 325.434452 -223.138746) (xy 325.434452 -222.948246) (xy 325.332852 -222.912178) (xy 325.282052 -222.912178)
			(xy 325.282052 -223.174814) (xy 325.332852 -223.174814)
		)
		(stroke
			(width 0)
			(type solid)
		)
		(fill yes)
		(layer "F.Cu")
		(net "M_A_CPU0_SB_DQ<17>")
	)
	(gr_poly
		(pts
			(xy 325.434452 -222.541846) (xy 325.434452 -222.351346) (xy 325.332852 -222.315278) (xy 325.282052 -222.315278)
			(xy 325.282052 -222.577914) (xy 325.332852 -222.577914)
		)
		(stroke
			(width 0)
			(type solid)
		)
		(fill yes)
		(layer "F.Cu")
		(net "M_A_CPU0_SB_DQ<17>")
	)
	(gr_poly
		(pts
			(xy 325.434452 -221.944946) (xy 325.434452 -221.754446) (xy 325.332852 -221.718378) (xy 325.282052 -221.718378)
			(xy 325.282052 -221.981014) (xy 325.332852 -221.981014)
		)
		(stroke
			(width 0)
			(type solid)
		)
		(fill yes)
		(layer "F.Cu")
		(net "M_A_CPU0_SB_DQ<17>")
	)
	(gr_poly
		(pts
			(xy 325.434452 -221.348046) (xy 325.434452 -221.157546) (xy 325.332852 -221.121478) (xy 325.282052 -221.121478)
			(xy 325.282052 -221.384114) (xy 325.332852 -221.384114)
		)
		(stroke
			(width 0)
			(type solid)
		)
		(fill yes)
		(layer "F.Cu")
		(net "M_A_CPU0_SB_DQ<17>")
	)
	(gr_poly
		(pts
			(xy 325.434452 -220.751146) (xy 325.434452 -220.560646) (xy 325.332852 -220.524578) (xy 325.282052 -220.524578)
			(xy 325.282052 -220.787214) (xy 325.332852 -220.787214)
		)
		(stroke
			(width 0)
			(type solid)
		)
		(fill yes)
		(layer "F.Cu")
		(net "M_A_CPU0_SB_DQ<17>")
	)
	(gr_poly
		(pts
			(xy 325.434452 -220.154246) (xy 325.434452 -219.963746) (xy 325.332852 -219.927678) (xy 325.282052 -219.927678)
			(xy 325.282052 -220.190314) (xy 325.332852 -220.190314)
		)
		(stroke
			(width 0)
			(type solid)
		)
		(fill yes)
		(layer "F.Cu")
		(net "M_A_CPU0_SB_DQ<17>")
	)
	(gr_poly
		(pts
			(xy 325.434452 -219.557346) (xy 325.434452 -219.366846) (xy 325.332852 -219.330778) (xy 325.282052 -219.330778)
			(xy 325.282052 -219.593414) (xy 325.332852 -219.593414)
		)
		(stroke
			(width 0)
			(type solid)
		)
		(fill yes)
		(layer "F.Cu")
		(net "M_A_CPU0_SB_DQ<17>")
	)
	(gr_poly
		(pts
			(xy 325.449692 -277.87854) (xy 325.486776 -277.691596) (xy 325.39432 -277.636224) (xy 325.344536 -277.626318)
			(xy 325.293228 -277.884128) (xy 325.343012 -277.894034)
		)
		(stroke
			(width 0)
			(type solid)
		)
		(fill yes)
		(layer "F.Cu")
		(net "M_A_CPU0_SA_DQ<26>")
	)
	(gr_poly
		(pts
			(xy 325.468996 -278.564086) (xy 325.419212 -278.55418) (xy 325.312532 -278.569928) (xy 325.275448 -278.756618)
			(xy 325.367904 -278.81199) (xy 325.417942 -278.821896)
		)
		(stroke
			(width 0)
			(type solid)
		)
		(fill yes)
		(layer "F.Cu")
		(net "M_A_CPU0_SA_DQ<24>")
	)
	(gr_poly
		(pts
			(xy 325.482458 -272.57121) (xy 325.435976 -272.473674) (xy 325.400162 -272.43786) (xy 325.214234 -272.623788)
			(xy 325.250302 -272.659602) (xy 325.347584 -272.70583)
		)
		(stroke
			(width 0)
			(type solid)
		)
		(fill yes)
		(layer "F.Cu")
		(net "M_A_CPU0_SA_DQ<29>")
	)
	(gr_poly
		(pts
			(xy 325.491856 -273.424904) (xy 325.445628 -273.327622) (xy 325.409814 -273.291554) (xy 325.223886 -273.477482)
			(xy 325.2597 -273.513296) (xy 325.357236 -273.559524)
		)
		(stroke
			(width 0)
			(type solid)
		)
		(fill yes)
		(layer "F.Cu")
		(net "M_A_CPU0_SA_DQ<28>")
	)
	(gr_poly
		(pts
			(xy 325.515732 -264.79881) (xy 325.479918 -264.762996) (xy 325.382382 -264.716768) (xy 325.247762 -264.851388)
			(xy 325.29399 -264.94867) (xy 325.329804 -264.984738)
		)
		(stroke
			(width 0)
			(type solid)
		)
		(fill yes)
		(layer "F.Cu")
		(net "M_A_CPU0_SA_CB<7>")
	)
	(gr_poly
		(pts
			(xy 325.51624 -279.108916) (xy 325.553324 -278.921972) (xy 325.460614 -278.8666) (xy 325.41083 -278.856694)
			(xy 325.359522 -279.114504) (xy 325.409306 -279.12441)
		)
		(stroke
			(width 0)
			(type solid)
		)
		(fill yes)
		(layer "F.Cu")
		(net "M_A_CPU0_SA_DQ<24>")
	)
	(gr_poly
		(pts
			(xy 325.51878 -284.600904) (xy 325.46798 -284.600904) (xy 325.36638 -284.637226) (xy 325.36638 -284.827726)
			(xy 325.46798 -284.863794) (xy 325.51878 -284.863794)
		)
		(stroke
			(width 0)
			(type solid)
		)
		(fill yes)
		(layer "F.Cu")
		(net "M_A_CPU0_SA_DQ<23>")
	)
	(gr_poly
		(pts
			(xy 325.51878 -284.004004) (xy 325.46798 -284.004004) (xy 325.36638 -284.040326) (xy 325.36638 -284.230826)
			(xy 325.46798 -284.266894) (xy 325.51878 -284.266894)
		)
		(stroke
			(width 0)
			(type solid)
		)
		(fill yes)
		(layer "F.Cu")
		(net "M_A_CPU0_SA_DQ<23>")
	)
	(gr_poly
		(pts
			(xy 325.51878 -283.407104) (xy 325.46798 -283.407104) (xy 325.36638 -283.443426) (xy 325.36638 -283.633926)
			(xy 325.46798 -283.669994) (xy 325.51878 -283.669994)
		)
		(stroke
			(width 0)
			(type solid)
		)
		(fill yes)
		(layer "F.Cu")
		(net "M_A_CPU0_SA_DQ<23>")
	)
	(gr_poly
		(pts
			(xy 325.51878 -282.810204) (xy 325.46798 -282.810204) (xy 325.36638 -282.846526) (xy 325.36638 -283.037026)
			(xy 325.46798 -283.073094) (xy 325.51878 -283.073094)
		)
		(stroke
			(width 0)
			(type solid)
		)
		(fill yes)
		(layer "F.Cu")
		(net "M_A_CPU0_SA_DQ<23>")
	)
	(gr_poly
		(pts
			(xy 325.51878 -282.213304) (xy 325.46798 -282.213304) (xy 325.36638 -282.249626) (xy 325.36638 -282.440126)
			(xy 325.46798 -282.476194) (xy 325.51878 -282.476194)
		)
		(stroke
			(width 0)
			(type solid)
		)
		(fill yes)
		(layer "F.Cu")
		(net "M_A_CPU0_SA_DQ<23>")
	)
	(gr_poly
		(pts
			(xy 325.51878 -281.616404) (xy 325.46798 -281.616404) (xy 325.36638 -281.652726) (xy 325.36638 -281.843226)
			(xy 325.46798 -281.879294) (xy 325.51878 -281.879294)
		)
		(stroke
			(width 0)
			(type solid)
		)
		(fill yes)
		(layer "F.Cu")
		(net "M_A_CPU0_SA_DQ<23>")
	)
	(gr_poly
		(pts
			(xy 325.52513 -265.652504) (xy 325.489316 -265.616436) (xy 325.39178 -265.570208) (xy 325.25716 -265.705082)
			(xy 325.303388 -265.802364) (xy 325.339202 -265.838432)
		)
		(stroke
			(width 0)
			(type solid)
		)
		(fill yes)
		(layer "F.Cu")
		(net "M_A_CPU0_SA_CB<6>")
	)
	(gr_poly
		(pts
			(xy 325.53021 -268.23543) (xy 325.494396 -268.199362) (xy 325.39686 -268.153134) (xy 325.26224 -268.288008)
			(xy 325.308468 -268.38529) (xy 325.344282 -268.421358)
		)
		(stroke
			(width 0)
			(type solid)
		)
		(fill yes)
		(layer "F.Cu")
		(net "M_A_CPU0_SA_CB<3>")
	)
	(gr_poly
		(pts
			(xy 325.536814 -224.387156) (xy 325.572628 -224.351342) (xy 325.3867 -224.165414) (xy 325.350886 -224.201482)
			(xy 325.304658 -224.298764) (xy 325.439278 -224.433638)
		)
		(stroke
			(width 0)
			(type solid)
		)
		(fill yes)
		(layer "F.Cu")
		(net "M_A_CPU0_SB_DQ<18>")
	)
	(gr_poly
		(pts
			(xy 325.539608 -269.08887) (xy 325.503794 -269.053056) (xy 325.406258 -269.006828) (xy 325.271638 -269.141448)
			(xy 325.317866 -269.238984) (xy 325.35368 -269.274798)
		)
		(stroke
			(width 0)
			(type solid)
		)
		(fill yes)
		(layer "F.Cu")
		(net "M_A_CPU0_SA_CB<2>")
	)
	(gr_poly
		(pts
			(xy 325.585582 -277.978616) (xy 325.535798 -277.96871) (xy 325.429118 -277.984458) (xy 325.39178 -278.171148)
			(xy 325.48449 -278.22652) (xy 325.534274 -278.236426)
		)
		(stroke
			(width 0)
			(type solid)
		)
		(fill yes)
		(layer "F.Cu")
		(net "M_A_CPU0_SA_DQ<24>")
	)
	(gr_poly
		(pts
			(xy 325.586852 -222.613474) (xy 325.536052 -222.613474) (xy 325.434452 -222.649796) (xy 325.434452 -222.840296)
			(xy 325.536052 -222.876618) (xy 325.586852 -222.876618)
		)
		(stroke
			(width 0)
			(type solid)
		)
		(fill yes)
		(layer "F.Cu")
		(net "M_A_CPU0_SB_DQ<19>")
	)
	(gr_poly
		(pts
			(xy 325.586852 -222.016574) (xy 325.536052 -222.016574) (xy 325.434452 -222.052896) (xy 325.434452 -222.243396)
			(xy 325.536052 -222.279718) (xy 325.586852 -222.279718)
		)
		(stroke
			(width 0)
			(type solid)
		)
		(fill yes)
		(layer "F.Cu")
		(net "M_A_CPU0_SB_DQ<19>")
	)
	(gr_poly
		(pts
			(xy 325.586852 -221.419674) (xy 325.536052 -221.419674) (xy 325.434452 -221.455996) (xy 325.434452 -221.646496)
			(xy 325.536052 -221.682818) (xy 325.586852 -221.682818)
		)
		(stroke
			(width 0)
			(type solid)
		)
		(fill yes)
		(layer "F.Cu")
		(net "M_A_CPU0_SB_DQ<19>")
	)
	(gr_poly
		(pts
			(xy 325.586852 -220.822774) (xy 325.536052 -220.822774) (xy 325.434452 -220.859096) (xy 325.434452 -221.049596)
			(xy 325.536052 -221.085918) (xy 325.586852 -221.085918)
		)
		(stroke
			(width 0)
			(type solid)
		)
		(fill yes)
		(layer "F.Cu")
		(net "M_A_CPU0_SB_DQ<19>")
	)
	(gr_poly
		(pts
			(xy 325.586852 -220.225874) (xy 325.536052 -220.225874) (xy 325.434452 -220.262196) (xy 325.434452 -220.452696)
			(xy 325.536052 -220.489018) (xy 325.586852 -220.489018)
		)
		(stroke
			(width 0)
			(type solid)
		)
		(fill yes)
		(layer "F.Cu")
		(net "M_A_CPU0_SB_DQ<19>")
	)
	(gr_poly
		(pts
			(xy 325.586852 -219.628974) (xy 325.536052 -219.628974) (xy 325.434452 -219.665296) (xy 325.434452 -219.855796)
			(xy 325.536052 -219.892118) (xy 325.586852 -219.892118)
		)
		(stroke
			(width 0)
			(type solid)
		)
		(fill yes)
		(layer "F.Cu")
		(net "M_A_CPU0_SB_DQ<19>")
	)
	(gr_poly
		(pts
			(xy 325.586852 -219.032074) (xy 325.536052 -219.032074) (xy 325.434452 -219.068396) (xy 325.434452 -219.258896)
			(xy 325.536052 -219.295218) (xy 325.586852 -219.295218)
		)
		(stroke
			(width 0)
			(type solid)
		)
		(fill yes)
		(layer "F.Cu")
		(net "M_A_CPU0_SB_DQ<19>")
	)
	(gr_poly
		(pts
			(xy 325.586852 -218.435174) (xy 325.536052 -218.435174) (xy 325.434452 -218.471496) (xy 325.434452 -218.661996)
			(xy 325.536052 -218.698318) (xy 325.586852 -218.698318)
		)
		(stroke
			(width 0)
			(type solid)
		)
		(fill yes)
		(layer "F.Cu")
		(net "M_A_CPU0_SB_DQ<19>")
	)
	(gr_poly
		(pts
			(xy 325.60133 -276.606762) (xy 325.52894 -276.527006) (xy 325.483982 -276.50313) (xy 325.36003 -276.735032)
			(xy 325.404988 -276.758908) (xy 325.511668 -276.77491)
		)
		(stroke
			(width 0)
			(type solid)
		)
		(fill yes)
		(layer "F.Cu")
		(net "M_A_CPU0_SA_DQ<25>")
	)
	(gr_poly
		(pts
			(xy 325.6026 -265.35888) (xy 325.556372 -265.261598) (xy 325.520558 -265.22553) (xy 325.33463 -265.411458)
			(xy 325.370444 -265.447526) (xy 325.46798 -265.493754)
		)
		(stroke
			(width 0)
			(type solid)
		)
		(fill yes)
		(layer "F.Cu")
		(net "M_A_CPU0_SA_CB<5>")
	)
	(gr_poly
		(pts
			(xy 325.60387 -224.742248) (xy 325.650098 -224.644712) (xy 325.515478 -224.510092) (xy 325.417942 -224.55632)
			(xy 325.382128 -224.592134) (xy 325.568056 -224.778062)
		)
		(stroke
			(width 0)
			(type solid)
		)
		(fill yes)
		(layer "F.Cu")
		(net "M_A_CPU0_SB_DQ<16>")
	)
	(gr_poly
		(pts
			(xy 325.611236 -272.226786) (xy 325.575422 -272.190972) (xy 325.477886 -272.144744) (xy 325.343266 -272.279364)
			(xy 325.389494 -272.3769) (xy 325.425308 -272.412714)
		)
		(stroke
			(width 0)
			(type solid)
		)
		(fill yes)
		(layer "F.Cu")
		(net "M_A_CPU0_SA_DQ<29>")
	)
	(gr_poly
		(pts
			(xy 325.611998 -266.212574) (xy 325.56577 -266.115038) (xy 325.529956 -266.079224) (xy 325.344028 -266.265152)
			(xy 325.379842 -266.300966) (xy 325.477378 -266.347194)
		)
		(stroke
			(width 0)
			(type solid)
		)
		(fill yes)
		(layer "F.Cu")
		(net "M_A_CPU0_SA_CB<4>")
	)
	(gr_poly
		(pts
			(xy 325.612252 -276.910038) (xy 325.567548 -276.886162) (xy 325.460868 -276.87016) (xy 325.370952 -277.038054)
			(xy 325.443596 -277.118064) (xy 325.4883 -277.14194)
		)
		(stroke
			(width 0)
			(type solid)
		)
		(fill yes)
		(layer "F.Cu")
		(net "M_A_CPU0_SA_DQ<26>")
	)
	(gr_poly
		(pts
			(xy 325.613268 -223.888808) (xy 325.659496 -223.791272) (xy 325.524622 -223.656652) (xy 325.42734 -223.70288)
			(xy 325.391272 -223.738694) (xy 325.5772 -223.924622)
		)
		(stroke
			(width 0)
			(type solid)
		)
		(fill yes)
		(layer "F.Cu")
		(net "M_A_CPU0_SB_DQ<17>")
	)
	(gr_poly
		(pts
			(xy 325.613522 -275.93671) (xy 325.541132 -275.8567) (xy 325.496174 -275.832824) (xy 325.372476 -276.064726)
			(xy 325.41718 -276.088602) (xy 325.52386 -276.104604)
		)
		(stroke
			(width 0)
			(type solid)
		)
		(fill yes)
		(layer "F.Cu")
		(net "M_A_CPU0_SA_DQ<27>")
	)
	(gr_poly
		(pts
			(xy 325.617078 -268.7955) (xy 325.57085 -268.697964) (xy 325.534782 -268.66215) (xy 325.348854 -268.848078)
			(xy 325.384922 -268.883892) (xy 325.482204 -268.93012)
		)
		(stroke
			(width 0)
			(type solid)
		)
		(fill yes)
		(layer "F.Cu")
		(net "M_A_CPU0_SA_CB<1>")
	)
	(gr_poly
		(pts
			(xy 325.620888 -273.08048) (xy 325.58482 -273.044666) (xy 325.487538 -272.998438) (xy 325.352664 -273.133058)
			(xy 325.398892 -273.230594) (xy 325.43496 -273.266408)
		)
		(stroke
			(width 0)
			(type solid)
		)
		(fill yes)
		(layer "F.Cu")
		(net "M_A_CPU0_SA_DQ<28>")
	)
	(gr_poly
		(pts
			(xy 325.624698 -276.239986) (xy 325.579994 -276.215856) (xy 325.473314 -276.199854) (xy 325.383398 -276.368002)
			(xy 325.456042 -276.447758) (xy 325.500746 -276.471634)
		)
		(stroke
			(width 0)
			(type solid)
		)
		(fill yes)
		(layer "F.Cu")
		(net "M_A_CPU0_SA_DQ<25>")
	)
	(gr_poly
		(pts
			(xy 325.626476 -269.64894) (xy 325.579994 -269.551404) (xy 325.54418 -269.51559) (xy 325.358252 -269.701518)
			(xy 325.39432 -269.737332) (xy 325.491602 -269.78356)
		)
		(stroke
			(width 0)
			(type solid)
		)
		(fill yes)
		(layer "F.Cu")
		(net "M_A_CPU0_SA_CB<0>")
	)
	(gr_poly
		(pts
			(xy 325.632572 -278.523446) (xy 325.669656 -278.336502) (xy 325.5772 -278.28113) (xy 325.527416 -278.271224)
			(xy 325.476108 -278.529288) (xy 325.525892 -278.539194)
		)
		(stroke
			(width 0)
			(type solid)
		)
		(fill yes)
		(layer "F.Cu")
		(net "M_A_CPU0_SA_DQ<24>")
	)
	(gr_poly
		(pts
			(xy 325.63689 -275.56968) (xy 325.592186 -275.545804) (xy 325.485506 -275.529802) (xy 325.395844 -275.697696)
			(xy 325.468234 -275.777452) (xy 325.512938 -275.801582)
		)
		(stroke
			(width 0)
			(type solid)
		)
		(fill yes)
		(layer "F.Cu")
		(net "M_A_CPU0_SA_DQ<27>")
	)
	(gr_poly
		(pts
			(xy 325.67118 -285.125922) (xy 325.67118 -284.935422) (xy 325.56958 -284.899354) (xy 325.51878 -284.899354)
			(xy 325.51878 -285.162244) (xy 325.56958 -285.162244)
		)
		(stroke
			(width 0)
			(type solid)
		)
		(fill yes)
		(layer "F.Cu")
		(net "M_A_CPU0_SA_DQ<23>")
	)
	(gr_poly
		(pts
			(xy 325.67118 -284.529022) (xy 325.67118 -284.338522) (xy 325.56958 -284.302454) (xy 325.51878 -284.302454)
			(xy 325.51878 -284.565344) (xy 325.56958 -284.565344)
		)
		(stroke
			(width 0)
			(type solid)
		)
		(fill yes)
		(layer "F.Cu")
		(net "M_A_CPU0_SA_DQ<23>")
	)
	(gr_poly
		(pts
			(xy 325.67118 -283.932122) (xy 325.67118 -283.741622) (xy 325.56958 -283.705554) (xy 325.51878 -283.705554)
			(xy 325.51878 -283.968444) (xy 325.56958 -283.968444)
		)
		(stroke
			(width 0)
			(type solid)
		)
		(fill yes)
		(layer "F.Cu")
		(net "M_A_CPU0_SA_DQ<23>")
	)
	(gr_poly
		(pts
			(xy 325.67118 -283.335222) (xy 325.67118 -283.144722) (xy 325.56958 -283.108654) (xy 325.51878 -283.108654)
			(xy 325.51878 -283.371544) (xy 325.56958 -283.371544)
		)
		(stroke
			(width 0)
			(type solid)
		)
		(fill yes)
		(layer "F.Cu")
		(net "M_A_CPU0_SA_DQ<23>")
	)
	(gr_poly
		(pts
			(xy 325.67118 -282.738322) (xy 325.67118 -282.547822) (xy 325.56958 -282.511754) (xy 325.51878 -282.511754)
			(xy 325.51878 -282.774644) (xy 325.56958 -282.774644)
		)
		(stroke
			(width 0)
			(type solid)
		)
		(fill yes)
		(layer "F.Cu")
		(net "M_A_CPU0_SA_DQ<23>")
	)
	(gr_poly
		(pts
			(xy 325.67118 -282.141422) (xy 325.67118 -281.950922) (xy 325.56958 -281.914854) (xy 325.51878 -281.914854)
			(xy 325.51878 -282.177744) (xy 325.56958 -282.177744)
		)
		(stroke
			(width 0)
			(type solid)
		)
		(fill yes)
		(layer "F.Cu")
		(net "M_A_CPU0_SA_DQ<23>")
	)
	(gr_poly
		(pts
			(xy 325.688706 -271.933416) (xy 325.642478 -271.83588) (xy 325.60641 -271.800066) (xy 325.420482 -271.985994)
			(xy 325.45655 -272.021808) (xy 325.553832 -272.068036)
		)
		(stroke
			(width 0)
			(type solid)
		)
		(fill yes)
		(layer "F.Cu")
		(net "M_A_CPU0_SA_DQ<31>")
	)
	(gr_poly
		(pts
			(xy 325.698358 -272.78711) (xy 325.65213 -272.689828) (xy 325.616316 -272.65376) (xy 325.430388 -272.839688)
			(xy 325.466202 -272.875756) (xy 325.563738 -272.921984)
		)
		(stroke
			(width 0)
			(type solid)
		)
		(fill yes)
		(layer "F.Cu")
		(net "M_A_CPU0_SA_DQ<30>")
	)
	(gr_poly
		(pts
			(xy 325.704708 -246.831612) (xy 325.66864 -246.730012) (xy 325.47814 -246.730012) (xy 325.441818 -246.831612)
			(xy 325.441818 -246.882412) (xy 325.704708 -246.882412)
		)
		(stroke
			(width 0)
			(type solid)
		)
		(fill yes)
		(layer "F.Cu")
		(net "M_A_CPU0_SB_CS_N<2>")
	)
	(gr_poly
		(pts
			(xy 325.704708 -246.526812) (xy 325.66864 -246.425212) (xy 325.47814 -246.425212) (xy 325.441818 -246.526812)
			(xy 325.441818 -246.577612) (xy 325.704708 -246.577612)
		)
		(stroke
			(width 0)
			(type solid)
		)
		(fill yes)
		(layer "F.Cu")
		(net "M_A_CPU0_SB_CS_N<0>")
	)
	(gr_poly
		(pts
			(xy 325.704708 -246.222012) (xy 325.66864 -246.120412) (xy 325.47814 -246.120412) (xy 325.441818 -246.222012)
			(xy 325.441818 -246.272812) (xy 325.704708 -246.272812)
		)
		(stroke
			(width 0)
			(type solid)
		)
		(fill yes)
		(layer "F.Cu")
		(net "M_A_CPU0_SB_CS_N<3>")
	)
	(gr_poly
		(pts
			(xy 325.704708 -245.917212) (xy 325.66864 -245.815612) (xy 325.47814 -245.815612) (xy 325.441818 -245.917212)
			(xy 325.441818 -245.968012) (xy 325.704708 -245.968012)
		)
		(stroke
			(width 0)
			(type solid)
		)
		(fill yes)
		(layer "F.Cu")
		(net "M_A_CPU0_SB_CS_N<1>")
	)
	(gr_poly
		(pts
			(xy 325.72071 -280.42997) (xy 325.670926 -280.41981) (xy 325.564246 -280.435558) (xy 325.526908 -280.622248)
			(xy 325.619618 -280.67762) (xy 325.669402 -280.68778)
		)
		(stroke
			(width 0)
			(type solid)
		)
		(fill yes)
		(layer "F.Cu")
		(net "M_A_CPU0_SA_DQ<23>")
	)
	(gr_poly
		(pts
			(xy 325.731378 -265.01471) (xy 325.695564 -264.978642) (xy 325.598028 -264.932414) (xy 325.463408 -265.067034)
			(xy 325.509636 -265.16457) (xy 325.545704 -265.200384)
		)
		(stroke
			(width 0)
			(type solid)
		)
		(fill yes)
		(layer "F.Cu")
		(net "M_A_CPU0_SA_CB<5>")
	)
	(gr_poly
		(pts
			(xy 325.739252 -223.138746) (xy 325.739252 -222.948246) (xy 325.637652 -222.912178) (xy 325.586852 -222.912178)
			(xy 325.586852 -223.174814) (xy 325.637652 -223.174814)
		)
		(stroke
			(width 0)
			(type solid)
		)
		(fill yes)
		(layer "F.Cu")
		(net "M_A_CPU0_SB_DQ<19>")
	)
	(gr_poly
		(pts
			(xy 325.739252 -222.541846) (xy 325.739252 -222.351346) (xy 325.637652 -222.315278) (xy 325.586852 -222.315278)
			(xy 325.586852 -222.577914) (xy 325.637652 -222.577914)
		)
		(stroke
			(width 0)
			(type solid)
		)
		(fill yes)
		(layer "F.Cu")
		(net "M_A_CPU0_SB_DQ<19>")
	)
	(gr_poly
		(pts
			(xy 325.739252 -221.944946) (xy 325.739252 -221.754446) (xy 325.637652 -221.718378) (xy 325.586852 -221.718378)
			(xy 325.586852 -221.981014) (xy 325.637652 -221.981014)
		)
		(stroke
			(width 0)
			(type solid)
		)
		(fill yes)
		(layer "F.Cu")
		(net "M_A_CPU0_SB_DQ<19>")
	)
	(gr_poly
		(pts
			(xy 325.739252 -221.348046) (xy 325.739252 -221.157546) (xy 325.637652 -221.121478) (xy 325.586852 -221.121478)
			(xy 325.586852 -221.384114) (xy 325.637652 -221.384114)
		)
		(stroke
			(width 0)
			(type solid)
		)
		(fill yes)
		(layer "F.Cu")
		(net "M_A_CPU0_SB_DQ<19>")
	)
	(gr_poly
		(pts
			(xy 325.739252 -220.751146) (xy 325.739252 -220.560646) (xy 325.637652 -220.524578) (xy 325.586852 -220.524578)
			(xy 325.586852 -220.787214) (xy 325.637652 -220.787214)
		)
		(stroke
			(width 0)
			(type solid)
		)
		(fill yes)
		(layer "F.Cu")
		(net "M_A_CPU0_SB_DQ<19>")
	)
	(gr_poly
		(pts
			(xy 325.739252 -220.154246) (xy 325.739252 -219.963746) (xy 325.637652 -219.927678) (xy 325.586852 -219.927678)
			(xy 325.586852 -220.190314) (xy 325.637652 -220.190314)
		)
		(stroke
			(width 0)
			(type solid)
		)
		(fill yes)
		(layer "F.Cu")
		(net "M_A_CPU0_SB_DQ<19>")
	)
	(gr_poly
		(pts
			(xy 325.739252 -219.557346) (xy 325.739252 -219.366846) (xy 325.637652 -219.330778) (xy 325.586852 -219.330778)
			(xy 325.586852 -219.593414) (xy 325.637652 -219.593414)
		)
		(stroke
			(width 0)
			(type solid)
		)
		(fill yes)
		(layer "F.Cu")
		(net "M_A_CPU0_SB_DQ<19>")
	)
	(gr_poly
		(pts
			(xy 325.739252 -218.960446) (xy 325.739252 -218.769946) (xy 325.637652 -218.733878) (xy 325.586852 -218.733878)
			(xy 325.586852 -218.996514) (xy 325.637652 -218.996514)
		)
		(stroke
			(width 0)
			(type solid)
		)
		(fill yes)
		(layer "F.Cu")
		(net "M_A_CPU0_SB_DQ<19>")
	)
	(gr_poly
		(pts
			(xy 325.74103 -265.86815) (xy 325.704962 -265.832336) (xy 325.60768 -265.786108) (xy 325.472806 -265.920728)
			(xy 325.519034 -266.018264) (xy 325.555102 -266.054078)
		)
		(stroke
			(width 0)
			(type solid)
		)
		(fill yes)
		(layer "F.Cu")
		(net "M_A_CPU0_SA_CB<4>")
	)
	(gr_poly
		(pts
			(xy 325.743062 -225.02495) (xy 325.77913 -224.989136) (xy 325.593202 -224.803208) (xy 325.557388 -224.839022)
			(xy 325.510906 -224.936558) (xy 325.64578 -225.071178)
		)
		(stroke
			(width 0)
			(type solid)
		)
		(fill yes)
		(layer "F.Cu")
		(net "M_A_CPU0_SB_DQ<16>")
	)
	(gr_poly
		(pts
			(xy 325.745856 -268.451076) (xy 325.710042 -268.415008) (xy 325.612506 -268.36878) (xy 325.477886 -268.503654)
			(xy 325.524114 -268.600936) (xy 325.559928 -268.637004)
		)
		(stroke
			(width 0)
			(type solid)
		)
		(fill yes)
		(layer "F.Cu")
		(net "M_A_CPU0_SA_CB<1>")
	)
	(gr_poly
		(pts
			(xy 325.749158 -277.937976) (xy 325.786242 -277.751032) (xy 325.693532 -277.695914) (xy 325.643748 -277.686008)
			(xy 325.59244 -277.943818) (xy 325.642478 -277.953724)
		)
		(stroke
			(width 0)
			(type solid)
		)
		(fill yes)
		(layer "F.Cu")
		(net "M_A_CPU0_SA_DQ<24>")
	)
	(gr_poly
		(pts
			(xy 325.75246 -224.17151) (xy 325.788274 -224.135696) (xy 325.602346 -223.949768) (xy 325.566532 -223.985836)
			(xy 325.520304 -224.083118) (xy 325.654924 -224.217992)
		)
		(stroke
			(width 0)
			(type solid)
		)
		(fill yes)
		(layer "F.Cu")
		(net "M_A_CPU0_SB_DQ<17>")
	)
	(gr_poly
		(pts
			(xy 325.755254 -269.304516) (xy 325.71944 -269.268702) (xy 325.621904 -269.222474) (xy 325.487284 -269.357094)
			(xy 325.533512 -269.45463) (xy 325.569326 -269.490444)
		)
		(stroke
			(width 0)
			(type solid)
		)
		(fill yes)
		(layer "F.Cu")
		(net "M_A_CPU0_SA_CB<0>")
	)
	(gr_poly
		(pts
			(xy 325.767446 -280.974546) (xy 325.804784 -280.787856) (xy 325.712328 -280.732484) (xy 325.66229 -280.722578)
			(xy 325.610982 -280.980388) (xy 325.660766 -280.990294)
		)
		(stroke
			(width 0)
			(type solid)
		)
		(fill yes)
		(layer "F.Cu")
		(net "M_A_CPU0_SA_DQ<23>")
	)
	(gr_poly
		(pts
			(xy 325.808848 -264.721086) (xy 325.76262 -264.623804) (xy 325.726806 -264.587736) (xy 325.540878 -264.773664)
			(xy 325.576692 -264.809478) (xy 325.674228 -264.85596)
		)
		(stroke
			(width 0)
			(type solid)
		)
		(fill yes)
		(layer "F.Cu")
		(net "M_A_CPU0_SA_CB<7>")
	)
	(gr_poly
		(pts
			(xy 325.817484 -271.588992) (xy 325.78167 -271.552924) (xy 325.684134 -271.506696) (xy 325.549514 -271.64157)
			(xy 325.595742 -271.738852) (xy 325.631556 -271.77492)
		)
		(stroke
			(width 0)
			(type solid)
		)
		(fill yes)
		(layer "F.Cu")
		(net "M_A_CPU0_SA_DQ<31>")
	)
	(gr_poly
		(pts
			(xy 325.8185 -265.57478) (xy 325.772272 -265.477244) (xy 325.736204 -265.44143) (xy 325.550276 -265.627358)
			(xy 325.586344 -265.663172) (xy 325.683626 -265.7094)
		)
		(stroke
			(width 0)
			(type solid)
		)
		(fill yes)
		(layer "F.Cu")
		(net "M_A_CPU0_SA_CB<6>")
	)
	(gr_poly
		(pts
			(xy 325.819516 -224.526602) (xy 325.865744 -224.429066) (xy 325.731124 -224.294446) (xy 325.633588 -224.340674)
			(xy 325.597774 -224.376488) (xy 325.783702 -224.562416)
		)
		(stroke
			(width 0)
			(type solid)
		)
		(fill yes)
		(layer "F.Cu")
		(net "M_A_CPU0_SB_DQ<18>")
	)
	(gr_poly
		(pts
			(xy 325.823326 -268.157706) (xy 325.777098 -268.06017) (xy 325.741284 -268.024356) (xy 325.555356 -268.210284)
			(xy 325.591424 -268.246098) (xy 325.688706 -268.292326)
		)
		(stroke
			(width 0)
			(type solid)
		)
		(fill yes)
		(layer "F.Cu")
		(net "M_A_CPU0_SA_CB<3>")
	)
	(gr_poly
		(pts
			(xy 325.82358 -284.600904) (xy 325.77278 -284.600904) (xy 325.67118 -284.637226) (xy 325.67118 -284.827726)
			(xy 325.77278 -284.863794) (xy 325.82358 -284.863794)
		)
		(stroke
			(width 0)
			(type solid)
		)
		(fill yes)
		(layer "F.Cu")
		(net "M_A_CPU0_SA_DQ<21>")
	)
	(gr_poly
		(pts
			(xy 325.82358 -284.004004) (xy 325.77278 -284.004004) (xy 325.67118 -284.040326) (xy 325.67118 -284.230826)
			(xy 325.77278 -284.266894) (xy 325.82358 -284.266894)
		)
		(stroke
			(width 0)
			(type solid)
		)
		(fill yes)
		(layer "F.Cu")
		(net "M_A_CPU0_SA_DQ<21>")
	)
	(gr_poly
		(pts
			(xy 325.82358 -283.407104) (xy 325.77278 -283.407104) (xy 325.67118 -283.443426) (xy 325.67118 -283.633926)
			(xy 325.77278 -283.669994) (xy 325.82358 -283.669994)
		)
		(stroke
			(width 0)
			(type solid)
		)
		(fill yes)
		(layer "F.Cu")
		(net "M_A_CPU0_SA_DQ<21>")
	)
	(gr_poly
		(pts
			(xy 325.82358 -282.810204) (xy 325.77278 -282.810204) (xy 325.67118 -282.846526) (xy 325.67118 -283.037026)
			(xy 325.77278 -283.073094) (xy 325.82358 -283.073094)
		)
		(stroke
			(width 0)
			(type solid)
		)
		(fill yes)
		(layer "F.Cu")
		(net "M_A_CPU0_SA_DQ<21>")
	)
	(gr_poly
		(pts
			(xy 325.82358 -282.213304) (xy 325.77278 -282.213304) (xy 325.67118 -282.249626) (xy 325.67118 -282.440126)
			(xy 325.77278 -282.476194) (xy 325.82358 -282.476194)
		)
		(stroke
			(width 0)
			(type solid)
		)
		(fill yes)
		(layer "F.Cu")
		(net "M_A_CPU0_SA_DQ<21>")
	)
	(gr_poly
		(pts
			(xy 325.82358 -281.616404) (xy 325.77278 -281.616404) (xy 325.67118 -281.652726) (xy 325.67118 -281.843226)
			(xy 325.77278 -281.879294) (xy 325.82358 -281.879294)
		)
		(stroke
			(width 0)
			(type solid)
		)
		(fill yes)
		(layer "F.Cu")
		(net "M_A_CPU0_SA_DQ<21>")
	)
	(gr_poly
		(pts
			(xy 325.827136 -272.44294) (xy 325.791322 -272.406872) (xy 325.693786 -272.360644) (xy 325.559166 -272.495264)
			(xy 325.605394 -272.5928) (xy 325.641462 -272.628614)
		)
		(stroke
			(width 0)
			(type solid)
		)
		(fill yes)
		(layer "F.Cu")
		(net "M_A_CPU0_SA_DQ<30>")
	)
	(gr_poly
		(pts
			(xy 325.832724 -269.011146) (xy 325.786496 -268.913864) (xy 325.750682 -268.877796) (xy 325.564754 -269.063724)
			(xy 325.600568 -269.099792) (xy 325.698104 -269.14602)
		)
		(stroke
			(width 0)
			(type solid)
		)
		(fill yes)
		(layer "F.Cu")
		(net "M_A_CPU0_SA_CB<2>")
	)
	(gr_poly
		(pts
			(xy 325.83755 -279.8445) (xy 325.787766 -279.834594) (xy 325.681086 -279.850088) (xy 325.643748 -280.037032)
			(xy 325.736458 -280.092404) (xy 325.786242 -280.10231)
		)
		(stroke
			(width 0)
			(type solid)
		)
		(fill yes)
		(layer "F.Cu")
		(net "M_A_CPU0_SA_DQ<23>")
	)
	(gr_poly
		(pts
			(xy 325.870316 -276.750526) (xy 325.797672 -276.67077) (xy 325.752968 -276.646894) (xy 325.629016 -276.878542)
			(xy 325.673974 -276.902672) (xy 325.7804 -276.918674)
		)
		(stroke
			(width 0)
			(type solid)
		)
		(fill yes)
		(layer "F.Cu")
		(net "M_A_CPU0_SA_DQ<26>")
	)
	(gr_poly
		(pts
			(xy 325.882762 -276.080474) (xy 325.810118 -276.000718) (xy 325.765414 -275.976588) (xy 325.641462 -276.20849)
			(xy 325.686166 -276.232366) (xy 325.792846 -276.248368)
		)
		(stroke
			(width 0)
			(type solid)
		)
		(fill yes)
		(layer "F.Cu")
		(net "M_A_CPU0_SA_DQ<25>")
	)
	(gr_poly
		(pts
			(xy 325.884286 -280.38933) (xy 325.921624 -280.202386) (xy 325.828914 -280.147014) (xy 325.77913 -280.137108)
			(xy 325.727822 -280.394918) (xy 325.777606 -280.404824)
		)
		(stroke
			(width 0)
			(type solid)
		)
		(fill yes)
		(layer "F.Cu")
		(net "M_A_CPU0_SA_DQ<23>")
	)
	(gr_poly
		(pts
			(xy 325.893938 -276.383496) (xy 325.84898 -276.35962) (xy 325.7423 -276.343618) (xy 325.652638 -276.511766)
			(xy 325.725282 -276.591522) (xy 325.769986 -276.615398)
		)
		(stroke
			(width 0)
			(type solid)
		)
		(fill yes)
		(layer "F.Cu")
		(net "M_A_CPU0_SA_DQ<26>")
	)
	(gr_poly
		(pts
			(xy 325.894954 -275.410168) (xy 325.822564 -275.330412) (xy 325.777606 -275.306536) (xy 325.653654 -275.538184)
			(xy 325.698612 -275.562314) (xy 325.805292 -275.578316)
		)
		(stroke
			(width 0)
			(type solid)
		)
		(fill yes)
		(layer "F.Cu")
		(net "M_A_CPU0_SA_DQ<27>")
	)
	(gr_poly
		(pts
			(xy 325.904352 -272.149062) (xy 325.858124 -272.05178) (xy 325.82231 -272.015712) (xy 325.636382 -272.20164)
			(xy 325.672196 -272.237708) (xy 325.769732 -272.283936)
		)
		(stroke
			(width 0)
			(type solid)
		)
		(fill yes)
		(layer "F.Cu")
		(net "M_A_CPU0_SA_DQ<29>")
	)
	(gr_poly
		(pts
			(xy 325.90613 -275.713444) (xy 325.861172 -275.689568) (xy 325.754492 -275.673566) (xy 325.66483 -275.84146)
			(xy 325.73722 -275.92147) (xy 325.782178 -275.945346)
		)
		(stroke
			(width 0)
			(type solid)
		)
		(fill yes)
		(layer "F.Cu")
		(net "M_A_CPU0_SA_DQ<25>")
	)
	(gr_poly
		(pts
			(xy 325.914004 -273.002756) (xy 325.867776 -272.905474) (xy 325.831962 -272.869406) (xy 325.646034 -273.055334)
			(xy 325.681848 -273.091402) (xy 325.779384 -273.13763)
		)
		(stroke
			(width 0)
			(type solid)
		)
		(fill yes)
		(layer "F.Cu")
		(net "M_A_CPU0_SA_DQ<28>")
	)
	(gr_poly
		(pts
			(xy 325.918322 -275.043138) (xy 325.873618 -275.019262) (xy 325.766938 -275.00326) (xy 325.677022 -275.171408)
			(xy 325.749666 -275.251164) (xy 325.79437 -275.27504)
		)
		(stroke
			(width 0)
			(type solid)
		)
		(fill yes)
		(layer "F.Cu")
		(net "M_A_CPU0_SA_DQ<27>")
	)
	(gr_poly
		(pts
			(xy 325.93788 -264.376662) (xy 325.901812 -264.340848) (xy 325.80453 -264.29462) (xy 325.669656 -264.42924)
			(xy 325.715884 -264.526776) (xy 325.751952 -264.56259)
		)
		(stroke
			(width 0)
			(type solid)
		)
		(fill yes)
		(layer "F.Cu")
		(net "M_A_CPU0_SA_CB<7>")
	)
	(gr_poly
		(pts
			(xy 325.947278 -265.230356) (xy 325.911464 -265.194542) (xy 325.813928 -265.148314) (xy 325.679308 -265.282934)
			(xy 325.725536 -265.380216) (xy 325.76135 -265.416284)
		)
		(stroke
			(width 0)
			(type solid)
		)
		(fill yes)
		(layer "F.Cu")
		(net "M_A_CPU0_SA_CB<6>")
	)
	(gr_poly
		(pts
			(xy 325.952358 -267.813282) (xy 325.91629 -267.777468) (xy 325.819008 -267.73124) (xy 325.684134 -267.86586)
			(xy 325.730616 -267.963396) (xy 325.76643 -267.99921)
		)
		(stroke
			(width 0)
			(type solid)
		)
		(fill yes)
		(layer "F.Cu")
		(net "M_A_CPU0_SA_CB<3>")
	)
	(gr_poly
		(pts
			(xy 325.95439 -279.25903) (xy 325.904606 -279.249124) (xy 325.797926 -279.264872) (xy 325.760588 -279.451562)
			(xy 325.853298 -279.506934) (xy 325.903082 -279.51684)
		)
		(stroke
			(width 0)
			(type solid)
		)
		(fill yes)
		(layer "F.Cu")
		(net "M_A_CPU0_SA_DQ<23>")
	)
	(gr_poly
		(pts
			(xy 325.958708 -224.809304) (xy 325.994776 -224.77349) (xy 325.808848 -224.587562) (xy 325.773034 -224.623376)
			(xy 325.726552 -224.720912) (xy 325.861426 -224.855532)
		)
		(stroke
			(width 0)
			(type solid)
		)
		(fill yes)
		(layer "F.Cu")
		(net "M_A_CPU0_SB_DQ<18>")
	)
	(gr_poly
		(pts
			(xy 325.961756 -268.666722) (xy 325.925688 -268.630908) (xy 325.828406 -268.58468) (xy 325.693532 -268.7193)
			(xy 325.73976 -268.816836) (xy 325.775828 -268.85265)
		)
		(stroke
			(width 0)
			(type solid)
		)
		(fill yes)
		(layer "F.Cu")
		(net "M_A_CPU0_SA_CB<2>")
	)
	(gr_poly
		(pts
			(xy 325.968106 -223.955864) (xy 326.00392 -223.92005) (xy 325.817992 -223.734122) (xy 325.782178 -223.77019)
			(xy 325.73595 -223.867472) (xy 325.87057 -224.002346)
		)
		(stroke
			(width 0)
			(type solid)
		)
		(fill yes)
		(layer "F.Cu")
		(net "M_A_CPU0_SB_DQ<19>")
	)
	(gr_poly
		(pts
			(xy 325.97598 -285.125922) (xy 325.97598 -284.935422) (xy 325.87438 -284.899354) (xy 325.82358 -284.899354)
			(xy 325.82358 -285.162244) (xy 325.87438 -285.162244)
		)
		(stroke
			(width 0)
			(type solid)
		)
		(fill yes)
		(layer "F.Cu")
		(net "M_A_CPU0_SA_DQ<21>")
	)
	(gr_poly
		(pts
			(xy 325.97598 -284.529022) (xy 325.97598 -284.338522) (xy 325.87438 -284.302454) (xy 325.82358 -284.302454)
			(xy 325.82358 -284.565344) (xy 325.87438 -284.565344)
		)
		(stroke
			(width 0)
			(type solid)
		)
		(fill yes)
		(layer "F.Cu")
		(net "M_A_CPU0_SA_DQ<21>")
	)
	(gr_poly
		(pts
			(xy 325.97598 -283.932122) (xy 325.97598 -283.741622) (xy 325.87438 -283.705554) (xy 325.82358 -283.705554)
			(xy 325.82358 -283.968444) (xy 325.87438 -283.968444)
		)
		(stroke
			(width 0)
			(type solid)
		)
		(fill yes)
		(layer "F.Cu")
		(net "M_A_CPU0_SA_DQ<21>")
	)
	(gr_poly
		(pts
			(xy 325.97598 -283.335222) (xy 325.97598 -283.144722) (xy 325.87438 -283.108654) (xy 325.82358 -283.108654)
			(xy 325.82358 -283.371544) (xy 325.87438 -283.371544)
		)
		(stroke
			(width 0)
			(type solid)
		)
		(fill yes)
		(layer "F.Cu")
		(net "M_A_CPU0_SA_DQ<21>")
	)
	(gr_poly
		(pts
			(xy 325.97598 -282.738322) (xy 325.97598 -282.547822) (xy 325.87438 -282.511754) (xy 325.82358 -282.511754)
			(xy 325.82358 -282.774644) (xy 325.87438 -282.774644)
		)
		(stroke
			(width 0)
			(type solid)
		)
		(fill yes)
		(layer "F.Cu")
		(net "M_A_CPU0_SA_DQ<21>")
	)
	(gr_poly
		(pts
			(xy 325.97598 -282.141422) (xy 325.97598 -281.950922) (xy 325.87438 -281.914854) (xy 325.82358 -281.914854)
			(xy 325.82358 -282.177744) (xy 325.87438 -282.177744)
		)
		(stroke
			(width 0)
			(type solid)
		)
		(fill yes)
		(layer "F.Cu")
		(net "M_A_CPU0_SA_DQ<21>")
	)
	(gr_poly
		(pts
			(xy 326.001126 -279.80386) (xy 326.038464 -279.61717) (xy 325.945754 -279.561798) (xy 325.89597 -279.551892)
			(xy 325.844662 -279.809702) (xy 325.894446 -279.819608)
		)
		(stroke
			(width 0)
			(type solid)
		)
		(fill yes)
		(layer "F.Cu")
		(net "M_A_CPU0_SA_DQ<23>")
	)
	(gr_poly
		(pts
			(xy 326.003158 -249.066812) (xy 326.003158 -249.016012) (xy 325.740268 -249.016012) (xy 325.740268 -249.066812)
			(xy 325.776336 -249.168412) (xy 325.966836 -249.168412)
		)
		(stroke
			(width 0)
			(type solid)
		)
		(fill yes)
		(layer "F.Cu")
		(net "M_A_CPU0_SB_CA<1>")
	)
	(gr_poly
		(pts
			(xy 326.003158 -247.542812) (xy 326.003158 -247.492012) (xy 325.740268 -247.492012) (xy 325.740268 -247.542812)
			(xy 325.776336 -247.644412) (xy 325.966836 -247.644412)
		)
		(stroke
			(width 0)
			(type solid)
		)
		(fill yes)
		(layer "F.Cu")
		(net "M_A_CPU0_SB_CA<6>")
	)
	(gr_poly
		(pts
			(xy 326.003158 -247.238012) (xy 326.003158 -247.187212) (xy 325.740268 -247.187212) (xy 325.740268 -247.238012)
			(xy 325.776336 -247.339612) (xy 325.966836 -247.339612)
		)
		(stroke
			(width 0)
			(type solid)
		)
		(fill yes)
		(layer "F.Cu")
		(net "M_A_CPU0_SB_PAR")
	)
	(gr_poly
		(pts
			(xy 326.003158 -246.933212) (xy 326.003158 -246.882412) (xy 325.740268 -246.882412) (xy 325.740268 -246.933212)
			(xy 325.776336 -247.034812) (xy 325.966836 -247.034812)
		)
		(stroke
			(width 0)
			(type solid)
		)
		(fill yes)
		(layer "F.Cu")
		(net "M_A_CPU0_SB_CS_N<2>")
	)
	(gr_poly
		(pts
			(xy 326.003158 -246.628412) (xy 326.003158 -246.577612) (xy 325.740268 -246.577612) (xy 325.740268 -246.628412)
			(xy 325.776336 -246.730012) (xy 325.966836 -246.730012)
		)
		(stroke
			(width 0)
			(type solid)
		)
		(fill yes)
		(layer "F.Cu")
		(net "M_A_CPU0_SB_CS_N<0>")
	)
	(gr_poly
		(pts
			(xy 326.003158 -246.323612) (xy 326.003158 -246.272812) (xy 325.740268 -246.272812) (xy 325.740268 -246.323612)
			(xy 325.776336 -246.425212) (xy 325.966836 -246.425212)
		)
		(stroke
			(width 0)
			(type solid)
		)
		(fill yes)
		(layer "F.Cu")
		(net "M_A_CPU0_SB_CS_N<3>")
	)
	(gr_poly
		(pts
			(xy 326.003158 -246.018812) (xy 326.003158 -245.968012) (xy 325.740268 -245.968012) (xy 325.740268 -246.018812)
			(xy 325.776336 -246.120412) (xy 325.966836 -246.120412)
		)
		(stroke
			(width 0)
			(type solid)
		)
		(fill yes)
		(layer "F.Cu")
		(net "M_A_CPU0_SB_CS_N<1>")
	)
	(gr_poly
		(pts
			(xy 326.019922 -280.489406) (xy 325.970138 -280.4795) (xy 325.863458 -280.495248) (xy 325.82612 -280.681938)
			(xy 325.91883 -280.73731) (xy 325.968614 -280.747216)
		)
		(stroke
			(width 0)
			(type solid)
		)
		(fill yes)
		(layer "F.Cu")
		(net "M_A_CPU0_SA_DQ<21>")
	)
	(gr_poly
		(pts
			(xy 326.024748 -264.936986) (xy 325.97852 -264.83945) (xy 325.942452 -264.803636) (xy 325.756524 -264.989564)
			(xy 325.792592 -265.025378) (xy 325.889874 -265.071606)
		)
		(stroke
			(width 0)
			(type solid)
		)
		(fill yes)
		(layer "F.Cu")
		(net "M_A_CPU0_SA_CB<5>")
	)
	(gr_poly
		(pts
			(xy 326.026018 -225.164142) (xy 326.072246 -225.06686) (xy 325.937626 -224.931986) (xy 325.84009 -224.978214)
			(xy 325.804276 -225.014282) (xy 325.990204 -225.20021)
		)
		(stroke
			(width 0)
			(type solid)
		)
		(fill yes)
		(layer "F.Cu")
		(net "M_A_CPU0_SB_DQ<16>")
	)
	(gr_poly
		(pts
			(xy 326.033384 -271.804638) (xy 325.997316 -271.768824) (xy 325.900034 -271.722596) (xy 325.76516 -271.857216)
			(xy 325.811388 -271.954752) (xy 325.847456 -271.990566)
		)
		(stroke
			(width 0)
			(type solid)
		)
		(fill yes)
		(layer "F.Cu")
		(net "M_A_CPU0_SA_DQ<29>")
	)
	(gr_poly
		(pts
			(xy 326.034146 -265.790426) (xy 325.987918 -265.693144) (xy 325.952104 -265.657076) (xy 325.766176 -265.843004)
			(xy 325.80199 -265.879072) (xy 325.899526 -265.9253)
		)
		(stroke
			(width 0)
			(type solid)
		)
		(fill yes)
		(layer "F.Cu")
		(net "M_A_CPU0_SA_CB<4>")
	)
	(gr_poly
		(pts
			(xy 326.035162 -224.310956) (xy 326.08139 -224.21342) (xy 325.94677 -224.0788) (xy 325.849234 -224.125028)
			(xy 325.81342 -224.160842) (xy 325.999348 -224.34677)
		)
		(stroke
			(width 0)
			(type solid)
		)
		(fill yes)
		(layer "F.Cu")
		(net "M_A_CPU0_SB_DQ<17>")
	)
	(gr_poly
		(pts
			(xy 326.038972 -268.373352) (xy 325.992744 -268.275816) (xy 325.95693 -268.240002) (xy 325.771002 -268.42593)
			(xy 325.80707 -268.461744) (xy 325.904352 -268.507972)
		)
		(stroke
			(width 0)
			(type solid)
		)
		(fill yes)
		(layer "F.Cu")
		(net "M_A_CPU0_SA_CB<1>")
	)
	(gr_poly
		(pts
			(xy 326.042782 -272.658586) (xy 326.006968 -272.622518) (xy 325.909432 -272.57629) (xy 325.774812 -272.71091)
			(xy 325.82104 -272.808446) (xy 325.857108 -272.84426)
		)
		(stroke
			(width 0)
			(type solid)
		)
		(fill yes)
		(layer "F.Cu")
		(net "M_A_CPU0_SA_DQ<28>")
	)
	(gr_poly
		(pts
			(xy 326.04837 -269.226792) (xy 326.002142 -269.12951) (xy 325.966328 -269.093442) (xy 325.7804 -269.27937)
			(xy 325.816214 -269.315438) (xy 325.91375 -269.361666)
		)
		(stroke
			(width 0)
			(type solid)
		)
		(fill yes)
		(layer "F.Cu")
		(net "M_A_CPU0_SA_CB<0>")
	)
	(gr_poly
		(pts
			(xy 326.066404 -281.034236) (xy 326.103742 -280.847546) (xy 326.011286 -280.792174) (xy 325.961248 -280.782268)
			(xy 325.90994 -281.040078) (xy 325.959724 -281.049984)
		)
		(stroke
			(width 0)
			(type solid)
		)
		(fill yes)
		(layer "F.Cu")
		(net "M_A_CPU0_SA_DQ<21>")
	)
	(gr_poly
		(pts
			(xy 326.07123 -278.673814) (xy 326.021446 -278.663908) (xy 325.914766 -278.679402) (xy 325.877428 -278.866346)
			(xy 325.969884 -278.921718) (xy 326.019922 -278.931624)
		)
		(stroke
			(width 0)
			(type solid)
		)
		(fill yes)
		(layer "F.Cu")
		(net "M_A_CPU0_SA_DQ<23>")
	)
	(gr_poly
		(pts
			(xy 326.1106 -271.511268) (xy 326.064372 -271.413732) (xy 326.028558 -271.377918) (xy 325.84263 -271.563846)
			(xy 325.878698 -271.59966) (xy 325.97598 -271.645888)
		)
		(stroke
			(width 0)
			(type solid)
		)
		(fill yes)
		(layer "F.Cu")
		(net "M_A_CPU0_SA_DQ<31>")
	)
	(gr_poly
		(pts
			(xy 326.117966 -279.218644) (xy 326.155304 -279.0317) (xy 326.062594 -278.976328) (xy 326.01281 -278.966422)
			(xy 325.961502 -279.224232) (xy 326.011286 -279.234138)
		)
		(stroke
			(width 0)
			(type solid)
		)
		(fill yes)
		(layer "F.Cu")
		(net "M_A_CPU0_SA_DQ<23>")
	)
	(gr_poly
		(pts
			(xy 326.120506 -272.365216) (xy 326.074278 -272.26768) (xy 326.03821 -272.231866) (xy 325.852282 -272.417794)
			(xy 325.88835 -272.453608) (xy 325.985632 -272.499836)
		)
		(stroke
			(width 0)
			(type solid)
		)
		(fill yes)
		(layer "F.Cu")
		(net "M_A_CPU0_SA_DQ<30>")
	)
	(gr_poly
		(pts
			(xy 326.12838 -285.794704) (xy 326.07758 -285.794704) (xy 325.97598 -285.831026) (xy 325.97598 -286.021526)
			(xy 326.07758 -286.057594) (xy 326.12838 -286.057594)
		)
		(stroke
			(width 0)
			(type solid)
		)
		(fill yes)
		(layer "F.Cu")
		(net "M_A_CPU0_SA_DQ<22>")
	)
	(gr_poly
		(pts
			(xy 326.12838 -285.197804) (xy 326.07758 -285.197804) (xy 325.97598 -285.234126) (xy 325.97598 -285.424626)
			(xy 326.07758 -285.460694) (xy 326.12838 -285.460694)
		)
		(stroke
			(width 0)
			(type solid)
		)
		(fill yes)
		(layer "F.Cu")
		(net "M_A_CPU0_SA_DQ<22>")
	)
	(gr_poly
		(pts
			(xy 326.12838 -284.600904) (xy 326.07758 -284.600904) (xy 325.97598 -284.637226) (xy 325.97598 -284.827726)
			(xy 326.07758 -284.863794) (xy 326.12838 -284.863794)
		)
		(stroke
			(width 0)
			(type solid)
		)
		(fill yes)
		(layer "F.Cu")
		(net "M_A_CPU0_SA_DQ<22>")
	)
	(gr_poly
		(pts
			(xy 326.12838 -284.004004) (xy 326.07758 -284.004004) (xy 325.97598 -284.040326) (xy 325.97598 -284.230826)
			(xy 326.07758 -284.266894) (xy 326.12838 -284.266894)
		)
		(stroke
			(width 0)
			(type solid)
		)
		(fill yes)
		(layer "F.Cu")
		(net "M_A_CPU0_SA_DQ<22>")
	)
	(gr_poly
		(pts
			(xy 326.12838 -283.407104) (xy 326.07758 -283.407104) (xy 325.97598 -283.443426) (xy 325.97598 -283.633926)
			(xy 326.07758 -283.669994) (xy 326.12838 -283.669994)
		)
		(stroke
			(width 0)
			(type solid)
		)
		(fill yes)
		(layer "F.Cu")
		(net "M_A_CPU0_SA_DQ<22>")
	)
	(gr_poly
		(pts
			(xy 326.12838 -282.810204) (xy 326.07758 -282.810204) (xy 325.97598 -282.846526) (xy 325.97598 -283.037026)
			(xy 326.07758 -283.073094) (xy 326.12838 -283.073094)
		)
		(stroke
			(width 0)
			(type solid)
		)
		(fill yes)
		(layer "F.Cu")
		(net "M_A_CPU0_SA_DQ<22>")
	)
	(gr_poly
		(pts
			(xy 326.12838 -282.213304) (xy 326.07758 -282.213304) (xy 325.97598 -282.249626) (xy 325.97598 -282.440126)
			(xy 326.07758 -282.476194) (xy 326.12838 -282.476194)
		)
		(stroke
			(width 0)
			(type solid)
		)
		(fill yes)
		(layer "F.Cu")
		(net "M_A_CPU0_SA_DQ<22>")
	)
	(gr_poly
		(pts
			(xy 326.132698 -232.140506) (xy 326.178926 -232.04297) (xy 326.044052 -231.90835) (xy 325.94677 -231.954578)
			(xy 325.910702 -231.990392) (xy 326.09663 -232.17632)
		)
		(stroke
			(width 0)
			(type solid)
		)
		(fill yes)
		(layer "F.Cu")
		(net "M_A_CPU0_SB_DQ<9>")
	)
	(gr_poly
		(pts
			(xy 326.136762 -279.90419) (xy 326.086724 -279.894284) (xy 325.980044 -279.909778) (xy 325.942706 -280.096722)
			(xy 326.035416 -280.152094) (xy 326.0852 -280.162)
		)
		(stroke
			(width 0)
			(type solid)
		)
		(fill yes)
		(layer "F.Cu")
		(net "M_A_CPU0_SA_DQ<21>")
	)
	(gr_poly
		(pts
			(xy 326.139302 -276.89429) (xy 326.066658 -276.814534) (xy 326.021954 -276.790404) (xy 325.898002 -277.022306)
			(xy 325.942706 -277.046182) (xy 326.049386 -277.062184)
		)
		(stroke
			(width 0)
			(type solid)
		)
		(fill yes)
		(layer "F.Cu")
		(net "M_A_CPU0_SA_DQ<24>")
	)
	(gr_poly
		(pts
			(xy 326.151494 -276.224238) (xy 326.07885 -276.144228) (xy 326.034146 -276.120352) (xy 325.910194 -276.352254)
			(xy 325.954898 -276.37613) (xy 326.061578 -276.392132)
		)
		(stroke
			(width 0)
			(type solid)
		)
		(fill yes)
		(layer "F.Cu")
		(net "M_A_CPU0_SA_DQ<26>")
	)
	(gr_poly
		(pts
			(xy 326.153526 -264.592562) (xy 326.117712 -264.556494) (xy 326.020176 -264.510266) (xy 325.885556 -264.64514)
			(xy 325.931784 -264.742422) (xy 325.967598 -264.77849)
		)
		(stroke
			(width 0)
			(type solid)
		)
		(fill yes)
		(layer "F.Cu")
		(net "M_A_CPU0_SA_CB<5>")
	)
	(gr_poly
		(pts
			(xy 326.162416 -276.52726) (xy 326.117712 -276.503384) (xy 326.011032 -276.487382) (xy 325.92137 -276.655276)
			(xy 325.99376 -276.735286) (xy 326.038718 -276.759162)
		)
		(stroke
			(width 0)
			(type solid)
		)
		(fill yes)
		(layer "F.Cu")
		(net "M_A_CPU0_SA_DQ<24>")
	)
	(gr_poly
		(pts
			(xy 326.162924 -265.446256) (xy 326.12711 -265.410188) (xy 326.029574 -265.36396) (xy 325.894954 -265.49858)
			(xy 325.941182 -265.596116) (xy 325.97725 -265.63193)
		)
		(stroke
			(width 0)
			(type solid)
		)
		(fill yes)
		(layer "F.Cu")
		(net "M_A_CPU0_SA_CB<4>")
	)
	(gr_poly
		(pts
			(xy 326.164194 -275.553932) (xy 326.09155 -275.474176) (xy 326.046846 -275.4503) (xy 325.922894 -275.682202)
			(xy 325.967598 -275.706078) (xy 326.074278 -275.72208)
		)
		(stroke
			(width 0)
			(type solid)
		)
		(fill yes)
		(layer "F.Cu")
		(net "M_A_CPU0_SA_DQ<25>")
	)
	(gr_poly
		(pts
			(xy 326.168004 -268.028928) (xy 326.131936 -267.993114) (xy 326.034654 -267.946886) (xy 325.89978 -268.081506)
			(xy 325.946262 -268.179042) (xy 325.982076 -268.214856)
		)
		(stroke
			(width 0)
			(type solid)
		)
		(fill yes)
		(layer "F.Cu")
		(net "M_A_CPU0_SA_CB<1>")
	)
	(gr_poly
		(pts
			(xy 326.17029 -229.5906) (xy 326.216518 -229.493064) (xy 326.081898 -229.358444) (xy 325.984616 -229.404672)
			(xy 325.948548 -229.440486) (xy 326.134476 -229.626414)
		)
		(stroke
			(width 0)
			(type solid)
		)
		(fill yes)
		(layer "F.Cu")
		(net "M_A_CPU0_SB_DQ<12>")
	)
	(gr_poly
		(pts
			(xy 326.174354 -224.593658) (xy 326.210422 -224.557844) (xy 326.024494 -224.371916) (xy 325.98868 -224.40773)
			(xy 325.942198 -224.505266) (xy 326.077072 -224.639886)
		)
		(stroke
			(width 0)
			(type solid)
		)
		(fill yes)
		(layer "F.Cu")
		(net "M_A_CPU0_SB_DQ<17>")
	)
	(gr_poly
		(pts
			(xy 326.174862 -275.857208) (xy 326.130158 -275.833078) (xy 326.023478 -275.81733) (xy 325.933816 -275.985224)
			(xy 326.006206 -276.06498) (xy 326.051164 -276.08911)
		)
		(stroke
			(width 0)
			(type solid)
		)
		(fill yes)
		(layer "F.Cu")
		(net "M_A_CPU0_SA_DQ<26>")
	)
	(gr_poly
		(pts
			(xy 326.177402 -268.882368) (xy 326.141334 -268.846554) (xy 326.044052 -268.800326) (xy 325.909178 -268.934946)
			(xy 325.955406 -269.032482) (xy 325.991474 -269.068296)
		)
		(stroke
			(width 0)
			(type solid)
		)
		(fill yes)
		(layer "F.Cu")
		(net "M_A_CPU0_SA_CB<0>")
	)
	(gr_poly
		(pts
			(xy 326.183244 -280.44902) (xy 326.220582 -280.262076) (xy 326.128126 -280.206704) (xy 326.078342 -280.196798)
			(xy 326.02678 -280.454608) (xy 326.076564 -280.464514)
		)
		(stroke
			(width 0)
			(type solid)
		)
		(fill yes)
		(layer "F.Cu")
		(net "M_A_CPU0_SA_DQ<21>")
	)
	(gr_poly
		(pts
			(xy 326.187308 -275.186902) (xy 326.142604 -275.163026) (xy 326.035924 -275.147024) (xy 325.946262 -275.315172)
			(xy 326.018652 -275.394928) (xy 326.06361 -275.418804)
		)
		(stroke
			(width 0)
			(type solid)
		)
		(fill yes)
		(layer "F.Cu")
		(net "M_A_CPU0_SA_DQ<25>")
	)
	(gr_poly
		(pts
			(xy 326.18807 -278.088344) (xy 326.138286 -278.078438) (xy 326.031606 -278.094186) (xy 325.994268 -278.280876)
			(xy 326.086724 -278.336248) (xy 326.136762 -278.346154)
		)
		(stroke
			(width 0)
			(type solid)
		)
		(fill yes)
		(layer "F.Cu")
		(net "M_A_CPU0_SA_DQ<23>")
	)
	(gr_poly
		(pts
			(xy 326.230996 -264.299192) (xy 326.184768 -264.201656) (xy 326.148954 -264.165588) (xy 325.963026 -264.351516)
			(xy 325.99884 -264.387584) (xy 326.096376 -264.433812)
		)
		(stroke
			(width 0)
			(type solid)
		)
		(fill yes)
		(layer "F.Cu")
		(net "M_A_CPU0_SA_CB<7>")
	)
	(gr_poly
		(pts
			(xy 326.234806 -278.633174) (xy 326.272144 -278.446484) (xy 326.179434 -278.391112) (xy 326.12965 -278.381206)
			(xy 326.078342 -278.639016) (xy 326.128126 -278.648922)
		)
		(stroke
			(width 0)
			(type solid)
		)
		(fill yes)
		(layer "F.Cu")
		(net "M_A_CPU0_SA_DQ<23>")
	)
	(gr_poly
		(pts
			(xy 326.239632 -271.166844) (xy 326.203564 -271.13103) (xy 326.106282 -271.084802) (xy 325.971408 -271.219422)
			(xy 326.01789 -271.316958) (xy 326.053704 -271.352772)
		)
		(stroke
			(width 0)
			(type solid)
		)
		(fill yes)
		(layer "F.Cu")
		(net "M_A_CPU0_SA_DQ<31>")
	)
	(gr_poly
		(pts
			(xy 326.240394 -265.152632) (xy 326.194166 -265.05535) (xy 326.158352 -265.019282) (xy 325.972424 -265.20521)
			(xy 326.008238 -265.241024) (xy 326.105774 -265.287506)
		)
		(stroke
			(width 0)
			(type solid)
		)
		(fill yes)
		(layer "F.Cu")
		(net "M_A_CPU0_SA_CB<6>")
	)
	(gr_poly
		(pts
			(xy 326.241664 -224.948496) (xy 326.287892 -224.851214) (xy 326.153272 -224.71634) (xy 326.055736 -224.762568)
			(xy 326.019922 -224.798636) (xy 326.20585 -224.984564)
		)
		(stroke
			(width 0)
			(type solid)
		)
		(fill yes)
		(layer "F.Cu")
		(net "M_A_CPU0_SB_DQ<18>")
	)
	(gr_poly
		(pts
			(xy 326.245474 -267.735558) (xy 326.199246 -267.638276) (xy 326.163432 -267.602208) (xy 325.977504 -267.788136)
			(xy 326.013318 -267.824204) (xy 326.110854 -267.870432)
		)
		(stroke
			(width 0)
			(type solid)
		)
		(fill yes)
		(layer "F.Cu")
		(net "M_A_CPU0_SA_CB<3>")
	)
	(gr_poly
		(pts
			(xy 326.249284 -272.020792) (xy 326.21347 -271.984724) (xy 326.115934 -271.938496) (xy 325.981314 -272.07337)
			(xy 326.027542 -272.170652) (xy 326.063356 -272.20672)
		)
		(stroke
			(width 0)
			(type solid)
		)
		(fill yes)
		(layer "F.Cu")
		(net "M_A_CPU0_SA_DQ<30>")
	)
	(gr_poly
		(pts
			(xy 326.250808 -224.09531) (xy 326.297036 -223.997774) (xy 326.162416 -223.863154) (xy 326.06488 -223.909382)
			(xy 326.029066 -223.945196) (xy 326.214994 -224.131124)
		)
		(stroke
			(width 0)
			(type solid)
		)
		(fill yes)
		(layer "F.Cu")
		(net "M_A_CPU0_SB_DQ<19>")
	)
	(gr_poly
		(pts
			(xy 326.253602 -279.31872) (xy 326.203564 -279.308814) (xy 326.096884 -279.324562) (xy 326.0598 -279.511252)
			(xy 326.152256 -279.566624) (xy 326.20204 -279.57653)
		)
		(stroke
			(width 0)
			(type solid)
		)
		(fill yes)
		(layer "F.Cu")
		(net "M_A_CPU0_SA_DQ<21>")
	)
	(gr_poly
		(pts
			(xy 326.254872 -268.589252) (xy 326.208644 -268.491716) (xy 326.172576 -268.455902) (xy 325.986902 -268.641576)
			(xy 326.022716 -268.677644) (xy 326.120252 -268.723872)
		)
		(stroke
			(width 0)
			(type solid)
		)
		(fill yes)
		(layer "F.Cu")
		(net "M_A_CPU0_SA_CB<2>")
	)
	(gr_poly
		(pts
			(xy 326.27189 -232.423208) (xy 326.307704 -232.387394) (xy 326.121776 -232.201466) (xy 326.085962 -232.237534)
			(xy 326.039734 -232.334816) (xy 326.174354 -232.46969)
		)
		(stroke
			(width 0)
			(type solid)
		)
		(fill yes)
		(layer "F.Cu")
		(net "M_A_CPU0_SB_DQ<9>")
	)
	(gr_poly
		(pts
			(xy 326.277732 -226.724718) (xy 326.226932 -226.724718) (xy 326.125332 -226.760786) (xy 326.125332 -226.951286)
			(xy 326.226932 -226.987354) (xy 326.277732 -226.987354)
		)
		(stroke
			(width 0)
			(type solid)
		)
		(fill yes)
		(layer "F.Cu")
		(net "M_A_CPU0_SB_DQ<16>")
	)
	(gr_poly
		(pts
			(xy 326.277732 -226.127818) (xy 326.226932 -226.127818) (xy 326.125332 -226.163886) (xy 326.125332 -226.354386)
			(xy 326.226932 -226.390454) (xy 326.277732 -226.390454)
		)
		(stroke
			(width 0)
			(type solid)
		)
		(fill yes)
		(layer "F.Cu")
		(net "M_A_CPU0_SB_DQ<16>")
	)
	(gr_poly
		(pts
			(xy 326.28078 -286.319722) (xy 326.28078 -286.129222) (xy 326.17918 -286.093154) (xy 326.12838 -286.093154)
			(xy 326.12838 -286.356044) (xy 326.17918 -286.356044)
		)
		(stroke
			(width 0)
			(type solid)
		)
		(fill yes)
		(layer "F.Cu")
		(net "M_A_CPU0_SA_DQ<22>")
	)
	(gr_poly
		(pts
			(xy 326.28078 -285.722822) (xy 326.28078 -285.532322) (xy 326.17918 -285.496254) (xy 326.12838 -285.496254)
			(xy 326.12838 -285.759144) (xy 326.17918 -285.759144)
		)
		(stroke
			(width 0)
			(type solid)
		)
		(fill yes)
		(layer "F.Cu")
		(net "M_A_CPU0_SA_DQ<22>")
	)
	(gr_poly
		(pts
			(xy 326.28078 -285.125922) (xy 326.28078 -284.935422) (xy 326.17918 -284.899354) (xy 326.12838 -284.899354)
			(xy 326.12838 -285.162244) (xy 326.17918 -285.162244)
		)
		(stroke
			(width 0)
			(type solid)
		)
		(fill yes)
		(layer "F.Cu")
		(net "M_A_CPU0_SA_DQ<22>")
	)
	(gr_poly
		(pts
			(xy 326.28078 -284.529022) (xy 326.28078 -284.338522) (xy 326.17918 -284.302454) (xy 326.12838 -284.302454)
			(xy 326.12838 -284.565344) (xy 326.17918 -284.565344)
		)
		(stroke
			(width 0)
			(type solid)
		)
		(fill yes)
		(layer "F.Cu")
		(net "M_A_CPU0_SA_DQ<22>")
	)
	(gr_poly
		(pts
			(xy 326.28078 -283.932122) (xy 326.28078 -283.741622) (xy 326.17918 -283.705554) (xy 326.12838 -283.705554)
			(xy 326.12838 -283.968444) (xy 326.17918 -283.968444)
		)
		(stroke
			(width 0)
			(type solid)
		)
		(fill yes)
		(layer "F.Cu")
		(net "M_A_CPU0_SA_DQ<22>")
	)
	(gr_poly
		(pts
			(xy 326.28078 -283.335222) (xy 326.28078 -283.144722) (xy 326.17918 -283.108654) (xy 326.12838 -283.108654)
			(xy 326.12838 -283.371544) (xy 326.17918 -283.371544)
		)
		(stroke
			(width 0)
			(type solid)
		)
		(fill yes)
		(layer "F.Cu")
		(net "M_A_CPU0_SA_DQ<22>")
	)
	(gr_poly
		(pts
			(xy 326.28078 -282.738322) (xy 326.28078 -282.547822) (xy 326.17918 -282.511754) (xy 326.12838 -282.511754)
			(xy 326.12838 -282.774644) (xy 326.17918 -282.774644)
		)
		(stroke
			(width 0)
			(type solid)
		)
		(fill yes)
		(layer "F.Cu")
		(net "M_A_CPU0_SA_DQ<22>")
	)
	(gr_poly
		(pts
			(xy 326.28078 -282.141422) (xy 326.28078 -281.950922) (xy 326.17918 -281.914854) (xy 326.12838 -281.914854)
			(xy 326.12838 -282.177744) (xy 326.17918 -282.177744)
		)
		(stroke
			(width 0)
			(type solid)
		)
		(fill yes)
		(layer "F.Cu")
		(net "M_A_CPU0_SA_DQ<22>")
	)
	(gr_poly
		(pts
			(xy 326.300084 -279.86355) (xy 326.337422 -279.67686) (xy 326.244966 -279.621488) (xy 326.195182 -279.611582)
			(xy 326.14362 -279.869392) (xy 326.193404 -279.879298)
		)
		(stroke
			(width 0)
			(type solid)
		)
		(fill yes)
		(layer "F.Cu")
		(net "M_A_CPU0_SA_DQ<21>")
	)
	(gr_poly
		(pts
			(xy 326.301608 -249.270266) (xy 326.26554 -249.168666) (xy 326.07504 -249.168666) (xy 326.038718 -249.270266)
			(xy 326.038718 -249.321066) (xy 326.301608 -249.321066)
		)
		(stroke
			(width 0)
			(type solid)
		)
		(fill yes)
		(layer "F.Cu")
		(net "M_A_CPU0_SB_CA<0>")
	)
	(gr_poly
		(pts
			(xy 326.301608 -248.965212) (xy 326.26554 -248.863612) (xy 326.07504 -248.863612) (xy 326.038718 -248.965212)
			(xy 326.038718 -249.016012) (xy 326.301608 -249.016012)
		)
		(stroke
			(width 0)
			(type solid)
		)
		(fill yes)
		(layer "F.Cu")
		(net "M_A_CPU0_SB_CA<1>")
	)
	(gr_poly
		(pts
			(xy 326.301608 -248.660412) (xy 326.26554 -248.558812) (xy 326.07504 -248.558812) (xy 326.038718 -248.660412)
			(xy 326.038718 -248.711212) (xy 326.301608 -248.711212)
		)
		(stroke
			(width 0)
			(type solid)
		)
		(fill yes)
		(layer "F.Cu")
		(net "M_A_CPU0_SB_CA<2>")
	)
	(gr_poly
		(pts
			(xy 326.301608 -248.355612) (xy 326.26554 -248.254012) (xy 326.07504 -248.254012) (xy 326.038718 -248.355612)
			(xy 326.038718 -248.406412) (xy 326.301608 -248.406412)
		)
		(stroke
			(width 0)
			(type solid)
		)
		(fill yes)
		(layer "F.Cu")
		(net "M_A_CPU0_SB_CA<3>")
	)
	(gr_poly
		(pts
			(xy 326.301608 -248.050812) (xy 326.26554 -247.949212) (xy 326.07504 -247.949212) (xy 326.038718 -248.050812)
			(xy 326.038718 -248.101612) (xy 326.301608 -248.101612)
		)
		(stroke
			(width 0)
			(type solid)
		)
		(fill yes)
		(layer "F.Cu")
		(net "M_A_CPU0_SB_CA<4>")
	)
	(gr_poly
		(pts
			(xy 326.301608 -247.746012) (xy 326.26554 -247.644412) (xy 326.07504 -247.644412) (xy 326.038718 -247.746012)
			(xy 326.038718 -247.796812) (xy 326.301608 -247.796812)
		)
		(stroke
			(width 0)
			(type solid)
		)
		(fill yes)
		(layer "F.Cu")
		(net "M_A_CPU0_SB_CA<5>")
	)
	(gr_poly
		(pts
			(xy 326.301608 -247.441212) (xy 326.26554 -247.339612) (xy 326.07504 -247.339612) (xy 326.038718 -247.441212)
			(xy 326.038718 -247.492012) (xy 326.301608 -247.492012)
		)
		(stroke
			(width 0)
			(type solid)
		)
		(fill yes)
		(layer "F.Cu")
		(net "M_A_CPU0_SB_CA<6>")
	)
	(gr_poly
		(pts
			(xy 326.301608 -247.136412) (xy 326.26554 -247.034812) (xy 326.07504 -247.034812) (xy 326.038718 -247.136412)
			(xy 326.038718 -247.187212) (xy 326.301608 -247.187212)
		)
		(stroke
			(width 0)
			(type solid)
		)
		(fill yes)
		(layer "F.Cu")
		(net "M_A_CPU0_SB_PAR")
	)
	(gr_poly
		(pts
			(xy 326.301608 -246.831612) (xy 326.26554 -246.730012) (xy 326.07504 -246.730012) (xy 326.038718 -246.831612)
			(xy 326.038718 -246.882412) (xy 326.301608 -246.882412)
		)
		(stroke
			(width 0)
			(type solid)
		)
		(fill yes)
		(layer "F.Cu")
		(net "M_A_CPU0_SB_CS_N<2>")
	)
	(gr_poly
		(pts
			(xy 326.301608 -246.526812) (xy 326.26554 -246.425212) (xy 326.07504 -246.425212) (xy 326.038718 -246.526812)
			(xy 326.038718 -246.577612) (xy 326.301608 -246.577612)
		)
		(stroke
			(width 0)
			(type solid)
		)
		(fill yes)
		(layer "F.Cu")
		(net "M_A_CPU0_SB_CS_N<0>")
	)
	(gr_poly
		(pts
			(xy 326.301608 -246.222012) (xy 326.26554 -246.120412) (xy 326.07504 -246.120412) (xy 326.038718 -246.222012)
			(xy 326.038718 -246.272812) (xy 326.301608 -246.272812)
		)
		(stroke
			(width 0)
			(type solid)
		)
		(fill yes)
		(layer "F.Cu")
		(net "M_A_CPU0_SB_CS_N<3>")
	)
	(gr_poly
		(pts
			(xy 326.301608 -245.917212) (xy 326.26554 -245.815612) (xy 326.07504 -245.815612) (xy 326.038718 -245.917212)
			(xy 326.038718 -245.968012) (xy 326.301608 -245.968012)
		)
		(stroke
			(width 0)
			(type solid)
		)
		(fill yes)
		(layer "F.Cu")
		(net "M_A_CPU0_SB_CS_N<1>")
	)
	(gr_poly
		(pts
			(xy 326.309482 -229.873302) (xy 326.34555 -229.837488) (xy 326.159622 -229.65156) (xy 326.123808 -229.687374)
			(xy 326.077326 -229.78491) (xy 326.2122 -229.91953)
		)
		(stroke
			(width 0)
			(type solid)
		)
		(fill yes)
		(layer "F.Cu")
		(net "M_A_CPU0_SB_DQ<12>")
	)
	(gr_poly
		(pts
			(xy 326.31888 -280.54935) (xy 326.269096 -280.53919) (xy 326.162416 -280.554938) (xy 326.125078 -280.741628)
			(xy 326.217788 -280.797) (xy 326.267572 -280.806906)
		)
		(stroke
			(width 0)
			(type solid)
		)
		(fill yes)
		(layer "F.Cu")
		(net "M_A_CPU0_SA_DQ<22>")
	)
	(gr_poly
		(pts
			(xy 326.3265 -271.727168) (xy 326.280272 -271.629632) (xy 326.244204 -271.593818) (xy 326.05853 -271.779492)
			(xy 326.094344 -271.81556) (xy 326.19188 -271.861788)
		)
		(stroke
			(width 0)
			(type solid)
		)
		(fill yes)
		(layer "F.Cu")
		(net "M_A_CPU0_SA_DQ<29>")
	)
	(gr_poly
		(pts
			(xy 326.336152 -272.580862) (xy 326.289924 -272.483326) (xy 326.253856 -272.447512) (xy 326.067928 -272.63344)
			(xy 326.103996 -272.669254) (xy 326.201278 -272.715482)
		)
		(stroke
			(width 0)
			(type solid)
		)
		(fill yes)
		(layer "F.Cu")
		(net "M_A_CPU0_SA_DQ<28>")
	)
	(gr_poly
		(pts
			(xy 326.338946 -232.7783) (xy 326.385174 -232.680764) (xy 326.250554 -232.546144) (xy 326.153018 -232.592372)
			(xy 326.117204 -232.628186) (xy 326.303132 -232.814114)
		)
		(stroke
			(width 0)
			(type solid)
		)
		(fill yes)
		(layer "F.Cu")
		(net "M_A_CPU0_SB_DQ<10>")
	)
	(gr_poly
		(pts
			(xy 326.348344 -231.92486) (xy 326.394572 -231.827324) (xy 326.259698 -231.692704) (xy 326.162416 -231.738932)
			(xy 326.126348 -231.774746) (xy 326.312276 -231.960674)
		)
		(stroke
			(width 0)
			(type solid)
		)
		(fill yes)
		(layer "F.Cu")
		(net "M_A_CPU0_SB_DQ<11>")
	)
	(gr_poly
		(pts
			(xy 326.351646 -278.047958) (xy 326.388984 -277.861014) (xy 326.296274 -277.805642) (xy 326.24649 -277.795736)
			(xy 326.194928 -278.053546) (xy 326.244966 -278.063452)
		)
		(stroke
			(width 0)
			(type solid)
		)
		(fill yes)
		(layer "F.Cu")
		(net "M_A_CPU0_SA_DQ<23>")
	)
	(gr_poly
		(pts
			(xy 326.359774 -263.954768) (xy 326.32396 -263.9187) (xy 326.226424 -263.872472) (xy 326.091804 -264.007092)
			(xy 326.138032 -264.104628) (xy 326.1741 -264.140442)
		)
		(stroke
			(width 0)
			(type solid)
		)
		(fill yes)
		(layer "F.Cu")
		(net "M_A_CPU0_SA_CB<7>")
	)
	(gr_poly
		(pts
			(xy 326.365616 -281.09418) (xy 326.402954 -280.907236) (xy 326.310244 -280.851864) (xy 326.26046 -280.841958)
			(xy 326.209152 -281.099768) (xy 326.258936 -281.109674)
		)
		(stroke
			(width 0)
			(type solid)
		)
		(fill yes)
		(layer "F.Cu")
		(net "M_A_CPU0_SA_DQ<22>")
	)
	(gr_poly
		(pts
			(xy 326.369426 -264.808208) (xy 326.333358 -264.772394) (xy 326.236076 -264.726166) (xy 326.101202 -264.860786)
			(xy 326.14743 -264.958322) (xy 326.183498 -264.994136)
		)
		(stroke
			(width 0)
			(type solid)
		)
		(fill yes)
		(layer "F.Cu")
		(net "M_A_CPU0_SA_CB<6>")
	)
	(gr_poly
		(pts
			(xy 326.370442 -278.733504) (xy 326.320658 -278.723598) (xy 326.213724 -278.739092) (xy 326.17664 -278.926036)
			(xy 326.269096 -278.981408) (xy 326.31888 -278.991314)
		)
		(stroke
			(width 0)
			(type solid)
		)
		(fill yes)
		(layer "F.Cu")
		(net "M_A_CPU0_SA_DQ<21>")
	)
	(gr_poly
		(pts
			(xy 326.373998 -274.484846) (xy 326.338184 -274.448778) (xy 326.240648 -274.40255) (xy 326.106028 -274.537424)
			(xy 326.152256 -274.634706) (xy 326.18807 -274.670774)
		)
		(stroke
			(width 0)
			(type solid)
		)
		(fill yes)
		(layer "F.Cu")
		(net "M_A_CPU0_SA_DQ<27>")
	)
	(gr_poly
		(pts
			(xy 326.374506 -267.391134) (xy 326.338438 -267.35532) (xy 326.240902 -267.309092) (xy 326.106282 -267.443712)
			(xy 326.15251 -267.541248) (xy 326.188578 -267.577062)
		)
		(stroke
			(width 0)
			(type solid)
		)
		(fill yes)
		(layer "F.Cu")
		(net "M_A_CPU0_SA_CB<3>")
	)
	(gr_poly
		(pts
			(xy 326.380856 -225.231452) (xy 326.41667 -225.195384) (xy 326.230996 -225.00971) (xy 326.194928 -225.045524)
			(xy 326.1487 -225.14306) (xy 326.28332 -225.27768)
		)
		(stroke
			(width 0)
			(type solid)
		)
		(fill yes)
		(layer "F.Cu")
		(net "M_A_CPU0_SB_DQ<18>")
	)
	(gr_poly
		(pts
			(xy 326.38365 -268.244828) (xy 326.347836 -268.20876) (xy 326.2503 -268.162532) (xy 326.11568 -268.297406)
			(xy 326.161908 -268.394688) (xy 326.197722 -268.430756)
		)
		(stroke
			(width 0)
			(type solid)
		)
		(fill yes)
		(layer "F.Cu")
		(net "M_A_CPU0_SA_CB<2>")
	)
	(gr_poly
		(pts
			(xy 326.38619 -229.3747) (xy 326.432418 -229.277164) (xy 326.297798 -229.142544) (xy 326.200262 -229.188772)
			(xy 326.164448 -229.22484) (xy 326.350122 -229.410514)
		)
		(stroke
			(width 0)
			(type solid)
		)
		(fill yes)
		(layer "F.Cu")
		(net "M_A_CPU0_SB_DQ<14>")
	)
	(gr_poly
		(pts
			(xy 326.39 -224.378012) (xy 326.426068 -224.342198) (xy 326.24014 -224.15627) (xy 326.204326 -224.192084)
			(xy 326.157844 -224.28962) (xy 326.292718 -224.42424)
		)
		(stroke
			(width 0)
			(type solid)
		)
		(fill yes)
		(layer "F.Cu")
		(net "M_A_CPU0_SB_DQ<19>")
	)
	(gr_poly
		(pts
			(xy 326.416924 -279.278334) (xy 326.454262 -279.09139) (xy 326.361806 -279.036018) (xy 326.312022 -279.026112)
			(xy 326.26046 -279.283922) (xy 326.310244 -279.293828)
		)
		(stroke
			(width 0)
			(type solid)
		)
		(fill yes)
		(layer "F.Cu")
		(net "M_A_CPU0_SA_DQ<21>")
	)
	(gr_poly
		(pts
			(xy 326.42048 -276.367748) (xy 326.34809 -276.287992) (xy 326.303132 -276.264116) (xy 326.17918 -276.496018)
			(xy 326.224138 -276.519894) (xy 326.330818 -276.535896)
		)
		(stroke
			(width 0)
			(type solid)
		)
		(fill yes)
		(layer "F.Cu")
		(net "M_A_CPU0_SA_DQ<24>")
	)
	(gr_poly
		(pts
			(xy 326.430132 -227.249736) (xy 326.430132 -227.059236) (xy 326.328532 -227.022914) (xy 326.277732 -227.022914)
			(xy 326.277732 -227.286058) (xy 326.328532 -227.286058)
		)
		(stroke
			(width 0)
			(type solid)
		)
		(fill yes)
		(layer "F.Cu")
		(net "M_A_CPU0_SB_DQ<16>")
	)
	(gr_poly
		(pts
			(xy 326.430132 -226.652836) (xy 326.430132 -226.462336) (xy 326.328532 -226.426014) (xy 326.277732 -226.426014)
			(xy 326.277732 -226.689158) (xy 326.328532 -226.689158)
		)
		(stroke
			(width 0)
			(type solid)
		)
		(fill yes)
		(layer "F.Cu")
		(net "M_A_CPU0_SB_DQ<16>")
	)
	(gr_poly
		(pts
			(xy 326.430132 -226.055936) (xy 326.430132 -225.865436) (xy 326.328532 -225.829114) (xy 326.277732 -225.829114)
			(xy 326.277732 -226.092258) (xy 326.328532 -226.092258)
		)
		(stroke
			(width 0)
			(type solid)
		)
		(fill yes)
		(layer "F.Cu")
		(net "M_A_CPU0_SB_DQ<16>")
	)
	(gr_poly
		(pts
			(xy 326.432926 -275.697696) (xy 326.360536 -275.61794) (xy 326.315578 -275.59381) (xy 326.191626 -275.825712)
			(xy 326.236584 -275.849842) (xy 326.343264 -275.86559)
		)
		(stroke
			(width 0)
			(type solid)
		)
		(fill yes)
		(layer "F.Cu")
		(net "M_A_CPU0_SA_DQ<26>")
	)
	(gr_poly
		(pts
			(xy 326.43318 -286.988504) (xy 326.38238 -286.988504) (xy 326.28078 -287.024826) (xy 326.28078 -287.215326)
			(xy 326.38238 -287.251394) (xy 326.43318 -287.251394)
		)
		(stroke
			(width 0)
			(type solid)
		)
		(fill yes)
		(layer "F.Cu")
		(net "M_A_CPU0_SA_DQ<20>")
	)
	(gr_poly
		(pts
			(xy 326.43318 -286.391604) (xy 326.38238 -286.391604) (xy 326.28078 -286.427926) (xy 326.28078 -286.618426)
			(xy 326.38238 -286.654494) (xy 326.43318 -286.654494)
		)
		(stroke
			(width 0)
			(type solid)
		)
		(fill yes)
		(layer "F.Cu")
		(net "M_A_CPU0_SA_DQ<20>")
	)
	(gr_poly
		(pts
			(xy 326.43318 -285.794704) (xy 326.38238 -285.794704) (xy 326.28078 -285.831026) (xy 326.28078 -286.021526)
			(xy 326.38238 -286.057594) (xy 326.43318 -286.057594)
		)
		(stroke
			(width 0)
			(type solid)
		)
		(fill yes)
		(layer "F.Cu")
		(net "M_A_CPU0_SA_DQ<20>")
	)
	(gr_poly
		(pts
			(xy 326.43318 -285.197804) (xy 326.38238 -285.197804) (xy 326.28078 -285.234126) (xy 326.28078 -285.424626)
			(xy 326.38238 -285.460694) (xy 326.43318 -285.460694)
		)
		(stroke
			(width 0)
			(type solid)
		)
		(fill yes)
		(layer "F.Cu")
		(net "M_A_CPU0_SA_DQ<20>")
	)
	(gr_poly
		(pts
			(xy 326.43318 -284.600904) (xy 326.38238 -284.600904) (xy 326.28078 -284.637226) (xy 326.28078 -284.827726)
			(xy 326.38238 -284.863794) (xy 326.43318 -284.863794)
		)
		(stroke
			(width 0)
			(type solid)
		)
		(fill yes)
		(layer "F.Cu")
		(net "M_A_CPU0_SA_DQ<20>")
	)
	(gr_poly
		(pts
			(xy 326.43318 -284.004004) (xy 326.38238 -284.004004) (xy 326.28078 -284.040326) (xy 326.28078 -284.230826)
			(xy 326.38238 -284.266894) (xy 326.43318 -284.266894)
		)
		(stroke
			(width 0)
			(type solid)
		)
		(fill yes)
		(layer "F.Cu")
		(net "M_A_CPU0_SA_DQ<20>")
	)
	(gr_poly
		(pts
			(xy 326.43318 -283.407104) (xy 326.38238 -283.407104) (xy 326.28078 -283.443426) (xy 326.28078 -283.633926)
			(xy 326.38238 -283.669994) (xy 326.43318 -283.669994)
		)
		(stroke
			(width 0)
			(type solid)
		)
		(fill yes)
		(layer "F.Cu")
		(net "M_A_CPU0_SA_DQ<20>")
	)
	(gr_poly
		(pts
			(xy 326.43318 -282.810204) (xy 326.38238 -282.810204) (xy 326.28078 -282.846526) (xy 326.28078 -283.037026)
			(xy 326.38238 -283.073094) (xy 326.43318 -283.073094)
		)
		(stroke
			(width 0)
			(type solid)
		)
		(fill yes)
		(layer "F.Cu")
		(net "M_A_CPU0_SA_DQ<20>")
	)
	(gr_poly
		(pts
			(xy 326.43318 -282.213304) (xy 326.38238 -282.213304) (xy 326.28078 -282.249626) (xy 326.28078 -282.440126)
			(xy 326.38238 -282.476194) (xy 326.43318 -282.476194)
		)
		(stroke
			(width 0)
			(type solid)
		)
		(fill yes)
		(layer "F.Cu")
		(net "M_A_CPU0_SA_DQ<20>")
	)
	(gr_poly
		(pts
			(xy 326.435974 -279.96388) (xy 326.38619 -279.953974) (xy 326.279256 -279.969468) (xy 326.242172 -280.156412)
			(xy 326.334628 -280.211784) (xy 326.384412 -280.22169)
		)
		(stroke
			(width 0)
			(type solid)
		)
		(fill yes)
		(layer "F.Cu")
		(net "M_A_CPU0_SA_DQ<22>")
	)
	(gr_poly
		(pts
			(xy 326.443848 -276.000718) (xy 326.399144 -275.976842) (xy 326.292464 -275.96084) (xy 326.202548 -276.128988)
			(xy 326.275192 -276.208744) (xy 326.319896 -276.23262)
		)
		(stroke
			(width 0)
			(type solid)
		)
		(fill yes)
		(layer "F.Cu")
		(net "M_A_CPU0_SA_DQ<24>")
	)
	(gr_poly
		(pts
			(xy 326.446896 -264.514838) (xy 326.400414 -264.417302) (xy 326.3646 -264.381488) (xy 326.178672 -264.567416)
			(xy 326.21474 -264.60323) (xy 326.312022 -264.649458)
		)
		(stroke
			(width 0)
			(type solid)
		)
		(fill yes)
		(layer "F.Cu")
		(net "M_A_CPU0_SA_CB<5>")
	)
	(gr_poly
		(pts
			(xy 326.455278 -271.382744) (xy 326.419464 -271.346676) (xy 326.321928 -271.300448) (xy 326.187308 -271.435322)
			(xy 326.233536 -271.532604) (xy 326.26935 -271.568672)
		)
		(stroke
			(width 0)
			(type solid)
		)
		(fill yes)
		(layer "F.Cu")
		(net "M_A_CPU0_SA_DQ<29>")
	)
	(gr_poly
		(pts
			(xy 326.456294 -265.368532) (xy 326.410066 -265.270996) (xy 326.373998 -265.235182) (xy 326.18807 -265.42111)
			(xy 326.224138 -265.456924) (xy 326.32142 -265.503152)
		)
		(stroke
			(width 0)
			(type solid)
		)
		(fill yes)
		(layer "F.Cu")
		(net "M_A_CPU0_SA_CB<4>")
	)
	(gr_poly
		(pts
			(xy 326.456548 -275.330666) (xy 326.411844 -275.30679) (xy 326.305164 -275.290788) (xy 326.215248 -275.458682)
			(xy 326.287892 -275.538692) (xy 326.332596 -275.562568)
		)
		(stroke
			(width 0)
			(type solid)
		)
		(fill yes)
		(layer "F.Cu")
		(net "M_A_CPU0_SA_DQ<26>")
	)
	(gr_poly
		(pts
			(xy 326.45731 -224.73285) (xy 326.503538 -224.635568) (xy 326.368918 -224.500694) (xy 326.271382 -224.546922)
			(xy 326.235568 -224.58299) (xy 326.421496 -224.768918)
		)
		(stroke
			(width 0)
			(type solid)
		)
		(fill yes)
		(layer "F.Cu")
		(net "M_A_CPU0_SB_DQ<17>")
	)
	(gr_poly
		(pts
			(xy 326.46112 -267.951204) (xy 326.414892 -267.853922) (xy 326.379078 -267.817854) (xy 326.19315 -268.003782)
			(xy 326.228964 -268.03985) (xy 326.3265 -268.086078)
		)
		(stroke
			(width 0)
			(type solid)
		)
		(fill yes)
		(layer "F.Cu")
		(net "M_A_CPU0_SA_CB<1>")
	)
	(gr_poly
		(pts
			(xy 326.46493 -272.236438) (xy 326.429116 -272.20037) (xy 326.33158 -272.154142) (xy 326.19696 -272.289016)
			(xy 326.243188 -272.386298) (xy 326.279002 -272.422366)
		)
		(stroke
			(width 0)
			(type solid)
		)
		(fill yes)
		(layer "F.Cu")
		(net "M_A_CPU0_SA_DQ<28>")
	)
	(gr_poly
		(pts
			(xy 326.470518 -268.804898) (xy 326.42429 -268.707362) (xy 326.388222 -268.671548) (xy 326.202548 -268.857222)
			(xy 326.238362 -268.89329) (xy 326.335898 -268.939518)
		)
		(stroke
			(width 0)
			(type solid)
		)
		(fill yes)
		(layer "F.Cu")
		(net "M_A_CPU0_SA_CB<0>")
	)
	(gr_poly
		(pts
			(xy 326.478138 -233.061002) (xy 326.514206 -233.025188) (xy 326.328278 -232.83926) (xy 326.29221 -232.875074)
			(xy 326.245982 -232.97261) (xy 326.380856 -233.10723)
		)
		(stroke
			(width 0)
			(type solid)
		)
		(fill yes)
		(layer "F.Cu")
		(net "M_A_CPU0_SB_DQ<10>")
	)
	(gr_poly
		(pts
			(xy 326.482456 -280.50871) (xy 326.519794 -280.32202) (xy 326.427338 -280.266394) (xy 326.377554 -280.256488)
			(xy 326.325992 -280.514298) (xy 326.375776 -280.524204)
		)
		(stroke
			(width 0)
			(type solid)
		)
		(fill yes)
		(layer "F.Cu")
		(net "M_A_CPU0_SA_DQ<22>")
	)
	(gr_poly
		(pts
			(xy 326.487282 -278.148034) (xy 326.437498 -278.138128) (xy 326.330818 -278.153876) (xy 326.29348 -278.340566)
			(xy 326.385936 -278.395938) (xy 326.43572 -278.405844)
		)
		(stroke
			(width 0)
			(type solid)
		)
		(fill yes)
		(layer "F.Cu")
		(net "M_A_CPU0_SA_DQ<21>")
	)
	(gr_poly
		(pts
			(xy 326.487536 -232.207562) (xy 326.52335 -232.171748) (xy 326.337422 -231.98582) (xy 326.301608 -232.021888)
			(xy 326.25538 -232.11917) (xy 326.39 -232.254044)
		)
		(stroke
			(width 0)
			(type solid)
		)
		(fill yes)
		(layer "F.Cu")
		(net "M_A_CPU0_SB_DQ<11>")
	)
	(gr_poly
		(pts
			(xy 326.525382 -229.657656) (xy 326.561196 -229.621588) (xy 326.375268 -229.43566) (xy 326.339454 -229.471728)
			(xy 326.293226 -229.56901) (xy 326.427846 -229.703884)
		)
		(stroke
			(width 0)
			(type solid)
		)
		(fill yes)
		(layer "F.Cu")
		(net "M_A_CPU0_SB_DQ<14>")
	)
	(gr_poly
		(pts
			(xy 326.532748 -271.08912) (xy 326.48652 -270.991838) (xy 326.450706 -270.95577) (xy 326.264778 -271.141698)
			(xy 326.300592 -271.177766) (xy 326.398128 -271.223994)
		)
		(stroke
			(width 0)
			(type solid)
		)
		(fill yes)
		(layer "F.Cu")
		(net "M_A_CPU0_SA_DQ<31>")
	)
	(gr_poly
		(pts
			(xy 326.533764 -278.692864) (xy 326.571102 -278.506174) (xy 326.478646 -278.450802) (xy 326.428862 -278.440896)
			(xy 326.3773 -278.698706) (xy 326.427084 -278.708612)
		)
		(stroke
			(width 0)
			(type solid)
		)
		(fill yes)
		(layer "F.Cu")
		(net "M_A_CPU0_SA_DQ<21>")
	)
	(gr_poly
		(pts
			(xy 326.534526 -228.804216) (xy 326.570594 -228.768402) (xy 326.384666 -228.582474) (xy 326.348598 -228.618288)
			(xy 326.30237 -228.715824) (xy 326.437244 -228.850444)
		)
		(stroke
			(width 0)
			(type solid)
		)
		(fill yes)
		(layer "F.Cu")
		(net "M_A_CPU0_SB_DQ<15>")
	)
	(gr_poly
		(pts
			(xy 326.5424 -271.943068) (xy 326.496172 -271.845532) (xy 326.460358 -271.809718) (xy 326.27443 -271.995646)
			(xy 326.310498 -272.03146) (xy 326.40778 -272.077688)
		)
		(stroke
			(width 0)
			(type solid)
		)
		(fill yes)
		(layer "F.Cu")
		(net "M_A_CPU0_SA_DQ<30>")
	)
	(gr_poly
		(pts
			(xy 326.545448 -233.41584) (xy 326.591676 -233.318558) (xy 326.457056 -233.183684) (xy 326.35952 -233.229912)
			(xy 326.323706 -233.26598) (xy 326.509634 -233.451908)
		)
		(stroke
			(width 0)
			(type solid)
		)
		(fill yes)
		(layer "F.Cu")
		(net "M_A_CPU0_SB_DQ<8>")
	)
	(gr_poly
		(pts
			(xy 326.552814 -279.378664) (xy 326.50303 -279.368504) (xy 326.39635 -279.384252) (xy 326.359012 -279.570942)
			(xy 326.451468 -279.626314) (xy 326.501252 -279.636474)
		)
		(stroke
			(width 0)
			(type solid)
		)
		(fill yes)
		(layer "F.Cu")
		(net "M_A_CPU0_SA_DQ<22>")
	)
	(gr_poly
		(pts
			(xy 326.554592 -232.562654) (xy 326.60082 -232.465118) (xy 326.4662 -232.330498) (xy 326.368664 -232.376726)
			(xy 326.33285 -232.41254) (xy 326.518778 -232.598468)
		)
		(stroke
			(width 0)
			(type solid)
		)
		(fill yes)
		(layer "F.Cu")
		(net "M_A_CPU0_SB_DQ<9>")
	)
	(gr_poly
		(pts
			(xy 326.575674 -264.170414) (xy 326.539606 -264.1346) (xy 326.442324 -264.088372) (xy 326.307704 -264.222992)
			(xy 326.353932 -264.320528) (xy 326.389746 -264.356342)
		)
		(stroke
			(width 0)
			(type solid)
		)
		(fill yes)
		(layer "F.Cu")
		(net "M_A_CPU0_SA_CB<5>")
	)
	(gr_poly
		(pts
			(xy 326.582532 -226.724718) (xy 326.531732 -226.724718) (xy 326.430132 -226.760786) (xy 326.430132 -226.951286)
			(xy 326.531732 -226.987354) (xy 326.582532 -226.987354)
		)
		(stroke
			(width 0)
			(type solid)
		)
		(fill yes)
		(layer "F.Cu")
		(net "M_A_CPU0_SB_DQ<18>")
	)
	(gr_poly
		(pts
			(xy 326.582532 -226.127818) (xy 326.531732 -226.127818) (xy 326.430132 -226.163886) (xy 326.430132 -226.354386)
			(xy 326.531732 -226.390454) (xy 326.582532 -226.390454)
		)
		(stroke
			(width 0)
			(type solid)
		)
		(fill yes)
		(layer "F.Cu")
		(net "M_A_CPU0_SB_DQ<18>")
	)
	(gr_poly
		(pts
			(xy 326.582532 -225.530918) (xy 326.531732 -225.530918) (xy 326.430132 -225.566986) (xy 326.430132 -225.757486)
			(xy 326.531732 -225.793554) (xy 326.582532 -225.793554)
		)
		(stroke
			(width 0)
			(type solid)
		)
		(fill yes)
		(layer "F.Cu")
		(net "M_A_CPU0_SB_DQ<18>")
	)
	(gr_poly
		(pts
			(xy 326.585072 -265.024108) (xy 326.549258 -264.98804) (xy 326.451722 -264.941812) (xy 326.317102 -265.076686)
			(xy 326.36333 -265.173968) (xy 326.399144 -265.210036)
		)
		(stroke
			(width 0)
			(type solid)
		)
		(fill yes)
		(layer "F.Cu")
		(net "M_A_CPU0_SA_CB<4>")
	)
	(gr_poly
		(pts
			(xy 326.58558 -287.513522) (xy 326.58558 -287.323022) (xy 326.48398 -287.286954) (xy 326.43318 -287.286954)
			(xy 326.43318 -287.549844) (xy 326.48398 -287.549844)
		)
		(stroke
			(width 0)
			(type solid)
		)
		(fill yes)
		(layer "F.Cu")
		(net "M_A_CPU0_SA_DQ<20>")
	)
	(gr_poly
		(pts
			(xy 326.58558 -286.916622) (xy 326.58558 -286.726122) (xy 326.48398 -286.690054) (xy 326.43318 -286.690054)
			(xy 326.43318 -286.952944) (xy 326.48398 -286.952944)
		)
		(stroke
			(width 0)
			(type solid)
		)
		(fill yes)
		(layer "F.Cu")
		(net "M_A_CPU0_SA_DQ<20>")
	)
	(gr_poly
		(pts
			(xy 326.58558 -286.319722) (xy 326.58558 -286.129222) (xy 326.48398 -286.093154) (xy 326.43318 -286.093154)
			(xy 326.43318 -286.356044) (xy 326.48398 -286.356044)
		)
		(stroke
			(width 0)
			(type solid)
		)
		(fill yes)
		(layer "F.Cu")
		(net "M_A_CPU0_SA_DQ<20>")
	)
	(gr_poly
		(pts
			(xy 326.58558 -285.722822) (xy 326.58558 -285.532322) (xy 326.48398 -285.496254) (xy 326.43318 -285.496254)
			(xy 326.43318 -285.759144) (xy 326.48398 -285.759144)
		)
		(stroke
			(width 0)
			(type solid)
		)
		(fill yes)
		(layer "F.Cu")
		(net "M_A_CPU0_SA_DQ<20>")
	)
	(gr_poly
		(pts
			(xy 326.58558 -285.125922) (xy 326.58558 -284.935422) (xy 326.48398 -284.899354) (xy 326.43318 -284.899354)
			(xy 326.43318 -285.162244) (xy 326.48398 -285.162244)
		)
		(stroke
			(width 0)
			(type solid)
		)
		(fill yes)
		(layer "F.Cu")
		(net "M_A_CPU0_SA_DQ<20>")
	)
	(gr_poly
		(pts
			(xy 326.58558 -284.529022) (xy 326.58558 -284.338522) (xy 326.48398 -284.302454) (xy 326.43318 -284.302454)
			(xy 326.43318 -284.565344) (xy 326.48398 -284.565344)
		)
		(stroke
			(width 0)
			(type solid)
		)
		(fill yes)
		(layer "F.Cu")
		(net "M_A_CPU0_SA_DQ<20>")
	)
	(gr_poly
		(pts
			(xy 326.58558 -283.932122) (xy 326.58558 -283.741622) (xy 326.48398 -283.705554) (xy 326.43318 -283.705554)
			(xy 326.43318 -283.968444) (xy 326.48398 -283.968444)
		)
		(stroke
			(width 0)
			(type solid)
		)
		(fill yes)
		(layer "F.Cu")
		(net "M_A_CPU0_SA_DQ<20>")
	)
	(gr_poly
		(pts
			(xy 326.58558 -283.335222) (xy 326.58558 -283.144722) (xy 326.48398 -283.108654) (xy 326.43318 -283.108654)
			(xy 326.43318 -283.371544) (xy 326.48398 -283.371544)
		)
		(stroke
			(width 0)
			(type solid)
		)
		(fill yes)
		(layer "F.Cu")
		(net "M_A_CPU0_SA_DQ<20>")
	)
	(gr_poly
		(pts
			(xy 326.58558 -282.738322) (xy 326.58558 -282.547822) (xy 326.48398 -282.511754) (xy 326.43318 -282.511754)
			(xy 326.43318 -282.774644) (xy 326.48398 -282.774644)
		)
		(stroke
			(width 0)
			(type solid)
		)
		(fill yes)
		(layer "F.Cu")
		(net "M_A_CPU0_SA_DQ<20>")
	)
	(gr_poly
		(pts
			(xy 326.58558 -282.141422) (xy 326.58558 -281.950922) (xy 326.48398 -281.914854) (xy 326.43318 -281.914854)
			(xy 326.43318 -282.177744) (xy 326.48398 -282.177744)
		)
		(stroke
			(width 0)
			(type solid)
		)
		(fill yes)
		(layer "F.Cu")
		(net "M_A_CPU0_SA_DQ<20>")
	)
	(gr_poly
		(pts
			(xy 326.589898 -274.700746) (xy 326.554084 -274.664678) (xy 326.456548 -274.61845) (xy 326.321928 -274.753324)
			(xy 326.368156 -274.850606) (xy 326.40397 -274.886674)
		)
		(stroke
			(width 0)
			(type solid)
		)
		(fill yes)
		(layer "F.Cu")
		(net "M_A_CPU0_SA_DQ<25>")
	)
	(gr_poly
		(pts
			(xy 326.590152 -267.60678) (xy 326.554084 -267.570966) (xy 326.456548 -267.524738) (xy 326.321928 -267.659358)
			(xy 326.368156 -267.756894) (xy 326.404224 -267.792708)
		)
		(stroke
			(width 0)
			(type solid)
		)
		(fill yes)
		(layer "F.Cu")
		(net "M_A_CPU0_SA_CB<1>")
	)
	(gr_poly
		(pts
			(xy 326.592438 -230.012494) (xy 326.638666 -229.915212) (xy 326.504046 -229.780338) (xy 326.40651 -229.826566)
			(xy 326.370696 -229.862634) (xy 326.556624 -230.048562)
		)
		(stroke
			(width 0)
			(type solid)
		)
		(fill yes)
		(layer "F.Cu")
		(net "M_A_CPU0_SB_DQ<12>")
	)
	(gr_poly
		(pts
			(xy 326.596502 -225.015806) (xy 326.632316 -224.979738) (xy 326.446642 -224.794064) (xy 326.410574 -224.829878)
			(xy 326.364346 -224.927414) (xy 326.498966 -225.062034)
		)
		(stroke
			(width 0)
			(type solid)
		)
		(fill yes)
		(layer "F.Cu")
		(net "M_A_CPU0_SB_DQ<17>")
	)
	(gr_poly
		(pts
			(xy 326.599296 -279.923494) (xy 326.63638 -279.73655) (xy 326.543924 -279.681178) (xy 326.49414 -279.671272)
			(xy 326.442578 -279.929082) (xy 326.492362 -279.938988)
		)
		(stroke
			(width 0)
			(type solid)
		)
		(fill yes)
		(layer "F.Cu")
		(net "M_A_CPU0_SA_DQ<22>")
	)
	(gr_poly
		(pts
			(xy 326.599296 -268.460474) (xy 326.563482 -268.424406) (xy 326.465946 -268.378178) (xy 326.331326 -268.513052)
			(xy 326.377554 -268.610334) (xy 326.413368 -268.646402)
		)
		(stroke
			(width 0)
			(type solid)
		)
		(fill yes)
		(layer "F.Cu")
		(net "M_A_CPU0_SA_CB<0>")
	)
	(gr_poly
		(pts
			(xy 326.600058 -249.371866) (xy 326.600058 -249.321066) (xy 326.337168 -249.321066) (xy 326.337168 -249.371866)
			(xy 326.373236 -249.473466) (xy 326.563736 -249.473466)
		)
		(stroke
			(width 0)
			(type solid)
		)
		(fill yes)
		(layer "F.Cu")
		(net "M_A_CPU0_SB_CA<0>")
	)
	(gr_poly
		(pts
			(xy 326.600058 -249.066812) (xy 326.600058 -249.016012) (xy 326.337168 -249.016012) (xy 326.337168 -249.066812)
			(xy 326.373236 -249.168412) (xy 326.563736 -249.168412)
		)
		(stroke
			(width 0)
			(type solid)
		)
		(fill yes)
		(layer "F.Cu")
		(net "M_A_CPU0_SB_CA<1>")
	)
	(gr_poly
		(pts
			(xy 326.600058 -248.762012) (xy 326.600058 -248.711212) (xy 326.337168 -248.711212) (xy 326.337168 -248.762012)
			(xy 326.373236 -248.863612) (xy 326.563736 -248.863612)
		)
		(stroke
			(width 0)
			(type solid)
		)
		(fill yes)
		(layer "F.Cu")
		(net "M_A_CPU0_SB_CA<2>")
	)
	(gr_poly
		(pts
			(xy 326.600058 -248.457212) (xy 326.600058 -248.406412) (xy 326.337168 -248.406412) (xy 326.337168 -248.457212)
			(xy 326.373236 -248.558812) (xy 326.563736 -248.558812)
		)
		(stroke
			(width 0)
			(type solid)
		)
		(fill yes)
		(layer "F.Cu")
		(net "M_A_CPU0_SB_CA<3>")
	)
	(gr_poly
		(pts
			(xy 326.600058 -248.152412) (xy 326.600058 -248.101612) (xy 326.337168 -248.101612) (xy 326.337168 -248.152412)
			(xy 326.373236 -248.254012) (xy 326.563736 -248.254012)
		)
		(stroke
			(width 0)
			(type solid)
		)
		(fill yes)
		(layer "F.Cu")
		(net "M_A_CPU0_SB_CA<4>")
	)
	(gr_poly
		(pts
			(xy 326.600058 -247.847612) (xy 326.600058 -247.796812) (xy 326.337168 -247.796812) (xy 326.337168 -247.847612)
			(xy 326.373236 -247.949212) (xy 326.563736 -247.949212)
		)
		(stroke
			(width 0)
			(type solid)
		)
		(fill yes)
		(layer "F.Cu")
		(net "M_A_CPU0_SB_CA<5>")
	)
	(gr_poly
		(pts
			(xy 326.600058 -247.542812) (xy 326.600058 -247.492012) (xy 326.337168 -247.492012) (xy 326.337168 -247.542812)
			(xy 326.373236 -247.644412) (xy 326.563736 -247.644412)
		)
		(stroke
			(width 0)
			(type solid)
		)
		(fill yes)
		(layer "F.Cu")
		(net "M_A_CPU0_SB_CA<6>")
	)
	(gr_poly
		(pts
			(xy 326.600058 -247.238012) (xy 326.600058 -247.187212) (xy 326.337168 -247.187212) (xy 326.337168 -247.238012)
			(xy 326.373236 -247.339612) (xy 326.563736 -247.339612)
		)
		(stroke
			(width 0)
			(type solid)
		)
		(fill yes)
		(layer "F.Cu")
		(net "M_A_CPU0_SB_PAR")
	)
	(gr_poly
		(pts
			(xy 326.600058 -246.933212) (xy 326.600058 -246.882412) (xy 326.337168 -246.882412) (xy 326.337168 -246.933212)
			(xy 326.373236 -247.034812) (xy 326.563736 -247.034812)
		)
		(stroke
			(width 0)
			(type solid)
		)
		(fill yes)
		(layer "F.Cu")
		(net "M_A_CPU0_SB_CS_N<2>")
	)
	(gr_poly
		(pts
			(xy 326.600058 -246.628412) (xy 326.600058 -246.577612) (xy 326.337168 -246.577612) (xy 326.337168 -246.628412)
			(xy 326.373236 -246.730012) (xy 326.563736 -246.730012)
		)
		(stroke
			(width 0)
			(type solid)
		)
		(fill yes)
		(layer "F.Cu")
		(net "M_A_CPU0_SB_CS_N<0>")
	)
	(gr_poly
		(pts
			(xy 326.600058 -246.323612) (xy 326.600058 -246.272812) (xy 326.337168 -246.272812) (xy 326.337168 -246.323612)
			(xy 326.373236 -246.425212) (xy 326.563736 -246.425212)
		)
		(stroke
			(width 0)
			(type solid)
		)
		(fill yes)
		(layer "F.Cu")
		(net "M_A_CPU0_SB_CS_N<3>")
	)
	(gr_poly
		(pts
			(xy 326.600058 -246.018812) (xy 326.600058 -245.968012) (xy 326.337168 -245.968012) (xy 326.337168 -246.018812)
			(xy 326.373236 -246.120412) (xy 326.563736 -246.120412)
		)
		(stroke
			(width 0)
			(type solid)
		)
		(fill yes)
		(layer "F.Cu")
		(net "M_A_CPU0_SB_CS_N<1>")
	)
	(gr_poly
		(pts
			(xy 326.601836 -229.159054) (xy 326.648064 -229.061518) (xy 326.513444 -228.926898) (xy 326.415908 -228.973126)
			(xy 326.380094 -229.009194) (xy 326.565768 -229.194868)
		)
		(stroke
			(width 0)
			(type solid)
		)
		(fill yes)
		(layer "F.Cu")
		(net "M_A_CPU0_SB_DQ<13>")
	)
	(gr_poly
		(pts
			(xy 326.611742 -227.889816) (xy 326.65797 -227.79228) (xy 326.52335 -227.65766) (xy 326.425814 -227.703888)
			(xy 326.39 -227.739702) (xy 326.575928 -227.92563)
		)
		(stroke
			(width 0)
			(type solid)
		)
		(fill yes)
		(layer "F.Cu")
		(net "M_A_CPU0_SB_DQ<16>")
	)
	(gr_poly
		(pts
			(xy 326.618346 -280.608786) (xy 326.568562 -280.59888) (xy 326.461628 -280.614628) (xy 326.42429 -280.801318)
			(xy 326.517 -280.85669) (xy 326.566784 -280.866596)
		)
		(stroke
			(width 0)
			(type solid)
		)
		(fill yes)
		(layer "F.Cu")
		(net "M_A_CPU0_SA_DQ<20>")
	)
	(gr_poly
		(pts
			(xy 326.632824 -256.570226) (xy 326.596756 -256.468626) (xy 326.406256 -256.468626) (xy 326.369934 -256.570226)
			(xy 326.369934 -256.621026) (xy 326.632824 -256.621026)
		)
		(stroke
			(width 0)
			(type solid)
		)
		(fill yes)
		(layer "F.Cu")
		(net "M_A_CPU0_SA_CA<6>")
	)
	(gr_poly
		(pts
			(xy 326.632824 -256.265426) (xy 326.596756 -256.163826) (xy 326.406256 -256.163826) (xy 326.369934 -256.265426)
			(xy 326.369934 -256.316226) (xy 326.632824 -256.316226)
		)
		(stroke
			(width 0)
			(type solid)
		)
		(fill yes)
		(layer "F.Cu")
		(net "M_A_CPU0_SA_PAR")
	)
	(gr_poly
		(pts
			(xy 326.650858 -278.107648) (xy 326.687942 -277.920704) (xy 326.595486 -277.865332) (xy 326.545702 -277.855426)
			(xy 326.49414 -278.113236) (xy 326.543924 -278.123142)
		)
		(stroke
			(width 0)
			(type solid)
		)
		(fill yes)
		(layer "F.Cu")
		(net "M_A_CPU0_SA_DQ<21>")
	)
	(gr_poly
		(pts
			(xy 326.653144 -263.877044) (xy 326.606916 -263.779508) (xy 326.570848 -263.743694) (xy 326.38492 -263.929622)
			(xy 326.420988 -263.965436) (xy 326.51827 -264.011664)
		)
		(stroke
			(width 0)
			(type solid)
		)
		(fill yes)
		(layer "F.Cu")
		(net "M_A_CPU0_SA_CB<7>")
	)
	(gr_poly
		(pts
			(xy 326.654922 -277.19655) (xy 326.582532 -277.116794) (xy 326.537828 -277.092918) (xy 326.413622 -277.324566)
			(xy 326.45858 -277.348442) (xy 326.565006 -277.364698)
		)
		(stroke
			(width 0)
			(type solid)
		)
		(fill yes)
		(layer "F.Cu")
		(net "M_A_CPU0_SA_DQ<23>")
	)
	(gr_poly
		(pts
			(xy 326.66178 -270.744696) (xy 326.625712 -270.708882) (xy 326.528176 -270.662654) (xy 326.393556 -270.797274)
			(xy 326.439784 -270.89481) (xy 326.475852 -270.930624)
		)
		(stroke
			(width 0)
			(type solid)
		)
		(fill yes)
		(layer "F.Cu")
		(net "M_A_CPU0_SA_DQ<31>")
	)
	(gr_poly
		(pts
			(xy 326.662542 -264.730738) (xy 326.616314 -264.633202) (xy 326.5805 -264.597134) (xy 326.394572 -264.783062)
			(xy 326.430386 -264.81913) (xy 326.527922 -264.865358)
		)
		(stroke
			(width 0)
			(type solid)
		)
		(fill yes)
		(layer "F.Cu")
		(net "M_A_CPU0_SA_CB<6>")
	)
	(gr_poly
		(pts
			(xy 326.667368 -274.407122) (xy 326.620886 -274.309586) (xy 326.585072 -274.273772) (xy 326.399144 -274.4597)
			(xy 326.435212 -274.495514) (xy 326.532494 -274.541742)
		)
		(stroke
			(width 0)
			(type solid)
		)
		(fill yes)
		(layer "F.Cu")
		(net "M_A_CPU0_SA_DQ<27>")
	)
	(gr_poly
		(pts
			(xy 326.667622 -267.313664) (xy 326.621394 -267.216128) (xy 326.585326 -267.180314) (xy 326.399652 -267.365988)
			(xy 326.435466 -267.402056) (xy 326.533002 -267.448284)
		)
		(stroke
			(width 0)
			(type solid)
		)
		(fill yes)
		(layer "F.Cu")
		(net "M_A_CPU0_SA_CB<3>")
	)
	(gr_poly
		(pts
			(xy 326.669654 -278.793194) (xy 326.61987 -278.783288) (xy 326.51319 -278.798782) (xy 326.475852 -278.985726)
			(xy 326.568562 -279.041098) (xy 326.618346 -279.051004)
		)
		(stroke
			(width 0)
			(type solid)
		)
		(fill yes)
		(layer "F.Cu")
		(net "M_A_CPU0_SA_DQ<22>")
	)
	(gr_poly
		(pts
			(xy 326.671432 -271.598644) (xy 326.635364 -271.56283) (xy 326.538082 -271.516602) (xy 326.403208 -271.651222)
			(xy 326.44969 -271.748758) (xy 326.485504 -271.784572)
		)
		(stroke
			(width 0)
			(type solid)
		)
		(fill yes)
		(layer "F.Cu")
		(net "M_A_CPU0_SA_DQ<30>")
	)
	(gr_poly
		(pts
			(xy 326.672956 -224.517204) (xy 326.719184 -224.419922) (xy 326.584564 -224.285048) (xy 326.487028 -224.331276)
			(xy 326.451214 -224.367344) (xy 326.637142 -224.553272)
		)
		(stroke
			(width 0)
			(type solid)
		)
		(fill yes)
		(layer "F.Cu")
		(net "M_A_CPU0_SB_DQ<19>")
	)
	(gr_poly
		(pts
			(xy 326.67702 -268.167104) (xy 326.630792 -268.069568) (xy 326.594724 -268.033754) (xy 326.408796 -268.219682)
			(xy 326.444864 -268.255496) (xy 326.542146 -268.301724)
		)
		(stroke
			(width 0)
			(type solid)
		)
		(fill yes)
		(layer "F.Cu")
		(net "M_A_CPU0_SA_CB<2>")
	)
	(gr_poly
		(pts
			(xy 326.678544 -276.829774) (xy 326.63384 -276.805644) (xy 326.52716 -276.789642) (xy 326.437244 -276.957536)
			(xy 326.509634 -277.037546) (xy 326.554592 -277.061422)
		)
		(stroke
			(width 0)
			(type solid)
		)
		(fill yes)
		(layer "F.Cu")
		(net "M_A_CPU0_SA_DQ<23>")
	)
	(gr_poly
		(pts
			(xy 326.68464 -233.698796) (xy 326.720454 -233.662728) (xy 326.53478 -233.477054) (xy 326.498712 -233.512868)
			(xy 326.452484 -233.610404) (xy 326.587104 -233.745024)
		)
		(stroke
			(width 0)
			(type solid)
		)
		(fill yes)
		(layer "F.Cu")
		(net "M_A_CPU0_SB_DQ<8>")
	)
	(gr_poly
		(pts
			(xy 326.693784 -232.845356) (xy 326.729852 -232.809542) (xy 326.543924 -232.623614) (xy 326.507856 -232.659428)
			(xy 326.461628 -232.756964) (xy 326.596502 -232.891584)
		)
		(stroke
			(width 0)
			(type solid)
		)
		(fill yes)
		(layer "F.Cu")
		(net "M_A_CPU0_SB_DQ<9>")
	)
	(gr_poly
		(pts
			(xy 326.701912 -275.84146) (xy 326.629268 -275.76145) (xy 326.584564 -275.737574) (xy 326.460612 -275.969476)
			(xy 326.505316 -275.993352) (xy 326.611996 -276.009354)
		)
		(stroke
			(width 0)
			(type solid)
		)
		(fill yes)
		(layer "F.Cu")
		(net "M_A_CPU0_SA_DQ<24>")
	)
	(gr_poly
		(pts
			(xy 326.71639 -279.338024) (xy 326.753728 -279.151334) (xy 326.661018 -279.095962) (xy 326.611234 -279.085802)
			(xy 326.559926 -279.343612) (xy 326.60971 -279.353518)
		)
		(stroke
			(width 0)
			(type solid)
		)
		(fill yes)
		(layer "F.Cu")
		(net "M_A_CPU0_SA_DQ<22>")
	)
	(gr_poly
		(pts
			(xy 326.73163 -230.29545) (xy 326.767698 -230.259636) (xy 326.58177 -230.073708) (xy 326.545702 -230.109522)
			(xy 326.499474 -230.207058) (xy 326.634094 -230.341678)
		)
		(stroke
			(width 0)
			(type solid)
		)
		(fill yes)
		(layer "F.Cu")
		(net "M_A_CPU0_SB_DQ<12>")
	)
	(gr_poly
		(pts
			(xy 326.734932 -280.02357) (xy 326.685148 -280.013664) (xy 326.578468 -280.029158) (xy 326.54113 -280.216102)
			(xy 326.633586 -280.271474) (xy 326.68337 -280.28138)
		)
		(stroke
			(width 0)
			(type solid)
		)
		(fill yes)
		(layer "F.Cu")
		(net "M_A_CPU0_SA_DQ<20>")
	)
	(gr_poly
		(pts
			(xy 326.734932 -227.249736) (xy 326.734932 -227.059236) (xy 326.633332 -227.022914) (xy 326.582532 -227.022914)
			(xy 326.582532 -227.286058) (xy 326.633332 -227.286058)
		)
		(stroke
			(width 0)
			(type solid)
		)
		(fill yes)
		(layer "F.Cu")
		(net "M_A_CPU0_SB_DQ<18>")
	)
	(gr_poly
		(pts
			(xy 326.734932 -226.652836) (xy 326.734932 -226.462336) (xy 326.633332 -226.426014) (xy 326.582532 -226.426014)
			(xy 326.582532 -226.689158) (xy 326.633332 -226.689158)
		)
		(stroke
			(width 0)
			(type solid)
		)
		(fill yes)
		(layer "F.Cu")
		(net "M_A_CPU0_SB_DQ<18>")
	)
	(gr_poly
		(pts
			(xy 326.734932 -226.055936) (xy 326.734932 -225.865436) (xy 326.633332 -225.829114) (xy 326.582532 -225.829114)
			(xy 326.582532 -226.092258) (xy 326.633332 -226.092258)
		)
		(stroke
			(width 0)
			(type solid)
		)
		(fill yes)
		(layer "F.Cu")
		(net "M_A_CPU0_SB_DQ<18>")
	)
	(gr_poly
		(pts
			(xy 326.741028 -229.44201) (xy 326.776842 -229.405942) (xy 326.590914 -229.220014) (xy 326.5551 -229.256082)
			(xy 326.508872 -229.353364) (xy 326.643492 -229.488238)
		)
		(stroke
			(width 0)
			(type solid)
		)
		(fill yes)
		(layer "F.Cu")
		(net "M_A_CPU0_SB_DQ<13>")
	)
	(gr_poly
		(pts
			(xy 326.748648 -271.30502) (xy 326.70242 -271.207484) (xy 326.666352 -271.17167) (xy 326.480424 -271.357598)
			(xy 326.516492 -271.393412) (xy 326.613774 -271.43964)
		)
		(stroke
			(width 0)
			(type solid)
		)
		(fill yes)
		(layer "F.Cu")
		(net "M_A_CPU0_SA_DQ<29>")
	)
	(gr_poly
		(pts
			(xy 326.750934 -228.172518) (xy 326.787002 -228.136704) (xy 326.601074 -227.950776) (xy 326.565006 -227.98659)
			(xy 326.518778 -228.084126) (xy 326.653652 -228.218746)
		)
		(stroke
			(width 0)
			(type solid)
		)
		(fill yes)
		(layer "F.Cu")
		(net "M_A_CPU0_SB_DQ<16>")
	)
	(gr_poly
		(pts
			(xy 326.758046 -272.158714) (xy 326.711818 -272.061178) (xy 326.676004 -272.025364) (xy 326.490076 -272.211292)
			(xy 326.526144 -272.247106) (xy 326.623426 -272.293334)
		)
		(stroke
			(width 0)
			(type solid)
		)
		(fill yes)
		(layer "F.Cu")
		(net "M_A_CPU0_SA_DQ<28>")
	)
	(gr_poly
		(pts
			(xy 326.761094 -233.200194) (xy 326.807322 -233.102912) (xy 326.672702 -232.968038) (xy 326.575166 -233.014266)
			(xy 326.539352 -233.050334) (xy 326.72528 -233.236262)
		)
		(stroke
			(width 0)
			(type solid)
		)
		(fill yes)
		(layer "F.Cu")
		(net "M_A_CPU0_SB_DQ<10>")
	)
	(gr_poly
		(pts
			(xy 326.770238 -232.347008) (xy 326.816466 -232.249472) (xy 326.681846 -232.114852) (xy 326.58431 -232.16108)
			(xy 326.548496 -232.196894) (xy 326.734424 -232.382822)
		)
		(stroke
			(width 0)
			(type solid)
		)
		(fill yes)
		(layer "F.Cu")
		(net "M_A_CPU0_SB_DQ<11>")
	)
	(gr_poly
		(pts
			(xy 326.781414 -280.5684) (xy 326.818752 -280.38171) (xy 326.726296 -280.326084) (xy 326.676512 -280.316178)
			(xy 326.62495 -280.573988) (xy 326.674734 -280.583894)
		)
		(stroke
			(width 0)
			(type solid)
		)
		(fill yes)
		(layer "F.Cu")
		(net "M_A_CPU0_SA_DQ<20>")
	)
	(gr_poly
		(pts
			(xy 326.781922 -263.53262) (xy 326.746108 -263.496806) (xy 326.648572 -263.450324) (xy 326.513952 -263.585198)
			(xy 326.56018 -263.68248) (xy 326.595994 -263.718548)
		)
		(stroke
			(width 0)
			(type solid)
		)
		(fill yes)
		(layer "F.Cu")
		(net "M_A_CPU0_SA_CB<7>")
	)
	(gr_poly
		(pts
			(xy 326.786748 -278.207978) (xy 326.736964 -278.197818) (xy 326.630284 -278.213566) (xy 326.592946 -278.400256)
			(xy 326.685402 -278.455628) (xy 326.735186 -278.465788)
		)
		(stroke
			(width 0)
			(type solid)
		)
		(fill yes)
		(layer "F.Cu")
		(net "M_A_CPU0_SA_DQ<22>")
	)
	(gr_poly
		(pts
			(xy 326.79132 -264.386314) (xy 326.755506 -264.350246) (xy 326.65797 -264.304018) (xy 326.52335 -264.438638)
			(xy 326.569578 -264.536174) (xy 326.605646 -264.571988)
		)
		(stroke
			(width 0)
			(type solid)
		)
		(fill yes)
		(layer "F.Cu")
		(net "M_A_CPU0_SA_CB<6>")
	)
	(gr_poly
		(pts
			(xy 326.796146 -274.062698) (xy 326.760332 -274.026884) (xy 326.662796 -273.980656) (xy 326.528176 -274.115276)
			(xy 326.574404 -274.212812) (xy 326.610218 -274.248626)
		)
		(stroke
			(width 0)
			(type solid)
		)
		(fill yes)
		(layer "F.Cu")
		(net "M_A_CPU0_SA_DQ<27>")
	)
	(gr_poly
		(pts
			(xy 326.7964 -266.96924) (xy 326.760586 -266.933172) (xy 326.66305 -266.886944) (xy 326.52843 -267.021818)
			(xy 326.574658 -267.1191) (xy 326.610472 -267.155168)
		)
		(stroke
			(width 0)
			(type solid)
		)
		(fill yes)
		(layer "F.Cu")
		(net "M_A_CPU0_SA_CB<3>")
	)
	(gr_poly
		(pts
			(xy 326.805798 -267.82268) (xy 326.769984 -267.786866) (xy 326.672448 -267.740384) (xy 326.537828 -267.875258)
			(xy 326.584056 -267.97254) (xy 326.61987 -268.008608)
		)
		(stroke
			(width 0)
			(type solid)
		)
		(fill yes)
		(layer "F.Cu")
		(net "M_A_CPU0_SA_CB<2>")
	)
	(gr_poly
		(pts
			(xy 326.808338 -229.796848) (xy 326.854566 -229.699312) (xy 326.719692 -229.564692) (xy 326.62241 -229.61092)
			(xy 326.586342 -229.646734) (xy 326.77227 -229.832662)
		)
		(stroke
			(width 0)
			(type solid)
		)
		(fill yes)
		(layer "F.Cu")
		(net "M_A_CPU0_SB_DQ<14>")
	)
	(gr_poly
		(pts
			(xy 326.812148 -224.80016) (xy 326.847962 -224.764092) (xy 326.662288 -224.578418) (xy 326.62622 -224.614232)
			(xy 326.579992 -224.711768) (xy 326.714612 -224.846388)
		)
		(stroke
			(width 0)
			(type solid)
		)
		(fill yes)
		(layer "F.Cu")
		(net "M_A_CPU0_SB_DQ<19>")
	)
	(gr_poly
		(pts
			(xy 326.817482 -228.943408) (xy 326.86371 -228.845872) (xy 326.72909 -228.711252) (xy 326.631554 -228.75748)
			(xy 326.59574 -228.793548) (xy 326.781414 -228.979222)
		)
		(stroke
			(width 0)
			(type solid)
		)
		(fill yes)
		(layer "F.Cu")
		(net "M_A_CPU0_SB_DQ<15>")
	)
	(gr_poly
		(pts
			(xy 326.83323 -278.752808) (xy 326.870568 -278.565864) (xy 326.778112 -278.510492) (xy 326.728328 -278.500586)
			(xy 326.676766 -278.758396) (xy 326.72655 -278.768302)
		)
		(stroke
			(width 0)
			(type solid)
		)
		(fill yes)
		(layer "F.Cu")
		(net "M_A_CPU0_SA_DQ<22>")
	)
	(gr_poly
		(pts
			(xy 326.851772 -279.438354) (xy 326.801988 -279.428194) (xy 326.695308 -279.443942) (xy 326.65797 -279.630632)
			(xy 326.750426 -279.686004) (xy 326.800464 -279.69591)
		)
		(stroke
			(width 0)
			(type solid)
		)
		(fill yes)
		(layer "F.Cu")
		(net "M_A_CPU0_SA_DQ<20>")
	)
	(gr_poly
		(pts
			(xy 326.86879 -264.09269) (xy 326.822562 -263.995408) (xy 326.786748 -263.95934) (xy 326.60082 -264.145268)
			(xy 326.636634 -264.181336) (xy 326.73417 -264.227564)
		)
		(stroke
			(width 0)
			(type solid)
		)
		(fill yes)
		(layer "F.Cu")
		(net "M_A_CPU0_SA_CB<5>")
	)
	(gr_poly
		(pts
			(xy 326.877426 -270.960596) (xy 326.841612 -270.924782) (xy 326.744076 -270.8783) (xy 326.609456 -271.013174)
			(xy 326.655684 -271.110456) (xy 326.691498 -271.146524)
		)
		(stroke
			(width 0)
			(type solid)
		)
		(fill yes)
		(layer "F.Cu")
		(net "M_A_CPU0_SA_DQ<29>")
	)
	(gr_poly
		(pts
			(xy 326.878442 -264.946384) (xy 326.83196 -264.848848) (xy 326.796146 -264.813034) (xy 326.610218 -264.998962)
			(xy 326.646286 -265.034776) (xy 326.743568 -265.081004)
		)
		(stroke
			(width 0)
			(type solid)
		)
		(fill yes)
		(layer "F.Cu")
		(net "M_A_CPU0_SA_CB<4>")
	)
	(gr_poly
		(pts
			(xy 326.883268 -274.623022) (xy 326.836786 -274.525486) (xy 326.800972 -274.489672) (xy 326.615044 -274.6756)
			(xy 326.651112 -274.711414) (xy 326.748394 -274.757642)
		)
		(stroke
			(width 0)
			(type solid)
		)
		(fill yes)
		(layer "F.Cu")
		(net "M_A_CPU0_SA_DQ<25>")
	)
	(gr_poly
		(pts
			(xy 326.883268 -267.52931) (xy 326.83704 -267.431774) (xy 326.800972 -267.39596) (xy 326.615298 -267.581634)
			(xy 326.651112 -267.617702) (xy 326.748648 -267.66393)
		)
		(stroke
			(width 0)
			(type solid)
		)
		(fill yes)
		(layer "F.Cu")
		(net "M_A_CPU0_SA_CB<1>")
	)
	(gr_poly
		(pts
			(xy 326.887078 -271.81429) (xy 326.85101 -271.778476) (xy 326.753728 -271.732248) (xy 326.618854 -271.866868)
			(xy 326.665336 -271.964404) (xy 326.70115 -272.000218)
		)
		(stroke
			(width 0)
			(type solid)
		)
		(fill yes)
		(layer "F.Cu")
		(net "M_A_CPU0_SA_DQ<28>")
	)
	(gr_poly
		(pts
			(xy 326.887332 -226.724718) (xy 326.836532 -226.724718) (xy 326.734932 -226.760786) (xy 326.734932 -226.951286)
			(xy 326.836532 -226.987354) (xy 326.887332 -226.987354)
		)
		(stroke
			(width 0)
			(type solid)
		)
		(fill yes)
		(layer "F.Cu")
		(net "M_A_CPU0_SB_DQ<17>")
	)
	(gr_poly
		(pts
			(xy 326.887332 -226.127818) (xy 326.836532 -226.127818) (xy 326.734932 -226.163886) (xy 326.734932 -226.354386)
			(xy 326.836532 -226.390454) (xy 326.887332 -226.390454)
		)
		(stroke
			(width 0)
			(type solid)
		)
		(fill yes)
		(layer "F.Cu")
		(net "M_A_CPU0_SB_DQ<17>")
	)
	(gr_poly
		(pts
			(xy 326.887332 -225.530918) (xy 326.836532 -225.530918) (xy 326.734932 -225.566986) (xy 326.734932 -225.757486)
			(xy 326.836532 -225.793554) (xy 326.887332 -225.793554)
		)
		(stroke
			(width 0)
			(type solid)
		)
		(fill yes)
		(layer "F.Cu")
		(net "M_A_CPU0_SB_DQ<17>")
	)
	(gr_poly
		(pts
			(xy 326.892666 -268.38275) (xy 326.846438 -268.285214) (xy 326.81037 -268.2494) (xy 326.624442 -268.435328)
			(xy 326.66051 -268.471142) (xy 326.757792 -268.51737)
		)
		(stroke
			(width 0)
			(type solid)
		)
		(fill yes)
		(layer "F.Cu")
		(net "M_A_CPU0_SA_CB<0>")
	)
	(gr_poly
		(pts
			(xy 326.898508 -279.983184) (xy 326.935846 -279.79624) (xy 326.843136 -279.740868) (xy 326.793352 -279.730962)
			(xy 326.74179 -279.988772) (xy 326.791828 -279.998678)
		)
		(stroke
			(width 0)
			(type solid)
		)
		(fill yes)
		(layer "F.Cu")
		(net "M_A_CPU0_SA_DQ<20>")
	)
	(gr_poly
		(pts
			(xy 326.898508 -249.270266) (xy 326.86244 -249.168666) (xy 326.67194 -249.168666) (xy 326.635618 -249.270266)
			(xy 326.635618 -249.321066) (xy 326.898508 -249.321066)
		)
		(stroke
			(width 0)
			(type solid)
		)
		(fill yes)
		(layer "F.Cu")
		(net "M_A_CPU0_SB_CA<0>")
	)
	(gr_poly
		(pts
			(xy 326.898508 -248.965212) (xy 326.86244 -248.863612) (xy 326.67194 -248.863612) (xy 326.635618 -248.965212)
			(xy 326.635618 -249.016012) (xy 326.898508 -249.016012)
		)
		(stroke
			(width 0)
			(type solid)
		)
		(fill yes)
		(layer "F.Cu")
		(net "M_A_CPU0_SB_CA<1>")
	)
	(gr_poly
		(pts
			(xy 326.898508 -248.660412) (xy 326.86244 -248.558812) (xy 326.67194 -248.558812) (xy 326.635618 -248.660412)
			(xy 326.635618 -248.711212) (xy 326.898508 -248.711212)
		)
		(stroke
			(width 0)
			(type solid)
		)
		(fill yes)
		(layer "F.Cu")
		(net "M_A_CPU0_SB_CA<2>")
	)
	(gr_poly
		(pts
			(xy 326.898508 -248.355612) (xy 326.86244 -248.254012) (xy 326.67194 -248.254012) (xy 326.635618 -248.355612)
			(xy 326.635618 -248.406412) (xy 326.898508 -248.406412)
		)
		(stroke
			(width 0)
			(type solid)
		)
		(fill yes)
		(layer "F.Cu")
		(net "M_A_CPU0_SB_CA<3>")
	)
	(gr_poly
		(pts
			(xy 326.898508 -248.050812) (xy 326.86244 -247.949212) (xy 326.67194 -247.949212) (xy 326.635618 -248.050812)
			(xy 326.635618 -248.101612) (xy 326.898508 -248.101612)
		)
		(stroke
			(width 0)
			(type solid)
		)
		(fill yes)
		(layer "F.Cu")
		(net "M_A_CPU0_SB_CA<4>")
	)
	(gr_poly
		(pts
			(xy 326.898508 -247.746012) (xy 326.86244 -247.644412) (xy 326.67194 -247.644412) (xy 326.635618 -247.746012)
			(xy 326.635618 -247.796812) (xy 326.898508 -247.796812)
		)
		(stroke
			(width 0)
			(type solid)
		)
		(fill yes)
		(layer "F.Cu")
		(net "M_A_CPU0_SB_CA<5>")
	)
	(gr_poly
		(pts
			(xy 326.898508 -247.441212) (xy 326.86244 -247.339612) (xy 326.67194 -247.339612) (xy 326.635618 -247.441212)
			(xy 326.635618 -247.492012) (xy 326.898508 -247.492012)
		)
		(stroke
			(width 0)
			(type solid)
		)
		(fill yes)
		(layer "F.Cu")
		(net "M_A_CPU0_SB_CA<6>")
	)
	(gr_poly
		(pts
			(xy 326.898508 -247.136412) (xy 326.86244 -247.034812) (xy 326.67194 -247.034812) (xy 326.635618 -247.136412)
			(xy 326.635618 -247.187212) (xy 326.898508 -247.187212)
		)
		(stroke
			(width 0)
			(type solid)
		)
		(fill yes)
		(layer "F.Cu")
		(net "M_A_CPU0_SB_PAR")
	)
	(gr_poly
		(pts
			(xy 326.898508 -246.831612) (xy 326.86244 -246.730012) (xy 326.67194 -246.730012) (xy 326.635618 -246.831612)
			(xy 326.635618 -246.882412) (xy 326.898508 -246.882412)
		)
		(stroke
			(width 0)
			(type solid)
		)
		(fill yes)
		(layer "F.Cu")
		(net "M_A_CPU0_SB_CS_N<2>")
	)
	(gr_poly
		(pts
			(xy 326.898508 -246.526812) (xy 326.86244 -246.425212) (xy 326.67194 -246.425212) (xy 326.635618 -246.526812)
			(xy 326.635618 -246.577612) (xy 326.898508 -246.577612)
		)
		(stroke
			(width 0)
			(type solid)
		)
		(fill yes)
		(layer "F.Cu")
		(net "M_A_CPU0_SB_CS_N<0>")
	)
	(gr_poly
		(pts
			(xy 326.898508 -246.222012) (xy 326.86244 -246.120412) (xy 326.67194 -246.120412) (xy 326.635618 -246.222012)
			(xy 326.635618 -246.272812) (xy 326.898508 -246.272812)
		)
		(stroke
			(width 0)
			(type solid)
		)
		(fill yes)
		(layer "F.Cu")
		(net "M_A_CPU0_SB_CS_N<3>")
	)
	(gr_poly
		(pts
			(xy 326.898508 -245.917212) (xy 326.86244 -245.815612) (xy 326.67194 -245.815612) (xy 326.635618 -245.917212)
			(xy 326.635618 -245.968012) (xy 326.898508 -245.968012)
		)
		(stroke
			(width 0)
			(type solid)
		)
		(fill yes)
		(layer "F.Cu")
		(net "M_A_CPU0_SB_CS_N<1>")
	)
	(gr_poly
		(pts
			(xy 326.900286 -233.48315) (xy 326.9361 -233.447082) (xy 326.750426 -233.261408) (xy 326.714358 -233.297222)
			(xy 326.66813 -233.394758) (xy 326.80275 -233.529378)
		)
		(stroke
			(width 0)
			(type solid)
		)
		(fill yes)
		(layer "F.Cu")
		(net "M_A_CPU0_SB_DQ<10>")
	)
	(gr_poly
		(pts
			(xy 326.90943 -232.62971) (xy 326.945498 -232.593896) (xy 326.75957 -232.407968) (xy 326.723502 -232.443782)
			(xy 326.677274 -232.541318) (xy 326.812148 -232.675938)
		)
		(stroke
			(width 0)
			(type solid)
		)
		(fill yes)
		(layer "F.Cu")
		(net "M_A_CPU0_SB_DQ<11>")
	)
	(gr_poly
		(pts
			(xy 326.923908 -277.340568) (xy 326.851518 -277.260812) (xy 326.806814 -277.236682) (xy 326.682608 -277.468584)
			(xy 326.727566 -277.49246) (xy 326.834246 -277.508462)
		)
		(stroke
			(width 0)
			(type solid)
		)
		(fill yes)
		(layer "F.Cu")
		(net "M_A_CPU0_SA_DQ<21>")
	)
	(gr_poly
		(pts
			(xy 326.931274 -257.586226) (xy 326.931274 -257.535426) (xy 326.668384 -257.535426) (xy 326.668384 -257.586226)
			(xy 326.704452 -257.687826) (xy 326.894952 -257.687826)
		)
		(stroke
			(width 0)
			(type solid)
		)
		(fill yes)
		(layer "F.Cu")
		(net "M_A_CPU0_SA_CA<3>")
	)
	(gr_poly
		(pts
			(xy 326.931274 -257.281426) (xy 326.931274 -257.230626) (xy 326.668384 -257.230626) (xy 326.668384 -257.281426)
			(xy 326.704452 -257.383026) (xy 326.894952 -257.383026)
		)
		(stroke
			(width 0)
			(type solid)
		)
		(fill yes)
		(layer "F.Cu")
		(net "M_A_CPU0_SA_CA<4>")
	)
	(gr_poly
		(pts
			(xy 326.931274 -256.976626) (xy 326.931274 -256.925826) (xy 326.668384 -256.925826) (xy 326.668384 -256.976626)
			(xy 326.704452 -257.078226) (xy 326.894952 -257.078226)
		)
		(stroke
			(width 0)
			(type solid)
		)
		(fill yes)
		(layer "F.Cu")
		(net "M_A_CPU0_SA_CA<5>")
	)
	(gr_poly
		(pts
			(xy 326.931274 -256.671826) (xy 326.931274 -256.621026) (xy 326.668384 -256.621026) (xy 326.668384 -256.671826)
			(xy 326.704452 -256.773426) (xy 326.894952 -256.773426)
		)
		(stroke
			(width 0)
			(type solid)
		)
		(fill yes)
		(layer "F.Cu")
		(net "M_A_CPU0_SA_CA<6>")
	)
	(gr_poly
		(pts
			(xy 326.931274 -256.367026) (xy 326.931274 -256.316226) (xy 326.668384 -256.316226) (xy 326.668384 -256.367026)
			(xy 326.704452 -256.468626) (xy 326.894952 -256.468626)
		)
		(stroke
			(width 0)
			(type solid)
		)
		(fill yes)
		(layer "F.Cu")
		(net "M_A_CPU0_SA_PAR")
	)
	(gr_poly
		(pts
			(xy 326.936608 -276.670516) (xy 326.864218 -276.590506) (xy 326.819514 -276.56663) (xy 326.695308 -276.798278)
			(xy 326.740266 -276.822408) (xy 326.846946 -276.83841)
		)
		(stroke
			(width 0)
			(type solid)
		)
		(fill yes)
		(layer "F.Cu")
		(net "M_A_CPU0_SA_DQ<23>")
	)
	(gr_poly
		(pts
			(xy 326.94753 -276.973538) (xy 326.902826 -276.949662) (xy 326.796146 -276.93366) (xy 326.70623 -277.101554)
			(xy 326.77862 -277.18131) (xy 326.823578 -277.20544)
		)
		(stroke
			(width 0)
			(type solid)
		)
		(fill yes)
		(layer "F.Cu")
		(net "M_A_CPU0_SA_DQ<21>")
	)
	(gr_poly
		(pts
			(xy 326.94753 -230.07955) (xy 326.983344 -230.043736) (xy 326.797416 -229.857808) (xy 326.761602 -229.893876)
			(xy 326.715374 -229.991158) (xy 326.849994 -230.126032)
		)
		(stroke
			(width 0)
			(type solid)
		)
		(fill yes)
		(layer "F.Cu")
		(net "M_A_CPU0_SB_DQ<14>")
	)
	(gr_poly
		(pts
			(xy 326.95007 -278.167338) (xy 326.987408 -277.980648) (xy 326.894698 -277.925276) (xy 326.844914 -277.915116)
			(xy 326.793352 -278.172926) (xy 326.843136 -278.183086)
		)
		(stroke
			(width 0)
			(type solid)
		)
		(fill yes)
		(layer "F.Cu")
		(net "M_A_CPU0_SA_DQ<22>")
	)
	(gr_poly
		(pts
			(xy 326.954896 -270.667226) (xy 326.908668 -270.56969) (xy 326.8726 -270.533876) (xy 326.686926 -270.71955)
			(xy 326.72274 -270.755618) (xy 326.820276 -270.801846)
		)
		(stroke
			(width 0)
			(type solid)
		)
		(fill yes)
		(layer "F.Cu")
		(net "M_A_CPU0_SA_DQ<31>")
	)
	(gr_poly
		(pts
			(xy 326.956674 -229.226364) (xy 326.992488 -229.190296) (xy 326.80656 -229.004368) (xy 326.770746 -229.040436)
			(xy 326.724518 -229.137718) (xy 326.859138 -229.272592)
		)
		(stroke
			(width 0)
			(type solid)
		)
		(fill yes)
		(layer "F.Cu")
		(net "M_A_CPU0_SB_DQ<15>")
	)
	(gr_poly
		(pts
			(xy 326.96023 -276.303486) (xy 326.915526 -276.279356) (xy 326.808846 -276.263354) (xy 326.71893 -276.431502)
			(xy 326.79132 -276.511258) (xy 326.836278 -276.535134)
		)
		(stroke
			(width 0)
			(type solid)
		)
		(fill yes)
		(layer "F.Cu")
		(net "M_A_CPU0_SA_DQ<23>")
	)
	(gr_poly
		(pts
			(xy 326.964548 -271.52092) (xy 326.91832 -271.423638) (xy 326.882506 -271.38757) (xy 326.696578 -271.573498)
			(xy 326.732392 -271.609566) (xy 326.829928 -271.655794)
		)
		(stroke
			(width 0)
			(type solid)
		)
		(fill yes)
		(layer "F.Cu")
		(net "M_A_CPU0_SA_DQ<30>")
	)
	(gr_poly
		(pts
			(xy 326.96658 -227.956872) (xy 327.002648 -227.921058) (xy 326.81672 -227.73513) (xy 326.780652 -227.770944)
			(xy 326.734424 -227.86848) (xy 326.869298 -228.0031)
		)
		(stroke
			(width 0)
			(type solid)
		)
		(fill yes)
		(layer "F.Cu")
		(net "M_A_CPU0_SB_DQ<18>")
	)
	(gr_poly
		(pts
			(xy 326.967596 -233.837988) (xy 327.013824 -233.740452) (xy 326.87895 -233.605832) (xy 326.781668 -233.65206)
			(xy 326.7456 -233.687874) (xy 326.931528 -233.873802)
		)
		(stroke
			(width 0)
			(type solid)
		)
		(fill yes)
		(layer "F.Cu")
		(net "M_A_CPU0_SB_DQ<8>")
	)
	(gr_poly
		(pts
			(xy 326.96912 -278.852884) (xy 326.919336 -278.842978) (xy 326.812402 -278.858472) (xy 326.775318 -279.045416)
			(xy 326.867774 -279.100788) (xy 326.917558 -279.110694)
		)
		(stroke
			(width 0)
			(type solid)
		)
		(fill yes)
		(layer "F.Cu")
		(net "M_A_CPU0_SA_DQ<20>")
	)
	(gr_poly
		(pts
			(xy 326.97674 -232.984548) (xy 327.022968 -232.887266) (xy 326.888348 -232.752392) (xy 326.790812 -232.79862)
			(xy 326.754998 -232.834688) (xy 326.940926 -233.020616)
		)
		(stroke
			(width 0)
			(type solid)
		)
		(fill yes)
		(layer "F.Cu")
		(net "M_A_CPU0_SB_DQ<9>")
	)
	(gr_poly
		(pts
			(xy 326.997822 -263.748266) (xy 326.961754 -263.712452) (xy 326.864472 -263.666224) (xy 326.729598 -263.800844)
			(xy 326.775826 -263.89838) (xy 326.811894 -263.934194)
		)
		(stroke
			(width 0)
			(type solid)
		)
		(fill yes)
		(layer "F.Cu")
		(net "M_A_CPU0_SA_CB<5>")
	)
	(gr_poly
		(pts
			(xy 327.00722 -264.60196) (xy 326.971152 -264.566146) (xy 326.87387 -264.519918) (xy 326.73925 -264.654538)
			(xy 326.785478 -264.752074) (xy 326.821292 -264.787888)
		)
		(stroke
			(width 0)
			(type solid)
		)
		(fill yes)
		(layer "F.Cu")
		(net "M_A_CPU0_SA_CB<4>")
	)
	(gr_poly
		(pts
			(xy 327.012046 -274.278598) (xy 326.976232 -274.242784) (xy 326.878696 -274.196556) (xy 326.744076 -274.331176)
			(xy 326.790304 -274.428712) (xy 326.826118 -274.464526)
		)
		(stroke
			(width 0)
			(type solid)
		)
		(fill yes)
		(layer "F.Cu")
		(net "M_A_CPU0_SA_DQ<25>")
	)
	(gr_poly
		(pts
			(xy 327.012046 -267.184886) (xy 326.976232 -267.148818) (xy 326.878696 -267.10259) (xy 326.744076 -267.237464)
			(xy 326.790304 -267.334746) (xy 326.826118 -267.370814)
		)
		(stroke
			(width 0)
			(type solid)
		)
		(fill yes)
		(layer "F.Cu")
		(net "M_A_CPU0_SA_CB<1>")
	)
	(gr_poly
		(pts
			(xy 327.014586 -230.434642) (xy 327.060814 -230.337106) (xy 326.926194 -230.202486) (xy 326.828658 -230.248714)
			(xy 326.792844 -230.284782) (xy 326.978518 -230.470456)
		)
		(stroke
			(width 0)
			(type solid)
		)
		(fill yes)
		(layer "F.Cu")
		(net "M_A_CPU0_SB_DQ<12>")
	)
	(gr_poly
		(pts
			(xy 327.015348 -279.397714) (xy 327.052686 -279.211024) (xy 326.96023 -279.155398) (xy 326.910446 -279.145492)
			(xy 326.858884 -279.403302) (xy 326.908668 -279.413208)
		)
		(stroke
			(width 0)
			(type solid)
		)
		(fill yes)
		(layer "F.Cu")
		(net "M_A_CPU0_SA_DQ<20>")
	)
	(gr_poly
		(pts
			(xy 327.021444 -268.038326) (xy 326.98563 -268.002512) (xy 326.888094 -267.95603) (xy 326.753474 -268.090904)
			(xy 326.799702 -268.188186) (xy 326.835516 -268.224254)
		)
		(stroke
			(width 0)
			(type solid)
		)
		(fill yes)
		(layer "F.Cu")
		(net "M_A_CPU0_SA_CB<0>")
	)
	(gr_poly
		(pts
			(xy 327.023984 -229.581202) (xy 327.070212 -229.483666) (xy 326.935338 -229.349046) (xy 326.838056 -229.395274)
			(xy 326.801988 -229.431088) (xy 326.987916 -229.617016)
		)
		(stroke
			(width 0)
			(type solid)
		)
		(fill yes)
		(layer "F.Cu")
		(net "M_A_CPU0_SB_DQ<13>")
	)
	(gr_poly
		(pts
			(xy 327.03389 -228.31171) (xy 327.080118 -228.214428) (xy 326.945498 -228.079554) (xy 326.847962 -228.125782)
			(xy 326.812148 -228.16185) (xy 326.998076 -228.347778)
		)
		(stroke
			(width 0)
			(type solid)
		)
		(fill yes)
		(layer "F.Cu")
		(net "M_A_CPU0_SB_DQ<16>")
	)
	(gr_poly
		(pts
			(xy 327.039732 -226.652836) (xy 327.039732 -226.462336) (xy 326.938132 -226.426014) (xy 326.887332 -226.426014)
			(xy 326.887332 -226.689158) (xy 326.938132 -226.689158)
		)
		(stroke
			(width 0)
			(type solid)
		)
		(fill yes)
		(layer "F.Cu")
		(net "M_A_CPU0_SB_DQ<17>")
	)
	(gr_poly
		(pts
			(xy 327.039732 -226.055936) (xy 327.039732 -225.865436) (xy 326.938132 -225.829114) (xy 326.887332 -225.829114)
			(xy 326.887332 -226.092258) (xy 326.938132 -226.092258)
		)
		(stroke
			(width 0)
			(type solid)
		)
		(fill yes)
		(layer "F.Cu")
		(net "M_A_CPU0_SB_DQ<17>")
	)
	(gr_poly
		(pts
			(xy 327.075038 -263.454896) (xy 327.02881 -263.35736) (xy 326.992996 -263.321546) (xy 326.807068 -263.507474)
			(xy 326.842882 -263.543288) (xy 326.940418 -263.589516)
		)
		(stroke
			(width 0)
			(type solid)
		)
		(fill yes)
		(layer "F.Cu")
		(net "M_A_CPU0_SA_CB<7>")
	)
	(gr_poly
		(pts
			(xy 327.083674 -270.322802) (xy 327.04786 -270.286734) (xy 326.950324 -270.240506) (xy 326.815704 -270.37538)
			(xy 326.861932 -270.472662) (xy 326.897746 -270.50873)
		)
		(stroke
			(width 0)
			(type solid)
		)
		(fill yes)
		(layer "F.Cu")
		(net "M_A_CPU0_SA_DQ<31>")
	)
	(gr_poly
		(pts
			(xy 327.08469 -264.30859) (xy 327.038462 -264.211054) (xy 327.002394 -264.17524) (xy 326.816466 -264.361168)
			(xy 326.852534 -264.396982) (xy 326.949816 -264.44321)
		)
		(stroke
			(width 0)
			(type solid)
		)
		(fill yes)
		(layer "F.Cu")
		(net "M_A_CPU0_SA_CB<6>")
	)
	(gr_poly
		(pts
			(xy 327.085706 -278.267668) (xy 327.035922 -278.257508) (xy 326.929242 -278.273256) (xy 326.891904 -278.459946)
			(xy 326.98436 -278.515318) (xy 327.034144 -278.525478)
		)
		(stroke
			(width 0)
			(type solid)
		)
		(fill yes)
		(layer "F.Cu")
		(net "M_A_CPU0_SA_DQ<20>")
	)
	(gr_poly
		(pts
			(xy 327.089262 -273.984974) (xy 327.043034 -273.887692) (xy 327.00722 -273.851624) (xy 326.821292 -274.037552)
			(xy 326.857106 -274.07362) (xy 326.954642 -274.119848)
		)
		(stroke
			(width 0)
			(type solid)
		)
		(fill yes)
		(layer "F.Cu")
		(net "M_A_CPU0_SA_DQ<27>")
	)
	(gr_poly
		(pts
			(xy 327.08977 -266.891516) (xy 327.043288 -266.79398) (xy 327.007474 -266.758166) (xy 326.821546 -266.944094)
			(xy 326.857614 -266.979908) (xy 326.954896 -267.026136)
		)
		(stroke
			(width 0)
			(type solid)
		)
		(fill yes)
		(layer "F.Cu")
		(net "M_A_CPU0_SA_CB<3>")
	)
	(gr_poly
		(pts
			(xy 327.09358 -271.176496) (xy 327.057512 -271.140682) (xy 326.959976 -271.094454) (xy 326.825356 -271.229074)
			(xy 326.871584 -271.32661) (xy 326.907652 -271.362424)
		)
		(stroke
			(width 0)
			(type solid)
		)
		(fill yes)
		(layer "F.Cu")
		(net "M_A_CPU0_SA_DQ<30>")
	)
	(gr_poly
		(pts
			(xy 327.095104 -224.939352) (xy 327.141332 -224.841816) (xy 327.006712 -224.707196) (xy 326.909176 -224.753424)
			(xy 326.873108 -224.789238) (xy 327.059036 -224.975166)
		)
		(stroke
			(width 0)
			(type solid)
		)
		(fill yes)
		(layer "F.Cu")
		(net "M_A_CPU0_SB_DQ<19>")
	)
	(gr_poly
		(pts
			(xy 327.098914 -274.838668) (xy 327.052432 -274.741132) (xy 327.016618 -274.705318) (xy 326.83069 -274.891246)
			(xy 326.866758 -274.92706) (xy 326.96404 -274.973288)
		)
		(stroke
			(width 0)
			(type solid)
		)
		(fill yes)
		(layer "F.Cu")
		(net "M_A_CPU0_SA_DQ<26>")
	)
	(gr_poly
		(pts
			(xy 327.098914 -267.744956) (xy 327.052686 -267.647674) (xy 327.016872 -267.611606) (xy 326.830944 -267.797534)
			(xy 326.866758 -267.833348) (xy 326.964294 -267.879576)
		)
		(stroke
			(width 0)
			(type solid)
		)
		(fill yes)
		(layer "F.Cu")
		(net "M_A_CPU0_SA_CB<2>")
	)
	(gr_poly
		(pts
			(xy 327.106788 -234.120944) (xy 327.142602 -234.084876) (xy 326.956674 -233.898948) (xy 326.92086 -233.935016)
			(xy 326.874632 -234.032298) (xy 327.009252 -234.167172)
		)
		(stroke
			(width 0)
			(type solid)
		)
		(fill yes)
		(layer "F.Cu")
		(net "M_A_CPU0_SB_DQ<8>")
	)
	(gr_poly
		(pts
			(xy 327.110852 -222.444818) (xy 327.060052 -222.444818) (xy 326.958452 -222.480886) (xy 326.958452 -222.671386)
			(xy 327.060052 -222.707454) (xy 327.110852 -222.707454)
		)
		(stroke
			(width 0)
			(type solid)
		)
		(fill yes)
		(layer "F.Cu")
		(net "M_A_CPU0_SB_DQ<20>")
	)
	(gr_poly
		(pts
			(xy 327.110852 -221.847918) (xy 327.060052 -221.847918) (xy 326.958452 -221.883986) (xy 326.958452 -222.074486)
			(xy 327.060052 -222.110554) (xy 327.110852 -222.110554)
		)
		(stroke
			(width 0)
			(type solid)
		)
		(fill yes)
		(layer "F.Cu")
		(net "M_A_CPU0_SB_DQ<20>")
	)
	(gr_poly
		(pts
			(xy 327.110852 -221.251018) (xy 327.060052 -221.251018) (xy 326.958452 -221.287086) (xy 326.958452 -221.477586)
			(xy 327.060052 -221.513654) (xy 327.110852 -221.513654)
		)
		(stroke
			(width 0)
			(type solid)
		)
		(fill yes)
		(layer "F.Cu")
		(net "M_A_CPU0_SB_DQ<20>")
	)
	(gr_poly
		(pts
			(xy 327.110852 -220.654118) (xy 327.060052 -220.654118) (xy 326.958452 -220.690186) (xy 326.958452 -220.880686)
			(xy 327.060052 -220.916754) (xy 327.110852 -220.916754)
		)
		(stroke
			(width 0)
			(type solid)
		)
		(fill yes)
		(layer "F.Cu")
		(net "M_A_CPU0_SB_DQ<20>")
	)
	(gr_poly
		(pts
			(xy 327.110852 -220.057218) (xy 327.060052 -220.057218) (xy 326.958452 -220.093286) (xy 326.958452 -220.283786)
			(xy 327.060052 -220.319854) (xy 327.110852 -220.319854)
		)
		(stroke
			(width 0)
			(type solid)
		)
		(fill yes)
		(layer "F.Cu")
		(net "M_A_CPU0_SB_DQ<20>")
	)
	(gr_poly
		(pts
			(xy 327.110852 -219.460318) (xy 327.060052 -219.460318) (xy 326.958452 -219.496386) (xy 326.958452 -219.686886)
			(xy 327.060052 -219.722954) (xy 327.110852 -219.722954)
		)
		(stroke
			(width 0)
			(type solid)
		)
		(fill yes)
		(layer "F.Cu")
		(net "M_A_CPU0_SB_DQ<20>")
	)
	(gr_poly
		(pts
			(xy 327.110852 -218.863418) (xy 327.060052 -218.863418) (xy 326.958452 -218.899486) (xy 326.958452 -219.089986)
			(xy 327.060052 -219.126054) (xy 327.110852 -219.126054)
		)
		(stroke
			(width 0)
			(type solid)
		)
		(fill yes)
		(layer "F.Cu")
		(net "M_A_CPU0_SB_DQ<20>")
	)
	(gr_poly
		(pts
			(xy 327.110852 -218.266518) (xy 327.060052 -218.266518) (xy 326.958452 -218.302586) (xy 326.958452 -218.493086)
			(xy 327.060052 -218.529154) (xy 327.110852 -218.529154)
		)
		(stroke
			(width 0)
			(type solid)
		)
		(fill yes)
		(layer "F.Cu")
		(net "M_A_CPU0_SB_DQ<20>")
	)
	(gr_poly
		(pts
			(xy 327.110852 -217.669618) (xy 327.060052 -217.669618) (xy 326.958452 -217.705686) (xy 326.958452 -217.896186)
			(xy 327.060052 -217.932254) (xy 327.110852 -217.932254)
		)
		(stroke
			(width 0)
			(type solid)
		)
		(fill yes)
		(layer "F.Cu")
		(net "M_A_CPU0_SB_DQ<20>")
	)
	(gr_poly
		(pts
			(xy 327.110852 -217.072718) (xy 327.060052 -217.072718) (xy 326.958452 -217.108786) (xy 326.958452 -217.299286)
			(xy 327.060052 -217.335354) (xy 327.110852 -217.335354)
		)
		(stroke
			(width 0)
			(type solid)
		)
		(fill yes)
		(layer "F.Cu")
		(net "M_A_CPU0_SB_DQ<20>")
	)
	(gr_poly
		(pts
			(xy 327.110852 -216.475818) (xy 327.060052 -216.475818) (xy 326.958452 -216.511886) (xy 326.958452 -216.702386)
			(xy 327.060052 -216.738454) (xy 327.110852 -216.738454)
		)
		(stroke
			(width 0)
			(type solid)
		)
		(fill yes)
		(layer "F.Cu")
		(net "M_A_CPU0_SB_DQ<20>")
	)
	(gr_poly
		(pts
			(xy 327.110852 -215.878918) (xy 327.060052 -215.878918) (xy 326.958452 -215.914986) (xy 326.958452 -216.105486)
			(xy 327.060052 -216.141554) (xy 327.110852 -216.141554)
		)
		(stroke
			(width 0)
			(type solid)
		)
		(fill yes)
		(layer "F.Cu")
		(net "M_A_CPU0_SB_DQ<20>")
	)
	(gr_poly
		(pts
			(xy 327.110852 -215.282018) (xy 327.060052 -215.282018) (xy 326.958452 -215.318086) (xy 326.958452 -215.508586)
			(xy 327.060052 -215.544654) (xy 327.110852 -215.544654)
		)
		(stroke
			(width 0)
			(type solid)
		)
		(fill yes)
		(layer "F.Cu")
		(net "M_A_CPU0_SB_DQ<20>")
	)
	(gr_poly
		(pts
			(xy 327.115932 -233.267504) (xy 327.151746 -233.231436) (xy 326.966072 -233.045762) (xy 326.930004 -233.081576)
			(xy 326.883776 -233.179112) (xy 327.018396 -233.313732)
		)
		(stroke
			(width 0)
			(type solid)
		)
		(fill yes)
		(layer "F.Cu")
		(net "M_A_CPU0_SB_DQ<9>")
	)
	(gr_poly
		(pts
			(xy 327.132188 -278.812498) (xy 327.169526 -278.625554) (xy 327.07707 -278.570182) (xy 327.027286 -278.560276)
			(xy 326.975724 -278.818086) (xy 327.025508 -278.827992)
		)
		(stroke
			(width 0)
			(type solid)
		)
		(fill yes)
		(layer "F.Cu")
		(net "M_A_CPU0_SA_DQ<20>")
	)
	(gr_poly
		(pts
			(xy 327.153778 -230.717598) (xy 327.189592 -230.68153) (xy 327.003664 -230.495602) (xy 326.96785 -230.53167)
			(xy 326.921622 -230.628952) (xy 327.056242 -230.763826)
		)
		(stroke
			(width 0)
			(type solid)
		)
		(fill yes)
		(layer "F.Cu")
		(net "M_A_CPU0_SB_DQ<12>")
	)
	(gr_poly
		(pts
			(xy 327.163176 -229.863904) (xy 327.19899 -229.82809) (xy 327.013062 -229.642162) (xy 326.977248 -229.67823)
			(xy 326.93102 -229.775512) (xy 327.06564 -229.910386)
		)
		(stroke
			(width 0)
			(type solid)
		)
		(fill yes)
		(layer "F.Cu")
		(net "M_A_CPU0_SB_DQ<13>")
	)
	(gr_poly
		(pts
			(xy 327.170542 -270.882872) (xy 327.124314 -270.78559) (xy 327.0885 -270.749522) (xy 326.902572 -270.93545)
			(xy 326.938386 -270.971264) (xy 327.035922 -271.017492)
		)
		(stroke
			(width 0)
			(type solid)
		)
		(fill yes)
		(layer "F.Cu")
		(net "M_A_CPU0_SA_DQ<29>")
	)
	(gr_poly
		(pts
			(xy 327.173082 -228.594666) (xy 327.208896 -228.558598) (xy 327.023222 -228.372924) (xy 326.987154 -228.408738)
			(xy 326.940926 -228.506274) (xy 327.075546 -228.640894)
		)
		(stroke
			(width 0)
			(type solid)
		)
		(fill yes)
		(layer "F.Cu")
		(net "M_A_CPU0_SB_DQ<16>")
	)
	(gr_poly
		(pts
			(xy 327.180194 -271.736566) (xy 327.133966 -271.639284) (xy 327.098152 -271.603216) (xy 326.912224 -271.789144)
			(xy 326.948038 -271.825212) (xy 327.045574 -271.87144)
		)
		(stroke
			(width 0)
			(type solid)
		)
		(fill yes)
		(layer "F.Cu")
		(net "M_A_CPU0_SA_DQ<28>")
	)
	(gr_poly
		(pts
			(xy 327.182226 -227.741226) (xy 327.218294 -227.705412) (xy 327.032366 -227.519484) (xy 326.996298 -227.555298)
			(xy 326.95007 -227.652834) (xy 327.084944 -227.787454)
		)
		(stroke
			(width 0)
			(type solid)
		)
		(fill yes)
		(layer "F.Cu")
		(net "M_A_CPU0_SB_DQ<17>")
	)
	(gr_poly
		(pts
			(xy 327.183242 -233.622342) (xy 327.22947 -233.524806) (xy 327.094596 -233.390186) (xy 326.997314 -233.436414)
			(xy 326.961246 -233.472228) (xy 327.147174 -233.658156)
		)
		(stroke
			(width 0)
			(type solid)
		)
		(fill yes)
		(layer "F.Cu")
		(net "M_A_CPU0_SB_DQ<10>")
	)
	(gr_poly
		(pts
			(xy 327.192132 -226.724718) (xy 327.141332 -226.724718) (xy 327.039732 -226.760786) (xy 327.039732 -226.951286)
			(xy 327.141332 -226.987354) (xy 327.192132 -226.987354)
		)
		(stroke
			(width 0)
			(type solid)
		)
		(fill yes)
		(layer "F.Cu")
		(net "M_A_CPU0_SB_DQ<19>")
	)
	(gr_poly
		(pts
			(xy 327.192132 -226.127818) (xy 327.141332 -226.127818) (xy 327.039732 -226.163886) (xy 327.039732 -226.354386)
			(xy 327.141332 -226.390454) (xy 327.192132 -226.390454)
		)
		(stroke
			(width 0)
			(type solid)
		)
		(fill yes)
		(layer "F.Cu")
		(net "M_A_CPU0_SB_DQ<19>")
	)
	(gr_poly
		(pts
			(xy 327.192132 -225.530918) (xy 327.141332 -225.530918) (xy 327.039732 -225.566986) (xy 327.039732 -225.757486)
			(xy 327.141332 -225.793554) (xy 327.192132 -225.793554)
		)
		(stroke
			(width 0)
			(type solid)
		)
		(fill yes)
		(layer "F.Cu")
		(net "M_A_CPU0_SB_DQ<19>")
	)
	(gr_poly
		(pts
			(xy 327.192386 -232.768902) (xy 327.238614 -232.67162) (xy 327.103994 -232.536746) (xy 327.006458 -232.582974)
			(xy 326.970644 -232.619042) (xy 327.156572 -232.80497)
		)
		(stroke
			(width 0)
			(type solid)
		)
		(fill yes)
		(layer "F.Cu")
		(net "M_A_CPU0_SB_DQ<11>")
	)
	(gr_poly
		(pts
			(xy 327.193148 -277.484586) (xy 327.120504 -277.404576) (xy 327.0758 -277.3807) (xy 326.951848 -277.612602)
			(xy 326.996552 -277.636478) (xy 327.103232 -277.65248)
		)
		(stroke
			(width 0)
			(type solid)
		)
		(fill yes)
		(layer "F.Cu")
		(net "M_A_CPU0_SA_DQ<22>")
	)
	(gr_poly
		(pts
			(xy 327.196958 -249.371866) (xy 327.196958 -249.321066) (xy 326.934068 -249.321066) (xy 326.934068 -249.371866)
			(xy 326.970136 -249.473466) (xy 327.160636 -249.473466)
		)
		(stroke
			(width 0)
			(type solid)
		)
		(fill yes)
		(layer "F.Cu")
		(net "M_A_CPU0_SB_CA<0>")
	)
	(gr_poly
		(pts
			(xy 327.196958 -249.066812) (xy 327.196958 -249.016012) (xy 326.934068 -249.016012) (xy 326.934068 -249.066812)
			(xy 326.970136 -249.168412) (xy 327.160636 -249.168412)
		)
		(stroke
			(width 0)
			(type solid)
		)
		(fill yes)
		(layer "F.Cu")
		(net "M_A_CPU0_SB_CA<1>")
	)
	(gr_poly
		(pts
			(xy 327.196958 -248.762012) (xy 327.196958 -248.711212) (xy 326.934068 -248.711212) (xy 326.934068 -248.762012)
			(xy 326.970136 -248.863612) (xy 327.160636 -248.863612)
		)
		(stroke
			(width 0)
			(type solid)
		)
		(fill yes)
		(layer "F.Cu")
		(net "M_A_CPU0_SB_CA<2>")
	)
	(gr_poly
		(pts
			(xy 327.196958 -248.457212) (xy 327.196958 -248.406412) (xy 326.934068 -248.406412) (xy 326.934068 -248.457212)
			(xy 326.970136 -248.558812) (xy 327.160636 -248.558812)
		)
		(stroke
			(width 0)
			(type solid)
		)
		(fill yes)
		(layer "F.Cu")
		(net "M_A_CPU0_SB_CA<3>")
	)
	(gr_poly
		(pts
			(xy 327.196958 -248.152412) (xy 327.196958 -248.101612) (xy 326.934068 -248.101612) (xy 326.934068 -248.152412)
			(xy 326.970136 -248.254012) (xy 327.160636 -248.254012)
		)
		(stroke
			(width 0)
			(type solid)
		)
		(fill yes)
		(layer "F.Cu")
		(net "M_A_CPU0_SB_CA<4>")
	)
	(gr_poly
		(pts
			(xy 327.196958 -247.847612) (xy 327.196958 -247.796812) (xy 326.934068 -247.796812) (xy 326.934068 -247.847612)
			(xy 326.970136 -247.949212) (xy 327.160636 -247.949212)
		)
		(stroke
			(width 0)
			(type solid)
		)
		(fill yes)
		(layer "F.Cu")
		(net "M_A_CPU0_SB_CA<5>")
	)
	(gr_poly
		(pts
			(xy 327.196958 -247.542812) (xy 327.196958 -247.492012) (xy 326.934068 -247.492012) (xy 326.934068 -247.542812)
			(xy 326.970136 -247.644412) (xy 327.160636 -247.644412)
		)
		(stroke
			(width 0)
			(type solid)
		)
		(fill yes)
		(layer "F.Cu")
		(net "M_A_CPU0_SB_CA<6>")
	)
	(gr_poly
		(pts
			(xy 327.196958 -247.238012) (xy 327.196958 -247.187212) (xy 326.934068 -247.187212) (xy 326.934068 -247.238012)
			(xy 326.970136 -247.339612) (xy 327.160636 -247.339612)
		)
		(stroke
			(width 0)
			(type solid)
		)
		(fill yes)
		(layer "F.Cu")
		(net "M_A_CPU0_SB_PAR")
	)
	(gr_poly
		(pts
			(xy 327.196958 -246.933212) (xy 327.196958 -246.882412) (xy 326.934068 -246.882412) (xy 326.934068 -246.933212)
			(xy 326.970136 -247.034812) (xy 327.160636 -247.034812)
		)
		(stroke
			(width 0)
			(type solid)
		)
		(fill yes)
		(layer "F.Cu")
		(net "M_A_CPU0_SB_CS_N<2>")
	)
	(gr_poly
		(pts
			(xy 327.196958 -246.628412) (xy 327.196958 -246.577612) (xy 326.934068 -246.577612) (xy 326.934068 -246.628412)
			(xy 326.970136 -246.730012) (xy 327.160636 -246.730012)
		)
		(stroke
			(width 0)
			(type solid)
		)
		(fill yes)
		(layer "F.Cu")
		(net "M_A_CPU0_SB_CS_N<0>")
	)
	(gr_poly
		(pts
			(xy 327.196958 -246.323612) (xy 327.196958 -246.272812) (xy 326.934068 -246.272812) (xy 326.934068 -246.323612)
			(xy 326.970136 -246.425212) (xy 327.160636 -246.425212)
		)
		(stroke
			(width 0)
			(type solid)
		)
		(fill yes)
		(layer "F.Cu")
		(net "M_A_CPU0_SB_CS_N<3>")
	)
	(gr_poly
		(pts
			(xy 327.196958 -246.018812) (xy 327.196958 -245.968012) (xy 326.934068 -245.968012) (xy 326.934068 -246.018812)
			(xy 326.970136 -246.120412) (xy 327.160636 -246.120412)
		)
		(stroke
			(width 0)
			(type solid)
		)
		(fill yes)
		(layer "F.Cu")
		(net "M_A_CPU0_SB_CS_N<1>")
	)
	(gr_poly
		(pts
			(xy 327.20407 -263.110472) (xy 327.168002 -263.074658) (xy 327.07072 -263.02843) (xy 326.935846 -263.16305)
			(xy 326.982328 -263.260586) (xy 327.018142 -263.2964)
		)
		(stroke
			(width 0)
			(type solid)
		)
		(fill yes)
		(layer "F.Cu")
		(net "M_A_CPU0_SA_CB<7>")
	)
	(gr_poly
		(pts
			(xy 327.205594 -276.81428) (xy 327.133204 -276.734524) (xy 327.088246 -276.710394) (xy 326.964294 -276.942296)
			(xy 327.008998 -276.966172) (xy 327.115678 -276.982174)
		)
		(stroke
			(width 0)
			(type solid)
		)
		(fill yes)
		(layer "F.Cu")
		(net "M_A_CPU0_SA_DQ<21>")
	)
	(gr_poly
		(pts
			(xy 327.213468 -263.964166) (xy 327.177654 -263.928352) (xy 327.080118 -263.88187) (xy 326.945498 -264.016744)
			(xy 326.991726 -264.114026) (xy 327.02754 -264.150094)
		)
		(stroke
			(width 0)
			(type solid)
		)
		(fill yes)
		(layer "F.Cu")
		(net "M_A_CPU0_SA_CB<6>")
	)
	(gr_poly
		(pts
			(xy 327.216516 -277.117556) (xy 327.171812 -277.09368) (xy 327.065132 -277.077424) (xy 326.975216 -277.245572)
			(xy 327.047606 -277.325328) (xy 327.092564 -277.349204)
		)
		(stroke
			(width 0)
			(type solid)
		)
		(fill yes)
		(layer "F.Cu")
		(net "M_A_CPU0_SA_DQ<22>")
	)
	(gr_poly
		(pts
			(xy 327.218294 -276.144228) (xy 327.145904 -276.064218) (xy 327.1012 -276.040342) (xy 326.976994 -276.27199)
			(xy 327.021952 -276.29612) (xy 327.128632 -276.312122)
		)
		(stroke
			(width 0)
			(type solid)
		)
		(fill yes)
		(layer "F.Cu")
		(net "M_A_CPU0_SA_DQ<23>")
	)
	(gr_poly
		(pts
			(xy 327.218294 -273.64055) (xy 327.182226 -273.604736) (xy 327.084944 -273.558508) (xy 326.95007 -273.693128)
			(xy 326.996298 -273.790664) (xy 327.032366 -273.826478)
		)
		(stroke
			(width 0)
			(type solid)
		)
		(fill yes)
		(layer "F.Cu")
		(net "M_A_CPU0_SA_DQ<27>")
	)
	(gr_poly
		(pts
			(xy 327.218548 -266.547092) (xy 327.182734 -266.511278) (xy 327.085198 -266.46505) (xy 326.950578 -266.59967)
			(xy 326.996806 -266.697206) (xy 327.03262 -266.73302)
		)
		(stroke
			(width 0)
			(type solid)
		)
		(fill yes)
		(layer "F.Cu")
		(net "M_A_CPU0_SA_CB<3>")
	)
	(gr_poly
		(pts
			(xy 327.227692 -274.494244) (xy 327.191878 -274.45843) (xy 327.094342 -274.412202) (xy 326.959722 -274.546822)
			(xy 327.00595 -274.644358) (xy 327.041764 -274.680172)
		)
		(stroke
			(width 0)
			(type solid)
		)
		(fill yes)
		(layer "F.Cu")
		(net "M_A_CPU0_SA_DQ<26>")
	)
	(gr_poly
		(pts
			(xy 327.227946 -267.400532) (xy 327.191878 -267.364718) (xy 327.094596 -267.31849) (xy 326.959722 -267.45311)
			(xy 327.00595 -267.550646) (xy 327.042018 -267.58646)
		)
		(stroke
			(width 0)
			(type solid)
		)
		(fill yes)
		(layer "F.Cu")
		(net "M_A_CPU0_SA_CB<2>")
	)
	(gr_poly
		(pts
			(xy 327.229216 -276.44725) (xy 327.184512 -276.423374) (xy 327.077832 -276.407372) (xy 326.987916 -276.575266)
			(xy 327.060306 -276.655022) (xy 327.10501 -276.679152)
		)
		(stroke
			(width 0)
			(type solid)
		)
		(fill yes)
		(layer "F.Cu")
		(net "M_A_CPU0_SA_DQ<21>")
	)
	(gr_poly
		(pts
			(xy 327.229724 -258.094226) (xy 327.193656 -257.992626) (xy 327.003156 -257.992626) (xy 326.966834 -258.094226)
			(xy 326.966834 -258.145026) (xy 327.229724 -258.145026)
		)
		(stroke
			(width 0)
			(type solid)
		)
		(fill yes)
		(layer "F.Cu")
		(net "M_A_CPU0_SA_CA<1>")
	)
	(gr_poly
		(pts
			(xy 327.229724 -257.789426) (xy 327.193656 -257.687826) (xy 327.003156 -257.687826) (xy 326.966834 -257.789426)
			(xy 326.966834 -257.840226) (xy 327.229724 -257.840226)
		)
		(stroke
			(width 0)
			(type solid)
		)
		(fill yes)
		(layer "F.Cu")
		(net "M_A_CPU0_SA_CA<2>")
	)
	(gr_poly
		(pts
			(xy 327.229724 -257.484626) (xy 327.193656 -257.383026) (xy 327.003156 -257.383026) (xy 326.966834 -257.484626)
			(xy 326.966834 -257.535426) (xy 327.229724 -257.535426)
		)
		(stroke
			(width 0)
			(type solid)
		)
		(fill yes)
		(layer "F.Cu")
		(net "M_A_CPU0_SA_CA<3>")
	)
	(gr_poly
		(pts
			(xy 327.229724 -257.179826) (xy 327.193656 -257.078226) (xy 327.003156 -257.078226) (xy 326.966834 -257.179826)
			(xy 326.966834 -257.230626) (xy 327.229724 -257.230626)
		)
		(stroke
			(width 0)
			(type solid)
		)
		(fill yes)
		(layer "F.Cu")
		(net "M_A_CPU0_SA_CA<4>")
	)
	(gr_poly
		(pts
			(xy 327.229724 -256.875026) (xy 327.193656 -256.773426) (xy 327.003156 -256.773426) (xy 326.966834 -256.875026)
			(xy 326.966834 -256.925826) (xy 327.229724 -256.925826)
		)
		(stroke
			(width 0)
			(type solid)
		)
		(fill yes)
		(layer "F.Cu")
		(net "M_A_CPU0_SA_CA<5>")
	)
	(gr_poly
		(pts
			(xy 327.229724 -256.570226) (xy 327.193656 -256.468626) (xy 327.003156 -256.468626) (xy 326.966834 -256.570226)
			(xy 326.966834 -256.621026) (xy 327.229724 -256.621026)
		)
		(stroke
			(width 0)
			(type solid)
		)
		(fill yes)
		(layer "F.Cu")
		(net "M_A_CPU0_SA_CA<6>")
	)
	(gr_poly
		(pts
			(xy 327.229724 -256.265426) (xy 327.193656 -256.163826) (xy 327.003156 -256.163826) (xy 326.966834 -256.265426)
			(xy 326.966834 -256.316226) (xy 327.229724 -256.316226)
		)
		(stroke
			(width 0)
			(type solid)
		)
		(fill yes)
		(layer "F.Cu")
		(net "M_A_CPU0_SA_PAR")
	)
	(gr_poly
		(pts
			(xy 327.230232 -230.218742) (xy 327.27646 -230.12146) (xy 327.14184 -229.98684) (xy 327.044304 -230.033068)
			(xy 327.00849 -230.068882) (xy 327.194418 -230.25481)
		)
		(stroke
			(width 0)
			(type solid)
		)
		(fill yes)
		(layer "F.Cu")
		(net "M_A_CPU0_SB_DQ<14>")
	)
	(gr_poly
		(pts
			(xy 327.23963 -229.365556) (xy 327.285858 -229.26802) (xy 327.150984 -229.1334) (xy 327.053702 -229.179628)
			(xy 327.017634 -229.215442) (xy 327.203562 -229.40137)
		)
		(stroke
			(width 0)
			(type solid)
		)
		(fill yes)
		(layer "F.Cu")
		(net "M_A_CPU0_SB_DQ<15>")
	)
	(gr_poly
		(pts
			(xy 327.249536 -228.096064) (xy 327.295764 -227.998782) (xy 327.161144 -227.863908) (xy 327.063608 -227.910136)
			(xy 327.027794 -227.946204) (xy 327.213722 -228.132132)
		)
		(stroke
			(width 0)
			(type solid)
		)
		(fill yes)
		(layer "F.Cu")
		(net "M_A_CPU0_SB_DQ<18>")
	)
	(gr_poly
		(pts
			(xy 327.263252 -222.372936) (xy 327.263252 -222.182436) (xy 327.161652 -222.146114) (xy 327.110852 -222.146114)
			(xy 327.110852 -222.409258) (xy 327.161652 -222.409258)
		)
		(stroke
			(width 0)
			(type solid)
		)
		(fill yes)
		(layer "F.Cu")
		(net "M_A_CPU0_SB_DQ<20>")
	)
	(gr_poly
		(pts
			(xy 327.263252 -221.776036) (xy 327.263252 -221.585536) (xy 327.161652 -221.549214) (xy 327.110852 -221.549214)
			(xy 327.110852 -221.812358) (xy 327.161652 -221.812358)
		)
		(stroke
			(width 0)
			(type solid)
		)
		(fill yes)
		(layer "F.Cu")
		(net "M_A_CPU0_SB_DQ<20>")
	)
	(gr_poly
		(pts
			(xy 327.263252 -221.179136) (xy 327.263252 -220.988636) (xy 327.161652 -220.952314) (xy 327.110852 -220.952314)
			(xy 327.110852 -221.215458) (xy 327.161652 -221.215458)
		)
		(stroke
			(width 0)
			(type solid)
		)
		(fill yes)
		(layer "F.Cu")
		(net "M_A_CPU0_SB_DQ<20>")
	)
	(gr_poly
		(pts
			(xy 327.263252 -220.582236) (xy 327.263252 -220.391736) (xy 327.161652 -220.355414) (xy 327.110852 -220.355414)
			(xy 327.110852 -220.618558) (xy 327.161652 -220.618558)
		)
		(stroke
			(width 0)
			(type solid)
		)
		(fill yes)
		(layer "F.Cu")
		(net "M_A_CPU0_SB_DQ<20>")
	)
	(gr_poly
		(pts
			(xy 327.263252 -219.985336) (xy 327.263252 -219.794836) (xy 327.161652 -219.758514) (xy 327.110852 -219.758514)
			(xy 327.110852 -220.021658) (xy 327.161652 -220.021658)
		)
		(stroke
			(width 0)
			(type solid)
		)
		(fill yes)
		(layer "F.Cu")
		(net "M_A_CPU0_SB_DQ<20>")
	)
	(gr_poly
		(pts
			(xy 327.263252 -219.388436) (xy 327.263252 -219.197936) (xy 327.161652 -219.161614) (xy 327.110852 -219.161614)
			(xy 327.110852 -219.424758) (xy 327.161652 -219.424758)
		)
		(stroke
			(width 0)
			(type solid)
		)
		(fill yes)
		(layer "F.Cu")
		(net "M_A_CPU0_SB_DQ<20>")
	)
	(gr_poly
		(pts
			(xy 327.263252 -218.791536) (xy 327.263252 -218.601036) (xy 327.161652 -218.564714) (xy 327.110852 -218.564714)
			(xy 327.110852 -218.827858) (xy 327.161652 -218.827858)
		)
		(stroke
			(width 0)
			(type solid)
		)
		(fill yes)
		(layer "F.Cu")
		(net "M_A_CPU0_SB_DQ<20>")
	)
	(gr_poly
		(pts
			(xy 327.263252 -218.194636) (xy 327.263252 -218.004136) (xy 327.161652 -217.967814) (xy 327.110852 -217.967814)
			(xy 327.110852 -218.230958) (xy 327.161652 -218.230958)
		)
		(stroke
			(width 0)
			(type solid)
		)
		(fill yes)
		(layer "F.Cu")
		(net "M_A_CPU0_SB_DQ<20>")
	)
	(gr_poly
		(pts
			(xy 327.263252 -217.597736) (xy 327.263252 -217.407236) (xy 327.161652 -217.370914) (xy 327.110852 -217.370914)
			(xy 327.110852 -217.634058) (xy 327.161652 -217.634058)
		)
		(stroke
			(width 0)
			(type solid)
		)
		(fill yes)
		(layer "F.Cu")
		(net "M_A_CPU0_SB_DQ<20>")
	)
	(gr_poly
		(pts
			(xy 327.263252 -217.000836) (xy 327.263252 -216.810336) (xy 327.161652 -216.774014) (xy 327.110852 -216.774014)
			(xy 327.110852 -217.037158) (xy 327.161652 -217.037158)
		)
		(stroke
			(width 0)
			(type solid)
		)
		(fill yes)
		(layer "F.Cu")
		(net "M_A_CPU0_SB_DQ<20>")
	)
	(gr_poly
		(pts
			(xy 327.263252 -216.403936) (xy 327.263252 -216.213436) (xy 327.161652 -216.177114) (xy 327.110852 -216.177114)
			(xy 327.110852 -216.440258) (xy 327.161652 -216.440258)
		)
		(stroke
			(width 0)
			(type solid)
		)
		(fill yes)
		(layer "F.Cu")
		(net "M_A_CPU0_SB_DQ<20>")
	)
	(gr_poly
		(pts
			(xy 327.263252 -215.807036) (xy 327.263252 -215.616536) (xy 327.161652 -215.580214) (xy 327.110852 -215.580214)
			(xy 327.110852 -215.843358) (xy 327.161652 -215.843358)
		)
		(stroke
			(width 0)
			(type solid)
		)
		(fill yes)
		(layer "F.Cu")
		(net "M_A_CPU0_SB_DQ<20>")
	)
	(gr_poly
		(pts
			(xy 327.290938 -263.670796) (xy 327.24471 -263.57326) (xy 327.208642 -263.537446) (xy 327.022968 -263.72312)
			(xy 327.058782 -263.759188) (xy 327.156318 -263.805416)
		)
		(stroke
			(width 0)
			(type solid)
		)
		(fill yes)
		(layer "F.Cu")
		(net "M_A_CPU0_SA_CB<5>")
	)
	(gr_poly
		(pts
			(xy 327.299574 -270.538448) (xy 327.263506 -270.502634) (xy 327.166224 -270.456406) (xy 327.03135 -270.591026)
			(xy 327.077578 -270.688562) (xy 327.113646 -270.724376)
		)
		(stroke
			(width 0)
			(type solid)
		)
		(fill yes)
		(layer "F.Cu")
		(net "M_A_CPU0_SA_DQ<29>")
	)
	(gr_poly
		(pts
			(xy 327.300336 -264.524236) (xy 327.254108 -264.426954) (xy 327.218294 -264.390886) (xy 327.032366 -264.576814)
			(xy 327.06818 -264.612882) (xy 327.165716 -264.65911)
		)
		(stroke
			(width 0)
			(type solid)
		)
		(fill yes)
		(layer "F.Cu")
		(net "M_A_CPU0_SA_CB<4>")
	)
	(gr_poly
		(pts
			(xy 327.305162 -274.200874) (xy 327.258934 -274.103592) (xy 327.22312 -274.067524) (xy 327.037192 -274.253452)
			(xy 327.073006 -274.28952) (xy 327.170542 -274.335748)
		)
		(stroke
			(width 0)
			(type solid)
		)
		(fill yes)
		(layer "F.Cu")
		(net "M_A_CPU0_SA_DQ<25>")
	)
	(gr_poly
		(pts
			(xy 327.305416 -267.107162) (xy 327.258934 -267.009626) (xy 327.22312 -266.973812) (xy 327.037192 -267.15974)
			(xy 327.07326 -267.195554) (xy 327.170542 -267.241782)
		)
		(stroke
			(width 0)
			(type solid)
		)
		(fill yes)
		(layer "F.Cu")
		(net "M_A_CPU0_SA_CB<1>")
	)
	(gr_poly
		(pts
			(xy 327.309226 -271.392142) (xy 327.273158 -271.356328) (xy 327.175622 -271.3101) (xy 327.041002 -271.44472)
			(xy 327.08723 -271.542256) (xy 327.123298 -271.57807)
		)
		(stroke
			(width 0)
			(type solid)
		)
		(fill yes)
		(layer "F.Cu")
		(net "M_A_CPU0_SA_DQ<28>")
	)
	(gr_poly
		(pts
			(xy 327.31456 -275.054314) (xy 327.268078 -274.956778) (xy 327.232264 -274.920964) (xy 327.046336 -275.106892)
			(xy 327.082404 -275.142706) (xy 327.179686 -275.188934)
		)
		(stroke
			(width 0)
			(type solid)
		)
		(fill yes)
		(layer "F.Cu")
		(net "M_A_CPU0_SA_DQ<24>")
	)
	(gr_poly
		(pts
			(xy 327.31456 -267.960602) (xy 327.268332 -267.86332) (xy 327.232518 -267.827252) (xy 327.04659 -268.01318)
			(xy 327.082404 -268.048994) (xy 327.17994 -268.095222)
		)
		(stroke
			(width 0)
			(type solid)
		)
		(fill yes)
		(layer "F.Cu")
		(net "M_A_CPU0_SA_CB<0>")
	)
	(gr_poly
		(pts
			(xy 327.322434 -233.905298) (xy 327.358248 -233.86923) (xy 327.17232 -233.683302) (xy 327.136506 -233.71937)
			(xy 327.090278 -233.816652) (xy 327.224898 -233.951526)
		)
		(stroke
			(width 0)
			(type solid)
		)
		(fill yes)
		(layer "F.Cu")
		(net "M_A_CPU0_SB_DQ<10>")
	)
	(gr_poly
		(pts
			(xy 327.331578 -233.051858) (xy 327.367392 -233.01579) (xy 327.181718 -232.830116) (xy 327.14565 -232.86593)
			(xy 327.099422 -232.963466) (xy 327.234042 -233.098086)
		)
		(stroke
			(width 0)
			(type solid)
		)
		(fill yes)
		(layer "F.Cu")
		(net "M_A_CPU0_SB_DQ<11>")
	)
	(gr_poly
		(pts
			(xy 327.344532 -226.652836) (xy 327.344532 -226.462336) (xy 327.242932 -226.426014) (xy 327.192132 -226.426014)
			(xy 327.192132 -226.689158) (xy 327.242932 -226.689158)
		)
		(stroke
			(width 0)
			(type solid)
		)
		(fill yes)
		(layer "F.Cu")
		(net "M_A_CPU0_SB_DQ<19>")
	)
	(gr_poly
		(pts
			(xy 327.344532 -226.055936) (xy 327.344532 -225.865436) (xy 327.242932 -225.829114) (xy 327.192132 -225.829114)
			(xy 327.192132 -226.092258) (xy 327.242932 -226.092258)
		)
		(stroke
			(width 0)
			(type solid)
		)
		(fill yes)
		(layer "F.Cu")
		(net "M_A_CPU0_SB_DQ<19>")
	)
	(gr_poly
		(pts
			(xy 327.369424 -230.501698) (xy 327.405492 -230.465884) (xy 327.219564 -230.279956) (xy 327.183496 -230.31577)
			(xy 327.137268 -230.413306) (xy 327.272142 -230.547926)
		)
		(stroke
			(width 0)
			(type solid)
		)
		(fill yes)
		(layer "F.Cu")
		(net "M_A_CPU0_SB_DQ<14>")
	)
	(gr_poly
		(pts
			(xy 327.377044 -270.245078) (xy 327.330562 -270.147542) (xy 327.294748 -270.111728) (xy 327.10882 -270.297656)
			(xy 327.144888 -270.33347) (xy 327.24217 -270.379698)
		)
		(stroke
			(width 0)
			(type solid)
		)
		(fill yes)
		(layer "F.Cu")
		(net "M_A_CPU0_SA_DQ<31>")
	)
	(gr_poly
		(pts
			(xy 327.378822 -229.648258) (xy 327.414636 -229.612444) (xy 327.228708 -229.426516) (xy 327.192894 -229.462584)
			(xy 327.146666 -229.559866) (xy 327.281286 -229.69474)
		)
		(stroke
			(width 0)
			(type solid)
		)
		(fill yes)
		(layer "F.Cu")
		(net "M_A_CPU0_SB_DQ<15>")
	)
	(gr_poly
		(pts
			(xy 327.386696 -271.099026) (xy 327.340468 -271.00149) (xy 327.3044 -270.965676) (xy 327.118726 -271.15135)
			(xy 327.15454 -271.187418) (xy 327.252076 -271.233646)
		)
		(stroke
			(width 0)
			(type solid)
		)
		(fill yes)
		(layer "F.Cu")
		(net "M_A_CPU0_SA_DQ<30>")
	)
	(gr_poly
		(pts
			(xy 327.388728 -228.37902) (xy 327.424542 -228.342952) (xy 327.238868 -228.157278) (xy 327.2028 -228.193092)
			(xy 327.156572 -228.290628) (xy 327.291192 -228.425248)
		)
		(stroke
			(width 0)
			(type solid)
		)
		(fill yes)
		(layer "F.Cu")
		(net "M_A_CPU0_SB_DQ<18>")
	)
	(gr_poly
		(pts
			(xy 327.38949 -234.260136) (xy 327.435972 -234.1626) (xy 327.301098 -234.02798) (xy 327.203816 -234.074208)
			(xy 327.167748 -234.110022) (xy 327.353676 -234.29595)
		)
		(stroke
			(width 0)
			(type solid)
		)
		(fill yes)
		(layer "F.Cu")
		(net "M_A_CPU0_SB_DQ<8>")
	)
	(gr_poly
		(pts
			(xy 327.398888 -233.406696) (xy 327.445116 -233.30916) (xy 327.310242 -233.17454) (xy 327.21296 -233.220768)
			(xy 327.176892 -233.256582) (xy 327.36282 -233.44251)
		)
		(stroke
			(width 0)
			(type solid)
		)
		(fill yes)
		(layer "F.Cu")
		(net "M_A_CPU0_SB_DQ<9>")
	)
	(gr_poly
		(pts
			(xy 327.415652 -221.847918) (xy 327.364852 -221.847918) (xy 327.263252 -221.883986) (xy 327.263252 -222.074486)
			(xy 327.364852 -222.110554) (xy 327.415652 -222.110554)
		)
		(stroke
			(width 0)
			(type solid)
		)
		(fill yes)
		(layer "F.Cu")
		(net "M_A_CPU0_SB_DQ<22>")
	)
	(gr_poly
		(pts
			(xy 327.415652 -221.251018) (xy 327.364852 -221.251018) (xy 327.263252 -221.287086) (xy 327.263252 -221.477586)
			(xy 327.364852 -221.513654) (xy 327.415652 -221.513654)
		)
		(stroke
			(width 0)
			(type solid)
		)
		(fill yes)
		(layer "F.Cu")
		(net "M_A_CPU0_SB_DQ<22>")
	)
	(gr_poly
		(pts
			(xy 327.415652 -220.654118) (xy 327.364852 -220.654118) (xy 327.263252 -220.690186) (xy 327.263252 -220.880686)
			(xy 327.364852 -220.916754) (xy 327.415652 -220.916754)
		)
		(stroke
			(width 0)
			(type solid)
		)
		(fill yes)
		(layer "F.Cu")
		(net "M_A_CPU0_SB_DQ<22>")
	)
	(gr_poly
		(pts
			(xy 327.415652 -220.057218) (xy 327.364852 -220.057218) (xy 327.263252 -220.093286) (xy 327.263252 -220.283786)
			(xy 327.364852 -220.319854) (xy 327.415652 -220.319854)
		)
		(stroke
			(width 0)
			(type solid)
		)
		(fill yes)
		(layer "F.Cu")
		(net "M_A_CPU0_SB_DQ<22>")
	)
	(gr_poly
		(pts
			(xy 327.415652 -219.460318) (xy 327.364852 -219.460318) (xy 327.263252 -219.496386) (xy 327.263252 -219.686886)
			(xy 327.364852 -219.722954) (xy 327.415652 -219.722954)
		)
		(stroke
			(width 0)
			(type solid)
		)
		(fill yes)
		(layer "F.Cu")
		(net "M_A_CPU0_SB_DQ<22>")
	)
	(gr_poly
		(pts
			(xy 327.415652 -218.863418) (xy 327.364852 -218.863418) (xy 327.263252 -218.899486) (xy 327.263252 -219.089986)
			(xy 327.364852 -219.126054) (xy 327.415652 -219.126054)
		)
		(stroke
			(width 0)
			(type solid)
		)
		(fill yes)
		(layer "F.Cu")
		(net "M_A_CPU0_SB_DQ<22>")
	)
	(gr_poly
		(pts
			(xy 327.415652 -218.266518) (xy 327.364852 -218.266518) (xy 327.263252 -218.302586) (xy 327.263252 -218.493086)
			(xy 327.364852 -218.529154) (xy 327.415652 -218.529154)
		)
		(stroke
			(width 0)
			(type solid)
		)
		(fill yes)
		(layer "F.Cu")
		(net "M_A_CPU0_SB_DQ<22>")
	)
	(gr_poly
		(pts
			(xy 327.415652 -217.669618) (xy 327.364852 -217.669618) (xy 327.263252 -217.705686) (xy 327.263252 -217.896186)
			(xy 327.364852 -217.932254) (xy 327.415652 -217.932254)
		)
		(stroke
			(width 0)
			(type solid)
		)
		(fill yes)
		(layer "F.Cu")
		(net "M_A_CPU0_SB_DQ<22>")
	)
	(gr_poly
		(pts
			(xy 327.415652 -217.072718) (xy 327.364852 -217.072718) (xy 327.263252 -217.108786) (xy 327.263252 -217.299286)
			(xy 327.364852 -217.335354) (xy 327.415652 -217.335354)
		)
		(stroke
			(width 0)
			(type solid)
		)
		(fill yes)
		(layer "F.Cu")
		(net "M_A_CPU0_SB_DQ<22>")
	)
	(gr_poly
		(pts
			(xy 327.415652 -216.475818) (xy 327.364852 -216.475818) (xy 327.263252 -216.511886) (xy 327.263252 -216.702386)
			(xy 327.364852 -216.738454) (xy 327.415652 -216.738454)
		)
		(stroke
			(width 0)
			(type solid)
		)
		(fill yes)
		(layer "F.Cu")
		(net "M_A_CPU0_SB_DQ<22>")
	)
	(gr_poly
		(pts
			(xy 327.415652 -215.878918) (xy 327.364852 -215.878918) (xy 327.263252 -215.914986) (xy 327.263252 -216.105486)
			(xy 327.364852 -216.141554) (xy 327.415652 -216.141554)
		)
		(stroke
			(width 0)
			(type solid)
		)
		(fill yes)
		(layer "F.Cu")
		(net "M_A_CPU0_SB_DQ<22>")
	)
	(gr_poly
		(pts
			(xy 327.415652 -215.282018) (xy 327.364852 -215.282018) (xy 327.263252 -215.318086) (xy 327.263252 -215.508586)
			(xy 327.364852 -215.544654) (xy 327.415652 -215.544654)
		)
		(stroke
			(width 0)
			(type solid)
		)
		(fill yes)
		(layer "F.Cu")
		(net "M_A_CPU0_SB_DQ<22>")
	)
	(gr_poly
		(pts
			(xy 327.419716 -263.326372) (xy 327.383902 -263.290304) (xy 327.286366 -263.244076) (xy 327.151746 -263.37895)
			(xy 327.197974 -263.476232) (xy 327.233788 -263.5123)
		)
		(stroke
			(width 0)
			(type solid)
		)
		(fill yes)
		(layer "F.Cu")
		(net "M_A_CPU0_SA_CB<5>")
	)
	(gr_poly
		(pts
			(xy 327.429368 -264.179812) (xy 327.3933 -264.143998) (xy 327.296018 -264.09777) (xy 327.161144 -264.23239)
			(xy 327.207372 -264.329926) (xy 327.24344 -264.36574)
		)
		(stroke
			(width 0)
			(type solid)
		)
		(fill yes)
		(layer "F.Cu")
		(net "M_A_CPU0_SA_CB<4>")
	)
	(gr_poly
		(pts
			(xy 327.434194 -273.85645) (xy 327.398126 -273.820636) (xy 327.300844 -273.774408) (xy 327.16597 -273.909028)
			(xy 327.212198 -274.006564) (xy 327.248266 -274.042378)
		)
		(stroke
			(width 0)
			(type solid)
		)
		(fill yes)
		(layer "F.Cu")
		(net "M_A_CPU0_SA_DQ<25>")
	)
	(gr_poly
		(pts
			(xy 327.434194 -266.762738) (xy 327.39838 -266.726924) (xy 327.300844 -266.680696) (xy 327.166224 -266.815316)
			(xy 327.212452 -266.912852) (xy 327.248266 -266.948666)
		)
		(stroke
			(width 0)
			(type solid)
		)
		(fill yes)
		(layer "F.Cu")
		(net "M_A_CPU0_SA_CB<1>")
	)
	(gr_poly
		(pts
			(xy 327.43648 -230.85679) (xy 327.482962 -230.759254) (xy 327.348088 -230.624634) (xy 327.250806 -230.670862)
			(xy 327.214738 -230.706676) (xy 327.400666 -230.892604)
		)
		(stroke
			(width 0)
			(type solid)
		)
		(fill yes)
		(layer "F.Cu")
		(net "M_A_CPU0_SB_DQ<12>")
	)
	(gr_poly
		(pts
			(xy 327.443338 -274.70989) (xy 327.407524 -274.674076) (xy 327.309988 -274.627848) (xy 327.175368 -274.762468)
			(xy 327.221596 -274.860004) (xy 327.25741 -274.895818)
		)
		(stroke
			(width 0)
			(type solid)
		)
		(fill yes)
		(layer "F.Cu")
		(net "M_A_CPU0_SA_DQ<24>")
	)
	(gr_poly
		(pts
			(xy 327.443592 -267.616178) (xy 327.407524 -267.580364) (xy 327.310242 -267.534136) (xy 327.175368 -267.668756)
			(xy 327.221596 -267.766292) (xy 327.257664 -267.802106)
		)
		(stroke
			(width 0)
			(type solid)
		)
		(fill yes)
		(layer "F.Cu")
		(net "M_A_CPU0_SA_CB<0>")
	)
	(gr_poly
		(pts
			(xy 327.445878 -230.003096) (xy 327.492106 -229.905814) (xy 327.357486 -229.771194) (xy 327.25995 -229.817422)
			(xy 327.224136 -229.853236) (xy 327.410064 -230.039164)
		)
		(stroke
			(width 0)
			(type solid)
		)
		(fill yes)
		(layer "F.Cu")
		(net "M_A_CPU0_SB_DQ<13>")
	)
	(gr_poly
		(pts
			(xy 327.456038 -228.733858) (xy 327.502266 -228.636322) (xy 327.367392 -228.501702) (xy 327.27011 -228.54793)
			(xy 327.234042 -228.583744) (xy 327.41997 -228.769672)
		)
		(stroke
			(width 0)
			(type solid)
		)
		(fill yes)
		(layer "F.Cu")
		(net "M_A_CPU0_SB_DQ<16>")
	)
	(gr_poly
		(pts
			(xy 327.465182 -227.880418) (xy 327.51141 -227.783136) (xy 327.37679 -227.648262) (xy 327.279254 -227.69449)
			(xy 327.24344 -227.730558) (xy 327.429368 -227.916486)
		)
		(stroke
			(width 0)
			(type solid)
		)
		(fill yes)
		(layer "F.Cu")
		(net "M_A_CPU0_SB_DQ<17>")
	)
	(gr_poly
		(pts
			(xy 327.47458 -276.958044) (xy 327.40219 -276.878288) (xy 327.357232 -276.854412) (xy 327.23328 -277.08606)
			(xy 327.277984 -277.11019) (xy 327.384664 -277.126192)
		)
		(stroke
			(width 0)
			(type solid)
		)
		(fill yes)
		(layer "F.Cu")
		(net "M_A_CPU0_SA_DQ<22>")
	)
	(gr_poly
		(pts
			(xy 327.485502 -277.261574) (xy 327.440798 -277.237444) (xy 327.334118 -277.221442) (xy 327.244202 -277.389336)
			(xy 327.316846 -277.469346) (xy 327.36155 -277.493222)
		)
		(stroke
			(width 0)
			(type solid)
		)
		(fill yes)
		(layer "F.Cu")
		(net "M_A_CPU0_SA_DQ<20>")
	)
	(gr_poly
		(pts
			(xy 327.48728 -276.287992) (xy 327.41489 -276.208236) (xy 327.369932 -276.184106) (xy 327.24598 -276.416008)
			(xy 327.290684 -276.439884) (xy 327.397364 -276.455886)
		)
		(stroke
			(width 0)
			(type solid)
		)
		(fill yes)
		(layer "F.Cu")
		(net "M_A_CPU0_SA_DQ<21>")
	)
	(gr_poly
		(pts
			(xy 327.495408 -249.270266) (xy 327.45934 -249.168666) (xy 327.26884 -249.168666) (xy 327.232518 -249.270266)
			(xy 327.232518 -249.321066) (xy 327.495408 -249.321066)
		)
		(stroke
			(width 0)
			(type solid)
		)
		(fill yes)
		(layer "F.Cu")
		(net "M_A_CPU0_SB_CA<0>")
	)
	(gr_poly
		(pts
			(xy 327.495408 -248.965212) (xy 327.45934 -248.863612) (xy 327.26884 -248.863612) (xy 327.232518 -248.965212)
			(xy 327.232518 -249.016012) (xy 327.495408 -249.016012)
		)
		(stroke
			(width 0)
			(type solid)
		)
		(fill yes)
		(layer "F.Cu")
		(net "M_A_CPU0_SB_CA<1>")
	)
	(gr_poly
		(pts
			(xy 327.495408 -248.660412) (xy 327.45934 -248.558812) (xy 327.26884 -248.558812) (xy 327.232518 -248.660412)
			(xy 327.232518 -248.711212) (xy 327.495408 -248.711212)
		)
		(stroke
			(width 0)
			(type solid)
		)
		(fill yes)
		(layer "F.Cu")
		(net "M_A_CPU0_SB_CA<2>")
	)
	(gr_poly
		(pts
			(xy 327.495408 -248.355612) (xy 327.45934 -248.254012) (xy 327.26884 -248.254012) (xy 327.232518 -248.355612)
			(xy 327.232518 -248.406412) (xy 327.495408 -248.406412)
		)
		(stroke
			(width 0)
			(type solid)
		)
		(fill yes)
		(layer "F.Cu")
		(net "M_A_CPU0_SB_CA<3>")
	)
	(gr_poly
		(pts
			(xy 327.495408 -248.050812) (xy 327.45934 -247.949212) (xy 327.26884 -247.949212) (xy 327.232518 -248.050812)
			(xy 327.232518 -248.101612) (xy 327.495408 -248.101612)
		)
		(stroke
			(width 0)
			(type solid)
		)
		(fill yes)
		(layer "F.Cu")
		(net "M_A_CPU0_SB_CA<4>")
	)
	(gr_poly
		(pts
			(xy 327.495408 -247.746012) (xy 327.45934 -247.644412) (xy 327.26884 -247.644412) (xy 327.232518 -247.746012)
			(xy 327.232518 -247.796812) (xy 327.495408 -247.796812)
		)
		(stroke
			(width 0)
			(type solid)
		)
		(fill yes)
		(layer "F.Cu")
		(net "M_A_CPU0_SB_CA<5>")
	)
	(gr_poly
		(pts
			(xy 327.495408 -247.441212) (xy 327.45934 -247.339612) (xy 327.26884 -247.339612) (xy 327.232518 -247.441212)
			(xy 327.232518 -247.492012) (xy 327.495408 -247.492012)
		)
		(stroke
			(width 0)
			(type solid)
		)
		(fill yes)
		(layer "F.Cu")
		(net "M_A_CPU0_SB_CA<6>")
	)
	(gr_poly
		(pts
			(xy 327.495408 -247.136412) (xy 327.45934 -247.034812) (xy 327.26884 -247.034812) (xy 327.232518 -247.136412)
			(xy 327.232518 -247.187212) (xy 327.495408 -247.187212)
		)
		(stroke
			(width 0)
			(type solid)
		)
		(fill yes)
		(layer "F.Cu")
		(net "M_A_CPU0_SB_PAR")
	)
	(gr_poly
		(pts
			(xy 327.495408 -246.831612) (xy 327.45934 -246.730012) (xy 327.26884 -246.730012) (xy 327.232518 -246.831612)
			(xy 327.232518 -246.882412) (xy 327.495408 -246.882412)
		)
		(stroke
			(width 0)
			(type solid)
		)
		(fill yes)
		(layer "F.Cu")
		(net "M_A_CPU0_SB_CS_N<2>")
	)
	(gr_poly
		(pts
			(xy 327.495408 -246.526812) (xy 327.45934 -246.425212) (xy 327.26884 -246.425212) (xy 327.232518 -246.526812)
			(xy 327.232518 -246.577612) (xy 327.495408 -246.577612)
		)
		(stroke
			(width 0)
			(type solid)
		)
		(fill yes)
		(layer "F.Cu")
		(net "M_A_CPU0_SB_CS_N<0>")
	)
	(gr_poly
		(pts
			(xy 327.495408 -246.222012) (xy 327.45934 -246.120412) (xy 327.26884 -246.120412) (xy 327.232518 -246.222012)
			(xy 327.232518 -246.272812) (xy 327.495408 -246.272812)
		)
		(stroke
			(width 0)
			(type solid)
		)
		(fill yes)
		(layer "F.Cu")
		(net "M_A_CPU0_SB_CS_N<3>")
	)
	(gr_poly
		(pts
			(xy 327.495408 -245.917212) (xy 327.45934 -245.815612) (xy 327.26884 -245.815612) (xy 327.232518 -245.917212)
			(xy 327.232518 -245.968012) (xy 327.495408 -245.968012)
		)
		(stroke
			(width 0)
			(type solid)
		)
		(fill yes)
		(layer "F.Cu")
		(net "M_A_CPU0_SB_CS_N<1>")
	)
	(gr_poly
		(pts
			(xy 327.497186 -263.032748) (xy 327.450958 -262.935466) (xy 327.415144 -262.899398) (xy 327.229216 -263.085326)
			(xy 327.26503 -263.121394) (xy 327.362566 -263.167622)
		)
		(stroke
			(width 0)
			(type solid)
		)
		(fill yes)
		(layer "F.Cu")
		(net "M_A_CPU0_SA_CB<7>")
	)
	(gr_poly
		(pts
			(xy 327.498202 -276.591268) (xy 327.453244 -276.567138) (xy 327.346564 -276.551136) (xy 327.256648 -276.719284)
			(xy 327.329292 -276.79904) (xy 327.373996 -276.822916)
		)
		(stroke
			(width 0)
			(type solid)
		)
		(fill yes)
		(layer "F.Cu")
		(net "M_A_CPU0_SA_DQ<22>")
	)
	(gr_poly
		(pts
			(xy 327.505822 -269.900654) (xy 327.470008 -269.86484) (xy 327.372472 -269.818612) (xy 327.237852 -269.953232)
			(xy 327.28408 -270.050768) (xy 327.319894 -270.086582)
		)
		(stroke
			(width 0)
			(type solid)
		)
		(fill yes)
		(layer "F.Cu")
		(net "M_A_CPU0_SA_DQ<31>")
	)
	(gr_poly
		(pts
			(xy 327.506584 -263.886442) (xy 327.460356 -263.788906) (xy 327.424542 -263.753092) (xy 327.238614 -263.93902)
			(xy 327.274428 -263.974834) (xy 327.371964 -264.021062)
		)
		(stroke
			(width 0)
			(type solid)
		)
		(fill yes)
		(layer "F.Cu")
		(net "M_A_CPU0_SA_CB<6>")
	)
	(gr_poly
		(pts
			(xy 327.51141 -273.56308) (xy 327.465182 -273.465544) (xy 327.429114 -273.42973) (xy 327.24344 -273.615404)
			(xy 327.279254 -273.651472) (xy 327.37679 -273.6977)
		)
		(stroke
			(width 0)
			(type solid)
		)
		(fill yes)
		(layer "F.Cu")
		(net "M_A_CPU0_SA_DQ<27>")
	)
	(gr_poly
		(pts
			(xy 327.511664 -266.469368) (xy 327.465436 -266.372086) (xy 327.429622 -266.336018) (xy 327.243694 -266.521946)
			(xy 327.279508 -266.55776) (xy 327.377044 -266.604242)
		)
		(stroke
			(width 0)
			(type solid)
		)
		(fill yes)
		(layer "F.Cu")
		(net "M_A_CPU0_SA_CB<3>")
	)
	(gr_poly
		(pts
			(xy 327.515474 -270.754602) (xy 327.47966 -270.718534) (xy 327.382124 -270.672306) (xy 327.247504 -270.80718)
			(xy 327.293732 -270.904462) (xy 327.329546 -270.94053)
		)
		(stroke
			(width 0)
			(type solid)
		)
		(fill yes)
		(layer "F.Cu")
		(net "M_A_CPU0_SA_DQ<30>")
	)
	(gr_poly
		(pts
			(xy 327.520808 -274.41652) (xy 327.47458 -274.319238) (xy 327.438766 -274.28317) (xy 327.252838 -274.469098)
			(xy 327.288652 -274.505166) (xy 327.386188 -274.551394)
		)
		(stroke
			(width 0)
			(type solid)
		)
		(fill yes)
		(layer "F.Cu")
		(net "M_A_CPU0_SA_DQ<26>")
	)
	(gr_poly
		(pts
			(xy 327.521062 -267.322808) (xy 327.474834 -267.225526) (xy 327.43902 -267.189458) (xy 327.253092 -267.375386)
			(xy 327.288906 -267.411454) (xy 327.386442 -267.457682)
		)
		(stroke
			(width 0)
			(type solid)
		)
		(fill yes)
		(layer "F.Cu")
		(net "M_A_CPU0_SA_CB<2>")
	)
	(gr_poly
		(pts
			(xy 327.528174 -258.805426) (xy 327.528174 -258.754626) (xy 327.265284 -258.754626) (xy 327.265284 -258.805426)
			(xy 327.301352 -258.907026) (xy 327.491852 -258.907026)
		)
		(stroke
			(width 0)
			(type solid)
		)
		(fill yes)
		(layer "F.Cu")
		(net "M_A_CPU0_SA_CS_N<1>")
	)
	(gr_poly
		(pts
			(xy 327.528174 -258.500626) (xy 327.528174 -258.449826) (xy 327.265284 -258.449826) (xy 327.265284 -258.500626)
			(xy 327.301352 -258.602226) (xy 327.491852 -258.602226)
		)
		(stroke
			(width 0)
			(type solid)
		)
		(fill yes)
		(layer "F.Cu")
		(net "M_A_CPU0_SA_CA<0>")
	)
	(gr_poly
		(pts
			(xy 327.528174 -258.195826) (xy 327.528174 -258.145026) (xy 327.265284 -258.145026) (xy 327.265284 -258.195826)
			(xy 327.301352 -258.297426) (xy 327.491852 -258.297426)
		)
		(stroke
			(width 0)
			(type solid)
		)
		(fill yes)
		(layer "F.Cu")
		(net "M_A_CPU0_SA_CA<1>")
	)
	(gr_poly
		(pts
			(xy 327.528174 -257.891026) (xy 327.528174 -257.840226) (xy 327.265284 -257.840226) (xy 327.265284 -257.891026)
			(xy 327.301352 -257.992626) (xy 327.491852 -257.992626)
		)
		(stroke
			(width 0)
			(type solid)
		)
		(fill yes)
		(layer "F.Cu")
		(net "M_A_CPU0_SA_CA<2>")
	)
	(gr_poly
		(pts
			(xy 327.528174 -257.586226) (xy 327.528174 -257.535426) (xy 327.265284 -257.535426) (xy 327.265284 -257.586226)
			(xy 327.301352 -257.687826) (xy 327.491852 -257.687826)
		)
		(stroke
			(width 0)
			(type solid)
		)
		(fill yes)
		(layer "F.Cu")
		(net "M_A_CPU0_SA_CA<3>")
	)
	(gr_poly
		(pts
			(xy 327.528174 -257.281426) (xy 327.528174 -257.230626) (xy 327.265284 -257.230626) (xy 327.265284 -257.281426)
			(xy 327.301352 -257.383026) (xy 327.491852 -257.383026)
		)
		(stroke
			(width 0)
			(type solid)
		)
		(fill yes)
		(layer "F.Cu")
		(net "M_A_CPU0_SA_CA<4>")
	)
	(gr_poly
		(pts
			(xy 327.528174 -256.976626) (xy 327.528174 -256.925826) (xy 327.265284 -256.925826) (xy 327.265284 -256.976626)
			(xy 327.301352 -257.078226) (xy 327.491852 -257.078226)
		)
		(stroke
			(width 0)
			(type solid)
		)
		(fill yes)
		(layer "F.Cu")
		(net "M_A_CPU0_SA_CA<5>")
	)
	(gr_poly
		(pts
			(xy 327.528174 -256.671826) (xy 327.528174 -256.621026) (xy 327.265284 -256.621026) (xy 327.265284 -256.671826)
			(xy 327.301352 -256.773426) (xy 327.491852 -256.773426)
		)
		(stroke
			(width 0)
			(type solid)
		)
		(fill yes)
		(layer "F.Cu")
		(net "M_A_CPU0_SA_CA<6>")
	)
	(gr_poly
		(pts
			(xy 327.528174 -256.367026) (xy 327.528174 -256.316226) (xy 327.265284 -256.316226) (xy 327.265284 -256.367026)
			(xy 327.301352 -256.468626) (xy 327.491852 -256.468626)
		)
		(stroke
			(width 0)
			(type solid)
		)
		(fill yes)
		(layer "F.Cu")
		(net "M_A_CPU0_SA_PAR")
	)
	(gr_poly
		(pts
			(xy 327.528682 -234.542838) (xy 327.56475 -234.507024) (xy 327.378822 -234.321096) (xy 327.343008 -234.35691)
			(xy 327.29678 -234.454446) (xy 327.4314 -234.589066)
		)
		(stroke
			(width 0)
			(type solid)
		)
		(fill yes)
		(layer "F.Cu")
		(net "M_A_CPU0_SB_DQ<8>")
	)
	(gr_poly
		(pts
			(xy 327.53808 -233.689652) (xy 327.573894 -233.653584) (xy 327.387966 -233.467656) (xy 327.352152 -233.503724)
			(xy 327.305924 -233.601006) (xy 327.440544 -233.73588)
		)
		(stroke
			(width 0)
			(type solid)
		)
		(fill yes)
		(layer "F.Cu")
		(net "M_A_CPU0_SB_DQ<9>")
	)
	(gr_poly
		(pts
			(xy 327.568052 -222.372936) (xy 327.568052 -222.182436) (xy 327.466452 -222.146114) (xy 327.415652 -222.146114)
			(xy 327.415652 -222.409258) (xy 327.466452 -222.409258)
		)
		(stroke
			(width 0)
			(type solid)
		)
		(fill yes)
		(layer "F.Cu")
		(net "M_A_CPU0_SB_DQ<22>")
	)
	(gr_poly
		(pts
			(xy 327.568052 -221.776036) (xy 327.568052 -221.585536) (xy 327.466452 -221.549214) (xy 327.415652 -221.549214)
			(xy 327.415652 -221.812358) (xy 327.466452 -221.812358)
		)
		(stroke
			(width 0)
			(type solid)
		)
		(fill yes)
		(layer "F.Cu")
		(net "M_A_CPU0_SB_DQ<22>")
	)
	(gr_poly
		(pts
			(xy 327.568052 -221.179136) (xy 327.568052 -220.988636) (xy 327.466452 -220.952314) (xy 327.415652 -220.952314)
			(xy 327.415652 -221.215458) (xy 327.466452 -221.215458)
		)
		(stroke
			(width 0)
			(type solid)
		)
		(fill yes)
		(layer "F.Cu")
		(net "M_A_CPU0_SB_DQ<22>")
	)
	(gr_poly
		(pts
			(xy 327.568052 -220.582236) (xy 327.568052 -220.391736) (xy 327.466452 -220.355414) (xy 327.415652 -220.355414)
			(xy 327.415652 -220.618558) (xy 327.466452 -220.618558)
		)
		(stroke
			(width 0)
			(type solid)
		)
		(fill yes)
		(layer "F.Cu")
		(net "M_A_CPU0_SB_DQ<22>")
	)
	(gr_poly
		(pts
			(xy 327.568052 -219.985336) (xy 327.568052 -219.794836) (xy 327.466452 -219.758514) (xy 327.415652 -219.758514)
			(xy 327.415652 -220.021658) (xy 327.466452 -220.021658)
		)
		(stroke
			(width 0)
			(type solid)
		)
		(fill yes)
		(layer "F.Cu")
		(net "M_A_CPU0_SB_DQ<22>")
	)
	(gr_poly
		(pts
			(xy 327.568052 -219.388436) (xy 327.568052 -219.197936) (xy 327.466452 -219.161614) (xy 327.415652 -219.161614)
			(xy 327.415652 -219.424758) (xy 327.466452 -219.424758)
		)
		(stroke
			(width 0)
			(type solid)
		)
		(fill yes)
		(layer "F.Cu")
		(net "M_A_CPU0_SB_DQ<22>")
	)
	(gr_poly
		(pts
			(xy 327.568052 -218.791536) (xy 327.568052 -218.601036) (xy 327.466452 -218.564714) (xy 327.415652 -218.564714)
			(xy 327.415652 -218.827858) (xy 327.466452 -218.827858)
		)
		(stroke
			(width 0)
			(type solid)
		)
		(fill yes)
		(layer "F.Cu")
		(net "M_A_CPU0_SB_DQ<22>")
	)
	(gr_poly
		(pts
			(xy 327.568052 -218.194636) (xy 327.568052 -218.004136) (xy 327.466452 -217.967814) (xy 327.415652 -217.967814)
			(xy 327.415652 -218.230958) (xy 327.466452 -218.230958)
		)
		(stroke
			(width 0)
			(type solid)
		)
		(fill yes)
		(layer "F.Cu")
		(net "M_A_CPU0_SB_DQ<22>")
	)
	(gr_poly
		(pts
			(xy 327.568052 -217.597736) (xy 327.568052 -217.407236) (xy 327.466452 -217.370914) (xy 327.415652 -217.370914)
			(xy 327.415652 -217.634058) (xy 327.466452 -217.634058)
		)
		(stroke
			(width 0)
			(type solid)
		)
		(fill yes)
		(layer "F.Cu")
		(net "M_A_CPU0_SB_DQ<22>")
	)
	(gr_poly
		(pts
			(xy 327.568052 -217.000836) (xy 327.568052 -216.810336) (xy 327.466452 -216.774014) (xy 327.415652 -216.774014)
			(xy 327.415652 -217.037158) (xy 327.466452 -217.037158)
		)
		(stroke
			(width 0)
			(type solid)
		)
		(fill yes)
		(layer "F.Cu")
		(net "M_A_CPU0_SB_DQ<22>")
	)
	(gr_poly
		(pts
			(xy 327.568052 -216.403936) (xy 327.568052 -216.213436) (xy 327.466452 -216.177114) (xy 327.415652 -216.177114)
			(xy 327.415652 -216.440258) (xy 327.466452 -216.440258)
		)
		(stroke
			(width 0)
			(type solid)
		)
		(fill yes)
		(layer "F.Cu")
		(net "M_A_CPU0_SB_DQ<22>")
	)
	(gr_poly
		(pts
			(xy 327.568052 -215.807036) (xy 327.568052 -215.616536) (xy 327.466452 -215.580214) (xy 327.415652 -215.580214)
			(xy 327.415652 -215.843358) (xy 327.466452 -215.843358)
		)
		(stroke
			(width 0)
			(type solid)
		)
		(fill yes)
		(layer "F.Cu")
		(net "M_A_CPU0_SB_DQ<22>")
	)
	(gr_poly
		(pts
			(xy 327.568052 -215.210136) (xy 327.568052 -215.019636) (xy 327.466452 -214.983314) (xy 327.415652 -214.983314)
			(xy 327.415652 -215.246458) (xy 327.466452 -215.246458)
		)
		(stroke
			(width 0)
			(type solid)
		)
		(fill yes)
		(layer "F.Cu")
		(net "M_A_CPU0_SB_DQ<22>")
	)
	(gr_poly
		(pts
			(xy 327.575926 -231.139492) (xy 327.61174 -231.103678) (xy 327.425812 -230.91775) (xy 327.389998 -230.953564)
			(xy 327.34377 -231.0511) (xy 327.47839 -231.18572)
		)
		(stroke
			(width 0)
			(type solid)
		)
		(fill yes)
		(layer "F.Cu")
		(net "M_A_CPU0_SB_DQ<12>")
	)
	(gr_poly
		(pts
			(xy 327.58507 -230.286052) (xy 327.621138 -230.250238) (xy 327.43521 -230.06431) (xy 327.399142 -230.100124)
			(xy 327.352914 -230.19766) (xy 327.487788 -230.33228)
		)
		(stroke
			(width 0)
			(type solid)
		)
		(fill yes)
		(layer "F.Cu")
		(net "M_A_CPU0_SB_DQ<13>")
	)
	(gr_poly
		(pts
			(xy 327.585578 -275.454618) (xy 327.549764 -275.41855) (xy 327.452228 -275.372322) (xy 327.317608 -275.507196)
			(xy 327.363836 -275.604478) (xy 327.399904 -275.640546)
		)
		(stroke
			(width 0)
			(type solid)
		)
		(fill yes)
		(layer "F.Cu")
		(net "M_A_CPU0_SA_DQ<23>")
	)
	(gr_poly
		(pts
			(xy 327.59269 -270.460724) (xy 327.546462 -270.363442) (xy 327.510648 -270.327374) (xy 327.32472 -270.513302)
			(xy 327.360534 -270.54937) (xy 327.45807 -270.595598)
		)
		(stroke
			(width 0)
			(type solid)
		)
		(fill yes)
		(layer "F.Cu")
		(net "M_A_CPU0_SA_DQ<29>")
	)
	(gr_poly
		(pts
			(xy 327.59523 -229.016814) (xy 327.631044 -228.980746) (xy 327.445116 -228.794818) (xy 327.409302 -228.830886)
			(xy 327.363074 -228.928168) (xy 327.497694 -229.063042)
		)
		(stroke
			(width 0)
			(type solid)
		)
		(fill yes)
		(layer "F.Cu")
		(net "M_A_CPU0_SB_DQ<16>")
	)
	(gr_poly
		(pts
			(xy 327.602342 -271.314672) (xy 327.556114 -271.217136) (xy 327.520046 -271.181322) (xy 327.334372 -271.366996)
			(xy 327.370186 -271.403064) (xy 327.467722 -271.449292)
		)
		(stroke
			(width 0)
			(type solid)
		)
		(fill yes)
		(layer "F.Cu")
		(net "M_A_CPU0_SA_DQ<28>")
	)
	(gr_poly
		(pts
			(xy 327.604374 -228.163374) (xy 327.640188 -228.127306) (xy 327.454514 -227.941632) (xy 327.418446 -227.977446)
			(xy 327.372218 -228.074982) (xy 327.506838 -228.209602)
		)
		(stroke
			(width 0)
			(type solid)
		)
		(fill yes)
		(layer "F.Cu")
		(net "M_A_CPU0_SB_DQ<17>")
	)
	(gr_poly
		(pts
			(xy 327.605136 -234.04449) (xy 327.651618 -233.946954) (xy 327.516744 -233.812334) (xy 327.419462 -233.858562)
			(xy 327.383394 -233.894376) (xy 327.569322 -234.080304)
		)
		(stroke
			(width 0)
			(type solid)
		)
		(fill yes)
		(layer "F.Cu")
		(net "M_A_CPU0_SB_DQ<10>")
	)
	(gr_poly
		(pts
			(xy 327.614534 -233.19105) (xy 327.660762 -233.093514) (xy 327.525888 -232.958894) (xy 327.428606 -233.005122)
			(xy 327.392538 -233.040936) (xy 327.578466 -233.226864)
		)
		(stroke
			(width 0)
			(type solid)
		)
		(fill yes)
		(layer "F.Cu")
		(net "M_A_CPU0_SB_DQ<11>")
	)
	(gr_poly
		(pts
			(xy 327.620376 -223.308672) (xy 327.666604 -223.211136) (xy 327.53173 -223.076516) (xy 327.434448 -223.122744)
			(xy 327.39838 -223.158558) (xy 327.584308 -223.344486)
		)
		(stroke
			(width 0)
			(type solid)
		)
		(fill yes)
		(layer "F.Cu")
		(net "M_A_CPU0_SB_DQ<20>")
	)
	(gr_poly
		(pts
			(xy 327.625964 -262.688578) (xy 327.59015 -262.65251) (xy 327.492614 -262.606282) (xy 327.357994 -262.740902)
			(xy 327.404222 -262.838438) (xy 327.44029 -262.874252)
		)
		(stroke
			(width 0)
			(type solid)
		)
		(fill yes)
		(layer "F.Cu")
		(net "M_A_CPU0_SA_CB<7>")
	)
	(gr_poly
		(pts
			(xy 327.635616 -263.542018) (xy 327.599548 -263.506204) (xy 327.502266 -263.459976) (xy 327.367392 -263.594596)
			(xy 327.413874 -263.692132) (xy 327.449688 -263.727946)
		)
		(stroke
			(width 0)
			(type solid)
		)
		(fill yes)
		(layer "F.Cu")
		(net "M_A_CPU0_SA_CB<6>")
	)
	(gr_poly
		(pts
			(xy 327.640188 -273.218656) (xy 327.604374 -273.182588) (xy 327.506838 -273.13636) (xy 327.372218 -273.271234)
			(xy 327.418446 -273.368516) (xy 327.45426 -273.404584)
		)
		(stroke
			(width 0)
			(type solid)
		)
		(fill yes)
		(layer "F.Cu")
		(net "M_A_CPU0_SA_DQ<27>")
	)
	(gr_poly
		(pts
			(xy 327.640696 -266.124944) (xy 327.604628 -266.08913) (xy 327.507346 -266.042902) (xy 327.372472 -266.177522)
			(xy 327.4187 -266.275058) (xy 327.454768 -266.310872)
		)
		(stroke
			(width 0)
			(type solid)
		)
		(fill yes)
		(layer "F.Cu")
		(net "M_A_CPU0_SA_CB<3>")
	)
	(gr_poly
		(pts
			(xy 327.64984 -274.072096) (xy 327.613772 -274.036282) (xy 327.51649 -273.990054) (xy 327.381616 -274.124674)
			(xy 327.427844 -274.22221) (xy 327.463912 -274.258024)
		)
		(stroke
			(width 0)
			(type solid)
		)
		(fill yes)
		(layer "F.Cu")
		(net "M_A_CPU0_SA_DQ<26>")
	)
	(gr_poly
		(pts
			(xy 327.64984 -266.978638) (xy 327.614026 -266.94257) (xy 327.51649 -266.896342) (xy 327.38187 -267.030962)
			(xy 327.428098 -267.128498) (xy 327.464166 -267.164312)
		)
		(stroke
			(width 0)
			(type solid)
		)
		(fill yes)
		(layer "F.Cu")
		(net "M_A_CPU0_SA_CB<2>")
	)
	(gr_poly
		(pts
			(xy 327.65238 -230.64089) (xy 327.698608 -230.543608) (xy 327.563988 -230.408734) (xy 327.466452 -230.454962)
			(xy 327.430638 -230.49103) (xy 327.616566 -230.676958)
		)
		(stroke
			(width 0)
			(type solid)
		)
		(fill yes)
		(layer "F.Cu")
		(net "M_A_CPU0_SB_DQ<14>")
	)
	(gr_poly
		(pts
			(xy 327.661524 -229.78745) (xy 327.707752 -229.690168) (xy 327.573132 -229.555548) (xy 327.475596 -229.601776)
			(xy 327.439782 -229.63759) (xy 327.62571 -229.823518)
		)
		(stroke
			(width 0)
			(type solid)
		)
		(fill yes)
		(layer "F.Cu")
		(net "M_A_CPU0_SB_DQ<15>")
	)
	(gr_poly
		(pts
			(xy 327.671684 -228.518212) (xy 327.717912 -228.420676) (xy 327.583038 -228.286056) (xy 327.485756 -228.332284)
			(xy 327.449688 -228.368098) (xy 327.635616 -228.554026)
		)
		(stroke
			(width 0)
			(type solid)
		)
		(fill yes)
		(layer "F.Cu")
		(net "M_A_CPU0_SB_DQ<18>")
	)
	(gr_poly
		(pts
			(xy 327.680828 -227.664772) (xy 327.727056 -227.56749) (xy 327.592436 -227.432616) (xy 327.4949 -227.478844)
			(xy 327.459086 -227.514912) (xy 327.645014 -227.70084)
		)
		(stroke
			(width 0)
			(type solid)
		)
		(fill yes)
		(layer "F.Cu")
		(net "M_A_CPU0_SB_DQ<19>")
	)
	(gr_poly
		(pts
			(xy 327.713086 -263.248648) (xy 327.666858 -263.151112) (xy 327.63079 -263.115298) (xy 327.444862 -263.301226)
			(xy 327.48093 -263.33704) (xy 327.578212 -263.383268)
		)
		(stroke
			(width 0)
			(type solid)
		)
		(fill yes)
		(layer "F.Cu")
		(net "M_A_CPU0_SA_CB<5>")
	)
	(gr_poly
		(pts
			(xy 327.720452 -221.847918) (xy 327.669652 -221.847918) (xy 327.568052 -221.883986) (xy 327.568052 -222.074486)
			(xy 327.669652 -222.110554) (xy 327.720452 -222.110554)
		)
		(stroke
			(width 0)
			(type solid)
		)
		(fill yes)
		(layer "F.Cu")
		(net "M_A_CPU0_SB_DQ<21>")
	)
	(gr_poly
		(pts
			(xy 327.720452 -221.251018) (xy 327.669652 -221.251018) (xy 327.568052 -221.287086) (xy 327.568052 -221.477586)
			(xy 327.669652 -221.513654) (xy 327.720452 -221.513654)
		)
		(stroke
			(width 0)
			(type solid)
		)
		(fill yes)
		(layer "F.Cu")
		(net "M_A_CPU0_SB_DQ<21>")
	)
	(gr_poly
		(pts
			(xy 327.720452 -220.654118) (xy 327.669652 -220.654118) (xy 327.568052 -220.690186) (xy 327.568052 -220.880686)
			(xy 327.669652 -220.916754) (xy 327.720452 -220.916754)
		)
		(stroke
			(width 0)
			(type solid)
		)
		(fill yes)
		(layer "F.Cu")
		(net "M_A_CPU0_SB_DQ<21>")
	)
	(gr_poly
		(pts
			(xy 327.720452 -220.057218) (xy 327.669652 -220.057218) (xy 327.568052 -220.093286) (xy 327.568052 -220.283786)
			(xy 327.669652 -220.319854) (xy 327.720452 -220.319854)
		)
		(stroke
			(width 0)
			(type solid)
		)
		(fill yes)
		(layer "F.Cu")
		(net "M_A_CPU0_SB_DQ<21>")
	)
	(gr_poly
		(pts
			(xy 327.720452 -219.460318) (xy 327.669652 -219.460318) (xy 327.568052 -219.496386) (xy 327.568052 -219.686886)
			(xy 327.669652 -219.722954) (xy 327.720452 -219.722954)
		)
		(stroke
			(width 0)
			(type solid)
		)
		(fill yes)
		(layer "F.Cu")
		(net "M_A_CPU0_SB_DQ<21>")
	)
	(gr_poly
		(pts
			(xy 327.720452 -218.863418) (xy 327.669652 -218.863418) (xy 327.568052 -218.899486) (xy 327.568052 -219.089986)
			(xy 327.669652 -219.126054) (xy 327.720452 -219.126054)
		)
		(stroke
			(width 0)
			(type solid)
		)
		(fill yes)
		(layer "F.Cu")
		(net "M_A_CPU0_SB_DQ<21>")
	)
	(gr_poly
		(pts
			(xy 327.720452 -218.266518) (xy 327.669652 -218.266518) (xy 327.568052 -218.302586) (xy 327.568052 -218.493086)
			(xy 327.669652 -218.529154) (xy 327.720452 -218.529154)
		)
		(stroke
			(width 0)
			(type solid)
		)
		(fill yes)
		(layer "F.Cu")
		(net "M_A_CPU0_SB_DQ<21>")
	)
	(gr_poly
		(pts
			(xy 327.720452 -217.669618) (xy 327.669652 -217.669618) (xy 327.568052 -217.705686) (xy 327.568052 -217.896186)
			(xy 327.669652 -217.932254) (xy 327.720452 -217.932254)
		)
		(stroke
			(width 0)
			(type solid)
		)
		(fill yes)
		(layer "F.Cu")
		(net "M_A_CPU0_SB_DQ<21>")
	)
	(gr_poly
		(pts
			(xy 327.720452 -217.072718) (xy 327.669652 -217.072718) (xy 327.568052 -217.108786) (xy 327.568052 -217.299286)
			(xy 327.669652 -217.335354) (xy 327.720452 -217.335354)
		)
		(stroke
			(width 0)
			(type solid)
		)
		(fill yes)
		(layer "F.Cu")
		(net "M_A_CPU0_SB_DQ<21>")
	)
	(gr_poly
		(pts
			(xy 327.720452 -216.475818) (xy 327.669652 -216.475818) (xy 327.568052 -216.511886) (xy 327.568052 -216.702386)
			(xy 327.669652 -216.738454) (xy 327.720452 -216.738454)
		)
		(stroke
			(width 0)
			(type solid)
		)
		(fill yes)
		(layer "F.Cu")
		(net "M_A_CPU0_SB_DQ<21>")
	)
	(gr_poly
		(pts
			(xy 327.720452 -215.878918) (xy 327.669652 -215.878918) (xy 327.568052 -215.914986) (xy 327.568052 -216.105486)
			(xy 327.669652 -216.141554) (xy 327.720452 -216.141554)
		)
		(stroke
			(width 0)
			(type solid)
		)
		(fill yes)
		(layer "F.Cu")
		(net "M_A_CPU0_SB_DQ<21>")
	)
	(gr_poly
		(pts
			(xy 327.720452 -215.282018) (xy 327.669652 -215.282018) (xy 327.568052 -215.318086) (xy 327.568052 -215.508586)
			(xy 327.669652 -215.544654) (xy 327.720452 -215.544654)
		)
		(stroke
			(width 0)
			(type solid)
		)
		(fill yes)
		(layer "F.Cu")
		(net "M_A_CPU0_SB_DQ<21>")
	)
	(gr_poly
		(pts
			(xy 327.721468 -270.116554) (xy 327.685654 -270.080486) (xy 327.588118 -270.034258) (xy 327.453498 -270.168878)
			(xy 327.499726 -270.266414) (xy 327.535794 -270.302228)
		)
		(stroke
			(width 0)
			(type solid)
		)
		(fill yes)
		(layer "F.Cu")
		(net "M_A_CPU0_SA_DQ<29>")
	)
	(gr_poly
		(pts
			(xy 327.722484 -264.102342) (xy 327.676256 -264.004806) (xy 327.640188 -263.968992) (xy 327.454514 -264.154666)
			(xy 327.490328 -264.190734) (xy 327.587864 -264.236962)
		)
		(stroke
			(width 0)
			(type solid)
		)
		(fill yes)
		(layer "F.Cu")
		(net "M_A_CPU0_SA_CB<4>")
	)
	(gr_poly
		(pts
			(xy 327.72731 -273.77898) (xy 327.681082 -273.681444) (xy 327.645014 -273.64563) (xy 327.45934 -273.831304)
			(xy 327.495154 -273.867372) (xy 327.59269 -273.9136)
		)
		(stroke
			(width 0)
			(type solid)
		)
		(fill yes)
		(layer "F.Cu")
		(net "M_A_CPU0_SA_DQ<25>")
	)
	(gr_poly
		(pts
			(xy 327.72731 -266.685014) (xy 327.681082 -266.587732) (xy 327.645268 -266.551664) (xy 327.45934 -266.737592)
			(xy 327.495154 -266.773406) (xy 327.59269 -266.819888)
		)
		(stroke
			(width 0)
			(type solid)
		)
		(fill yes)
		(layer "F.Cu")
		(net "M_A_CPU0_SA_CB<1>")
	)
	(gr_poly
		(pts
			(xy 327.73112 -270.970248) (xy 327.695306 -270.93418) (xy 327.59777 -270.887952) (xy 327.46315 -271.022826)
			(xy 327.509378 -271.120108) (xy 327.545192 -271.156176)
		)
		(stroke
			(width 0)
			(type solid)
		)
		(fill yes)
		(layer "F.Cu")
		(net "M_A_CPU0_SA_DQ<28>")
	)
	(gr_poly
		(pts
			(xy 327.736454 -274.632166) (xy 327.690226 -274.534884) (xy 327.654412 -274.498816) (xy 327.468484 -274.684744)
			(xy 327.504298 -274.720812) (xy 327.601834 -274.76704)
		)
		(stroke
			(width 0)
			(type solid)
		)
		(fill yes)
		(layer "F.Cu")
		(net "M_A_CPU0_SA_DQ<24>")
	)
	(gr_poly
		(pts
			(xy 327.736708 -267.538454) (xy 327.69048 -267.441172) (xy 327.654666 -267.405104) (xy 327.468738 -267.591032)
			(xy 327.504552 -267.6271) (xy 327.602088 -267.673328)
		)
		(stroke
			(width 0)
			(type solid)
		)
		(fill yes)
		(layer "F.Cu")
		(net "M_A_CPU0_SA_CB<0>")
	)
	(gr_poly
		(pts
			(xy 327.743566 -277.102062) (xy 327.671176 -277.022306) (xy 327.626218 -276.99843) (xy 327.502266 -277.230078)
			(xy 327.547224 -277.253954) (xy 327.65365 -277.27021)
		)
		(stroke
			(width 0)
			(type solid)
		)
		(fill yes)
		(layer "F.Cu")
		(net "M_A_CPU0_SA_DQ<20>")
	)
	(gr_poly
		(pts
			(xy 327.744328 -234.327192) (xy 327.780396 -234.291378) (xy 327.594468 -234.10545) (xy 327.558654 -234.141264)
			(xy 327.512426 -234.2388) (xy 327.647046 -234.37342)
		)
		(stroke
			(width 0)
			(type solid)
		)
		(fill yes)
		(layer "F.Cu")
		(net "M_A_CPU0_SB_DQ<10>")
	)
	(gr_poly
		(pts
			(xy 327.753726 -233.474006) (xy 327.78954 -233.437938) (xy 327.603612 -233.25201) (xy 327.567798 -233.288078)
			(xy 327.52157 -233.38536) (xy 327.65619 -233.520234)
		)
		(stroke
			(width 0)
			(type solid)
		)
		(fill yes)
		(layer "F.Cu")
		(net "M_A_CPU0_SB_DQ<11>")
	)
	(gr_poly
		(pts
			(xy 327.756266 -276.431756) (xy 327.683622 -276.352) (xy 327.638918 -276.328124) (xy 327.514966 -276.559772)
			(xy 327.55967 -276.583902) (xy 327.66635 -276.599904)
		)
		(stroke
			(width 0)
			(type solid)
		)
		(fill yes)
		(layer "F.Cu")
		(net "M_A_CPU0_SA_DQ<22>")
	)
	(gr_poly
		(pts
			(xy 327.759568 -223.591374) (xy 327.795382 -223.55556) (xy 327.609454 -223.369632) (xy 327.57364 -223.4057)
			(xy 327.527412 -223.502982) (xy 327.662032 -223.637856)
		)
		(stroke
			(width 0)
			(type solid)
		)
		(fill yes)
		(layer "F.Cu")
		(net "M_A_CPU0_SB_DQ<20>")
	)
	(gr_poly
		(pts
			(xy 327.767188 -276.735286) (xy 327.72223 -276.711156) (xy 327.61555 -276.695154) (xy 327.525888 -276.863048)
			(xy 327.598278 -276.943058) (xy 327.643236 -276.966934)
		)
		(stroke
			(width 0)
			(type solid)
		)
		(fill yes)
		(layer "F.Cu")
		(net "M_A_CPU0_SA_DQ<20>")
	)
	(gr_poly
		(pts
			(xy 327.791572 -230.923846) (xy 327.827386 -230.887778) (xy 327.641712 -230.702104) (xy 327.605644 -230.737918)
			(xy 327.559416 -230.835454) (xy 327.694036 -230.970074)
		)
		(stroke
			(width 0)
			(type solid)
		)
		(fill yes)
		(layer "F.Cu")
		(net "M_A_CPU0_SB_DQ<14>")
	)
	(gr_poly
		(pts
			(xy 327.793858 -249.371866) (xy 327.793858 -249.321066) (xy 327.530968 -249.321066) (xy 327.530968 -249.371866)
			(xy 327.567036 -249.473466) (xy 327.757536 -249.473466)
		)
		(stroke
			(width 0)
			(type solid)
		)
		(fill yes)
		(layer "F.Cu")
		(net "M_A_CPU0_SB_CA<0>")
	)
	(gr_poly
		(pts
			(xy 327.793858 -249.066812) (xy 327.793858 -249.016012) (xy 327.530968 -249.016012) (xy 327.530968 -249.066812)
			(xy 327.567036 -249.168412) (xy 327.757536 -249.168412)
		)
		(stroke
			(width 0)
			(type solid)
		)
		(fill yes)
		(layer "F.Cu")
		(net "M_A_CPU0_SB_CA<1>")
	)
	(gr_poly
		(pts
			(xy 327.793858 -248.762012) (xy 327.793858 -248.711212) (xy 327.530968 -248.711212) (xy 327.530968 -248.762012)
			(xy 327.567036 -248.863612) (xy 327.757536 -248.863612)
		)
		(stroke
			(width 0)
			(type solid)
		)
		(fill yes)
		(layer "F.Cu")
		(net "M_A_CPU0_SB_CA<2>")
	)
	(gr_poly
		(pts
			(xy 327.793858 -248.457212) (xy 327.793858 -248.406412) (xy 327.530968 -248.406412) (xy 327.530968 -248.457212)
			(xy 327.567036 -248.558812) (xy 327.757536 -248.558812)
		)
		(stroke
			(width 0)
			(type solid)
		)
		(fill yes)
		(layer "F.Cu")
		(net "M_A_CPU0_SB_CA<3>")
	)
	(gr_poly
		(pts
			(xy 327.793858 -248.152412) (xy 327.793858 -248.101612) (xy 327.530968 -248.101612) (xy 327.530968 -248.152412)
			(xy 327.567036 -248.254012) (xy 327.757536 -248.254012)
		)
		(stroke
			(width 0)
			(type solid)
		)
		(fill yes)
		(layer "F.Cu")
		(net "M_A_CPU0_SB_CA<4>")
	)
	(gr_poly
		(pts
			(xy 327.793858 -247.847612) (xy 327.793858 -247.796812) (xy 327.530968 -247.796812) (xy 327.530968 -247.847612)
			(xy 327.567036 -247.949212) (xy 327.757536 -247.949212)
		)
		(stroke
			(width 0)
			(type solid)
		)
		(fill yes)
		(layer "F.Cu")
		(net "M_A_CPU0_SB_CA<5>")
	)
	(gr_poly
		(pts
			(xy 327.793858 -247.542812) (xy 327.793858 -247.492012) (xy 327.530968 -247.492012) (xy 327.530968 -247.542812)
			(xy 327.567036 -247.644412) (xy 327.757536 -247.644412)
		)
		(stroke
			(width 0)
			(type solid)
		)
		(fill yes)
		(layer "F.Cu")
		(net "M_A_CPU0_SB_CA<6>")
	)
	(gr_poly
		(pts
			(xy 327.793858 -247.238012) (xy 327.793858 -247.187212) (xy 327.530968 -247.187212) (xy 327.530968 -247.238012)
			(xy 327.567036 -247.339612) (xy 327.757536 -247.339612)
		)
		(stroke
			(width 0)
			(type solid)
		)
		(fill yes)
		(layer "F.Cu")
		(net "M_A_CPU0_SB_PAR")
	)
	(gr_poly
		(pts
			(xy 327.793858 -246.933212) (xy 327.793858 -246.882412) (xy 327.530968 -246.882412) (xy 327.530968 -246.933212)
			(xy 327.567036 -247.034812) (xy 327.757536 -247.034812)
		)
		(stroke
			(width 0)
			(type solid)
		)
		(fill yes)
		(layer "F.Cu")
		(net "M_A_CPU0_SB_CS_N<2>")
	)
	(gr_poly
		(pts
			(xy 327.793858 -246.628412) (xy 327.793858 -246.577612) (xy 327.530968 -246.577612) (xy 327.530968 -246.628412)
			(xy 327.567036 -246.730012) (xy 327.757536 -246.730012)
		)
		(stroke
			(width 0)
			(type solid)
		)
		(fill yes)
		(layer "F.Cu")
		(net "M_A_CPU0_SB_CS_N<0>")
	)
	(gr_poly
		(pts
			(xy 327.793858 -246.323612) (xy 327.793858 -246.272812) (xy 327.530968 -246.272812) (xy 327.530968 -246.323612)
			(xy 327.567036 -246.425212) (xy 327.757536 -246.425212)
		)
		(stroke
			(width 0)
			(type solid)
		)
		(fill yes)
		(layer "F.Cu")
		(net "M_A_CPU0_SB_CS_N<3>")
	)
	(gr_poly
		(pts
			(xy 327.793858 -246.018812) (xy 327.793858 -245.968012) (xy 327.530968 -245.968012) (xy 327.530968 -246.018812)
			(xy 327.567036 -246.120412) (xy 327.757536 -246.120412)
		)
		(stroke
			(width 0)
			(type solid)
		)
		(fill yes)
		(layer "F.Cu")
		(net "M_A_CPU0_SB_CS_N<1>")
	)
	(gr_poly
		(pts
			(xy 327.798938 -269.82293) (xy 327.75271 -269.725648) (xy 327.716896 -269.68958) (xy 327.530968 -269.875508)
			(xy 327.566782 -269.911322) (xy 327.664318 -269.957804)
		)
		(stroke
			(width 0)
			(type solid)
		)
		(fill yes)
		(layer "F.Cu")
		(net "M_A_CPU0_SA_DQ<31>")
	)
	(gr_poly
		(pts
			(xy 327.800716 -230.070406) (xy 327.836784 -230.034592) (xy 327.650856 -229.848664) (xy 327.614788 -229.884478)
			(xy 327.56856 -229.982014) (xy 327.703434 -230.116634)
		)
		(stroke
			(width 0)
			(type solid)
		)
		(fill yes)
		(layer "F.Cu")
		(net "M_A_CPU0_SB_DQ<15>")
	)
	(gr_poly
		(pts
			(xy 327.801224 -275.670264) (xy 327.76541 -275.634196) (xy 327.667874 -275.587968) (xy 327.533254 -275.722842)
			(xy 327.579482 -275.820124) (xy 327.615296 -275.856192)
		)
		(stroke
			(width 0)
			(type solid)
		)
		(fill yes)
		(layer "F.Cu")
		(net "M_A_CPU0_SA_DQ<21>")
	)
	(gr_poly
		(pts
			(xy 327.808844 -270.676878) (xy 327.762362 -270.579342) (xy 327.726548 -270.543528) (xy 327.54062 -270.729456)
			(xy 327.576688 -270.76527) (xy 327.67397 -270.811498)
		)
		(stroke
			(width 0)
			(type solid)
		)
		(fill yes)
		(layer "F.Cu")
		(net "M_A_CPU0_SA_DQ<30>")
	)
	(gr_poly
		(pts
			(xy 327.810876 -228.801168) (xy 327.84669 -228.7651) (xy 327.660762 -228.579172) (xy 327.624948 -228.61524)
			(xy 327.57872 -228.712522) (xy 327.71334 -228.847396)
		)
		(stroke
			(width 0)
			(type solid)
		)
		(fill yes)
		(layer "F.Cu")
		(net "M_A_CPU0_SB_DQ<18>")
	)
	(gr_poly
		(pts
			(xy 327.811638 -234.68203) (xy 327.857866 -234.584748) (xy 327.723246 -234.449874) (xy 327.62571 -234.496102)
			(xy 327.589896 -234.53217) (xy 327.775824 -234.718098)
		)
		(stroke
			(width 0)
			(type solid)
		)
		(fill yes)
		(layer "F.Cu")
		(net "M_A_CPU0_SB_DQ<8>")
	)
	(gr_poly
		(pts
			(xy 327.82002 -227.947728) (xy 327.855834 -227.91166) (xy 327.67016 -227.725986) (xy 327.634092 -227.7618)
			(xy 327.587864 -227.859336) (xy 327.722484 -227.993956)
		)
		(stroke
			(width 0)
			(type solid)
		)
		(fill yes)
		(layer "F.Cu")
		(net "M_A_CPU0_SB_DQ<19>")
	)
	(gr_poly
		(pts
			(xy 327.820782 -233.828844) (xy 327.867264 -233.731308) (xy 327.73239 -233.596688) (xy 327.635108 -233.642916)
			(xy 327.59904 -233.67873) (xy 327.784968 -233.864658)
		)
		(stroke
			(width 0)
			(type solid)
		)
		(fill yes)
		(layer "F.Cu")
		(net "M_A_CPU0_SB_DQ<9>")
	)
	(gr_poly
		(pts
			(xy 327.826624 -259.008626) (xy 327.790556 -258.907026) (xy 327.600056 -258.907026) (xy 327.563734 -259.008626)
			(xy 327.563734 -259.059426) (xy 327.826624 -259.059426)
		)
		(stroke
			(width 0)
			(type solid)
		)
		(fill yes)
		(layer "F.Cu")
		(net "M_A_CPU0_SA_CS_N<3>")
	)
	(gr_poly
		(pts
			(xy 327.826624 -258.703826) (xy 327.790556 -258.602226) (xy 327.600056 -258.602226) (xy 327.563734 -258.703826)
			(xy 327.563734 -258.754626) (xy 327.826624 -258.754626)
		)
		(stroke
			(width 0)
			(type solid)
		)
		(fill yes)
		(layer "F.Cu")
		(net "M_A_CPU0_SA_CS_N<1>")
	)
	(gr_poly
		(pts
			(xy 327.826624 -258.399026) (xy 327.790556 -258.297426) (xy 327.600056 -258.297426) (xy 327.563734 -258.399026)
			(xy 327.563734 -258.449826) (xy 327.826624 -258.449826)
		)
		(stroke
			(width 0)
			(type solid)
		)
		(fill yes)
		(layer "F.Cu")
		(net "M_A_CPU0_SA_CA<0>")
	)
	(gr_poly
		(pts
			(xy 327.826624 -258.094226) (xy 327.790556 -257.992626) (xy 327.600056 -257.992626) (xy 327.563734 -258.094226)
			(xy 327.563734 -258.145026) (xy 327.826624 -258.145026)
		)
		(stroke
			(width 0)
			(type solid)
		)
		(fill yes)
		(layer "F.Cu")
		(net "M_A_CPU0_SA_CA<1>")
	)
	(gr_poly
		(pts
			(xy 327.826624 -257.789426) (xy 327.790556 -257.687826) (xy 327.600056 -257.687826) (xy 327.563734 -257.789426)
			(xy 327.563734 -257.840226) (xy 327.826624 -257.840226)
		)
		(stroke
			(width 0)
			(type solid)
		)
		(fill yes)
		(layer "F.Cu")
		(net "M_A_CPU0_SA_CA<2>")
	)
	(gr_poly
		(pts
			(xy 327.826624 -257.484626) (xy 327.790556 -257.383026) (xy 327.600056 -257.383026) (xy 327.563734 -257.484626)
			(xy 327.563734 -257.535426) (xy 327.826624 -257.535426)
		)
		(stroke
			(width 0)
			(type solid)
		)
		(fill yes)
		(layer "F.Cu")
		(net "M_A_CPU0_SA_CA<3>")
	)
	(gr_poly
		(pts
			(xy 327.826624 -257.179826) (xy 327.790556 -257.078226) (xy 327.600056 -257.078226) (xy 327.563734 -257.179826)
			(xy 327.563734 -257.230626) (xy 327.826624 -257.230626)
		)
		(stroke
			(width 0)
			(type solid)
		)
		(fill yes)
		(layer "F.Cu")
		(net "M_A_CPU0_SA_CA<4>")
	)
	(gr_poly
		(pts
			(xy 327.826624 -256.875026) (xy 327.790556 -256.773426) (xy 327.600056 -256.773426) (xy 327.563734 -256.875026)
			(xy 327.563734 -256.925826) (xy 327.826624 -256.925826)
		)
		(stroke
			(width 0)
			(type solid)
		)
		(fill yes)
		(layer "F.Cu")
		(net "M_A_CPU0_SA_CA<5>")
	)
	(gr_poly
		(pts
			(xy 327.826624 -256.570226) (xy 327.790556 -256.468626) (xy 327.600056 -256.468626) (xy 327.563734 -256.570226)
			(xy 327.563734 -256.621026) (xy 327.826624 -256.621026)
		)
		(stroke
			(width 0)
			(type solid)
		)
		(fill yes)
		(layer "F.Cu")
		(net "M_A_CPU0_SA_CA<6>")
	)
	(gr_poly
		(pts
			(xy 327.826624 -256.265426) (xy 327.790556 -256.163826) (xy 327.600056 -256.163826) (xy 327.563734 -256.265426)
			(xy 327.563734 -256.316226) (xy 327.826624 -256.316226)
		)
		(stroke
			(width 0)
			(type solid)
		)
		(fill yes)
		(layer "F.Cu")
		(net "M_A_CPU0_SA_PAR")
	)
	(gr_poly
		(pts
			(xy 327.836022 -223.093026) (xy 327.88225 -222.99549) (xy 327.747376 -222.86087) (xy 327.650094 -222.907098)
			(xy 327.614026 -222.942912) (xy 327.799954 -223.12884)
		)
		(stroke
			(width 0)
			(type solid)
		)
		(fill yes)
		(layer "F.Cu")
		(net "M_A_CPU0_SB_DQ<22>")
	)
	(gr_poly
		(pts
			(xy 327.841864 -262.904224) (xy 327.80605 -262.86841) (xy 327.708514 -262.822182) (xy 327.573894 -262.956802)
			(xy 327.620122 -263.054084) (xy 327.655936 -263.090152)
		)
		(stroke
			(width 0)
			(type solid)
		)
		(fill yes)
		(layer "F.Cu")
		(net "M_A_CPU0_SA_CB<5>")
	)
	(gr_poly
		(pts
			(xy 327.851262 -263.757918) (xy 327.815448 -263.72185) (xy 327.717912 -263.675622) (xy 327.583292 -263.810496)
			(xy 327.62952 -263.907778) (xy 327.665334 -263.943846)
		)
		(stroke
			(width 0)
			(type solid)
		)
		(fill yes)
		(layer "F.Cu")
		(net "M_A_CPU0_SA_CB<4>")
	)
	(gr_poly
		(pts
			(xy 327.856088 -273.434556) (xy 327.820274 -273.398488) (xy 327.722738 -273.35226) (xy 327.588118 -273.487134)
			(xy 327.634346 -273.584416) (xy 327.67016 -273.620484)
		)
		(stroke
			(width 0)
			(type solid)
		)
		(fill yes)
		(layer "F.Cu")
		(net "M_A_CPU0_SA_DQ<25>")
	)
	(gr_poly
		(pts
			(xy 327.856342 -266.34059) (xy 327.820274 -266.304776) (xy 327.722992 -266.258548) (xy 327.588118 -266.393168)
			(xy 327.634346 -266.490704) (xy 327.670414 -266.526518)
		)
		(stroke
			(width 0)
			(type solid)
		)
		(fill yes)
		(layer "F.Cu")
		(net "M_A_CPU0_SA_CB<1>")
	)
	(gr_poly
		(pts
			(xy 327.858628 -231.278684) (xy 327.904856 -231.181402) (xy 327.770236 -231.046528) (xy 327.6727 -231.09301)
			(xy 327.636886 -231.128824) (xy 327.822814 -231.314752)
		)
		(stroke
			(width 0)
			(type solid)
		)
		(fill yes)
		(layer "F.Cu")
		(net "M_A_CPU0_SB_DQ<12>")
	)
	(gr_poly
		(pts
			(xy 327.865486 -274.287742) (xy 327.829418 -274.251928) (xy 327.732136 -274.2057) (xy 327.597262 -274.34032)
			(xy 327.64349 -274.437856) (xy 327.679558 -274.47367)
		)
		(stroke
			(width 0)
			(type solid)
		)
		(fill yes)
		(layer "F.Cu")
		(net "M_A_CPU0_SA_DQ<24>")
	)
	(gr_poly
		(pts
			(xy 327.865486 -267.194284) (xy 327.829672 -267.158216) (xy 327.732136 -267.111988) (xy 327.597516 -267.246608)
			(xy 327.643744 -267.344144) (xy 327.679812 -267.379958)
		)
		(stroke
			(width 0)
			(type solid)
		)
		(fill yes)
		(layer "F.Cu")
		(net "M_A_CPU0_SA_CB<0>")
	)
	(gr_poly
		(pts
			(xy 327.868026 -230.425244) (xy 327.914254 -230.327962) (xy 327.779634 -230.193088) (xy 327.682098 -230.239316)
			(xy 327.646284 -230.275384) (xy 327.832212 -230.461312)
		)
		(stroke
			(width 0)
			(type solid)
		)
		(fill yes)
		(layer "F.Cu")
		(net "M_A_CPU0_SB_DQ<13>")
	)
	(gr_poly
		(pts
			(xy 327.872852 -222.372936) (xy 327.872852 -222.182436) (xy 327.771252 -222.146114) (xy 327.720452 -222.146114)
			(xy 327.720452 -222.409258) (xy 327.771252 -222.409258)
		)
		(stroke
			(width 0)
			(type solid)
		)
		(fill yes)
		(layer "F.Cu")
		(net "M_A_CPU0_SB_DQ<21>")
	)
	(gr_poly
		(pts
			(xy 327.872852 -221.776036) (xy 327.872852 -221.585536) (xy 327.771252 -221.549214) (xy 327.720452 -221.549214)
			(xy 327.720452 -221.812358) (xy 327.771252 -221.812358)
		)
		(stroke
			(width 0)
			(type solid)
		)
		(fill yes)
		(layer "F.Cu")
		(net "M_A_CPU0_SB_DQ<21>")
	)
	(gr_poly
		(pts
			(xy 327.872852 -221.179136) (xy 327.872852 -220.988636) (xy 327.771252 -220.952314) (xy 327.720452 -220.952314)
			(xy 327.720452 -221.215458) (xy 327.771252 -221.215458)
		)
		(stroke
			(width 0)
			(type solid)
		)
		(fill yes)
		(layer "F.Cu")
		(net "M_A_CPU0_SB_DQ<21>")
	)
	(gr_poly
		(pts
			(xy 327.872852 -220.582236) (xy 327.872852 -220.391736) (xy 327.771252 -220.355414) (xy 327.720452 -220.355414)
			(xy 327.720452 -220.618558) (xy 327.771252 -220.618558)
		)
		(stroke
			(width 0)
			(type solid)
		)
		(fill yes)
		(layer "F.Cu")
		(net "M_A_CPU0_SB_DQ<21>")
	)
	(gr_poly
		(pts
			(xy 327.872852 -219.985336) (xy 327.872852 -219.794836) (xy 327.771252 -219.758514) (xy 327.720452 -219.758514)
			(xy 327.720452 -220.021658) (xy 327.771252 -220.021658)
		)
		(stroke
			(width 0)
			(type solid)
		)
		(fill yes)
		(layer "F.Cu")
		(net "M_A_CPU0_SB_DQ<21>")
	)
	(gr_poly
		(pts
			(xy 327.872852 -219.388436) (xy 327.872852 -219.197936) (xy 327.771252 -219.161614) (xy 327.720452 -219.161614)
			(xy 327.720452 -219.424758) (xy 327.771252 -219.424758)
		)
		(stroke
			(width 0)
			(type solid)
		)
		(fill yes)
		(layer "F.Cu")
		(net "M_A_CPU0_SB_DQ<21>")
	)
	(gr_poly
		(pts
			(xy 327.872852 -218.791536) (xy 327.872852 -218.601036) (xy 327.771252 -218.564714) (xy 327.720452 -218.564714)
			(xy 327.720452 -218.827858) (xy 327.771252 -218.827858)
		)
		(stroke
			(width 0)
			(type solid)
		)
		(fill yes)
		(layer "F.Cu")
		(net "M_A_CPU0_SB_DQ<21>")
	)
	(gr_poly
		(pts
			(xy 327.872852 -218.194636) (xy 327.872852 -218.004136) (xy 327.771252 -217.967814) (xy 327.720452 -217.967814)
			(xy 327.720452 -218.230958) (xy 327.771252 -218.230958)
		)
		(stroke
			(width 0)
			(type solid)
		)
		(fill yes)
		(layer "F.Cu")
		(net "M_A_CPU0_SB_DQ<21>")
	)
	(gr_poly
		(pts
			(xy 327.872852 -217.597736) (xy 327.872852 -217.407236) (xy 327.771252 -217.370914) (xy 327.720452 -217.370914)
			(xy 327.720452 -217.634058) (xy 327.771252 -217.634058)
		)
		(stroke
			(width 0)
			(type solid)
		)
		(fill yes)
		(layer "F.Cu")
		(net "M_A_CPU0_SB_DQ<21>")
	)
	(gr_poly
		(pts
			(xy 327.872852 -217.000836) (xy 327.872852 -216.810336) (xy 327.771252 -216.774014) (xy 327.720452 -216.774014)
			(xy 327.720452 -217.037158) (xy 327.771252 -217.037158)
		)
		(stroke
			(width 0)
			(type solid)
		)
		(fill yes)
		(layer "F.Cu")
		(net "M_A_CPU0_SB_DQ<21>")
	)
	(gr_poly
		(pts
			(xy 327.872852 -216.403936) (xy 327.872852 -216.213436) (xy 327.771252 -216.177114) (xy 327.720452 -216.177114)
			(xy 327.720452 -216.440258) (xy 327.771252 -216.440258)
		)
		(stroke
			(width 0)
			(type solid)
		)
		(fill yes)
		(layer "F.Cu")
		(net "M_A_CPU0_SB_DQ<21>")
	)
	(gr_poly
		(pts
			(xy 327.872852 -215.807036) (xy 327.872852 -215.616536) (xy 327.771252 -215.580214) (xy 327.720452 -215.580214)
			(xy 327.720452 -215.843358) (xy 327.771252 -215.843358)
		)
		(stroke
			(width 0)
			(type solid)
		)
		(fill yes)
		(layer "F.Cu")
		(net "M_A_CPU0_SB_DQ<21>")
	)
	(gr_poly
		(pts
			(xy 327.872852 -215.210136) (xy 327.872852 -215.019636) (xy 327.771252 -214.983314) (xy 327.720452 -214.983314)
			(xy 327.720452 -215.246458) (xy 327.771252 -215.246458)
		)
		(stroke
			(width 0)
			(type solid)
		)
		(fill yes)
		(layer "F.Cu")
		(net "M_A_CPU0_SB_DQ<21>")
	)
	(gr_poly
		(pts
			(xy 327.877932 -229.156006) (xy 327.924414 -229.05847) (xy 327.78954 -228.92385) (xy 327.692258 -228.970078)
			(xy 327.65619 -229.005892) (xy 327.842118 -229.19182)
		)
		(stroke
			(width 0)
			(type solid)
		)
		(fill yes)
		(layer "F.Cu")
		(net "M_A_CPU0_SB_DQ<16>")
	)
	(gr_poly
		(pts
			(xy 327.878948 -275.376894) (xy 327.83272 -275.279358) (xy 327.796652 -275.243544) (xy 327.610724 -275.429472)
			(xy 327.646792 -275.465286) (xy 327.744074 -275.511514)
		)
		(stroke
			(width 0)
			(type solid)
		)
		(fill yes)
		(layer "F.Cu")
		(net "M_A_CPU0_SA_DQ<23>")
	)
	(gr_poly
		(pts
			(xy 327.88733 -228.302566) (xy 327.933558 -228.20503) (xy 327.798684 -228.07041) (xy 327.701402 -228.116638)
			(xy 327.665334 -228.152452) (xy 327.851262 -228.33838)
		)
		(stroke
			(width 0)
			(type solid)
		)
		(fill yes)
		(layer "F.Cu")
		(net "M_A_CPU0_SB_DQ<17>")
	)
	(gr_poly
		(pts
			(xy 327.919334 -262.610854) (xy 327.873106 -262.513318) (xy 327.837038 -262.477504) (xy 327.65111 -262.663432)
			(xy 327.687178 -262.699246) (xy 327.784714 -262.745474)
		)
		(stroke
			(width 0)
			(type solid)
		)
		(fill yes)
		(layer "F.Cu")
		(net "M_A_CPU0_SA_CB<7>")
	)
	(gr_poly
		(pts
			(xy 327.92797 -269.478506) (xy 327.891902 -269.442692) (xy 327.79462 -269.396464) (xy 327.659746 -269.531084)
			(xy 327.705974 -269.62862) (xy 327.742042 -269.664434)
		)
		(stroke
			(width 0)
			(type solid)
		)
		(fill yes)
		(layer "F.Cu")
		(net "M_A_CPU0_SA_DQ<31>")
	)
	(gr_poly
		(pts
			(xy 327.928732 -263.464294) (xy 327.882504 -263.367012) (xy 327.84669 -263.330944) (xy 327.660762 -263.516872)
			(xy 327.696576 -263.55294) (xy 327.794112 -263.599168)
		)
		(stroke
			(width 0)
			(type solid)
		)
		(fill yes)
		(layer "F.Cu")
		(net "M_A_CPU0_SA_CB<6>")
	)
	(gr_poly
		(pts
			(xy 327.933558 -273.140932) (xy 327.88733 -273.043396) (xy 327.851262 -273.007582) (xy 327.665334 -273.19351)
			(xy 327.701402 -273.229324) (xy 327.798684 -273.275552)
		)
		(stroke
			(width 0)
			(type solid)
		)
		(fill yes)
		(layer "F.Cu")
		(net "M_A_CPU0_SA_DQ<27>")
	)
	(gr_poly
		(pts
			(xy 327.933812 -266.047474) (xy 327.887584 -265.949938) (xy 327.851516 -265.914124) (xy 327.665842 -266.099798)
			(xy 327.701656 -266.135866) (xy 327.799192 -266.182094)
		)
		(stroke
			(width 0)
			(type solid)
		)
		(fill yes)
		(layer "F.Cu")
		(net "M_A_CPU0_SA_CB<3>")
	)
	(gr_poly
		(pts
			(xy 327.937622 -270.332454) (xy 327.901808 -270.29664) (xy 327.804272 -270.250412) (xy 327.669652 -270.385032)
			(xy 327.71588 -270.482568) (xy 327.751694 -270.518382)
		)
		(stroke
			(width 0)
			(type solid)
		)
		(fill yes)
		(layer "F.Cu")
		(net "M_A_CPU0_SA_DQ<30>")
	)
	(gr_poly
		(pts
			(xy 327.942956 -273.994626) (xy 327.896728 -273.89709) (xy 327.86066 -273.861276) (xy 327.674986 -274.04695)
			(xy 327.7108 -274.083018) (xy 327.808336 -274.129246)
		)
		(stroke
			(width 0)
			(type solid)
		)
		(fill yes)
		(layer "F.Cu")
		(net "M_A_CPU0_SA_DQ<26>")
	)
	(gr_poly
		(pts
			(xy 327.94321 -266.900914) (xy 327.896982 -266.803378) (xy 327.860914 -266.767564) (xy 327.674986 -266.953492)
			(xy 327.711054 -266.989306) (xy 327.808336 -267.035534)
		)
		(stroke
			(width 0)
			(type solid)
		)
		(fill yes)
		(layer "F.Cu")
		(net "M_A_CPU0_SA_CB<2>")
	)
	(gr_poly
		(pts
			(xy 327.95083 -234.964986) (xy 327.986898 -234.929172) (xy 327.80097 -234.743244) (xy 327.764902 -234.779058)
			(xy 327.718674 -234.876594) (xy 327.853548 -235.011214)
		)
		(stroke
			(width 0)
			(type solid)
		)
		(fill yes)
		(layer "F.Cu")
		(net "M_A_CPU0_SB_DQ<8>")
	)
	(gr_poly
		(pts
			(xy 327.95718 -288.65576) (xy 327.90638 -288.65576) (xy 327.80478 -288.692082) (xy 327.80478 -288.882582)
			(xy 327.90638 -288.91865) (xy 327.95718 -288.91865)
		)
		(stroke
			(width 0)
			(type solid)
		)
		(fill yes)
		(layer "F.Cu")
		(net "M_A_CPU0_SA_DQ<19>")
	)
	(gr_poly
		(pts
			(xy 327.95718 -288.05886) (xy 327.90638 -288.05886) (xy 327.80478 -288.095182) (xy 327.80478 -288.285682)
			(xy 327.90638 -288.32175) (xy 327.95718 -288.32175)
		)
		(stroke
			(width 0)
			(type solid)
		)
		(fill yes)
		(layer "F.Cu")
		(net "M_A_CPU0_SA_DQ<19>")
	)
	(gr_poly
		(pts
			(xy 327.95718 -287.46196) (xy 327.90638 -287.46196) (xy 327.80478 -287.498282) (xy 327.80478 -287.688782)
			(xy 327.90638 -287.72485) (xy 327.95718 -287.72485)
		)
		(stroke
			(width 0)
			(type solid)
		)
		(fill yes)
		(layer "F.Cu")
		(net "M_A_CPU0_SA_DQ<19>")
	)
	(gr_poly
		(pts
			(xy 327.95718 -286.86506) (xy 327.90638 -286.86506) (xy 327.80478 -286.901382) (xy 327.80478 -287.091882)
			(xy 327.90638 -287.12795) (xy 327.95718 -287.12795)
		)
		(stroke
			(width 0)
			(type solid)
		)
		(fill yes)
		(layer "F.Cu")
		(net "M_A_CPU0_SA_DQ<19>")
	)
	(gr_poly
		(pts
			(xy 327.95718 -286.26816) (xy 327.90638 -286.26816) (xy 327.80478 -286.304482) (xy 327.80478 -286.494982)
			(xy 327.90638 -286.53105) (xy 327.95718 -286.53105)
		)
		(stroke
			(width 0)
			(type solid)
		)
		(fill yes)
		(layer "F.Cu")
		(net "M_A_CPU0_SA_DQ<19>")
	)
	(gr_poly
		(pts
			(xy 327.95718 -285.67126) (xy 327.90638 -285.67126) (xy 327.80478 -285.707582) (xy 327.80478 -285.898082)
			(xy 327.90638 -285.93415) (xy 327.95718 -285.93415)
		)
		(stroke
			(width 0)
			(type solid)
		)
		(fill yes)
		(layer "F.Cu")
		(net "M_A_CPU0_SA_DQ<19>")
	)
	(gr_poly
		(pts
			(xy 327.95718 -285.07436) (xy 327.90638 -285.07436) (xy 327.80478 -285.110682) (xy 327.80478 -285.301182)
			(xy 327.90638 -285.33725) (xy 327.95718 -285.33725)
		)
		(stroke
			(width 0)
			(type solid)
		)
		(fill yes)
		(layer "F.Cu")
		(net "M_A_CPU0_SA_DQ<19>")
	)
	(gr_poly
		(pts
			(xy 327.95718 -284.47746) (xy 327.90638 -284.47746) (xy 327.80478 -284.513782) (xy 327.80478 -284.704282)
			(xy 327.90638 -284.74035) (xy 327.95718 -284.74035)
		)
		(stroke
			(width 0)
			(type solid)
		)
		(fill yes)
		(layer "F.Cu")
		(net "M_A_CPU0_SA_DQ<19>")
	)
	(gr_poly
		(pts
			(xy 327.95718 -283.88056) (xy 327.90638 -283.88056) (xy 327.80478 -283.916882) (xy 327.80478 -284.107382)
			(xy 327.90638 -284.14345) (xy 327.95718 -284.14345)
		)
		(stroke
			(width 0)
			(type solid)
		)
		(fill yes)
		(layer "F.Cu")
		(net "M_A_CPU0_SA_DQ<19>")
	)
	(gr_poly
		(pts
			(xy 327.95718 -283.28366) (xy 327.90638 -283.28366) (xy 327.80478 -283.319982) (xy 327.80478 -283.510482)
			(xy 327.90638 -283.54655) (xy 327.95718 -283.54655)
		)
		(stroke
			(width 0)
			(type solid)
		)
		(fill yes)
		(layer "F.Cu")
		(net "M_A_CPU0_SA_DQ<19>")
	)
	(gr_poly
		(pts
			(xy 327.95718 -282.68676) (xy 327.90638 -282.68676) (xy 327.80478 -282.723082) (xy 327.80478 -282.913582)
			(xy 327.90638 -282.94965) (xy 327.95718 -282.94965)
		)
		(stroke
			(width 0)
			(type solid)
		)
		(fill yes)
		(layer "F.Cu")
		(net "M_A_CPU0_SA_DQ<19>")
	)
	(gr_poly
		(pts
			(xy 327.95718 -282.08986) (xy 327.90638 -282.08986) (xy 327.80478 -282.126182) (xy 327.80478 -282.316682)
			(xy 327.90638 -282.35275) (xy 327.95718 -282.35275)
		)
		(stroke
			(width 0)
			(type solid)
		)
		(fill yes)
		(layer "F.Cu")
		(net "M_A_CPU0_SA_DQ<19>")
	)
	(gr_poly
		(pts
			(xy 327.959974 -234.111546) (xy 327.996042 -234.075732) (xy 327.810114 -233.889804) (xy 327.7743 -233.925618)
			(xy 327.728072 -234.023154) (xy 327.862692 -234.157774)
		)
		(stroke
			(width 0)
			(type solid)
		)
		(fill yes)
		(layer "F.Cu")
		(net "M_A_CPU0_SB_DQ<9>")
	)
	(gr_poly
		(pts
			(xy 327.975214 -223.375728) (xy 328.011028 -223.339914) (xy 327.8251 -223.153986) (xy 327.789286 -223.190054)
			(xy 327.743058 -223.287336) (xy 327.877678 -223.42221)
		)
		(stroke
			(width 0)
			(type solid)
		)
		(fill yes)
		(layer "F.Cu")
		(net "M_A_CPU0_SB_DQ<22>")
	)
	(gr_poly
		(pts
			(xy 327.99782 -231.56164) (xy 328.033888 -231.525826) (xy 327.84796 -231.339898) (xy 327.811892 -231.375712)
			(xy 327.765664 -231.473248) (xy 327.900538 -231.607868)
		)
		(stroke
			(width 0)
			(type solid)
		)
		(fill yes)
		(layer "F.Cu")
		(net "M_A_CPU0_SB_DQ<12>")
	)
	(gr_poly
		(pts
			(xy 328.007218 -230.7082) (xy 328.043032 -230.672132) (xy 327.857358 -230.486458) (xy 327.82129 -230.522272)
			(xy 327.775062 -230.619808) (xy 327.909682 -230.754428)
		)
		(stroke
			(width 0)
			(type solid)
		)
		(fill yes)
		(layer "F.Cu")
		(net "M_A_CPU0_SB_DQ<13>")
	)
	(gr_poly
		(pts
			(xy 328.007726 -275.03247) (xy 327.971912 -274.996656) (xy 327.874376 -274.950428) (xy 327.739756 -275.085048)
			(xy 327.785984 -275.182584) (xy 327.821798 -275.218398)
		)
		(stroke
			(width 0)
			(type solid)
		)
		(fill yes)
		(layer "F.Cu")
		(net "M_A_CPU0_SA_DQ<23>")
	)
	(gr_poly
		(pts
			(xy 328.014838 -270.03883) (xy 327.96861 -269.941294) (xy 327.932542 -269.90548) (xy 327.746614 -270.091408)
			(xy 327.782682 -270.127222) (xy 327.879964 -270.17345)
		)
		(stroke
			(width 0)
			(type solid)
		)
		(fill yes)
		(layer "F.Cu")
		(net "M_A_CPU0_SA_DQ<29>")
	)
	(gr_poly
		(pts
			(xy 328.017124 -275.886164) (xy 327.981056 -275.850096) (xy 327.883774 -275.803868) (xy 327.7489 -275.938488)
			(xy 327.795128 -276.036024) (xy 327.831196 -276.071838)
		)
		(stroke
			(width 0)
			(type solid)
		)
		(fill yes)
		(layer "F.Cu")
		(net "M_A_CPU0_SA_DQ<22>")
	)
	(gr_poly
		(pts
			(xy 328.017124 -229.438708) (xy 328.053192 -229.402894) (xy 327.867264 -229.216966) (xy 327.83145 -229.25278)
			(xy 327.785222 -229.350316) (xy 327.919842 -229.484936)
		)
		(stroke
			(width 0)
			(type solid)
		)
		(fill yes)
		(layer "F.Cu")
		(net "M_A_CPU0_SB_DQ<16>")
	)
	(gr_poly
		(pts
			(xy 328.02449 -270.892524) (xy 327.978008 -270.794988) (xy 327.942194 -270.759174) (xy 327.756266 -270.945102)
			(xy 327.792334 -270.980916) (xy 327.889616 -271.027144)
		)
		(stroke
			(width 0)
			(type solid)
		)
		(fill yes)
		(layer "F.Cu")
		(net "M_A_CPU0_SA_DQ<28>")
	)
	(gr_poly
		(pts
			(xy 328.025252 -221.847918) (xy 327.974452 -221.847918) (xy 327.872852 -221.883986) (xy 327.872852 -222.074486)
			(xy 327.974452 -222.110554) (xy 328.025252 -222.110554)
		)
		(stroke
			(width 0)
			(type solid)
		)
		(fill yes)
		(layer "F.Cu")
		(net "M_A_CPU0_SB_DQ<23>")
	)
	(gr_poly
		(pts
			(xy 328.025252 -221.251018) (xy 327.974452 -221.251018) (xy 327.872852 -221.287086) (xy 327.872852 -221.477586)
			(xy 327.974452 -221.513654) (xy 328.025252 -221.513654)
		)
		(stroke
			(width 0)
			(type solid)
		)
		(fill yes)
		(layer "F.Cu")
		(net "M_A_CPU0_SB_DQ<23>")
	)
	(gr_poly
		(pts
			(xy 328.025252 -220.654118) (xy 327.974452 -220.654118) (xy 327.872852 -220.690186) (xy 327.872852 -220.880686)
			(xy 327.974452 -220.916754) (xy 328.025252 -220.916754)
		)
		(stroke
			(width 0)
			(type solid)
		)
		(fill yes)
		(layer "F.Cu")
		(net "M_A_CPU0_SB_DQ<23>")
	)
	(gr_poly
		(pts
			(xy 328.025252 -220.057218) (xy 327.974452 -220.057218) (xy 327.872852 -220.093286) (xy 327.872852 -220.283786)
			(xy 327.974452 -220.319854) (xy 328.025252 -220.319854)
		)
		(stroke
			(width 0)
			(type solid)
		)
		(fill yes)
		(layer "F.Cu")
		(net "M_A_CPU0_SB_DQ<23>")
	)
	(gr_poly
		(pts
			(xy 328.025252 -219.460318) (xy 327.974452 -219.460318) (xy 327.872852 -219.496386) (xy 327.872852 -219.686886)
			(xy 327.974452 -219.722954) (xy 328.025252 -219.722954)
		)
		(stroke
			(width 0)
			(type solid)
		)
		(fill yes)
		(layer "F.Cu")
		(net "M_A_CPU0_SB_DQ<23>")
	)
	(gr_poly
		(pts
			(xy 328.025252 -218.863418) (xy 327.974452 -218.863418) (xy 327.872852 -218.899486) (xy 327.872852 -219.089986)
			(xy 327.974452 -219.126054) (xy 328.025252 -219.126054)
		)
		(stroke
			(width 0)
			(type solid)
		)
		(fill yes)
		(layer "F.Cu")
		(net "M_A_CPU0_SB_DQ<23>")
	)
	(gr_poly
		(pts
			(xy 328.025252 -218.266518) (xy 327.974452 -218.266518) (xy 327.872852 -218.302586) (xy 327.872852 -218.493086)
			(xy 327.974452 -218.529154) (xy 328.025252 -218.529154)
		)
		(stroke
			(width 0)
			(type solid)
		)
		(fill yes)
		(layer "F.Cu")
		(net "M_A_CPU0_SB_DQ<23>")
	)
	(gr_poly
		(pts
			(xy 328.025252 -217.669618) (xy 327.974452 -217.669618) (xy 327.872852 -217.705686) (xy 327.872852 -217.896186)
			(xy 327.974452 -217.932254) (xy 328.025252 -217.932254)
		)
		(stroke
			(width 0)
			(type solid)
		)
		(fill yes)
		(layer "F.Cu")
		(net "M_A_CPU0_SB_DQ<23>")
	)
	(gr_poly
		(pts
			(xy 328.025252 -217.072718) (xy 327.974452 -217.072718) (xy 327.872852 -217.108786) (xy 327.872852 -217.299286)
			(xy 327.974452 -217.335354) (xy 328.025252 -217.335354)
		)
		(stroke
			(width 0)
			(type solid)
		)
		(fill yes)
		(layer "F.Cu")
		(net "M_A_CPU0_SB_DQ<23>")
	)
	(gr_poly
		(pts
			(xy 328.025252 -216.475818) (xy 327.974452 -216.475818) (xy 327.872852 -216.511886) (xy 327.872852 -216.702386)
			(xy 327.974452 -216.738454) (xy 328.025252 -216.738454)
		)
		(stroke
			(width 0)
			(type solid)
		)
		(fill yes)
		(layer "F.Cu")
		(net "M_A_CPU0_SB_DQ<23>")
	)
	(gr_poly
		(pts
			(xy 328.025252 -215.878918) (xy 327.974452 -215.878918) (xy 327.872852 -215.914986) (xy 327.872852 -216.105486)
			(xy 327.974452 -216.141554) (xy 328.025252 -216.141554)
		)
		(stroke
			(width 0)
			(type solid)
		)
		(fill yes)
		(layer "F.Cu")
		(net "M_A_CPU0_SB_DQ<23>")
	)
	(gr_poly
		(pts
			(xy 328.025252 -215.282018) (xy 327.974452 -215.282018) (xy 327.872852 -215.318086) (xy 327.872852 -215.508586)
			(xy 327.974452 -215.544654) (xy 328.025252 -215.544654)
		)
		(stroke
			(width 0)
			(type solid)
		)
		(fill yes)
		(layer "F.Cu")
		(net "M_A_CPU0_SB_DQ<23>")
	)
	(gr_poly
		(pts
			(xy 328.025252 -214.685118) (xy 327.974452 -214.685118) (xy 327.872852 -214.721186) (xy 327.872852 -214.911686)
			(xy 327.974452 -214.947754) (xy 328.025252 -214.947754)
		)
		(stroke
			(width 0)
			(type solid)
		)
		(fill yes)
		(layer "F.Cu")
		(net "M_A_CPU0_SB_DQ<23>")
	)
	(gr_poly
		(pts
			(xy 328.026522 -228.585522) (xy 328.062336 -228.549454) (xy 327.876408 -228.363526) (xy 327.840594 -228.399594)
			(xy 327.794366 -228.496876) (xy 327.928986 -228.63175)
		)
		(stroke
			(width 0)
			(type solid)
		)
		(fill yes)
		(layer "F.Cu")
		(net "M_A_CPU0_SB_DQ<17>")
	)
	(gr_poly
		(pts
			(xy 328.027284 -234.466384) (xy 328.073512 -234.369102) (xy 327.938892 -234.234228) (xy 327.841356 -234.280456)
			(xy 327.805542 -234.316524) (xy 327.99147 -234.502452)
		)
		(stroke
			(width 0)
			(type solid)
		)
		(fill yes)
		(layer "F.Cu")
		(net "M_A_CPU0_SB_DQ<10>")
	)
	(gr_poly
		(pts
			(xy 328.036428 -233.613198) (xy 328.08291 -233.515662) (xy 327.948036 -233.381042) (xy 327.850754 -233.42727)
			(xy 327.814686 -233.463084) (xy 328.000614 -233.649012)
		)
		(stroke
			(width 0)
			(type solid)
		)
		(fill yes)
		(layer "F.Cu")
		(net "M_A_CPU0_SB_DQ<11>")
	)
	(gr_poly
		(pts
			(xy 328.04227 -223.73082) (xy 328.088498 -223.633284) (xy 327.953878 -223.498664) (xy 327.856342 -223.544892)
			(xy 327.820528 -223.580706) (xy 328.006456 -223.766634)
		)
		(stroke
			(width 0)
			(type solid)
		)
		(fill yes)
		(layer "F.Cu")
		(net "M_A_CPU0_SB_DQ<20>")
	)
	(gr_poly
		(pts
			(xy 328.048112 -262.26643) (xy 328.012298 -262.230362) (xy 327.914762 -262.184134) (xy 327.780142 -262.319008)
			(xy 327.82637 -262.41629) (xy 327.862184 -262.452358)
		)
		(stroke
			(width 0)
			(type solid)
		)
		(fill yes)
		(layer "F.Cu")
		(net "M_A_CPU0_SA_CB<7>")
	)
	(gr_poly
		(pts
			(xy 328.051668 -222.87738) (xy 328.097896 -222.779844) (xy 327.963022 -222.645224) (xy 327.86574 -222.691452)
			(xy 327.829672 -222.727266) (xy 328.0156 -222.913194)
		)
		(stroke
			(width 0)
			(type solid)
		)
		(fill yes)
		(layer "F.Cu")
		(net "M_A_CPU0_SB_DQ<21>")
	)
	(gr_poly
		(pts
			(xy 328.05751 -263.120124) (xy 328.021696 -263.084056) (xy 327.92416 -263.037828) (xy 327.78954 -263.172448)
			(xy 327.835768 -263.269984) (xy 327.871836 -263.305798)
		)
		(stroke
			(width 0)
			(type solid)
		)
		(fill yes)
		(layer "F.Cu")
		(net "M_A_CPU0_SA_CB<6>")
	)
	(gr_poly
		(pts
			(xy 328.062336 -272.796508) (xy 328.026522 -272.760694) (xy 327.928986 -272.714212) (xy 327.794366 -272.849086)
			(xy 327.840594 -272.946368) (xy 327.876408 -272.982436)
		)
		(stroke
			(width 0)
			(type solid)
		)
		(fill yes)
		(layer "F.Cu")
		(net "M_A_CPU0_SA_DQ<27>")
	)
	(gr_poly
		(pts
			(xy 328.06259 -265.70305) (xy 328.026776 -265.666982) (xy 327.92924 -265.620754) (xy 327.79462 -265.755374)
			(xy 327.840848 -265.85291) (xy 327.876662 -265.888978)
		)
		(stroke
			(width 0)
			(type solid)
		)
		(fill yes)
		(layer "F.Cu")
		(net "M_A_CPU0_SA_CB<3>")
	)
	(gr_poly
		(pts
			(xy 328.071734 -273.650202) (xy 328.03592 -273.614134) (xy 327.938384 -273.567906) (xy 327.803764 -273.70278)
			(xy 327.849992 -273.800062) (xy 327.885806 -273.83613)
		)
		(stroke
			(width 0)
			(type solid)
		)
		(fill yes)
		(layer "F.Cu")
		(net "M_A_CPU0_SA_DQ<26>")
	)
	(gr_poly
		(pts
			(xy 328.071988 -266.55649) (xy 328.036174 -266.520422) (xy 327.938638 -266.474194) (xy 327.804018 -266.609068)
			(xy 327.850246 -266.70635) (xy 327.88606 -266.742418)
		)
		(stroke
			(width 0)
			(type solid)
		)
		(fill yes)
		(layer "F.Cu")
		(net "M_A_CPU0_SA_CB<2>")
	)
	(gr_poly
		(pts
			(xy 328.074528 -231.063038) (xy 328.120756 -230.965502) (xy 327.985882 -230.830882) (xy 327.8886 -230.87711)
			(xy 327.852532 -230.912924) (xy 328.03846 -231.098852)
		)
		(stroke
			(width 0)
			(type solid)
		)
		(fill yes)
		(layer "F.Cu")
		(net "M_A_CPU0_SB_DQ<14>")
	)
	(gr_poly
		(pts
			(xy 328.083672 -230.209598) (xy 328.1299 -230.112316) (xy 327.99528 -229.977442) (xy 327.897744 -230.02367)
			(xy 327.86193 -230.059738) (xy 328.047858 -230.245666)
		)
		(stroke
			(width 0)
			(type solid)
		)
		(fill yes)
		(layer "F.Cu")
		(net "M_A_CPU0_SB_DQ<15>")
	)
	(gr_poly
		(pts
			(xy 328.092308 -249.270266) (xy 328.05624 -249.168666) (xy 327.86574 -249.168666) (xy 327.829418 -249.270266)
			(xy 327.829418 -249.321066) (xy 328.092308 -249.321066)
		)
		(stroke
			(width 0)
			(type solid)
		)
		(fill yes)
		(layer "F.Cu")
		(net "M_A_CPU0_SB_CA<0>")
	)
	(gr_poly
		(pts
			(xy 328.092308 -248.965212) (xy 328.05624 -248.863612) (xy 327.86574 -248.863612) (xy 327.829418 -248.965212)
			(xy 327.829418 -249.016012) (xy 328.092308 -249.016012)
		)
		(stroke
			(width 0)
			(type solid)
		)
		(fill yes)
		(layer "F.Cu")
		(net "M_A_CPU0_SB_CA<1>")
	)
	(gr_poly
		(pts
			(xy 328.092308 -248.660412) (xy 328.05624 -248.558812) (xy 327.86574 -248.558812) (xy 327.829418 -248.660412)
			(xy 327.829418 -248.711212) (xy 328.092308 -248.711212)
		)
		(stroke
			(width 0)
			(type solid)
		)
		(fill yes)
		(layer "F.Cu")
		(net "M_A_CPU0_SB_CA<2>")
	)
	(gr_poly
		(pts
			(xy 328.092308 -248.355612) (xy 328.05624 -248.254012) (xy 327.86574 -248.254012) (xy 327.829418 -248.355612)
			(xy 327.829418 -248.406412) (xy 328.092308 -248.406412)
		)
		(stroke
			(width 0)
			(type solid)
		)
		(fill yes)
		(layer "F.Cu")
		(net "M_A_CPU0_SB_CA<3>")
	)
	(gr_poly
		(pts
			(xy 328.092308 -248.050812) (xy 328.05624 -247.949212) (xy 327.86574 -247.949212) (xy 327.829418 -248.050812)
			(xy 327.829418 -248.101612) (xy 328.092308 -248.101612)
		)
		(stroke
			(width 0)
			(type solid)
		)
		(fill yes)
		(layer "F.Cu")
		(net "M_A_CPU0_SB_CA<4>")
	)
	(gr_poly
		(pts
			(xy 328.092308 -247.746012) (xy 328.05624 -247.644412) (xy 327.86574 -247.644412) (xy 327.829418 -247.746012)
			(xy 327.829418 -247.796812) (xy 328.092308 -247.796812)
		)
		(stroke
			(width 0)
			(type solid)
		)
		(fill yes)
		(layer "F.Cu")
		(net "M_A_CPU0_SB_CA<5>")
	)
	(gr_poly
		(pts
			(xy 328.092308 -247.441212) (xy 328.05624 -247.339612) (xy 327.86574 -247.339612) (xy 327.829418 -247.441212)
			(xy 327.829418 -247.492012) (xy 328.092308 -247.492012)
		)
		(stroke
			(width 0)
			(type solid)
		)
		(fill yes)
		(layer "F.Cu")
		(net "M_A_CPU0_SB_CA<6>")
	)
	(gr_poly
		(pts
			(xy 328.092308 -247.136412) (xy 328.05624 -247.034812) (xy 327.86574 -247.034812) (xy 327.829418 -247.136412)
			(xy 327.829418 -247.187212) (xy 328.092308 -247.187212)
		)
		(stroke
			(width 0)
			(type solid)
		)
		(fill yes)
		(layer "F.Cu")
		(net "M_A_CPU0_SB_PAR")
	)
	(gr_poly
		(pts
			(xy 328.092308 -246.831612) (xy 328.05624 -246.730012) (xy 327.86574 -246.730012) (xy 327.829418 -246.831612)
			(xy 327.829418 -246.882412) (xy 328.092308 -246.882412)
		)
		(stroke
			(width 0)
			(type solid)
		)
		(fill yes)
		(layer "F.Cu")
		(net "M_A_CPU0_SB_CS_N<2>")
	)
	(gr_poly
		(pts
			(xy 328.092308 -246.526812) (xy 328.05624 -246.425212) (xy 327.86574 -246.425212) (xy 327.829418 -246.526812)
			(xy 327.829418 -246.577612) (xy 328.092308 -246.577612)
		)
		(stroke
			(width 0)
			(type solid)
		)
		(fill yes)
		(layer "F.Cu")
		(net "M_A_CPU0_SB_CS_N<0>")
	)
	(gr_poly
		(pts
			(xy 328.092308 -246.222012) (xy 328.05624 -246.120412) (xy 327.86574 -246.120412) (xy 327.829418 -246.222012)
			(xy 327.829418 -246.272812) (xy 328.092308 -246.272812)
		)
		(stroke
			(width 0)
			(type solid)
		)
		(fill yes)
		(layer "F.Cu")
		(net "M_A_CPU0_SB_CS_N<3>")
	)
	(gr_poly
		(pts
			(xy 328.092308 -245.917212) (xy 328.05624 -245.815612) (xy 327.86574 -245.815612) (xy 327.829418 -245.917212)
			(xy 327.829418 -245.968012) (xy 328.092308 -245.968012)
		)
		(stroke
			(width 0)
			(type solid)
		)
		(fill yes)
		(layer "F.Cu")
		(net "M_A_CPU0_SB_CS_N<1>")
	)
	(gr_poly
		(pts
			(xy 328.093578 -228.94036) (xy 328.14006 -228.842824) (xy 328.005186 -228.708204) (xy 327.907904 -228.754432)
			(xy 327.871836 -228.790246) (xy 328.057764 -228.976174)
		)
		(stroke
			(width 0)
			(type solid)
		)
		(fill yes)
		(layer "F.Cu")
		(net "M_A_CPU0_SB_DQ<18>")
	)
	(gr_poly
		(pts
			(xy 328.094594 -275.59254) (xy 328.048366 -275.495258) (xy 328.012298 -275.45919) (xy 327.82637 -275.645118)
			(xy 327.862438 -275.680932) (xy 327.95972 -275.727414)
		)
		(stroke
			(width 0)
			(type solid)
		)
		(fill yes)
		(layer "F.Cu")
		(net "M_A_CPU0_SA_DQ<21>")
	)
	(gr_poly
		(pts
			(xy 328.102976 -228.08692) (xy 328.149204 -227.989384) (xy 328.01433 -227.854764) (xy 327.917048 -227.900992)
			(xy 327.88098 -227.936806) (xy 328.066908 -228.122734)
		)
		(stroke
			(width 0)
			(type solid)
		)
		(fill yes)
		(layer "F.Cu")
		(net "M_A_CPU0_SB_DQ<19>")
	)
	(gr_poly
		(pts
			(xy 328.10958 -288.584132) (xy 328.10958 -288.393632) (xy 328.00798 -288.35731) (xy 327.95718 -288.35731)
			(xy 327.95718 -288.6202) (xy 328.00798 -288.6202)
		)
		(stroke
			(width 0)
			(type solid)
		)
		(fill yes)
		(layer "F.Cu")
		(net "M_A_CPU0_SA_DQ<19>")
	)
	(gr_poly
		(pts
			(xy 328.10958 -287.987232) (xy 328.10958 -287.796732) (xy 328.00798 -287.76041) (xy 327.95718 -287.76041)
			(xy 327.95718 -288.0233) (xy 328.00798 -288.0233)
		)
		(stroke
			(width 0)
			(type solid)
		)
		(fill yes)
		(layer "F.Cu")
		(net "M_A_CPU0_SA_DQ<19>")
	)
	(gr_poly
		(pts
			(xy 328.10958 -287.390332) (xy 328.10958 -287.199832) (xy 328.00798 -287.16351) (xy 327.95718 -287.16351)
			(xy 327.95718 -287.4264) (xy 328.00798 -287.4264)
		)
		(stroke
			(width 0)
			(type solid)
		)
		(fill yes)
		(layer "F.Cu")
		(net "M_A_CPU0_SA_DQ<19>")
	)
	(gr_poly
		(pts
			(xy 328.10958 -286.793432) (xy 328.10958 -286.602932) (xy 328.00798 -286.56661) (xy 327.95718 -286.56661)
			(xy 327.95718 -286.8295) (xy 328.00798 -286.8295)
		)
		(stroke
			(width 0)
			(type solid)
		)
		(fill yes)
		(layer "F.Cu")
		(net "M_A_CPU0_SA_DQ<19>")
	)
	(gr_poly
		(pts
			(xy 328.10958 -286.196532) (xy 328.10958 -286.006032) (xy 328.00798 -285.96971) (xy 327.95718 -285.96971)
			(xy 327.95718 -286.2326) (xy 328.00798 -286.2326)
		)
		(stroke
			(width 0)
			(type solid)
		)
		(fill yes)
		(layer "F.Cu")
		(net "M_A_CPU0_SA_DQ<19>")
	)
	(gr_poly
		(pts
			(xy 328.10958 -285.599632) (xy 328.10958 -285.409132) (xy 328.00798 -285.37281) (xy 327.95718 -285.37281)
			(xy 327.95718 -285.6357) (xy 328.00798 -285.6357)
		)
		(stroke
			(width 0)
			(type solid)
		)
		(fill yes)
		(layer "F.Cu")
		(net "M_A_CPU0_SA_DQ<19>")
	)
	(gr_poly
		(pts
			(xy 328.10958 -285.002732) (xy 328.10958 -284.812232) (xy 328.00798 -284.77591) (xy 327.95718 -284.77591)
			(xy 327.95718 -285.0388) (xy 328.00798 -285.0388)
		)
		(stroke
			(width 0)
			(type solid)
		)
		(fill yes)
		(layer "F.Cu")
		(net "M_A_CPU0_SA_DQ<19>")
	)
	(gr_poly
		(pts
			(xy 328.10958 -284.405832) (xy 328.10958 -284.215332) (xy 328.00798 -284.17901) (xy 327.95718 -284.17901)
			(xy 327.95718 -284.4419) (xy 328.00798 -284.4419)
		)
		(stroke
			(width 0)
			(type solid)
		)
		(fill yes)
		(layer "F.Cu")
		(net "M_A_CPU0_SA_DQ<19>")
	)
	(gr_poly
		(pts
			(xy 328.10958 -283.808932) (xy 328.10958 -283.618432) (xy 328.00798 -283.58211) (xy 327.95718 -283.58211)
			(xy 327.95718 -283.845) (xy 328.00798 -283.845)
		)
		(stroke
			(width 0)
			(type solid)
		)
		(fill yes)
		(layer "F.Cu")
		(net "M_A_CPU0_SA_DQ<19>")
	)
	(gr_poly
		(pts
			(xy 328.10958 -283.212032) (xy 328.10958 -283.021532) (xy 328.00798 -282.98521) (xy 327.95718 -282.98521)
			(xy 327.95718 -283.2481) (xy 328.00798 -283.2481)
		)
		(stroke
			(width 0)
			(type solid)
		)
		(fill yes)
		(layer "F.Cu")
		(net "M_A_CPU0_SA_DQ<19>")
	)
	(gr_poly
		(pts
			(xy 328.10958 -282.615132) (xy 328.10958 -282.424632) (xy 328.00798 -282.38831) (xy 327.95718 -282.38831)
			(xy 327.95718 -282.6512) (xy 328.00798 -282.6512)
		)
		(stroke
			(width 0)
			(type solid)
		)
		(fill yes)
		(layer "F.Cu")
		(net "M_A_CPU0_SA_DQ<19>")
	)
	(gr_poly
		(pts
			(xy 328.125074 -259.110226) (xy 328.125074 -259.059426) (xy 327.862184 -259.059426) (xy 327.862184 -259.110226)
			(xy 327.898252 -259.211826) (xy 328.088752 -259.211826)
		)
		(stroke
			(width 0)
			(type solid)
		)
		(fill yes)
		(layer "F.Cu")
		(net "M_A_CPU0_SA_CS_N<3>")
	)
	(gr_poly
		(pts
			(xy 328.125074 -258.805426) (xy 328.125074 -258.754626) (xy 327.862184 -258.754626) (xy 327.862184 -258.805426)
			(xy 327.898252 -258.907026) (xy 328.088752 -258.907026)
		)
		(stroke
			(width 0)
			(type solid)
		)
		(fill yes)
		(layer "F.Cu")
		(net "M_A_CPU0_SA_CS_N<1>")
	)
	(gr_poly
		(pts
			(xy 328.125074 -258.500626) (xy 328.125074 -258.449826) (xy 327.862184 -258.449826) (xy 327.862184 -258.500626)
			(xy 327.898252 -258.602226) (xy 328.088752 -258.602226)
		)
		(stroke
			(width 0)
			(type solid)
		)
		(fill yes)
		(layer "F.Cu")
		(net "M_A_CPU0_SA_CA<0>")
	)
	(gr_poly
		(pts
			(xy 328.125074 -258.195826) (xy 328.125074 -258.145026) (xy 327.862184 -258.145026) (xy 327.862184 -258.195826)
			(xy 327.898252 -258.297426) (xy 328.088752 -258.297426)
		)
		(stroke
			(width 0)
			(type solid)
		)
		(fill yes)
		(layer "F.Cu")
		(net "M_A_CPU0_SA_CA<1>")
	)
	(gr_poly
		(pts
			(xy 328.125074 -257.891026) (xy 328.125074 -257.840226) (xy 327.862184 -257.840226) (xy 327.862184 -257.891026)
			(xy 327.898252 -257.992626) (xy 328.088752 -257.992626)
		)
		(stroke
			(width 0)
			(type solid)
		)
		(fill yes)
		(layer "F.Cu")
		(net "M_A_CPU0_SA_CA<2>")
	)
	(gr_poly
		(pts
			(xy 328.125074 -257.586226) (xy 328.125074 -257.535426) (xy 327.862184 -257.535426) (xy 327.862184 -257.586226)
			(xy 327.898252 -257.687826) (xy 328.088752 -257.687826)
		)
		(stroke
			(width 0)
			(type solid)
		)
		(fill yes)
		(layer "F.Cu")
		(net "M_A_CPU0_SA_CA<3>")
	)
	(gr_poly
		(pts
			(xy 328.125074 -257.281426) (xy 328.125074 -257.230626) (xy 327.862184 -257.230626) (xy 327.862184 -257.281426)
			(xy 327.898252 -257.383026) (xy 328.088752 -257.383026)
		)
		(stroke
			(width 0)
			(type solid)
		)
		(fill yes)
		(layer "F.Cu")
		(net "M_A_CPU0_SA_CA<4>")
	)
	(gr_poly
		(pts
			(xy 328.125074 -256.976626) (xy 328.125074 -256.925826) (xy 327.862184 -256.925826) (xy 327.862184 -256.976626)
			(xy 327.898252 -257.078226) (xy 328.088752 -257.078226)
		)
		(stroke
			(width 0)
			(type solid)
		)
		(fill yes)
		(layer "F.Cu")
		(net "M_A_CPU0_SA_CA<5>")
	)
	(gr_poly
		(pts
			(xy 328.125074 -256.671826) (xy 328.125074 -256.621026) (xy 327.862184 -256.621026) (xy 327.862184 -256.671826)
			(xy 327.898252 -256.773426) (xy 328.088752 -256.773426)
		)
		(stroke
			(width 0)
			(type solid)
		)
		(fill yes)
		(layer "F.Cu")
		(net "M_A_CPU0_SA_CA<6>")
	)
	(gr_poly
		(pts
			(xy 328.125074 -256.367026) (xy 328.125074 -256.316226) (xy 327.862184 -256.316226) (xy 327.862184 -256.367026)
			(xy 327.898252 -256.468626) (xy 328.088752 -256.468626)
		)
		(stroke
			(width 0)
			(type solid)
		)
		(fill yes)
		(layer "F.Cu")
		(net "M_A_CPU0_SA_PAR")
	)
	(gr_poly
		(pts
			(xy 328.13498 -262.8265) (xy 328.088752 -262.729218) (xy 328.052938 -262.69315) (xy 327.86701 -262.879078)
			(xy 327.902824 -262.914892) (xy 328.00036 -262.961374)
		)
		(stroke
			(width 0)
			(type solid)
		)
		(fill yes)
		(layer "F.Cu")
		(net "M_A_CPU0_SA_CB<5>")
	)
	(gr_poly
		(pts
			(xy 328.143616 -269.694406) (xy 328.107802 -269.658338) (xy 328.010266 -269.61211) (xy 327.875646 -269.746984)
			(xy 327.921874 -269.844266) (xy 327.957688 -269.880334)
		)
		(stroke
			(width 0)
			(type solid)
		)
		(fill yes)
		(layer "F.Cu")
		(net "M_A_CPU0_SA_DQ<29>")
	)
	(gr_poly
		(pts
			(xy 328.144632 -263.680194) (xy 328.098404 -263.582658) (xy 328.062336 -263.546844) (xy 327.876408 -263.732772)
			(xy 327.912476 -263.768586) (xy 328.009758 -263.814814)
		)
		(stroke
			(width 0)
			(type solid)
		)
		(fill yes)
		(layer "F.Cu")
		(net "M_A_CPU0_SA_CB<4>")
	)
	(gr_poly
		(pts
			(xy 328.149458 -273.356832) (xy 328.10323 -273.259296) (xy 328.067162 -273.223482) (xy 327.881234 -273.40941)
			(xy 327.917302 -273.445224) (xy 328.014584 -273.491452)
		)
		(stroke
			(width 0)
			(type solid)
		)
		(fill yes)
		(layer "F.Cu")
		(net "M_A_CPU0_SA_DQ<25>")
	)
	(gr_poly
		(pts
			(xy 328.149458 -266.26312) (xy 328.10323 -266.165584) (xy 328.067162 -266.12977) (xy 327.881488 -266.315444)
			(xy 327.917302 -266.351512) (xy 328.014838 -266.39774)
		)
		(stroke
			(width 0)
			(type solid)
		)
		(fill yes)
		(layer "F.Cu")
		(net "M_A_CPU0_SA_CB<1>")
	)
	(gr_poly
		(pts
			(xy 328.153268 -270.5481) (xy 328.117454 -270.512286) (xy 328.019918 -270.466058) (xy 327.885298 -270.600678)
			(xy 327.931526 -270.698214) (xy 327.96734 -270.734028)
		)
		(stroke
			(width 0)
			(type solid)
		)
		(fill yes)
		(layer "F.Cu")
		(net "M_A_CPU0_SA_DQ<28>")
	)
	(gr_poly
		(pts
			(xy 328.158602 -274.210272) (xy 328.112374 -274.112736) (xy 328.076306 -274.076922) (xy 327.890632 -274.262596)
			(xy 327.926446 -274.298664) (xy 328.023982 -274.344892)
		)
		(stroke
			(width 0)
			(type solid)
		)
		(fill yes)
		(layer "F.Cu")
		(net "M_A_CPU0_SA_DQ<24>")
	)
	(gr_poly
		(pts
			(xy 328.158856 -267.11656) (xy 328.112628 -267.019024) (xy 328.07656 -266.98321) (xy 327.890632 -267.169138)
			(xy 327.9267 -267.204952) (xy 328.023982 -267.25118)
		)
		(stroke
			(width 0)
			(type solid)
		)
		(fill yes)
		(layer "F.Cu")
		(net "M_A_CPU0_SA_CB<0>")
	)
	(gr_poly
		(pts
			(xy 328.16419 -280.656792) (xy 328.114406 -280.646886) (xy 328.007726 -280.66238) (xy 327.970388 -280.849324)
			(xy 328.063098 -280.904696) (xy 328.112882 -280.914602)
		)
		(stroke
			(width 0)
			(type solid)
		)
		(fill yes)
		(layer "F.Cu")
		(net "M_A_CPU0_SA_DQ<19>")
	)
	(gr_poly
		(pts
			(xy 328.166476 -234.74934) (xy 328.202544 -234.713526) (xy 328.016616 -234.527598) (xy 327.980548 -234.563412)
			(xy 327.93432 -234.660948) (xy 328.069194 -234.795568)
		)
		(stroke
			(width 0)
			(type solid)
		)
		(fill yes)
		(layer "F.Cu")
		(net "M_A_CPU0_SB_DQ<10>")
	)
	(gr_poly
		(pts
			(xy 328.17562 -233.8959) (xy 328.211688 -233.860086) (xy 328.02576 -233.674158) (xy 327.989946 -233.709972)
			(xy 327.943718 -233.807508) (xy 328.078338 -233.942128)
		)
		(stroke
			(width 0)
			(type solid)
		)
		(fill yes)
		(layer "F.Cu")
		(net "M_A_CPU0_SB_DQ<11>")
	)
	(gr_poly
		(pts
			(xy 328.177652 -221.776036) (xy 328.177652 -221.585536) (xy 328.076052 -221.549214) (xy 328.025252 -221.549214)
			(xy 328.025252 -221.812358) (xy 328.076052 -221.812358)
		)
		(stroke
			(width 0)
			(type solid)
		)
		(fill yes)
		(layer "F.Cu")
		(net "M_A_CPU0_SB_DQ<23>")
	)
	(gr_poly
		(pts
			(xy 328.177652 -221.179136) (xy 328.177652 -220.988636) (xy 328.076052 -220.952314) (xy 328.025252 -220.952314)
			(xy 328.025252 -221.215458) (xy 328.076052 -221.215458)
		)
		(stroke
			(width 0)
			(type solid)
		)
		(fill yes)
		(layer "F.Cu")
		(net "M_A_CPU0_SB_DQ<23>")
	)
	(gr_poly
		(pts
			(xy 328.177652 -220.582236) (xy 328.177652 -220.391736) (xy 328.076052 -220.355414) (xy 328.025252 -220.355414)
			(xy 328.025252 -220.618558) (xy 328.076052 -220.618558)
		)
		(stroke
			(width 0)
			(type solid)
		)
		(fill yes)
		(layer "F.Cu")
		(net "M_A_CPU0_SB_DQ<23>")
	)
	(gr_poly
		(pts
			(xy 328.177652 -219.985336) (xy 328.177652 -219.794836) (xy 328.076052 -219.758514) (xy 328.025252 -219.758514)
			(xy 328.025252 -220.021658) (xy 328.076052 -220.021658)
		)
		(stroke
			(width 0)
			(type solid)
		)
		(fill yes)
		(layer "F.Cu")
		(net "M_A_CPU0_SB_DQ<23>")
	)
	(gr_poly
		(pts
			(xy 328.177652 -219.388436) (xy 328.177652 -219.197936) (xy 328.076052 -219.161614) (xy 328.025252 -219.161614)
			(xy 328.025252 -219.424758) (xy 328.076052 -219.424758)
		)
		(stroke
			(width 0)
			(type solid)
		)
		(fill yes)
		(layer "F.Cu")
		(net "M_A_CPU0_SB_DQ<23>")
	)
	(gr_poly
		(pts
			(xy 328.177652 -218.791536) (xy 328.177652 -218.601036) (xy 328.076052 -218.564714) (xy 328.025252 -218.564714)
			(xy 328.025252 -218.827858) (xy 328.076052 -218.827858)
		)
		(stroke
			(width 0)
			(type solid)
		)
		(fill yes)
		(layer "F.Cu")
		(net "M_A_CPU0_SB_DQ<23>")
	)
	(gr_poly
		(pts
			(xy 328.177652 -218.194636) (xy 328.177652 -218.004136) (xy 328.076052 -217.967814) (xy 328.025252 -217.967814)
			(xy 328.025252 -218.230958) (xy 328.076052 -218.230958)
		)
		(stroke
			(width 0)
			(type solid)
		)
		(fill yes)
		(layer "F.Cu")
		(net "M_A_CPU0_SB_DQ<23>")
	)
	(gr_poly
		(pts
			(xy 328.177652 -217.597736) (xy 328.177652 -217.407236) (xy 328.076052 -217.370914) (xy 328.025252 -217.370914)
			(xy 328.025252 -217.634058) (xy 328.076052 -217.634058)
		)
		(stroke
			(width 0)
			(type solid)
		)
		(fill yes)
		(layer "F.Cu")
		(net "M_A_CPU0_SB_DQ<23>")
	)
	(gr_poly
		(pts
			(xy 328.177652 -217.000836) (xy 328.177652 -216.810336) (xy 328.076052 -216.774014) (xy 328.025252 -216.774014)
			(xy 328.025252 -217.037158) (xy 328.076052 -217.037158)
		)
		(stroke
			(width 0)
			(type solid)
		)
		(fill yes)
		(layer "F.Cu")
		(net "M_A_CPU0_SB_DQ<23>")
	)
	(gr_poly
		(pts
			(xy 328.177652 -216.403936) (xy 328.177652 -216.213436) (xy 328.076052 -216.177114) (xy 328.025252 -216.177114)
			(xy 328.025252 -216.440258) (xy 328.076052 -216.440258)
		)
		(stroke
			(width 0)
			(type solid)
		)
		(fill yes)
		(layer "F.Cu")
		(net "M_A_CPU0_SB_DQ<23>")
	)
	(gr_poly
		(pts
			(xy 328.177652 -215.807036) (xy 328.177652 -215.616536) (xy 328.076052 -215.580214) (xy 328.025252 -215.580214)
			(xy 328.025252 -215.843358) (xy 328.076052 -215.843358)
		)
		(stroke
			(width 0)
			(type solid)
		)
		(fill yes)
		(layer "F.Cu")
		(net "M_A_CPU0_SB_DQ<23>")
	)
	(gr_poly
		(pts
			(xy 328.177652 -215.210136) (xy 328.177652 -215.019636) (xy 328.076052 -214.983314) (xy 328.025252 -214.983314)
			(xy 328.025252 -215.246458) (xy 328.076052 -215.246458)
		)
		(stroke
			(width 0)
			(type solid)
		)
		(fill yes)
		(layer "F.Cu")
		(net "M_A_CPU0_SB_DQ<23>")
	)
	(gr_poly
		(pts
			(xy 328.181462 -224.013522) (xy 328.21753 -223.977708) (xy 328.031602 -223.79178) (xy 327.995788 -223.827594)
			(xy 327.949306 -223.92513) (xy 328.08418 -224.05975)
		)
		(stroke
			(width 0)
			(type solid)
		)
		(fill yes)
		(layer "F.Cu")
		(net "M_A_CPU0_SB_DQ<20>")
	)
	(gr_poly
		(pts
			(xy 328.19086 -223.160082) (xy 328.226674 -223.124268) (xy 328.040746 -222.93834) (xy 328.004932 -222.974408)
			(xy 327.958704 -223.07169) (xy 328.093324 -223.206564)
		)
		(stroke
			(width 0)
			(type solid)
		)
		(fill yes)
		(layer "F.Cu")
		(net "M_A_CPU0_SB_DQ<21>")
	)
	(gr_poly
		(pts
			(xy 328.210926 -281.201622) (xy 328.248264 -281.014932) (xy 328.155554 -280.95956) (xy 328.10577 -280.9494)
			(xy 328.054208 -281.20721) (xy 328.104246 -281.21737)
		)
		(stroke
			(width 0)
			(type solid)
		)
		(fill yes)
		(layer "F.Cu")
		(net "M_A_CPU0_SA_DQ<19>")
	)
	(gr_poly
		(pts
			(xy 328.21372 -231.345994) (xy 328.249534 -231.309926) (xy 328.063606 -231.123998) (xy 328.027792 -231.160066)
			(xy 327.981564 -231.257348) (xy 328.116184 -231.392222)
		)
		(stroke
			(width 0)
			(type solid)
		)
		(fill yes)
		(layer "F.Cu")
		(net "M_A_CPU0_SB_DQ<14>")
	)
	(gr_poly
		(pts
			(xy 328.221086 -269.401036) (xy 328.174858 -269.3035) (xy 328.13879 -269.267686) (xy 327.953116 -269.45336)
			(xy 327.98893 -269.489428) (xy 328.086466 -269.535656)
		)
		(stroke
			(width 0)
			(type solid)
		)
		(fill yes)
		(layer "F.Cu")
		(net "M_A_CPU0_SA_DQ<31>")
	)
	(gr_poly
		(pts
			(xy 328.222864 -230.492554) (xy 328.258678 -230.456486) (xy 328.073004 -230.270812) (xy 328.036936 -230.306626)
			(xy 327.990708 -230.404162) (xy 328.125328 -230.538782)
		)
		(stroke
			(width 0)
			(type solid)
		)
		(fill yes)
		(layer "F.Cu")
		(net "M_A_CPU0_SB_DQ<15>")
	)
	(gr_poly
		(pts
			(xy 328.223372 -275.248116) (xy 328.187558 -275.212302) (xy 328.090022 -275.166074) (xy 327.955402 -275.300694)
			(xy 328.00163 -275.39823) (xy 328.037444 -275.434044)
		)
		(stroke
			(width 0)
			(type solid)
		)
		(fill yes)
		(layer "F.Cu")
		(net "M_A_CPU0_SA_DQ<21>")
	)
	(gr_poly
		(pts
			(xy 328.230738 -270.25473) (xy 328.18451 -270.157448) (xy 328.148696 -270.12138) (xy 327.962768 -270.307308)
			(xy 327.998582 -270.343122) (xy 328.096118 -270.389604)
		)
		(stroke
			(width 0)
			(type solid)
		)
		(fill yes)
		(layer "F.Cu")
		(net "M_A_CPU0_SA_DQ<30>")
	)
	(gr_poly
		(pts
			(xy 328.23277 -229.223062) (xy 328.268838 -229.187248) (xy 328.08291 -229.00132) (xy 328.047096 -229.037134)
			(xy 328.000868 -229.13467) (xy 328.135488 -229.26929)
		)
		(stroke
			(width 0)
			(type solid)
		)
		(fill yes)
		(layer "F.Cu")
		(net "M_A_CPU0_SB_DQ<18>")
	)
	(gr_poly
		(pts
			(xy 328.233786 -235.104178) (xy 328.280014 -235.006642) (xy 328.145394 -234.872022) (xy 328.047858 -234.91825)
			(xy 328.012044 -234.954318) (xy 328.197718 -235.139992)
		)
		(stroke
			(width 0)
			(type solid)
		)
		(fill yes)
		(layer "F.Cu")
		(net "M_A_CPU0_SB_DQ<8>")
	)
	(gr_poly
		(pts
			(xy 328.242168 -228.369876) (xy 328.277982 -228.333808) (xy 328.092054 -228.14788) (xy 328.05624 -228.183948)
			(xy 328.010012 -228.28123) (xy 328.144632 -228.416104)
		)
		(stroke
			(width 0)
			(type solid)
		)
		(fill yes)
		(layer "F.Cu")
		(net "M_A_CPU0_SB_DQ<19>")
	)
	(gr_poly
		(pts
			(xy 328.24293 -234.250738) (xy 328.289158 -234.153456) (xy 328.154538 -234.018582) (xy 328.057002 -234.06481)
			(xy 328.021188 -234.100878) (xy 328.207116 -234.286806)
		)
		(stroke
			(width 0)
			(type solid)
		)
		(fill yes)
		(layer "F.Cu")
		(net "M_A_CPU0_SB_DQ<9>")
	)
	(gr_poly
		(pts
			(xy 328.257916 -223.515174) (xy 328.304144 -223.417638) (xy 328.169524 -223.283018) (xy 328.071988 -223.329246)
			(xy 328.036174 -223.36506) (xy 328.222102 -223.550988)
		)
		(stroke
			(width 0)
			(type solid)
		)
		(fill yes)
		(layer "F.Cu")
		(net "M_A_CPU0_SB_DQ<22>")
	)
	(gr_poly
		(pts
			(xy 328.26198 -289.25266) (xy 328.21118 -289.25266) (xy 328.10958 -289.288982) (xy 328.10958 -289.479482)
			(xy 328.21118 -289.51555) (xy 328.26198 -289.51555)
		)
		(stroke
			(width 0)
			(type solid)
		)
		(fill yes)
		(layer "F.Cu")
		(net "M_A_CPU0_SA_DQ<17>")
	)
	(gr_poly
		(pts
			(xy 328.26198 -288.65576) (xy 328.21118 -288.65576) (xy 328.10958 -288.692082) (xy 328.10958 -288.882582)
			(xy 328.21118 -288.91865) (xy 328.26198 -288.91865)
		)
		(stroke
			(width 0)
			(type solid)
		)
		(fill yes)
		(layer "F.Cu")
		(net "M_A_CPU0_SA_DQ<17>")
	)
	(gr_poly
		(pts
			(xy 328.26198 -288.05886) (xy 328.21118 -288.05886) (xy 328.10958 -288.095182) (xy 328.10958 -288.285682)
			(xy 328.21118 -288.32175) (xy 328.26198 -288.32175)
		)
		(stroke
			(width 0)
			(type solid)
		)
		(fill yes)
		(layer "F.Cu")
		(net "M_A_CPU0_SA_DQ<17>")
	)
	(gr_poly
		(pts
			(xy 328.26198 -287.46196) (xy 328.21118 -287.46196) (xy 328.10958 -287.498282) (xy 328.10958 -287.688782)
			(xy 328.21118 -287.72485) (xy 328.26198 -287.72485)
		)
		(stroke
			(width 0)
			(type solid)
		)
		(fill yes)
		(layer "F.Cu")
		(net "M_A_CPU0_SA_DQ<17>")
	)
	(gr_poly
		(pts
			(xy 328.26198 -286.86506) (xy 328.21118 -286.86506) (xy 328.10958 -286.901382) (xy 328.10958 -287.091882)
			(xy 328.21118 -287.12795) (xy 328.26198 -287.12795)
		)
		(stroke
			(width 0)
			(type solid)
		)
		(fill yes)
		(layer "F.Cu")
		(net "M_A_CPU0_SA_DQ<17>")
	)
	(gr_poly
		(pts
			(xy 328.26198 -286.26816) (xy 328.21118 -286.26816) (xy 328.10958 -286.304482) (xy 328.10958 -286.494982)
			(xy 328.21118 -286.53105) (xy 328.26198 -286.53105)
		)
		(stroke
			(width 0)
			(type solid)
		)
		(fill yes)
		(layer "F.Cu")
		(net "M_A_CPU0_SA_DQ<17>")
	)
	(gr_poly
		(pts
			(xy 328.26198 -285.67126) (xy 328.21118 -285.67126) (xy 328.10958 -285.707582) (xy 328.10958 -285.898082)
			(xy 328.21118 -285.93415) (xy 328.26198 -285.93415)
		)
		(stroke
			(width 0)
			(type solid)
		)
		(fill yes)
		(layer "F.Cu")
		(net "M_A_CPU0_SA_DQ<17>")
	)
	(gr_poly
		(pts
			(xy 328.26198 -285.07436) (xy 328.21118 -285.07436) (xy 328.10958 -285.110682) (xy 328.10958 -285.301182)
			(xy 328.21118 -285.33725) (xy 328.26198 -285.33725)
		)
		(stroke
			(width 0)
			(type solid)
		)
		(fill yes)
		(layer "F.Cu")
		(net "M_A_CPU0_SA_DQ<17>")
	)
	(gr_poly
		(pts
			(xy 328.26198 -284.47746) (xy 328.21118 -284.47746) (xy 328.10958 -284.513782) (xy 328.10958 -284.704282)
			(xy 328.21118 -284.74035) (xy 328.26198 -284.74035)
		)
		(stroke
			(width 0)
			(type solid)
		)
		(fill yes)
		(layer "F.Cu")
		(net "M_A_CPU0_SA_DQ<17>")
	)
	(gr_poly
		(pts
			(xy 328.26198 -283.88056) (xy 328.21118 -283.88056) (xy 328.10958 -283.916882) (xy 328.10958 -284.107382)
			(xy 328.21118 -284.14345) (xy 328.26198 -284.14345)
		)
		(stroke
			(width 0)
			(type solid)
		)
		(fill yes)
		(layer "F.Cu")
		(net "M_A_CPU0_SA_DQ<17>")
	)
	(gr_poly
		(pts
			(xy 328.26198 -283.28366) (xy 328.21118 -283.28366) (xy 328.10958 -283.319982) (xy 328.10958 -283.510482)
			(xy 328.21118 -283.54655) (xy 328.26198 -283.54655)
		)
		(stroke
			(width 0)
			(type solid)
		)
		(fill yes)
		(layer "F.Cu")
		(net "M_A_CPU0_SA_DQ<17>")
	)
	(gr_poly
		(pts
			(xy 328.26198 -282.68676) (xy 328.21118 -282.68676) (xy 328.10958 -282.723082) (xy 328.10958 -282.913582)
			(xy 328.21118 -282.94965) (xy 328.26198 -282.94965)
		)
		(stroke
			(width 0)
			(type solid)
		)
		(fill yes)
		(layer "F.Cu")
		(net "M_A_CPU0_SA_DQ<17>")
	)
	(gr_poly
		(pts
			(xy 328.26198 -282.08986) (xy 328.21118 -282.08986) (xy 328.10958 -282.126182) (xy 328.10958 -282.316682)
			(xy 328.21118 -282.35275) (xy 328.26198 -282.35275)
		)
		(stroke
			(width 0)
			(type solid)
		)
		(fill yes)
		(layer "F.Cu")
		(net "M_A_CPU0_SA_DQ<17>")
	)
	(gr_poly
		(pts
			(xy 328.264012 -262.482076) (xy 328.227944 -262.446262) (xy 328.130662 -262.400034) (xy 327.995788 -262.534654)
			(xy 328.042016 -262.63219) (xy 328.078084 -262.668004)
		)
		(stroke
			(width 0)
			(type solid)
		)
		(fill yes)
		(layer "F.Cu")
		(net "M_A_CPU0_SA_CB<5>")
	)
	(gr_poly
		(pts
			(xy 328.27341 -263.33577) (xy 328.237596 -263.299956) (xy 328.14006 -263.253728) (xy 328.00544 -263.388348)
			(xy 328.051668 -263.48563) (xy 328.087482 -263.521698)
		)
		(stroke
			(width 0)
			(type solid)
		)
		(fill yes)
		(layer "F.Cu")
		(net "M_A_CPU0_SA_CB<4>")
	)
	(gr_poly
		(pts
			(xy 328.278236 -273.012408) (xy 328.242422 -272.976594) (xy 328.144886 -272.930112) (xy 328.010266 -273.064986)
			(xy 328.056494 -273.162268) (xy 328.092308 -273.198336)
		)
		(stroke
			(width 0)
			(type solid)
		)
		(fill yes)
		(layer "F.Cu")
		(net "M_A_CPU0_SA_DQ<25>")
	)
	(gr_poly
		(pts
			(xy 328.278236 -265.918696) (xy 328.242422 -265.882628) (xy 328.144886 -265.8364) (xy 328.010266 -265.97102)
			(xy 328.056494 -266.068556) (xy 328.092308 -266.104624)
		)
		(stroke
			(width 0)
			(type solid)
		)
		(fill yes)
		(layer "F.Cu")
		(net "M_A_CPU0_SA_CB<1>")
	)
	(gr_poly
		(pts
			(xy 328.280776 -231.700832) (xy 328.327004 -231.603296) (xy 328.192384 -231.468676) (xy 328.094848 -231.514904)
			(xy 328.059034 -231.550972) (xy 328.244708 -231.736646)
		)
		(stroke
			(width 0)
			(type solid)
		)
		(fill yes)
		(layer "F.Cu")
		(net "M_A_CPU0_SB_DQ<12>")
	)
	(gr_poly
		(pts
			(xy 328.281284 -280.071576) (xy 328.2315 -280.06167) (xy 328.124566 -280.077164) (xy 328.087482 -280.263854)
			(xy 328.179938 -280.31948) (xy 328.229722 -280.329386)
		)
		(stroke
			(width 0)
			(type solid)
		)
		(fill yes)
		(layer "F.Cu")
		(net "M_A_CPU0_SA_DQ<19>")
	)
	(gr_poly
		(pts
			(xy 328.28738 -273.865848) (xy 328.251566 -273.82978) (xy 328.15403 -273.783552) (xy 328.01941 -273.918426)
			(xy 328.065638 -274.015708) (xy 328.101452 -274.051776)
		)
		(stroke
			(width 0)
			(type solid)
		)
		(fill yes)
		(layer "F.Cu")
		(net "M_A_CPU0_SA_DQ<24>")
	)
	(gr_poly
		(pts
			(xy 328.287634 -266.772136) (xy 328.25182 -266.736068) (xy 328.154284 -266.68984) (xy 328.019664 -266.824714)
			(xy 328.065892 -266.921996) (xy 328.101706 -266.958064)
		)
		(stroke
			(width 0)
			(type solid)
		)
		(fill yes)
		(layer "F.Cu")
		(net "M_A_CPU0_SA_CB<0>")
	)
	(gr_poly
		(pts
			(xy 328.290174 -230.847392) (xy 328.336402 -230.749856) (xy 328.201528 -230.615236) (xy 328.104246 -230.661464)
			(xy 328.068178 -230.697278) (xy 328.254106 -230.883206)
		)
		(stroke
			(width 0)
			(type solid)
		)
		(fill yes)
		(layer "F.Cu")
		(net "M_A_CPU0_SB_DQ<13>")
	)
	(gr_poly
		(pts
			(xy 328.30008 -229.5779) (xy 328.346308 -229.480618) (xy 328.211688 -229.345744) (xy 328.114152 -229.391972)
			(xy 328.078338 -229.42804) (xy 328.264266 -229.613968)
		)
		(stroke
			(width 0)
			(type solid)
		)
		(fill yes)
		(layer "F.Cu")
		(net "M_A_CPU0_SB_DQ<16>")
	)
	(gr_poly
		(pts
			(xy 328.301096 -274.954746) (xy 328.254868 -274.857464) (xy 328.2188 -274.821396) (xy 328.032872 -275.007324)
			(xy 328.06894 -275.043392) (xy 328.166222 -275.08962)
		)
		(stroke
			(width 0)
			(type solid)
		)
		(fill yes)
		(layer "F.Cu")
		(net "M_A_CPU0_SA_DQ<23>")
	)
	(gr_poly
		(pts
			(xy 328.309224 -228.724714) (xy 328.355706 -228.627178) (xy 328.220832 -228.492558) (xy 328.12355 -228.538786)
			(xy 328.087482 -228.5746) (xy 328.27341 -228.760528)
		)
		(stroke
			(width 0)
			(type solid)
		)
		(fill yes)
		(layer "F.Cu")
		(net "M_A_CPU0_SB_DQ<17>")
	)
	(gr_poly
		(pts
			(xy 328.31024 -275.80844) (xy 328.264012 -275.710904) (xy 328.228198 -275.67509) (xy 328.04227 -275.861018)
			(xy 328.078084 -275.896832) (xy 328.17562 -275.94306)
		)
		(stroke
			(width 0)
			(type solid)
		)
		(fill yes)
		(layer "F.Cu")
		(net "M_A_CPU0_SA_DQ<22>")
	)
	(gr_poly
		(pts
			(xy 328.327766 -280.616406) (xy 328.365104 -280.429462) (xy 328.272648 -280.37409) (xy 328.222864 -280.364184)
			(xy 328.171302 -280.621994) (xy 328.221086 -280.6319)
		)
		(stroke
			(width 0)
			(type solid)
		)
		(fill yes)
		(layer "F.Cu")
		(net "M_A_CPU0_SA_DQ<19>")
	)
	(gr_poly
		(pts
			(xy 328.341482 -262.188706) (xy 328.295 -262.09117) (xy 328.259186 -262.055356) (xy 328.073258 -262.241284)
			(xy 328.109326 -262.277098) (xy 328.206608 -262.323326)
		)
		(stroke
			(width 0)
			(type solid)
		)
		(fill yes)
		(layer "F.Cu")
		(net "M_A_CPU0_SA_CB<7>")
	)
	(gr_poly
		(pts
			(xy 328.349864 -269.056612) (xy 328.31405 -269.020544) (xy 328.216514 -268.974316) (xy 328.081894 -269.108936)
			(xy 328.128122 -269.206472) (xy 328.163936 -269.24254)
		)
		(stroke
			(width 0)
			(type solid)
		)
		(fill yes)
		(layer "F.Cu")
		(net "M_A_CPU0_SA_DQ<31>")
	)
	(gr_poly
		(pts
			(xy 328.35088 -263.0424) (xy 328.304652 -262.944864) (xy 328.268584 -262.90905) (xy 328.082656 -263.094978)
			(xy 328.118724 -263.130792) (xy 328.21626 -263.17702)
		)
		(stroke
			(width 0)
			(type solid)
		)
		(fill yes)
		(layer "F.Cu")
		(net "M_A_CPU0_SA_CB<6>")
	)
	(gr_poly
		(pts
			(xy 328.355452 -272.718784) (xy 328.309224 -272.621502) (xy 328.27341 -272.585434) (xy 328.087482 -272.771362)
			(xy 328.123296 -272.807176) (xy 328.220832 -272.853404)
		)
		(stroke
			(width 0)
			(type solid)
		)
		(fill yes)
		(layer "F.Cu")
		(net "M_A_CPU0_SA_DQ<27>")
	)
	(gr_poly
		(pts
			(xy 328.35596 -265.625326) (xy 328.309732 -265.52779) (xy 328.273664 -265.491976) (xy 328.087736 -265.677904)
			(xy 328.123804 -265.713718) (xy 328.221086 -265.759946)
		)
		(stroke
			(width 0)
			(type solid)
		)
		(fill yes)
		(layer "F.Cu")
		(net "M_A_CPU0_SA_CB<3>")
	)
	(gr_poly
		(pts
			(xy 328.35977 -269.910306) (xy 328.323702 -269.874492) (xy 328.22642 -269.828264) (xy 328.091546 -269.962884)
			(xy 328.137774 -270.06042) (xy 328.173842 -270.096234)
		)
		(stroke
			(width 0)
			(type solid)
		)
		(fill yes)
		(layer "F.Cu")
		(net "M_A_CPU0_SA_DQ<30>")
	)
	(gr_poly
		(pts
			(xy 328.365104 -273.572478) (xy 328.318876 -273.474942) (xy 328.282808 -273.439128) (xy 328.09688 -273.625056)
			(xy 328.132948 -273.66087) (xy 328.23023 -273.707098)
		)
		(stroke
			(width 0)
			(type solid)
		)
		(fill yes)
		(layer "F.Cu")
		(net "M_A_CPU0_SA_DQ<26>")
	)
	(gr_poly
		(pts
			(xy 328.365104 -266.478766) (xy 328.318876 -266.38123) (xy 328.283062 -266.345416) (xy 328.097134 -266.531344)
			(xy 328.133202 -266.567158) (xy 328.230484 -266.613386)
		)
		(stroke
			(width 0)
			(type solid)
		)
		(fill yes)
		(layer "F.Cu")
		(net "M_A_CPU0_SA_CB<2>")
	)
	(gr_poly
		(pts
			(xy 328.372978 -235.387134) (xy 328.408792 -235.351066) (xy 328.222864 -235.165138) (xy 328.18705 -235.201206)
			(xy 328.140822 -235.298488) (xy 328.275442 -235.433362)
		)
		(stroke
			(width 0)
			(type solid)
		)
		(fill yes)
		(layer "F.Cu")
		(net "M_A_CPU0_SB_DQ<8>")
	)
	(gr_poly
		(pts
			(xy 328.382122 -234.533694) (xy 328.41819 -234.49788) (xy 328.232262 -234.311952) (xy 328.196194 -234.347766)
			(xy 328.149966 -234.445302) (xy 328.28484 -234.579922)
		)
		(stroke
			(width 0)
			(type solid)
		)
		(fill yes)
		(layer "F.Cu")
		(net "M_A_CPU0_SB_DQ<9>")
	)
	(gr_poly
		(pts
			(xy 328.390758 -249.371866) (xy 328.390758 -249.321066) (xy 328.127868 -249.321066) (xy 328.127868 -249.371866)
			(xy 328.163936 -249.473466) (xy 328.354436 -249.473466)
		)
		(stroke
			(width 0)
			(type solid)
		)
		(fill yes)
		(layer "F.Cu")
		(net "M_A_CPU0_SB_CA<0>")
	)
	(gr_poly
		(pts
			(xy 328.390758 -249.066812) (xy 328.390758 -249.016012) (xy 328.127868 -249.016012) (xy 328.127868 -249.066812)
			(xy 328.163936 -249.168412) (xy 328.354436 -249.168412)
		)
		(stroke
			(width 0)
			(type solid)
		)
		(fill yes)
		(layer "F.Cu")
		(net "M_A_CPU0_SB_CA<1>")
	)
	(gr_poly
		(pts
			(xy 328.390758 -248.762012) (xy 328.390758 -248.711212) (xy 328.127868 -248.711212) (xy 328.127868 -248.762012)
			(xy 328.163936 -248.863612) (xy 328.354436 -248.863612)
		)
		(stroke
			(width 0)
			(type solid)
		)
		(fill yes)
		(layer "F.Cu")
		(net "M_A_CPU0_SB_CA<2>")
	)
	(gr_poly
		(pts
			(xy 328.390758 -248.457212) (xy 328.390758 -248.406412) (xy 328.127868 -248.406412) (xy 328.127868 -248.457212)
			(xy 328.163936 -248.558812) (xy 328.354436 -248.558812)
		)
		(stroke
			(width 0)
			(type solid)
		)
		(fill yes)
		(layer "F.Cu")
		(net "M_A_CPU0_SB_CA<3>")
	)
	(gr_poly
		(pts
			(xy 328.390758 -248.152412) (xy 328.390758 -248.101612) (xy 328.127868 -248.101612) (xy 328.127868 -248.152412)
			(xy 328.163936 -248.254012) (xy 328.354436 -248.254012)
		)
		(stroke
			(width 0)
			(type solid)
		)
		(fill yes)
		(layer "F.Cu")
		(net "M_A_CPU0_SB_CA<4>")
	)
	(gr_poly
		(pts
			(xy 328.390758 -247.847612) (xy 328.390758 -247.796812) (xy 328.127868 -247.796812) (xy 328.127868 -247.847612)
			(xy 328.163936 -247.949212) (xy 328.354436 -247.949212)
		)
		(stroke
			(width 0)
			(type solid)
		)
		(fill yes)
		(layer "F.Cu")
		(net "M_A_CPU0_SB_CA<5>")
	)
	(gr_poly
		(pts
			(xy 328.390758 -247.542812) (xy 328.390758 -247.492012) (xy 328.127868 -247.492012) (xy 328.127868 -247.542812)
			(xy 328.163936 -247.644412) (xy 328.354436 -247.644412)
		)
		(stroke
			(width 0)
			(type solid)
		)
		(fill yes)
		(layer "F.Cu")
		(net "M_A_CPU0_SB_CA<6>")
	)
	(gr_poly
		(pts
			(xy 328.390758 -247.238012) (xy 328.390758 -247.187212) (xy 328.127868 -247.187212) (xy 328.127868 -247.238012)
			(xy 328.163936 -247.339612) (xy 328.354436 -247.339612)
		)
		(stroke
			(width 0)
			(type solid)
		)
		(fill yes)
		(layer "F.Cu")
		(net "M_A_CPU0_SB_PAR")
	)
	(gr_poly
		(pts
			(xy 328.390758 -246.933212) (xy 328.390758 -246.882412) (xy 328.127868 -246.882412) (xy 328.127868 -246.933212)
			(xy 328.163936 -247.034812) (xy 328.354436 -247.034812)
		)
		(stroke
			(width 0)
			(type solid)
		)
		(fill yes)
		(layer "F.Cu")
		(net "M_A_CPU0_SB_CS_N<2>")
	)
	(gr_poly
		(pts
			(xy 328.390758 -246.628412) (xy 328.390758 -246.577612) (xy 328.127868 -246.577612) (xy 328.127868 -246.628412)
			(xy 328.163936 -246.730012) (xy 328.354436 -246.730012)
		)
		(stroke
			(width 0)
			(type solid)
		)
		(fill yes)
		(layer "F.Cu")
		(net "M_A_CPU0_SB_CS_N<0>")
	)
	(gr_poly
		(pts
			(xy 328.390758 -246.323612) (xy 328.390758 -246.272812) (xy 328.127868 -246.272812) (xy 328.127868 -246.323612)
			(xy 328.163936 -246.425212) (xy 328.354436 -246.425212)
		)
		(stroke
			(width 0)
			(type solid)
		)
		(fill yes)
		(layer "F.Cu")
		(net "M_A_CPU0_SB_CS_N<3>")
	)
	(gr_poly
		(pts
			(xy 328.390758 -246.018812) (xy 328.390758 -245.968012) (xy 328.127868 -245.968012) (xy 328.127868 -246.018812)
			(xy 328.163936 -246.120412) (xy 328.354436 -246.120412)
		)
		(stroke
			(width 0)
			(type solid)
		)
		(fill yes)
		(layer "F.Cu")
		(net "M_A_CPU0_SB_CS_N<1>")
	)
	(gr_poly
		(pts
			(xy 328.397108 -223.797876) (xy 328.433176 -223.762062) (xy 328.247248 -223.576134) (xy 328.211434 -223.611948)
			(xy 328.164952 -223.709484) (xy 328.299826 -223.844104)
		)
		(stroke
			(width 0)
			(type solid)
		)
		(fill yes)
		(layer "F.Cu")
		(net "M_A_CPU0_SB_DQ<22>")
	)
	(gr_poly
		(pts
			(xy 328.398124 -279.486106) (xy 328.34834 -279.4762) (xy 328.24166 -279.491948) (xy 328.204322 -279.678638)
			(xy 328.296778 -279.73401) (xy 328.346562 -279.743916)
		)
		(stroke
			(width 0)
			(type solid)
		)
		(fill yes)
		(layer "F.Cu")
		(net "M_A_CPU0_SA_DQ<19>")
	)
	(gr_poly
		(pts
			(xy 328.406506 -222.944436) (xy 328.44232 -222.908622) (xy 328.256392 -222.722694) (xy 328.220578 -222.758762)
			(xy 328.17435 -222.856044) (xy 328.30897 -222.990918)
		)
		(stroke
			(width 0)
			(type solid)
		)
		(fill yes)
		(layer "F.Cu")
		(net "M_A_CPU0_SB_DQ<23>")
	)
	(gr_poly
		(pts
			(xy 328.41438 -289.181032) (xy 328.41438 -288.990532) (xy 328.31278 -288.95421) (xy 328.26198 -288.95421)
			(xy 328.26198 -289.2171) (xy 328.31278 -289.2171)
		)
		(stroke
			(width 0)
			(type solid)
		)
		(fill yes)
		(layer "F.Cu")
		(net "M_A_CPU0_SA_DQ<17>")
	)
	(gr_poly
		(pts
			(xy 328.41438 -288.584132) (xy 328.41438 -288.393632) (xy 328.31278 -288.35731) (xy 328.26198 -288.35731)
			(xy 328.26198 -288.6202) (xy 328.31278 -288.6202)
		)
		(stroke
			(width 0)
			(type solid)
		)
		(fill yes)
		(layer "F.Cu")
		(net "M_A_CPU0_SA_DQ<17>")
	)
	(gr_poly
		(pts
			(xy 328.41438 -287.987232) (xy 328.41438 -287.796732) (xy 328.31278 -287.76041) (xy 328.26198 -287.76041)
			(xy 328.26198 -288.0233) (xy 328.31278 -288.0233)
		)
		(stroke
			(width 0)
			(type solid)
		)
		(fill yes)
		(layer "F.Cu")
		(net "M_A_CPU0_SA_DQ<17>")
	)
	(gr_poly
		(pts
			(xy 328.41438 -287.390332) (xy 328.41438 -287.199832) (xy 328.31278 -287.16351) (xy 328.26198 -287.16351)
			(xy 328.26198 -287.4264) (xy 328.31278 -287.4264)
		)
		(stroke
			(width 0)
			(type solid)
		)
		(fill yes)
		(layer "F.Cu")
		(net "M_A_CPU0_SA_DQ<17>")
	)
	(gr_poly
		(pts
			(xy 328.41438 -286.793432) (xy 328.41438 -286.602932) (xy 328.31278 -286.56661) (xy 328.26198 -286.56661)
			(xy 328.26198 -286.8295) (xy 328.31278 -286.8295)
		)
		(stroke
			(width 0)
			(type solid)
		)
		(fill yes)
		(layer "F.Cu")
		(net "M_A_CPU0_SA_DQ<17>")
	)
	(gr_poly
		(pts
			(xy 328.41438 -286.196532) (xy 328.41438 -286.006032) (xy 328.31278 -285.96971) (xy 328.26198 -285.96971)
			(xy 328.26198 -286.2326) (xy 328.31278 -286.2326)
		)
		(stroke
			(width 0)
			(type solid)
		)
		(fill yes)
		(layer "F.Cu")
		(net "M_A_CPU0_SA_DQ<17>")
	)
	(gr_poly
		(pts
			(xy 328.41438 -285.599632) (xy 328.41438 -285.409132) (xy 328.31278 -285.37281) (xy 328.26198 -285.37281)
			(xy 328.26198 -285.6357) (xy 328.31278 -285.6357)
		)
		(stroke
			(width 0)
			(type solid)
		)
		(fill yes)
		(layer "F.Cu")
		(net "M_A_CPU0_SA_DQ<17>")
	)
	(gr_poly
		(pts
			(xy 328.41438 -285.002732) (xy 328.41438 -284.812232) (xy 328.31278 -284.77591) (xy 328.26198 -284.77591)
			(xy 328.26198 -285.0388) (xy 328.31278 -285.0388)
		)
		(stroke
			(width 0)
			(type solid)
		)
		(fill yes)
		(layer "F.Cu")
		(net "M_A_CPU0_SA_DQ<17>")
	)
	(gr_poly
		(pts
			(xy 328.41438 -284.405832) (xy 328.41438 -284.215332) (xy 328.31278 -284.17901) (xy 328.26198 -284.17901)
			(xy 328.26198 -284.4419) (xy 328.31278 -284.4419)
		)
		(stroke
			(width 0)
			(type solid)
		)
		(fill yes)
		(layer "F.Cu")
		(net "M_A_CPU0_SA_DQ<17>")
	)
	(gr_poly
		(pts
			(xy 328.41438 -283.808932) (xy 328.41438 -283.618432) (xy 328.31278 -283.58211) (xy 328.26198 -283.58211)
			(xy 328.26198 -283.845) (xy 328.31278 -283.845)
		)
		(stroke
			(width 0)
			(type solid)
		)
		(fill yes)
		(layer "F.Cu")
		(net "M_A_CPU0_SA_DQ<17>")
	)
	(gr_poly
		(pts
			(xy 328.41438 -283.212032) (xy 328.41438 -283.021532) (xy 328.31278 -282.98521) (xy 328.26198 -282.98521)
			(xy 328.26198 -283.2481) (xy 328.31278 -283.2481)
		)
		(stroke
			(width 0)
			(type solid)
		)
		(fill yes)
		(layer "F.Cu")
		(net "M_A_CPU0_SA_DQ<17>")
	)
	(gr_poly
		(pts
			(xy 328.41438 -282.615132) (xy 328.41438 -282.424632) (xy 328.31278 -282.38831) (xy 328.26198 -282.38831)
			(xy 328.26198 -282.6512) (xy 328.31278 -282.6512)
		)
		(stroke
			(width 0)
			(type solid)
		)
		(fill yes)
		(layer "F.Cu")
		(net "M_A_CPU0_SA_DQ<17>")
	)
	(gr_poly
		(pts
			(xy 328.419968 -231.983788) (xy 328.455782 -231.94772) (xy 328.269854 -231.761792) (xy 328.23404 -231.79786)
			(xy 328.187812 -231.895396) (xy 328.322432 -232.030016)
		)
		(stroke
			(width 0)
			(type solid)
		)
		(fill yes)
		(layer "F.Cu")
		(net "M_A_CPU0_SB_DQ<12>")
	)
	(gr_poly
		(pts
			(xy 328.423524 -259.313426) (xy 328.387456 -259.211826) (xy 328.196956 -259.211826) (xy 328.160634 -259.313426)
			(xy 328.160634 -259.364226) (xy 328.423524 -259.364226)
		)
		(stroke
			(width 0)
			(type solid)
		)
		(fill yes)
		(layer "F.Cu")
		(net "M_A_CPU0_SA_CS_N<2>")
	)
	(gr_poly
		(pts
			(xy 328.423524 -259.008626) (xy 328.387456 -258.907026) (xy 328.196956 -258.907026) (xy 328.160634 -259.008626)
			(xy 328.160634 -259.059426) (xy 328.423524 -259.059426)
		)
		(stroke
			(width 0)
			(type solid)
		)
		(fill yes)
		(layer "F.Cu")
		(net "M_A_CPU0_SA_CS_N<3>")
	)
	(gr_poly
		(pts
			(xy 328.423524 -258.703826) (xy 328.387456 -258.602226) (xy 328.196956 -258.602226) (xy 328.160634 -258.703826)
			(xy 328.160634 -258.754626) (xy 328.423524 -258.754626)
		)
		(stroke
			(width 0)
			(type solid)
		)
		(fill yes)
		(layer "F.Cu")
		(net "M_A_CPU0_SA_CS_N<1>")
	)
	(gr_poly
		(pts
			(xy 328.423524 -258.399026) (xy 328.387456 -258.297426) (xy 328.196956 -258.297426) (xy 328.160634 -258.399026)
			(xy 328.160634 -258.449826) (xy 328.423524 -258.449826)
		)
		(stroke
			(width 0)
			(type solid)
		)
		(fill yes)
		(layer "F.Cu")
		(net "M_A_CPU0_SA_CA<0>")
	)
	(gr_poly
		(pts
			(xy 328.423524 -258.094226) (xy 328.387456 -257.992626) (xy 328.196956 -257.992626) (xy 328.160634 -258.094226)
			(xy 328.160634 -258.145026) (xy 328.423524 -258.145026)
		)
		(stroke
			(width 0)
			(type solid)
		)
		(fill yes)
		(layer "F.Cu")
		(net "M_A_CPU0_SA_CA<1>")
	)
	(gr_poly
		(pts
			(xy 328.423524 -257.789426) (xy 328.387456 -257.687826) (xy 328.196956 -257.687826) (xy 328.160634 -257.789426)
			(xy 328.160634 -257.840226) (xy 328.423524 -257.840226)
		)
		(stroke
			(width 0)
			(type solid)
		)
		(fill yes)
		(layer "F.Cu")
		(net "M_A_CPU0_SA_CA<2>")
	)
	(gr_poly
		(pts
			(xy 328.423524 -257.484626) (xy 328.387456 -257.383026) (xy 328.196956 -257.383026) (xy 328.160634 -257.484626)
			(xy 328.160634 -257.535426) (xy 328.423524 -257.535426)
		)
		(stroke
			(width 0)
			(type solid)
		)
		(fill yes)
		(layer "F.Cu")
		(net "M_A_CPU0_SA_CA<3>")
	)
	(gr_poly
		(pts
			(xy 328.423524 -257.179826) (xy 328.387456 -257.078226) (xy 328.196956 -257.078226) (xy 328.160634 -257.179826)
			(xy 328.160634 -257.230626) (xy 328.423524 -257.230626)
		)
		(stroke
			(width 0)
			(type solid)
		)
		(fill yes)
		(layer "F.Cu")
		(net "M_A_CPU0_SA_CA<4>")
	)
	(gr_poly
		(pts
			(xy 328.423524 -256.875026) (xy 328.387456 -256.773426) (xy 328.196956 -256.773426) (xy 328.160634 -256.875026)
			(xy 328.160634 -256.925826) (xy 328.423524 -256.925826)
		)
		(stroke
			(width 0)
			(type solid)
		)
		(fill yes)
		(layer "F.Cu")
		(net "M_A_CPU0_SA_CA<5>")
	)
	(gr_poly
		(pts
			(xy 328.423524 -256.570226) (xy 328.387456 -256.468626) (xy 328.196956 -256.468626) (xy 328.160634 -256.570226)
			(xy 328.160634 -256.621026) (xy 328.423524 -256.621026)
		)
		(stroke
			(width 0)
			(type solid)
		)
		(fill yes)
		(layer "F.Cu")
		(net "M_A_CPU0_SA_CA<6>")
	)
	(gr_poly
		(pts
			(xy 328.423524 -256.265426) (xy 328.387456 -256.163826) (xy 328.196956 -256.163826) (xy 328.160634 -256.265426)
			(xy 328.160634 -256.316226) (xy 328.423524 -256.316226)
		)
		(stroke
			(width 0)
			(type solid)
		)
		(fill yes)
		(layer "F.Cu")
		(net "M_A_CPU0_SA_PAR")
	)
	(gr_poly
		(pts
			(xy 328.429366 -231.130348) (xy 328.46518 -231.09428) (xy 328.279252 -230.908352) (xy 328.243438 -230.94442)
			(xy 328.19721 -231.041702) (xy 328.33183 -231.176576)
		)
		(stroke
			(width 0)
			(type solid)
		)
		(fill yes)
		(layer "F.Cu")
		(net "M_A_CPU0_SB_DQ<13>")
	)
	(gr_poly
		(pts
			(xy 328.429874 -274.610576) (xy 328.39406 -274.574508) (xy 328.296524 -274.52828) (xy 328.161904 -274.6629)
			(xy 328.208132 -274.760436) (xy 328.243946 -274.79625)
		)
		(stroke
			(width 0)
			(type solid)
		)
		(fill yes)
		(layer "F.Cu")
		(net "M_A_CPU0_SA_DQ<23>")
	)
	(gr_poly
		(pts
			(xy 328.436732 -269.616682) (xy 328.390504 -269.519146) (xy 328.35469 -269.483332) (xy 328.168762 -269.66926)
			(xy 328.20483 -269.705074) (xy 328.302112 -269.751302)
		)
		(stroke
			(width 0)
			(type solid)
		)
		(fill yes)
		(layer "F.Cu")
		(net "M_A_CPU0_SA_DQ<29>")
	)
	(gr_poly
		(pts
			(xy 328.439272 -275.464016) (xy 328.403204 -275.428202) (xy 328.305922 -275.38172) (xy 328.171048 -275.516594)
			(xy 328.217276 -275.613876) (xy 328.253344 -275.649944)
		)
		(stroke
			(width 0)
			(type solid)
		)
		(fill yes)
		(layer "F.Cu")
		(net "M_A_CPU0_SA_DQ<22>")
	)
	(gr_poly
		(pts
			(xy 328.439272 -229.860856) (xy 328.47534 -229.825042) (xy 328.289412 -229.639114) (xy 328.253344 -229.674928)
			(xy 328.207116 -229.772464) (xy 328.34199 -229.907084)
		)
		(stroke
			(width 0)
			(type solid)
		)
		(fill yes)
		(layer "F.Cu")
		(net "M_A_CPU0_SB_DQ<16>")
	)
	(gr_poly
		(pts
			(xy 328.444606 -280.030936) (xy 328.481944 -279.844246) (xy 328.389488 -279.788874) (xy 328.339704 -279.778968)
			(xy 328.288142 -280.036524) (xy 328.337926 -280.046684)
		)
		(stroke
			(width 0)
			(type solid)
		)
		(fill yes)
		(layer "F.Cu")
		(net "M_A_CPU0_SA_DQ<19>")
	)
	(gr_poly
		(pts
			(xy 328.446384 -270.470376) (xy 328.400156 -270.373094) (xy 328.364342 -270.337026) (xy 328.178414 -270.522954)
			(xy 328.214228 -270.558768) (xy 328.311764 -270.60525)
		)
		(stroke
			(width 0)
			(type solid)
		)
		(fill yes)
		(layer "F.Cu")
		(net "M_A_CPU0_SA_DQ<28>")
	)
	(gr_poly
		(pts
			(xy 328.448416 -229.007416) (xy 328.484484 -228.971602) (xy 328.298556 -228.785674) (xy 328.262742 -228.821488)
			(xy 328.216514 -228.919024) (xy 328.351134 -229.053644)
		)
		(stroke
			(width 0)
			(type solid)
		)
		(fill yes)
		(layer "F.Cu")
		(net "M_A_CPU0_SB_DQ<17>")
	)
	(gr_poly
		(pts
			(xy 328.449432 -234.888532) (xy 328.49566 -234.790996) (xy 328.36104 -234.656376) (xy 328.263504 -234.702604)
			(xy 328.22769 -234.738672) (xy 328.413364 -234.924346)
		)
		(stroke
			(width 0)
			(type solid)
		)
		(fill yes)
		(layer "F.Cu")
		(net "M_A_CPU0_SB_DQ<10>")
	)
	(gr_poly
		(pts
			(xy 328.458576 -234.035092) (xy 328.504804 -233.93781) (xy 328.370184 -233.802936) (xy 328.272648 -233.849164)
			(xy 328.236834 -233.885232) (xy 328.422762 -234.07116)
		)
		(stroke
			(width 0)
			(type solid)
		)
		(fill yes)
		(layer "F.Cu")
		(net "M_A_CPU0_SB_DQ<11>")
	)
	(gr_poly
		(pts
			(xy 328.463656 -280.716736) (xy 328.413872 -280.70683) (xy 328.307192 -280.722324) (xy 328.269854 -280.909268)
			(xy 328.36231 -280.96464) (xy 328.412094 -280.974546)
		)
		(stroke
			(width 0)
			(type solid)
		)
		(fill yes)
		(layer "F.Cu")
		(net "M_A_CPU0_SA_DQ<17>")
	)
	(gr_poly
		(pts
			(xy 328.464418 -224.152714) (xy 328.510646 -224.055432) (xy 328.376026 -223.920558) (xy 328.27849 -223.966786)
			(xy 328.242676 -224.002854) (xy 328.428604 -224.188782)
		)
		(stroke
			(width 0)
			(type solid)
		)
		(fill yes)
		(layer "F.Cu")
		(net "M_A_CPU0_SB_DQ<20>")
	)
	(gr_poly
		(pts
			(xy 328.47026 -261.844282) (xy 328.434192 -261.808468) (xy 328.33691 -261.76224) (xy 328.20229 -261.89686)
			(xy 328.248518 -261.994396) (xy 328.284332 -262.03021)
		)
		(stroke
			(width 0)
			(type solid)
		)
		(fill yes)
		(layer "F.Cu")
		(net "M_A_CPU0_SA_CB<7>")
	)
	(gr_poly
		(pts
			(xy 328.473562 -223.299528) (xy 328.51979 -223.201992) (xy 328.38517 -223.067372) (xy 328.287634 -223.1136)
			(xy 328.25182 -223.149414) (xy 328.437748 -223.335342)
		)
		(stroke
			(width 0)
			(type solid)
		)
		(fill yes)
		(layer "F.Cu")
		(net "M_A_CPU0_SB_DQ<21>")
	)
	(gr_poly
		(pts
			(xy 328.479658 -262.697976) (xy 328.443844 -262.661908) (xy 328.346308 -262.61568) (xy 328.211688 -262.750554)
			(xy 328.257916 -262.847836) (xy 328.29373 -262.883904)
		)
		(stroke
			(width 0)
			(type solid)
		)
		(fill yes)
		(layer "F.Cu")
		(net "M_A_CPU0_SA_CB<6>")
	)
	(gr_poly
		(pts
			(xy 328.484484 -272.37436) (xy 328.448416 -272.338546) (xy 328.351134 -272.292318) (xy 328.21626 -272.426938)
			(xy 328.262488 -272.524474) (xy 328.298556 -272.560288)
		)
		(stroke
			(width 0)
			(type solid)
		)
		(fill yes)
		(layer "F.Cu")
		(net "M_A_CPU0_SA_DQ<27>")
	)
	(gr_poly
		(pts
			(xy 328.484738 -265.280902) (xy 328.448924 -265.245088) (xy 328.351388 -265.198606) (xy 328.216768 -265.33348)
			(xy 328.262996 -265.430762) (xy 328.29881 -265.46683)
		)
		(stroke
			(width 0)
			(type solid)
		)
		(fill yes)
		(layer "F.Cu")
		(net "M_A_CPU0_SA_CB<3>")
	)
	(gr_poly
		(pts
			(xy 328.493882 -273.228054) (xy 328.458068 -273.19224) (xy 328.360532 -273.145758) (xy 328.225912 -273.280632)
			(xy 328.27214 -273.377914) (xy 328.307954 -273.413982)
		)
		(stroke
			(width 0)
			(type solid)
		)
		(fill yes)
		(layer "F.Cu")
		(net "M_A_CPU0_SA_DQ<26>")
	)
	(gr_poly
		(pts
			(xy 328.494136 -266.134342) (xy 328.458068 -266.098528) (xy 328.360786 -266.0523) (xy 328.225912 -266.18692)
			(xy 328.272394 -266.284456) (xy 328.308208 -266.32027)
		)
		(stroke
			(width 0)
			(type solid)
		)
		(fill yes)
		(layer "F.Cu")
		(net "M_A_CPU0_SA_CB<2>")
	)
	(gr_poly
		(pts
			(xy 328.496422 -231.485186) (xy 328.54265 -231.38765) (xy 328.40803 -231.25303) (xy 328.310748 -231.299258)
			(xy 328.27468 -231.335072) (xy 328.460608 -231.521)
		)
		(stroke
			(width 0)
			(type solid)
		)
		(fill yes)
		(layer "F.Cu")
		(net "M_A_CPU0_SB_DQ<14>")
	)
	(gr_poly
		(pts
			(xy 328.50582 -230.631746) (xy 328.552048 -230.53421) (xy 328.417174 -230.39959) (xy 328.319892 -230.445818)
			(xy 328.283824 -230.481632) (xy 328.469752 -230.66756)
		)
		(stroke
			(width 0)
			(type solid)
		)
		(fill yes)
		(layer "F.Cu")
		(net "M_A_CPU0_SB_DQ<15>")
	)
	(gr_poly
		(pts
			(xy 328.510138 -281.261566) (xy 328.547476 -281.074622) (xy 328.45502 -281.01925) (xy 328.405236 -281.009344)
			(xy 328.353674 -281.267154) (xy 328.403458 -281.27706)
		)
		(stroke
			(width 0)
			(type solid)
		)
		(fill yes)
		(layer "F.Cu")
		(net "M_A_CPU0_SA_DQ<17>")
	)
	(gr_poly
		(pts
			(xy 328.514964 -278.90089) (xy 328.46518 -278.890984) (xy 328.3585 -278.906478) (xy 328.321162 -279.093168)
			(xy 328.413618 -279.148794) (xy 328.463656 -279.1587)
		)
		(stroke
			(width 0)
			(type solid)
		)
		(fill yes)
		(layer "F.Cu")
		(net "M_A_CPU0_SA_DQ<19>")
	)
	(gr_poly
		(pts
			(xy 328.515726 -229.362254) (xy 328.561954 -229.264972) (xy 328.427334 -229.130098) (xy 328.329798 -229.176326)
			(xy 328.293984 -229.212394) (xy 328.479912 -229.398322)
		)
		(stroke
			(width 0)
			(type solid)
		)
		(fill yes)
		(layer "F.Cu")
		(net "M_A_CPU0_SB_DQ<18>")
	)
	(gr_poly
		(pts
			(xy 328.516742 -275.170646) (xy 328.470514 -275.07311) (xy 328.434446 -275.037296) (xy 328.248518 -275.22297)
			(xy 328.284586 -275.259038) (xy 328.381868 -275.305266)
		)
		(stroke
			(width 0)
			(type solid)
		)
		(fill yes)
		(layer "F.Cu")
		(net "M_A_CPU0_SA_DQ<21>")
	)
	(gr_poly
		(pts
			(xy 328.52487 -228.509068) (xy 328.571352 -228.411532) (xy 328.436478 -228.276912) (xy 328.339196 -228.32314)
			(xy 328.303128 -228.358954) (xy 328.489056 -228.544882)
		)
		(stroke
			(width 0)
			(type solid)
		)
		(fill yes)
		(layer "F.Cu")
		(net "M_A_CPU0_SB_DQ<19>")
	)
	(gr_poly
		(pts
			(xy 328.526648 -276.024848) (xy 328.48042 -275.927312) (xy 328.444606 -275.891498) (xy 328.258678 -276.077426)
			(xy 328.294492 -276.11324) (xy 328.392028 -276.159468)
		)
		(stroke
			(width 0)
			(type solid)
		)
		(fill yes)
		(layer "F.Cu")
		(net "M_A_CPU0_SA_DQ<20>")
	)
	(gr_poly
		(pts
			(xy 328.557128 -262.404352) (xy 328.5109 -262.30707) (xy 328.475086 -262.271002) (xy 328.289158 -262.45693)
			(xy 328.324972 -262.492998) (xy 328.422508 -262.539226)
		)
		(stroke
			(width 0)
			(type solid)
		)
		(fill yes)
		(layer "F.Cu")
		(net "M_A_CPU0_SA_CB<5>")
	)
	(gr_poly
		(pts
			(xy 328.5617 -279.44572) (xy 328.599038 -279.258776) (xy 328.506328 -279.203404) (xy 328.456544 -279.193498)
			(xy 328.404982 -279.451308) (xy 328.45502 -279.461214)
		)
		(stroke
			(width 0)
			(type solid)
		)
		(fill yes)
		(layer "F.Cu")
		(net "M_A_CPU0_SA_DQ<19>")
	)
	(gr_poly
		(pts
			(xy 328.565764 -269.272258) (xy 328.529696 -269.236444) (xy 328.432414 -269.190216) (xy 328.29754 -269.324836)
			(xy 328.344022 -269.422372) (xy 328.379836 -269.458186)
		)
		(stroke
			(width 0)
			(type solid)
		)
		(fill yes)
		(layer "F.Cu")
		(net "M_A_CPU0_SA_DQ<29>")
	)
	(gr_poly
		(pts
			(xy 328.566526 -263.258046) (xy 328.520298 -263.160764) (xy 328.484484 -263.124696) (xy 328.298556 -263.310624)
			(xy 328.33437 -263.346438) (xy 328.431906 -263.39292)
		)
		(stroke
			(width 0)
			(type solid)
		)
		(fill yes)
		(layer "F.Cu")
		(net "M_A_CPU0_SA_CB<4>")
	)
	(gr_poly
		(pts
			(xy 328.56678 -289.25266) (xy 328.51598 -289.25266) (xy 328.41438 -289.288982) (xy 328.41438 -289.479482)
			(xy 328.51598 -289.51555) (xy 328.56678 -289.51555)
		)
		(stroke
			(width 0)
			(type solid)
		)
		(fill yes)
		(layer "F.Cu")
		(net "M_A_CPU0_SA_DQ<18>")
	)
	(gr_poly
		(pts
			(xy 328.56678 -288.65576) (xy 328.51598 -288.65576) (xy 328.41438 -288.692082) (xy 328.41438 -288.882582)
			(xy 328.51598 -288.91865) (xy 328.56678 -288.91865)
		)
		(stroke
			(width 0)
			(type solid)
		)
		(fill yes)
		(layer "F.Cu")
		(net "M_A_CPU0_SA_DQ<18>")
	)
	(gr_poly
		(pts
			(xy 328.56678 -288.05886) (xy 328.51598 -288.05886) (xy 328.41438 -288.095182) (xy 328.41438 -288.285682)
			(xy 328.51598 -288.32175) (xy 328.56678 -288.32175)
		)
		(stroke
			(width 0)
			(type solid)
		)
		(fill yes)
		(layer "F.Cu")
		(net "M_A_CPU0_SA_DQ<18>")
	)
	(gr_poly
		(pts
			(xy 328.56678 -287.46196) (xy 328.51598 -287.46196) (xy 328.41438 -287.498282) (xy 328.41438 -287.688782)
			(xy 328.51598 -287.72485) (xy 328.56678 -287.72485)
		)
		(stroke
			(width 0)
			(type solid)
		)
		(fill yes)
		(layer "F.Cu")
		(net "M_A_CPU0_SA_DQ<18>")
	)
	(gr_poly
		(pts
			(xy 328.56678 -286.86506) (xy 328.51598 -286.86506) (xy 328.41438 -286.901382) (xy 328.41438 -287.091882)
			(xy 328.51598 -287.12795) (xy 328.56678 -287.12795)
		)
		(stroke
			(width 0)
			(type solid)
		)
		(fill yes)
		(layer "F.Cu")
		(net "M_A_CPU0_SA_DQ<18>")
	)
	(gr_poly
		(pts
			(xy 328.56678 -286.26816) (xy 328.51598 -286.26816) (xy 328.41438 -286.304482) (xy 328.41438 -286.494982)
			(xy 328.51598 -286.53105) (xy 328.56678 -286.53105)
		)
		(stroke
			(width 0)
			(type solid)
		)
		(fill yes)
		(layer "F.Cu")
		(net "M_A_CPU0_SA_DQ<18>")
	)
	(gr_poly
		(pts
			(xy 328.56678 -285.67126) (xy 328.51598 -285.67126) (xy 328.41438 -285.707582) (xy 328.41438 -285.898082)
			(xy 328.51598 -285.93415) (xy 328.56678 -285.93415)
		)
		(stroke
			(width 0)
			(type solid)
		)
		(fill yes)
		(layer "F.Cu")
		(net "M_A_CPU0_SA_DQ<18>")
	)
	(gr_poly
		(pts
			(xy 328.56678 -285.07436) (xy 328.51598 -285.07436) (xy 328.41438 -285.110682) (xy 328.41438 -285.301182)
			(xy 328.51598 -285.33725) (xy 328.56678 -285.33725)
		)
		(stroke
			(width 0)
			(type solid)
		)
		(fill yes)
		(layer "F.Cu")
		(net "M_A_CPU0_SA_DQ<18>")
	)
	(gr_poly
		(pts
			(xy 328.56678 -284.47746) (xy 328.51598 -284.47746) (xy 328.41438 -284.513782) (xy 328.41438 -284.704282)
			(xy 328.51598 -284.74035) (xy 328.56678 -284.74035)
		)
		(stroke
			(width 0)
			(type solid)
		)
		(fill yes)
		(layer "F.Cu")
		(net "M_A_CPU0_SA_DQ<18>")
	)
	(gr_poly
		(pts
			(xy 328.56678 -283.88056) (xy 328.51598 -283.88056) (xy 328.41438 -283.916882) (xy 328.41438 -284.107382)
			(xy 328.51598 -284.14345) (xy 328.56678 -284.14345)
		)
		(stroke
			(width 0)
			(type solid)
		)
		(fill yes)
		(layer "F.Cu")
		(net "M_A_CPU0_SA_DQ<18>")
	)
	(gr_poly
		(pts
			(xy 328.56678 -283.28366) (xy 328.51598 -283.28366) (xy 328.41438 -283.319982) (xy 328.41438 -283.510482)
			(xy 328.51598 -283.54655) (xy 328.56678 -283.54655)
		)
		(stroke
			(width 0)
			(type solid)
		)
		(fill yes)
		(layer "F.Cu")
		(net "M_A_CPU0_SA_DQ<18>")
	)
	(gr_poly
		(pts
			(xy 328.56678 -282.68676) (xy 328.51598 -282.68676) (xy 328.41438 -282.723082) (xy 328.41438 -282.913582)
			(xy 328.51598 -282.94965) (xy 328.56678 -282.94965)
		)
		(stroke
			(width 0)
			(type solid)
		)
		(fill yes)
		(layer "F.Cu")
		(net "M_A_CPU0_SA_DQ<18>")
	)
	(gr_poly
		(pts
			(xy 328.56678 -282.08986) (xy 328.51598 -282.08986) (xy 328.41438 -282.126182) (xy 328.41438 -282.316682)
			(xy 328.51598 -282.35275) (xy 328.56678 -282.35275)
		)
		(stroke
			(width 0)
			(type solid)
		)
		(fill yes)
		(layer "F.Cu")
		(net "M_A_CPU0_SA_DQ<18>")
	)
	(gr_poly
		(pts
			(xy 328.571352 -272.934684) (xy 328.525124 -272.837402) (xy 328.48931 -272.801334) (xy 328.303382 -272.987262)
			(xy 328.339196 -273.023076) (xy 328.436732 -273.069304)
		)
		(stroke
			(width 0)
			(type solid)
		)
		(fill yes)
		(layer "F.Cu")
		(net "M_A_CPU0_SA_DQ<25>")
	)
	(gr_poly
		(pts
			(xy 328.571606 -265.840972) (xy 328.525378 -265.743436) (xy 328.48931 -265.707622) (xy 328.303382 -265.89355)
			(xy 328.33945 -265.929364) (xy 328.436732 -265.975592)
		)
		(stroke
			(width 0)
			(type solid)
		)
		(fill yes)
		(layer "F.Cu")
		(net "M_A_CPU0_SA_CB<1>")
	)
	(gr_poly
		(pts
			(xy 328.575416 -270.125952) (xy 328.539348 -270.090138) (xy 328.442066 -270.04391) (xy 328.307192 -270.17853)
			(xy 328.35342 -270.276066) (xy 328.389488 -270.31188)
		)
		(stroke
			(width 0)
			(type solid)
		)
		(fill yes)
		(layer "F.Cu")
		(net "M_A_CPU0_SA_DQ<28>")
	)
	(gr_poly
		(pts
			(xy 328.58075 -280.13152) (xy 328.530966 -280.12136) (xy 328.424286 -280.137108) (xy 328.386948 -280.323798)
			(xy 328.479404 -280.37917) (xy 328.529188 -280.389076)
		)
		(stroke
			(width 0)
			(type solid)
		)
		(fill yes)
		(layer "F.Cu")
		(net "M_A_CPU0_SA_DQ<17>")
	)
	(gr_poly
		(pts
			(xy 328.58075 -273.788124) (xy 328.534522 -273.690588) (xy 328.498454 -273.654774) (xy 328.312526 -273.840702)
			(xy 328.348594 -273.876516) (xy 328.445876 -273.922744)
		)
		(stroke
			(width 0)
			(type solid)
		)
		(fill yes)
		(layer "F.Cu")
		(net "M_A_CPU0_SA_DQ<24>")
	)
	(gr_poly
		(pts
			(xy 328.58075 -266.694412) (xy 328.534522 -266.596876) (xy 328.498708 -266.561062) (xy 328.31278 -266.74699)
			(xy 328.348848 -266.782804) (xy 328.44613 -266.829032)
		)
		(stroke
			(width 0)
			(type solid)
		)
		(fill yes)
		(layer "F.Cu")
		(net "M_A_CPU0_SA_CB<0>")
	)
	(gr_poly
		(pts
			(xy 328.588624 -235.171488) (xy 328.624438 -235.13542) (xy 328.43851 -234.949492) (xy 328.402696 -234.98556)
			(xy 328.356468 -235.082842) (xy 328.491088 -235.217716)
		)
		(stroke
			(width 0)
			(type solid)
		)
		(fill yes)
		(layer "F.Cu")
		(net "M_A_CPU0_SB_DQ<10>")
	)
	(gr_poly
		(pts
			(xy 328.597768 -234.318048) (xy 328.633836 -234.282234) (xy 328.447908 -234.096306) (xy 328.41184 -234.13212)
			(xy 328.365612 -234.229656) (xy 328.500486 -234.364276)
		)
		(stroke
			(width 0)
			(type solid)
		)
		(fill yes)
		(layer "F.Cu")
		(net "M_A_CPU0_SB_DQ<11>")
	)
	(gr_poly
		(pts
			(xy 328.612754 -223.58223) (xy 328.648822 -223.546416) (xy 328.462894 -223.360488) (xy 328.42708 -223.396302)
			(xy 328.380598 -223.493838) (xy 328.515472 -223.628458)
		)
		(stroke
			(width 0)
			(type solid)
		)
		(fill yes)
		(layer "F.Cu")
		(net "M_A_CPU0_SB_DQ<21>")
	)
	(gr_poly
		(pts
			(xy 328.627232 -280.67635) (xy 328.66457 -280.489406) (xy 328.572114 -280.434034) (xy 328.52233 -280.424128)
			(xy 328.470768 -280.681938) (xy 328.520552 -280.691844)
		)
		(stroke
			(width 0)
			(type solid)
		)
		(fill yes)
		(layer "F.Cu")
		(net "M_A_CPU0_SA_DQ<17>")
	)
	(gr_poly
		(pts
			(xy 328.635614 -231.767888) (xy 328.671682 -231.732074) (xy 328.485754 -231.546146) (xy 328.44994 -231.58196)
			(xy 328.403458 -231.679496) (xy 328.538332 -231.814116)
		)
		(stroke
			(width 0)
			(type solid)
		)
		(fill yes)
		(layer "F.Cu")
		(net "M_A_CPU0_SB_DQ<14>")
	)
	(gr_poly
		(pts
			(xy 328.643234 -268.978888) (xy 328.597006 -268.881352) (xy 328.560938 -268.845538) (xy 328.37501 -269.031466)
			(xy 328.411078 -269.06728) (xy 328.50836 -269.113508)
		)
		(stroke
			(width 0)
			(type solid)
		)
		(fill yes)
		(layer "F.Cu")
		(net "M_A_CPU0_SA_DQ<31>")
	)
	(gr_poly
		(pts
			(xy 328.645012 -230.914702) (xy 328.680826 -230.878634) (xy 328.494898 -230.692706) (xy 328.459084 -230.728774)
			(xy 328.412856 -230.826056) (xy 328.547476 -230.96093)
		)
		(stroke
			(width 0)
			(type solid)
		)
		(fill yes)
		(layer "F.Cu")
		(net "M_A_CPU0_SB_DQ<15>")
	)
	(gr_poly
		(pts
			(xy 328.64552 -274.826222) (xy 328.609706 -274.790154) (xy 328.51217 -274.743926) (xy 328.37755 -274.8788)
			(xy 328.423778 -274.976082) (xy 328.459592 -275.01215)
		)
		(stroke
			(width 0)
			(type solid)
		)
		(fill yes)
		(layer "F.Cu")
		(net "M_A_CPU0_SA_DQ<21>")
	)
	(gr_poly
		(pts
			(xy 328.652886 -269.832836) (xy 328.606658 -269.7353) (xy 328.57059 -269.699486) (xy 328.384916 -269.88516)
			(xy 328.42073 -269.921228) (xy 328.518266 -269.967456)
		)
		(stroke
			(width 0)
			(type solid)
		)
		(fill yes)
		(layer "F.Cu")
		(net "M_A_CPU0_SA_DQ<30>")
	)
	(gr_poly
		(pts
			(xy 328.654918 -229.64521) (xy 328.690986 -229.609396) (xy 328.505058 -229.423468) (xy 328.46899 -229.459282)
			(xy 328.422762 -229.556818) (xy 328.557636 -229.691438)
		)
		(stroke
			(width 0)
			(type solid)
		)
		(fill yes)
		(layer "F.Cu")
		(net "M_A_CPU0_SB_DQ<18>")
	)
	(gr_poly
		(pts
			(xy 328.65568 -275.680424) (xy 328.619612 -275.64461) (xy 328.52233 -275.598382) (xy 328.387456 -275.733002)
			(xy 328.433684 -275.830284) (xy 328.469752 -275.866352)
		)
		(stroke
			(width 0)
			(type solid)
		)
		(fill yes)
		(layer "F.Cu")
		(net "M_A_CPU0_SA_DQ<20>")
	)
	(gr_poly
		(pts
			(xy 328.655934 -235.526326) (xy 328.702162 -235.42879) (xy 328.567288 -235.29417) (xy 328.470006 -235.340398)
			(xy 328.433938 -235.376212) (xy 328.619866 -235.56214)
		)
		(stroke
			(width 0)
			(type solid)
		)
		(fill yes)
		(layer "F.Cu")
		(net "M_A_CPU0_SB_DQ<8>")
	)
	(gr_poly
		(pts
			(xy 328.664062 -228.79177) (xy 328.70013 -228.755956) (xy 328.514202 -228.570028) (xy 328.478388 -228.605842)
			(xy 328.43216 -228.703378) (xy 328.56678 -228.837998)
		)
		(stroke
			(width 0)
			(type solid)
		)
		(fill yes)
		(layer "F.Cu")
		(net "M_A_CPU0_SB_DQ<19>")
	)
	(gr_poly
		(pts
			(xy 328.665078 -234.672886) (xy 328.711306 -234.57535) (xy 328.576686 -234.44073) (xy 328.47915 -234.486958)
			(xy 328.443336 -234.523026) (xy 328.62901 -234.7087)
		)
		(stroke
			(width 0)
			(type solid)
		)
		(fill yes)
		(layer "F.Cu")
		(net "M_A_CPU0_SB_DQ<9>")
	)
	(gr_poly
		(pts
			(xy 328.67854 -278.86025) (xy 328.715878 -278.67356) (xy 328.623422 -278.618188) (xy 328.573638 -278.608282)
			(xy 328.522076 -278.866092) (xy 328.57186 -278.875998)
		)
		(stroke
			(width 0)
			(type solid)
		)
		(fill yes)
		(layer "F.Cu")
		(net "M_A_CPU0_SA_DQ<19>")
	)
	(gr_poly
		(pts
			(xy 328.680064 -223.937068) (xy 328.726292 -223.839786) (xy 328.591672 -223.704912) (xy 328.494136 -223.75114)
			(xy 328.458322 -223.787208) (xy 328.64425 -223.973136)
		)
		(stroke
			(width 0)
			(type solid)
		)
		(fill yes)
		(layer "F.Cu")
		(net "M_A_CPU0_SB_DQ<22>")
	)
	(gr_poly
		(pts
			(xy 328.685906 -262.060182) (xy 328.650092 -262.024114) (xy 328.552556 -261.977886) (xy 328.417936 -262.112506)
			(xy 328.464164 -262.210042) (xy 328.500232 -262.245856)
		)
		(stroke
			(width 0)
			(type solid)
		)
		(fill yes)
		(layer "F.Cu")
		(net "M_A_CPU0_SA_CB<5>")
	)
	(gr_poly
		(pts
			(xy 328.689208 -249.270266) (xy 328.65314 -249.168666) (xy 328.46264 -249.168666) (xy 328.426318 -249.270266)
			(xy 328.426318 -249.321066) (xy 328.689208 -249.321066)
		)
		(stroke
			(width 0)
			(type solid)
		)
		(fill yes)
		(layer "F.Cu")
		(net "M_A_CPU0_SB_CA<0>")
	)
	(gr_poly
		(pts
			(xy 328.689208 -248.965212) (xy 328.65314 -248.863612) (xy 328.46264 -248.863612) (xy 328.426318 -248.965212)
			(xy 328.426318 -249.016012) (xy 328.689208 -249.016012)
		)
		(stroke
			(width 0)
			(type solid)
		)
		(fill yes)
		(layer "F.Cu")
		(net "M_A_CPU0_SB_CA<1>")
	)
	(gr_poly
		(pts
			(xy 328.689208 -248.660412) (xy 328.65314 -248.558812) (xy 328.46264 -248.558812) (xy 328.426318 -248.660412)
			(xy 328.426318 -248.711212) (xy 328.689208 -248.711212)
		)
		(stroke
			(width 0)
			(type solid)
		)
		(fill yes)
		(layer "F.Cu")
		(net "M_A_CPU0_SB_CA<2>")
	)
	(gr_poly
		(pts
			(xy 328.689208 -248.355612) (xy 328.65314 -248.254012) (xy 328.46264 -248.254012) (xy 328.426318 -248.355612)
			(xy 328.426318 -248.406412) (xy 328.689208 -248.406412)
		)
		(stroke
			(width 0)
			(type solid)
		)
		(fill yes)
		(layer "F.Cu")
		(net "M_A_CPU0_SB_CA<3>")
	)
	(gr_poly
		(pts
			(xy 328.689208 -248.050812) (xy 328.65314 -247.949212) (xy 328.46264 -247.949212) (xy 328.426318 -248.050812)
			(xy 328.426318 -248.101612) (xy 328.689208 -248.101612)
		)
		(stroke
			(width 0)
			(type solid)
		)
		(fill yes)
		(layer "F.Cu")
		(net "M_A_CPU0_SB_CA<4>")
	)
	(gr_poly
		(pts
			(xy 328.689208 -247.746012) (xy 328.65314 -247.644412) (xy 328.46264 -247.644412) (xy 328.426318 -247.746012)
			(xy 328.426318 -247.796812) (xy 328.689208 -247.796812)
		)
		(stroke
			(width 0)
			(type solid)
		)
		(fill yes)
		(layer "F.Cu")
		(net "M_A_CPU0_SB_CA<5>")
	)
	(gr_poly
		(pts
			(xy 328.689208 -247.441212) (xy 328.65314 -247.339612) (xy 328.46264 -247.339612) (xy 328.426318 -247.441212)
			(xy 328.426318 -247.492012) (xy 328.689208 -247.492012)
		)
		(stroke
			(width 0)
			(type solid)
		)
		(fill yes)
		(layer "F.Cu")
		(net "M_A_CPU0_SB_CA<6>")
	)
	(gr_poly
		(pts
			(xy 328.689208 -247.136412) (xy 328.65314 -247.034812) (xy 328.46264 -247.034812) (xy 328.426318 -247.136412)
			(xy 328.426318 -247.187212) (xy 328.689208 -247.187212)
		)
		(stroke
			(width 0)
			(type solid)
		)
		(fill yes)
		(layer "F.Cu")
		(net "M_A_CPU0_SB_PAR")
	)
	(gr_poly
		(pts
			(xy 328.689208 -246.831612) (xy 328.65314 -246.730012) (xy 328.46264 -246.730012) (xy 328.426318 -246.831612)
			(xy 328.426318 -246.882412) (xy 328.689208 -246.882412)
		)
		(stroke
			(width 0)
			(type solid)
		)
		(fill yes)
		(layer "F.Cu")
		(net "M_A_CPU0_SB_CS_N<2>")
	)
	(gr_poly
		(pts
			(xy 328.689208 -246.526812) (xy 328.65314 -246.425212) (xy 328.46264 -246.425212) (xy 328.426318 -246.526812)
			(xy 328.426318 -246.577612) (xy 328.689208 -246.577612)
		)
		(stroke
			(width 0)
			(type solid)
		)
		(fill yes)
		(layer "F.Cu")
		(net "M_A_CPU0_SB_CS_N<0>")
	)
	(gr_poly
		(pts
			(xy 328.689208 -223.083882) (xy 328.735436 -222.986346) (xy 328.600816 -222.851726) (xy 328.50328 -222.897954)
			(xy 328.467466 -222.933768) (xy 328.653394 -223.119696)
		)
		(stroke
			(width 0)
			(type solid)
		)
		(fill yes)
		(layer "F.Cu")
		(net "M_A_CPU0_SB_DQ<23>")
	)
	(gr_poly
		(pts
			(xy 328.695558 -262.913622) (xy 328.65949 -262.877808) (xy 328.562208 -262.83158) (xy 328.427334 -262.9662)
			(xy 328.473562 -263.063736) (xy 328.50963 -263.09955)
		)
		(stroke
			(width 0)
			(type solid)
		)
		(fill yes)
		(layer "F.Cu")
		(net "M_A_CPU0_SA_CB<4>")
	)
	(gr_poly
		(pts
			(xy 328.69759 -279.54605) (xy 328.647806 -279.536144) (xy 328.541126 -279.551638) (xy 328.503788 -279.738582)
			(xy 328.596498 -279.793954) (xy 328.646282 -279.80386)
		)
		(stroke
			(width 0)
			(type solid)
		)
		(fill yes)
		(layer "F.Cu")
		(net "M_A_CPU0_SA_DQ<17>")
	)
	(gr_poly
		(pts
			(xy 328.700384 -272.59026) (xy 328.664316 -272.554446) (xy 328.567034 -272.508218) (xy 328.43216 -272.642838)
			(xy 328.478388 -272.740374) (xy 328.514456 -272.776188)
		)
		(stroke
			(width 0)
			(type solid)
		)
		(fill yes)
		(layer "F.Cu")
		(net "M_A_CPU0_SA_DQ<25>")
	)
	(gr_poly
		(pts
			(xy 328.700384 -265.496548) (xy 328.66457 -265.460734) (xy 328.567034 -265.414252) (xy 328.432414 -265.549126)
			(xy 328.478642 -265.646408) (xy 328.514456 -265.682476)
		)
		(stroke
			(width 0)
			(type solid)
		)
		(fill yes)
		(layer "F.Cu")
		(net "M_A_CPU0_SA_CB<1>")
	)
	(gr_poly
		(pts
			(xy 328.702924 -232.12298) (xy 328.749152 -232.025444) (xy 328.614278 -231.890824) (xy 328.516996 -231.937052)
			(xy 328.480928 -231.972866) (xy 328.666856 -232.158794)
		)
		(stroke
			(width 0)
			(type solid)
		)
		(fill yes)
		(layer "F.Cu")
		(net "M_A_CPU0_SB_DQ<12>")
	)
	(gr_poly
		(pts
			(xy 328.709528 -273.4437) (xy 328.673714 -273.407886) (xy 328.576178 -273.361404) (xy 328.441558 -273.496278)
			(xy 328.487786 -273.59356) (xy 328.5236 -273.629628)
		)
		(stroke
			(width 0)
			(type solid)
		)
		(fill yes)
		(layer "F.Cu")
		(net "M_A_CPU0_SA_DQ<24>")
	)
	(gr_poly
		(pts
			(xy 328.709782 -266.349988) (xy 328.673714 -266.314174) (xy 328.576432 -266.267946) (xy 328.441558 -266.402566)
			(xy 328.48804 -266.500102) (xy 328.523854 -266.535916)
		)
		(stroke
			(width 0)
			(type solid)
		)
		(fill yes)
		(layer "F.Cu")
		(net "M_A_CPU0_SA_CB<0>")
	)
	(gr_poly
		(pts
			(xy 328.712068 -231.26954) (xy 328.758296 -231.172004) (xy 328.623676 -231.037384) (xy 328.526394 -231.083612)
			(xy 328.490326 -231.119426) (xy 328.676254 -231.305354)
		)
		(stroke
			(width 0)
			(type solid)
		)
		(fill yes)
		(layer "F.Cu")
		(net "M_A_CPU0_SB_DQ<13>")
	)
	(gr_poly
		(pts
			(xy 328.716132 -225.712782) (xy 328.665332 -225.712782) (xy 328.563732 -225.749104) (xy 328.563732 -225.939604)
			(xy 328.665332 -225.975926) (xy 328.716132 -225.975926)
		)
		(stroke
			(width 0)
			(type solid)
		)
		(fill yes)
		(layer "F.Cu")
		(net "M_A_CPU0_SB_DQ<20>")
	)
	(gr_poly
		(pts
			(xy 328.716132 -225.115882) (xy 328.665332 -225.115882) (xy 328.563732 -225.152204) (xy 328.563732 -225.342704)
			(xy 328.665332 -225.379026) (xy 328.716132 -225.379026)
		)
		(stroke
			(width 0)
			(type solid)
		)
		(fill yes)
		(layer "F.Cu")
		(net "M_A_CPU0_SB_DQ<20>")
	)
	(gr_poly
		(pts
			(xy 328.71918 -289.181032) (xy 328.71918 -288.990532) (xy 328.61758 -288.95421) (xy 328.56678 -288.95421)
			(xy 328.56678 -289.2171) (xy 328.61758 -289.2171)
		)
		(stroke
			(width 0)
			(type solid)
		)
		(fill yes)
		(layer "F.Cu")
		(net "M_A_CPU0_SA_DQ<18>")
	)
	(gr_poly
		(pts
			(xy 328.71918 -288.584132) (xy 328.71918 -288.393632) (xy 328.61758 -288.35731) (xy 328.56678 -288.35731)
			(xy 328.56678 -288.6202) (xy 328.61758 -288.6202)
		)
		(stroke
			(width 0)
			(type solid)
		)
		(fill yes)
		(layer "F.Cu")
		(net "M_A_CPU0_SA_DQ<18>")
	)
	(gr_poly
		(pts
			(xy 328.71918 -287.987232) (xy 328.71918 -287.796732) (xy 328.61758 -287.76041) (xy 328.56678 -287.76041)
			(xy 328.56678 -288.0233) (xy 328.61758 -288.0233)
		)
		(stroke
			(width 0)
			(type solid)
		)
		(fill yes)
		(layer "F.Cu")
		(net "M_A_CPU0_SA_DQ<18>")
	)
	(gr_poly
		(pts
			(xy 328.71918 -287.390332) (xy 328.71918 -287.199832) (xy 328.61758 -287.16351) (xy 328.56678 -287.16351)
			(xy 328.56678 -287.4264) (xy 328.61758 -287.4264)
		)
		(stroke
			(width 0)
			(type solid)
		)
		(fill yes)
		(layer "F.Cu")
		(net "M_A_CPU0_SA_DQ<18>")
	)
	(gr_poly
		(pts
			(xy 328.71918 -286.793432) (xy 328.71918 -286.602932) (xy 328.61758 -286.56661) (xy 328.56678 -286.56661)
			(xy 328.56678 -286.8295) (xy 328.61758 -286.8295)
		)
		(stroke
			(width 0)
			(type solid)
		)
		(fill yes)
		(layer "F.Cu")
		(net "M_A_CPU0_SA_DQ<18>")
	)
	(gr_poly
		(pts
			(xy 328.71918 -286.196532) (xy 328.71918 -286.006032) (xy 328.61758 -285.96971) (xy 328.56678 -285.96971)
			(xy 328.56678 -286.2326) (xy 328.61758 -286.2326)
		)
		(stroke
			(width 0)
			(type solid)
		)
		(fill yes)
		(layer "F.Cu")
		(net "M_A_CPU0_SA_DQ<18>")
	)
	(gr_poly
		(pts
			(xy 328.71918 -285.599632) (xy 328.71918 -285.409132) (xy 328.61758 -285.37281) (xy 328.56678 -285.37281)
			(xy 328.56678 -285.6357) (xy 328.61758 -285.6357)
		)
		(stroke
			(width 0)
			(type solid)
		)
		(fill yes)
		(layer "F.Cu")
		(net "M_A_CPU0_SA_DQ<18>")
	)
	(gr_poly
		(pts
			(xy 328.71918 -285.002732) (xy 328.71918 -284.812232) (xy 328.61758 -284.77591) (xy 328.56678 -284.77591)
			(xy 328.56678 -285.0388) (xy 328.61758 -285.0388)
		)
		(stroke
			(width 0)
			(type solid)
		)
		(fill yes)
		(layer "F.Cu")
		(net "M_A_CPU0_SA_DQ<18>")
	)
	(gr_poly
		(pts
			(xy 328.71918 -284.405832) (xy 328.71918 -284.215332) (xy 328.61758 -284.17901) (xy 328.56678 -284.17901)
			(xy 328.56678 -284.4419) (xy 328.61758 -284.4419)
		)
		(stroke
			(width 0)
			(type solid)
		)
		(fill yes)
		(layer "F.Cu")
		(net "M_A_CPU0_SA_DQ<18>")
	)
	(gr_poly
		(pts
			(xy 328.71918 -283.808932) (xy 328.71918 -283.618432) (xy 328.61758 -283.58211) (xy 328.56678 -283.58211)
			(xy 328.56678 -283.845) (xy 328.61758 -283.845)
		)
		(stroke
			(width 0)
			(type solid)
		)
		(fill yes)
		(layer "F.Cu")
		(net "M_A_CPU0_SA_DQ<18>")
	)
	(gr_poly
		(pts
			(xy 328.71918 -283.212032) (xy 328.71918 -283.021532) (xy 328.61758 -282.98521) (xy 328.56678 -282.98521)
			(xy 328.56678 -283.2481) (xy 328.61758 -283.2481)
		)
		(stroke
			(width 0)
			(type solid)
		)
		(fill yes)
		(layer "F.Cu")
		(net "M_A_CPU0_SA_DQ<18>")
	)
	(gr_poly
		(pts
			(xy 328.71918 -282.615132) (xy 328.71918 -282.424632) (xy 328.61758 -282.38831) (xy 328.56678 -282.38831)
			(xy 328.56678 -282.6512) (xy 328.61758 -282.6512)
		)
		(stroke
			(width 0)
			(type solid)
		)
		(fill yes)
		(layer "F.Cu")
		(net "M_A_CPU0_SA_DQ<18>")
	)
	(gr_poly
		(pts
			(xy 328.721974 -259.415026) (xy 328.721974 -259.364226) (xy 328.459084 -259.364226) (xy 328.459084 -259.415026)
			(xy 328.495152 -259.516626) (xy 328.685652 -259.516626)
		)
		(stroke
			(width 0)
			(type solid)
		)
		(fill yes)
		(layer "F.Cu")
		(net "M_A_CPU0_SA_CS_N<2>")
	)
	(gr_poly
		(pts
			(xy 328.721974 -259.110226) (xy 328.721974 -259.059426) (xy 328.459084 -259.059426) (xy 328.459084 -259.110226)
			(xy 328.495152 -259.211826) (xy 328.685652 -259.211826)
		)
		(stroke
			(width 0)
			(type solid)
		)
		(fill yes)
		(layer "F.Cu")
		(net "M_A_CPU0_SA_CS_N<3>")
	)
	(gr_poly
		(pts
			(xy 328.721974 -258.805426) (xy 328.721974 -258.754626) (xy 328.459084 -258.754626) (xy 328.459084 -258.805426)
			(xy 328.495152 -258.907026) (xy 328.685652 -258.907026)
		)
		(stroke
			(width 0)
			(type solid)
		)
		(fill yes)
		(layer "F.Cu")
		(net "M_A_CPU0_SA_CS_N<1>")
	)
	(gr_poly
		(pts
			(xy 328.721974 -258.500626) (xy 328.721974 -258.449826) (xy 328.459084 -258.449826) (xy 328.459084 -258.500626)
			(xy 328.495152 -258.602226) (xy 328.685652 -258.602226)
		)
		(stroke
			(width 0)
			(type solid)
		)
		(fill yes)
		(layer "F.Cu")
		(net "M_A_CPU0_SA_CA<0>")
	)
	(gr_poly
		(pts
			(xy 328.721974 -258.195826) (xy 328.721974 -258.145026) (xy 328.459084 -258.145026) (xy 328.459084 -258.195826)
			(xy 328.495152 -258.297426) (xy 328.685652 -258.297426)
		)
		(stroke
			(width 0)
			(type solid)
		)
		(fill yes)
		(layer "F.Cu")
		(net "M_A_CPU0_SA_CA<1>")
	)
	(gr_poly
		(pts
			(xy 328.721974 -257.891026) (xy 328.721974 -257.840226) (xy 328.459084 -257.840226) (xy 328.459084 -257.891026)
			(xy 328.495152 -257.992626) (xy 328.685652 -257.992626)
		)
		(stroke
			(width 0)
			(type solid)
		)
		(fill yes)
		(layer "F.Cu")
		(net "M_A_CPU0_SA_CA<2>")
	)
	(gr_poly
		(pts
			(xy 328.721974 -257.586226) (xy 328.721974 -257.535426) (xy 328.459084 -257.535426) (xy 328.459084 -257.586226)
			(xy 328.495152 -257.687826) (xy 328.685652 -257.687826)
		)
		(stroke
			(width 0)
			(type solid)
		)
		(fill yes)
		(layer "F.Cu")
		(net "M_A_CPU0_SA_CA<3>")
	)
	(gr_poly
		(pts
			(xy 328.721974 -257.281426) (xy 328.721974 -257.230626) (xy 328.459084 -257.230626) (xy 328.459084 -257.281426)
			(xy 328.495152 -257.383026) (xy 328.685652 -257.383026)
		)
		(stroke
			(width 0)
			(type solid)
		)
		(fill yes)
		(layer "F.Cu")
		(net "M_A_CPU0_SA_CA<4>")
	)
	(gr_poly
		(pts
			(xy 328.721974 -256.976626) (xy 328.721974 -256.925826) (xy 328.459084 -256.925826) (xy 328.459084 -256.976626)
			(xy 328.495152 -257.078226) (xy 328.685652 -257.078226)
		)
		(stroke
			(width 0)
			(type solid)
		)
		(fill yes)
		(layer "F.Cu")
		(net "M_A_CPU0_SA_CA<5>")
	)
	(gr_poly
		(pts
			(xy 328.721974 -256.671826) (xy 328.721974 -256.621026) (xy 328.459084 -256.621026) (xy 328.459084 -256.671826)
			(xy 328.495152 -256.773426) (xy 328.685652 -256.773426)
		)
		(stroke
			(width 0)
			(type solid)
		)
		(fill yes)
		(layer "F.Cu")
		(net "M_A_CPU0_SA_CA<6>")
	)
	(gr_poly
		(pts
			(xy 328.721974 -256.367026) (xy 328.721974 -256.316226) (xy 328.459084 -256.316226) (xy 328.459084 -256.367026)
			(xy 328.495152 -256.468626) (xy 328.685652 -256.468626)
		)
		(stroke
			(width 0)
			(type solid)
		)
		(fill yes)
		(layer "F.Cu")
		(net "M_A_CPU0_SA_PAR")
	)
	(gr_poly
		(pts
			(xy 328.722228 -230.000048) (xy 328.768456 -229.902512) (xy 328.633836 -229.767892) (xy 328.5363 -229.81412)
			(xy 328.500486 -229.850188) (xy 328.68616 -230.035862)
		)
		(stroke
			(width 0)
			(type solid)
		)
		(fill yes)
		(layer "F.Cu")
		(net "M_A_CPU0_SB_DQ<16>")
	)
	(gr_poly
		(pts
			(xy 328.72299 -274.532852) (xy 328.676762 -274.435316) (xy 328.640948 -274.399502) (xy 328.45502 -274.58543)
			(xy 328.490834 -274.621244) (xy 328.58837 -274.667472)
		)
		(stroke
			(width 0)
			(type solid)
		)
		(fill yes)
		(layer "F.Cu")
		(net "M_A_CPU0_SA_DQ<23>")
	)
	(gr_poly
		(pts
			(xy 328.731372 -229.146608) (xy 328.7776 -229.049326) (xy 328.64298 -228.914452) (xy 328.545444 -228.96068)
			(xy 328.50963 -228.996748) (xy 328.695558 -229.182676)
		)
		(stroke
			(width 0)
			(type solid)
		)
		(fill yes)
		(layer "F.Cu")
		(net "M_A_CPU0_SB_DQ<17>")
	)
	(gr_poly
		(pts
			(xy 328.732388 -275.386292) (xy 328.68616 -275.28901) (xy 328.650346 -275.252942) (xy 328.464418 -275.43887)
			(xy 328.500232 -275.474684) (xy 328.597768 -275.521166)
		)
		(stroke
			(width 0)
			(type solid)
		)
		(fill yes)
		(layer "F.Cu")
		(net "M_A_CPU0_SA_DQ<22>")
	)
	(gr_poly
		(pts
			(xy 328.744326 -280.09088) (xy 328.781664 -279.90419) (xy 328.688954 -279.848818) (xy 328.63917 -279.838658)
			(xy 328.587608 -280.096468) (xy 328.637392 -280.106374)
		)
		(stroke
			(width 0)
			(type solid)
		)
		(fill yes)
		(layer "F.Cu")
		(net "M_A_CPU0_SA_DQ<17>")
	)
	(gr_poly
		(pts
			(xy 328.762614 -280.776426) (xy 328.71283 -280.76652) (xy 328.60615 -280.782014) (xy 328.568812 -280.968958)
			(xy 328.661268 -281.02433) (xy 328.711052 -281.034236)
		)
		(stroke
			(width 0)
			(type solid)
		)
		(fill yes)
		(layer "F.Cu")
		(net "M_A_CPU0_SA_DQ<18>")
	)
	(gr_poly
		(pts
			(xy 328.763376 -261.766558) (xy 328.717148 -261.669276) (xy 328.681334 -261.633208) (xy 328.495406 -261.819136)
			(xy 328.53122 -261.855204) (xy 328.628756 -261.901432)
		)
		(stroke
			(width 0)
			(type solid)
		)
		(fill yes)
		(layer "F.Cu")
		(net "M_A_CPU0_SA_CB<7>")
	)
	(gr_poly
		(pts
			(xy 328.772012 -268.634464) (xy 328.736198 -268.59865) (xy 328.638662 -268.552168) (xy 328.504042 -268.687042)
			(xy 328.55027 -268.784324) (xy 328.586084 -268.820392)
		)
		(stroke
			(width 0)
			(type solid)
		)
		(fill yes)
		(layer "F.Cu")
		(net "M_A_CPU0_SA_DQ<31>")
	)
	(gr_poly
		(pts
			(xy 328.773028 -262.620252) (xy 328.726546 -262.522716) (xy 328.690732 -262.486902) (xy 328.504804 -262.67283)
			(xy 328.540872 -262.708644) (xy 328.638154 -262.754872)
		)
		(stroke
			(width 0)
			(type solid)
		)
		(fill yes)
		(layer "F.Cu")
		(net "M_A_CPU0_SA_CB<6>")
	)
	(gr_poly
		(pts
			(xy 328.7776 -272.296636) (xy 328.731372 -272.199354) (xy 328.695558 -272.163286) (xy 328.50963 -272.349214)
			(xy 328.545444 -272.385282) (xy 328.64298 -272.43151)
		)
		(stroke
			(width 0)
			(type solid)
		)
		(fill yes)
		(layer "F.Cu")
		(net "M_A_CPU0_SA_DQ<27>")
	)
	(gr_poly
		(pts
			(xy 328.777854 -265.203178) (xy 328.731626 -265.105896) (xy 328.695812 -265.069828) (xy 328.509884 -265.255756)
			(xy 328.545698 -265.29157) (xy 328.643234 -265.337798)
		)
		(stroke
			(width 0)
			(type solid)
		)
		(fill yes)
		(layer "F.Cu")
		(net "M_A_CPU0_SA_CB<3>")
	)
	(gr_poly
		(pts
			(xy 328.781664 -269.488412) (xy 328.74585 -269.452344) (xy 328.648314 -269.406116) (xy 328.513694 -269.540736)
			(xy 328.559922 -269.638272) (xy 328.595736 -269.67434)
		)
		(stroke
			(width 0)
			(type solid)
		)
		(fill yes)
		(layer "F.Cu")
		(net "M_A_CPU0_SA_DQ<30>")
	)
	(gr_poly
		(pts
			(xy 328.786998 -273.15033) (xy 328.74077 -273.053048) (xy 328.704956 -273.01698) (xy 328.519028 -273.202908)
			(xy 328.554842 -273.238722) (xy 328.652378 -273.28495)
		)
		(stroke
			(width 0)
			(type solid)
		)
		(fill yes)
		(layer "F.Cu")
		(net "M_A_CPU0_SA_DQ<26>")
	)
	(gr_poly
		(pts
			(xy 328.787252 -266.056618) (xy 328.741024 -265.959336) (xy 328.70521 -265.923268) (xy 328.519282 -266.109196)
			(xy 328.555096 -266.145264) (xy 328.652632 -266.191492)
		)
		(stroke
			(width 0)
			(type solid)
		)
		(fill yes)
		(layer "F.Cu")
		(net "M_A_CPU0_SA_CB<2>")
	)
	(gr_poly
		(pts
			(xy 328.795126 -235.809028) (xy 328.83094 -235.773214) (xy 328.645012 -235.587286) (xy 328.609198 -235.623354)
			(xy 328.56297 -235.720636) (xy 328.69759 -235.855256)
		)
		(stroke
			(width 0)
			(type solid)
		)
		(fill yes)
		(layer "F.Cu")
		(net "M_A_CPU0_SB_DQ<8>")
	)
	(gr_poly
		(pts
			(xy 328.80427 -234.955842) (xy 328.840084 -234.919774) (xy 328.654156 -234.733846) (xy 328.618342 -234.769914)
			(xy 328.572114 -234.867196) (xy 328.706734 -235.00207)
		)
		(stroke
			(width 0)
			(type solid)
		)
		(fill yes)
		(layer "F.Cu")
		(net "M_A_CPU0_SB_DQ<9>")
	)
	(gr_poly
		(pts
			(xy 328.809096 -281.321256) (xy 328.846434 -281.134566) (xy 328.753978 -281.079194) (xy 328.704194 -281.069288)
			(xy 328.652632 -281.326844) (xy 328.702416 -281.337004)
		)
		(stroke
			(width 0)
			(type solid)
		)
		(fill yes)
		(layer "F.Cu")
		(net "M_A_CPU0_SA_DQ<18>")
	)
	(gr_poly
		(pts
			(xy 328.814684 -278.960834) (xy 328.7649 -278.950928) (xy 328.65822 -278.966422) (xy 328.620882 -279.153112)
			(xy 328.713338 -279.208484) (xy 328.763122 -279.218644)
		)
		(stroke
			(width 0)
			(type solid)
		)
		(fill yes)
		(layer "F.Cu")
		(net "M_A_CPU0_SA_DQ<17>")
	)
	(gr_poly
		(pts
			(xy 328.819256 -224.220024) (xy 328.85507 -224.183956) (xy 328.669396 -223.998282) (xy 328.633328 -224.034096)
			(xy 328.5871 -224.131632) (xy 328.72172 -224.266252)
		)
		(stroke
			(width 0)
			(type solid)
		)
		(fill yes)
		(layer "F.Cu")
		(net "M_A_CPU0_SB_DQ<22>")
	)
	(gr_poly
		(pts
			(xy 328.8284 -223.366584) (xy 328.864468 -223.33077) (xy 328.67854 -223.144842) (xy 328.642726 -223.180656)
			(xy 328.596244 -223.278192) (xy 328.731118 -223.412812)
		)
		(stroke
			(width 0)
			(type solid)
		)
		(fill yes)
		(layer "F.Cu")
		(net "M_A_CPU0_SB_DQ<23>")
	)
	(gr_poly
		(pts
			(xy 328.830686 -277.982426) (xy 328.785982 -277.95855) (xy 328.679302 -277.942294) (xy 328.589386 -278.110442)
			(xy 328.661776 -278.190198) (xy 328.70648 -278.214074)
		)
		(stroke
			(width 0)
			(type solid)
		)
		(fill yes)
		(layer "F.Cu")
		(net "M_A_CPU0_SA_DQ<19>")
	)
	(gr_poly
		(pts
			(xy 328.842116 -232.405682) (xy 328.87793 -232.369868) (xy 328.692002 -232.18394) (xy 328.656188 -232.220008)
			(xy 328.60996 -232.31729) (xy 328.74458 -232.452164)
		)
		(stroke
			(width 0)
			(type solid)
		)
		(fill yes)
		(layer "F.Cu")
		(net "M_A_CPU0_SB_DQ<12>")
	)
	(gr_poly
		(pts
			(xy 328.85126 -231.552242) (xy 328.887328 -231.516428) (xy 328.7014 -231.3305) (xy 328.665586 -231.366314)
			(xy 328.619104 -231.46385) (xy 328.753978 -231.59847)
		)
		(stroke
			(width 0)
			(type solid)
		)
		(fill yes)
		(layer "F.Cu")
		(net "M_A_CPU0_SB_DQ<13>")
	)
	(gr_poly
		(pts
			(xy 328.852022 -274.188428) (xy 328.815954 -274.152614) (xy 328.718672 -274.106386) (xy 328.584052 -274.241006)
			(xy 328.63028 -274.338288) (xy 328.666094 -274.374356)
		)
		(stroke
			(width 0)
			(type solid)
		)
		(fill yes)
		(layer "F.Cu")
		(net "M_A_CPU0_SA_DQ<23>")
	)
	(gr_poly
		(pts
			(xy 328.85888 -269.194534) (xy 328.812652 -269.097252) (xy 328.776838 -269.061184) (xy 328.59091 -269.247112)
			(xy 328.626724 -269.28318) (xy 328.72426 -269.329408)
		)
		(stroke
			(width 0)
			(type solid)
		)
		(fill yes)
		(layer "F.Cu")
		(net "M_A_CPU0_SA_DQ<29>")
	)
	(gr_poly
		(pts
			(xy 328.861166 -279.505664) (xy 328.898504 -279.31872) (xy 328.806048 -279.263348) (xy 328.756264 -279.253442)
			(xy 328.704702 -279.511252) (xy 328.754486 -279.521158)
		)
		(stroke
			(width 0)
			(type solid)
		)
		(fill yes)
		(layer "F.Cu")
		(net "M_A_CPU0_SA_DQ<17>")
	)
	(gr_poly
		(pts
			(xy 328.86142 -275.041868) (xy 328.825352 -275.006054) (xy 328.72807 -274.959826) (xy 328.593196 -275.094446)
			(xy 328.639424 -275.191982) (xy 328.675492 -275.227796)
		)
		(stroke
			(width 0)
			(type solid)
		)
		(fill yes)
		(layer "F.Cu")
		(net "M_A_CPU0_SA_DQ<22>")
	)
	(gr_poly
		(pts
			(xy 328.86142 -230.283004) (xy 328.897234 -230.246936) (xy 328.711306 -230.061008) (xy 328.675492 -230.097076)
			(xy 328.629264 -230.194358) (xy 328.763884 -230.329232)
		)
		(stroke
			(width 0)
			(type solid)
		)
		(fill yes)
		(layer "F.Cu")
		(net "M_A_CPU0_SB_DQ<16>")
	)
	(gr_poly
		(pts
			(xy 328.868532 -270.048482) (xy 328.822304 -269.950946) (xy 328.786236 -269.915132) (xy 328.600562 -270.100806)
			(xy 328.636376 -270.136874) (xy 328.733912 -270.183102)
		)
		(stroke
			(width 0)
			(type solid)
		)
		(fill yes)
		(layer "F.Cu")
		(net "M_A_CPU0_SA_DQ<28>")
	)
	(gr_poly
		(pts
			(xy 328.868532 -226.238054) (xy 328.868532 -226.047554) (xy 328.766932 -226.011486) (xy 328.716132 -226.011486)
			(xy 328.716132 -226.274122) (xy 328.766932 -226.274122)
		)
		(stroke
			(width 0)
			(type solid)
		)
		(fill yes)
		(layer "F.Cu")
		(net "M_A_CPU0_SB_DQ<20>")
	)
	(gr_poly
		(pts
			(xy 328.868532 -225.641154) (xy 328.868532 -225.450654) (xy 328.766932 -225.414586) (xy 328.716132 -225.414586)
			(xy 328.716132 -225.677222) (xy 328.766932 -225.677222)
		)
		(stroke
			(width 0)
			(type solid)
		)
		(fill yes)
		(layer "F.Cu")
		(net "M_A_CPU0_SB_DQ<20>")
	)
	(gr_poly
		(pts
			(xy 328.868532 -225.044254) (xy 328.868532 -224.853754) (xy 328.766932 -224.817686) (xy 328.716132 -224.817686)
			(xy 328.716132 -225.080322) (xy 328.766932 -225.080322)
		)
		(stroke
			(width 0)
			(type solid)
		)
		(fill yes)
		(layer "F.Cu")
		(net "M_A_CPU0_SB_DQ<20>")
	)
	(gr_poly
		(pts
			(xy 328.870564 -229.429564) (xy 328.906632 -229.39375) (xy 328.720704 -229.207822) (xy 328.684636 -229.243636)
			(xy 328.638408 -229.341172) (xy 328.773282 -229.475792)
		)
		(stroke
			(width 0)
			(type solid)
		)
		(fill yes)
		(layer "F.Cu")
		(net "M_A_CPU0_SB_DQ<17>")
	)
	(gr_poly
		(pts
			(xy 328.87158 -289.25266) (xy 328.82078 -289.25266) (xy 328.71918 -289.288982) (xy 328.71918 -289.479482)
			(xy 328.82078 -289.51555) (xy 328.87158 -289.51555)
		)
		(stroke
			(width 0)
			(type solid)
		)
		(fill yes)
		(layer "F.Cu")
		(net "M_A_CPU0_SA_DQ<16>")
	)
	(gr_poly
		(pts
			(xy 328.87158 -288.65576) (xy 328.82078 -288.65576) (xy 328.71918 -288.692082) (xy 328.71918 -288.882582)
			(xy 328.82078 -288.91865) (xy 328.87158 -288.91865)
		)
		(stroke
			(width 0)
			(type solid)
		)
		(fill yes)
		(layer "F.Cu")
		(net "M_A_CPU0_SA_DQ<16>")
	)
	(gr_poly
		(pts
			(xy 328.87158 -288.05886) (xy 328.82078 -288.05886) (xy 328.71918 -288.095182) (xy 328.71918 -288.285682)
			(xy 328.82078 -288.32175) (xy 328.87158 -288.32175)
		)
		(stroke
			(width 0)
			(type solid)
		)
		(fill yes)
		(layer "F.Cu")
		(net "M_A_CPU0_SA_DQ<16>")
	)
	(gr_poly
		(pts
			(xy 328.87158 -287.46196) (xy 328.82078 -287.46196) (xy 328.71918 -287.498282) (xy 328.71918 -287.688782)
			(xy 328.82078 -287.72485) (xy 328.87158 -287.72485)
		)
		(stroke
			(width 0)
			(type solid)
		)
		(fill yes)
		(layer "F.Cu")
		(net "M_A_CPU0_SA_DQ<16>")
	)
	(gr_poly
		(pts
			(xy 328.87158 -286.86506) (xy 328.82078 -286.86506) (xy 328.71918 -286.901382) (xy 328.71918 -287.091882)
			(xy 328.82078 -287.12795) (xy 328.87158 -287.12795)
		)
		(stroke
			(width 0)
			(type solid)
		)
		(fill yes)
		(layer "F.Cu")
		(net "M_A_CPU0_SA_DQ<16>")
	)
	(gr_poly
		(pts
			(xy 328.87158 -286.26816) (xy 328.82078 -286.26816) (xy 328.71918 -286.304482) (xy 328.71918 -286.494982)
			(xy 328.82078 -286.53105) (xy 328.87158 -286.53105)
		)
		(stroke
			(width 0)
			(type solid)
		)
		(fill yes)
		(layer "F.Cu")
		(net "M_A_CPU0_SA_DQ<16>")
	)
	(gr_poly
		(pts
			(xy 328.87158 -285.67126) (xy 328.82078 -285.67126) (xy 328.71918 -285.707582) (xy 328.71918 -285.898082)
			(xy 328.82078 -285.93415) (xy 328.87158 -285.93415)
		)
		(stroke
			(width 0)
			(type solid)
		)
		(fill yes)
		(layer "F.Cu")
		(net "M_A_CPU0_SA_DQ<16>")
	)
	(gr_poly
		(pts
			(xy 328.87158 -285.07436) (xy 328.82078 -285.07436) (xy 328.71918 -285.110682) (xy 328.71918 -285.301182)
			(xy 328.82078 -285.33725) (xy 328.87158 -285.33725)
		)
		(stroke
			(width 0)
			(type solid)
		)
		(fill yes)
		(layer "F.Cu")
		(net "M_A_CPU0_SA_DQ<16>")
	)
	(gr_poly
		(pts
			(xy 328.87158 -284.47746) (xy 328.82078 -284.47746) (xy 328.71918 -284.513782) (xy 328.71918 -284.704282)
			(xy 328.82078 -284.74035) (xy 328.87158 -284.74035)
		)
		(stroke
			(width 0)
			(type solid)
		)
		(fill yes)
		(layer "F.Cu")
		(net "M_A_CPU0_SA_DQ<16>")
	)
	(gr_poly
		(pts
			(xy 328.87158 -283.88056) (xy 328.82078 -283.88056) (xy 328.71918 -283.916882) (xy 328.71918 -284.107382)
			(xy 328.82078 -284.14345) (xy 328.87158 -284.14345)
		)
		(stroke
			(width 0)
			(type solid)
		)
		(fill yes)
		(layer "F.Cu")
		(net "M_A_CPU0_SA_DQ<16>")
	)
	(gr_poly
		(pts
			(xy 328.87158 -283.28366) (xy 328.82078 -283.28366) (xy 328.71918 -283.319982) (xy 328.71918 -283.510482)
			(xy 328.82078 -283.54655) (xy 328.87158 -283.54655)
		)
		(stroke
			(width 0)
			(type solid)
		)
		(fill yes)
		(layer "F.Cu")
		(net "M_A_CPU0_SA_DQ<16>")
	)
	(gr_poly
		(pts
			(xy 328.87158 -282.68676) (xy 328.82078 -282.68676) (xy 328.71918 -282.723082) (xy 328.71918 -282.913582)
			(xy 328.82078 -282.94965) (xy 328.87158 -282.94965)
		)
		(stroke
			(width 0)
			(type solid)
		)
		(fill yes)
		(layer "F.Cu")
		(net "M_A_CPU0_SA_DQ<16>")
	)
	(gr_poly
		(pts
			(xy 328.87158 -282.08986) (xy 328.82078 -282.08986) (xy 328.71918 -282.126182) (xy 328.71918 -282.316682)
			(xy 328.82078 -282.35275) (xy 328.87158 -282.35275)
		)
		(stroke
			(width 0)
			(type solid)
		)
		(fill yes)
		(layer "F.Cu")
		(net "M_A_CPU0_SA_DQ<16>")
	)
	(gr_poly
		(pts
			(xy 328.87158 -235.31068) (xy 328.917808 -235.213144) (xy 328.782934 -235.078524) (xy 328.685652 -235.124752)
			(xy 328.649584 -235.160566) (xy 328.835512 -235.346494)
		)
		(stroke
			(width 0)
			(type solid)
		)
		(fill yes)
		(layer "F.Cu")
		(net "M_A_CPU0_SB_DQ<10>")
	)
	(gr_poly
		(pts
			(xy 328.879708 -280.19121) (xy 328.829924 -280.181304) (xy 328.723244 -280.196798) (xy 328.685906 -280.383742)
			(xy 328.778362 -280.439114) (xy 328.828146 -280.44902)
		)
		(stroke
			(width 0)
			(type solid)
		)
		(fill yes)
		(layer "F.Cu")
		(net "M_A_CPU0_SA_DQ<18>")
	)
	(gr_poly
		(pts
			(xy 328.880724 -234.45724) (xy 328.926952 -234.359704) (xy 328.792332 -234.225084) (xy 328.694796 -234.271312)
			(xy 328.658982 -234.30738) (xy 328.844656 -234.493054)
		)
		(stroke
			(width 0)
			(type solid)
		)
		(fill yes)
		(layer "F.Cu")
		(net "M_A_CPU0_SB_DQ<11>")
	)
	(gr_poly
		(pts
			(xy 328.892408 -261.422134) (xy 328.85634 -261.38632) (xy 328.759058 -261.340092) (xy 328.624184 -261.474712)
			(xy 328.670412 -261.572248) (xy 328.70648 -261.608062)
		)
		(stroke
			(width 0)
			(type solid)
		)
		(fill yes)
		(layer "F.Cu")
		(net "M_A_CPU0_SA_CB<7>")
	)
	(gr_poly
		(pts
			(xy 328.89571 -223.721422) (xy 328.941938 -223.62414) (xy 328.807318 -223.489266) (xy 328.709782 -223.535494)
			(xy 328.673968 -223.571562) (xy 328.859896 -223.75749)
		)
		(stroke
			(width 0)
			(type solid)
		)
		(fill yes)
		(layer "F.Cu")
		(net "M_A_CPU0_SB_DQ<21>")
	)
	(gr_poly
		(pts
			(xy 328.901806 -262.275828) (xy 328.865738 -262.240014) (xy 328.768456 -262.193786) (xy 328.633836 -262.328406)
			(xy 328.680064 -262.425942) (xy 328.715878 -262.461756)
		)
		(stroke
			(width 0)
			(type solid)
		)
		(fill yes)
		(layer "F.Cu")
		(net "M_A_CPU0_SA_CB<6>")
	)
	(gr_poly
		(pts
			(xy 328.906378 -271.952466) (xy 328.870564 -271.916398) (xy 328.773028 -271.87017) (xy 328.638408 -272.00479)
			(xy 328.684636 -272.102326) (xy 328.720704 -272.13814)
		)
		(stroke
			(width 0)
			(type solid)
		)
		(fill yes)
		(layer "F.Cu")
		(net "M_A_CPU0_SA_DQ<27>")
	)
	(gr_poly
		(pts
			(xy 328.906886 -264.858754) (xy 328.870818 -264.82294) (xy 328.773536 -264.776712) (xy 328.638662 -264.911332)
			(xy 328.68489 -265.008868) (xy 328.720958 -265.044682)
		)
		(stroke
			(width 0)
			(type solid)
		)
		(fill yes)
		(layer "F.Cu")
		(net "M_A_CPU0_SA_CB<3>")
	)
	(gr_poly
		(pts
			(xy 328.91603 -272.805906) (xy 328.879962 -272.770092) (xy 328.78268 -272.723864) (xy 328.647806 -272.858484)
			(xy 328.694034 -272.95602) (xy 328.730102 -272.991834)
		)
		(stroke
			(width 0)
			(type solid)
		)
		(fill yes)
		(layer "F.Cu")
		(net "M_A_CPU0_SA_DQ<26>")
	)
	(gr_poly
		(pts
			(xy 328.916284 -265.712194) (xy 328.880216 -265.67638) (xy 328.782934 -265.630152) (xy 328.64806 -265.764772)
			(xy 328.694288 -265.862308) (xy 328.730356 -265.898122)
		)
		(stroke
			(width 0)
			(type solid)
		)
		(fill yes)
		(layer "F.Cu")
		(net "M_A_CPU0_SA_CB<2>")
	)
	(gr_poly
		(pts
			(xy 328.91857 -231.90708) (xy 328.964798 -231.809798) (xy 328.830178 -231.674924) (xy 328.732642 -231.721152)
			(xy 328.696828 -231.75722) (xy 328.882756 -231.943148)
		)
		(stroke
			(width 0)
			(type solid)
		)
		(fill yes)
		(layer "F.Cu")
		(net "M_A_CPU0_SB_DQ<14>")
	)
	(gr_poly
		(pts
			(xy 328.92619 -280.73604) (xy 328.963528 -280.549096) (xy 328.871072 -280.493724) (xy 328.821288 -280.483818)
			(xy 328.769726 -280.741628) (xy 328.81951 -280.751534)
		)
		(stroke
			(width 0)
			(type solid)
		)
		(fill yes)
		(layer "F.Cu")
		(net "M_A_CPU0_SA_DQ<18>")
	)
	(gr_poly
		(pts
			(xy 328.927714 -231.053894) (xy 328.973942 -230.956358) (xy 328.839322 -230.821738) (xy 328.74204 -230.867966)
			(xy 328.705972 -230.90378) (xy 328.8919 -231.089708)
		)
		(stroke
			(width 0)
			(type solid)
		)
		(fill yes)
		(layer "F.Cu")
		(net "M_A_CPU0_SB_DQ<15>")
	)
	(gr_poly
		(pts
			(xy 328.937874 -229.784402) (xy 328.984102 -229.686866) (xy 328.849482 -229.552246) (xy 328.751946 -229.598474)
			(xy 328.716132 -229.634542) (xy 328.901806 -229.820216)
		)
		(stroke
			(width 0)
			(type solid)
		)
		(fill yes)
		(layer "F.Cu")
		(net "M_A_CPU0_SB_DQ<18>")
	)
	(gr_poly
		(pts
			(xy 328.93889 -274.748498) (xy 328.892662 -274.651216) (xy 328.856594 -274.615148) (xy 328.670666 -274.801076)
			(xy 328.706734 -274.83689) (xy 328.804016 -274.883372)
		)
		(stroke
			(width 0)
			(type solid)
		)
		(fill yes)
		(layer "F.Cu")
		(net "M_A_CPU0_SA_DQ<21>")
	)
	(gr_poly
		(pts
			(xy 328.947018 -228.930962) (xy 328.993246 -228.83368) (xy 328.858626 -228.698806) (xy 328.76109 -228.745034)
			(xy 328.725276 -228.781102) (xy 328.911204 -228.96703)
		)
		(stroke
			(width 0)
			(type solid)
		)
		(fill yes)
		(layer "F.Cu")
		(net "M_A_CPU0_SB_DQ<19>")
	)
	(gr_poly
		(pts
			(xy 328.948796 -275.6027) (xy 328.902568 -275.505418) (xy 328.8665 -275.46935) (xy 328.680826 -275.655278)
			(xy 328.71664 -275.691346) (xy 328.814176 -275.737574)
		)
		(stroke
			(width 0)
			(type solid)
		)
		(fill yes)
		(layer "F.Cu")
		(net "M_A_CPU0_SA_DQ<20>")
	)
	(gr_poly
		(pts
			(xy 328.97826 -278.920194) (xy 329.015598 -278.733504) (xy 328.923142 -278.678132) (xy 328.873104 -278.667972)
			(xy 328.821796 -278.925782) (xy 328.87158 -278.935942)
		)
		(stroke
			(width 0)
			(type solid)
		)
		(fill yes)
		(layer "F.Cu")
		(net "M_A_CPU0_SA_DQ<17>")
	)
	(gr_poly
		(pts
			(xy 328.979276 -261.982458) (xy 328.933048 -261.884922) (xy 328.89698 -261.849108) (xy 328.711052 -262.035036)
			(xy 328.74712 -262.07085) (xy 328.844402 -262.117078)
		)
		(stroke
			(width 0)
			(type solid)
		)
		(fill yes)
		(layer "F.Cu")
		(net "M_A_CPU0_SA_CB<5>")
	)
	(gr_poly
		(pts
			(xy 328.987658 -249.371866) (xy 328.987658 -249.321066) (xy 328.724768 -249.321066) (xy 328.724768 -249.371866)
			(xy 328.760836 -249.473466) (xy 328.951336 -249.473466)
		)
		(stroke
			(width 0)
			(type solid)
		)
		(fill yes)
		(layer "F.Cu")
		(net "M_A_CPU0_SB_CA<0>")
	)
	(gr_poly
		(pts
			(xy 328.987658 -249.066812) (xy 328.987658 -249.016012) (xy 328.724768 -249.016012) (xy 328.724768 -249.066812)
			(xy 328.760836 -249.168412) (xy 328.951336 -249.168412)
		)
		(stroke
			(width 0)
			(type solid)
		)
		(fill yes)
		(layer "F.Cu")
		(net "M_A_CPU0_SB_CA<1>")
	)
	(gr_poly
		(pts
			(xy 328.987658 -248.762012) (xy 328.987658 -248.711212) (xy 328.724768 -248.711212) (xy 328.724768 -248.762012)
			(xy 328.760836 -248.863612) (xy 328.951336 -248.863612)
		)
		(stroke
			(width 0)
			(type solid)
		)
		(fill yes)
		(layer "F.Cu")
		(net "M_A_CPU0_SB_CA<2>")
	)
	(gr_poly
		(pts
			(xy 328.987658 -248.457212) (xy 328.987658 -248.406412) (xy 328.724768 -248.406412) (xy 328.724768 -248.457212)
			(xy 328.760836 -248.558812) (xy 328.951336 -248.558812)
		)
		(stroke
			(width 0)
			(type solid)
		)
		(fill yes)
		(layer "F.Cu")
		(net "M_A_CPU0_SB_CA<3>")
	)
	(gr_poly
		(pts
			(xy 328.987658 -248.152412) (xy 328.987658 -248.101612) (xy 328.724768 -248.101612) (xy 328.724768 -248.152412)
			(xy 328.760836 -248.254012) (xy 328.951336 -248.254012)
		)
		(stroke
			(width 0)
			(type solid)
		)
		(fill yes)
		(layer "F.Cu")
		(net "M_A_CPU0_SB_CA<4>")
	)
	(gr_poly
		(pts
			(xy 328.987658 -247.847612) (xy 328.987658 -247.796812) (xy 328.724768 -247.796812) (xy 328.724768 -247.847612)
			(xy 328.760836 -247.949212) (xy 328.951336 -247.949212)
		)
		(stroke
			(width 0)
			(type solid)
		)
		(fill yes)
		(layer "F.Cu")
		(net "M_A_CPU0_SB_CA<5>")
	)
	(gr_poly
		(pts
			(xy 328.987658 -247.542812) (xy 328.987658 -247.492012) (xy 328.724768 -247.492012) (xy 328.724768 -247.542812)
			(xy 328.760836 -247.644412) (xy 328.951336 -247.644412)
		)
		(stroke
			(width 0)
			(type solid)
		)
		(fill yes)
		(layer "F.Cu")
		(net "M_A_CPU0_SB_CA<6>")
	)
	(gr_poly
		(pts
			(xy 328.987658 -247.238012) (xy 328.987658 -247.187212) (xy 328.724768 -247.187212) (xy 328.724768 -247.238012)
			(xy 328.760836 -247.339612) (xy 328.951336 -247.339612)
		)
		(stroke
			(width 0)
			(type solid)
		)
		(fill yes)
		(layer "F.Cu")
		(net "M_A_CPU0_SB_PAR")
	)
	(gr_poly
		(pts
			(xy 328.987912 -268.85011) (xy 328.951844 -268.814296) (xy 328.854562 -268.768068) (xy 328.719688 -268.902688)
			(xy 328.765916 -269.000224) (xy 328.801984 -269.036038)
		)
		(stroke
			(width 0)
			(type solid)
		)
		(fill yes)
		(layer "F.Cu")
		(net "M_A_CPU0_SA_DQ<29>")
	)
	(gr_poly
		(pts
			(xy 328.988674 -262.835898) (xy 328.942446 -262.738616) (xy 328.906632 -262.702548) (xy 328.720704 -262.888476)
			(xy 328.756518 -262.924544) (xy 328.854054 -262.970772)
		)
		(stroke
			(width 0)
			(type solid)
		)
		(fill yes)
		(layer "F.Cu")
		(net "M_A_CPU0_SA_CB<4>")
	)
	(gr_poly
		(pts
			(xy 328.9935 -272.512536) (xy 328.947272 -272.415254) (xy 328.911458 -272.379186) (xy 328.72553 -272.565114)
			(xy 328.761344 -272.601182) (xy 328.85888 -272.64741)
		)
		(stroke
			(width 0)
			(type solid)
		)
		(fill yes)
		(layer "F.Cu")
		(net "M_A_CPU0_SA_DQ<25>")
	)
	(gr_poly
		(pts
			(xy 328.9935 -265.418824) (xy 328.947272 -265.321542) (xy 328.911458 -265.285474) (xy 328.72553 -265.471402)
			(xy 328.761344 -265.507216) (xy 328.85888 -265.553444)
		)
		(stroke
			(width 0)
			(type solid)
		)
		(fill yes)
		(layer "F.Cu")
		(net "M_A_CPU0_SA_CB<1>")
	)
	(gr_poly
		(pts
			(xy 328.996802 -279.605994) (xy 328.947018 -279.595834) (xy 328.840338 -279.611582) (xy 328.803 -279.798272)
			(xy 328.895456 -279.853644) (xy 328.94524 -279.86355)
		)
		(stroke
			(width 0)
			(type solid)
		)
		(fill yes)
		(layer "F.Cu")
		(net "M_A_CPU0_SA_DQ<18>")
	)
	(gr_poly
		(pts
			(xy 328.99731 -269.704058) (xy 328.961496 -269.66799) (xy 328.86396 -269.621762) (xy 328.72934 -269.756382)
			(xy 328.775568 -269.853918) (xy 328.811382 -269.889986)
		)
		(stroke
			(width 0)
			(type solid)
		)
		(fill yes)
		(layer "F.Cu")
		(net "M_A_CPU0_SA_DQ<28>")
	)
	(gr_poly
		(pts
			(xy 329.002644 -273.365976) (xy 328.956416 -273.268694) (xy 328.920602 -273.232626) (xy 328.734674 -273.418554)
			(xy 328.770488 -273.454368) (xy 328.868024 -273.500596)
		)
		(stroke
			(width 0)
			(type solid)
		)
		(fill yes)
		(layer "F.Cu")
		(net "M_A_CPU0_SA_DQ<24>")
	)
	(gr_poly
		(pts
			(xy 329.002898 -266.272264) (xy 328.95667 -266.174982) (xy 328.920856 -266.138914) (xy 328.734928 -266.324842)
			(xy 328.770742 -266.36091) (xy 328.868278 -266.407138)
		)
		(stroke
			(width 0)
			(type solid)
		)
		(fill yes)
		(layer "F.Cu")
		(net "M_A_CPU0_SA_CB<0>")
	)
	(gr_poly
		(pts
			(xy 329.010772 -235.593382) (xy 329.046586 -235.557568) (xy 328.860658 -235.37164) (xy 328.824844 -235.407708)
			(xy 328.778616 -235.50499) (xy 328.913236 -235.63961)
		)
		(stroke
			(width 0)
			(type solid)
		)
		(fill yes)
		(layer "F.Cu")
		(net "M_A_CPU0_SB_DQ<10>")
	)
	(gr_poly
		(pts
			(xy 329.019916 -234.740196) (xy 329.05573 -234.704128) (xy 328.869802 -234.5182) (xy 328.833988 -234.554268)
			(xy 328.78776 -234.65155) (xy 328.92238 -234.786424)
		)
		(stroke
			(width 0)
			(type solid)
		)
		(fill yes)
		(layer "F.Cu")
		(net "M_A_CPU0_SB_DQ<11>")
	)
	(gr_poly
		(pts
			(xy 329.020424 -259.618226) (xy 328.984356 -259.516626) (xy 328.793856 -259.516626) (xy 328.757534 -259.618226)
			(xy 328.757534 -259.669026) (xy 329.020424 -259.669026)
		)
		(stroke
			(width 0)
			(type solid)
		)
		(fill yes)
		(layer "F.Cu")
		(net "M_A_CPU0_SA_CS_N<0>")
	)
	(gr_poly
		(pts
			(xy 329.020424 -259.313426) (xy 328.984356 -259.211826) (xy 328.793856 -259.211826) (xy 328.757534 -259.313426)
			(xy 328.757534 -259.364226) (xy 329.020424 -259.364226)
		)
		(stroke
			(width 0)
			(type solid)
		)
		(fill yes)
		(layer "F.Cu")
		(net "M_A_CPU0_SA_CS_N<2>")
	)
	(gr_poly
		(pts
			(xy 329.020424 -259.008626) (xy 328.984356 -258.907026) (xy 328.793856 -258.907026) (xy 328.757534 -259.008626)
			(xy 328.757534 -259.059426) (xy 329.020424 -259.059426)
		)
		(stroke
			(width 0)
			(type solid)
		)
		(fill yes)
		(layer "F.Cu")
		(net "M_A_CPU0_SA_CS_N<3>")
	)
	(gr_poly
		(pts
			(xy 329.020424 -258.703826) (xy 328.984356 -258.602226) (xy 328.793856 -258.602226) (xy 328.757534 -258.703826)
			(xy 328.757534 -258.754626) (xy 329.020424 -258.754626)
		)
		(stroke
			(width 0)
			(type solid)
		)
		(fill yes)
		(layer "F.Cu")
		(net "M_A_CPU0_SA_CS_N<1>")
	)
	(gr_poly
		(pts
			(xy 329.020424 -258.399026) (xy 328.984356 -258.297426) (xy 328.793856 -258.297426) (xy 328.757534 -258.399026)
			(xy 328.757534 -258.449826) (xy 329.020424 -258.449826)
		)
		(stroke
			(width 0)
			(type solid)
		)
		(fill yes)
		(layer "F.Cu")
		(net "M_A_CPU0_SA_CA<0>")
	)
	(gr_poly
		(pts
			(xy 329.020424 -258.094226) (xy 328.984356 -257.992626) (xy 328.793856 -257.992626) (xy 328.757534 -258.094226)
			(xy 328.757534 -258.145026) (xy 329.020424 -258.145026)
		)
		(stroke
			(width 0)
			(type solid)
		)
		(fill yes)
		(layer "F.Cu")
		(net "M_A_CPU0_SA_CA<1>")
	)
	(gr_poly
		(pts
			(xy 329.020424 -257.789426) (xy 328.984356 -257.687826) (xy 328.793856 -257.687826) (xy 328.757534 -257.789426)
			(xy 328.757534 -257.840226) (xy 329.020424 -257.840226)
		)
		(stroke
			(width 0)
			(type solid)
		)
		(fill yes)
		(layer "F.Cu")
		(net "M_A_CPU0_SA_CA<2>")
	)
	(gr_poly
		(pts
			(xy 329.020424 -257.484626) (xy 328.984356 -257.383026) (xy 328.793856 -257.383026) (xy 328.757534 -257.484626)
			(xy 328.757534 -257.535426) (xy 329.020424 -257.535426)
		)
		(stroke
			(width 0)
			(type solid)
		)
		(fill yes)
		(layer "F.Cu")
		(net "M_A_CPU0_SA_CA<3>")
	)
	(gr_poly
		(pts
			(xy 329.020424 -257.179826) (xy 328.984356 -257.078226) (xy 328.793856 -257.078226) (xy 328.757534 -257.179826)
			(xy 328.757534 -257.230626) (xy 329.020424 -257.230626)
		)
		(stroke
			(width 0)
			(type solid)
		)
		(fill yes)
		(layer "F.Cu")
		(net "M_A_CPU0_SA_CA<4>")
	)
	(gr_poly
		(pts
			(xy 329.020424 -256.875026) (xy 328.984356 -256.773426) (xy 328.793856 -256.773426) (xy 328.757534 -256.875026)
			(xy 328.757534 -256.925826) (xy 329.020424 -256.925826)
		)
		(stroke
			(width 0)
			(type solid)
		)
		(fill yes)
		(layer "F.Cu")
		(net "M_A_CPU0_SA_CA<5>")
	)
	(gr_poly
		(pts
			(xy 329.020424 -256.570226) (xy 328.984356 -256.468626) (xy 328.793856 -256.468626) (xy 328.757534 -256.570226)
			(xy 328.757534 -256.621026) (xy 329.020424 -256.621026)
		)
		(stroke
			(width 0)
			(type solid)
		)
		(fill yes)
		(layer "F.Cu")
		(net "M_A_CPU0_SA_CA<6>")
	)
	(gr_poly
		(pts
			(xy 329.020424 -256.265426) (xy 328.984356 -256.163826) (xy 328.793856 -256.163826) (xy 328.757534 -256.265426)
			(xy 328.757534 -256.316226) (xy 329.020424 -256.316226)
		)
		(stroke
			(width 0)
			(type solid)
		)
		(fill yes)
		(layer "F.Cu")
		(net "M_A_CPU0_SA_PAR")
	)
	(gr_poly
		(pts
			(xy 329.020932 -225.712782) (xy 328.970132 -225.712782) (xy 328.868532 -225.749104) (xy 328.868532 -225.939604)
			(xy 328.970132 -225.975926) (xy 329.020932 -225.975926)
		)
		(stroke
			(width 0)
			(type solid)
		)
		(fill yes)
		(layer "F.Cu")
		(net "M_A_CPU0_SB_DQ<22>")
	)
	(gr_poly
		(pts
			(xy 329.020932 -225.115882) (xy 328.970132 -225.115882) (xy 328.868532 -225.152204) (xy 328.868532 -225.342704)
			(xy 328.970132 -225.379026) (xy 329.020932 -225.379026)
		)
		(stroke
			(width 0)
			(type solid)
		)
		(fill yes)
		(layer "F.Cu")
		(net "M_A_CPU0_SB_DQ<22>")
	)
	(gr_poly
		(pts
			(xy 329.020932 -224.518982) (xy 328.970132 -224.518982) (xy 328.868532 -224.555304) (xy 328.868532 -224.745804)
			(xy 328.970132 -224.782126) (xy 329.020932 -224.782126)
		)
		(stroke
			(width 0)
			(type solid)
		)
		(fill yes)
		(layer "F.Cu")
		(net "M_A_CPU0_SB_DQ<22>")
	)
	(gr_poly
		(pts
			(xy 329.02398 -289.181032) (xy 329.02398 -288.990532) (xy 328.92238 -288.95421) (xy 328.87158 -288.95421)
			(xy 328.87158 -289.2171) (xy 328.92238 -289.2171)
		)
		(stroke
			(width 0)
			(type solid)
		)
		(fill yes)
		(layer "F.Cu")
		(net "M_A_CPU0_SA_DQ<16>")
	)
	(gr_poly
		(pts
			(xy 329.02398 -288.584132) (xy 329.02398 -288.393632) (xy 328.92238 -288.35731) (xy 328.87158 -288.35731)
			(xy 328.87158 -288.6202) (xy 328.92238 -288.6202)
		)
		(stroke
			(width 0)
			(type solid)
		)
		(fill yes)
		(layer "F.Cu")
		(net "M_A_CPU0_SA_DQ<16>")
	)
	(gr_poly
		(pts
			(xy 329.02398 -287.987232) (xy 329.02398 -287.796732) (xy 328.92238 -287.76041) (xy 328.87158 -287.76041)
			(xy 328.87158 -288.0233) (xy 328.92238 -288.0233)
		)
		(stroke
			(width 0)
			(type solid)
		)
		(fill yes)
		(layer "F.Cu")
		(net "M_A_CPU0_SA_DQ<16>")
	)
	(gr_poly
		(pts
			(xy 329.02398 -287.390332) (xy 329.02398 -287.199832) (xy 328.92238 -287.16351) (xy 328.87158 -287.16351)
			(xy 328.87158 -287.4264) (xy 328.92238 -287.4264)
		)
		(stroke
			(width 0)
			(type solid)
		)
		(fill yes)
		(layer "F.Cu")
		(net "M_A_CPU0_SA_DQ<16>")
	)
	(gr_poly
		(pts
			(xy 329.02398 -286.793432) (xy 329.02398 -286.602932) (xy 328.92238 -286.56661) (xy 328.87158 -286.56661)
			(xy 328.87158 -286.8295) (xy 328.92238 -286.8295)
		)
		(stroke
			(width 0)
			(type solid)
		)
		(fill yes)
		(layer "F.Cu")
		(net "M_A_CPU0_SA_DQ<16>")
	)
	(gr_poly
		(pts
			(xy 329.02398 -286.196532) (xy 329.02398 -286.006032) (xy 328.92238 -285.96971) (xy 328.87158 -285.96971)
			(xy 328.87158 -286.2326) (xy 328.92238 -286.2326)
		)
		(stroke
			(width 0)
			(type solid)
		)
		(fill yes)
		(layer "F.Cu")
		(net "M_A_CPU0_SA_DQ<16>")
	)
	(gr_poly
		(pts
			(xy 329.02398 -285.599632) (xy 329.02398 -285.409132) (xy 328.92238 -285.37281) (xy 328.87158 -285.37281)
			(xy 328.87158 -285.6357) (xy 328.92238 -285.6357)
		)
		(stroke
			(width 0)
			(type solid)
		)
		(fill yes)
		(layer "F.Cu")
		(net "M_A_CPU0_SA_DQ<16>")
	)
	(gr_poly
		(pts
			(xy 329.02398 -285.002732) (xy 329.02398 -284.812232) (xy 328.92238 -284.77591) (xy 328.87158 -284.77591)
			(xy 328.87158 -285.0388) (xy 328.92238 -285.0388)
		)
		(stroke
			(width 0)
			(type solid)
		)
		(fill yes)
		(layer "F.Cu")
		(net "M_A_CPU0_SA_DQ<16>")
	)
	(gr_poly
		(pts
			(xy 329.02398 -284.405832) (xy 329.02398 -284.215332) (xy 328.92238 -284.17901) (xy 328.87158 -284.17901)
			(xy 328.87158 -284.4419) (xy 328.92238 -284.4419)
		)
		(stroke
			(width 0)
			(type solid)
		)
		(fill yes)
		(layer "F.Cu")
		(net "M_A_CPU0_SA_DQ<16>")
	)
	(gr_poly
		(pts
			(xy 329.02398 -283.808932) (xy 329.02398 -283.618432) (xy 328.92238 -283.58211) (xy 328.87158 -283.58211)
			(xy 328.87158 -283.845) (xy 328.92238 -283.845)
		)
		(stroke
			(width 0)
			(type solid)
		)
		(fill yes)
		(layer "F.Cu")
		(net "M_A_CPU0_SA_DQ<16>")
	)
	(gr_poly
		(pts
			(xy 329.02398 -283.212032) (xy 329.02398 -283.021532) (xy 328.92238 -282.98521) (xy 328.87158 -282.98521)
			(xy 328.87158 -283.2481) (xy 328.92238 -283.2481)
		)
		(stroke
			(width 0)
			(type solid)
		)
		(fill yes)
		(layer "F.Cu")
		(net "M_A_CPU0_SA_DQ<16>")
	)
	(gr_poly
		(pts
			(xy 329.02398 -282.615132) (xy 329.02398 -282.424632) (xy 328.92238 -282.38831) (xy 328.87158 -282.38831)
			(xy 328.87158 -282.6512) (xy 328.92238 -282.6512)
		)
		(stroke
			(width 0)
			(type solid)
		)
		(fill yes)
		(layer "F.Cu")
		(net "M_A_CPU0_SA_DQ<16>")
	)
	(gr_poly
		(pts
			(xy 329.034902 -224.004378) (xy 329.070716 -223.96831) (xy 328.885042 -223.782636) (xy 328.848974 -223.81845)
			(xy 328.802746 -223.915986) (xy 328.937366 -224.050606)
		)
		(stroke
			(width 0)
			(type solid)
		)
		(fill yes)
		(layer "F.Cu")
		(net "M_A_CPU0_SB_DQ<21>")
	)
	(gr_poly
		(pts
			(xy 329.043284 -280.150824) (xy 329.080622 -279.96388) (xy 328.988166 -279.908508) (xy 328.938382 -279.898602)
			(xy 328.88682 -280.156412) (xy 328.936604 -280.166318)
		)
		(stroke
			(width 0)
			(type solid)
		)
		(fill yes)
		(layer "F.Cu")
		(net "M_A_CPU0_SA_DQ<18>")
	)
	(gr_poly
		(pts
			(xy 329.057762 -232.190036) (xy 329.09383 -232.154222) (xy 328.907902 -231.968294) (xy 328.871834 -232.004108)
			(xy 328.825606 -232.101644) (xy 328.96048 -232.236264)
		)
		(stroke
			(width 0)
			(type solid)
		)
		(fill yes)
		(layer "F.Cu")
		(net "M_A_CPU0_SB_DQ<14>")
	)
	(gr_poly
		(pts
			(xy 329.061826 -280.83637) (xy 329.012042 -280.826464) (xy 328.905362 -280.841958) (xy 328.868024 -281.028648)
			(xy 328.96048 -281.08402) (xy 329.010264 -281.09418)
		)
		(stroke
			(width 0)
			(type solid)
		)
		(fill yes)
		(layer "F.Cu")
		(net "M_A_CPU0_SA_DQ<16>")
	)
	(gr_poly
		(pts
			(xy 329.065128 -268.55674) (xy 329.0189 -268.459458) (xy 328.983086 -268.42339) (xy 328.797158 -268.609318)
			(xy 328.832972 -268.645132) (xy 328.930508 -268.69136)
		)
		(stroke
			(width 0)
			(type solid)
		)
		(fill yes)
		(layer "F.Cu")
		(net "M_A_CPU0_SA_DQ<31>")
	)
	(gr_poly
		(pts
			(xy 329.066906 -231.336596) (xy 329.102974 -231.300782) (xy 328.917046 -231.114854) (xy 328.881232 -231.150668)
			(xy 328.83475 -231.248204) (xy 328.969624 -231.382824)
		)
		(stroke
			(width 0)
			(type solid)
		)
		(fill yes)
		(layer "F.Cu")
		(net "M_A_CPU0_SB_DQ<15>")
	)
	(gr_poly
		(pts
			(xy 329.067668 -274.404074) (xy 329.031854 -274.36826) (xy 328.934318 -274.322032) (xy 328.799698 -274.456652)
			(xy 328.845926 -274.554188) (xy 328.88174 -274.590002)
		)
		(stroke
			(width 0)
			(type solid)
		)
		(fill yes)
		(layer "F.Cu")
		(net "M_A_CPU0_SA_DQ<21>")
	)
	(gr_poly
		(pts
			(xy 329.075034 -269.410688) (xy 329.028806 -269.313152) (xy 328.992738 -269.277338) (xy 328.80681 -269.463266)
			(xy 328.842878 -269.49908) (xy 328.94016 -269.545308)
		)
		(stroke
			(width 0)
			(type solid)
		)
		(fill yes)
		(layer "F.Cu")
		(net "M_A_CPU0_SA_DQ<30>")
	)
	(gr_poly
		(pts
			(xy 329.077066 -230.067358) (xy 329.11288 -230.03129) (xy 328.926952 -229.845362) (xy 328.891138 -229.88143)
			(xy 328.84491 -229.978712) (xy 328.97953 -230.113586)
		)
		(stroke
			(width 0)
			(type solid)
		)
		(fill yes)
		(layer "F.Cu")
		(net "M_A_CPU0_SB_DQ<18>")
	)
	(gr_poly
		(pts
			(xy 329.077574 -275.25853) (xy 329.04176 -275.222462) (xy 328.944224 -275.176234) (xy 328.809604 -275.310854)
			(xy 328.855832 -275.40839) (xy 328.8919 -275.444204)
		)
		(stroke
			(width 0)
			(type solid)
		)
		(fill yes)
		(layer "F.Cu")
		(net "M_A_CPU0_SA_DQ<20>")
	)
	(gr_poly
		(pts
			(xy 329.077828 -235.94822) (xy 329.124056 -235.850938) (xy 328.989436 -235.716064) (xy 328.8919 -235.762546)
			(xy 328.856086 -235.79836) (xy 329.042014 -235.984288)
		)
		(stroke
			(width 0)
			(type solid)
		)
		(fill yes)
		(layer "F.Cu")
		(net "M_A_CPU0_SB_DQ<8>")
	)
	(gr_poly
		(pts
			(xy 329.08621 -229.213918) (xy 329.122278 -229.178104) (xy 328.93635 -228.992176) (xy 328.900282 -229.02799)
			(xy 328.854054 -229.125526) (xy 328.988928 -229.260146)
		)
		(stroke
			(width 0)
			(type solid)
		)
		(fill yes)
		(layer "F.Cu")
		(net "M_A_CPU0_SB_DQ<19>")
	)
	(gr_poly
		(pts
			(xy 329.087226 -235.095034) (xy 329.133454 -234.997498) (xy 328.99858 -234.862878) (xy 328.901298 -234.909106)
			(xy 328.86523 -234.94492) (xy 329.051158 -235.130848)
		)
		(stroke
			(width 0)
			(type solid)
		)
		(fill yes)
		(layer "F.Cu")
		(net "M_A_CPU0_SB_DQ<9>")
	)
	(gr_poly
		(pts
			(xy 329.08875 -277.823168) (xy 329.01636 -277.743412) (xy 328.971656 -277.719282) (xy 328.84745 -277.951184)
			(xy 328.892154 -277.97506) (xy 328.998834 -277.991062)
		)
		(stroke
			(width 0)
			(type solid)
		)
		(fill yes)
		(layer "F.Cu")
		(net "M_A_CPU0_SA_DQ<19>")
	)
	(gr_poly
		(pts
			(xy 329.092052 -227.0633) (xy 329.12812 -227.027486) (xy 328.942192 -226.841558) (xy 328.906124 -226.877372)
			(xy 328.859896 -226.974908) (xy 328.99477 -227.109528)
		)
		(stroke
			(width 0)
			(type solid)
		)
		(fill yes)
		(layer "F.Cu")
		(net "M_A_CPU0_SB_DQ<20>")
	)
	(gr_poly
		(pts
			(xy 329.108054 -261.638034) (xy 329.07224 -261.601966) (xy 328.974704 -261.555738) (xy 328.840084 -261.690612)
			(xy 328.886312 -261.787894) (xy 328.922126 -261.823962)
		)
		(stroke
			(width 0)
			(type solid)
		)
		(fill yes)
		(layer "F.Cu")
		(net "M_A_CPU0_SA_CB<5>")
	)
	(gr_poly
		(pts
			(xy 329.108308 -281.3812) (xy 329.145646 -281.194256) (xy 329.05319 -281.138884) (xy 329.003406 -281.128978)
			(xy 328.951844 -281.386788) (xy 329.001628 -281.396694)
		)
		(stroke
			(width 0)
			(type solid)
		)
		(fill yes)
		(layer "F.Cu")
		(net "M_A_CPU0_SA_DQ<16>")
	)
	(gr_poly
		(pts
			(xy 329.111356 -223.505776) (xy 329.157584 -223.408494) (xy 329.022964 -223.27362) (xy 328.925428 -223.319848)
			(xy 328.889614 -223.355916) (xy 329.075542 -223.541844)
		)
		(stroke
			(width 0)
			(type solid)
		)
		(fill yes)
		(layer "F.Cu")
		(net "M_A_CPU0_SB_DQ<23>")
	)
	(gr_poly
		(pts
			(xy 329.112626 -277.456392) (xy 329.067668 -277.432262) (xy 328.960988 -277.41626) (xy 328.871072 -277.584154)
			(xy 328.943716 -277.66391) (xy 328.98842 -277.68804)
		)
		(stroke
			(width 0)
			(type solid)
		)
		(fill yes)
		(layer "F.Cu")
		(net "M_A_CPU0_SA_DQ<19>")
	)
	(gr_poly
		(pts
			(xy 329.113896 -279.020524) (xy 329.064112 -279.010618) (xy 328.957178 -279.026112) (xy 328.91984 -279.213056)
			(xy 329.01255 -279.268428) (xy 329.062334 -279.278334)
		)
		(stroke
			(width 0)
			(type solid)
		)
		(fill yes)
		(layer "F.Cu")
		(net "M_A_CPU0_SA_DQ<18>")
	)
	(gr_poly
		(pts
			(xy 329.117452 -262.491728) (xy 329.081638 -262.45566) (xy 328.984102 -262.409432) (xy 328.849482 -262.544052)
			(xy 328.89571 -262.641588) (xy 328.931778 -262.677402)
		)
		(stroke
			(width 0)
			(type solid)
		)
		(fill yes)
		(layer "F.Cu")
		(net "M_A_CPU0_SA_CB<4>")
	)
	(gr_poly
		(pts
			(xy 329.122278 -272.168366) (xy 329.086464 -272.132298) (xy 328.988928 -272.08607) (xy 328.854308 -272.22069)
			(xy 328.900536 -272.318226) (xy 328.936604 -272.35404)
		)
		(stroke
			(width 0)
			(type solid)
		)
		(fill yes)
		(layer "F.Cu")
		(net "M_A_CPU0_SA_DQ<25>")
	)
	(gr_poly
		(pts
			(xy 329.122532 -265.0744) (xy 329.086464 -265.038586) (xy 328.989182 -264.992358) (xy 328.854308 -265.126978)
			(xy 328.900536 -265.224514) (xy 328.936604 -265.260328)
		)
		(stroke
			(width 0)
			(type solid)
		)
		(fill yes)
		(layer "F.Cu")
		(net "M_A_CPU0_SA_CB<1>")
	)
	(gr_poly
		(pts
			(xy 329.124818 -232.544874) (xy 329.171046 -232.447592) (xy 329.036426 -232.312972) (xy 328.93889 -232.3592)
			(xy 328.903076 -232.395014) (xy 329.089004 -232.580942)
		)
		(stroke
			(width 0)
			(type solid)
		)
		(fill yes)
		(layer "F.Cu")
		(net "M_A_CPU0_SB_DQ<12>")
	)
	(gr_poly
		(pts
			(xy 329.131676 -273.021552) (xy 329.095608 -272.985738) (xy 328.998326 -272.93951) (xy 328.863452 -273.07413)
			(xy 328.90968 -273.171666) (xy 328.945748 -273.20748)
		)
		(stroke
			(width 0)
			(type solid)
		)
		(fill yes)
		(layer "F.Cu")
		(net "M_A_CPU0_SA_DQ<24>")
	)
	(gr_poly
		(pts
			(xy 329.13193 -265.92784) (xy 329.095862 -265.892026) (xy 328.99858 -265.845798) (xy 328.863706 -265.980418)
			(xy 328.909934 -266.077954) (xy 328.946002 -266.113768)
		)
		(stroke
			(width 0)
			(type solid)
		)
		(fill yes)
		(layer "F.Cu")
		(net "M_A_CPU0_SA_CB<0>")
	)
	(gr_poly
		(pts
			(xy 329.134216 -231.691434) (xy 329.180444 -231.594152) (xy 329.045824 -231.459278) (xy 328.948288 -231.505506)
			(xy 328.912474 -231.541574) (xy 329.098402 -231.727502)
		)
		(stroke
			(width 0)
			(type solid)
		)
		(fill yes)
		(layer "F.Cu")
		(net "M_A_CPU0_SB_DQ<13>")
	)
	(gr_poly
		(pts
			(xy 329.144376 -230.422196) (xy 329.190604 -230.32466) (xy 329.05573 -230.19004) (xy 328.958448 -230.236268)
			(xy 328.92238 -230.272082) (xy 329.108308 -230.45801)
		)
		(stroke
			(width 0)
			(type solid)
		)
		(fill yes)
		(layer "F.Cu")
		(net "M_A_CPU0_SB_DQ<16>")
	)
	(gr_poly
		(pts
			(xy 329.145138 -274.110704) (xy 329.09891 -274.013422) (xy 329.063096 -273.977354) (xy 328.877168 -274.163282)
			(xy 328.912982 -274.199096) (xy 329.010518 -274.245578)
		)
		(stroke
			(width 0)
			(type solid)
		)
		(fill yes)
		(layer "F.Cu")
		(net "M_A_CPU0_SA_DQ<23>")
	)
	(gr_poly
		(pts
			(xy 329.15352 -229.568756) (xy 329.199748 -229.47122) (xy 329.065128 -229.3366) (xy 328.967592 -229.382828)
			(xy 328.931778 -229.418896) (xy 329.117452 -229.60457)
		)
		(stroke
			(width 0)
			(type solid)
		)
		(fill yes)
		(layer "F.Cu")
		(net "M_A_CPU0_SB_DQ<17>")
	)
	(gr_poly
		(pts
			(xy 329.154536 -274.964398) (xy 329.108308 -274.866862) (xy 329.07224 -274.831048) (xy 328.886566 -275.016722)
			(xy 328.92238 -275.05279) (xy 329.019916 -275.099018)
		)
		(stroke
			(width 0)
			(type solid)
		)
		(fill yes)
		(layer "F.Cu")
		(net "M_A_CPU0_SA_DQ<22>")
	)
	(gr_poly
		(pts
			(xy 329.160378 -279.565354) (xy 329.197716 -279.378664) (xy 329.105006 -279.323292) (xy 329.055222 -279.313132)
			(xy 329.00366 -279.570942) (xy 329.053444 -279.580848)
		)
		(stroke
			(width 0)
			(type solid)
		)
		(fill yes)
		(layer "F.Cu")
		(net "M_A_CPU0_SA_DQ<18>")
	)
	(gr_poly
		(pts
			(xy 329.173332 -226.238054) (xy 329.173332 -226.047554) (xy 329.071732 -226.011486) (xy 329.020932 -226.011486)
			(xy 329.020932 -226.274122) (xy 329.071732 -226.274122)
		)
		(stroke
			(width 0)
			(type solid)
		)
		(fill yes)
		(layer "F.Cu")
		(net "M_A_CPU0_SB_DQ<22>")
	)
	(gr_poly
		(pts
			(xy 329.173332 -225.641154) (xy 329.173332 -225.450654) (xy 329.071732 -225.414586) (xy 329.020932 -225.414586)
			(xy 329.020932 -225.677222) (xy 329.071732 -225.677222)
		)
		(stroke
			(width 0)
			(type solid)
		)
		(fill yes)
		(layer "F.Cu")
		(net "M_A_CPU0_SB_DQ<22>")
	)
	(gr_poly
		(pts
			(xy 329.173332 -225.044254) (xy 329.173332 -224.853754) (xy 329.071732 -224.817686) (xy 329.020932 -224.817686)
			(xy 329.020932 -225.080322) (xy 329.071732 -225.080322)
		)
		(stroke
			(width 0)
			(type solid)
		)
		(fill yes)
		(layer "F.Cu")
		(net "M_A_CPU0_SB_DQ<22>")
	)
	(gr_poly
		(pts
			(xy 329.17892 -280.2509) (xy 329.129136 -280.240994) (xy 329.022456 -280.256488) (xy 328.985118 -280.443432)
			(xy 329.077574 -280.498804) (xy 329.127358 -280.50871)
		)
		(stroke
			(width 0)
			(type solid)
		)
		(fill yes)
		(layer "F.Cu")
		(net "M_A_CPU0_SA_DQ<16>")
	)
	(gr_poly
		(pts
			(xy 329.185524 -261.344664) (xy 329.139296 -261.247128) (xy 329.103228 -261.211314) (xy 328.917554 -261.396988)
			(xy 328.953368 -261.433056) (xy 329.050904 -261.479284)
		)
		(stroke
			(width 0)
			(type solid)
		)
		(fill yes)
		(layer "F.Cu")
		(net "M_A_CPU0_SA_CB<7>")
	)
	(gr_poly
		(pts
			(xy 329.19416 -268.212316) (xy 329.158092 -268.176502) (xy 329.06081 -268.130274) (xy 328.925936 -268.264894)
			(xy 328.972164 -268.36243) (xy 329.008232 -268.398244)
		)
		(stroke
			(width 0)
			(type solid)
		)
		(fill yes)
		(layer "F.Cu")
		(net "M_A_CPU0_SA_DQ<31>")
	)
	(gr_poly
		(pts
			(xy 329.194922 -262.198104) (xy 329.148694 -262.100822) (xy 329.11288 -262.064754) (xy 328.926952 -262.250682)
			(xy 328.962766 -262.28675) (xy 329.060302 -262.332978)
		)
		(stroke
			(width 0)
			(type solid)
		)
		(fill yes)
		(layer "F.Cu")
		(net "M_A_CPU0_SA_CB<6>")
	)
	(gr_poly
		(pts
			(xy 329.199748 -271.874742) (xy 329.15352 -271.777206) (xy 329.117452 -271.741392) (xy 328.931524 -271.92732)
			(xy 328.967592 -271.963134) (xy 329.064874 -272.009362)
		)
		(stroke
			(width 0)
			(type solid)
		)
		(fill yes)
		(layer "F.Cu")
		(net "M_A_CPU0_SA_DQ<27>")
	)
	(gr_poly
		(pts
			(xy 329.200002 -264.78103) (xy 329.153774 -264.683748) (xy 329.11796 -264.64768) (xy 328.932032 -264.833608)
			(xy 328.967846 -264.869676) (xy 329.065382 -264.915904)
		)
		(stroke
			(width 0)
			(type solid)
		)
		(fill yes)
		(layer "F.Cu")
		(net "M_A_CPU0_SA_CB<3>")
	)
	(gr_poly
		(pts
			(xy 329.203812 -269.066264) (xy 329.167998 -269.03045) (xy 329.070462 -268.983968) (xy 328.935842 -269.118842)
			(xy 328.98207 -269.216124) (xy 329.017884 -269.252192)
		)
		(stroke
			(width 0)
			(type solid)
		)
		(fill yes)
		(layer "F.Cu")
		(net "M_A_CPU0_SA_DQ<30>")
	)
	(gr_poly
		(pts
			(xy 329.209146 -272.728182) (xy 329.162918 -272.6309) (xy 329.127104 -272.594832) (xy 328.941176 -272.78076)
			(xy 328.97699 -272.816828) (xy 329.074526 -272.863056)
		)
		(stroke
			(width 0)
			(type solid)
		)
		(fill yes)
		(layer "F.Cu")
		(net "M_A_CPU0_SA_DQ<26>")
	)
	(gr_poly
		(pts
			(xy 329.2094 -265.634724) (xy 329.163172 -265.537188) (xy 329.127104 -265.501374) (xy 328.94143 -265.687048)
			(xy 328.977244 -265.723116) (xy 329.07478 -265.769344)
		)
		(stroke
			(width 0)
			(type solid)
		)
		(fill yes)
		(layer "F.Cu")
		(net "M_A_CPU0_SA_CB<2>")
	)
	(gr_poly
		(pts
			(xy 329.21702 -236.231176) (xy 329.253088 -236.195362) (xy 329.06716 -236.009434) (xy 329.031092 -236.045248)
			(xy 328.984864 -236.142784) (xy 329.119738 -236.277404)
		)
		(stroke
			(width 0)
			(type solid)
		)
		(fill yes)
		(layer "F.Cu")
		(net "M_A_CPU0_SB_DQ<8>")
	)
	(gr_poly
		(pts
			(xy 329.225402 -280.79573) (xy 329.26274 -280.60904) (xy 329.170284 -280.553668) (xy 329.120246 -280.543762)
			(xy 329.068938 -280.801572) (xy 329.118722 -280.811478)
		)
		(stroke
			(width 0)
			(type solid)
		)
		(fill yes)
		(layer "F.Cu")
		(net "M_A_CPU0_SA_DQ<16>")
	)
	(gr_poly
		(pts
			(xy 329.226418 -235.377736) (xy 329.262232 -235.341922) (xy 329.076304 -235.155994) (xy 329.04049 -235.192062)
			(xy 328.994262 -235.289344) (xy 329.128882 -235.423964)
		)
		(stroke
			(width 0)
			(type solid)
		)
		(fill yes)
		(layer "F.Cu")
		(net "M_A_CPU0_SB_DQ<9>")
	)
	(gr_poly
		(pts
			(xy 329.250548 -223.788732) (xy 329.286362 -223.752664) (xy 329.100688 -223.56699) (xy 329.06462 -223.602804)
			(xy 329.018392 -223.70034) (xy 329.153012 -223.83496)
		)
		(stroke
			(width 0)
			(type solid)
		)
		(fill yes)
		(layer "F.Cu")
		(net "M_A_CPU0_SB_DQ<23>")
	)
	(gr_poly
		(pts
			(xy 329.26401 -232.82783) (xy 329.300078 -232.792016) (xy 329.11415 -232.606088) (xy 329.078082 -232.641902)
			(xy 329.031854 -232.739438) (xy 329.166728 -232.874058)
		)
		(stroke
			(width 0)
			(type solid)
		)
		(fill yes)
		(layer "F.Cu")
		(net "M_A_CPU0_SB_DQ<12>")
	)
	(gr_poly
		(pts
			(xy 329.273408 -231.97439) (xy 329.309476 -231.938576) (xy 329.123548 -231.752648) (xy 329.08748 -231.788462)
			(xy 329.041252 -231.885998) (xy 329.176126 -232.020618)
		)
		(stroke
			(width 0)
			(type solid)
		)
		(fill yes)
		(layer "F.Cu")
		(net "M_A_CPU0_SB_DQ<13>")
	)
	(gr_poly
		(pts
			(xy 329.27417 -273.76628) (xy 329.238102 -273.730466) (xy 329.14082 -273.684238) (xy 329.005946 -273.818858)
			(xy 329.052174 -273.916394) (xy 329.088242 -273.952208)
		)
		(stroke
			(width 0)
			(type solid)
		)
		(fill yes)
		(layer "F.Cu")
		(net "M_A_CPU0_SA_DQ<23>")
	)
	(gr_poly
		(pts
			(xy 329.277218 -278.980138) (xy 329.314556 -278.793194) (xy 329.2221 -278.737822) (xy 329.172316 -278.727916)
			(xy 329.120754 -278.985726) (xy 329.170538 -278.995632)
		)
		(stroke
			(width 0)
			(type solid)
		)
		(fill yes)
		(layer "F.Cu")
		(net "M_A_CPU0_SA_DQ<18>")
	)
	(gr_poly
		(pts
			(xy 329.281028 -268.77264) (xy 329.2348 -268.675104) (xy 329.198732 -268.63929) (xy 329.013058 -268.824964)
			(xy 329.048872 -268.861032) (xy 329.146408 -268.90726)
		)
		(stroke
			(width 0)
			(type solid)
		)
		(fill yes)
		(layer "F.Cu")
		(net "M_A_CPU0_SA_DQ<29>")
	)
	(gr_poly
		(pts
			(xy 329.283314 -274.619974) (xy 329.2475 -274.58416) (xy 329.149964 -274.537678) (xy 329.015344 -274.672552)
			(xy 329.061572 -274.769834) (xy 329.097386 -274.805902)
		)
		(stroke
			(width 0)
			(type solid)
		)
		(fill yes)
		(layer "F.Cu")
		(net "M_A_CPU0_SA_DQ<22>")
	)
	(gr_poly
		(pts
			(xy 329.283568 -230.704898) (xy 329.319382 -230.669084) (xy 329.133454 -230.483156) (xy 329.09764 -230.519224)
			(xy 329.051412 -230.616506) (xy 329.186032 -230.751126)
		)
		(stroke
			(width 0)
			(type solid)
		)
		(fill yes)
		(layer "F.Cu")
		(net "M_A_CPU0_SB_DQ<16>")
	)
	(gr_poly
		(pts
			(xy 329.286108 -249.270266) (xy 329.25004 -249.168666) (xy 329.05954 -249.168666) (xy 329.023218 -249.270266)
			(xy 329.023218 -249.321066) (xy 329.286108 -249.321066)
		)
		(stroke
			(width 0)
			(type solid)
		)
		(fill yes)
		(layer "F.Cu")
		(net "M_A_CPU0_SB_CA<0>")
	)
	(gr_poly
		(pts
			(xy 329.286108 -248.660412) (xy 329.25004 -248.558812) (xy 329.05954 -248.558812) (xy 329.023218 -248.660412)
			(xy 329.023218 -248.711212) (xy 329.286108 -248.711212)
		)
		(stroke
			(width 0)
			(type solid)
		)
		(fill yes)
		(layer "F.Cu")
		(net "M_A_CPU0_SB_CA<2>")
	)
	(gr_poly
		(pts
			(xy 329.286108 -248.355612) (xy 329.25004 -248.254012) (xy 329.05954 -248.254012) (xy 329.023218 -248.355612)
			(xy 329.023218 -248.406412) (xy 329.286108 -248.406412)
		)
		(stroke
			(width 0)
			(type solid)
		)
		(fill yes)
		(layer "F.Cu")
		(net "M_A_CPU0_SB_CA<3>")
	)
	(gr_poly
		(pts
			(xy 329.286108 -248.050812) (xy 329.25004 -247.949212) (xy 329.05954 -247.949212) (xy 329.023218 -248.050812)
			(xy 329.023218 -248.101612) (xy 329.286108 -248.101612)
		)
		(stroke
			(width 0)
			(type solid)
		)
		(fill yes)
		(layer "F.Cu")
		(net "M_A_CPU0_SB_CA<4>")
	)
	(gr_poly
		(pts
			(xy 329.286108 -247.746012) (xy 329.25004 -247.644412) (xy 329.05954 -247.644412) (xy 329.023218 -247.746012)
			(xy 329.023218 -247.796812) (xy 329.286108 -247.796812)
		)
		(stroke
			(width 0)
			(type solid)
		)
		(fill yes)
		(layer "F.Cu")
		(net "M_A_CPU0_SB_CA<5>")
	)
	(gr_poly
		(pts
			(xy 329.29068 -269.626334) (xy 329.244452 -269.528798) (xy 329.208384 -269.492984) (xy 329.022456 -269.678912)
			(xy 329.058524 -269.714726) (xy 329.155806 -269.760954)
		)
		(stroke
			(width 0)
			(type solid)
		)
		(fill yes)
		(layer "F.Cu")
		(net "M_A_CPU0_SA_DQ<28>")
	)
	(gr_poly
		(pts
			(xy 329.292712 -229.851712) (xy 329.328526 -229.815644) (xy 329.142598 -229.629716) (xy 329.106784 -229.665784)
			(xy 329.060556 -229.763066) (xy 329.195176 -229.89794)
		)
		(stroke
			(width 0)
			(type solid)
		)
		(fill yes)
		(layer "F.Cu")
		(net "M_A_CPU0_SB_DQ<17>")
	)
	(gr_poly
		(pts
			(xy 329.293474 -235.732574) (xy 329.339702 -235.635292) (xy 329.205082 -235.500418) (xy 329.107546 -235.5469)
			(xy 329.071732 -235.582714) (xy 329.25766 -235.768642)
		)
		(stroke
			(width 0)
			(type solid)
		)
		(fill yes)
		(layer "F.Cu")
		(net "M_A_CPU0_SB_DQ<10>")
	)
	(gr_poly
		(pts
			(xy 329.296014 -279.665684) (xy 329.245976 -279.655778) (xy 329.139296 -279.671272) (xy 329.101958 -279.858216)
			(xy 329.194668 -279.913588) (xy 329.244452 -279.923494)
		)
		(stroke
			(width 0)
			(type solid)
		)
		(fill yes)
		(layer "F.Cu")
		(net "M_A_CPU0_SA_DQ<16>")
	)
	(gr_poly
		(pts
			(xy 329.302872 -234.879388) (xy 329.3491 -234.781852) (xy 329.214226 -234.647232) (xy 329.116944 -234.69346)
			(xy 329.080876 -234.729274) (xy 329.266804 -234.915202)
		)
		(stroke
			(width 0)
			(type solid)
		)
		(fill yes)
		(layer "F.Cu")
		(net "M_A_CPU0_SB_DQ<11>")
	)
	(gr_poly
		(pts
			(xy 329.307952 -226.847654) (xy 329.343766 -226.811586) (xy 329.157838 -226.625658) (xy 329.122024 -226.661726)
			(xy 329.075796 -226.759008) (xy 329.210416 -226.893882)
		)
		(stroke
			(width 0)
			(type solid)
		)
		(fill yes)
		(layer "F.Cu")
		(net "M_A_CPU0_SB_DQ<22>")
	)
	(gr_poly
		(pts
			(xy 329.314302 -261.00024) (xy 329.278488 -260.964172) (xy 329.180952 -260.917944) (xy 329.046332 -261.052818)
			(xy 329.09256 -261.1501) (xy 329.128374 -261.186168)
		)
		(stroke
			(width 0)
			(type solid)
		)
		(fill yes)
		(layer "F.Cu")
		(net "M_A_CPU0_SA_CB<7>")
	)
	(gr_poly
		(pts
			(xy 329.318874 -259.719826) (xy 329.318874 -259.669026) (xy 329.055984 -259.669026) (xy 329.055984 -259.719826)
			(xy 329.092052 -259.821426) (xy 329.282552 -259.821426)
		)
		(stroke
			(width 0)
			(type solid)
		)
		(fill yes)
		(layer "F.Cu")
		(net "M_A_CPU0_SA_CS_N<0>")
	)
	(gr_poly
		(pts
			(xy 329.318874 -259.415026) (xy 329.318874 -259.364226) (xy 329.055984 -259.364226) (xy 329.055984 -259.415026)
			(xy 329.092052 -259.516626) (xy 329.282552 -259.516626)
		)
		(stroke
			(width 0)
			(type solid)
		)
		(fill yes)
		(layer "F.Cu")
		(net "M_A_CPU0_SA_CS_N<2>")
	)
	(gr_poly
		(pts
			(xy 329.318874 -259.110226) (xy 329.318874 -259.059426) (xy 329.055984 -259.059426) (xy 329.055984 -259.110226)
			(xy 329.092052 -259.211826) (xy 329.282552 -259.211826)
		)
		(stroke
			(width 0)
			(type solid)
		)
		(fill yes)
		(layer "F.Cu")
		(net "M_A_CPU0_SA_CS_N<3>")
	)
	(gr_poly
		(pts
			(xy 329.318874 -258.805426) (xy 329.318874 -258.754626) (xy 329.055984 -258.754626) (xy 329.055984 -258.805426)
			(xy 329.092052 -258.907026) (xy 329.282552 -258.907026)
		)
		(stroke
			(width 0)
			(type solid)
		)
		(fill yes)
		(layer "F.Cu")
		(net "M_A_CPU0_SA_CS_N<1>")
	)
	(gr_poly
		(pts
			(xy 329.318874 -258.500626) (xy 329.318874 -258.449826) (xy 329.055984 -258.449826) (xy 329.055984 -258.500626)
			(xy 329.092052 -258.602226) (xy 329.282552 -258.602226)
		)
		(stroke
			(width 0)
			(type solid)
		)
		(fill yes)
		(layer "F.Cu")
		(net "M_A_CPU0_SA_CA<0>")
	)
	(gr_poly
		(pts
			(xy 329.318874 -258.195826) (xy 329.318874 -258.145026) (xy 329.055984 -258.145026) (xy 329.055984 -258.195826)
			(xy 329.092052 -258.297426) (xy 329.282552 -258.297426)
		)
		(stroke
			(width 0)
			(type solid)
		)
		(fill yes)
		(layer "F.Cu")
		(net "M_A_CPU0_SA_CA<1>")
	)
	(gr_poly
		(pts
			(xy 329.318874 -257.891026) (xy 329.318874 -257.840226) (xy 329.055984 -257.840226) (xy 329.055984 -257.891026)
			(xy 329.092052 -257.992626) (xy 329.282552 -257.992626)
		)
		(stroke
			(width 0)
			(type solid)
		)
		(fill yes)
		(layer "F.Cu")
		(net "M_A_CPU0_SA_CA<2>")
	)
	(gr_poly
		(pts
			(xy 329.318874 -257.586226) (xy 329.318874 -257.535426) (xy 329.055984 -257.535426) (xy 329.055984 -257.586226)
			(xy 329.092052 -257.687826) (xy 329.282552 -257.687826)
		)
		(stroke
			(width 0)
			(type solid)
		)
		(fill yes)
		(layer "F.Cu")
		(net "M_A_CPU0_SA_CA<3>")
	)
	(gr_poly
		(pts
			(xy 329.318874 -257.281426) (xy 329.318874 -257.230626) (xy 329.055984 -257.230626) (xy 329.055984 -257.281426)
			(xy 329.092052 -257.383026) (xy 329.282552 -257.383026)
		)
		(stroke
			(width 0)
			(type solid)
		)
		(fill yes)
		(layer "F.Cu")
		(net "M_A_CPU0_SA_CA<4>")
	)
	(gr_poly
		(pts
			(xy 329.318874 -256.976626) (xy 329.318874 -256.925826) (xy 329.055984 -256.925826) (xy 329.055984 -256.976626)
			(xy 329.092052 -257.078226) (xy 329.282552 -257.078226)
		)
		(stroke
			(width 0)
			(type solid)
		)
		(fill yes)
		(layer "F.Cu")
		(net "M_A_CPU0_SA_CA<5>")
	)
	(gr_poly
		(pts
			(xy 329.318874 -256.671826) (xy 329.318874 -256.621026) (xy 329.055984 -256.621026) (xy 329.055984 -256.671826)
			(xy 329.092052 -256.773426) (xy 329.282552 -256.773426)
		)
		(stroke
			(width 0)
			(type solid)
		)
		(fill yes)
		(layer "F.Cu")
		(net "M_A_CPU0_SA_CA<6>")
	)
	(gr_poly
		(pts
			(xy 329.318874 -256.367026) (xy 329.318874 -256.316226) (xy 329.055984 -256.316226) (xy 329.055984 -256.367026)
			(xy 329.092052 -256.468626) (xy 329.282552 -256.468626)
		)
		(stroke
			(width 0)
			(type solid)
		)
		(fill yes)
		(layer "F.Cu")
		(net "M_A_CPU0_SA_PAR")
	)
	(gr_poly
		(pts
			(xy 329.323954 -261.85368) (xy 329.287886 -261.817866) (xy 329.190604 -261.771638) (xy 329.05573 -261.906258)
			(xy 329.101958 -262.003794) (xy 329.138026 -262.039608)
		)
		(stroke
			(width 0)
			(type solid)
		)
		(fill yes)
		(layer "F.Cu")
		(net "M_A_CPU0_SA_CB<6>")
	)
	(gr_poly
		(pts
			(xy 329.325732 -225.712782) (xy 329.274932 -225.712782) (xy 329.173332 -225.749104) (xy 329.173332 -225.939604)
			(xy 329.274932 -225.975926) (xy 329.325732 -225.975926)
		)
		(stroke
			(width 0)
			(type solid)
		)
		(fill yes)
		(layer "F.Cu")
		(net "M_A_CPU0_SB_DQ<21>")
	)
	(gr_poly
		(pts
			(xy 329.325732 -225.115882) (xy 329.274932 -225.115882) (xy 329.173332 -225.152204) (xy 329.173332 -225.342704)
			(xy 329.274932 -225.379026) (xy 329.325732 -225.379026)
		)
		(stroke
			(width 0)
			(type solid)
		)
		(fill yes)
		(layer "F.Cu")
		(net "M_A_CPU0_SB_DQ<21>")
	)
	(gr_poly
		(pts
			(xy 329.325732 -224.518982) (xy 329.274932 -224.518982) (xy 329.173332 -224.555304) (xy 329.173332 -224.745804)
			(xy 329.274932 -224.782126) (xy 329.325732 -224.782126)
		)
		(stroke
			(width 0)
			(type solid)
		)
		(fill yes)
		(layer "F.Cu")
		(net "M_A_CPU0_SB_DQ<21>")
	)
	(gr_poly
		(pts
			(xy 329.328526 -271.530318) (xy 329.292712 -271.49425) (xy 329.195176 -271.448022) (xy 329.060556 -271.582896)
			(xy 329.106784 -271.680178) (xy 329.142598 -271.716246)
		)
		(stroke
			(width 0)
			(type solid)
		)
		(fill yes)
		(layer "F.Cu")
		(net "M_A_CPU0_SA_DQ<27>")
	)
	(gr_poly
		(pts
			(xy 329.32878 -264.43686) (xy 329.292966 -264.400792) (xy 329.19543 -264.354564) (xy 329.06081 -264.489184)
			(xy 329.107038 -264.58672) (xy 329.143106 -264.622534)
		)
		(stroke
			(width 0)
			(type solid)
		)
		(fill yes)
		(layer "F.Cu")
		(net "M_A_CPU0_SA_CB<3>")
	)
	(gr_poly
		(pts
			(xy 329.337924 -272.384012) (xy 329.30211 -272.347944) (xy 329.204574 -272.301716) (xy 329.069954 -272.436336)
			(xy 329.116182 -272.533872) (xy 329.15225 -272.569686)
		)
		(stroke
			(width 0)
			(type solid)
		)
		(fill yes)
		(layer "F.Cu")
		(net "M_A_CPU0_SA_DQ<26>")
	)
	(gr_poly
		(pts
			(xy 329.338178 -265.2903) (xy 329.302364 -265.254232) (xy 329.204828 -265.208004) (xy 329.070208 -265.342878)
			(xy 329.116436 -265.44016) (xy 329.15225 -265.476228)
		)
		(stroke
			(width 0)
			(type solid)
		)
		(fill yes)
		(layer "F.Cu")
		(net "M_A_CPU0_SA_CB<2>")
	)
	(gr_poly
		(pts
			(xy 329.340718 -232.329228) (xy 329.386946 -232.231692) (xy 329.252326 -232.097072) (xy 329.15479 -232.1433)
			(xy 329.118976 -232.179368) (xy 329.30465 -232.365042)
		)
		(stroke
			(width 0)
			(type solid)
		)
		(fill yes)
		(layer "F.Cu")
		(net "M_A_CPU0_SB_DQ<14>")
	)
	(gr_poly
		(pts
			(xy 329.340972 -217.801698) (xy 329.290172 -217.801698) (xy 329.188572 -217.837766) (xy 329.188572 -218.028266)
			(xy 329.290172 -218.064334) (xy 329.340972 -218.064334)
		)
		(stroke
			(width 0)
			(type solid)
		)
		(fill yes)
		(layer "F.Cu")
		(net "M_A_CPU0_SB_DQ<24>")
	)
	(gr_poly
		(pts
			(xy 329.340972 -217.204798) (xy 329.290172 -217.204798) (xy 329.188572 -217.240866) (xy 329.188572 -217.431366)
			(xy 329.290172 -217.467434) (xy 329.340972 -217.467434)
		)
		(stroke
			(width 0)
			(type solid)
		)
		(fill yes)
		(layer "F.Cu")
		(net "M_A_CPU0_SB_DQ<24>")
	)
	(gr_poly
		(pts
			(xy 329.340972 -216.607898) (xy 329.290172 -216.607898) (xy 329.188572 -216.643966) (xy 329.188572 -216.834466)
			(xy 329.290172 -216.870534) (xy 329.340972 -216.870534)
		)
		(stroke
			(width 0)
			(type solid)
		)
		(fill yes)
		(layer "F.Cu")
		(net "M_A_CPU0_SB_DQ<24>")
	)
	(gr_poly
		(pts
			(xy 329.342496 -280.210514) (xy 329.379834 -280.023824) (xy 329.287124 -279.968198) (xy 329.23734 -279.958292)
			(xy 329.185778 -280.216102) (xy 329.235562 -280.226008)
		)
		(stroke
			(width 0)
			(type solid)
		)
		(fill yes)
		(layer "F.Cu")
		(net "M_A_CPU0_SA_DQ<16>")
	)
	(gr_poly
		(pts
			(xy 329.349862 -231.475788) (xy 329.39609 -231.378506) (xy 329.26147 -231.243632) (xy 329.163934 -231.28986)
			(xy 329.12812 -231.325928) (xy 329.314048 -231.511856)
		)
		(stroke
			(width 0)
			(type solid)
		)
		(fill yes)
		(layer "F.Cu")
		(net "M_A_CPU0_SB_DQ<15>")
	)
	(gr_poly
		(pts
			(xy 329.35799 -277.96744) (xy 329.285346 -277.887684) (xy 329.240642 -277.863554) (xy 329.116436 -278.095202)
			(xy 329.16114 -278.119332) (xy 329.26782 -278.135334)
		)
		(stroke
			(width 0)
			(type solid)
		)
		(fill yes)
		(layer "F.Cu")
		(net "M_A_CPU0_SA_DQ<17>")
	)
	(gr_poly
		(pts
			(xy 329.360022 -230.20655) (xy 329.40625 -230.109014) (xy 329.271376 -229.974394) (xy 329.174094 -230.020622)
			(xy 329.138026 -230.056436) (xy 329.323954 -230.242364)
		)
		(stroke
			(width 0)
			(type solid)
		)
		(fill yes)
		(layer "F.Cu")
		(net "M_A_CPU0_SB_DQ<18>")
	)
	(gr_poly
		(pts
			(xy 329.360784 -274.326604) (xy 329.314556 -274.229068) (xy 329.278742 -274.193254) (xy 329.092814 -274.378928)
			(xy 329.128882 -274.414996) (xy 329.226164 -274.461224)
		)
		(stroke
			(width 0)
			(type solid)
		)
		(fill yes)
		(layer "F.Cu")
		(net "M_A_CPU0_SA_DQ<21>")
	)
	(gr_poly
		(pts
			(xy 329.369166 -229.35311) (xy 329.415394 -229.255574) (xy 329.280774 -229.120954) (xy 329.183238 -229.167182)
			(xy 329.147424 -229.20325) (xy 329.333098 -229.388924)
		)
		(stroke
			(width 0)
			(type solid)
		)
		(fill yes)
		(layer "F.Cu")
		(net "M_A_CPU0_SB_DQ<19>")
	)
	(gr_poly
		(pts
			(xy 329.370944 -275.180806) (xy 329.324716 -275.08327) (xy 329.288648 -275.047456) (xy 329.10272 -275.233384)
			(xy 329.138788 -275.269198) (xy 329.23607 -275.315426)
		)
		(stroke
			(width 0)
			(type solid)
		)
		(fill yes)
		(layer "F.Cu")
		(net "M_A_CPU0_SA_DQ<20>")
	)
	(gr_poly
		(pts
			(xy 329.375008 -227.202492) (xy 329.421236 -227.104956) (xy 329.286616 -226.970336) (xy 329.18908 -227.016564)
			(xy 329.153266 -227.052632) (xy 329.339194 -227.23856)
		)
		(stroke
			(width 0)
			(type solid)
		)
		(fill yes)
		(layer "F.Cu")
		(net "M_A_CPU0_SB_DQ<20>")
	)
	(gr_poly
		(pts
			(xy 329.40117 -261.56031) (xy 329.354942 -261.462774) (xy 329.319128 -261.42696) (xy 329.1332 -261.612888)
			(xy 329.169014 -261.648702) (xy 329.26655 -261.69493)
		)
		(stroke
			(width 0)
			(type solid)
		)
		(fill yes)
		(layer "F.Cu")
		(net "M_A_CPU0_SA_CB<5>")
	)
	(gr_poly
		(pts
			(xy 329.409806 -268.428216) (xy 329.373992 -268.392148) (xy 329.276456 -268.34592) (xy 329.141836 -268.480794)
			(xy 329.188064 -268.578076) (xy 329.223878 -268.614144)
		)
		(stroke
			(width 0)
			(type solid)
		)
		(fill yes)
		(layer "F.Cu")
		(net "M_A_CPU0_SA_DQ<29>")
	)
	(gr_poly
		(pts
			(xy 329.410822 -262.414004) (xy 329.364594 -262.316468) (xy 329.328526 -262.280654) (xy 329.142598 -262.466582)
			(xy 329.178666 -262.502396) (xy 329.275948 -262.548624)
		)
		(stroke
			(width 0)
			(type solid)
		)
		(fill yes)
		(layer "F.Cu")
		(net "M_A_CPU0_SA_CB<4>")
	)
	(gr_poly
		(pts
			(xy 329.412854 -279.080468) (xy 329.36307 -279.070308) (xy 329.25639 -279.086056) (xy 329.219052 -279.272746)
			(xy 329.311508 -279.328118) (xy 329.361292 -279.338278)
		)
		(stroke
			(width 0)
			(type solid)
		)
		(fill yes)
		(layer "F.Cu")
		(net "M_A_CPU0_SA_DQ<16>")
	)
	(gr_poly
		(pts
			(xy 329.415648 -272.090642) (xy 329.36942 -271.993106) (xy 329.333352 -271.957292) (xy 329.147424 -272.14322)
			(xy 329.183492 -272.179034) (xy 329.280774 -272.225262)
		)
		(stroke
			(width 0)
			(type solid)
		)
		(fill yes)
		(layer "F.Cu")
		(net "M_A_CPU0_SA_DQ<25>")
	)
	(gr_poly
		(pts
			(xy 329.415648 -264.996676) (xy 329.36942 -264.899394) (xy 329.333606 -264.863326) (xy 329.147678 -265.049254)
			(xy 329.183492 -265.085322) (xy 329.281028 -265.13155)
		)
		(stroke
			(width 0)
			(type solid)
		)
		(fill yes)
		(layer "F.Cu")
		(net "M_A_CPU0_SA_CB<1>")
	)
	(gr_poly
		(pts
			(xy 329.419458 -269.28191) (xy 329.383644 -269.246096) (xy 329.286108 -269.199614) (xy 329.151488 -269.334488)
			(xy 329.197716 -269.43177) (xy 329.23353 -269.467838)
		)
		(stroke
			(width 0)
			(type solid)
		)
		(fill yes)
		(layer "F.Cu")
		(net "M_A_CPU0_SA_DQ<28>")
	)
	(gr_poly
		(pts
			(xy 329.424792 -272.943828) (xy 329.378564 -272.846546) (xy 329.34275 -272.810478) (xy 329.156822 -272.996406)
			(xy 329.192636 -273.032474) (xy 329.290172 -273.078702)
		)
		(stroke
			(width 0)
			(type solid)
		)
		(fill yes)
		(layer "F.Cu")
		(net "M_A_CPU0_SA_DQ<24>")
	)
	(gr_poly
		(pts
			(xy 329.425046 -265.85037) (xy 329.378818 -265.752834) (xy 329.34275 -265.71702) (xy 329.157076 -265.902694)
			(xy 329.19289 -265.938762) (xy 329.290426 -265.98499)
		)
		(stroke
			(width 0)
			(type solid)
		)
		(fill yes)
		(layer "F.Cu")
		(net "M_A_CPU0_SA_CB<0>")
	)
	(gr_poly
		(pts
			(xy 329.43038 -293.57955) (xy 329.37958 -293.57955) (xy 329.27798 -293.615872) (xy 329.27798 -293.806372)
			(xy 329.37958 -293.84244) (xy 329.43038 -293.84244)
		)
		(stroke
			(width 0)
			(type solid)
		)
		(fill yes)
		(layer "F.Cu")
		(net "M_A_CPU0_SA_DQ<7>")
	)
	(gr_poly
		(pts
			(xy 329.43038 -292.98265) (xy 329.37958 -292.98265) (xy 329.27798 -293.018972) (xy 329.27798 -293.209472)
			(xy 329.37958 -293.24554) (xy 329.43038 -293.24554)
		)
		(stroke
			(width 0)
			(type solid)
		)
		(fill yes)
		(layer "F.Cu")
		(net "M_A_CPU0_SA_DQ<7>")
	)
	(gr_poly
		(pts
			(xy 329.43038 -292.38575) (xy 329.37958 -292.38575) (xy 329.27798 -292.422072) (xy 329.27798 -292.612572)
			(xy 329.37958 -292.64864) (xy 329.43038 -292.64864)
		)
		(stroke
			(width 0)
			(type solid)
		)
		(fill yes)
		(layer "F.Cu")
		(net "M_A_CPU0_SA_DQ<7>")
	)
	(gr_poly
		(pts
			(xy 329.43038 -291.78885) (xy 329.37958 -291.78885) (xy 329.27798 -291.825172) (xy 329.27798 -292.015672)
			(xy 329.37958 -292.05174) (xy 329.43038 -292.05174)
		)
		(stroke
			(width 0)
			(type solid)
		)
		(fill yes)
		(layer "F.Cu")
		(net "M_A_CPU0_SA_DQ<7>")
	)
	(gr_poly
		(pts
			(xy 329.43038 -291.19195) (xy 329.37958 -291.19195) (xy 329.27798 -291.228272) (xy 329.27798 -291.418772)
			(xy 329.37958 -291.45484) (xy 329.43038 -291.45484)
		)
		(stroke
			(width 0)
			(type solid)
		)
		(fill yes)
		(layer "F.Cu")
		(net "M_A_CPU0_SA_DQ<7>")
	)
	(gr_poly
		(pts
			(xy 329.43038 -290.59505) (xy 329.37958 -290.59505) (xy 329.27798 -290.631372) (xy 329.27798 -290.821872)
			(xy 329.37958 -290.85794) (xy 329.43038 -290.85794)
		)
		(stroke
			(width 0)
			(type solid)
		)
		(fill yes)
		(layer "F.Cu")
		(net "M_A_CPU0_SA_DQ<7>")
	)
	(gr_poly
		(pts
			(xy 329.43038 -289.99815) (xy 329.37958 -289.99815) (xy 329.27798 -290.034472) (xy 329.27798 -290.224972)
			(xy 329.37958 -290.26104) (xy 329.43038 -290.26104)
		)
		(stroke
			(width 0)
			(type solid)
		)
		(fill yes)
		(layer "F.Cu")
		(net "M_A_CPU0_SA_DQ<7>")
	)
	(gr_poly
		(pts
			(xy 329.43038 -289.40125) (xy 329.37958 -289.40125) (xy 329.27798 -289.437572) (xy 329.27798 -289.628072)
			(xy 329.37958 -289.66414) (xy 329.43038 -289.66414)
		)
		(stroke
			(width 0)
			(type solid)
		)
		(fill yes)
		(layer "F.Cu")
		(net "M_A_CPU0_SA_DQ<7>")
	)
	(gr_poly
		(pts
			(xy 329.43038 -288.80435) (xy 329.37958 -288.80435) (xy 329.27798 -288.840672) (xy 329.27798 -289.031172)
			(xy 329.37958 -289.06724) (xy 329.43038 -289.06724)
		)
		(stroke
			(width 0)
			(type solid)
		)
		(fill yes)
		(layer "F.Cu")
		(net "M_A_CPU0_SA_DQ<7>")
	)
	(gr_poly
		(pts
			(xy 329.43038 -288.20745) (xy 329.37958 -288.20745) (xy 329.27798 -288.243772) (xy 329.27798 -288.434272)
			(xy 329.37958 -288.47034) (xy 329.43038 -288.47034)
		)
		(stroke
			(width 0)
			(type solid)
		)
		(fill yes)
		(layer "F.Cu")
		(net "M_A_CPU0_SA_DQ<7>")
	)
	(gr_poly
		(pts
			(xy 329.43038 -287.61055) (xy 329.37958 -287.61055) (xy 329.27798 -287.646872) (xy 329.27798 -287.837372)
			(xy 329.37958 -287.87344) (xy 329.43038 -287.87344)
		)
		(stroke
			(width 0)
			(type solid)
		)
		(fill yes)
		(layer "F.Cu")
		(net "M_A_CPU0_SA_DQ<7>")
	)
	(gr_poly
		(pts
			(xy 329.43038 -287.01365) (xy 329.37958 -287.01365) (xy 329.27798 -287.049972) (xy 329.27798 -287.240472)
			(xy 329.37958 -287.27654) (xy 329.43038 -287.27654)
		)
		(stroke
			(width 0)
			(type solid)
		)
		(fill yes)
		(layer "F.Cu")
		(net "M_A_CPU0_SA_DQ<7>")
	)
	(gr_poly
		(pts
			(xy 329.43038 -286.41675) (xy 329.37958 -286.41675) (xy 329.27798 -286.453072) (xy 329.27798 -286.643572)
			(xy 329.37958 -286.67964) (xy 329.43038 -286.67964)
		)
		(stroke
			(width 0)
			(type solid)
		)
		(fill yes)
		(layer "F.Cu")
		(net "M_A_CPU0_SA_DQ<7>")
	)
	(gr_poly
		(pts
			(xy 329.43038 -285.81985) (xy 329.37958 -285.81985) (xy 329.27798 -285.856172) (xy 329.27798 -286.046672)
			(xy 329.37958 -286.08274) (xy 329.43038 -286.08274)
		)
		(stroke
			(width 0)
			(type solid)
		)
		(fill yes)
		(layer "F.Cu")
		(net "M_A_CPU0_SA_DQ<7>")
	)
	(gr_poly
		(pts
			(xy 329.43038 -285.22295) (xy 329.37958 -285.22295) (xy 329.27798 -285.259272) (xy 329.27798 -285.449772)
			(xy 329.37958 -285.48584) (xy 329.43038 -285.48584)
		)
		(stroke
			(width 0)
			(type solid)
		)
		(fill yes)
		(layer "F.Cu")
		(net "M_A_CPU0_SA_DQ<7>")
	)
	(gr_poly
		(pts
			(xy 329.43038 -284.62605) (xy 329.37958 -284.62605) (xy 329.27798 -284.662372) (xy 329.27798 -284.852872)
			(xy 329.37958 -284.88894) (xy 329.43038 -284.88894)
		)
		(stroke
			(width 0)
			(type solid)
		)
		(fill yes)
		(layer "F.Cu")
		(net "M_A_CPU0_SA_DQ<7>")
	)
	(gr_poly
		(pts
			(xy 329.43038 -284.02915) (xy 329.37958 -284.02915) (xy 329.27798 -284.065472) (xy 329.27798 -284.255972)
			(xy 329.37958 -284.29204) (xy 329.43038 -284.29204)
		)
		(stroke
			(width 0)
			(type solid)
		)
		(fill yes)
		(layer "F.Cu")
		(net "M_A_CPU0_SA_DQ<7>")
	)
	(gr_poly
		(pts
			(xy 329.43038 -283.43225) (xy 329.37958 -283.43225) (xy 329.27798 -283.468572) (xy 329.27798 -283.659072)
			(xy 329.37958 -283.69514) (xy 329.43038 -283.69514)
		)
		(stroke
			(width 0)
			(type solid)
		)
		(fill yes)
		(layer "F.Cu")
		(net "M_A_CPU0_SA_DQ<7>")
	)
	(gr_poly
		(pts
			(xy 329.43038 -282.83535) (xy 329.37958 -282.83535) (xy 329.27798 -282.871672) (xy 329.27798 -283.062172)
			(xy 329.37958 -283.09824) (xy 329.43038 -283.09824)
		)
		(stroke
			(width 0)
			(type solid)
		)
		(fill yes)
		(layer "F.Cu")
		(net "M_A_CPU0_SA_DQ<7>")
	)
	(gr_poly
		(pts
			(xy 329.432666 -236.01553) (xy 329.468734 -235.979716) (xy 329.282806 -235.793788) (xy 329.246738 -235.829602)
			(xy 329.20051 -235.927138) (xy 329.335384 -236.061758)
		)
		(stroke
			(width 0)
			(type solid)
		)
		(fill yes)
		(layer "F.Cu")
		(net "M_A_CPU0_SB_DQ<10>")
	)
	(gr_poly
		(pts
			(xy 329.442064 -235.16209) (xy 329.477878 -235.126276) (xy 329.29195 -234.940348) (xy 329.256136 -234.976416)
			(xy 329.209908 -235.073698) (xy 329.344528 -235.208318)
		)
		(stroke
			(width 0)
			(type solid)
		)
		(fill yes)
		(layer "F.Cu")
		(net "M_A_CPU0_SB_DQ<11>")
	)
	(gr_poly
		(pts
			(xy 329.459336 -279.625298) (xy 329.496674 -279.438354) (xy 329.404218 -279.382982) (xy 329.354434 -279.373076)
			(xy 329.302872 -279.630886) (xy 329.352656 -279.640792)
		)
		(stroke
			(width 0)
			(type solid)
		)
		(fill yes)
		(layer "F.Cu")
		(net "M_A_CPU0_SA_DQ<16>")
	)
	(gr_poly
		(pts
			(xy 329.478132 -225.641154) (xy 329.478132 -225.450654) (xy 329.376532 -225.414586) (xy 329.325732 -225.414586)
			(xy 329.325732 -225.677222) (xy 329.376532 -225.677222)
		)
		(stroke
			(width 0)
			(type solid)
		)
		(fill yes)
		(layer "F.Cu")
		(net "M_A_CPU0_SB_DQ<21>")
	)
	(gr_poly
		(pts
			(xy 329.478132 -225.044254) (xy 329.478132 -224.853754) (xy 329.376532 -224.817686) (xy 329.325732 -224.817686)
			(xy 329.325732 -225.080322) (xy 329.376532 -225.080322)
		)
		(stroke
			(width 0)
			(type solid)
		)
		(fill yes)
		(layer "F.Cu")
		(net "M_A_CPU0_SB_DQ<21>")
	)
	(gr_poly
		(pts
			(xy 329.47991 -232.612184) (xy 329.515724 -232.576116) (xy 329.329796 -232.390188) (xy 329.293982 -232.426256)
			(xy 329.247754 -232.523538) (xy 329.382374 -232.658412)
		)
		(stroke
			(width 0)
			(type solid)
		)
		(fill yes)
		(layer "F.Cu")
		(net "M_A_CPU0_SB_DQ<14>")
	)
	(gr_poly
		(pts
			(xy 329.487276 -268.134592) (xy 329.441048 -268.03731) (xy 329.405234 -268.001242) (xy 329.219306 -268.18717)
			(xy 329.25512 -268.223238) (xy 329.352656 -268.269466)
		)
		(stroke
			(width 0)
			(type solid)
		)
		(fill yes)
		(layer "F.Cu")
		(net "M_A_CPU0_SA_DQ<31>")
	)
	(gr_poly
		(pts
			(xy 329.489054 -231.758744) (xy 329.525122 -231.72293) (xy 329.339194 -231.537002) (xy 329.303126 -231.572816)
			(xy 329.256898 -231.670352) (xy 329.391772 -231.804972)
		)
		(stroke
			(width 0)
			(type solid)
		)
		(fill yes)
		(layer "F.Cu")
		(net "M_A_CPU0_SB_DQ<15>")
	)
	(gr_poly
		(pts
			(xy 329.489816 -273.98218) (xy 329.454002 -273.946366) (xy 329.356466 -273.899884) (xy 329.221846 -274.034758)
			(xy 329.268074 -274.13204) (xy 329.303888 -274.168108)
		)
		(stroke
			(width 0)
			(type solid)
		)
		(fill yes)
		(layer "F.Cu")
		(net "M_A_CPU0_SA_DQ<21>")
	)
	(gr_poly
		(pts
			(xy 329.493372 -218.326716) (xy 329.493372 -218.136216) (xy 329.391772 -218.099894) (xy 329.340972 -218.099894)
			(xy 329.340972 -218.363038) (xy 329.391772 -218.363038)
		)
		(stroke
			(width 0)
			(type solid)
		)
		(fill yes)
		(layer "F.Cu")
		(net "M_A_CPU0_SB_DQ<24>")
	)
	(gr_poly
		(pts
			(xy 329.493372 -217.729816) (xy 329.493372 -217.539316) (xy 329.391772 -217.502994) (xy 329.340972 -217.502994)
			(xy 329.340972 -217.766138) (xy 329.391772 -217.766138)
		)
		(stroke
			(width 0)
			(type solid)
		)
		(fill yes)
		(layer "F.Cu")
		(net "M_A_CPU0_SB_DQ<24>")
	)
	(gr_poly
		(pts
			(xy 329.493372 -217.132916) (xy 329.493372 -216.942416) (xy 329.391772 -216.906094) (xy 329.340972 -216.906094)
			(xy 329.340972 -217.169238) (xy 329.391772 -217.169238)
		)
		(stroke
			(width 0)
			(type solid)
		)
		(fill yes)
		(layer "F.Cu")
		(net "M_A_CPU0_SB_DQ<24>")
	)
	(gr_poly
		(pts
			(xy 329.493372 -216.536016) (xy 329.493372 -216.345516) (xy 329.391772 -216.309194) (xy 329.340972 -216.309194)
			(xy 329.340972 -216.572338) (xy 329.391772 -216.572338)
		)
		(stroke
			(width 0)
			(type solid)
		)
		(fill yes)
		(layer "F.Cu")
		(net "M_A_CPU0_SB_DQ<24>")
	)
	(gr_poly
		(pts
			(xy 329.496928 -268.98854) (xy 329.4507 -268.891258) (xy 329.414886 -268.85519) (xy 329.228958 -269.041118)
			(xy 329.264772 -269.076932) (xy 329.362308 -269.12316)
		)
		(stroke
			(width 0)
			(type solid)
		)
		(fill yes)
		(layer "F.Cu")
		(net "M_A_CPU0_SA_DQ<30>")
	)
	(gr_poly
		(pts
			(xy 329.499214 -230.489252) (xy 329.535028 -230.453438) (xy 329.3491 -230.26751) (xy 329.313286 -230.303578)
			(xy 329.267058 -230.40086) (xy 329.401678 -230.53548)
		)
		(stroke
			(width 0)
			(type solid)
		)
		(fill yes)
		(layer "F.Cu")
		(net "M_A_CPU0_SB_DQ<18>")
	)
	(gr_poly
		(pts
			(xy 329.499722 -274.836382) (xy 329.463908 -274.800568) (xy 329.366372 -274.75434) (xy 329.231752 -274.88896)
			(xy 329.27798 -274.986242) (xy 329.313794 -275.02231)
		)
		(stroke
			(width 0)
			(type solid)
		)
		(fill yes)
		(layer "F.Cu")
		(net "M_A_CPU0_SA_DQ<20>")
	)
	(gr_poly
		(pts
			(xy 329.499976 -236.370368) (xy 329.546204 -236.273086) (xy 329.411584 -236.138212) (xy 329.314048 -236.18444)
			(xy 329.278234 -236.220508) (xy 329.464162 -236.406436)
		)
		(stroke
			(width 0)
			(type solid)
		)
		(fill yes)
		(layer "F.Cu")
		(net "M_A_CPU0_SB_DQ<8>")
	)
	(gr_poly
		(pts
			(xy 329.508358 -229.636066) (xy 329.544172 -229.599998) (xy 329.358244 -229.41407) (xy 329.32243 -229.450138)
			(xy 329.276202 -229.54742) (xy 329.410822 -229.682294)
		)
		(stroke
			(width 0)
			(type solid)
		)
		(fill yes)
		(layer "F.Cu")
		(net "M_A_CPU0_SB_DQ<19>")
	)
	(gr_poly
		(pts
			(xy 329.50912 -235.516928) (xy 329.555348 -235.419646) (xy 329.420728 -235.284772) (xy 329.323192 -235.331254)
			(xy 329.287378 -235.367068) (xy 329.473306 -235.552996)
		)
		(stroke
			(width 0)
			(type solid)
		)
		(fill yes)
		(layer "F.Cu")
		(net "M_A_CPU0_SB_DQ<9>")
	)
	(gr_poly
		(pts
			(xy 329.513184 -281.532584) (xy 329.4634 -281.522678) (xy 329.35672 -281.538172) (xy 329.319382 -281.725116)
			(xy 329.412092 -281.780488) (xy 329.461876 -281.790394)
		)
		(stroke
			(width 0)
			(type solid)
		)
		(fill yes)
		(layer "F.Cu")
		(net "M_A_CPU0_SA_DQ<7>")
	)
	(gr_poly
		(pts
			(xy 329.5142 -227.485448) (xy 329.550014 -227.44938) (xy 329.36434 -227.263706) (xy 329.328272 -227.29952)
			(xy 329.282044 -227.397056) (xy 329.416664 -227.531676)
		)
		(stroke
			(width 0)
			(type solid)
		)
		(fill yes)
		(layer "F.Cu")
		(net "M_A_CPU0_SB_DQ<20>")
	)
	(gr_poly
		(pts
			(xy 329.530202 -261.215886) (xy 329.494134 -261.180072) (xy 329.396852 -261.133844) (xy 329.261978 -261.268464)
			(xy 329.30846 -261.366) (xy 329.344274 -261.401814)
		)
		(stroke
			(width 0)
			(type solid)
		)
		(fill yes)
		(layer "F.Cu")
		(net "M_A_CPU0_SA_CB<5>")
	)
	(gr_poly
		(pts
			(xy 329.533504 -223.927924) (xy 329.579732 -223.830388) (xy 329.445112 -223.695768) (xy 329.347576 -223.741996)
			(xy 329.311508 -223.77781) (xy 329.497436 -223.963738)
		)
		(stroke
			(width 0)
			(type solid)
		)
		(fill yes)
		(layer "F.Cu")
		(net "M_A_CPU0_SB_DQ<23>")
	)
	(gr_poly
		(pts
			(xy 329.5396 -262.06958) (xy 329.503786 -262.033512) (xy 329.40625 -261.987284) (xy 329.27163 -262.122158)
			(xy 329.317858 -262.21944) (xy 329.353672 -262.255508)
		)
		(stroke
			(width 0)
			(type solid)
		)
		(fill yes)
		(layer "F.Cu")
		(net "M_A_CPU0_SA_CB<4>")
	)
	(gr_poly
		(pts
			(xy 329.544426 -271.746218) (xy 329.508612 -271.71015) (xy 329.411076 -271.663922) (xy 329.276456 -271.798796)
			(xy 329.322684 -271.896078) (xy 329.358498 -271.932146)
		)
		(stroke
			(width 0)
			(type solid)
		)
		(fill yes)
		(layer "F.Cu")
		(net "M_A_CPU0_SA_DQ<25>")
	)
	(gr_poly
		(pts
			(xy 329.544426 -264.652506) (xy 329.508612 -264.616438) (xy 329.411076 -264.57021) (xy 329.276456 -264.70483)
			(xy 329.322684 -264.802366) (xy 329.358752 -264.83818)
		)
		(stroke
			(width 0)
			(type solid)
		)
		(fill yes)
		(layer "F.Cu")
		(net "M_A_CPU0_SA_CB<1>")
	)
	(gr_poly
		(pts
			(xy 329.546966 -232.967022) (xy 329.593194 -232.86974) (xy 329.458574 -232.734866) (xy 329.361038 -232.781094)
			(xy 329.325224 -232.817162) (xy 329.511152 -233.00309)
		)
		(stroke
			(width 0)
			(type solid)
		)
		(fill yes)
		(layer "F.Cu")
		(net "M_A_CPU0_SB_DQ<12>")
	)
	(gr_poly
		(pts
			(xy 329.55357 -272.599658) (xy 329.517756 -272.56359) (xy 329.42022 -272.517362) (xy 329.2856 -272.651982)
			(xy 329.331828 -272.749518) (xy 329.367896 -272.785332)
		)
		(stroke
			(width 0)
			(type solid)
		)
		(fill yes)
		(layer "F.Cu")
		(net "M_A_CPU0_SA_DQ<24>")
	)
	(gr_poly
		(pts
			(xy 329.553824 -265.505946) (xy 329.51801 -265.469878) (xy 329.420474 -265.42365) (xy 329.285854 -265.558524)
			(xy 329.332082 -265.655806) (xy 329.367896 -265.691874)
		)
		(stroke
			(width 0)
			(type solid)
		)
		(fill yes)
		(layer "F.Cu")
		(net "M_A_CPU0_SA_CB<0>")
	)
	(gr_poly
		(pts
			(xy 329.556364 -232.113582) (xy 329.602592 -232.016046) (xy 329.467972 -231.881426) (xy 329.370436 -231.927654)
			(xy 329.334622 -231.963722) (xy 329.520296 -232.149396)
		)
		(stroke
			(width 0)
			(type solid)
		)
		(fill yes)
		(layer "F.Cu")
		(net "M_A_CPU0_SB_DQ<13>")
	)
	(gr_poly
		(pts
			(xy 329.56627 -230.84409) (xy 329.612498 -230.746808) (xy 329.477878 -230.611934) (xy 329.380342 -230.658416)
			(xy 329.344528 -230.69423) (xy 329.530456 -230.880158)
		)
		(stroke
			(width 0)
			(type solid)
		)
		(fill yes)
		(layer "F.Cu")
		(net "M_A_CPU0_SB_DQ<16>")
	)
	(gr_poly
		(pts
			(xy 329.567286 -273.68881) (xy 329.521058 -273.591274) (xy 329.485244 -273.55546) (xy 329.299316 -273.741134)
			(xy 329.33513 -273.777202) (xy 329.432666 -273.82343)
		)
		(stroke
			(width 0)
			(type solid)
		)
		(fill yes)
		(layer "F.Cu")
		(net "M_A_CPU0_SA_DQ<23>")
	)
	(gr_poly
		(pts
			(xy 329.575668 -229.990904) (xy 329.621896 -229.893368) (xy 329.487022 -229.758748) (xy 329.38974 -229.804976)
			(xy 329.353672 -229.84079) (xy 329.5396 -230.026718)
		)
		(stroke
			(width 0)
			(type solid)
		)
		(fill yes)
		(layer "F.Cu")
		(net "M_A_CPU0_SB_DQ<17>")
	)
	(gr_poly
		(pts
			(xy 329.576684 -274.54225) (xy 329.530456 -274.444968) (xy 329.494388 -274.4089) (xy 329.30846 -274.594828)
			(xy 329.344528 -274.630642) (xy 329.44181 -274.677124)
		)
		(stroke
			(width 0)
			(type solid)
		)
		(fill yes)
		(layer "F.Cu")
		(net "M_A_CPU0_SA_DQ<22>")
	)
	(gr_poly
		(pts
			(xy 329.58278 -293.507922) (xy 329.58278 -293.317422) (xy 329.48118 -293.2811) (xy 329.43038 -293.2811)
			(xy 329.43038 -293.54399) (xy 329.48118 -293.54399)
		)
		(stroke
			(width 0)
			(type solid)
		)
		(fill yes)
		(layer "F.Cu")
		(net "M_A_CPU0_SA_DQ<7>")
	)
	(gr_poly
		(pts
			(xy 329.58278 -292.911022) (xy 329.58278 -292.720522) (xy 329.48118 -292.6842) (xy 329.43038 -292.6842)
			(xy 329.43038 -292.94709) (xy 329.48118 -292.94709)
		)
		(stroke
			(width 0)
			(type solid)
		)
		(fill yes)
		(layer "F.Cu")
		(net "M_A_CPU0_SA_DQ<7>")
	)
	(gr_poly
		(pts
			(xy 329.58278 -292.314122) (xy 329.58278 -292.123622) (xy 329.48118 -292.0873) (xy 329.43038 -292.0873)
			(xy 329.43038 -292.35019) (xy 329.48118 -292.35019)
		)
		(stroke
			(width 0)
			(type solid)
		)
		(fill yes)
		(layer "F.Cu")
		(net "M_A_CPU0_SA_DQ<7>")
	)
	(gr_poly
		(pts
			(xy 329.58278 -291.717222) (xy 329.58278 -291.526722) (xy 329.48118 -291.4904) (xy 329.43038 -291.4904)
			(xy 329.43038 -291.75329) (xy 329.48118 -291.75329)
		)
		(stroke
			(width 0)
			(type solid)
		)
		(fill yes)
		(layer "F.Cu")
		(net "M_A_CPU0_SA_DQ<7>")
	)
	(gr_poly
		(pts
			(xy 329.58278 -291.120322) (xy 329.58278 -290.929822) (xy 329.48118 -290.8935) (xy 329.43038 -290.8935)
			(xy 329.43038 -291.15639) (xy 329.48118 -291.15639)
		)
		(stroke
			(width 0)
			(type solid)
		)
		(fill yes)
		(layer "F.Cu")
		(net "M_A_CPU0_SA_DQ<7>")
	)
	(gr_poly
		(pts
			(xy 329.58278 -290.523422) (xy 329.58278 -290.332922) (xy 329.48118 -290.2966) (xy 329.43038 -290.2966)
			(xy 329.43038 -290.55949) (xy 329.48118 -290.55949)
		)
		(stroke
			(width 0)
			(type solid)
		)
		(fill yes)
		(layer "F.Cu")
		(net "M_A_CPU0_SA_DQ<7>")
	)
	(gr_poly
		(pts
			(xy 329.58278 -289.926522) (xy 329.58278 -289.736022) (xy 329.48118 -289.6997) (xy 329.43038 -289.6997)
			(xy 329.43038 -289.96259) (xy 329.48118 -289.96259)
		)
		(stroke
			(width 0)
			(type solid)
		)
		(fill yes)
		(layer "F.Cu")
		(net "M_A_CPU0_SA_DQ<7>")
	)
	(gr_poly
		(pts
			(xy 329.58278 -289.329622) (xy 329.58278 -289.139122) (xy 329.48118 -289.1028) (xy 329.43038 -289.1028)
			(xy 329.43038 -289.36569) (xy 329.48118 -289.36569)
		)
		(stroke
			(width 0)
			(type solid)
		)
		(fill yes)
		(layer "F.Cu")
		(net "M_A_CPU0_SA_DQ<7>")
	)
	(gr_poly
		(pts
			(xy 329.58278 -288.732722) (xy 329.58278 -288.542222) (xy 329.48118 -288.5059) (xy 329.43038 -288.5059)
			(xy 329.43038 -288.76879) (xy 329.48118 -288.76879)
		)
		(stroke
			(width 0)
			(type solid)
		)
		(fill yes)
		(layer "F.Cu")
		(net "M_A_CPU0_SA_DQ<7>")
	)
	(gr_poly
		(pts
			(xy 329.58278 -288.135822) (xy 329.58278 -287.945322) (xy 329.48118 -287.909) (xy 329.43038 -287.909)
			(xy 329.43038 -288.17189) (xy 329.48118 -288.17189)
		)
		(stroke
			(width 0)
			(type solid)
		)
		(fill yes)
		(layer "F.Cu")
		(net "M_A_CPU0_SA_DQ<7>")
	)
	(gr_poly
		(pts
			(xy 329.58278 -287.538922) (xy 329.58278 -287.348422) (xy 329.48118 -287.3121) (xy 329.43038 -287.3121)
			(xy 329.43038 -287.57499) (xy 329.48118 -287.57499)
		)
		(stroke
			(width 0)
			(type solid)
		)
		(fill yes)
		(layer "F.Cu")
		(net "M_A_CPU0_SA_DQ<7>")
	)
	(gr_poly
		(pts
			(xy 329.58278 -286.942022) (xy 329.58278 -286.751522) (xy 329.48118 -286.7152) (xy 329.43038 -286.7152)
			(xy 329.43038 -286.97809) (xy 329.48118 -286.97809)
		)
		(stroke
			(width 0)
			(type solid)
		)
		(fill yes)
		(layer "F.Cu")
		(net "M_A_CPU0_SA_DQ<7>")
	)
	(gr_poly
		(pts
			(xy 329.58278 -286.345122) (xy 329.58278 -286.154622) (xy 329.48118 -286.1183) (xy 329.43038 -286.1183)
			(xy 329.43038 -286.38119) (xy 329.48118 -286.38119)
		)
		(stroke
			(width 0)
			(type solid)
		)
		(fill yes)
		(layer "F.Cu")
		(net "M_A_CPU0_SA_DQ<7>")
	)
	(gr_poly
		(pts
			(xy 329.58278 -285.748222) (xy 329.58278 -285.557722) (xy 329.48118 -285.5214) (xy 329.43038 -285.5214)
			(xy 329.43038 -285.78429) (xy 329.48118 -285.78429)
		)
		(stroke
			(width 0)
			(type solid)
		)
		(fill yes)
		(layer "F.Cu")
		(net "M_A_CPU0_SA_DQ<7>")
	)
	(gr_poly
		(pts
			(xy 329.58278 -285.151322) (xy 329.58278 -284.960822) (xy 329.48118 -284.9245) (xy 329.43038 -284.9245)
			(xy 329.43038 -285.18739) (xy 329.48118 -285.18739)
		)
		(stroke
			(width 0)
			(type solid)
		)
		(fill yes)
		(layer "F.Cu")
		(net "M_A_CPU0_SA_DQ<7>")
	)
	(gr_poly
		(pts
			(xy 329.58278 -284.554422) (xy 329.58278 -284.363922) (xy 329.48118 -284.3276) (xy 329.43038 -284.3276)
			(xy 329.43038 -284.59049) (xy 329.48118 -284.59049)
		)
		(stroke
			(width 0)
			(type solid)
		)
		(fill yes)
		(layer "F.Cu")
		(net "M_A_CPU0_SA_DQ<7>")
	)
	(gr_poly
		(pts
			(xy 329.58278 -283.957522) (xy 329.58278 -283.767022) (xy 329.48118 -283.7307) (xy 329.43038 -283.7307)
			(xy 329.43038 -283.99359) (xy 329.48118 -283.99359)
		)
		(stroke
			(width 0)
			(type solid)
		)
		(fill yes)
		(layer "F.Cu")
		(net "M_A_CPU0_SA_DQ<7>")
	)
	(gr_poly
		(pts
			(xy 329.58278 -283.360622) (xy 329.58278 -283.170122) (xy 329.48118 -283.1338) (xy 329.43038 -283.1338)
			(xy 329.43038 -283.39669) (xy 329.48118 -283.39669)
		)
		(stroke
			(width 0)
			(type solid)
		)
		(fill yes)
		(layer "F.Cu")
		(net "M_A_CPU0_SA_DQ<7>")
	)
	(gr_poly
		(pts
			(xy 329.58278 -282.763722) (xy 329.58278 -282.573222) (xy 329.48118 -282.5369) (xy 329.43038 -282.5369)
			(xy 329.43038 -282.79979) (xy 329.48118 -282.79979)
		)
		(stroke
			(width 0)
			(type solid)
		)
		(fill yes)
		(layer "F.Cu")
		(net "M_A_CPU0_SA_DQ<7>")
	)
	(gr_poly
		(pts
			(xy 329.590654 -226.986846) (xy 329.637136 -226.88931) (xy 329.502262 -226.75469) (xy 329.40498 -226.800918)
			(xy 329.368912 -226.836732) (xy 329.55484 -227.02266)
		)
		(stroke
			(width 0)
			(type solid)
		)
		(fill yes)
		(layer "F.Cu")
		(net "M_A_CPU0_SB_DQ<22>")
	)
	(gr_poly
		(pts
			(xy 329.591162 -276.902418) (xy 329.555348 -276.86635) (xy 329.457812 -276.820122) (xy 329.323192 -276.954996)
			(xy 329.36942 -277.052278) (xy 329.405234 -277.088346)
		)
		(stroke
			(width 0)
			(type solid)
		)
		(fill yes)
		(layer "F.Cu")
		(net "M_A_CPU0_SA_DQ<19>")
	)
	(gr_poly
		(pts
			(xy 329.607672 -260.922516) (xy 329.561444 -260.82498) (xy 329.525376 -260.789166) (xy 329.339448 -260.975094)
			(xy 329.375516 -261.010908) (xy 329.472798 -261.057136)
		)
		(stroke
			(width 0)
			(type solid)
		)
		(fill yes)
		(layer "F.Cu")
		(net "M_A_CPU0_SA_CB<7>")
	)
	(gr_poly
		(pts
			(xy 329.616054 -267.790422) (xy 329.58024 -267.754354) (xy 329.482704 -267.708126) (xy 329.348084 -267.842746)
			(xy 329.394312 -267.940282) (xy 329.43038 -267.976096)
		)
		(stroke
			(width 0)
			(type solid)
		)
		(fill yes)
		(layer "F.Cu")
		(net "M_A_CPU0_SA_DQ<31>")
	)
	(gr_poly
		(pts
			(xy 329.61707 -261.77621) (xy 329.570842 -261.678674) (xy 329.534774 -261.64286) (xy 329.3491 -261.828534)
			(xy 329.384914 -261.864602) (xy 329.48245 -261.91083)
		)
		(stroke
			(width 0)
			(type solid)
		)
		(fill yes)
		(layer "F.Cu")
		(net "M_A_CPU0_SA_CB<6>")
	)
	(gr_poly
		(pts
			(xy 329.617324 -259.618226) (xy 329.581256 -259.516626) (xy 329.390756 -259.516626) (xy 329.354434 -259.618226)
			(xy 329.354434 -259.669026) (xy 329.617324 -259.669026)
		)
		(stroke
			(width 0)
			(type solid)
		)
		(fill yes)
		(layer "F.Cu")
		(net "M_A_CPU0_SA_CS_N<0>")
	)
	(gr_poly
		(pts
			(xy 329.617324 -259.313426) (xy 329.581256 -259.211826) (xy 329.390756 -259.211826) (xy 329.354434 -259.313426)
			(xy 329.354434 -259.364226) (xy 329.617324 -259.364226)
		)
		(stroke
			(width 0)
			(type solid)
		)
		(fill yes)
		(layer "F.Cu")
		(net "M_A_CPU0_SA_CS_N<2>")
	)
	(gr_poly
		(pts
			(xy 329.617324 -259.008626) (xy 329.581256 -258.907026) (xy 329.390756 -258.907026) (xy 329.354434 -259.008626)
			(xy 329.354434 -259.059426) (xy 329.617324 -259.059426)
		)
		(stroke
			(width 0)
			(type solid)
		)
		(fill yes)
		(layer "F.Cu")
		(net "M_A_CPU0_SA_CS_N<3>")
	)
	(gr_poly
		(pts
			(xy 329.617324 -258.703826) (xy 329.581256 -258.602226) (xy 329.390756 -258.602226) (xy 329.354434 -258.703826)
			(xy 329.354434 -258.754626) (xy 329.617324 -258.754626)
		)
		(stroke
			(width 0)
			(type solid)
		)
		(fill yes)
		(layer "F.Cu")
		(net "M_A_CPU0_SA_CS_N<1>")
	)
	(gr_poly
		(pts
			(xy 329.617324 -258.399026) (xy 329.581256 -258.297426) (xy 329.390756 -258.297426) (xy 329.354434 -258.399026)
			(xy 329.354434 -258.449826) (xy 329.617324 -258.449826)
		)
		(stroke
			(width 0)
			(type solid)
		)
		(fill yes)
		(layer "F.Cu")
		(net "M_A_CPU0_SA_CA<0>")
	)
	(gr_poly
		(pts
			(xy 329.617324 -258.094226) (xy 329.581256 -257.992626) (xy 329.390756 -257.992626) (xy 329.354434 -258.094226)
			(xy 329.354434 -258.145026) (xy 329.617324 -258.145026)
		)
		(stroke
			(width 0)
			(type solid)
		)
		(fill yes)
		(layer "F.Cu")
		(net "M_A_CPU0_SA_CA<1>")
	)
	(gr_poly
		(pts
			(xy 329.617324 -257.789426) (xy 329.581256 -257.687826) (xy 329.390756 -257.687826) (xy 329.354434 -257.789426)
			(xy 329.354434 -257.840226) (xy 329.617324 -257.840226)
		)
		(stroke
			(width 0)
			(type solid)
		)
		(fill yes)
		(layer "F.Cu")
		(net "M_A_CPU0_SA_CA<2>")
	)
	(gr_poly
		(pts
			(xy 329.617324 -257.484626) (xy 329.581256 -257.383026) (xy 329.390756 -257.383026) (xy 329.354434 -257.484626)
			(xy 329.354434 -257.535426) (xy 329.617324 -257.535426)
		)
		(stroke
			(width 0)
			(type solid)
		)
		(fill yes)
		(layer "F.Cu")
		(net "M_A_CPU0_SA_CA<3>")
	)
	(gr_poly
		(pts
			(xy 329.617324 -257.179826) (xy 329.581256 -257.078226) (xy 329.390756 -257.078226) (xy 329.354434 -257.179826)
			(xy 329.354434 -257.230626) (xy 329.617324 -257.230626)
		)
		(stroke
			(width 0)
			(type solid)
		)
		(fill yes)
		(layer "F.Cu")
		(net "M_A_CPU0_SA_CA<4>")
	)
	(gr_poly
		(pts
			(xy 329.617324 -256.875026) (xy 329.581256 -256.773426) (xy 329.390756 -256.773426) (xy 329.354434 -256.875026)
			(xy 329.354434 -256.925826) (xy 329.617324 -256.925826)
		)
		(stroke
			(width 0)
			(type solid)
		)
		(fill yes)
		(layer "F.Cu")
		(net "M_A_CPU0_SA_CA<5>")
	)
	(gr_poly
		(pts
			(xy 329.617324 -256.570226) (xy 329.581256 -256.468626) (xy 329.390756 -256.468626) (xy 329.354434 -256.570226)
			(xy 329.354434 -256.621026) (xy 329.617324 -256.621026)
		)
		(stroke
			(width 0)
			(type solid)
		)
		(fill yes)
		(layer "F.Cu")
		(net "M_A_CPU0_SA_CA<6>")
	)
	(gr_poly
		(pts
			(xy 329.617324 -256.265426) (xy 329.581256 -256.163826) (xy 329.390756 -256.163826) (xy 329.354434 -256.265426)
			(xy 329.354434 -256.316226) (xy 329.617324 -256.316226)
		)
		(stroke
			(width 0)
			(type solid)
		)
		(fill yes)
		(layer "F.Cu")
		(net "M_A_CPU0_SA_PAR")
	)
	(gr_poly
		(pts
			(xy 329.621642 -271.452594) (xy 329.575414 -271.355058) (xy 329.5396 -271.319244) (xy 329.353672 -271.505172)
			(xy 329.38974 -271.540986) (xy 329.487022 -271.587214)
		)
		(stroke
			(width 0)
			(type solid)
		)
		(fill yes)
		(layer "F.Cu")
		(net "M_A_CPU0_SA_DQ<27>")
	)
	(gr_poly
		(pts
			(xy 329.62215 -264.359136) (xy 329.575922 -264.2616) (xy 329.539854 -264.225786) (xy 329.353926 -264.411714)
			(xy 329.389994 -264.447528) (xy 329.487276 -264.493756)
		)
		(stroke
			(width 0)
			(type solid)
		)
		(fill yes)
		(layer "F.Cu")
		(net "M_A_CPU0_SA_CB<3>")
	)
	(gr_poly
		(pts
			(xy 329.625706 -278.113998) (xy 329.553316 -278.033988) (xy 329.508612 -278.010112) (xy 329.384406 -278.24176)
			(xy 329.429364 -278.26589) (xy 329.53579 -278.281892)
		)
		(stroke
			(width 0)
			(type solid)
		)
		(fill yes)
		(layer "F.Cu")
		(net "M_A_CPU0_SA_DQ<18>")
	)
	(gr_poly
		(pts
			(xy 329.62596 -268.644116) (xy 329.589892 -268.608302) (xy 329.49261 -268.562074) (xy 329.357736 -268.696694)
			(xy 329.403964 -268.79423) (xy 329.440032 -268.830044)
		)
		(stroke
			(width 0)
			(type solid)
		)
		(fill yes)
		(layer "F.Cu")
		(net "M_A_CPU0_SA_DQ<30>")
	)
	(gr_poly
		(pts
			(xy 329.630278 -280.947368) (xy 329.580494 -280.937462) (xy 329.47356 -280.952956) (xy 329.436476 -281.139646)
			(xy 329.528932 -281.195018) (xy 329.578716 -281.205178)
		)
		(stroke
			(width 0)
			(type solid)
		)
		(fill yes)
		(layer "F.Cu")
		(net "M_A_CPU0_SA_DQ<7>")
	)
	(gr_poly
		(pts
			(xy 329.630532 -225.712782) (xy 329.579732 -225.712782) (xy 329.478132 -225.749104) (xy 329.478132 -225.939604)
			(xy 329.579732 -225.975926) (xy 329.630532 -225.975926)
		)
		(stroke
			(width 0)
			(type solid)
		)
		(fill yes)
		(layer "F.Cu")
		(net "M_A_CPU0_SB_DQ<23>")
	)
	(gr_poly
		(pts
			(xy 329.630532 -225.115882) (xy 329.579732 -225.115882) (xy 329.478132 -225.152204) (xy 329.478132 -225.342704)
			(xy 329.579732 -225.379026) (xy 329.630532 -225.379026)
		)
		(stroke
			(width 0)
			(type solid)
		)
		(fill yes)
		(layer "F.Cu")
		(net "M_A_CPU0_SB_DQ<23>")
	)
	(gr_poly
		(pts
			(xy 329.630532 -224.518982) (xy 329.579732 -224.518982) (xy 329.478132 -224.555304) (xy 329.478132 -224.745804)
			(xy 329.579732 -224.782126) (xy 329.630532 -224.782126)
		)
		(stroke
			(width 0)
			(type solid)
		)
		(fill yes)
		(layer "F.Cu")
		(net "M_A_CPU0_SB_DQ<23>")
	)
	(gr_poly
		(pts
			(xy 329.631294 -272.306288) (xy 329.585066 -272.208752) (xy 329.548998 -272.172938) (xy 329.36307 -272.358866)
			(xy 329.399138 -272.39468) (xy 329.49642 -272.440908)
		)
		(stroke
			(width 0)
			(type solid)
		)
		(fill yes)
		(layer "F.Cu")
		(net "M_A_CPU0_SA_DQ<26>")
	)
	(gr_poly
		(pts
			(xy 329.631548 -265.212576) (xy 329.58532 -265.11504) (xy 329.549252 -265.079226) (xy 329.363324 -265.265154)
			(xy 329.399392 -265.300968) (xy 329.496674 -265.347196)
		)
		(stroke
			(width 0)
			(type solid)
		)
		(fill yes)
		(layer "F.Cu")
		(net "M_A_CPU0_SA_CB<2>")
	)
	(gr_poly
		(pts
			(xy 329.639168 -236.653324) (xy 329.674982 -236.617256) (xy 329.489308 -236.431582) (xy 329.45324 -236.467396)
			(xy 329.407012 -236.564932) (xy 329.541632 -236.699552)
		)
		(stroke
			(width 0)
			(type solid)
		)
		(fill yes)
		(layer "F.Cu")
		(net "M_A_CPU0_SB_DQ<8>")
	)
	(gr_poly
		(pts
			(xy 329.645772 -217.801698) (xy 329.594972 -217.801698) (xy 329.493372 -217.837766) (xy 329.493372 -218.028266)
			(xy 329.594972 -218.064334) (xy 329.645772 -218.064334)
		)
		(stroke
			(width 0)
			(type solid)
		)
		(fill yes)
		(layer "F.Cu")
		(net "M_A_CPU0_SB_DQ<26>")
	)
	(gr_poly
		(pts
			(xy 329.645772 -217.204798) (xy 329.594972 -217.204798) (xy 329.493372 -217.240866) (xy 329.493372 -217.431366)
			(xy 329.594972 -217.467434) (xy 329.645772 -217.467434)
		)
		(stroke
			(width 0)
			(type solid)
		)
		(fill yes)
		(layer "F.Cu")
		(net "M_A_CPU0_SB_DQ<26>")
	)
	(gr_poly
		(pts
			(xy 329.645772 -216.607898) (xy 329.594972 -216.607898) (xy 329.493372 -216.643966) (xy 329.493372 -216.834466)
			(xy 329.594972 -216.870534) (xy 329.645772 -216.870534)
		)
		(stroke
			(width 0)
			(type solid)
		)
		(fill yes)
		(layer "F.Cu")
		(net "M_A_CPU0_SB_DQ<26>")
	)
	(gr_poly
		(pts
			(xy 329.648312 -235.799884) (xy 329.68438 -235.76407) (xy 329.498452 -235.578142) (xy 329.462384 -235.613956)
			(xy 329.416156 -235.711492) (xy 329.55103 -235.846112)
		)
		(stroke
			(width 0)
			(type solid)
		)
		(fill yes)
		(layer "F.Cu")
		(net "M_A_CPU0_SB_DQ<9>")
	)
	(gr_poly
		(pts
			(xy 329.67676 -281.492198) (xy 329.714098 -281.305254) (xy 329.621642 -281.249882) (xy 329.571858 -281.239976)
			(xy 329.520296 -281.497786) (xy 329.57008 -281.507692)
		)
		(stroke
			(width 0)
			(type solid)
		)
		(fill yes)
		(layer "F.Cu")
		(net "M_A_CPU0_SA_DQ<7>")
	)
	(gr_poly
		(pts
			(xy 329.686158 -233.249978) (xy 329.721972 -233.21391) (xy 329.536298 -233.028236) (xy 329.50023 -233.06405)
			(xy 329.454002 -233.161586) (xy 329.588622 -233.296206)
		)
		(stroke
			(width 0)
			(type solid)
		)
		(fill yes)
		(layer "F.Cu")
		(net "M_A_CPU0_SB_DQ<12>")
	)
	(gr_poly
		(pts
			(xy 329.695556 -232.396538) (xy 329.73137 -232.36047) (xy 329.545442 -232.174542) (xy 329.509628 -232.21061)
			(xy 329.4634 -232.307892) (xy 329.59802 -232.442766)
		)
		(stroke
			(width 0)
			(type solid)
		)
		(fill yes)
		(layer "F.Cu")
		(net "M_A_CPU0_SB_DQ<13>")
	)
	(gr_poly
		(pts
			(xy 329.696318 -273.344386) (xy 329.66025 -273.308318) (xy 329.562968 -273.26209) (xy 329.428094 -273.396964)
			(xy 329.474322 -273.494246) (xy 329.51039 -273.530314)
		)
		(stroke
			(width 0)
			(type solid)
		)
		(fill yes)
		(layer "F.Cu")
		(net "M_A_CPU0_SA_DQ<23>")
	)
	(gr_poly
		(pts
			(xy 329.703176 -268.350492) (xy 329.656948 -268.252956) (xy 329.62088 -268.217142) (xy 329.434952 -268.40307)
			(xy 329.47102 -268.438884) (xy 329.568302 -268.485112)
		)
		(stroke
			(width 0)
			(type solid)
		)
		(fill yes)
		(layer "F.Cu")
		(net "M_A_CPU0_SA_DQ<29>")
	)
	(gr_poly
		(pts
			(xy 329.705462 -274.197826) (xy 329.669648 -274.162012) (xy 329.572112 -274.115784) (xy 329.437492 -274.250404)
			(xy 329.48372 -274.34794) (xy 329.519534 -274.383754)
		)
		(stroke
			(width 0)
			(type solid)
		)
		(fill yes)
		(layer "F.Cu")
		(net "M_A_CPU0_SA_DQ<22>")
	)
	(gr_poly
		(pts
			(xy 329.705462 -231.127046) (xy 329.74153 -231.091232) (xy 329.555602 -230.905304) (xy 329.519534 -230.941118)
			(xy 329.473306 -231.038654) (xy 329.60818 -231.173274)
		)
		(stroke
			(width 0)
			(type solid)
		)
		(fill yes)
		(layer "F.Cu")
		(net "M_A_CPU0_SB_DQ<16>")
	)
	(gr_poly
		(pts
			(xy 329.712574 -269.204186) (xy 329.666346 -269.106904) (xy 329.630532 -269.070836) (xy 329.444604 -269.256764)
			(xy 329.480418 -269.292578) (xy 329.577954 -269.338806)
		)
		(stroke
			(width 0)
			(type solid)
		)
		(fill yes)
		(layer "F.Cu")
		(net "M_A_CPU0_SA_DQ<28>")
	)
	(gr_poly
		(pts
			(xy 329.71486 -230.273606) (xy 329.750674 -230.237792) (xy 329.564746 -230.051864) (xy 329.528932 -230.087932)
			(xy 329.482704 -230.185214) (xy 329.617324 -230.319834)
		)
		(stroke
			(width 0)
			(type solid)
		)
		(fill yes)
		(layer "F.Cu")
		(net "M_A_CPU0_SB_DQ<17>")
	)
	(gr_poly
		(pts
			(xy 329.715622 -236.154722) (xy 329.76185 -236.05744) (xy 329.62723 -235.922566) (xy 329.529694 -235.968794)
			(xy 329.49388 -236.004862) (xy 329.679808 -236.19079)
		)
		(stroke
			(width 0)
			(type solid)
		)
		(fill yes)
		(layer "F.Cu")
		(net "M_A_CPU0_SB_DQ<10>")
	)
	(gr_poly
		(pts
			(xy 329.724766 -235.301282) (xy 329.770994 -235.204) (xy 329.636374 -235.069126) (xy 329.538838 -235.115608)
			(xy 329.503024 -235.151422) (xy 329.688952 -235.33735)
		)
		(stroke
			(width 0)
			(type solid)
		)
		(fill yes)
		(layer "F.Cu")
		(net "M_A_CPU0_SB_DQ<11>")
	)
	(gr_poly
		(pts
			(xy 329.729846 -227.269548) (xy 329.765914 -227.233734) (xy 329.579986 -227.047806) (xy 329.544172 -227.08362)
			(xy 329.497944 -227.181156) (xy 329.632564 -227.315776)
		)
		(stroke
			(width 0)
			(type solid)
		)
		(fill yes)
		(layer "F.Cu")
		(net "M_A_CPU0_SB_DQ<22>")
	)
	(gr_poly
		(pts
			(xy 329.73518 -293.57955) (xy 329.68438 -293.57955) (xy 329.58278 -293.615872) (xy 329.58278 -293.806372)
			(xy 329.68438 -293.84244) (xy 329.73518 -293.84244)
		)
		(stroke
			(width 0)
			(type solid)
		)
		(fill yes)
		(layer "F.Cu")
		(net "M_A_CPU0_SA_DQ<5>")
	)
	(gr_poly
		(pts
			(xy 329.73518 -292.98265) (xy 329.68438 -292.98265) (xy 329.58278 -293.018972) (xy 329.58278 -293.209472)
			(xy 329.68438 -293.24554) (xy 329.73518 -293.24554)
		)
		(stroke
			(width 0)
			(type solid)
		)
		(fill yes)
		(layer "F.Cu")
		(net "M_A_CPU0_SA_DQ<5>")
	)
	(gr_poly
		(pts
			(xy 329.73518 -292.38575) (xy 329.68438 -292.38575) (xy 329.58278 -292.422072) (xy 329.58278 -292.612572)
			(xy 329.68438 -292.64864) (xy 329.73518 -292.64864)
		)
		(stroke
			(width 0)
			(type solid)
		)
		(fill yes)
		(layer "F.Cu")
		(net "M_A_CPU0_SA_DQ<5>")
	)
	(gr_poly
		(pts
			(xy 329.73518 -291.78885) (xy 329.68438 -291.78885) (xy 329.58278 -291.825172) (xy 329.58278 -292.015672)
			(xy 329.68438 -292.05174) (xy 329.73518 -292.05174)
		)
		(stroke
			(width 0)
			(type solid)
		)
		(fill yes)
		(layer "F.Cu")
		(net "M_A_CPU0_SA_DQ<5>")
	)
	(gr_poly
		(pts
			(xy 329.73518 -291.19195) (xy 329.68438 -291.19195) (xy 329.58278 -291.228272) (xy 329.58278 -291.418772)
			(xy 329.68438 -291.45484) (xy 329.73518 -291.45484)
		)
		(stroke
			(width 0)
			(type solid)
		)
		(fill yes)
		(layer "F.Cu")
		(net "M_A_CPU0_SA_DQ<5>")
	)
	(gr_poly
		(pts
			(xy 329.73518 -290.59505) (xy 329.68438 -290.59505) (xy 329.58278 -290.631372) (xy 329.58278 -290.821872)
			(xy 329.68438 -290.85794) (xy 329.73518 -290.85794)
		)
		(stroke
			(width 0)
			(type solid)
		)
		(fill yes)
		(layer "F.Cu")
		(net "M_A_CPU0_SA_DQ<5>")
	)
	(gr_poly
		(pts
			(xy 329.73518 -289.99815) (xy 329.68438 -289.99815) (xy 329.58278 -290.034472) (xy 329.58278 -290.224972)
			(xy 329.68438 -290.26104) (xy 329.73518 -290.26104)
		)
		(stroke
			(width 0)
			(type solid)
		)
		(fill yes)
		(layer "F.Cu")
		(net "M_A_CPU0_SA_DQ<5>")
	)
	(gr_poly
		(pts
			(xy 329.73518 -289.40125) (xy 329.68438 -289.40125) (xy 329.58278 -289.437572) (xy 329.58278 -289.628072)
			(xy 329.68438 -289.66414) (xy 329.73518 -289.66414)
		)
		(stroke
			(width 0)
			(type solid)
		)
		(fill yes)
		(layer "F.Cu")
		(net "M_A_CPU0_SA_DQ<5>")
	)
	(gr_poly
		(pts
			(xy 329.73518 -288.80435) (xy 329.68438 -288.80435) (xy 329.58278 -288.840672) (xy 329.58278 -289.031172)
			(xy 329.68438 -289.06724) (xy 329.73518 -289.06724)
		)
		(stroke
			(width 0)
			(type solid)
		)
		(fill yes)
		(layer "F.Cu")
		(net "M_A_CPU0_SA_DQ<5>")
	)
	(gr_poly
		(pts
			(xy 329.73518 -288.20745) (xy 329.68438 -288.20745) (xy 329.58278 -288.243772) (xy 329.58278 -288.434272)
			(xy 329.68438 -288.47034) (xy 329.73518 -288.47034)
		)
		(stroke
			(width 0)
			(type solid)
		)
		(fill yes)
		(layer "F.Cu")
		(net "M_A_CPU0_SA_DQ<5>")
	)
	(gr_poly
		(pts
			(xy 329.73518 -287.61055) (xy 329.68438 -287.61055) (xy 329.58278 -287.646872) (xy 329.58278 -287.837372)
			(xy 329.68438 -287.87344) (xy 329.73518 -287.87344)
		)
		(stroke
			(width 0)
			(type solid)
		)
		(fill yes)
		(layer "F.Cu")
		(net "M_A_CPU0_SA_DQ<5>")
	)
	(gr_poly
		(pts
			(xy 329.73518 -287.01365) (xy 329.68438 -287.01365) (xy 329.58278 -287.049972) (xy 329.58278 -287.240472)
			(xy 329.68438 -287.27654) (xy 329.73518 -287.27654)
		)
		(stroke
			(width 0)
			(type solid)
		)
		(fill yes)
		(layer "F.Cu")
		(net "M_A_CPU0_SA_DQ<5>")
	)
	(gr_poly
		(pts
			(xy 329.73518 -286.41675) (xy 329.68438 -286.41675) (xy 329.58278 -286.453072) (xy 329.58278 -286.643572)
			(xy 329.68438 -286.67964) (xy 329.73518 -286.67964)
		)
		(stroke
			(width 0)
			(type solid)
		)
		(fill yes)
		(layer "F.Cu")
		(net "M_A_CPU0_SA_DQ<5>")
	)
	(gr_poly
		(pts
			(xy 329.73518 -285.81985) (xy 329.68438 -285.81985) (xy 329.58278 -285.856172) (xy 329.58278 -286.046672)
			(xy 329.68438 -286.08274) (xy 329.73518 -286.08274)
		)
		(stroke
			(width 0)
			(type solid)
		)
		(fill yes)
		(layer "F.Cu")
		(net "M_A_CPU0_SA_DQ<5>")
	)
	(gr_poly
		(pts
			(xy 329.73518 -285.22295) (xy 329.68438 -285.22295) (xy 329.58278 -285.259272) (xy 329.58278 -285.449772)
			(xy 329.68438 -285.48584) (xy 329.73518 -285.48584)
		)
		(stroke
			(width 0)
			(type solid)
		)
		(fill yes)
		(layer "F.Cu")
		(net "M_A_CPU0_SA_DQ<5>")
	)
	(gr_poly
		(pts
			(xy 329.73518 -284.62605) (xy 329.68438 -284.62605) (xy 329.58278 -284.662372) (xy 329.58278 -284.852872)
			(xy 329.68438 -284.88894) (xy 329.73518 -284.88894)
		)
		(stroke
			(width 0)
			(type solid)
		)
		(fill yes)
		(layer "F.Cu")
		(net "M_A_CPU0_SA_DQ<5>")
	)
	(gr_poly
		(pts
			(xy 329.73518 -284.02915) (xy 329.68438 -284.02915) (xy 329.58278 -284.065472) (xy 329.58278 -284.255972)
			(xy 329.68438 -284.29204) (xy 329.73518 -284.29204)
		)
		(stroke
			(width 0)
			(type solid)
		)
		(fill yes)
		(layer "F.Cu")
		(net "M_A_CPU0_SA_DQ<5>")
	)
	(gr_poly
		(pts
			(xy 329.73518 -283.43225) (xy 329.68438 -283.43225) (xy 329.58278 -283.468572) (xy 329.58278 -283.659072)
			(xy 329.68438 -283.69514) (xy 329.73518 -283.69514)
		)
		(stroke
			(width 0)
			(type solid)
		)
		(fill yes)
		(layer "F.Cu")
		(net "M_A_CPU0_SA_DQ<5>")
	)
	(gr_poly
		(pts
			(xy 329.73518 -282.83535) (xy 329.68438 -282.83535) (xy 329.58278 -282.871672) (xy 329.58278 -283.062172)
			(xy 329.68438 -283.09824) (xy 329.73518 -283.09824)
		)
		(stroke
			(width 0)
			(type solid)
		)
		(fill yes)
		(layer "F.Cu")
		(net "M_A_CPU0_SA_DQ<5>")
	)
	(gr_poly
		(pts
			(xy 329.745848 -261.431786) (xy 329.710034 -261.395718) (xy 329.612498 -261.34949) (xy 329.477878 -261.484364)
			(xy 329.524106 -261.581646) (xy 329.55992 -261.617714)
		)
		(stroke
			(width 0)
			(type solid)
		)
		(fill yes)
		(layer "F.Cu")
		(net "M_A_CPU0_SA_CB<6>")
	)
	(gr_poly
		(pts
			(xy 329.747118 -280.361898) (xy 329.697334 -280.351992) (xy 329.590654 -280.367486) (xy 329.553316 -280.55443)
			(xy 329.645772 -280.609802) (xy 329.695556 -280.619708)
		)
		(stroke
			(width 0)
			(type solid)
		)
		(fill yes)
		(layer "F.Cu")
		(net "M_A_CPU0_SA_DQ<7>")
	)
	(gr_poly
		(pts
			(xy 329.750674 -271.10817) (xy 329.714606 -271.072356) (xy 329.617324 -271.026128) (xy 329.48245 -271.160748)
			(xy 329.528932 -271.258284) (xy 329.564746 -271.294098)
		)
		(stroke
			(width 0)
			(type solid)
		)
		(fill yes)
		(layer "F.Cu")
		(net "M_A_CPU0_SA_DQ<27>")
	)
	(gr_poly
		(pts
			(xy 329.750928 -264.014712) (xy 329.715114 -263.978644) (xy 329.617578 -263.932416) (xy 329.482958 -264.06729)
			(xy 329.529186 -264.164572) (xy 329.565 -264.20064)
		)
		(stroke
			(width 0)
			(type solid)
		)
		(fill yes)
		(layer "F.Cu")
		(net "M_A_CPU0_SA_CB<3>")
	)
	(gr_poly
		(pts
			(xy 329.760072 -271.961864) (xy 329.724258 -271.925796) (xy 329.626722 -271.879568) (xy 329.492102 -272.014442)
			(xy 329.53833 -272.111724) (xy 329.574144 -272.147792)
		)
		(stroke
			(width 0)
			(type solid)
		)
		(fill yes)
		(layer "F.Cu")
		(net "M_A_CPU0_SA_DQ<26>")
	)
	(gr_poly
		(pts
			(xy 329.760326 -264.868152) (xy 329.724512 -264.832338) (xy 329.626976 -264.78611) (xy 329.492356 -264.92073)
			(xy 329.538584 -265.018266) (xy 329.574398 -265.05408)
		)
		(stroke
			(width 0)
			(type solid)
		)
		(fill yes)
		(layer "F.Cu")
		(net "M_A_CPU0_SA_CB<2>")
	)
	(gr_poly
		(pts
			(xy 329.762866 -232.751376) (xy 329.809094 -232.65384) (xy 329.67422 -232.51922) (xy 329.576938 -232.565448)
			(xy 329.54087 -232.601262) (xy 329.726798 -232.78719)
		)
		(stroke
			(width 0)
			(type solid)
		)
		(fill yes)
		(layer "F.Cu")
		(net "M_A_CPU0_SB_DQ<14>")
	)
	(gr_poly
		(pts
			(xy 329.77201 -231.897936) (xy 329.818238 -231.8004) (xy 329.683618 -231.66578) (xy 329.586082 -231.712008)
			(xy 329.550268 -231.748076) (xy 329.735942 -231.93375)
		)
		(stroke
			(width 0)
			(type solid)
		)
		(fill yes)
		(layer "F.Cu")
		(net "M_A_CPU0_SB_DQ<15>")
	)
	(gr_poly
		(pts
			(xy 329.781916 -230.628444) (xy 329.828144 -230.531162) (xy 329.693524 -230.396288) (xy 329.595988 -230.44277)
			(xy 329.560174 -230.478584) (xy 329.746102 -230.664512)
		)
		(stroke
			(width 0)
			(type solid)
		)
		(fill yes)
		(layer "F.Cu")
		(net "M_A_CPU0_SB_DQ<18>")
	)
	(gr_poly
		(pts
			(xy 329.782932 -273.904456) (xy 329.736704 -273.807174) (xy 329.70089 -273.771106) (xy 329.514962 -273.957034)
			(xy 329.550776 -273.992848) (xy 329.648312 -274.03933)
		)
		(stroke
			(width 0)
			(type solid)
		)
		(fill yes)
		(layer "F.Cu")
		(net "M_A_CPU0_SA_DQ<21>")
	)
	(gr_poly
		(pts
			(xy 329.782932 -225.641154) (xy 329.782932 -225.450654) (xy 329.681332 -225.414586) (xy 329.630532 -225.414586)
			(xy 329.630532 -225.677222) (xy 329.681332 -225.677222)
		)
		(stroke
			(width 0)
			(type solid)
		)
		(fill yes)
		(layer "F.Cu")
		(net "M_A_CPU0_SB_DQ<23>")
	)
	(gr_poly
		(pts
			(xy 329.782932 -225.044254) (xy 329.782932 -224.853754) (xy 329.681332 -224.817686) (xy 329.630532 -224.817686)
			(xy 329.630532 -225.080322) (xy 329.681332 -225.080322)
		)
		(stroke
			(width 0)
			(type solid)
		)
		(fill yes)
		(layer "F.Cu")
		(net "M_A_CPU0_SB_DQ<23>")
	)
	(gr_poly
		(pts
			(xy 329.791314 -229.775258) (xy 329.837542 -229.677722) (xy 329.702668 -229.543102) (xy 329.605386 -229.58933)
			(xy 329.569318 -229.625144) (xy 329.755246 -229.811072)
		)
		(stroke
			(width 0)
			(type solid)
		)
		(fill yes)
		(layer "F.Cu")
		(net "M_A_CPU0_SB_DQ<19>")
	)
	(gr_poly
		(pts
			(xy 329.793092 -274.758658) (xy 329.746864 -274.661376) (xy 329.710796 -274.625308) (xy 329.524868 -274.811236)
			(xy 329.560936 -274.847304) (xy 329.658218 -274.893532)
		)
		(stroke
			(width 0)
			(type solid)
		)
		(fill yes)
		(layer "F.Cu")
		(net "M_A_CPU0_SA_DQ<20>")
	)
	(gr_poly
		(pts
			(xy 329.7936 -280.906728) (xy 329.830938 -280.720038) (xy 329.738482 -280.664666) (xy 329.688698 -280.654506)
			(xy 329.637136 -280.912316) (xy 329.68692 -280.922476)
		)
		(stroke
			(width 0)
			(type solid)
		)
		(fill yes)
		(layer "F.Cu")
		(net "M_A_CPU0_SA_DQ<7>")
	)
	(gr_poly
		(pts
			(xy 329.797156 -227.62464) (xy 329.843384 -227.527104) (xy 329.70851 -227.392484) (xy 329.611228 -227.438712)
			(xy 329.57516 -227.474526) (xy 329.761088 -227.660454)
		)
		(stroke
			(width 0)
			(type solid)
		)
		(fill yes)
		(layer "F.Cu")
		(net "M_A_CPU0_SB_DQ<20>")
	)
	(gr_poly
		(pts
			(xy 329.798172 -218.326716) (xy 329.798172 -218.136216) (xy 329.696572 -218.099894) (xy 329.645772 -218.099894)
			(xy 329.645772 -218.363038) (xy 329.696572 -218.363038)
		)
		(stroke
			(width 0)
			(type solid)
		)
		(fill yes)
		(layer "F.Cu")
		(net "M_A_CPU0_SB_DQ<26>")
	)
	(gr_poly
		(pts
			(xy 329.798172 -217.729816) (xy 329.798172 -217.539316) (xy 329.696572 -217.502994) (xy 329.645772 -217.502994)
			(xy 329.645772 -217.766138) (xy 329.696572 -217.766138)
		)
		(stroke
			(width 0)
			(type solid)
		)
		(fill yes)
		(layer "F.Cu")
		(net "M_A_CPU0_SB_DQ<26>")
	)
	(gr_poly
		(pts
			(xy 329.798172 -217.132916) (xy 329.798172 -216.942416) (xy 329.696572 -216.906094) (xy 329.645772 -216.906094)
			(xy 329.645772 -217.169238) (xy 329.696572 -217.169238)
		)
		(stroke
			(width 0)
			(type solid)
		)
		(fill yes)
		(layer "F.Cu")
		(net "M_A_CPU0_SB_DQ<26>")
	)
	(gr_poly
		(pts
			(xy 329.798172 -216.536016) (xy 329.798172 -216.345516) (xy 329.696572 -216.309194) (xy 329.645772 -216.309194)
			(xy 329.645772 -216.572338) (xy 329.696572 -216.572338)
		)
		(stroke
			(width 0)
			(type solid)
		)
		(fill yes)
		(layer "F.Cu")
		(net "M_A_CPU0_SB_DQ<26>")
	)
	(gr_poly
		(pts
			(xy 329.8063 -226.7712) (xy 329.852782 -226.673664) (xy 329.717908 -226.539044) (xy 329.620626 -226.585272)
			(xy 329.584558 -226.621086) (xy 329.770486 -226.807014)
		)
		(stroke
			(width 0)
			(type solid)
		)
		(fill yes)
		(layer "F.Cu")
		(net "M_A_CPU0_SB_DQ<21>")
	)
	(gr_poly
		(pts
			(xy 329.808586 -277.119588) (xy 329.772518 -277.083774) (xy 329.675236 -277.037546) (xy 329.540362 -277.172166)
			(xy 329.58659 -277.269702) (xy 329.622658 -277.305516)
		)
		(stroke
			(width 0)
			(type solid)
		)
		(fill yes)
		(layer "F.Cu")
		(net "M_A_CPU0_SA_DQ<17>")
	)
	(gr_poly
		(pts
			(xy 329.812396 -281.592274) (xy 329.762612 -281.582368) (xy 329.655932 -281.598116) (xy 329.618594 -281.784806)
			(xy 329.711304 -281.840178) (xy 329.761088 -281.850084)
		)
		(stroke
			(width 0)
			(type solid)
		)
		(fill yes)
		(layer "F.Cu")
		(net "M_A_CPU0_SA_DQ<5>")
	)
	(gr_poly
		(pts
			(xy 329.831954 -268.006068) (xy 329.79614 -267.970254) (xy 329.698604 -267.924026) (xy 329.563984 -268.058646)
			(xy 329.610212 -268.156182) (xy 329.646026 -268.191996)
		)
		(stroke
			(width 0)
			(type solid)
		)
		(fill yes)
		(layer "F.Cu")
		(net "M_A_CPU0_SA_DQ<29>")
	)
	(gr_poly
		(pts
			(xy 329.832716 -261.991856) (xy 329.786488 -261.89432) (xy 329.750674 -261.858506) (xy 329.564746 -262.044434)
			(xy 329.60056 -262.080248) (xy 329.698096 -262.126476)
		)
		(stroke
			(width 0)
			(type solid)
		)
		(fill yes)
		(layer "F.Cu")
		(net "M_A_CPU0_SA_CB<4>")
	)
	(gr_poly
		(pts
			(xy 329.837542 -271.668494) (xy 329.791314 -271.570958) (xy 329.7555 -271.535144) (xy 329.569572 -271.721072)
			(xy 329.60564 -271.756886) (xy 329.702922 -271.803114)
		)
		(stroke
			(width 0)
			(type solid)
		)
		(fill yes)
		(layer "F.Cu")
		(net "M_A_CPU0_SA_DQ<25>")
	)
	(gr_poly
		(pts
			(xy 329.837796 -264.574782) (xy 329.791568 -264.477246) (xy 329.7555 -264.441432) (xy 329.569572 -264.62736)
			(xy 329.60564 -264.663174) (xy 329.702922 -264.709402)
		)
		(stroke
			(width 0)
			(type solid)
		)
		(fill yes)
		(layer "F.Cu")
		(net "M_A_CPU0_SA_CB<1>")
	)
	(gr_poly
		(pts
			(xy 329.841606 -268.859762) (xy 329.805538 -268.823948) (xy 329.708256 -268.77772) (xy 329.573382 -268.91234)
			(xy 329.61961 -269.009876) (xy 329.655678 -269.04569)
		)
		(stroke
			(width 0)
			(type solid)
		)
		(fill yes)
		(layer "F.Cu")
		(net "M_A_CPU0_SA_DQ<28>")
	)
	(gr_poly
		(pts
			(xy 329.84694 -272.521934) (xy 329.800712 -272.424398) (xy 329.764644 -272.388584) (xy 329.578716 -272.574512)
			(xy 329.614784 -272.610326) (xy 329.712066 -272.656554)
		)
		(stroke
			(width 0)
			(type solid)
		)
		(fill yes)
		(layer "F.Cu")
		(net "M_A_CPU0_SA_DQ<24>")
	)
	(gr_poly
		(pts
			(xy 329.847194 -265.428222) (xy 329.800966 -265.330686) (xy 329.764898 -265.294872) (xy 329.57897 -265.4808)
			(xy 329.615038 -265.516614) (xy 329.71232 -265.562842)
		)
		(stroke
			(width 0)
			(type solid)
		)
		(fill yes)
		(layer "F.Cu")
		(net "M_A_CPU0_SA_CB<0>")
	)
	(gr_poly
		(pts
			(xy 329.854814 -236.437678) (xy 329.890628 -236.40161) (xy 329.704954 -236.215936) (xy 329.668886 -236.25175)
			(xy 329.622658 -236.349286) (xy 329.757278 -236.483906)
		)
		(stroke
			(width 0)
			(type solid)
		)
		(fill yes)
		(layer "F.Cu")
		(net "M_A_CPU0_SB_DQ<10>")
	)
	(gr_poly
		(pts
			(xy 329.863958 -279.776682) (xy 329.814174 -279.766776) (xy 329.707494 -279.78227) (xy 329.670156 -279.96896)
			(xy 329.762866 -280.024586) (xy 329.81265 -280.034492)
		)
		(stroke
			(width 0)
			(type solid)
		)
		(fill yes)
		(layer "F.Cu")
		(net "M_A_CPU0_SA_DQ<7>")
	)
	(gr_poly
		(pts
			(xy 329.863958 -235.584238) (xy 329.900026 -235.548424) (xy 329.714098 -235.362496) (xy 329.67803 -235.39831)
			(xy 329.631802 -235.495846) (xy 329.766676 -235.630466)
		)
		(stroke
			(width 0)
			(type solid)
		)
		(fill yes)
		(layer "F.Cu")
		(net "M_A_CPU0_SB_DQ<11>")
	)
	(gr_poly
		(pts
			(xy 329.884532 -276.824694) (xy 329.83805 -276.727158) (xy 329.802236 -276.691344) (xy 329.616308 -276.877272)
			(xy 329.652376 -276.913086) (xy 329.749658 -276.959314)
		)
		(stroke
			(width 0)
			(type solid)
		)
		(fill yes)
		(layer "F.Cu")
		(net "M_A_CPU0_SA_DQ<19>")
	)
	(gr_poly
		(pts
			(xy 329.88758 -294.104822) (xy 329.88758 -293.914322) (xy 329.78598 -293.878) (xy 329.73518 -293.878)
			(xy 329.73518 -294.14089) (xy 329.78598 -294.14089)
		)
		(stroke
			(width 0)
			(type solid)
		)
		(fill yes)
		(layer "F.Cu")
		(net "M_A_CPU0_SA_DQ<5>")
	)
	(gr_poly
		(pts
			(xy 329.88758 -293.507922) (xy 329.88758 -293.317422) (xy 329.78598 -293.2811) (xy 329.73518 -293.2811)
			(xy 329.73518 -293.54399) (xy 329.78598 -293.54399)
		)
		(stroke
			(width 0)
			(type solid)
		)
		(fill yes)
		(layer "F.Cu")
		(net "M_A_CPU0_SA_DQ<5>")
	)
	(gr_poly
		(pts
			(xy 329.88758 -292.911022) (xy 329.88758 -292.720522) (xy 329.78598 -292.6842) (xy 329.73518 -292.6842)
			(xy 329.73518 -292.94709) (xy 329.78598 -292.94709)
		)
		(stroke
			(width 0)
			(type solid)
		)
		(fill yes)
		(layer "F.Cu")
		(net "M_A_CPU0_SA_DQ<5>")
	)
	(gr_poly
		(pts
			(xy 329.88758 -292.314122) (xy 329.88758 -292.123622) (xy 329.78598 -292.0873) (xy 329.73518 -292.0873)
			(xy 329.73518 -292.35019) (xy 329.78598 -292.35019)
		)
		(stroke
			(width 0)
			(type solid)
		)
		(fill yes)
		(layer "F.Cu")
		(net "M_A_CPU0_SA_DQ<5>")
	)
	(gr_poly
		(pts
			(xy 329.88758 -291.717222) (xy 329.88758 -291.526722) (xy 329.78598 -291.4904) (xy 329.73518 -291.4904)
			(xy 329.73518 -291.75329) (xy 329.78598 -291.75329)
		)
		(stroke
			(width 0)
			(type solid)
		)
		(fill yes)
		(layer "F.Cu")
		(net "M_A_CPU0_SA_DQ<5>")
	)
	(gr_poly
		(pts
			(xy 329.88758 -291.120322) (xy 329.88758 -290.929822) (xy 329.78598 -290.8935) (xy 329.73518 -290.8935)
			(xy 329.73518 -291.15639) (xy 329.78598 -291.15639)
		)
		(stroke
			(width 0)
			(type solid)
		)
		(fill yes)
		(layer "F.Cu")
		(net "M_A_CPU0_SA_DQ<5>")
	)
	(gr_poly
		(pts
			(xy 329.88758 -290.523422) (xy 329.88758 -290.332922) (xy 329.78598 -290.2966) (xy 329.73518 -290.2966)
			(xy 329.73518 -290.55949) (xy 329.78598 -290.55949)
		)
		(stroke
			(width 0)
			(type solid)
		)
		(fill yes)
		(layer "F.Cu")
		(net "M_A_CPU0_SA_DQ<5>")
	)
	(gr_poly
		(pts
			(xy 329.88758 -289.926522) (xy 329.88758 -289.736022) (xy 329.78598 -289.6997) (xy 329.73518 -289.6997)
			(xy 329.73518 -289.96259) (xy 329.78598 -289.96259)
		)
		(stroke
			(width 0)
			(type solid)
		)
		(fill yes)
		(layer "F.Cu")
		(net "M_A_CPU0_SA_DQ<5>")
	)
	(gr_poly
		(pts
			(xy 329.88758 -289.329622) (xy 329.88758 -289.139122) (xy 329.78598 -289.1028) (xy 329.73518 -289.1028)
			(xy 329.73518 -289.36569) (xy 329.78598 -289.36569)
		)
		(stroke
			(width 0)
			(type solid)
		)
		(fill yes)
		(layer "F.Cu")
		(net "M_A_CPU0_SA_DQ<5>")
	)
	(gr_poly
		(pts
			(xy 329.88758 -288.732722) (xy 329.88758 -288.542222) (xy 329.78598 -288.5059) (xy 329.73518 -288.5059)
			(xy 329.73518 -288.76879) (xy 329.78598 -288.76879)
		)
		(stroke
			(width 0)
			(type solid)
		)
		(fill yes)
		(layer "F.Cu")
		(net "M_A_CPU0_SA_DQ<5>")
	)
	(gr_poly
		(pts
			(xy 329.88758 -288.135822) (xy 329.88758 -287.945322) (xy 329.78598 -287.909) (xy 329.73518 -287.909)
			(xy 329.73518 -288.17189) (xy 329.78598 -288.17189)
		)
		(stroke
			(width 0)
			(type solid)
		)
		(fill yes)
		(layer "F.Cu")
		(net "M_A_CPU0_SA_DQ<5>")
	)
	(gr_poly
		(pts
			(xy 329.88758 -287.538922) (xy 329.88758 -287.348422) (xy 329.78598 -287.3121) (xy 329.73518 -287.3121)
			(xy 329.73518 -287.57499) (xy 329.78598 -287.57499)
		)
		(stroke
			(width 0)
			(type solid)
		)
		(fill yes)
		(layer "F.Cu")
		(net "M_A_CPU0_SA_DQ<5>")
	)
	(gr_poly
		(pts
			(xy 329.88758 -286.942022) (xy 329.88758 -286.751522) (xy 329.78598 -286.7152) (xy 329.73518 -286.7152)
			(xy 329.73518 -286.97809) (xy 329.78598 -286.97809)
		)
		(stroke
			(width 0)
			(type solid)
		)
		(fill yes)
		(layer "F.Cu")
		(net "M_A_CPU0_SA_DQ<5>")
	)
	(gr_poly
		(pts
			(xy 329.88758 -286.345122) (xy 329.88758 -286.154622) (xy 329.78598 -286.1183) (xy 329.73518 -286.1183)
			(xy 329.73518 -286.38119) (xy 329.78598 -286.38119)
		)
		(stroke
			(width 0)
			(type solid)
		)
		(fill yes)
		(layer "F.Cu")
		(net "M_A_CPU0_SA_DQ<5>")
	)
	(gr_poly
		(pts
			(xy 329.88758 -285.748222) (xy 329.88758 -285.557722) (xy 329.78598 -285.5214) (xy 329.73518 -285.5214)
			(xy 329.73518 -285.78429) (xy 329.78598 -285.78429)
		)
		(stroke
			(width 0)
			(type solid)
		)
		(fill yes)
		(layer "F.Cu")
		(net "M_A_CPU0_SA_DQ<5>")
	)
	(gr_poly
		(pts
			(xy 329.88758 -285.151322) (xy 329.88758 -284.960822) (xy 329.78598 -284.9245) (xy 329.73518 -284.9245)
			(xy 329.73518 -285.18739) (xy 329.78598 -285.18739)
		)
		(stroke
			(width 0)
			(type solid)
		)
		(fill yes)
		(layer "F.Cu")
		(net "M_A_CPU0_SA_DQ<5>")
	)
	(gr_poly
		(pts
			(xy 329.88758 -284.554422) (xy 329.88758 -284.363922) (xy 329.78598 -284.3276) (xy 329.73518 -284.3276)
			(xy 329.73518 -284.59049) (xy 329.78598 -284.59049)
		)
		(stroke
			(width 0)
			(type solid)
		)
		(fill yes)
		(layer "F.Cu")
		(net "M_A_CPU0_SA_DQ<5>")
	)
	(gr_poly
		(pts
			(xy 329.88758 -283.957522) (xy 329.88758 -283.767022) (xy 329.78598 -283.7307) (xy 329.73518 -283.7307)
			(xy 329.73518 -283.99359) (xy 329.78598 -283.99359)
		)
		(stroke
			(width 0)
			(type solid)
		)
		(fill yes)
		(layer "F.Cu")
		(net "M_A_CPU0_SA_DQ<5>")
	)
	(gr_poly
		(pts
			(xy 329.88758 -283.360622) (xy 329.88758 -283.170122) (xy 329.78598 -283.1338) (xy 329.73518 -283.1338)
			(xy 329.73518 -283.39669) (xy 329.78598 -283.39669)
		)
		(stroke
			(width 0)
			(type solid)
		)
		(fill yes)
		(layer "F.Cu")
		(net "M_A_CPU0_SA_DQ<5>")
	)
	(gr_poly
		(pts
			(xy 329.88758 -282.763722) (xy 329.88758 -282.573222) (xy 329.78598 -282.5369) (xy 329.73518 -282.5369)
			(xy 329.73518 -282.79979) (xy 329.78598 -282.79979)
		)
		(stroke
			(width 0)
			(type solid)
		)
		(fill yes)
		(layer "F.Cu")
		(net "M_A_CPU0_SA_DQ<5>")
	)
	(gr_poly
		(pts
			(xy 329.894692 -278.258016) (xy 329.822302 -278.17826) (xy 329.777598 -278.154384) (xy 329.653392 -278.386032)
			(xy 329.69835 -278.409908) (xy 329.804776 -278.426164)
		)
		(stroke
			(width 0)
			(type solid)
		)
		(fill yes)
		(layer "F.Cu")
		(net "M_A_CPU0_SA_DQ<16>")
	)
	(gr_poly
		(pts
			(xy 329.902058 -233.034078) (xy 329.937872 -232.998264) (xy 329.751944 -232.812336) (xy 329.71613 -232.84815)
			(xy 329.669902 -232.945686) (xy 329.804522 -233.080306)
		)
		(stroke
			(width 0)
			(type solid)
		)
		(fill yes)
		(layer "F.Cu")
		(net "M_A_CPU0_SB_DQ<14>")
	)
	(gr_poly
		(pts
			(xy 329.909424 -267.712698) (xy 329.863196 -267.615162) (xy 329.827128 -267.579348) (xy 329.6412 -267.765276)
			(xy 329.677268 -267.80109) (xy 329.77455 -267.847318)
		)
		(stroke
			(width 0)
			(type solid)
		)
		(fill yes)
		(layer "F.Cu")
		(net "M_A_CPU0_SA_DQ<31>")
	)
	(gr_poly
		(pts
			(xy 329.910694 -280.321512) (xy 329.948032 -280.134568) (xy 329.855322 -280.079196) (xy 329.805538 -280.06929)
			(xy 329.753976 -280.3271) (xy 329.804014 -280.337006)
		)
		(stroke
			(width 0)
			(type solid)
		)
		(fill yes)
		(layer "F.Cu")
		(net "M_A_CPU0_SA_DQ<7>")
	)
	(gr_poly
		(pts
			(xy 329.911202 -232.180892) (xy 329.947016 -232.144824) (xy 329.761088 -231.958896) (xy 329.725274 -231.994964)
			(xy 329.679046 -232.092246) (xy 329.813666 -232.22712)
		)
		(stroke
			(width 0)
			(type solid)
		)
		(fill yes)
		(layer "F.Cu")
		(net "M_A_CPU0_SB_DQ<15>")
	)
	(gr_poly
		(pts
			(xy 329.911964 -273.560032) (xy 329.875896 -273.524218) (xy 329.778614 -273.47799) (xy 329.643994 -273.61261)
			(xy 329.690222 -273.710146) (xy 329.726036 -273.74596)
		)
		(stroke
			(width 0)
			(type solid)
		)
		(fill yes)
		(layer "F.Cu")
		(net "M_A_CPU0_SA_DQ<21>")
	)
	(gr_poly
		(pts
			(xy 329.915774 -259.719826) (xy 329.915774 -259.669026) (xy 329.652884 -259.669026) (xy 329.652884 -259.719826)
			(xy 329.688952 -259.821426) (xy 329.879452 -259.821426)
		)
		(stroke
			(width 0)
			(type solid)
		)
		(fill yes)
		(layer "F.Cu")
		(net "M_A_CPU0_SA_CS_N<0>")
	)
	(gr_poly
		(pts
			(xy 329.915774 -259.415026) (xy 329.915774 -259.364226) (xy 329.652884 -259.364226) (xy 329.652884 -259.415026)
			(xy 329.688952 -259.516626) (xy 329.879452 -259.516626)
		)
		(stroke
			(width 0)
			(type solid)
		)
		(fill yes)
		(layer "F.Cu")
		(net "M_A_CPU0_SA_CS_N<2>")
	)
	(gr_poly
		(pts
			(xy 329.915774 -259.110226) (xy 329.915774 -259.059426) (xy 329.652884 -259.059426) (xy 329.652884 -259.110226)
			(xy 329.688952 -259.211826) (xy 329.879452 -259.211826)
		)
		(stroke
			(width 0)
			(type solid)
		)
		(fill yes)
		(layer "F.Cu")
		(net "M_A_CPU0_SA_CS_N<3>")
	)
	(gr_poly
		(pts
			(xy 329.915774 -258.805426) (xy 329.915774 -258.754626) (xy 329.652884 -258.754626) (xy 329.652884 -258.805426)
			(xy 329.688952 -258.907026) (xy 329.879452 -258.907026)
		)
		(stroke
			(width 0)
			(type solid)
		)
		(fill yes)
		(layer "F.Cu")
		(net "M_A_CPU0_SA_CS_N<1>")
	)
	(gr_poly
		(pts
			(xy 329.915774 -258.500626) (xy 329.915774 -258.449826) (xy 329.652884 -258.449826) (xy 329.652884 -258.500626)
			(xy 329.688952 -258.602226) (xy 329.879452 -258.602226)
		)
		(stroke
			(width 0)
			(type solid)
		)
		(fill yes)
		(layer "F.Cu")
		(net "M_A_CPU0_SA_CA<0>")
	)
	(gr_poly
		(pts
			(xy 329.915774 -258.195826) (xy 329.915774 -258.145026) (xy 329.652884 -258.145026) (xy 329.652884 -258.195826)
			(xy 329.688952 -258.297426) (xy 329.879452 -258.297426)
		)
		(stroke
			(width 0)
			(type solid)
		)
		(fill yes)
		(layer "F.Cu")
		(net "M_A_CPU0_SA_CA<1>")
	)
	(gr_poly
		(pts
			(xy 329.915774 -257.891026) (xy 329.915774 -257.840226) (xy 329.652884 -257.840226) (xy 329.652884 -257.891026)
			(xy 329.688952 -257.992626) (xy 329.879452 -257.992626)
		)
		(stroke
			(width 0)
			(type solid)
		)
		(fill yes)
		(layer "F.Cu")
		(net "M_A_CPU0_SA_CA<2>")
	)
	(gr_poly
		(pts
			(xy 329.915774 -257.586226) (xy 329.915774 -257.535426) (xy 329.652884 -257.535426) (xy 329.652884 -257.586226)
			(xy 329.688952 -257.687826) (xy 329.879452 -257.687826)
		)
		(stroke
			(width 0)
			(type solid)
		)
		(fill yes)
		(layer "F.Cu")
		(net "M_A_CPU0_SA_CA<3>")
	)
	(gr_poly
		(pts
			(xy 329.915774 -257.281426) (xy 329.915774 -257.230626) (xy 329.652884 -257.230626) (xy 329.652884 -257.281426)
			(xy 329.688952 -257.383026) (xy 329.879452 -257.383026)
		)
		(stroke
			(width 0)
			(type solid)
		)
		(fill yes)
		(layer "F.Cu")
		(net "M_A_CPU0_SA_CA<4>")
	)
	(gr_poly
		(pts
			(xy 329.915774 -256.976626) (xy 329.915774 -256.925826) (xy 329.652884 -256.925826) (xy 329.652884 -256.976626)
			(xy 329.688952 -257.078226) (xy 329.879452 -257.078226)
		)
		(stroke
			(width 0)
			(type solid)
		)
		(fill yes)
		(layer "F.Cu")
		(net "M_A_CPU0_SA_CA<5>")
	)
	(gr_poly
		(pts
			(xy 329.919076 -268.566392) (xy 329.872848 -268.46911) (xy 329.837034 -268.433042) (xy 329.651106 -268.61897)
			(xy 329.68692 -268.655038) (xy 329.784456 -268.701266)
		)
		(stroke
			(width 0)
			(type solid)
		)
		(fill yes)
		(layer "F.Cu")
		(net "M_A_CPU0_SA_DQ<30>")
	)
	(gr_poly
		(pts
			(xy 329.921108 -230.9114) (xy 329.957176 -230.875586) (xy 329.771248 -230.689658) (xy 329.73518 -230.725472)
			(xy 329.688952 -230.823008) (xy 329.823826 -230.957628)
		)
		(stroke
			(width 0)
			(type solid)
		)
		(fill yes)
		(layer "F.Cu")
		(net "M_A_CPU0_SB_DQ<18>")
	)
	(gr_poly
		(pts
			(xy 329.92187 -274.414488) (xy 329.886056 -274.37842) (xy 329.78852 -274.332192) (xy 329.6539 -274.466812)
			(xy 329.700128 -274.564348) (xy 329.735942 -274.600162)
		)
		(stroke
			(width 0)
			(type solid)
		)
		(fill yes)
		(layer "F.Cu")
		(net "M_A_CPU0_SA_DQ<20>")
	)
	(gr_poly
		(pts
			(xy 329.922124 -236.792516) (xy 329.968352 -236.69498) (xy 329.833478 -236.56036) (xy 329.736196 -236.606588)
			(xy 329.700128 -236.642402) (xy 329.886056 -236.82833)
		)
		(stroke
			(width 0)
			(type solid)
		)
		(fill yes)
		(layer "F.Cu")
		(net "M_A_CPU0_SB_DQ<8>")
	)
	(gr_poly
		(pts
			(xy 329.929744 -281.007058) (xy 329.87996 -280.997152) (xy 329.77328 -281.012646) (xy 329.735942 -281.19959)
			(xy 329.828398 -281.254962) (xy 329.878182 -281.264868)
		)
		(stroke
			(width 0)
			(type solid)
		)
		(fill yes)
		(layer "F.Cu")
		(net "M_A_CPU0_SA_DQ<5>")
	)
	(gr_poly
		(pts
			(xy 329.930506 -230.05796) (xy 329.96632 -230.022146) (xy 329.780392 -229.836218) (xy 329.744578 -229.872286)
			(xy 329.69835 -229.969568) (xy 329.83297 -230.104188)
		)
		(stroke
			(width 0)
			(type solid)
		)
		(fill yes)
		(layer "F.Cu")
		(net "M_A_CPU0_SB_DQ<19>")
	)
	(gr_poly
		(pts
			(xy 329.931268 -235.939076) (xy 329.977496 -235.841794) (xy 329.842876 -235.70692) (xy 329.74534 -235.753148)
			(xy 329.709526 -235.789216) (xy 329.895454 -235.975144)
		)
		(stroke
			(width 0)
			(type solid)
		)
		(fill yes)
		(layer "F.Cu")
		(net "M_A_CPU0_SB_DQ<9>")
	)
	(gr_poly
		(pts
			(xy 329.936348 -227.907342) (xy 329.972162 -227.871528) (xy 329.786234 -227.6856) (xy 329.75042 -227.721668)
			(xy 329.704192 -227.81895) (xy 329.838812 -227.953824)
		)
		(stroke
			(width 0)
			(type solid)
		)
		(fill yes)
		(layer "F.Cu")
		(net "M_A_CPU0_SB_DQ<20>")
	)
	(gr_poly
		(pts
			(xy 329.945492 -227.053902) (xy 329.98156 -227.018088) (xy 329.795632 -226.83216) (xy 329.759818 -226.867974)
			(xy 329.71359 -226.96551) (xy 329.84821 -227.10013)
		)
		(stroke
			(width 0)
			(type solid)
		)
		(fill yes)
		(layer "F.Cu")
		(net "M_A_CPU0_SB_DQ<21>")
	)
	(gr_poly
		(pts
			(xy 329.950572 -217.801698) (xy 329.899772 -217.801698) (xy 329.798172 -217.837766) (xy 329.798172 -218.028266)
			(xy 329.899772 -218.064334) (xy 329.950572 -218.064334)
		)
		(stroke
			(width 0)
			(type solid)
		)
		(fill yes)
		(layer "F.Cu")
		(net "M_A_CPU0_SB_DQ<25>")
	)
	(gr_poly
		(pts
			(xy 329.950572 -217.204798) (xy 329.899772 -217.204798) (xy 329.798172 -217.240866) (xy 329.798172 -217.431366)
			(xy 329.899772 -217.467434) (xy 329.950572 -217.467434)
		)
		(stroke
			(width 0)
			(type solid)
		)
		(fill yes)
		(layer "F.Cu")
		(net "M_A_CPU0_SB_DQ<25>")
	)
	(gr_poly
		(pts
			(xy 329.950572 -216.607898) (xy 329.899772 -216.607898) (xy 329.798172 -216.643966) (xy 329.798172 -216.834466)
			(xy 329.899772 -216.870534) (xy 329.950572 -216.870534)
		)
		(stroke
			(width 0)
			(type solid)
		)
		(fill yes)
		(layer "F.Cu")
		(net "M_A_CPU0_SB_DQ<25>")
	)
	(gr_poly
		(pts
			(xy 329.966574 -271.32407) (xy 329.930506 -271.288256) (xy 329.833224 -271.242028) (xy 329.69835 -271.376648)
			(xy 329.744832 -271.474184) (xy 329.780646 -271.509998)
		)
		(stroke
			(width 0)
			(type solid)
		)
		(fill yes)
		(layer "F.Cu")
		(net "M_A_CPU0_SA_DQ<25>")
	)
	(gr_poly
		(pts
			(xy 329.966574 -264.230358) (xy 329.93076 -264.19429) (xy 329.833224 -264.148062) (xy 329.698604 -264.282936)
			(xy 329.744832 -264.380218) (xy 329.780646 -264.416286)
		)
		(stroke
			(width 0)
			(type solid)
		)
		(fill yes)
		(layer "F.Cu")
		(net "M_A_CPU0_SA_CB<1>")
	)
	(gr_poly
		(pts
			(xy 329.969114 -233.38917) (xy 330.015342 -233.291634) (xy 329.880468 -233.157014) (xy 329.783186 -233.203242)
			(xy 329.747118 -233.239056) (xy 329.933046 -233.424984)
		)
		(stroke
			(width 0)
			(type solid)
		)
		(fill yes)
		(layer "F.Cu")
		(net "M_A_CPU0_SB_DQ<12>")
	)
	(gr_poly
		(pts
			(xy 329.975718 -272.17751) (xy 329.939904 -272.141442) (xy 329.842368 -272.095214) (xy 329.707748 -272.230088)
			(xy 329.753976 -272.32737) (xy 329.78979 -272.363438)
		)
		(stroke
			(width 0)
			(type solid)
		)
		(fill yes)
		(layer "F.Cu")
		(net "M_A_CPU0_SA_DQ<24>")
	)
	(gr_poly
		(pts
			(xy 329.975972 -281.551888) (xy 330.013564 -281.365198) (xy 329.920854 -281.309826) (xy 329.87107 -281.299666)
			(xy 329.819508 -281.557476) (xy 329.869292 -281.567636)
		)
		(stroke
			(width 0)
			(type solid)
		)
		(fill yes)
		(layer "F.Cu")
		(net "M_A_CPU0_SA_DQ<5>")
	)
	(gr_poly
		(pts
			(xy 329.975972 -265.083798) (xy 329.940158 -265.047984) (xy 329.842622 -265.001756) (xy 329.708002 -265.136376)
			(xy 329.75423 -265.233912) (xy 329.790044 -265.269726)
		)
		(stroke
			(width 0)
			(type solid)
		)
		(fill yes)
		(layer "F.Cu")
		(net "M_A_CPU0_SA_CB<0>")
	)
	(gr_poly
		(pts
			(xy 329.978512 -232.53573) (xy 330.02474 -232.438194) (xy 329.889866 -232.303574) (xy 329.792584 -232.349802)
			(xy 329.756516 -232.385616) (xy 329.942444 -232.571544)
		)
		(stroke
			(width 0)
			(type solid)
		)
		(fill yes)
		(layer "F.Cu")
		(net "M_A_CPU0_SB_DQ<13>")
	)
	(gr_poly
		(pts
			(xy 329.981052 -279.191212) (xy 329.931268 -279.181306) (xy 329.824334 -279.1968) (xy 329.786996 -279.383744)
			(xy 329.879706 -279.439116) (xy 329.92949 -279.449022)
		)
		(stroke
			(width 0)
			(type solid)
		)
		(fill yes)
		(layer "F.Cu")
		(net "M_A_CPU0_SA_DQ<7>")
	)
	(gr_poly
		(pts
			(xy 329.988418 -231.266238) (xy 330.034646 -231.168956) (xy 329.900026 -231.034082) (xy 329.80249 -231.08031)
			(xy 329.766676 -231.116378) (xy 329.952604 -231.302306)
		)
		(stroke
			(width 0)
			(type solid)
		)
		(fill yes)
		(layer "F.Cu")
		(net "M_A_CPU0_SB_DQ<16>")
	)
	(gr_poly
		(pts
			(xy 329.989434 -273.266662) (xy 329.943206 -273.16938) (xy 329.907138 -273.133312) (xy 329.721464 -273.31924)
			(xy 329.757278 -273.355054) (xy 329.854814 -273.401282)
		)
		(stroke
			(width 0)
			(type solid)
		)
		(fill yes)
		(layer "F.Cu")
		(net "M_A_CPU0_SA_DQ<23>")
	)
	(gr_poly
		(pts
			(xy 329.997562 -230.412798) (xy 330.04379 -230.315516) (xy 329.90917 -230.180642) (xy 329.811634 -230.227124)
			(xy 329.77582 -230.262938) (xy 329.961748 -230.448866)
		)
		(stroke
			(width 0)
			(type solid)
		)
		(fill yes)
		(layer "F.Cu")
		(net "M_A_CPU0_SB_DQ<17>")
	)
	(gr_poly
		(pts
			(xy 329.998832 -274.120356) (xy 329.952604 -274.02282) (xy 329.916536 -273.987006) (xy 329.730608 -274.17268)
			(xy 329.766676 -274.208748) (xy 329.863958 -274.254976)
		)
		(stroke
			(width 0)
			(type solid)
		)
		(fill yes)
		(layer "F.Cu")
		(net "M_A_CPU0_SA_DQ<22>")
	)
	(gr_poly
		(pts
			(xy 330.012802 -227.40874) (xy 330.05903 -227.311458) (xy 329.92441 -227.176584) (xy 329.826874 -227.222812)
			(xy 329.79106 -227.25888) (xy 329.976988 -227.444808)
		)
		(stroke
			(width 0)
			(type solid)
		)
		(fill yes)
		(layer "F.Cu")
		(net "M_A_CPU0_SB_DQ<22>")
	)
	(gr_poly
		(pts
			(xy 330.01331 -276.48027) (xy 329.977242 -276.444456) (xy 329.87996 -276.398228) (xy 329.74534 -276.532848)
			(xy 329.791568 -276.630384) (xy 329.827382 -276.666198)
		)
		(stroke
			(width 0)
			(type solid)
		)
		(fill yes)
		(layer "F.Cu")
		(net "M_A_CPU0_SA_DQ<19>")
	)
	(gr_poly
		(pts
			(xy 330.021946 -226.555554) (xy 330.068428 -226.458018) (xy 329.933554 -226.323398) (xy 329.836272 -226.369626)
			(xy 329.800204 -226.40544) (xy 329.986132 -226.591368)
		)
		(stroke
			(width 0)
			(type solid)
		)
		(fill yes)
		(layer "F.Cu")
		(net "M_A_CPU0_SB_DQ<23>")
	)
	(gr_poly
		(pts
			(xy 330.024232 -277.335234) (xy 329.988164 -277.29942) (xy 329.890882 -277.253192) (xy 329.756008 -277.387812)
			(xy 329.802236 -277.485348) (xy 329.838304 -277.521162)
		)
		(stroke
			(width 0)
			(type solid)
		)
		(fill yes)
		(layer "F.Cu")
		(net "M_A_CPU0_SA_DQ<18>")
	)
	(gr_poly
		(pts
			(xy 330.027534 -279.736042) (xy 330.064872 -279.549352) (xy 329.972416 -279.49398) (xy 329.922632 -279.484074)
			(xy 329.87107 -279.74163) (xy 329.920854 -279.75179)
		)
		(stroke
			(width 0)
			(type solid)
		)
		(fill yes)
		(layer "F.Cu")
		(net "M_A_CPU0_SA_DQ<7>")
	)
	(gr_poly
		(pts
			(xy 330.038202 -267.368274) (xy 330.002388 -267.332206) (xy 329.904852 -267.285978) (xy 329.770232 -267.420852)
			(xy 329.81646 -267.518134) (xy 329.852274 -267.554202)
		)
		(stroke
			(width 0)
			(type solid)
		)
		(fill yes)
		(layer "F.Cu")
		(net "M_A_CPU0_SA_DQ<31>")
	)
	(gr_poly
		(pts
			(xy 330.03998 -294.17645) (xy 329.98918 -294.17645) (xy 329.88758 -294.212772) (xy 329.88758 -294.403272)
			(xy 329.98918 -294.43934) (xy 330.03998 -294.43934)
		)
		(stroke
			(width 0)
			(type solid)
		)
		(fill yes)
		(layer "F.Cu")
		(net "M_A_CPU0_SA_DQ<6>")
	)
	(gr_poly
		(pts
			(xy 330.03998 -293.57955) (xy 329.98918 -293.57955) (xy 329.88758 -293.615872) (xy 329.88758 -293.806372)
			(xy 329.98918 -293.84244) (xy 330.03998 -293.84244)
		)
		(stroke
			(width 0)
			(type solid)
		)
		(fill yes)
		(layer "F.Cu")
		(net "M_A_CPU0_SA_DQ<6>")
	)
	(gr_poly
		(pts
			(xy 330.03998 -292.98265) (xy 329.98918 -292.98265) (xy 329.88758 -293.018972) (xy 329.88758 -293.209472)
			(xy 329.98918 -293.24554) (xy 330.03998 -293.24554)
		)
		(stroke
			(width 0)
			(type solid)
		)
		(fill yes)
		(layer "F.Cu")
		(net "M_A_CPU0_SA_DQ<6>")
	)
	(gr_poly
		(pts
			(xy 330.03998 -292.38575) (xy 329.98918 -292.38575) (xy 329.88758 -292.422072) (xy 329.88758 -292.612572)
			(xy 329.98918 -292.64864) (xy 330.03998 -292.64864)
		)
		(stroke
			(width 0)
			(type solid)
		)
		(fill yes)
		(layer "F.Cu")
		(net "M_A_CPU0_SA_DQ<6>")
	)
	(gr_poly
		(pts
			(xy 330.03998 -291.78885) (xy 329.98918 -291.78885) (xy 329.88758 -291.825172) (xy 329.88758 -292.015672)
			(xy 329.98918 -292.05174) (xy 330.03998 -292.05174)
		)
		(stroke
			(width 0)
			(type solid)
		)
		(fill yes)
		(layer "F.Cu")
		(net "M_A_CPU0_SA_DQ<6>")
	)
	(gr_poly
		(pts
			(xy 330.03998 -291.19195) (xy 329.98918 -291.19195) (xy 329.88758 -291.228272) (xy 329.88758 -291.418772)
			(xy 329.98918 -291.45484) (xy 330.03998 -291.45484)
		)
		(stroke
			(width 0)
			(type solid)
		)
		(fill yes)
		(layer "F.Cu")
		(net "M_A_CPU0_SA_DQ<6>")
	)
	(gr_poly
		(pts
			(xy 330.03998 -290.59505) (xy 329.98918 -290.59505) (xy 329.88758 -290.631372) (xy 329.88758 -290.821872)
			(xy 329.98918 -290.85794) (xy 330.03998 -290.85794)
		)
		(stroke
			(width 0)
			(type solid)
		)
		(fill yes)
		(layer "F.Cu")
		(net "M_A_CPU0_SA_DQ<6>")
	)
	(gr_poly
		(pts
			(xy 330.03998 -289.99815) (xy 329.98918 -289.99815) (xy 329.88758 -290.034472) (xy 329.88758 -290.224972)
			(xy 329.98918 -290.26104) (xy 330.03998 -290.26104)
		)
		(stroke
			(width 0)
			(type solid)
		)
		(fill yes)
		(layer "F.Cu")
		(net "M_A_CPU0_SA_DQ<6>")
	)
	(gr_poly
		(pts
			(xy 330.03998 -289.40125) (xy 329.98918 -289.40125) (xy 329.88758 -289.437572) (xy 329.88758 -289.628072)
			(xy 329.98918 -289.66414) (xy 330.03998 -289.66414)
		)
		(stroke
			(width 0)
			(type solid)
		)
		(fill yes)
		(layer "F.Cu")
		(net "M_A_CPU0_SA_DQ<6>")
	)
	(gr_poly
		(pts
			(xy 330.03998 -288.80435) (xy 329.98918 -288.80435) (xy 329.88758 -288.840672) (xy 329.88758 -289.031172)
			(xy 329.98918 -289.06724) (xy 330.03998 -289.06724)
		)
		(stroke
			(width 0)
			(type solid)
		)
		(fill yes)
		(layer "F.Cu")
		(net "M_A_CPU0_SA_DQ<6>")
	)
	(gr_poly
		(pts
			(xy 330.03998 -288.20745) (xy 329.98918 -288.20745) (xy 329.88758 -288.243772) (xy 329.88758 -288.434272)
			(xy 329.98918 -288.47034) (xy 330.03998 -288.47034)
		)
		(stroke
			(width 0)
			(type solid)
		)
		(fill yes)
		(layer "F.Cu")
		(net "M_A_CPU0_SA_DQ<6>")
	)
	(gr_poly
		(pts
			(xy 330.03998 -287.61055) (xy 329.98918 -287.61055) (xy 329.88758 -287.646872) (xy 329.88758 -287.837372)
			(xy 329.98918 -287.87344) (xy 330.03998 -287.87344)
		)
		(stroke
			(width 0)
			(type solid)
		)
		(fill yes)
		(layer "F.Cu")
		(net "M_A_CPU0_SA_DQ<6>")
	)
	(gr_poly
		(pts
			(xy 330.03998 -287.01365) (xy 329.98918 -287.01365) (xy 329.88758 -287.049972) (xy 329.88758 -287.240472)
			(xy 329.98918 -287.27654) (xy 330.03998 -287.27654)
		)
		(stroke
			(width 0)
			(type solid)
		)
		(fill yes)
		(layer "F.Cu")
		(net "M_A_CPU0_SA_DQ<6>")
	)
	(gr_poly
		(pts
			(xy 330.03998 -286.41675) (xy 329.98918 -286.41675) (xy 329.88758 -286.453072) (xy 329.88758 -286.643572)
			(xy 329.98918 -286.67964) (xy 330.03998 -286.67964)
		)
		(stroke
			(width 0)
			(type solid)
		)
		(fill yes)
		(layer "F.Cu")
		(net "M_A_CPU0_SA_DQ<6>")
	)
	(gr_poly
		(pts
			(xy 330.03998 -285.81985) (xy 329.98918 -285.81985) (xy 329.88758 -285.856172) (xy 329.88758 -286.046672)
			(xy 329.98918 -286.08274) (xy 330.03998 -286.08274)
		)
		(stroke
			(width 0)
			(type solid)
		)
		(fill yes)
		(layer "F.Cu")
		(net "M_A_CPU0_SA_DQ<6>")
	)
	(gr_poly
		(pts
			(xy 330.03998 -285.22295) (xy 329.98918 -285.22295) (xy 329.88758 -285.259272) (xy 329.88758 -285.449772)
			(xy 329.98918 -285.48584) (xy 330.03998 -285.48584)
		)
		(stroke
			(width 0)
			(type solid)
		)
		(fill yes)
		(layer "F.Cu")
		(net "M_A_CPU0_SA_DQ<6>")
	)
	(gr_poly
		(pts
			(xy 330.03998 -284.62605) (xy 329.98918 -284.62605) (xy 329.88758 -284.662372) (xy 329.88758 -284.852872)
			(xy 329.98918 -284.88894) (xy 330.03998 -284.88894)
		)
		(stroke
			(width 0)
			(type solid)
		)
		(fill yes)
		(layer "F.Cu")
		(net "M_A_CPU0_SA_DQ<6>")
	)
	(gr_poly
		(pts
			(xy 330.03998 -284.02915) (xy 329.98918 -284.02915) (xy 329.88758 -284.065472) (xy 329.88758 -284.255972)
			(xy 329.98918 -284.29204) (xy 330.03998 -284.29204)
		)
		(stroke
			(width 0)
			(type solid)
		)
		(fill yes)
		(layer "F.Cu")
		(net "M_A_CPU0_SA_DQ<6>")
	)
	(gr_poly
		(pts
			(xy 330.03998 -283.43225) (xy 329.98918 -283.43225) (xy 329.88758 -283.468572) (xy 329.88758 -283.659072)
			(xy 329.98918 -283.69514) (xy 330.03998 -283.69514)
		)
		(stroke
			(width 0)
			(type solid)
		)
		(fill yes)
		(layer "F.Cu")
		(net "M_A_CPU0_SA_DQ<6>")
	)
	(gr_poly
		(pts
			(xy 330.03998 -282.83535) (xy 329.98918 -282.83535) (xy 329.88758 -282.871672) (xy 329.88758 -283.062172)
			(xy 329.98918 -283.09824) (xy 330.03998 -283.09824)
		)
		(stroke
			(width 0)
			(type solid)
		)
		(fill yes)
		(layer "F.Cu")
		(net "M_A_CPU0_SA_DQ<6>")
	)
	(gr_poly
		(pts
			(xy 330.04379 -271.030446) (xy 329.997562 -270.933164) (xy 329.961748 -270.897096) (xy 329.77582 -271.083024)
			(xy 329.811634 -271.119092) (xy 329.90917 -271.16532)
		)
		(stroke
			(width 0)
			(type solid)
		)
		(fill yes)
		(layer "F.Cu")
		(net "M_A_CPU0_SA_DQ<27>")
	)
	(gr_poly
		(pts
			(xy 330.044044 -263.936988) (xy 329.997816 -263.839452) (xy 329.962002 -263.803638) (xy 329.776074 -263.989566)
			(xy 329.812142 -264.02538) (xy 329.909424 -264.071608)
		)
		(stroke
			(width 0)
			(type solid)
		)
		(fill yes)
		(layer "F.Cu")
		(net "M_A_CPU0_SA_CB<3>")
	)
	(gr_poly
		(pts
			(xy 330.046838 -280.421842) (xy 329.997054 -280.411936) (xy 329.890374 -280.42743) (xy 329.853036 -280.614374)
			(xy 329.945492 -280.669746) (xy 329.99553 -280.679652)
		)
		(stroke
			(width 0)
			(type solid)
		)
		(fill yes)
		(layer "F.Cu")
		(net "M_A_CPU0_SA_DQ<5>")
	)
	(gr_poly
		(pts
			(xy 330.047854 -268.222222) (xy 330.01204 -268.186154) (xy 329.914504 -268.139926) (xy 329.779884 -268.274546)
			(xy 329.826112 -268.372082) (xy 329.86218 -268.407896)
		)
		(stroke
			(width 0)
			(type solid)
		)
		(fill yes)
		(layer "F.Cu")
		(net "M_A_CPU0_SA_DQ<30>")
	)
	(gr_poly
		(pts
			(xy 330.053188 -271.88414) (xy 330.00696 -271.786604) (xy 329.971146 -271.75079) (xy 329.785218 -271.936718)
			(xy 329.821286 -271.972532) (xy 329.918568 -272.01876)
		)
		(stroke
			(width 0)
			(type solid)
		)
		(fill yes)
		(layer "F.Cu")
		(net "M_A_CPU0_SA_DQ<26>")
	)
	(gr_poly
		(pts
			(xy 330.053442 -264.790428) (xy 330.007214 -264.693146) (xy 329.9714 -264.657078) (xy 329.785472 -264.843006)
			(xy 329.821286 -264.87882) (xy 329.918822 -264.925302)
		)
		(stroke
			(width 0)
			(type solid)
		)
		(fill yes)
		(layer "F.Cu")
		(net "M_A_CPU0_SA_CB<2>")
	)
	(gr_poly
		(pts
			(xy 330.09332 -280.966672) (xy 330.130658 -280.779982) (xy 330.038202 -280.724356) (xy 329.988418 -280.71445)
			(xy 329.936856 -280.97226) (xy 329.98664 -280.982166)
		)
		(stroke
			(width 0)
			(type solid)
		)
		(fill yes)
		(layer "F.Cu")
		(net "M_A_CPU0_SA_DQ<5>")
	)
	(gr_poly
		(pts
			(xy 330.101702 -277.042118) (xy 330.055474 -276.944582) (xy 330.01966 -276.908514) (xy 329.833732 -277.094442)
			(xy 329.869546 -277.13051) (xy 329.967082 -277.176738)
		)
		(stroke
			(width 0)
			(type solid)
		)
		(fill yes)
		(layer "F.Cu")
		(net "M_A_CPU0_SA_DQ<17>")
	)
	(gr_poly
		(pts
			(xy 330.102972 -218.326716) (xy 330.102972 -218.136216) (xy 330.001372 -218.099894) (xy 329.950572 -218.099894)
			(xy 329.950572 -218.363038) (xy 330.001372 -218.363038)
		)
		(stroke
			(width 0)
			(type solid)
		)
		(fill yes)
		(layer "F.Cu")
		(net "M_A_CPU0_SB_DQ<25>")
	)
	(gr_poly
		(pts
			(xy 330.102972 -217.729816) (xy 330.102972 -217.539316) (xy 330.001372 -217.502994) (xy 329.950572 -217.502994)
			(xy 329.950572 -217.766138) (xy 330.001372 -217.766138)
		)
		(stroke
			(width 0)
			(type solid)
		)
		(fill yes)
		(layer "F.Cu")
		(net "M_A_CPU0_SB_DQ<25>")
	)
	(gr_poly
		(pts
			(xy 330.102972 -217.132916) (xy 330.102972 -216.942416) (xy 330.001372 -216.906094) (xy 329.950572 -216.906094)
			(xy 329.950572 -217.169238) (xy 330.001372 -217.169238)
		)
		(stroke
			(width 0)
			(type solid)
		)
		(fill yes)
		(layer "F.Cu")
		(net "M_A_CPU0_SB_DQ<25>")
	)
	(gr_poly
		(pts
			(xy 330.102972 -216.536016) (xy 330.102972 -216.345516) (xy 330.001372 -216.309194) (xy 329.950572 -216.309194)
			(xy 329.950572 -216.572338) (xy 330.001372 -216.572338)
		)
		(stroke
			(width 0)
			(type solid)
		)
		(fill yes)
		(layer "F.Cu")
		(net "M_A_CPU0_SB_DQ<25>")
	)
	(gr_poly
		(pts
			(xy 330.111608 -281.652218) (xy 330.061824 -281.642058) (xy 329.955144 -281.657806) (xy 329.917806 -281.844496)
			(xy 330.010262 -281.899868) (xy 330.060046 -281.910028)
		)
		(stroke
			(width 0)
			(type solid)
		)
		(fill yes)
		(layer "F.Cu")
		(net "M_A_CPU0_SA_DQ<6>")
	)
	(gr_poly
		(pts
			(xy 330.117704 -232.818432) (xy 330.153518 -232.782618) (xy 329.96759 -232.59669) (xy 329.931776 -232.632504)
			(xy 329.885548 -232.73004) (xy 330.020168 -232.86466)
		)
		(stroke
			(width 0)
			(type solid)
		)
		(fill yes)
		(layer "F.Cu")
		(net "M_A_CPU0_SB_DQ<13>")
	)
	(gr_poly
		(pts
			(xy 330.118212 -272.922238) (xy 330.082398 -272.886424) (xy 329.984862 -272.840196) (xy 329.850242 -272.974816)
			(xy 329.89647 -273.072352) (xy 329.932284 -273.108166)
		)
		(stroke
			(width 0)
			(type solid)
		)
		(fill yes)
		(layer "F.Cu")
		(net "M_A_CPU0_SA_DQ<23>")
	)
	(gr_poly
		(pts
			(xy 330.120752 -238.761016) (xy 330.120752 -238.710216) (xy 329.858116 -238.710216) (xy 329.858116 -238.761016)
			(xy 329.894184 -238.862616) (xy 330.084684 -238.862616)
		)
		(stroke
			(width 0)
			(type solid)
		)
		(fill yes)
		(layer "F.Cu")
		(net "M_A_CPU0_SB_CB<0>")
	)
	(gr_poly
		(pts
			(xy 330.120752 -238.456216) (xy 330.120752 -238.405416) (xy 329.858116 -238.405416) (xy 329.858116 -238.456216)
			(xy 329.894184 -238.557816) (xy 330.084684 -238.557816)
		)
		(stroke
			(width 0)
			(type solid)
		)
		(fill yes)
		(layer "F.Cu")
		(net "M_A_CPU0_SB_CB<2>")
	)
	(gr_poly
		(pts
			(xy 330.120752 -238.151416) (xy 330.120752 -238.100616) (xy 329.858116 -238.100616) (xy 329.858116 -238.151416)
			(xy 329.894184 -238.253016) (xy 330.084684 -238.253016)
		)
		(stroke
			(width 0)
			(type solid)
		)
		(fill yes)
		(layer "F.Cu")
		(net "M_A_CPU0_SB_CB<1>")
	)
	(gr_poly
		(pts
			(xy 330.12507 -267.928344) (xy 330.078842 -267.831062) (xy 330.043028 -267.794994) (xy 329.8571 -267.980922)
			(xy 329.892914 -268.016736) (xy 329.99045 -268.063218)
		)
		(stroke
			(width 0)
			(type solid)
		)
		(fill yes)
		(layer "F.Cu")
		(net "M_A_CPU0_SA_DQ<29>")
	)
	(gr_poly
		(pts
			(xy 330.12761 -273.775932) (xy 330.091796 -273.739864) (xy 329.99426 -273.693636) (xy 329.85964 -273.82851)
			(xy 329.905868 -273.925792) (xy 329.941682 -273.96186)
		)
		(stroke
			(width 0)
			(type solid)
		)
		(fill yes)
		(layer "F.Cu")
		(net "M_A_CPU0_SA_DQ<22>")
	)
	(gr_poly
		(pts
			(xy 330.12761 -231.549194) (xy 330.163424 -231.513126) (xy 329.97775 -231.327452) (xy 329.941682 -231.363266)
			(xy 329.895454 -231.460802) (xy 330.030074 -231.595422)
		)
		(stroke
			(width 0)
			(type solid)
		)
		(fill yes)
		(layer "F.Cu")
		(net "M_A_CPU0_SB_DQ<16>")
	)
	(gr_poly
		(pts
			(xy 330.134722 -268.782038) (xy 330.088494 -268.684756) (xy 330.05268 -268.648688) (xy 329.866752 -268.834616)
			(xy 329.902566 -268.870684) (xy 330.000102 -268.916912)
		)
		(stroke
			(width 0)
			(type solid)
		)
		(fill yes)
		(layer "F.Cu")
		(net "M_A_CPU0_SA_DQ<28>")
	)
	(gr_poly
		(pts
			(xy 330.136754 -230.695754) (xy 330.172822 -230.65994) (xy 329.986894 -230.474012) (xy 329.950826 -230.509826)
			(xy 329.904598 -230.607362) (xy 330.039472 -230.741982)
		)
		(stroke
			(width 0)
			(type solid)
		)
		(fill yes)
		(layer "F.Cu")
		(net "M_A_CPU0_SB_DQ<17>")
	)
	(gr_poly
		(pts
			(xy 330.144374 -279.150826) (xy 330.181712 -278.963882) (xy 330.089256 -278.90851) (xy 330.039472 -278.898604)
			(xy 329.98791 -279.156414) (xy 330.037694 -279.16632)
		)
		(stroke
			(width 0)
			(type solid)
		)
		(fill yes)
		(layer "F.Cu")
		(net "M_A_CPU0_SA_DQ<7>")
	)
	(gr_poly
		(pts
			(xy 330.146914 -235.72343) (xy 330.193142 -235.626148) (xy 330.058522 -235.491274) (xy 329.960986 -235.537502)
			(xy 329.925172 -235.57357) (xy 330.1111 -235.759498)
		)
		(stroke
			(width 0)
			(type solid)
		)
		(fill yes)
		(layer "F.Cu")
		(net "M_A_CPU0_SB_DQ<11>")
	)
	(gr_poly
		(pts
			(xy 330.151994 -227.691696) (xy 330.188062 -227.655882) (xy 330.002134 -227.469954) (xy 329.966066 -227.505768)
			(xy 329.919838 -227.603304) (xy 330.054712 -227.737924)
		)
		(stroke
			(width 0)
			(type solid)
		)
		(fill yes)
		(layer "F.Cu")
		(net "M_A_CPU0_SB_DQ<22>")
	)
	(gr_poly
		(pts
			(xy 330.161138 -226.838256) (xy 330.197206 -226.802442) (xy 330.011278 -226.616514) (xy 329.975464 -226.652328)
			(xy 329.929236 -226.749864) (xy 330.063856 -226.884484)
		)
		(stroke
			(width 0)
			(type solid)
		)
		(fill yes)
		(layer "F.Cu")
		(net "M_A_CPU0_SB_DQ<23>")
	)
	(gr_poly
		(pts
			(xy 330.164186 -279.836626) (xy 330.114402 -279.82672) (xy 330.007468 -279.842214) (xy 329.970384 -280.028904)
			(xy 330.06284 -280.08453) (xy 330.112624 -280.094436)
		)
		(stroke
			(width 0)
			(type solid)
		)
		(fill yes)
		(layer "F.Cu")
		(net "M_A_CPU0_SA_DQ<5>")
	)
	(gr_poly
		(pts
			(xy 330.172822 -270.686022) (xy 330.136754 -270.650208) (xy 330.039472 -270.60398) (xy 329.904598 -270.7386)
			(xy 329.950826 -270.836136) (xy 329.986894 -270.87195)
		)
		(stroke
			(width 0)
			(type solid)
		)
		(fill yes)
		(layer "F.Cu")
		(net "M_A_CPU0_SA_DQ<27>")
	)
	(gr_poly
		(pts
			(xy 330.173076 -263.592564) (xy 330.137008 -263.55675) (xy 330.039726 -263.510522) (xy 329.904852 -263.645142)
			(xy 329.951334 -263.742678) (xy 329.987148 -263.778492)
		)
		(stroke
			(width 0)
			(type solid)
		)
		(fill yes)
		(layer "F.Cu")
		(net "M_A_CPU0_SA_CB<3>")
	)
	(gr_poly
		(pts
			(xy 330.18222 -271.539716) (xy 330.146152 -271.503902) (xy 330.04887 -271.457674) (xy 329.913996 -271.592294)
			(xy 329.960478 -271.68983) (xy 329.996292 -271.725644)
		)
		(stroke
			(width 0)
			(type solid)
		)
		(fill yes)
		(layer "F.Cu")
		(net "M_A_CPU0_SA_DQ<26>")
	)
	(gr_poly
		(pts
			(xy 330.182474 -264.446004) (xy 330.146406 -264.41019) (xy 330.049124 -264.363962) (xy 329.91425 -264.498582)
			(xy 329.960478 -264.596118) (xy 329.996546 -264.631932)
		)
		(stroke
			(width 0)
			(type solid)
		)
		(fill yes)
		(layer "F.Cu")
		(net "M_A_CPU0_SA_CB<2>")
	)
	(gr_poly
		(pts
			(xy 330.18476 -233.17327) (xy 330.230988 -233.075988) (xy 330.096368 -232.941114) (xy 329.998832 -232.987596)
			(xy 329.963018 -233.02341) (xy 330.148946 -233.209338)
		)
		(stroke
			(width 0)
			(type solid)
		)
		(fill yes)
		(layer "F.Cu")
		(net "M_A_CPU0_SB_DQ<14>")
	)
	(gr_poly
		(pts
			(xy 330.19238 -294.701722) (xy 330.19238 -294.511222) (xy 330.09078 -294.4749) (xy 330.03998 -294.4749)
			(xy 330.03998 -294.73779) (xy 330.09078 -294.73779)
		)
		(stroke
			(width 0)
			(type solid)
		)
		(fill yes)
		(layer "F.Cu")
		(net "M_A_CPU0_SA_DQ<6>")
	)
	(gr_poly
		(pts
			(xy 330.19238 -294.104822) (xy 330.19238 -293.914322) (xy 330.09078 -293.878) (xy 330.03998 -293.878)
			(xy 330.03998 -294.14089) (xy 330.09078 -294.14089)
		)
		(stroke
			(width 0)
			(type solid)
		)
		(fill yes)
		(layer "F.Cu")
		(net "M_A_CPU0_SA_DQ<6>")
	)
	(gr_poly
		(pts
			(xy 330.19238 -293.507922) (xy 330.19238 -293.317422) (xy 330.09078 -293.2811) (xy 330.03998 -293.2811)
			(xy 330.03998 -293.54399) (xy 330.09078 -293.54399)
		)
		(stroke
			(width 0)
			(type solid)
		)
		(fill yes)
		(layer "F.Cu")
		(net "M_A_CPU0_SA_DQ<6>")
	)
	(gr_poly
		(pts
			(xy 330.19238 -292.911022) (xy 330.19238 -292.720522) (xy 330.09078 -292.6842) (xy 330.03998 -292.6842)
			(xy 330.03998 -292.94709) (xy 330.09078 -292.94709)
		)
		(stroke
			(width 0)
			(type solid)
		)
		(fill yes)
		(layer "F.Cu")
		(net "M_A_CPU0_SA_DQ<6>")
	)
	(gr_poly
		(pts
			(xy 330.19238 -292.314122) (xy 330.19238 -292.123622) (xy 330.09078 -292.0873) (xy 330.03998 -292.0873)
			(xy 330.03998 -292.35019) (xy 330.09078 -292.35019)
		)
		(stroke
			(width 0)
			(type solid)
		)
		(fill yes)
		(layer "F.Cu")
		(net "M_A_CPU0_SA_DQ<6>")
	)
	(gr_poly
		(pts
			(xy 330.19238 -291.717222) (xy 330.19238 -291.526722) (xy 330.09078 -291.4904) (xy 330.03998 -291.4904)
			(xy 330.03998 -291.75329) (xy 330.09078 -291.75329)
		)
		(stroke
			(width 0)
			(type solid)
		)
		(fill yes)
		(layer "F.Cu")
		(net "M_A_CPU0_SA_DQ<6>")
	)
	(gr_poly
		(pts
			(xy 330.19238 -291.120322) (xy 330.19238 -290.929822) (xy 330.09078 -290.8935) (xy 330.03998 -290.8935)
			(xy 330.03998 -291.15639) (xy 330.09078 -291.15639)
		)
		(stroke
			(width 0)
			(type solid)
		)
		(fill yes)
		(layer "F.Cu")
		(net "M_A_CPU0_SA_DQ<6>")
	)
	(gr_poly
		(pts
			(xy 330.19238 -290.523422) (xy 330.19238 -290.332922) (xy 330.09078 -290.2966) (xy 330.03998 -290.2966)
			(xy 330.03998 -290.55949) (xy 330.09078 -290.55949)
		)
		(stroke
			(width 0)
			(type solid)
		)
		(fill yes)
		(layer "F.Cu")
		(net "M_A_CPU0_SA_DQ<6>")
	)
	(gr_poly
		(pts
			(xy 330.19238 -289.926522) (xy 330.19238 -289.736022) (xy 330.09078 -289.6997) (xy 330.03998 -289.6997)
			(xy 330.03998 -289.96259) (xy 330.09078 -289.96259)
		)
		(stroke
			(width 0)
			(type solid)
		)
		(fill yes)
		(layer "F.Cu")
		(net "M_A_CPU0_SA_DQ<6>")
	)
	(gr_poly
		(pts
			(xy 330.19238 -289.329622) (xy 330.19238 -289.139122) (xy 330.09078 -289.1028) (xy 330.03998 -289.1028)
			(xy 330.03998 -289.36569) (xy 330.09078 -289.36569)
		)
		(stroke
			(width 0)
			(type solid)
		)
		(fill yes)
		(layer "F.Cu")
		(net "M_A_CPU0_SA_DQ<6>")
	)
	(gr_poly
		(pts
			(xy 330.19238 -288.732722) (xy 330.19238 -288.542222) (xy 330.09078 -288.5059) (xy 330.03998 -288.5059)
			(xy 330.03998 -288.76879) (xy 330.09078 -288.76879)
		)
		(stroke
			(width 0)
			(type solid)
		)
		(fill yes)
		(layer "F.Cu")
		(net "M_A_CPU0_SA_DQ<6>")
	)
	(gr_poly
		(pts
			(xy 330.19238 -288.135822) (xy 330.19238 -287.945322) (xy 330.09078 -287.909) (xy 330.03998 -287.909)
			(xy 330.03998 -288.17189) (xy 330.09078 -288.17189)
		)
		(stroke
			(width 0)
			(type solid)
		)
		(fill yes)
		(layer "F.Cu")
		(net "M_A_CPU0_SA_DQ<6>")
	)
	(gr_poly
		(pts
			(xy 330.19238 -287.538922) (xy 330.19238 -287.348422) (xy 330.09078 -287.3121) (xy 330.03998 -287.3121)
			(xy 330.03998 -287.57499) (xy 330.09078 -287.57499)
		)
		(stroke
			(width 0)
			(type solid)
		)
		(fill yes)
		(layer "F.Cu")
		(net "M_A_CPU0_SA_DQ<6>")
	)
	(gr_poly
		(pts
			(xy 330.19238 -286.942022) (xy 330.19238 -286.751522) (xy 330.09078 -286.7152) (xy 330.03998 -286.7152)
			(xy 330.03998 -286.97809) (xy 330.09078 -286.97809)
		)
		(stroke
			(width 0)
			(type solid)
		)
		(fill yes)
		(layer "F.Cu")
		(net "M_A_CPU0_SA_DQ<6>")
	)
	(gr_poly
		(pts
			(xy 330.19238 -286.345122) (xy 330.19238 -286.154622) (xy 330.09078 -286.1183) (xy 330.03998 -286.1183)
			(xy 330.03998 -286.38119) (xy 330.09078 -286.38119)
		)
		(stroke
			(width 0)
			(type solid)
		)
		(fill yes)
		(layer "F.Cu")
		(net "M_A_CPU0_SA_DQ<6>")
	)
	(gr_poly
		(pts
			(xy 330.19238 -285.748222) (xy 330.19238 -285.557722) (xy 330.09078 -285.5214) (xy 330.03998 -285.5214)
			(xy 330.03998 -285.78429) (xy 330.09078 -285.78429)
		)
		(stroke
			(width 0)
			(type solid)
		)
		(fill yes)
		(layer "F.Cu")
		(net "M_A_CPU0_SA_DQ<6>")
	)
	(gr_poly
		(pts
			(xy 330.19238 -285.151322) (xy 330.19238 -284.960822) (xy 330.09078 -284.9245) (xy 330.03998 -284.9245)
			(xy 330.03998 -285.18739) (xy 330.09078 -285.18739)
		)
		(stroke
			(width 0)
			(type solid)
		)
		(fill yes)
		(layer "F.Cu")
		(net "M_A_CPU0_SA_DQ<6>")
	)
	(gr_poly
		(pts
			(xy 330.19238 -284.554422) (xy 330.19238 -284.363922) (xy 330.09078 -284.3276) (xy 330.03998 -284.3276)
			(xy 330.03998 -284.59049) (xy 330.09078 -284.59049)
		)
		(stroke
			(width 0)
			(type solid)
		)
		(fill yes)
		(layer "F.Cu")
		(net "M_A_CPU0_SA_DQ<6>")
	)
	(gr_poly
		(pts
			(xy 330.19238 -283.957522) (xy 330.19238 -283.767022) (xy 330.09078 -283.7307) (xy 330.03998 -283.7307)
			(xy 330.03998 -283.99359) (xy 330.09078 -283.99359)
		)
		(stroke
			(width 0)
			(type solid)
		)
		(fill yes)
		(layer "F.Cu")
		(net "M_A_CPU0_SA_DQ<6>")
	)
	(gr_poly
		(pts
			(xy 330.19238 -283.360622) (xy 330.19238 -283.170122) (xy 330.09078 -283.1338) (xy 330.03998 -283.1338)
			(xy 330.03998 -283.39669) (xy 330.09078 -283.39669)
		)
		(stroke
			(width 0)
			(type solid)
		)
		(fill yes)
		(layer "F.Cu")
		(net "M_A_CPU0_SA_DQ<6>")
	)
	(gr_poly
		(pts
			(xy 330.19238 -282.763722) (xy 330.19238 -282.573222) (xy 330.09078 -282.5369) (xy 330.03998 -282.5369)
			(xy 330.03998 -282.79979) (xy 330.09078 -282.79979)
		)
		(stroke
			(width 0)
			(type solid)
		)
		(fill yes)
		(layer "F.Cu")
		(net "M_A_CPU0_SA_DQ<6>")
	)
	(gr_poly
		(pts
			(xy 330.194158 -232.320084) (xy 330.240386 -232.222548) (xy 330.105512 -232.087928) (xy 330.00823 -232.134156)
			(xy 329.972162 -232.16997) (xy 330.15809 -232.355898)
		)
		(stroke
			(width 0)
			(type solid)
		)
		(fill yes)
		(layer "F.Cu")
		(net "M_A_CPU0_SB_DQ<15>")
	)
	(gr_poly
		(pts
			(xy 330.204064 -231.050592) (xy 330.250292 -230.95331) (xy 330.115672 -230.818436) (xy 330.018136 -230.864664)
			(xy 329.982322 -230.900732) (xy 330.16825 -231.08666)
		)
		(stroke
			(width 0)
			(type solid)
		)
		(fill yes)
		(layer "F.Cu")
		(net "M_A_CPU0_SB_DQ<18>")
	)
	(gr_poly
		(pts
			(xy 330.20508 -273.482562) (xy 330.158852 -273.385026) (xy 330.123038 -273.349212) (xy 329.93711 -273.534886)
			(xy 329.972924 -273.570954) (xy 330.07046 -273.617182)
		)
		(stroke
			(width 0)
			(type solid)
		)
		(fill yes)
		(layer "F.Cu")
		(net "M_A_CPU0_SA_DQ<21>")
	)
	(gr_poly
		(pts
			(xy 330.210414 -280.381456) (xy 330.248006 -280.194512) (xy 330.155296 -280.13914) (xy 330.105512 -280.129234)
			(xy 330.05395 -280.387044) (xy 330.103734 -280.39695)
		)
		(stroke
			(width 0)
			(type solid)
		)
		(fill yes)
		(layer "F.Cu")
		(net "M_A_CPU0_SA_DQ<5>")
	)
	(gr_poly
		(pts
			(xy 330.213208 -230.197152) (xy 330.259436 -230.09987) (xy 330.124816 -229.964996) (xy 330.02728 -230.011478)
			(xy 329.991466 -230.047292) (xy 330.177394 -230.23322)
		)
		(stroke
			(width 0)
			(type solid)
		)
		(fill yes)
		(layer "F.Cu")
		(net "M_A_CPU0_SB_DQ<19>")
	)
	(gr_poly
		(pts
			(xy 330.214224 -259.618226) (xy 330.178156 -259.516626) (xy 329.987656 -259.516626) (xy 329.951334 -259.618226)
			(xy 329.951334 -259.669026) (xy 330.214224 -259.669026)
		)
		(stroke
			(width 0)
			(type solid)
		)
		(fill yes)
		(layer "F.Cu")
		(net "M_A_CPU0_SA_CS_N<0>")
	)
	(gr_poly
		(pts
			(xy 330.214224 -259.313426) (xy 330.178156 -259.211826) (xy 329.987656 -259.211826) (xy 329.951334 -259.313426)
			(xy 329.951334 -259.364226) (xy 330.214224 -259.364226)
		)
		(stroke
			(width 0)
			(type solid)
		)
		(fill yes)
		(layer "F.Cu")
		(net "M_A_CPU0_SA_CS_N<2>")
	)
	(gr_poly
		(pts
			(xy 330.214224 -259.008626) (xy 330.178156 -258.907026) (xy 329.987656 -258.907026) (xy 329.951334 -259.008626)
			(xy 329.951334 -259.059426) (xy 330.214224 -259.059426)
		)
		(stroke
			(width 0)
			(type solid)
		)
		(fill yes)
		(layer "F.Cu")
		(net "M_A_CPU0_SA_CS_N<3>")
	)
	(gr_poly
		(pts
			(xy 330.214224 -258.703826) (xy 330.178156 -258.602226) (xy 329.987656 -258.602226) (xy 329.951334 -258.703826)
			(xy 329.951334 -258.754626) (xy 330.214224 -258.754626)
		)
		(stroke
			(width 0)
			(type solid)
		)
		(fill yes)
		(layer "F.Cu")
		(net "M_A_CPU0_SA_CS_N<1>")
	)
	(gr_poly
		(pts
			(xy 330.214224 -258.399026) (xy 330.178156 -258.297426) (xy 329.987656 -258.297426) (xy 329.951334 -258.399026)
			(xy 329.951334 -258.449826) (xy 330.214224 -258.449826)
		)
		(stroke
			(width 0)
			(type solid)
		)
		(fill yes)
		(layer "F.Cu")
		(net "M_A_CPU0_SA_CA<0>")
	)
	(gr_poly
		(pts
			(xy 330.214224 -258.094226) (xy 330.178156 -257.992626) (xy 329.987656 -257.992626) (xy 329.951334 -258.094226)
			(xy 329.951334 -258.145026) (xy 330.214224 -258.145026)
		)
		(stroke
			(width 0)
			(type solid)
		)
		(fill yes)
		(layer "F.Cu")
		(net "M_A_CPU0_SA_CA<1>")
	)
	(gr_poly
		(pts
			(xy 330.214224 -257.789426) (xy 330.178156 -257.687826) (xy 329.987656 -257.687826) (xy 329.951334 -257.789426)
			(xy 329.951334 -257.840226) (xy 330.214224 -257.840226)
		)
		(stroke
			(width 0)
			(type solid)
		)
		(fill yes)
		(layer "F.Cu")
		(net "M_A_CPU0_SA_CA<2>")
	)
	(gr_poly
		(pts
			(xy 330.21524 -274.336764) (xy 330.169012 -274.239228) (xy 330.132944 -274.203414) (xy 329.947016 -274.389342)
			(xy 329.983084 -274.425156) (xy 330.080366 -274.471384)
		)
		(stroke
			(width 0)
			(type solid)
		)
		(fill yes)
		(layer "F.Cu")
		(net "M_A_CPU0_SA_DQ<20>")
	)
	(gr_poly
		(pts
			(xy 330.21905 -228.046788) (xy 330.265278 -227.949252) (xy 330.130658 -227.814632) (xy 330.033122 -227.86086)
			(xy 329.997308 -227.896674) (xy 330.183236 -228.082602)
		)
		(stroke
			(width 0)
			(type solid)
		)
		(fill yes)
		(layer "F.Cu")
		(net "M_A_CPU0_SB_DQ<20>")
	)
	(gr_poly
		(pts
			(xy 330.228448 -227.193094) (xy 330.274676 -227.095812) (xy 330.140056 -226.960938) (xy 330.04252 -227.007166)
			(xy 330.006706 -227.043234) (xy 330.192634 -227.229162)
		)
		(stroke
			(width 0)
			(type solid)
		)
		(fill yes)
		(layer "F.Cu")
		(net "M_A_CPU0_SB_DQ<21>")
	)
	(gr_poly
		(pts
			(xy 330.228956 -281.067002) (xy 330.179172 -281.056842) (xy 330.072238 -281.072336) (xy 330.0349 -281.25928)
			(xy 330.127356 -281.314652) (xy 330.17714 -281.324558)
		)
		(stroke
			(width 0)
			(type solid)
		)
		(fill yes)
		(layer "F.Cu")
		(net "M_A_CPU0_SA_DQ<6>")
	)
	(gr_poly
		(pts
			(xy 330.23048 -276.697694) (xy 330.194666 -276.661626) (xy 330.09713 -276.615398) (xy 329.96251 -276.750018)
			(xy 330.008738 -276.847554) (xy 330.044806 -276.883368)
		)
		(stroke
			(width 0)
			(type solid)
		)
		(fill yes)
		(layer "F.Cu")
		(net "M_A_CPU0_SA_DQ<17>")
	)
	(gr_poly
		(pts
			(xy 330.239878 -277.551134) (xy 330.204064 -277.515066) (xy 330.106528 -277.468838) (xy 329.971908 -277.603712)
			(xy 330.018136 -277.700994) (xy 330.05395 -277.737062)
		)
		(stroke
			(width 0)
			(type solid)
		)
		(fill yes)
		(layer "F.Cu")
		(net "M_A_CPU0_SA_DQ<16>")
	)
	(gr_poly
		(pts
			(xy 330.254102 -267.58392) (xy 330.218034 -267.548106) (xy 330.120752 -267.501878) (xy 329.985878 -267.636498)
			(xy 330.032106 -267.734034) (xy 330.068174 -267.769848)
		)
		(stroke
			(width 0)
			(type solid)
		)
		(fill yes)
		(layer "F.Cu")
		(net "M_A_CPU0_SA_DQ<29>")
	)
	(gr_poly
		(pts
			(xy 330.255372 -217.801698) (xy 330.204572 -217.801698) (xy 330.102972 -217.837766) (xy 330.102972 -218.028266)
			(xy 330.204572 -218.064334) (xy 330.255372 -218.064334)
		)
		(stroke
			(width 0)
			(type solid)
		)
		(fill yes)
		(layer "F.Cu")
		(net "M_A_CPU0_SB_DQ<27>")
	)
	(gr_poly
		(pts
			(xy 330.255372 -217.204798) (xy 330.204572 -217.204798) (xy 330.102972 -217.240866) (xy 330.102972 -217.431366)
			(xy 330.204572 -217.467434) (xy 330.255372 -217.467434)
		)
		(stroke
			(width 0)
			(type solid)
		)
		(fill yes)
		(layer "F.Cu")
		(net "M_A_CPU0_SB_DQ<27>")
	)
	(gr_poly
		(pts
			(xy 330.255372 -216.607898) (xy 330.204572 -216.607898) (xy 330.102972 -216.643966) (xy 330.102972 -216.834466)
			(xy 330.204572 -216.870534) (xy 330.255372 -216.870534)
		)
		(stroke
			(width 0)
			(type solid)
		)
		(fill yes)
		(layer "F.Cu")
		(net "M_A_CPU0_SB_DQ<27>")
	)
	(gr_poly
		(pts
			(xy 330.25969 -271.246346) (xy 330.213462 -271.149064) (xy 330.177648 -271.112996) (xy 329.99172 -271.298924)
			(xy 330.027534 -271.334992) (xy 330.12507 -271.38122)
		)
		(stroke
			(width 0)
			(type solid)
		)
		(fill yes)
		(layer "F.Cu")
		(net "M_A_CPU0_SA_DQ<25>")
	)
	(gr_poly
		(pts
			(xy 330.25969 -264.152634) (xy 330.213462 -264.055098) (xy 330.177648 -264.019284) (xy 329.99172 -264.205212)
			(xy 330.027788 -264.241026) (xy 330.12507 -264.287254)
		)
		(stroke
			(width 0)
			(type solid)
		)
		(fill yes)
		(layer "F.Cu")
		(net "M_A_CPU0_SA_CB<1>")
	)
	(gr_poly
		(pts
			(xy 330.2635 -268.437868) (xy 330.227686 -268.4018) (xy 330.13015 -268.355572) (xy 329.99553 -268.490192)
			(xy 330.041758 -268.587728) (xy 330.077826 -268.623542)
		)
		(stroke
			(width 0)
			(type solid)
		)
		(fill yes)
		(layer "F.Cu")
		(net "M_A_CPU0_SA_DQ<28>")
	)
	(gr_poly
		(pts
			(xy 330.268834 -272.099786) (xy 330.222606 -272.00225) (xy 330.186792 -271.966436) (xy 330.000864 -272.152364)
			(xy 330.036932 -272.188178) (xy 330.134214 -272.234406)
		)
		(stroke
			(width 0)
			(type solid)
		)
		(fill yes)
		(layer "F.Cu")
		(net "M_A_CPU0_SA_DQ<24>")
	)
	(gr_poly
		(pts
			(xy 330.269088 -265.006074) (xy 330.22286 -264.908792) (xy 330.187046 -264.872724) (xy 330.001118 -265.058652)
			(xy 330.036932 -265.094466) (xy 330.134468 -265.140948)
		)
		(stroke
			(width 0)
			(type solid)
		)
		(fill yes)
		(layer "F.Cu")
		(net "M_A_CPU0_SA_CB<0>")
	)
	(gr_poly
		(pts
			(xy 330.275184 -281.611832) (xy 330.312522 -281.424888) (xy 330.220066 -281.369516) (xy 330.170282 -281.35961)
			(xy 330.11872 -281.617166) (xy 330.168504 -281.627326)
		)
		(stroke
			(width 0)
			(type solid)
		)
		(fill yes)
		(layer "F.Cu")
		(net "M_A_CPU0_SA_DQ<6>")
	)
	(gr_poly
		(pts
			(xy 330.28128 -279.251156) (xy 330.231496 -279.24125) (xy 330.124816 -279.256998) (xy 330.087478 -279.443688)
			(xy 330.179934 -279.49906) (xy 330.229718 -279.508966)
		)
		(stroke
			(width 0)
			(type solid)
		)
		(fill yes)
		(layer "F.Cu")
		(net "M_A_CPU0_SA_DQ<5>")
	)
	(gr_poly
		(pts
			(xy 330.306426 -276.402546) (xy 330.260198 -276.305264) (xy 330.224384 -276.269196) (xy 330.038456 -276.455124)
			(xy 330.07427 -276.491192) (xy 330.171806 -276.53742)
		)
		(stroke
			(width 0)
			(type solid)
		)
		(fill yes)
		(layer "F.Cu")
		(net "M_A_CPU0_SA_DQ<19>")
	)
	(gr_poly
		(pts
			(xy 330.317348 -277.257764) (xy 330.27112 -277.160228) (xy 330.235306 -277.12416) (xy 330.049378 -277.310088)
			(xy 330.085192 -277.346156) (xy 330.182728 -277.392384)
		)
		(stroke
			(width 0)
			(type solid)
		)
		(fill yes)
		(layer "F.Cu")
		(net "M_A_CPU0_SA_DQ<18>")
	)
	(gr_poly
		(pts
			(xy 330.327762 -279.79624) (xy 330.3651 -279.609296) (xy 330.272644 -279.553924) (xy 330.22286 -279.544018)
			(xy 330.171044 -279.801828) (xy 330.221082 -279.811734)
		)
		(stroke
			(width 0)
			(type solid)
		)
		(fill yes)
		(layer "F.Cu")
		(net "M_A_CPU0_SA_DQ<5>")
	)
	(gr_poly
		(pts
			(xy 330.331318 -267.29055) (xy 330.28509 -267.193014) (xy 330.249276 -267.1572) (xy 330.063348 -267.343128)
			(xy 330.099416 -267.378942) (xy 330.196698 -267.42517)
		)
		(stroke
			(width 0)
			(type solid)
		)
		(fill yes)
		(layer "F.Cu")
		(net "M_A_CPU0_SA_DQ<31>")
	)
	(gr_poly
		(pts
			(xy 330.33335 -232.602786) (xy 330.369164 -232.566972) (xy 330.183236 -232.381044) (xy 330.147422 -232.416858)
			(xy 330.101194 -232.514394) (xy 330.235814 -232.649014)
		)
		(stroke
			(width 0)
			(type solid)
		)
		(fill yes)
		(layer "F.Cu")
		(net "M_A_CPU0_SB_DQ<15>")
	)
	(gr_poly
		(pts
			(xy 330.334112 -273.138138) (xy 330.298044 -273.102324) (xy 330.200762 -273.055842) (xy 330.065888 -273.190716)
			(xy 330.112116 -273.287998) (xy 330.148184 -273.324066)
		)
		(stroke
			(width 0)
			(type solid)
		)
		(fill yes)
		(layer "F.Cu")
		(net "M_A_CPU0_SA_DQ<21>")
	)
	(gr_poly
		(pts
			(xy 330.341224 -268.144498) (xy 330.294996 -268.046962) (xy 330.258928 -268.011148) (xy 330.073 -268.197076)
			(xy 330.109068 -268.23289) (xy 330.20635 -268.279118)
		)
		(stroke
			(width 0)
			(type solid)
		)
		(fill yes)
		(layer "F.Cu")
		(net "M_A_CPU0_SA_DQ<30>")
	)
	(gr_poly
		(pts
			(xy 330.343256 -231.333548) (xy 330.37907 -231.29748) (xy 330.193396 -231.111806) (xy 330.157328 -231.14762)
			(xy 330.1111 -231.245156) (xy 330.24572 -231.379776)
		)
		(stroke
			(width 0)
			(type solid)
		)
		(fill yes)
		(layer "F.Cu")
		(net "M_A_CPU0_SB_DQ<18>")
	)
	(gr_poly
		(pts
			(xy 330.344018 -273.99234) (xy 330.308204 -273.956526) (xy 330.210668 -273.910044) (xy 330.076048 -274.044918)
			(xy 330.122276 -274.1422) (xy 330.15809 -274.178268)
		)
		(stroke
			(width 0)
			(type solid)
		)
		(fill yes)
		(layer "F.Cu")
		(net "M_A_CPU0_SA_DQ<20>")
	)
	(gr_poly
		(pts
			(xy 330.34478 -294.77335) (xy 330.29398 -294.77335) (xy 330.19238 -294.809672) (xy 330.19238 -295.000172)
			(xy 330.29398 -295.03624) (xy 330.34478 -295.03624)
		)
		(stroke
			(width 0)
			(type solid)
		)
		(fill yes)
		(layer "F.Cu")
		(net "M_A_CPU0_SA_DQ<4>")
	)
	(gr_poly
		(pts
			(xy 330.34478 -294.17645) (xy 330.29398 -294.17645) (xy 330.19238 -294.212772) (xy 330.19238 -294.403272)
			(xy 330.29398 -294.43934) (xy 330.34478 -294.43934)
		)
		(stroke
			(width 0)
			(type solid)
		)
		(fill yes)
		(layer "F.Cu")
		(net "M_A_CPU0_SA_DQ<4>")
	)
	(gr_poly
		(pts
			(xy 330.34478 -293.57955) (xy 330.29398 -293.57955) (xy 330.19238 -293.615872) (xy 330.19238 -293.806372)
			(xy 330.29398 -293.84244) (xy 330.34478 -293.84244)
		)
		(stroke
			(width 0)
			(type solid)
		)
		(fill yes)
		(layer "F.Cu")
		(net "M_A_CPU0_SA_DQ<4>")
	)
	(gr_poly
		(pts
			(xy 330.34478 -292.98265) (xy 330.29398 -292.98265) (xy 330.19238 -293.018972) (xy 330.19238 -293.209472)
			(xy 330.29398 -293.24554) (xy 330.34478 -293.24554)
		)
		(stroke
			(width 0)
			(type solid)
		)
		(fill yes)
		(layer "F.Cu")
		(net "M_A_CPU0_SA_DQ<4>")
	)
	(gr_poly
		(pts
			(xy 330.34478 -292.38575) (xy 330.29398 -292.38575) (xy 330.19238 -292.422072) (xy 330.19238 -292.612572)
			(xy 330.29398 -292.64864) (xy 330.34478 -292.64864)
		)
		(stroke
			(width 0)
			(type solid)
		)
		(fill yes)
		(layer "F.Cu")
		(net "M_A_CPU0_SA_DQ<4>")
	)
	(gr_poly
		(pts
			(xy 330.34478 -291.78885) (xy 330.29398 -291.78885) (xy 330.19238 -291.825172) (xy 330.19238 -292.015672)
			(xy 330.29398 -292.05174) (xy 330.34478 -292.05174)
		)
		(stroke
			(width 0)
			(type solid)
		)
		(fill yes)
		(layer "F.Cu")
		(net "M_A_CPU0_SA_DQ<4>")
	)
	(gr_poly
		(pts
			(xy 330.34478 -291.19195) (xy 330.29398 -291.19195) (xy 330.19238 -291.228272) (xy 330.19238 -291.418772)
			(xy 330.29398 -291.45484) (xy 330.34478 -291.45484)
		)
		(stroke
			(width 0)
			(type solid)
		)
		(fill yes)
		(layer "F.Cu")
		(net "M_A_CPU0_SA_DQ<4>")
	)
	(gr_poly
		(pts
			(xy 330.34478 -290.59505) (xy 330.29398 -290.59505) (xy 330.19238 -290.631372) (xy 330.19238 -290.821872)
			(xy 330.29398 -290.85794) (xy 330.34478 -290.85794)
		)
		(stroke
			(width 0)
			(type solid)
		)
		(fill yes)
		(layer "F.Cu")
		(net "M_A_CPU0_SA_DQ<4>")
	)
	(gr_poly
		(pts
			(xy 330.34478 -289.99815) (xy 330.29398 -289.99815) (xy 330.19238 -290.034472) (xy 330.19238 -290.224972)
			(xy 330.29398 -290.26104) (xy 330.34478 -290.26104)
		)
		(stroke
			(width 0)
			(type solid)
		)
		(fill yes)
		(layer "F.Cu")
		(net "M_A_CPU0_SA_DQ<4>")
	)
	(gr_poly
		(pts
			(xy 330.34478 -289.40125) (xy 330.29398 -289.40125) (xy 330.19238 -289.437572) (xy 330.19238 -289.628072)
			(xy 330.29398 -289.66414) (xy 330.34478 -289.66414)
		)
		(stroke
			(width 0)
			(type solid)
		)
		(fill yes)
		(layer "F.Cu")
		(net "M_A_CPU0_SA_DQ<4>")
	)
	(gr_poly
		(pts
			(xy 330.34478 -288.80435) (xy 330.29398 -288.80435) (xy 330.19238 -288.840672) (xy 330.19238 -289.031172)
			(xy 330.29398 -289.06724) (xy 330.34478 -289.06724)
		)
		(stroke
			(width 0)
			(type solid)
		)
		(fill yes)
		(layer "F.Cu")
		(net "M_A_CPU0_SA_DQ<4>")
	)
	(gr_poly
		(pts
			(xy 330.34478 -288.20745) (xy 330.29398 -288.20745) (xy 330.19238 -288.243772) (xy 330.19238 -288.434272)
			(xy 330.29398 -288.47034) (xy 330.34478 -288.47034)
		)
		(stroke
			(width 0)
			(type solid)
		)
		(fill yes)
		(layer "F.Cu")
		(net "M_A_CPU0_SA_DQ<4>")
	)
	(gr_poly
		(pts
			(xy 330.34478 -287.61055) (xy 330.29398 -287.61055) (xy 330.19238 -287.646872) (xy 330.19238 -287.837372)
			(xy 330.29398 -287.87344) (xy 330.34478 -287.87344)
		)
		(stroke
			(width 0)
			(type solid)
		)
		(fill yes)
		(layer "F.Cu")
		(net "M_A_CPU0_SA_DQ<4>")
	)
	(gr_poly
		(pts
			(xy 330.34478 -287.01365) (xy 330.29398 -287.01365) (xy 330.19238 -287.049972) (xy 330.19238 -287.240472)
			(xy 330.29398 -287.27654) (xy 330.34478 -287.27654)
		)
		(stroke
			(width 0)
			(type solid)
		)
		(fill yes)
		(layer "F.Cu")
		(net "M_A_CPU0_SA_DQ<4>")
	)
	(gr_poly
		(pts
			(xy 330.34478 -286.41675) (xy 330.29398 -286.41675) (xy 330.19238 -286.453072) (xy 330.19238 -286.643572)
			(xy 330.29398 -286.67964) (xy 330.34478 -286.67964)
		)
		(stroke
			(width 0)
			(type solid)
		)
		(fill yes)
		(layer "F.Cu")
		(net "M_A_CPU0_SA_DQ<4>")
	)
	(gr_poly
		(pts
			(xy 330.34478 -285.81985) (xy 330.29398 -285.81985) (xy 330.19238 -285.856172) (xy 330.19238 -286.046672)
			(xy 330.29398 -286.08274) (xy 330.34478 -286.08274)
		)
		(stroke
			(width 0)
			(type solid)
		)
		(fill yes)
		(layer "F.Cu")
		(net "M_A_CPU0_SA_DQ<4>")
	)
	(gr_poly
		(pts
			(xy 330.34478 -285.22295) (xy 330.29398 -285.22295) (xy 330.19238 -285.259272) (xy 330.19238 -285.449772)
			(xy 330.29398 -285.48584) (xy 330.34478 -285.48584)
		)
		(stroke
			(width 0)
			(type solid)
		)
		(fill yes)
		(layer "F.Cu")
		(net "M_A_CPU0_SA_DQ<4>")
	)
	(gr_poly
		(pts
			(xy 330.34478 -284.62605) (xy 330.29398 -284.62605) (xy 330.19238 -284.662372) (xy 330.19238 -284.852872)
			(xy 330.29398 -284.88894) (xy 330.34478 -284.88894)
		)
		(stroke
			(width 0)
			(type solid)
		)
		(fill yes)
		(layer "F.Cu")
		(net "M_A_CPU0_SA_DQ<4>")
	)
	(gr_poly
		(pts
			(xy 330.34478 -284.02915) (xy 330.29398 -284.02915) (xy 330.19238 -284.065472) (xy 330.19238 -284.255972)
			(xy 330.29398 -284.29204) (xy 330.34478 -284.29204)
		)
		(stroke
			(width 0)
			(type solid)
		)
		(fill yes)
		(layer "F.Cu")
		(net "M_A_CPU0_SA_DQ<4>")
	)
	(gr_poly
		(pts
			(xy 330.34478 -283.43225) (xy 330.29398 -283.43225) (xy 330.19238 -283.468572) (xy 330.19238 -283.659072)
			(xy 330.29398 -283.69514) (xy 330.34478 -283.69514)
		)
		(stroke
			(width 0)
			(type solid)
		)
		(fill yes)
		(layer "F.Cu")
		(net "M_A_CPU0_SA_DQ<4>")
	)
	(gr_poly
		(pts
			(xy 330.34478 -282.83535) (xy 330.29398 -282.83535) (xy 330.19238 -282.871672) (xy 330.19238 -283.062172)
			(xy 330.29398 -283.09824) (xy 330.34478 -283.09824)
		)
		(stroke
			(width 0)
			(type solid)
		)
		(fill yes)
		(layer "F.Cu")
		(net "M_A_CPU0_SA_DQ<4>")
	)
	(gr_poly
		(pts
			(xy 330.34605 -280.481532) (xy 330.296266 -280.471626) (xy 330.189586 -280.48712) (xy 330.152248 -280.674064)
			(xy 330.244704 -280.729436) (xy 330.294488 -280.739342)
		)
		(stroke
			(width 0)
			(type solid)
		)
		(fill yes)
		(layer "F.Cu")
		(net "M_A_CPU0_SA_DQ<6>")
	)
	(gr_poly
		(pts
			(xy 330.3524 -230.480108) (xy 330.388468 -230.444294) (xy 330.20254 -230.258366) (xy 330.166472 -230.29418)
			(xy 330.120244 -230.391716) (xy 330.255118 -230.526336)
		)
		(stroke
			(width 0)
			(type solid)
		)
		(fill yes)
		(layer "F.Cu")
		(net "M_A_CPU0_SB_DQ<19>")
	)
	(gr_poly
		(pts
			(xy 330.358242 -228.32949) (xy 330.39431 -228.293676) (xy 330.208382 -228.107748) (xy 330.172568 -228.143562)
			(xy 330.126086 -228.241098) (xy 330.26096 -228.375718)
		)
		(stroke
			(width 0)
			(type solid)
		)
		(fill yes)
		(layer "F.Cu")
		(net "M_A_CPU0_SB_DQ<20>")
	)
	(gr_poly
		(pts
			(xy 330.36764 -227.47605) (xy 330.403708 -227.440236) (xy 330.21778 -227.254308) (xy 330.181712 -227.290122)
			(xy 330.135484 -227.387658) (xy 330.270358 -227.522278)
		)
		(stroke
			(width 0)
			(type solid)
		)
		(fill yes)
		(layer "F.Cu")
		(net "M_A_CPU0_SB_DQ<21>")
	)
	(gr_poly
		(pts
			(xy 330.388722 -270.901922) (xy 330.352654 -270.866108) (xy 330.255372 -270.81988) (xy 330.120498 -270.9545)
			(xy 330.166726 -271.052036) (xy 330.202794 -271.08785)
		)
		(stroke
			(width 0)
			(type solid)
		)
		(fill yes)
		(layer "F.Cu")
		(net "M_A_CPU0_SA_DQ<25>")
	)
	(gr_poly
		(pts
			(xy 330.388722 -263.80821) (xy 330.352654 -263.772396) (xy 330.255372 -263.726168) (xy 330.120498 -263.860788)
			(xy 330.16698 -263.958324) (xy 330.202794 -263.994138)
		)
		(stroke
			(width 0)
			(type solid)
		)
		(fill yes)
		(layer "F.Cu")
		(net "M_A_CPU0_SA_CB<1>")
	)
	(gr_poly
		(pts
			(xy 330.392278 -281.026362) (xy 330.42987 -280.839672) (xy 330.337414 -280.7843) (xy 330.287376 -280.77414)
			(xy 330.235814 -281.03195) (xy 330.285598 -281.04211)
		)
		(stroke
			(width 0)
			(type solid)
		)
		(fill yes)
		(layer "F.Cu")
		(net "M_A_CPU0_SA_DQ<6>")
	)
	(gr_poly
		(pts
			(xy 330.397866 -271.755362) (xy 330.361798 -271.719548) (xy 330.264516 -271.67332) (xy 330.129642 -271.80794)
			(xy 330.176124 -271.905476) (xy 330.211938 -271.94129)
		)
		(stroke
			(width 0)
			(type solid)
		)
		(fill yes)
		(layer "F.Cu")
		(net "M_A_CPU0_SA_DQ<24>")
	)
	(gr_poly
		(pts
			(xy 330.39812 -264.66165) (xy 330.362052 -264.625836) (xy 330.26477 -264.579608) (xy 330.129896 -264.714228)
			(xy 330.176124 -264.811764) (xy 330.212192 -264.847578)
		)
		(stroke
			(width 0)
			(type solid)
		)
		(fill yes)
		(layer "F.Cu")
		(net "M_A_CPU0_SA_CB<0>")
	)
	(gr_poly
		(pts
			(xy 330.400406 -232.957624) (xy 330.446634 -232.860342) (xy 330.312014 -232.725468) (xy 330.214478 -232.77195)
			(xy 330.178664 -232.807764) (xy 330.364592 -232.993692)
		)
		(stroke
			(width 0)
			(type solid)
		)
		(fill yes)
		(layer "F.Cu")
		(net "M_A_CPU0_SB_DQ<13>")
	)
	(gr_poly
		(pts
			(xy 330.407772 -218.326716) (xy 330.407772 -218.136216) (xy 330.306172 -218.099894) (xy 330.255372 -218.099894)
			(xy 330.255372 -218.363038) (xy 330.306172 -218.363038)
		)
		(stroke
			(width 0)
			(type solid)
		)
		(fill yes)
		(layer "F.Cu")
		(net "M_A_CPU0_SB_DQ<27>")
	)
	(gr_poly
		(pts
			(xy 330.407772 -217.729816) (xy 330.407772 -217.539316) (xy 330.306172 -217.502994) (xy 330.255372 -217.502994)
			(xy 330.255372 -217.766138) (xy 330.306172 -217.766138)
		)
		(stroke
			(width 0)
			(type solid)
		)
		(fill yes)
		(layer "F.Cu")
		(net "M_A_CPU0_SB_DQ<27>")
	)
	(gr_poly
		(pts
			(xy 330.407772 -217.132916) (xy 330.407772 -216.942416) (xy 330.306172 -216.906094) (xy 330.255372 -216.906094)
			(xy 330.255372 -217.169238) (xy 330.306172 -217.169238)
		)
		(stroke
			(width 0)
			(type solid)
		)
		(fill yes)
		(layer "F.Cu")
		(net "M_A_CPU0_SB_DQ<27>")
	)
	(gr_poly
		(pts
			(xy 330.407772 -216.536016) (xy 330.407772 -216.345516) (xy 330.306172 -216.309194) (xy 330.255372 -216.309194)
			(xy 330.255372 -216.572338) (xy 330.306172 -216.572338)
		)
		(stroke
			(width 0)
			(type solid)
		)
		(fill yes)
		(layer "F.Cu")
		(net "M_A_CPU0_SB_DQ<27>")
	)
	(gr_poly
		(pts
			(xy 330.410566 -231.688386) (xy 330.456794 -231.59085) (xy 330.32192 -231.45623) (xy 330.224638 -231.502458)
			(xy 330.18857 -231.538272) (xy 330.374498 -231.7242)
		)
		(stroke
			(width 0)
			(type solid)
		)
		(fill yes)
		(layer "F.Cu")
		(net "M_A_CPU0_SB_DQ<16>")
	)
	(gr_poly
		(pts
			(xy 330.411074 -281.711908) (xy 330.361036 -281.702002) (xy 330.254356 -281.717496) (xy 330.217018 -281.904186)
			(xy 330.309474 -281.959812) (xy 330.359258 -281.969718)
		)
		(stroke
			(width 0)
			(type solid)
		)
		(fill yes)
		(layer "F.Cu")
		(net "M_A_CPU0_SA_DQ<4>")
	)
	(gr_poly
		(pts
			(xy 330.411582 -272.844768) (xy 330.365354 -272.747232) (xy 330.329286 -272.711418) (xy 330.143358 -272.897092)
			(xy 330.179426 -272.93316) (xy 330.276708 -272.979388)
		)
		(stroke
			(width 0)
			(type solid)
		)
		(fill yes)
		(layer "F.Cu")
		(net "M_A_CPU0_SA_DQ<23>")
	)
	(gr_poly
		(pts
			(xy 330.419456 -238.659416) (xy 330.383134 -238.557816) (xy 330.192634 -238.557816) (xy 330.156312 -238.659416)
			(xy 330.156312 -238.710216) (xy 330.419456 -238.710216)
		)
		(stroke
			(width 0)
			(type solid)
		)
		(fill yes)
		(layer "F.Cu")
		(net "M_A_CPU0_SB_CB<0>")
	)
	(gr_poly
		(pts
			(xy 330.419456 -238.354616) (xy 330.383134 -238.253016) (xy 330.192634 -238.253016) (xy 330.156312 -238.354616)
			(xy 330.156312 -238.405416) (xy 330.419456 -238.405416)
		)
		(stroke
			(width 0)
			(type solid)
		)
		(fill yes)
		(layer "F.Cu")
		(net "M_A_CPU0_SB_CB<2>")
	)
	(gr_poly
		(pts
			(xy 330.419456 -238.049816) (xy 330.383134 -237.948216) (xy 330.192634 -237.948216) (xy 330.156312 -238.049816)
			(xy 330.156312 -238.100616) (xy 330.419456 -238.100616)
		)
		(stroke
			(width 0)
			(type solid)
		)
		(fill yes)
		(layer "F.Cu")
		(net "M_A_CPU0_SB_CB<1>")
	)
	(gr_poly
		(pts
			(xy 330.419456 -237.745016) (xy 330.383134 -237.643416) (xy 330.192634 -237.643416) (xy 330.156312 -237.745016)
			(xy 330.156312 -237.795816) (xy 330.419456 -237.795816)
		)
		(stroke
			(width 0)
			(type solid)
		)
		(fill yes)
		(layer "F.Cu")
		(net "M_A_CPU0_SB_CB<3>")
	)
	(gr_poly
		(pts
			(xy 330.41971 -230.834946) (xy 330.465938 -230.737664) (xy 330.331318 -230.60279) (xy 330.233782 -230.649018)
			(xy 330.197968 -230.685086) (xy 330.383896 -230.871014)
		)
		(stroke
			(width 0)
			(type solid)
		)
		(fill yes)
		(layer "F.Cu")
		(net "M_A_CPU0_SB_DQ<17>")
	)
	(gr_poly
		(pts
			(xy 330.42098 -273.698208) (xy 330.374752 -273.600926) (xy 330.338684 -273.564858) (xy 330.152756 -273.750786)
			(xy 330.188824 -273.7866) (xy 330.286106 -273.832828)
		)
		(stroke
			(width 0)
			(type solid)
		)
		(fill yes)
		(layer "F.Cu")
		(net "M_A_CPU0_SA_DQ<22>")
	)
	(gr_poly
		(pts
			(xy 330.43495 -227.830888) (xy 330.481178 -227.733352) (xy 330.346558 -227.598732) (xy 330.249022 -227.64496)
			(xy 330.213208 -227.681028) (xy 330.398882 -227.866702)
		)
		(stroke
			(width 0)
			(type solid)
		)
		(fill yes)
		(layer "F.Cu")
		(net "M_A_CPU0_SB_DQ<22>")
	)
	(gr_poly
		(pts
			(xy 330.435458 -276.058122) (xy 330.39939 -276.022308) (xy 330.302108 -275.97608) (xy 330.167234 -276.1107)
			(xy 330.213462 -276.208236) (xy 330.24953 -276.24405)
		)
		(stroke
			(width 0)
			(type solid)
		)
		(fill yes)
		(layer "F.Cu")
		(net "M_A_CPU0_SA_DQ<19>")
	)
	(gr_poly
		(pts
			(xy 330.444094 -226.977448) (xy 330.490322 -226.880166) (xy 330.355702 -226.745292) (xy 330.258166 -226.79152)
			(xy 330.222352 -226.827588) (xy 330.40828 -227.013516)
		)
		(stroke
			(width 0)
			(type solid)
		)
		(fill yes)
		(layer "F.Cu")
		(net "M_A_CPU0_SB_DQ<23>")
	)
	(gr_poly
		(pts
			(xy 330.444856 -279.21077) (xy 330.482194 -279.02408) (xy 330.389738 -278.968708) (xy 330.339954 -278.958548)
			(xy 330.288392 -279.216358) (xy 330.338176 -279.226518)
		)
		(stroke
			(width 0)
			(type solid)
		)
		(fill yes)
		(layer "F.Cu")
		(net "M_A_CPU0_SA_DQ<5>")
	)
	(gr_poly
		(pts
			(xy 330.446126 -276.91334) (xy 330.410312 -276.877272) (xy 330.312776 -276.831044) (xy 330.178156 -276.965664)
			(xy 330.224384 -277.0632) (xy 330.260452 -277.099014)
		)
		(stroke
			(width 0)
			(type solid)
		)
		(fill yes)
		(layer "F.Cu")
		(net "M_A_CPU0_SA_DQ<18>")
	)
	(gr_poly
		(pts
			(xy 330.46035 -266.946126) (xy 330.424282 -266.910312) (xy 330.327 -266.864084) (xy 330.192126 -266.998704)
			(xy 330.238608 -267.09624) (xy 330.274422 -267.132054)
		)
		(stroke
			(width 0)
			(type solid)
		)
		(fill yes)
		(layer "F.Cu")
		(net "M_A_CPU0_SA_DQ<31>")
	)
	(gr_poly
		(pts
			(xy 330.463398 -279.896316) (xy 330.41336 -279.88641) (xy 330.30668 -279.901904) (xy 330.269342 -280.088594)
			(xy 330.361798 -280.14422) (xy 330.411582 -280.154126)
		)
		(stroke
			(width 0)
			(type solid)
		)
		(fill yes)
		(layer "F.Cu")
		(net "M_A_CPU0_SA_DQ<6>")
	)
	(gr_poly
		(pts
			(xy 330.465938 -270.608552) (xy 330.41971 -270.511016) (xy 330.383642 -270.475202) (xy 330.197968 -270.660876)
			(xy 330.233782 -270.696944) (xy 330.331318 -270.743172)
		)
		(stroke
			(width 0)
			(type solid)
		)
		(fill yes)
		(layer "F.Cu")
		(net "M_A_CPU0_SA_DQ<27>")
	)
	(gr_poly
		(pts
			(xy 330.470002 -267.800074) (xy 330.434188 -267.764006) (xy 330.336652 -267.717778) (xy 330.202032 -267.852652)
			(xy 330.24826 -267.949934) (xy 330.284074 -267.986002)
		)
		(stroke
			(width 0)
			(type solid)
		)
		(fill yes)
		(layer "F.Cu")
		(net "M_A_CPU0_SA_DQ<30>")
	)
	(gr_poly
		(pts
			(xy 330.475336 -271.461992) (xy 330.429108 -271.36471) (xy 330.393294 -271.328642) (xy 330.207366 -271.51457)
			(xy 330.24318 -271.550638) (xy 330.340716 -271.596866)
		)
		(stroke
			(width 0)
			(type solid)
		)
		(fill yes)
		(layer "F.Cu")
		(net "M_A_CPU0_SA_DQ<26>")
	)
	(gr_poly
		(pts
			(xy 330.47559 -264.368534) (xy 330.429362 -264.270998) (xy 330.393294 -264.235184) (xy 330.20762 -264.420858)
			(xy 330.243434 -264.456926) (xy 330.34097 -264.503154)
		)
		(stroke
			(width 0)
			(type solid)
		)
		(fill yes)
		(layer "F.Cu")
		(net "M_A_CPU0_SA_CB<2>")
	)
	(gr_poly
		(pts
			(xy 330.49718 -295.298622) (xy 330.49718 -295.108122) (xy 330.39558 -295.0718) (xy 330.34478 -295.0718)
			(xy 330.34478 -295.33469) (xy 330.39558 -295.33469)
		)
		(stroke
			(width 0)
			(type solid)
		)
		(fill yes)
		(layer "F.Cu")
		(net "M_A_CPU0_SA_DQ<4>")
	)
	(gr_poly
		(pts
			(xy 330.49718 -294.701722) (xy 330.49718 -294.511222) (xy 330.39558 -294.4749) (xy 330.34478 -294.4749)
			(xy 330.34478 -294.73779) (xy 330.39558 -294.73779)
		)
		(stroke
			(width 0)
			(type solid)
		)
		(fill yes)
		(layer "F.Cu")
		(net "M_A_CPU0_SA_DQ<4>")
	)
	(gr_poly
		(pts
			(xy 330.49718 -294.104822) (xy 330.49718 -293.914322) (xy 330.39558 -293.878) (xy 330.34478 -293.878)
			(xy 330.34478 -294.14089) (xy 330.39558 -294.14089)
		)
		(stroke
			(width 0)
			(type solid)
		)
		(fill yes)
		(layer "F.Cu")
		(net "M_A_CPU0_SA_DQ<4>")
	)
	(gr_poly
		(pts
			(xy 330.49718 -293.507922) (xy 330.49718 -293.317422) (xy 330.39558 -293.2811) (xy 330.34478 -293.2811)
			(xy 330.34478 -293.54399) (xy 330.39558 -293.54399)
		)
		(stroke
			(width 0)
			(type solid)
		)
		(fill yes)
		(layer "F.Cu")
		(net "M_A_CPU0_SA_DQ<4>")
	)
	(gr_poly
		(pts
			(xy 330.49718 -292.911022) (xy 330.49718 -292.720522) (xy 330.39558 -292.6842) (xy 330.34478 -292.6842)
			(xy 330.34478 -292.94709) (xy 330.39558 -292.94709)
		)
		(stroke
			(width 0)
			(type solid)
		)
		(fill yes)
		(layer "F.Cu")
		(net "M_A_CPU0_SA_DQ<4>")
	)
	(gr_poly
		(pts
			(xy 330.49718 -292.314122) (xy 330.49718 -292.123622) (xy 330.39558 -292.0873) (xy 330.34478 -292.0873)
			(xy 330.34478 -292.35019) (xy 330.39558 -292.35019)
		)
		(stroke
			(width 0)
			(type solid)
		)
		(fill yes)
		(layer "F.Cu")
		(net "M_A_CPU0_SA_DQ<4>")
	)
	(gr_poly
		(pts
			(xy 330.49718 -291.717222) (xy 330.49718 -291.526722) (xy 330.39558 -291.4904) (xy 330.34478 -291.4904)
			(xy 330.34478 -291.75329) (xy 330.39558 -291.75329)
		)
		(stroke
			(width 0)
			(type solid)
		)
		(fill yes)
		(layer "F.Cu")
		(net "M_A_CPU0_SA_DQ<4>")
	)
	(gr_poly
		(pts
			(xy 330.49718 -291.120322) (xy 330.49718 -290.929822) (xy 330.39558 -290.8935) (xy 330.34478 -290.8935)
			(xy 330.34478 -291.15639) (xy 330.39558 -291.15639)
		)
		(stroke
			(width 0)
			(type solid)
		)
		(fill yes)
		(layer "F.Cu")
		(net "M_A_CPU0_SA_DQ<4>")
	)
	(gr_poly
		(pts
			(xy 330.49718 -290.523422) (xy 330.49718 -290.332922) (xy 330.39558 -290.2966) (xy 330.34478 -290.2966)
			(xy 330.34478 -290.55949) (xy 330.39558 -290.55949)
		)
		(stroke
			(width 0)
			(type solid)
		)
		(fill yes)
		(layer "F.Cu")
		(net "M_A_CPU0_SA_DQ<4>")
	)
	(gr_poly
		(pts
			(xy 330.49718 -289.926522) (xy 330.49718 -289.736022) (xy 330.39558 -289.6997) (xy 330.34478 -289.6997)
			(xy 330.34478 -289.96259) (xy 330.39558 -289.96259)
		)
		(stroke
			(width 0)
			(type solid)
		)
		(fill yes)
		(layer "F.Cu")
		(net "M_A_CPU0_SA_DQ<4>")
	)
	(gr_poly
		(pts
			(xy 330.49718 -289.329622) (xy 330.49718 -289.139122) (xy 330.39558 -289.1028) (xy 330.34478 -289.1028)
			(xy 330.34478 -289.36569) (xy 330.39558 -289.36569)
		)
		(stroke
			(width 0)
			(type solid)
		)
		(fill yes)
		(layer "F.Cu")
		(net "M_A_CPU0_SA_DQ<4>")
	)
	(gr_poly
		(pts
			(xy 330.49718 -288.732722) (xy 330.49718 -288.542222) (xy 330.39558 -288.5059) (xy 330.34478 -288.5059)
			(xy 330.34478 -288.76879) (xy 330.39558 -288.76879)
		)
		(stroke
			(width 0)
			(type solid)
		)
		(fill yes)
		(layer "F.Cu")
		(net "M_A_CPU0_SA_DQ<4>")
	)
	(gr_poly
		(pts
			(xy 330.49718 -288.135822) (xy 330.49718 -287.945322) (xy 330.39558 -287.909) (xy 330.34478 -287.909)
			(xy 330.34478 -288.17189) (xy 330.39558 -288.17189)
		)
		(stroke
			(width 0)
			(type solid)
		)
		(fill yes)
		(layer "F.Cu")
		(net "M_A_CPU0_SA_DQ<4>")
	)
	(gr_poly
		(pts
			(xy 330.49718 -287.538922) (xy 330.49718 -287.348422) (xy 330.39558 -287.3121) (xy 330.34478 -287.3121)
			(xy 330.34478 -287.57499) (xy 330.39558 -287.57499)
		)
		(stroke
			(width 0)
			(type solid)
		)
		(fill yes)
		(layer "F.Cu")
		(net "M_A_CPU0_SA_DQ<4>")
	)
	(gr_poly
		(pts
			(xy 330.49718 -286.942022) (xy 330.49718 -286.751522) (xy 330.39558 -286.7152) (xy 330.34478 -286.7152)
			(xy 330.34478 -286.97809) (xy 330.39558 -286.97809)
		)
		(stroke
			(width 0)
			(type solid)
		)
		(fill yes)
		(layer "F.Cu")
		(net "M_A_CPU0_SA_DQ<4>")
	)
	(gr_poly
		(pts
			(xy 330.49718 -286.345122) (xy 330.49718 -286.154622) (xy 330.39558 -286.1183) (xy 330.34478 -286.1183)
			(xy 330.34478 -286.38119) (xy 330.39558 -286.38119)
		)
		(stroke
			(width 0)
			(type solid)
		)
		(fill yes)
		(layer "F.Cu")
		(net "M_A_CPU0_SA_DQ<4>")
	)
	(gr_poly
		(pts
			(xy 330.49718 -285.748222) (xy 330.49718 -285.557722) (xy 330.39558 -285.5214) (xy 330.34478 -285.5214)
			(xy 330.34478 -285.78429) (xy 330.39558 -285.78429)
		)
		(stroke
			(width 0)
			(type solid)
		)
		(fill yes)
		(layer "F.Cu")
		(net "M_A_CPU0_SA_DQ<4>")
	)
	(gr_poly
		(pts
			(xy 330.49718 -285.151322) (xy 330.49718 -284.960822) (xy 330.39558 -284.9245) (xy 330.34478 -284.9245)
			(xy 330.34478 -285.18739) (xy 330.39558 -285.18739)
		)
		(stroke
			(width 0)
			(type solid)
		)
		(fill yes)
		(layer "F.Cu")
		(net "M_A_CPU0_SA_DQ<4>")
	)
	(gr_poly
		(pts
			(xy 330.49718 -284.554422) (xy 330.49718 -284.363922) (xy 330.39558 -284.3276) (xy 330.34478 -284.3276)
			(xy 330.34478 -284.59049) (xy 330.39558 -284.59049)
		)
		(stroke
			(width 0)
			(type solid)
		)
		(fill yes)
		(layer "F.Cu")
		(net "M_A_CPU0_SA_DQ<4>")
	)
	(gr_poly
		(pts
			(xy 330.49718 -283.957522) (xy 330.49718 -283.767022) (xy 330.39558 -283.7307) (xy 330.34478 -283.7307)
			(xy 330.34478 -283.99359) (xy 330.39558 -283.99359)
		)
		(stroke
			(width 0)
			(type solid)
		)
		(fill yes)
		(layer "F.Cu")
		(net "M_A_CPU0_SA_DQ<4>")
	)
	(gr_poly
		(pts
			(xy 330.49718 -283.360622) (xy 330.49718 -283.170122) (xy 330.39558 -283.1338) (xy 330.34478 -283.1338)
			(xy 330.34478 -283.39669) (xy 330.39558 -283.39669)
		)
		(stroke
			(width 0)
			(type solid)
		)
		(fill yes)
		(layer "F.Cu")
		(net "M_A_CPU0_SA_DQ<4>")
	)
	(gr_poly
		(pts
			(xy 330.49718 -282.763722) (xy 330.49718 -282.573222) (xy 330.39558 -282.5369) (xy 330.34478 -282.5369)
			(xy 330.34478 -282.79979) (xy 330.39558 -282.79979)
		)
		(stroke
			(width 0)
			(type solid)
		)
		(fill yes)
		(layer "F.Cu")
		(net "M_A_CPU0_SA_DQ<4>")
	)
	(gr_poly
		(pts
			(xy 330.509626 -280.441146) (xy 330.546964 -280.254456) (xy 330.454508 -280.19883) (xy 330.404724 -280.188924)
			(xy 330.353162 -280.446734) (xy 330.402946 -280.45664)
		)
		(stroke
			(width 0)
			(type solid)
		)
		(fill yes)
		(layer "F.Cu")
		(net "M_A_CPU0_SA_DQ<6>")
	)
	(gr_poly
		(pts
			(xy 330.512674 -259.719826) (xy 330.512674 -259.669026) (xy 330.249784 -259.669026) (xy 330.249784 -259.719826)
			(xy 330.285852 -259.821426) (xy 330.476352 -259.821426)
		)
		(stroke
			(width 0)
			(type solid)
		)
		(fill yes)
		(layer "F.Cu")
		(net "M_A_CPU0_SA_CS_N<0>")
	)
	(gr_poly
		(pts
			(xy 330.512674 -259.415026) (xy 330.512674 -259.364226) (xy 330.249784 -259.364226) (xy 330.249784 -259.415026)
			(xy 330.285852 -259.516626) (xy 330.476352 -259.516626)
		)
		(stroke
			(width 0)
			(type solid)
		)
		(fill yes)
		(layer "F.Cu")
		(net "M_A_CPU0_SA_CS_N<2>")
	)
	(gr_poly
		(pts
			(xy 330.512674 -259.110226) (xy 330.512674 -259.059426) (xy 330.249784 -259.059426) (xy 330.249784 -259.110226)
			(xy 330.285852 -259.211826) (xy 330.476352 -259.211826)
		)
		(stroke
			(width 0)
			(type solid)
		)
		(fill yes)
		(layer "F.Cu")
		(net "M_A_CPU0_SA_CS_N<3>")
	)
	(gr_poly
		(pts
			(xy 330.512674 -258.805426) (xy 330.512674 -258.754626) (xy 330.249784 -258.754626) (xy 330.249784 -258.805426)
			(xy 330.285852 -258.907026) (xy 330.476352 -258.907026)
		)
		(stroke
			(width 0)
			(type solid)
		)
		(fill yes)
		(layer "F.Cu")
		(net "M_A_CPU0_SA_CS_N<1>")
	)
	(gr_poly
		(pts
			(xy 330.512674 -258.500626) (xy 330.512674 -258.449826) (xy 330.249784 -258.449826) (xy 330.249784 -258.500626)
			(xy 330.285852 -258.602226) (xy 330.476352 -258.602226)
		)
		(stroke
			(width 0)
			(type solid)
		)
		(fill yes)
		(layer "F.Cu")
		(net "M_A_CPU0_SA_CA<0>")
	)
	(gr_poly
		(pts
			(xy 330.52385 -276.61997) (xy 330.477622 -276.522434) (xy 330.441554 -276.48662) (xy 330.255626 -276.672548)
			(xy 330.291694 -276.708362) (xy 330.388976 -276.75459)
		)
		(stroke
			(width 0)
			(type solid)
		)
		(fill yes)
		(layer "F.Cu")
		(net "M_A_CPU0_SA_DQ<17>")
	)
	(gr_poly
		(pts
			(xy 330.528168 -281.126692) (xy 330.478384 -281.116786) (xy 330.371704 -281.13228) (xy 330.334112 -281.31897)
			(xy 330.426822 -281.374342) (xy 330.476606 -281.384502)
		)
		(stroke
			(width 0)
			(type solid)
		)
		(fill yes)
		(layer "F.Cu")
		(net "M_A_CPU0_SA_DQ<4>")
	)
	(gr_poly
		(pts
			(xy 330.533248 -277.47341) (xy 330.486766 -277.375874) (xy 330.450952 -277.34006) (xy 330.265024 -277.525988)
			(xy 330.301092 -277.561802) (xy 330.398374 -277.60803)
		)
		(stroke
			(width 0)
			(type solid)
		)
		(fill yes)
		(layer "F.Cu")
		(net "M_A_CPU0_SA_DQ<16>")
	)
	(gr_poly
		(pts
			(xy 330.54036 -272.500344) (xy 330.504546 -272.464276) (xy 330.40701 -272.418048) (xy 330.27239 -272.552668)
			(xy 330.318618 -272.650204) (xy 330.354432 -272.686272)
		)
		(stroke
			(width 0)
			(type solid)
		)
		(fill yes)
		(layer "F.Cu")
		(net "M_A_CPU0_SA_DQ<23>")
	)
	(gr_poly
		(pts
			(xy 330.547218 -267.50645) (xy 330.50099 -267.408914) (xy 330.464922 -267.3731) (xy 330.279248 -267.558774)
			(xy 330.315062 -267.594842) (xy 330.412598 -267.64107)
		)
		(stroke
			(width 0)
			(type solid)
		)
		(fill yes)
		(layer "F.Cu")
		(net "M_A_CPU0_SA_DQ<29>")
	)
	(gr_poly
		(pts
			(xy 330.549758 -273.353784) (xy 330.513944 -273.31797) (xy 330.416408 -273.271742) (xy 330.281788 -273.406362)
			(xy 330.328016 -273.503898) (xy 330.36383 -273.539712)
		)
		(stroke
			(width 0)
			(type solid)
		)
		(fill yes)
		(layer "F.Cu")
		(net "M_A_CPU0_SA_DQ<22>")
	)
	(gr_poly
		(pts
			(xy 330.549758 -231.971342) (xy 330.585572 -231.935274) (xy 330.399644 -231.749346) (xy 330.36383 -231.785414)
			(xy 330.317602 -231.882696) (xy 330.452222 -232.01757)
		)
		(stroke
			(width 0)
			(type solid)
		)
		(fill yes)
		(layer "F.Cu")
		(net "M_A_CPU0_SB_DQ<16>")
	)
	(gr_poly
		(pts
			(xy 330.5556 -242.211098) (xy 330.519786 -242.17503) (xy 330.42225 -242.128802) (xy 330.28763 -242.263422)
			(xy 330.333858 -242.360958) (xy 330.369926 -242.396772)
		)
		(stroke
			(width 0)
			(type solid)
		)
		(fill yes)
		(layer "F.Cu")
		(net "M_A_CPU0_SB_CB<6>")
	)
	(gr_poly
		(pts
			(xy 330.55687 -268.360144) (xy 330.510642 -268.262608) (xy 330.474574 -268.226794) (xy 330.288646 -268.412722)
			(xy 330.324714 -268.448536) (xy 330.421996 -268.494764)
		)
		(stroke
			(width 0)
			(type solid)
		)
		(fill yes)
		(layer "F.Cu")
		(net "M_A_CPU0_SA_DQ<28>")
	)
	(gr_poly
		(pts
			(xy 330.558902 -231.117902) (xy 330.594716 -231.081834) (xy 330.409042 -230.89616) (xy 330.372974 -230.931974)
			(xy 330.326746 -231.02951) (xy 330.461366 -231.16413)
		)
		(stroke
			(width 0)
			(type solid)
		)
		(fill yes)
		(layer "F.Cu")
		(net "M_A_CPU0_SB_DQ<17>")
	)
	(gr_poly
		(pts
			(xy 330.574142 -228.113844) (xy 330.609956 -228.077776) (xy 330.424028 -227.891848) (xy 330.388214 -227.927916)
			(xy 330.341986 -228.025198) (xy 330.476606 -228.160072)
		)
		(stroke
			(width 0)
			(type solid)
		)
		(fill yes)
		(layer "F.Cu")
		(net "M_A_CPU0_SB_DQ<22>")
	)
	(gr_poly
		(pts
			(xy 330.574396 -281.671522) (xy 330.611988 -281.484832) (xy 330.519278 -281.429206) (xy 330.469494 -281.4193)
			(xy 330.417932 -281.67711) (xy 330.467716 -281.687016)
		)
		(stroke
			(width 0)
			(type solid)
		)
		(fill yes)
		(layer "F.Cu")
		(net "M_A_CPU0_SA_DQ<4>")
	)
	(gr_poly
		(pts
			(xy 330.580492 -279.3111) (xy 330.530708 -279.301194) (xy 330.424028 -279.316688) (xy 330.386436 -279.503378)
			(xy 330.479146 -279.55875) (xy 330.52893 -279.56891)
		)
		(stroke
			(width 0)
			(type solid)
		)
		(fill yes)
		(layer "F.Cu")
		(net "M_A_CPU0_SA_DQ<6>")
	)
	(gr_poly
		(pts
			(xy 330.583286 -227.260404) (xy 330.619354 -227.22459) (xy 330.433426 -227.038662) (xy 330.397358 -227.074476)
			(xy 330.35113 -227.172012) (xy 330.486004 -227.306632)
		)
		(stroke
			(width 0)
			(type solid)
		)
		(fill yes)
		(layer "F.Cu")
		(net "M_A_CPU0_SB_DQ<23>")
	)
	(gr_poly
		(pts
			(xy 330.594716 -270.264128) (xy 330.558902 -270.22806) (xy 330.461366 -270.181832) (xy 330.326746 -270.316706)
			(xy 330.372974 -270.413988) (xy 330.408788 -270.450056)
		)
		(stroke
			(width 0)
			(type solid)
		)
		(fill yes)
		(layer "F.Cu")
		(net "M_A_CPU0_SA_DQ<27>")
	)
	(gr_poly
		(pts
			(xy 330.604368 -271.117568) (xy 330.5683 -271.081754) (xy 330.471018 -271.035526) (xy 330.336144 -271.170146)
			(xy 330.382372 -271.267682) (xy 330.41844 -271.303496)
		)
		(stroke
			(width 0)
			(type solid)
		)
		(fill yes)
		(layer "F.Cu")
		(net "M_A_CPU0_SA_DQ<26>")
	)
	(gr_poly
		(pts
			(xy 330.626212 -231.47274) (xy 330.67244 -231.375204) (xy 330.537566 -231.240584) (xy 330.440284 -231.286812)
			(xy 330.404216 -231.322626) (xy 330.590144 -231.508554)
		)
		(stroke
			(width 0)
			(type solid)
		)
		(fill yes)
		(layer "F.Cu")
		(net "M_A_CPU0_SB_DQ<18>")
	)
	(gr_poly
		(pts
			(xy 330.62672 -279.85593) (xy 330.664312 -279.668986) (xy 330.571602 -279.613614) (xy 330.521818 -279.603708)
			(xy 330.470256 -279.861518) (xy 330.52004 -279.871424)
		)
		(stroke
			(width 0)
			(type solid)
		)
		(fill yes)
		(layer "F.Cu")
		(net "M_A_CPU0_SA_DQ<6>")
	)
	(gr_poly
		(pts
			(xy 330.627228 -273.060414) (xy 330.581 -272.963132) (xy 330.545186 -272.927064) (xy 330.359258 -273.112992)
			(xy 330.395072 -273.148806) (xy 330.492608 -273.195288)
		)
		(stroke
			(width 0)
			(type solid)
		)
		(fill yes)
		(layer "F.Cu")
		(net "M_A_CPU0_SA_DQ<21>")
	)
	(gr_poly
		(pts
			(xy 330.633324 -241.917728) (xy 330.587096 -241.820192) (xy 330.551028 -241.784124) (xy 330.3651 -241.970052)
			(xy 330.401168 -242.00612) (xy 330.49845 -242.052348)
		)
		(stroke
			(width 0)
			(type solid)
		)
		(fill yes)
		(layer "F.Cu")
		(net "M_A_CPU0_SB_CB<5>")
	)
	(gr_poly
		(pts
			(xy 330.635356 -230.6193) (xy 330.681584 -230.522018) (xy 330.546964 -230.387144) (xy 330.449428 -230.433372)
			(xy 330.413614 -230.46944) (xy 330.599542 -230.655368)
		)
		(stroke
			(width 0)
			(type solid)
		)
		(fill yes)
		(layer "F.Cu")
		(net "M_A_CPU0_SB_DQ<19>")
	)
	(gr_poly
		(pts
			(xy 330.637388 -273.914616) (xy 330.590906 -273.817334) (xy 330.555092 -273.781266) (xy 330.369164 -273.967194)
			(xy 330.405232 -274.003262) (xy 330.502514 -274.04949)
		)
		(stroke
			(width 0)
			(type solid)
		)
		(fill yes)
		(layer "F.Cu")
		(net "M_A_CPU0_SA_DQ<20>")
	)
	(gr_poly
		(pts
			(xy 330.641198 -228.468682) (xy 330.687426 -228.3714) (xy 330.552806 -228.236526) (xy 330.45527 -228.282754)
			(xy 330.419456 -228.318822) (xy 330.605384 -228.50475)
		)
		(stroke
			(width 0)
			(type solid)
		)
		(fill yes)
		(layer "F.Cu")
		(net "M_A_CPU0_SB_DQ<20>")
	)
	(gr_poly
		(pts
			(xy 330.645262 -280.541476) (xy 330.595478 -280.531316) (xy 330.488798 -280.54681) (xy 330.45146 -280.733754)
			(xy 330.543916 -280.789126) (xy 330.5937 -280.799032)
		)
		(stroke
			(width 0)
			(type solid)
		)
		(fill yes)
		(layer "F.Cu")
		(net "M_A_CPU0_SA_DQ<4>")
	)
	(gr_poly
		(pts
			(xy 330.650596 -227.615242) (xy 330.696824 -227.517706) (xy 330.562204 -227.383086) (xy 330.464668 -227.429314)
			(xy 330.428854 -227.465382) (xy 330.614528 -227.651056)
		)
		(stroke
			(width 0)
			(type solid)
		)
		(fill yes)
		(layer "F.Cu")
		(net "M_A_CPU0_SB_DQ<21>")
	)
	(gr_poly
		(pts
			(xy 330.652628 -276.275546) (xy 330.616814 -276.239732) (xy 330.519278 -276.19325) (xy 330.384658 -276.328124)
			(xy 330.430886 -276.425406) (xy 330.4667 -276.461474)
		)
		(stroke
			(width 0)
			(type solid)
		)
		(fill yes)
		(layer "F.Cu")
		(net "M_A_CPU0_SA_DQ<17>")
	)
	(gr_poly
		(pts
			(xy 330.662026 -277.128986) (xy 330.625958 -277.093172) (xy 330.528676 -277.046944) (xy 330.394056 -277.181564)
			(xy 330.440284 -277.2791) (xy 330.476098 -277.314914)
		)
		(stroke
			(width 0)
			(type solid)
		)
		(fill yes)
		(layer "F.Cu")
		(net "M_A_CPU0_SA_DQ<16>")
	)
	(gr_poly
		(pts
			(xy 330.675996 -267.162026) (xy 330.640182 -267.125958) (xy 330.542646 -267.07973) (xy 330.408026 -267.21435)
			(xy 330.454254 -267.311886) (xy 330.490068 -267.347954)
		)
		(stroke
			(width 0)
			(type solid)
		)
		(fill yes)
		(layer "F.Cu")
		(net "M_A_CPU0_SA_DQ<29>")
	)
	(gr_poly
		(pts
			(xy 330.681838 -270.824452) (xy 330.63561 -270.726916) (xy 330.599542 -270.691102) (xy 330.413868 -270.876776)
			(xy 330.449682 -270.912844) (xy 330.547218 -270.959072)
		)
		(stroke
			(width 0)
			(type solid)
		)
		(fill yes)
		(layer "F.Cu")
		(net "M_A_CPU0_SA_DQ<25>")
	)
	(gr_poly
		(pts
			(xy 330.685648 -268.01572) (xy 330.649834 -267.979652) (xy 330.552298 -267.933424) (xy 330.417678 -268.068298)
			(xy 330.463906 -268.16558) (xy 330.49972 -268.201648)
		)
		(stroke
			(width 0)
			(type solid)
		)
		(fill yes)
		(layer "F.Cu")
		(net "M_A_CPU0_SA_DQ<28>")
	)
	(gr_poly
		(pts
			(xy 330.690982 -271.677638) (xy 330.644754 -271.580356) (xy 330.60894 -271.544288) (xy 330.423012 -271.730216)
			(xy 330.458826 -271.766284) (xy 330.556362 -271.812512)
		)
		(stroke
			(width 0)
			(type solid)
		)
		(fill yes)
		(layer "F.Cu")
		(net "M_A_CPU0_SA_DQ<24>")
	)
	(gr_poly
		(pts
			(xy 330.691744 -281.086306) (xy 330.729082 -280.899362) (xy 330.636626 -280.84399) (xy 330.586588 -280.834084)
			(xy 330.535026 -281.091894) (xy 330.58481 -281.1018)
		)
		(stroke
			(width 0)
			(type solid)
		)
		(fill yes)
		(layer "F.Cu")
		(net "M_A_CPU0_SA_DQ<4>")
	)
	(gr_poly
		(pts
			(xy 330.717652 -238.761016) (xy 330.717652 -238.710216) (xy 330.455016 -238.710216) (xy 330.455016 -238.761016)
			(xy 330.491084 -238.862616) (xy 330.681584 -238.862616)
		)
		(stroke
			(width 0)
			(type solid)
		)
		(fill yes)
		(layer "F.Cu")
		(net "M_A_CPU0_SB_CB<0>")
	)
	(gr_poly
		(pts
			(xy 330.717652 -238.456216) (xy 330.717652 -238.405416) (xy 330.455016 -238.405416) (xy 330.455016 -238.456216)
			(xy 330.491084 -238.557816) (xy 330.681584 -238.557816)
		)
		(stroke
			(width 0)
			(type solid)
		)
		(fill yes)
		(layer "F.Cu")
		(net "M_A_CPU0_SB_CB<2>")
	)
	(gr_poly
		(pts
			(xy 330.717652 -238.151416) (xy 330.717652 -238.100616) (xy 330.455016 -238.100616) (xy 330.455016 -238.151416)
			(xy 330.491084 -238.253016) (xy 330.681584 -238.253016)
		)
		(stroke
			(width 0)
			(type solid)
		)
		(fill yes)
		(layer "F.Cu")
		(net "M_A_CPU0_SB_CB<1>")
	)
	(gr_poly
		(pts
			(xy 330.717652 -237.846616) (xy 330.717652 -237.795816) (xy 330.455016 -237.795816) (xy 330.455016 -237.846616)
			(xy 330.491084 -237.948216) (xy 330.681584 -237.948216)
		)
		(stroke
			(width 0)
			(type solid)
		)
		(fill yes)
		(layer "F.Cu")
		(net "M_A_CPU0_SB_CB<3>")
	)
	(gr_poly
		(pts
			(xy 330.728574 -275.980652) (xy 330.682346 -275.883116) (xy 330.646278 -275.847302) (xy 330.460604 -276.032976)
			(xy 330.496418 -276.069044) (xy 330.593954 -276.115272)
		)
		(stroke
			(width 0)
			(type solid)
		)
		(fill yes)
		(layer "F.Cu")
		(net "M_A_CPU0_SA_DQ<19>")
	)
	(gr_poly
		(pts
			(xy 330.739496 -276.835616) (xy 330.693268 -276.73808) (xy 330.6572 -276.702266) (xy 330.471272 -276.888194)
			(xy 330.50734 -276.924008) (xy 330.604622 -276.970236)
		)
		(stroke
			(width 0)
			(type solid)
		)
		(fill yes)
		(layer "F.Cu")
		(net "M_A_CPU0_SA_DQ<18>")
	)
	(gr_poly
		(pts
			(xy 330.75626 -272.71599) (xy 330.720192 -272.680176) (xy 330.62291 -272.633948) (xy 330.488036 -272.768568)
			(xy 330.534264 -272.866104) (xy 330.570332 -272.901918)
		)
		(stroke
			(width 0)
			(type solid)
		)
		(fill yes)
		(layer "F.Cu")
		(net "M_A_CPU0_SA_DQ<21>")
	)
	(gr_poly
		(pts
			(xy 330.762102 -241.57305) (xy 330.726034 -241.537236) (xy 330.628498 -241.491008) (xy 330.493878 -241.625628)
			(xy 330.540106 -241.723164) (xy 330.576174 -241.758978)
		)
		(stroke
			(width 0)
			(type solid)
		)
		(fill yes)
		(layer "F.Cu")
		(net "M_A_CPU0_SB_CB<5>")
	)
	(gr_poly
		(pts
			(xy 330.762356 -279.956006) (xy 330.712572 -279.9461) (xy 330.605892 -279.961594) (xy 330.568554 -280.148538)
			(xy 330.66101 -280.20391) (xy 330.710794 -280.213816)
		)
		(stroke
			(width 0)
			(type solid)
		)
		(fill yes)
		(layer "F.Cu")
		(net "M_A_CPU0_SA_DQ<4>")
	)
	(gr_poly
		(pts
			(xy 330.763118 -267.72235) (xy 330.71689 -267.624814) (xy 330.681076 -267.589) (xy 330.495148 -267.774928)
			(xy 330.531216 -267.810742) (xy 330.628498 -267.85697)
		)
		(stroke
			(width 0)
			(type solid)
		)
		(fill yes)
		(layer "F.Cu")
		(net "M_A_CPU0_SA_DQ<30>")
	)
	(gr_poly
		(pts
			(xy 330.765404 -231.755696) (xy 330.801218 -231.719628) (xy 330.61529 -231.5337) (xy 330.579476 -231.569768)
			(xy 330.533248 -231.66705) (xy 330.667868 -231.801924)
		)
		(stroke
			(width 0)
			(type solid)
		)
		(fill yes)
		(layer "F.Cu")
		(net "M_A_CPU0_SB_DQ<18>")
	)
	(gr_poly
		(pts
			(xy 330.766166 -273.570446) (xy 330.730352 -273.534378) (xy 330.632816 -273.48815) (xy 330.498196 -273.62277)
			(xy 330.544424 -273.720306) (xy 330.580238 -273.75612)
		)
		(stroke
			(width 0)
			(type solid)
		)
		(fill yes)
		(layer "F.Cu")
		(net "M_A_CPU0_SA_DQ<20>")
	)
	(gr_poly
		(pts
			(xy 330.7715 -242.426744) (xy 330.735432 -242.39093) (xy 330.63815 -242.344702) (xy 330.50353 -242.479322)
			(xy 330.549758 -242.576858) (xy 330.585572 -242.612672)
		)
		(stroke
			(width 0)
			(type solid)
		)
		(fill yes)
		(layer "F.Cu")
		(net "M_A_CPU0_SB_CB<4>")
	)
	(gr_poly
		(pts
			(xy 330.774548 -230.902256) (xy 330.810362 -230.866188) (xy 330.624688 -230.680514) (xy 330.58862 -230.716328)
			(xy 330.542392 -230.813864) (xy 330.677012 -230.948484)
		)
		(stroke
			(width 0)
			(type solid)
		)
		(fill yes)
		(layer "F.Cu")
		(net "M_A_CPU0_SB_DQ<19>")
	)
	(gr_poly
		(pts
			(xy 330.78039 -228.751638) (xy 330.816204 -228.71557) (xy 330.63053 -228.529896) (xy 330.594462 -228.56571)
			(xy 330.548234 -228.663246) (xy 330.682854 -228.797866)
		)
		(stroke
			(width 0)
			(type solid)
		)
		(fill yes)
		(layer "F.Cu")
		(net "M_A_CPU0_SB_DQ<20>")
	)
	(gr_poly
		(pts
			(xy 330.789788 -227.898198) (xy 330.825602 -227.86213) (xy 330.639674 -227.676202) (xy 330.60386 -227.71227)
			(xy 330.557632 -227.809552) (xy 330.692252 -227.944426)
		)
		(stroke
			(width 0)
			(type solid)
		)
		(fill yes)
		(layer "F.Cu")
		(net "M_A_CPU0_SB_DQ<21>")
	)
	(gr_poly
		(pts
			(xy 330.808838 -280.500836) (xy 330.846176 -280.314146) (xy 330.75372 -280.258774) (xy 330.703936 -280.248614)
			(xy 330.652374 -280.506424) (xy 330.702158 -280.516584)
		)
		(stroke
			(width 0)
			(type solid)
		)
		(fill yes)
		(layer "F.Cu")
		(net "M_A_CPU0_SA_DQ<4>")
	)
	(gr_poly
		(pts
			(xy 330.810616 -270.480028) (xy 330.774802 -270.44396) (xy 330.677266 -270.397732) (xy 330.542646 -270.532606)
			(xy 330.588874 -270.629888) (xy 330.624688 -270.665956)
		)
		(stroke
			(width 0)
			(type solid)
		)
		(fill yes)
		(layer "F.Cu")
		(net "M_A_CPU0_SA_DQ<25>")
	)
	(gr_poly
		(pts
			(xy 330.811124 -259.618226) (xy 330.775056 -259.516626) (xy 330.584556 -259.516626) (xy 330.548234 -259.618226)
			(xy 330.548234 -259.669026) (xy 330.811124 -259.669026)
		)
		(stroke
			(width 0)
			(type solid)
		)
		(fill yes)
		(layer "F.Cu")
		(net "M_A_CPU0_SA_CS_N<0>")
	)
	(gr_poly
		(pts
			(xy 330.811124 -259.313426) (xy 330.775056 -259.211826) (xy 330.584556 -259.211826) (xy 330.548234 -259.313426)
			(xy 330.548234 -259.364226) (xy 330.811124 -259.364226)
		)
		(stroke
			(width 0)
			(type solid)
		)
		(fill yes)
		(layer "F.Cu")
		(net "M_A_CPU0_SA_CS_N<2>")
	)
	(gr_poly
		(pts
			(xy 330.811124 -259.008626) (xy 330.775056 -258.907026) (xy 330.584556 -258.907026) (xy 330.548234 -259.008626)
			(xy 330.548234 -259.059426) (xy 330.811124 -259.059426)
		)
		(stroke
			(width 0)
			(type solid)
		)
		(fill yes)
		(layer "F.Cu")
		(net "M_A_CPU0_SA_CS_N<3>")
	)
	(gr_poly
		(pts
			(xy 330.820014 -271.333214) (xy 330.783946 -271.2974) (xy 330.686664 -271.251172) (xy 330.55179 -271.385792)
			(xy 330.598018 -271.483328) (xy 330.634086 -271.519142)
		)
		(stroke
			(width 0)
			(type solid)
		)
		(fill yes)
		(layer "F.Cu")
		(net "M_A_CPU0_SA_DQ<24>")
	)
	(gr_poly
		(pts
			(xy 330.83246 -232.110534) (xy 330.878688 -232.012998) (xy 330.744068 -231.878378) (xy 330.646532 -231.924606)
			(xy 330.610718 -231.96042) (xy 330.796646 -232.146348)
		)
		(stroke
			(width 0)
			(type solid)
		)
		(fill yes)
		(layer "F.Cu")
		(net "M_A_CPU0_SB_DQ<16>")
	)
	(gr_poly
		(pts
			(xy 330.83373 -272.42262) (xy 330.787502 -272.325084) (xy 330.751434 -272.28927) (xy 330.565506 -272.475198)
			(xy 330.601574 -272.511012) (xy 330.698856 -272.55724)
		)
		(stroke
			(width 0)
			(type solid)
		)
		(fill yes)
		(layer "F.Cu")
		(net "M_A_CPU0_SA_DQ<23>")
	)
	(gr_poly
		(pts
			(xy 330.839572 -241.27968) (xy 330.793344 -241.182144) (xy 330.757276 -241.14633) (xy 330.571602 -241.332004)
			(xy 330.607416 -241.368072) (xy 330.704952 -241.4143)
		)
		(stroke
			(width 0)
			(type solid)
		)
		(fill yes)
		(layer "F.Cu")
		(net "M_A_CPU0_SB_CB<7>")
	)
	(gr_poly
		(pts
			(xy 330.841858 -231.257094) (xy 330.888086 -231.159558) (xy 330.753212 -231.024938) (xy 330.65593 -231.071166)
			(xy 330.619862 -231.10698) (xy 330.80579 -231.292908)
		)
		(stroke
			(width 0)
			(type solid)
		)
		(fill yes)
		(layer "F.Cu")
		(net "M_A_CPU0_SB_DQ<17>")
	)
	(gr_poly
		(pts
			(xy 330.842874 -273.276314) (xy 330.796646 -273.178778) (xy 330.760832 -273.142964) (xy 330.574904 -273.328638)
			(xy 330.610718 -273.364706) (xy 330.708254 -273.410934)
		)
		(stroke
			(width 0)
			(type solid)
		)
		(fill yes)
		(layer "F.Cu")
		(net "M_A_CPU0_SA_DQ<22>")
	)
	(gr_poly
		(pts
			(xy 330.84897 -242.133374) (xy 330.802742 -242.035838) (xy 330.766674 -242.000024) (xy 330.580746 -242.185952)
			(xy 330.616814 -242.221766) (xy 330.714096 -242.267994)
		)
		(stroke
			(width 0)
			(type solid)
		)
		(fill yes)
		(layer "F.Cu")
		(net "M_A_CPU0_SB_CB<6>")
	)
	(gr_poly
		(pts
			(xy 330.857352 -275.636228) (xy 330.821538 -275.60016) (xy 330.724002 -275.553932) (xy 330.589382 -275.688806)
			(xy 330.63561 -275.786088) (xy 330.671424 -275.822156)
		)
		(stroke
			(width 0)
			(type solid)
		)
		(fill yes)
		(layer "F.Cu")
		(net "M_A_CPU0_SA_DQ<19>")
	)
	(gr_poly
		(pts
			(xy 330.866242 -227.399596) (xy 330.91247 -227.30206) (xy 330.77785 -227.16744) (xy 330.680314 -227.213668)
			(xy 330.6445 -227.249736) (xy 330.830174 -227.43541)
		)
		(stroke
			(width 0)
			(type solid)
		)
		(fill yes)
		(layer "F.Cu")
		(net "M_A_CPU0_SB_DQ<23>")
	)
	(gr_poly
		(pts
			(xy 330.868274 -276.491192) (xy 330.83246 -276.455378) (xy 330.734924 -276.408896) (xy 330.600304 -276.54377)
			(xy 330.646532 -276.641052) (xy 330.682346 -276.67712)
		)
		(stroke
			(width 0)
			(type solid)
		)
		(fill yes)
		(layer "F.Cu")
		(net "M_A_CPU0_SA_DQ<18>")
	)
	(gr_poly
		(pts
			(xy 330.888086 -270.186404) (xy 330.841858 -270.088868) (xy 330.80579 -270.053054) (xy 330.619862 -270.238982)
			(xy 330.65593 -270.274796) (xy 330.753212 -270.321024)
		)
		(stroke
			(width 0)
			(type solid)
		)
		(fill yes)
		(layer "F.Cu")
		(net "M_A_CPU0_SA_DQ<27>")
	)
	(gr_poly
		(pts
			(xy 330.89215 -267.377926) (xy 330.856082 -267.342112) (xy 330.7588 -267.295884) (xy 330.623926 -267.430504)
			(xy 330.670408 -267.52804) (xy 330.706222 -267.563854)
		)
		(stroke
			(width 0)
			(type solid)
		)
		(fill yes)
		(layer "F.Cu")
		(net "M_A_CPU0_SA_DQ<30>")
	)
	(gr_poly
		(pts
			(xy 330.897484 -271.040098) (xy 330.851256 -270.942562) (xy 330.815188 -270.906748) (xy 330.629514 -271.092422)
			(xy 330.665328 -271.12849) (xy 330.762864 -271.174718)
		)
		(stroke
			(width 0)
			(type solid)
		)
		(fill yes)
		(layer "F.Cu")
		(net "M_A_CPU0_SA_DQ<26>")
	)
	(gr_poly
		(pts
			(xy 330.945744 -276.197822) (xy 330.899516 -276.100286) (xy 330.863702 -276.064472) (xy 330.677774 -276.2504)
			(xy 330.713588 -276.286214) (xy 330.811124 -276.332442)
		)
		(stroke
			(width 0)
			(type solid)
		)
		(fill yes)
		(layer "F.Cu")
		(net "M_A_CPU0_SA_DQ<17>")
	)
	(gr_poly
		(pts
			(xy 330.955142 -277.051262) (xy 330.908914 -276.95398) (xy 330.8731 -276.917912) (xy 330.687172 -277.10384)
			(xy 330.722986 -277.139908) (xy 330.820522 -277.186136)
		)
		(stroke
			(width 0)
			(type solid)
		)
		(fill yes)
		(layer "F.Cu")
		(net "M_A_CPU0_SA_DQ<16>")
	)
	(gr_poly
		(pts
			(xy 330.962508 -272.078196) (xy 330.926694 -272.042382) (xy 330.829158 -271.996154) (xy 330.694538 -272.130774)
			(xy 330.740766 -272.22831) (xy 330.77658 -272.264124)
		)
		(stroke
			(width 0)
			(type solid)
		)
		(fill yes)
		(layer "F.Cu")
		(net "M_A_CPU0_SA_DQ<23>")
	)
	(gr_poly
		(pts
			(xy 330.977748 -241.78895) (xy 330.941934 -241.753136) (xy 330.844398 -241.706654) (xy 330.709778 -241.841528)
			(xy 330.756006 -241.93881) (xy 330.79182 -241.974878)
		)
		(stroke
			(width 0)
			(type solid)
		)
		(fill yes)
		(layer "F.Cu")
		(net "M_A_CPU0_SB_CB<6>")
	)
	(gr_poly
		(pts
			(xy 330.978764 -267.937996) (xy 330.932536 -267.84046) (xy 330.896722 -267.804646) (xy 330.710794 -267.990574)
			(xy 330.746862 -268.026388) (xy 330.844144 -268.072616)
		)
		(stroke
			(width 0)
			(type solid)
		)
		(fill yes)
		(layer "F.Cu")
		(net "M_A_CPU0_SA_DQ<28>")
	)
	(gr_poly
		(pts
			(xy 330.98105 -231.54005) (xy 331.016864 -231.503982) (xy 330.830936 -231.318054) (xy 330.795122 -231.354122)
			(xy 330.748894 -231.451404) (xy 330.883514 -231.586278)
		)
		(stroke
			(width 0)
			(type solid)
		)
		(fill yes)
		(layer "F.Cu")
		(net "M_A_CPU0_SB_DQ<17>")
	)
	(gr_poly
		(pts
			(xy 331.005434 -227.682552) (xy 331.041248 -227.646484) (xy 330.85532 -227.460556) (xy 330.819506 -227.496624)
			(xy 330.773278 -227.593906) (xy 330.907898 -227.72878)
		)
		(stroke
			(width 0)
			(type solid)
		)
		(fill yes)
		(layer "F.Cu")
		(net "M_A_CPU0_SB_DQ<23>")
	)
	(gr_poly
		(pts
			(xy 331.016356 -237.745016) (xy 330.980034 -237.643416) (xy 330.789534 -237.643416) (xy 330.753212 -237.745016)
			(xy 330.753212 -237.795816) (xy 331.016356 -237.795816)
		)
		(stroke
			(width 0)
			(type solid)
		)
		(fill yes)
		(layer "F.Cu")
		(net "M_A_CPU0_SB_CB<3>")
	)
	(gr_poly
		(pts
			(xy 331.026262 -270.695674) (xy 330.990448 -270.659606) (xy 330.892912 -270.613378) (xy 330.758292 -270.748252)
			(xy 330.80452 -270.845534) (xy 330.840334 -270.881602)
		)
		(stroke
			(width 0)
			(type solid)
		)
		(fill yes)
		(layer "F.Cu")
		(net "M_A_CPU0_SA_DQ<26>")
	)
	(gr_poly
		(pts
			(xy 331.049376 -272.63852) (xy 331.003148 -272.540984) (xy 330.967334 -272.50517) (xy 330.781406 -272.690844)
			(xy 330.81722 -272.726912) (xy 330.914756 -272.77314)
		)
		(stroke
			(width 0)
			(type solid)
		)
		(fill yes)
		(layer "F.Cu")
		(net "M_A_CPU0_SA_DQ<21>")
	)
	(gr_poly
		(pts
			(xy 331.055218 -241.49558) (xy 331.00899 -241.398044) (xy 330.972922 -241.36223) (xy 330.787248 -241.547904)
			(xy 330.823062 -241.583972) (xy 330.920598 -241.6302)
		)
		(stroke
			(width 0)
			(type solid)
		)
		(fill yes)
		(layer "F.Cu")
		(net "M_A_CPU0_SB_CB<5>")
	)
	(gr_poly
		(pts
			(xy 331.057504 -231.041448) (xy 331.103732 -230.943912) (xy 330.968858 -230.809292) (xy 330.871576 -230.85552)
			(xy 330.835508 -230.891334) (xy 331.021436 -231.077262)
		)
		(stroke
			(width 0)
			(type solid)
		)
		(fill yes)
		(layer "F.Cu")
		(net "M_A_CPU0_SB_DQ<19>")
	)
	(gr_poly
		(pts
			(xy 331.059282 -273.492722) (xy 331.013054 -273.395186) (xy 330.97724 -273.359372) (xy 330.791312 -273.5453)
			(xy 330.827126 -273.581114) (xy 330.924662 -273.627342)
		)
		(stroke
			(width 0)
			(type solid)
		)
		(fill yes)
		(layer "F.Cu")
		(net "M_A_CPU0_SA_DQ<20>")
	)
	(gr_poly
		(pts
			(xy 331.064616 -242.34902) (xy 331.018388 -242.251738) (xy 330.982574 -242.21567) (xy 330.796646 -242.401598)
			(xy 330.83246 -242.437666) (xy 330.929996 -242.483894)
		)
		(stroke
			(width 0)
			(type solid)
		)
		(fill yes)
		(layer "F.Cu")
		(net "M_A_CPU0_SB_CB<4>")
	)
	(gr_poly
		(pts
			(xy 331.072744 -228.03739) (xy 331.118972 -227.939854) (xy 330.984098 -227.805234) (xy 330.886816 -227.851462)
			(xy 330.850748 -227.887276) (xy 331.036676 -228.073204)
		)
		(stroke
			(width 0)
			(type solid)
		)
		(fill yes)
		(layer "F.Cu")
		(net "M_A_CPU0_SB_DQ<21>")
	)
	(gr_poly
		(pts
			(xy 331.074776 -275.853398) (xy 331.038708 -275.817584) (xy 330.941426 -275.771356) (xy 330.806552 -275.905976)
			(xy 330.853034 -276.003512) (xy 330.888848 -276.039326)
		)
		(stroke
			(width 0)
			(type solid)
		)
		(fill yes)
		(layer "F.Cu")
		(net "M_A_CPU0_SA_DQ<17>")
	)
	(gr_poly
		(pts
			(xy 331.084174 -276.706838) (xy 331.048106 -276.671024) (xy 330.950824 -276.624796) (xy 330.81595 -276.759416)
			(xy 330.862178 -276.856952) (xy 330.898246 -276.892766)
		)
		(stroke
			(width 0)
			(type solid)
		)
		(fill yes)
		(layer "F.Cu")
		(net "M_A_CPU0_SA_DQ<16>")
	)
	(gr_poly
		(pts
			(xy 331.103986 -270.402304) (xy 331.057758 -270.304768) (xy 331.02169 -270.268954) (xy 330.835762 -270.454882)
			(xy 330.87183 -270.490696) (xy 330.969112 -270.536924)
		)
		(stroke
			(width 0)
			(type solid)
		)
		(fill yes)
		(layer "F.Cu")
		(net "M_A_CPU0_SA_DQ<25>")
	)
	(gr_poly
		(pts
			(xy 331.107796 -267.593572) (xy 331.071728 -267.557758) (xy 330.974446 -267.51153) (xy 330.839572 -267.64615)
			(xy 330.886054 -267.743686) (xy 330.921868 -267.7795)
		)
		(stroke
			(width 0)
			(type solid)
		)
		(fill yes)
		(layer "F.Cu")
		(net "M_A_CPU0_SA_DQ<28>")
	)
	(gr_poly
		(pts
			(xy 331.109574 -259.719826) (xy 331.109574 -259.669026) (xy 330.846684 -259.669026) (xy 330.846684 -259.719826)
			(xy 330.882752 -259.821426) (xy 331.073252 -259.821426)
		)
		(stroke
			(width 0)
			(type solid)
		)
		(fill yes)
		(layer "F.Cu")
		(net "M_A_CPU0_SA_CS_N<0>")
	)
	(gr_poly
		(pts
			(xy 331.11313 -271.255744) (xy 331.066902 -271.158208) (xy 331.030834 -271.122394) (xy 330.84516 -271.308068)
			(xy 330.880974 -271.344136) (xy 330.97851 -271.390364)
		)
		(stroke
			(width 0)
			(type solid)
		)
		(fill yes)
		(layer "F.Cu")
		(net "M_A_CPU0_SA_DQ<24>")
	)
	(gr_poly
		(pts
			(xy 331.150722 -275.558504) (xy 331.104494 -275.460968) (xy 331.068426 -275.425154) (xy 330.882498 -275.611082)
			(xy 330.918566 -275.646896) (xy 331.015848 -275.693124)
		)
		(stroke
			(width 0)
			(type solid)
		)
		(fill yes)
		(layer "F.Cu")
		(net "M_A_CPU0_SA_DQ<19>")
	)
	(gr_poly
		(pts
			(xy 331.16139 -276.413468) (xy 331.115162 -276.315932) (xy 331.079348 -276.280118) (xy 330.89342 -276.466046)
			(xy 330.929234 -276.50186) (xy 331.02677 -276.548088)
		)
		(stroke
			(width 0)
			(type solid)
		)
		(fill yes)
		(layer "F.Cu")
		(net "M_A_CPU0_SA_DQ<18>")
	)
	(gr_poly
		(pts
			(xy 331.178408 -272.294096) (xy 331.14234 -272.258282) (xy 331.045058 -272.2118) (xy 330.910184 -272.346674)
			(xy 330.956412 -272.443956) (xy 330.99248 -272.480024)
		)
		(stroke
			(width 0)
			(type solid)
		)
		(fill yes)
		(layer "F.Cu")
		(net "M_A_CPU0_SA_DQ<21>")
	)
	(gr_poly
		(pts
			(xy 331.193648 -242.004596) (xy 331.15758 -241.968782) (xy 331.060298 -241.922554) (xy 330.925424 -242.057174)
			(xy 330.971652 -242.15471) (xy 331.00772 -242.190524)
		)
		(stroke
			(width 0)
			(type solid)
		)
		(fill yes)
		(layer "F.Cu")
		(net "M_A_CPU0_SB_CB<4>")
	)
	(gr_poly
		(pts
			(xy 331.211936 -228.320092) (xy 331.24775 -228.284278) (xy 331.061822 -228.09835) (xy 331.026008 -228.134418)
			(xy 330.97978 -228.2317) (xy 331.1144 -228.36632)
		)
		(stroke
			(width 0)
			(type solid)
		)
		(fill yes)
		(layer "F.Cu")
		(net "M_A_CPU0_SB_DQ<21>")
	)
	(gr_poly
		(pts
			(xy 331.232764 -270.05788) (xy 331.19695 -270.022066) (xy 331.099414 -269.975838) (xy 330.964794 -270.110458)
			(xy 331.011022 -270.207994) (xy 331.046836 -270.243808)
		)
		(stroke
			(width 0)
			(type solid)
		)
		(fill yes)
		(layer "F.Cu")
		(net "M_A_CPU0_SA_DQ<25>")
	)
	(gr_poly
		(pts
			(xy 331.241908 -270.91132) (xy 331.206094 -270.875252) (xy 331.108558 -270.829024) (xy 330.973938 -270.963898)
			(xy 331.020166 -271.06118) (xy 331.05598 -271.097248)
		)
		(stroke
			(width 0)
			(type solid)
		)
		(fill yes)
		(layer "F.Cu")
		(net "M_A_CPU0_SA_DQ<24>")
	)
	(gr_poly
		(pts
			(xy 331.2795 -275.21408) (xy 331.243686 -275.178266) (xy 331.14615 -275.132038) (xy 331.01153 -275.266658)
			(xy 331.057758 -275.36394) (xy 331.093572 -275.400008)
		)
		(stroke
			(width 0)
			(type solid)
		)
		(fill yes)
		(layer "F.Cu")
		(net "M_A_CPU0_SA_DQ<19>")
	)
	(gr_poly
		(pts
			(xy 331.28839 -227.821744) (xy 331.334618 -227.724208) (xy 331.199744 -227.589588) (xy 331.102462 -227.635816)
			(xy 331.066394 -227.67163) (xy 331.252322 -227.857558)
		)
		(stroke
			(width 0)
			(type solid)
		)
		(fill yes)
		(layer "F.Cu")
		(net "M_A_CPU0_SB_DQ<23>")
	)
	(gr_poly
		(pts
			(xy 331.290422 -276.069044) (xy 331.254354 -276.03323) (xy 331.157072 -275.987002) (xy 331.022198 -276.121622)
			(xy 331.06868 -276.219158) (xy 331.104494 -276.254972)
		)
		(stroke
			(width 0)
			(type solid)
		)
		(fill yes)
		(layer "F.Cu")
		(net "M_A_CPU0_SA_DQ<18>")
	)
	(gr_poly
		(pts
			(xy 331.319632 -270.61795) (xy 331.273404 -270.520414) (xy 331.237336 -270.4846) (xy 331.051408 -270.670528)
			(xy 331.087476 -270.706342) (xy 331.184758 -270.75257)
		)
		(stroke
			(width 0)
			(type solid)
		)
		(fill yes)
		(layer "F.Cu")
		(net "M_A_CPU0_SA_DQ<26>")
	)
	(gr_poly
		(pts
			(xy 331.367892 -275.775674) (xy 331.321664 -275.678392) (xy 331.28585 -275.642324) (xy 331.099922 -275.828252)
			(xy 331.135736 -275.86432) (xy 331.233272 -275.910548)
		)
		(stroke
			(width 0)
			(type solid)
		)
		(fill yes)
		(layer "F.Cu")
		(net "M_A_CPU0_SA_DQ<17>")
	)
	(gr_poly
		(pts
			(xy 331.37729 -276.629368) (xy 331.331062 -276.531832) (xy 331.294994 -276.496018) (xy 331.10932 -276.681692)
			(xy 331.145134 -276.71776) (xy 331.24267 -276.763988)
		)
		(stroke
			(width 0)
			(type solid)
		)
		(fill yes)
		(layer "F.Cu")
		(net "M_A_CPU0_SA_DQ<16>")
	)
	(gr_poly
		(pts
			(xy 331.408024 -259.618226) (xy 331.371956 -259.516626) (xy 331.181456 -259.516626) (xy 331.145134 -259.618226)
			(xy 331.145134 -259.669026) (xy 331.408024 -259.669026)
		)
		(stroke
			(width 0)
			(type solid)
		)
		(fill yes)
		(layer "F.Cu")
		(net "M_A_CPU0_SA_CS_N<0>")
	)
	(gr_poly
		(pts
			(xy 331.427582 -228.104446) (xy 331.463396 -228.068632) (xy 331.277468 -227.882704) (xy 331.241654 -227.918772)
			(xy 331.195426 -228.016054) (xy 331.330046 -228.150674)
		)
		(stroke
			(width 0)
			(type solid)
		)
		(fill yes)
		(layer "F.Cu")
		(net "M_A_CPU0_SB_DQ<23>")
	)
	(gr_poly
		(pts
			(xy 331.44841 -270.273526) (xy 331.412596 -270.237712) (xy 331.31506 -270.191484) (xy 331.18044 -270.326104)
			(xy 331.226668 -270.42364) (xy 331.262482 -270.459454)
		)
		(stroke
			(width 0)
			(type solid)
		)
		(fill yes)
		(layer "F.Cu")
		(net "M_A_CPU0_SA_DQ<26>")
	)
	(gr_poly
		(pts
			(xy 331.49667 -275.431504) (xy 331.460856 -275.395436) (xy 331.36332 -275.349208) (xy 331.2287 -275.483828)
			(xy 331.274928 -275.581364) (xy 331.310996 -275.617178)
		)
		(stroke
			(width 0)
			(type solid)
		)
		(fill yes)
		(layer "F.Cu")
		(net "M_A_CPU0_SA_DQ<17>")
	)
	(gr_poly
		(pts
			(xy 331.506068 -276.284944) (xy 331.470254 -276.248876) (xy 331.372718 -276.202648) (xy 331.238098 -276.337522)
			(xy 331.284326 -276.434804) (xy 331.32014 -276.470872)
		)
		(stroke
			(width 0)
			(type solid)
		)
		(fill yes)
		(layer "F.Cu")
		(net "M_A_CPU0_SA_DQ<16>")
	)
	(gr_poly
		(pts
			(xy 331.52588 -269.980156) (xy 331.479652 -269.882874) (xy 331.443838 -269.846806) (xy 331.25791 -270.032734)
			(xy 331.293724 -270.068548) (xy 331.39126 -270.11503)
		)
		(stroke
			(width 0)
			(type solid)
		)
		(fill yes)
		(layer "F.Cu")
		(net "M_A_CPU0_SA_DQ<25>")
	)
	(gr_poly
		(pts
			(xy 331.535278 -270.833596) (xy 331.48905 -270.73606) (xy 331.452982 -270.700246) (xy 331.267054 -270.886174)
			(xy 331.303122 -270.921988) (xy 331.400404 -270.968216)
		)
		(stroke
			(width 0)
			(type solid)
		)
		(fill yes)
		(layer "F.Cu")
		(net "M_A_CPU0_SA_DQ<24>")
	)
	(gr_poly
		(pts
			(xy 331.572616 -275.136356) (xy 331.526388 -275.039074) (xy 331.490574 -275.003006) (xy 331.304646 -275.188934)
			(xy 331.34046 -275.224748) (xy 331.437996 -275.27123)
		)
		(stroke
			(width 0)
			(type solid)
		)
		(fill yes)
		(layer "F.Cu")
		(net "M_A_CPU0_SA_DQ<19>")
	)
	(gr_poly
		(pts
			(xy 331.583538 -275.99132) (xy 331.53731 -275.894038) (xy 331.501496 -275.85797) (xy 331.315568 -276.043898)
			(xy 331.351382 -276.079966) (xy 331.448918 -276.126194)
		)
		(stroke
			(width 0)
			(type solid)
		)
		(fill yes)
		(layer "F.Cu")
		(net "M_A_CPU0_SA_DQ<18>")
	)
	(gr_poly
		(pts
			(xy 331.664056 -270.489172) (xy 331.628242 -270.453358) (xy 331.530706 -270.40713) (xy 331.396086 -270.54175)
			(xy 331.442314 -270.639286) (xy 331.478128 -270.6751)
		)
		(stroke
			(width 0)
			(type solid)
		)
		(fill yes)
		(layer "F.Cu")
		(net "M_A_CPU0_SA_DQ<24>")
	)
	(gr_poly
		(pts
			(xy 331.701648 -274.791932) (xy 331.66558 -274.756118) (xy 331.568298 -274.70989) (xy 331.433424 -274.84451)
			(xy 331.479652 -274.942046) (xy 331.51572 -274.97786)
		)
		(stroke
			(width 0)
			(type solid)
		)
		(fill yes)
		(layer "F.Cu")
		(net "M_A_CPU0_SA_DQ<19>")
	)
	(gr_poly
		(pts
			(xy 331.706474 -259.719826) (xy 331.706474 -259.669026) (xy 331.443584 -259.669026) (xy 331.443584 -259.719826)
			(xy 331.479652 -259.821426) (xy 331.670152 -259.821426)
		)
		(stroke
			(width 0)
			(type solid)
		)
		(fill yes)
		(layer "F.Cu")
		(net "M_A_CPU0_SA_CS_N<0>")
	)
	(gr_poly
		(pts
			(xy 331.712316 -275.64715) (xy 331.676502 -275.611082) (xy 331.578966 -275.564854) (xy 331.444346 -275.699474)
			(xy 331.490574 -275.79701) (xy 331.526642 -275.832824)
		)
		(stroke
			(width 0)
			(type solid)
		)
		(fill yes)
		(layer "F.Cu")
		(net "M_A_CPU0_SA_DQ<18>")
	)
	(gr_poly
		(pts
			(xy 331.741526 -270.195802) (xy 331.695298 -270.09852) (xy 331.659484 -270.062452) (xy 331.473556 -270.24838)
			(xy 331.50937 -270.284194) (xy 331.606906 -270.330676)
		)
		(stroke
			(width 0)
			(type solid)
		)
		(fill yes)
		(layer "F.Cu")
		(net "M_A_CPU0_SA_DQ<26>")
	)
	(gr_poly
		(pts
			(xy 331.779372 -217.80119) (xy 331.728572 -217.80119) (xy 331.626972 -217.837258) (xy 331.626972 -218.027758)
			(xy 331.728572 -218.063826) (xy 331.779372 -218.063826)
		)
		(stroke
			(width 0)
			(type solid)
		)
		(fill yes)
		(layer "F.Cu")
		(net "M_A_CPU0_SB_DQ<28>")
	)
	(gr_poly
		(pts
			(xy 331.779372 -217.20429) (xy 331.728572 -217.20429) (xy 331.626972 -217.240358) (xy 331.626972 -217.430858)
			(xy 331.728572 -217.466926) (xy 331.779372 -217.466926)
		)
		(stroke
			(width 0)
			(type solid)
		)
		(fill yes)
		(layer "F.Cu")
		(net "M_A_CPU0_SB_DQ<28>")
	)
	(gr_poly
		(pts
			(xy 331.779372 -216.60739) (xy 331.728572 -216.60739) (xy 331.626972 -216.643458) (xy 331.626972 -216.833958)
			(xy 331.728572 -216.870026) (xy 331.779372 -216.870026)
		)
		(stroke
			(width 0)
			(type solid)
		)
		(fill yes)
		(layer "F.Cu")
		(net "M_A_CPU0_SB_DQ<28>")
	)
	(gr_poly
		(pts
			(xy 331.79004 -275.35378) (xy 331.743812 -275.256244) (xy 331.707744 -275.22043) (xy 331.521816 -275.406358)
			(xy 331.557884 -275.442172) (xy 331.65542 -275.4884)
		)
		(stroke
			(width 0)
			(type solid)
		)
		(fill yes)
		(layer "F.Cu")
		(net "M_A_CPU0_SA_DQ<17>")
	)
	(gr_poly
		(pts
			(xy 331.799438 -276.20722) (xy 331.75321 -276.109684) (xy 331.717142 -276.07387) (xy 331.531214 -276.259798)
			(xy 331.567282 -276.295612) (xy 331.664564 -276.34184)
		)
		(stroke
			(width 0)
			(type solid)
		)
		(fill yes)
		(layer "F.Cu")
		(net "M_A_CPU0_SA_DQ<16>")
	)
	(gr_poly
		(pts
			(xy 331.86878 -296.54246) (xy 331.81798 -296.54246) (xy 331.71638 -296.578782) (xy 331.71638 -296.769282)
			(xy 331.81798 -296.80535) (xy 331.86878 -296.80535)
		)
		(stroke
			(width 0)
			(type solid)
		)
		(fill yes)
		(layer "F.Cu")
		(net "M_A_CPU0_SA_DQ<3>")
	)
	(gr_poly
		(pts
			(xy 331.86878 -295.94556) (xy 331.81798 -295.94556) (xy 331.71638 -295.981882) (xy 331.71638 -296.172382)
			(xy 331.81798 -296.20845) (xy 331.86878 -296.20845)
		)
		(stroke
			(width 0)
			(type solid)
		)
		(fill yes)
		(layer "F.Cu")
		(net "M_A_CPU0_SA_DQ<3>")
	)
	(gr_poly
		(pts
			(xy 331.86878 -295.34866) (xy 331.81798 -295.34866) (xy 331.71638 -295.384982) (xy 331.71638 -295.575482)
			(xy 331.81798 -295.61155) (xy 331.86878 -295.61155)
		)
		(stroke
			(width 0)
			(type solid)
		)
		(fill yes)
		(layer "F.Cu")
		(net "M_A_CPU0_SA_DQ<3>")
	)
	(gr_poly
		(pts
			(xy 331.86878 -294.75176) (xy 331.81798 -294.75176) (xy 331.71638 -294.788082) (xy 331.71638 -294.978582)
			(xy 331.81798 -295.01465) (xy 331.86878 -295.01465)
		)
		(stroke
			(width 0)
			(type solid)
		)
		(fill yes)
		(layer "F.Cu")
		(net "M_A_CPU0_SA_DQ<3>")
	)
	(gr_poly
		(pts
			(xy 331.86878 -294.15486) (xy 331.81798 -294.15486) (xy 331.71638 -294.191182) (xy 331.71638 -294.381682)
			(xy 331.81798 -294.41775) (xy 331.86878 -294.41775)
		)
		(stroke
			(width 0)
			(type solid)
		)
		(fill yes)
		(layer "F.Cu")
		(net "M_A_CPU0_SA_DQ<3>")
	)
	(gr_poly
		(pts
			(xy 331.86878 -293.55796) (xy 331.81798 -293.55796) (xy 331.71638 -293.594282) (xy 331.71638 -293.784782)
			(xy 331.81798 -293.82085) (xy 331.86878 -293.82085)
		)
		(stroke
			(width 0)
			(type solid)
		)
		(fill yes)
		(layer "F.Cu")
		(net "M_A_CPU0_SA_DQ<3>")
	)
	(gr_poly
		(pts
			(xy 331.86878 -292.96106) (xy 331.81798 -292.96106) (xy 331.71638 -292.997382) (xy 331.71638 -293.187882)
			(xy 331.81798 -293.22395) (xy 331.86878 -293.22395)
		)
		(stroke
			(width 0)
			(type solid)
		)
		(fill yes)
		(layer "F.Cu")
		(net "M_A_CPU0_SA_DQ<3>")
	)
	(gr_poly
		(pts
			(xy 331.86878 -292.36416) (xy 331.81798 -292.36416) (xy 331.71638 -292.400482) (xy 331.71638 -292.590982)
			(xy 331.81798 -292.62705) (xy 331.86878 -292.62705)
		)
		(stroke
			(width 0)
			(type solid)
		)
		(fill yes)
		(layer "F.Cu")
		(net "M_A_CPU0_SA_DQ<3>")
	)
	(gr_poly
		(pts
			(xy 331.86878 -291.76726) (xy 331.81798 -291.76726) (xy 331.71638 -291.803582) (xy 331.71638 -291.994082)
			(xy 331.81798 -292.03015) (xy 331.86878 -292.03015)
		)
		(stroke
			(width 0)
			(type solid)
		)
		(fill yes)
		(layer "F.Cu")
		(net "M_A_CPU0_SA_DQ<3>")
	)
	(gr_poly
		(pts
			(xy 331.86878 -291.17036) (xy 331.81798 -291.17036) (xy 331.71638 -291.206682) (xy 331.71638 -291.397182)
			(xy 331.81798 -291.43325) (xy 331.86878 -291.43325)
		)
		(stroke
			(width 0)
			(type solid)
		)
		(fill yes)
		(layer "F.Cu")
		(net "M_A_CPU0_SA_DQ<3>")
	)
	(gr_poly
		(pts
			(xy 331.86878 -290.57346) (xy 331.81798 -290.57346) (xy 331.71638 -290.609782) (xy 331.71638 -290.800282)
			(xy 331.81798 -290.83635) (xy 331.86878 -290.83635)
		)
		(stroke
			(width 0)
			(type solid)
		)
		(fill yes)
		(layer "F.Cu")
		(net "M_A_CPU0_SA_DQ<3>")
	)
	(gr_poly
		(pts
			(xy 331.86878 -289.97656) (xy 331.81798 -289.97656) (xy 331.71638 -290.012882) (xy 331.71638 -290.203382)
			(xy 331.81798 -290.23945) (xy 331.86878 -290.23945)
		)
		(stroke
			(width 0)
			(type solid)
		)
		(fill yes)
		(layer "F.Cu")
		(net "M_A_CPU0_SA_DQ<3>")
	)
	(gr_poly
		(pts
			(xy 331.86878 -289.37966) (xy 331.81798 -289.37966) (xy 331.71638 -289.415982) (xy 331.71638 -289.606482)
			(xy 331.81798 -289.64255) (xy 331.86878 -289.64255)
		)
		(stroke
			(width 0)
			(type solid)
		)
		(fill yes)
		(layer "F.Cu")
		(net "M_A_CPU0_SA_DQ<3>")
	)
	(gr_poly
		(pts
			(xy 331.86878 -288.78276) (xy 331.81798 -288.78276) (xy 331.71638 -288.819082) (xy 331.71638 -289.009582)
			(xy 331.81798 -289.04565) (xy 331.86878 -289.04565)
		)
		(stroke
			(width 0)
			(type solid)
		)
		(fill yes)
		(layer "F.Cu")
		(net "M_A_CPU0_SA_DQ<3>")
	)
	(gr_poly
		(pts
			(xy 331.86878 -288.18586) (xy 331.81798 -288.18586) (xy 331.71638 -288.222182) (xy 331.71638 -288.412682)
			(xy 331.81798 -288.44875) (xy 331.86878 -288.44875)
		)
		(stroke
			(width 0)
			(type solid)
		)
		(fill yes)
		(layer "F.Cu")
		(net "M_A_CPU0_SA_DQ<3>")
	)
	(gr_poly
		(pts
			(xy 331.86878 -287.58896) (xy 331.81798 -287.58896) (xy 331.71638 -287.625282) (xy 331.71638 -287.815782)
			(xy 331.81798 -287.85185) (xy 331.86878 -287.85185)
		)
		(stroke
			(width 0)
			(type solid)
		)
		(fill yes)
		(layer "F.Cu")
		(net "M_A_CPU0_SA_DQ<3>")
	)
	(gr_poly
		(pts
			(xy 331.86878 -286.99206) (xy 331.81798 -286.99206) (xy 331.71638 -287.028382) (xy 331.71638 -287.218882)
			(xy 331.81798 -287.25495) (xy 331.86878 -287.25495)
		)
		(stroke
			(width 0)
			(type solid)
		)
		(fill yes)
		(layer "F.Cu")
		(net "M_A_CPU0_SA_DQ<3>")
	)
	(gr_poly
		(pts
			(xy 331.86878 -286.39516) (xy 331.81798 -286.39516) (xy 331.71638 -286.431482) (xy 331.71638 -286.621982)
			(xy 331.81798 -286.65805) (xy 331.86878 -286.65805)
		)
		(stroke
			(width 0)
			(type solid)
		)
		(fill yes)
		(layer "F.Cu")
		(net "M_A_CPU0_SA_DQ<3>")
	)
	(gr_poly
		(pts
			(xy 331.86878 -285.79826) (xy 331.81798 -285.79826) (xy 331.71638 -285.834582) (xy 331.71638 -286.025082)
			(xy 331.81798 -286.06115) (xy 331.86878 -286.06115)
		)
		(stroke
			(width 0)
			(type solid)
		)
		(fill yes)
		(layer "F.Cu")
		(net "M_A_CPU0_SA_DQ<3>")
	)
	(gr_poly
		(pts
			(xy 331.86878 -285.20136) (xy 331.81798 -285.20136) (xy 331.71638 -285.237682) (xy 331.71638 -285.428182)
			(xy 331.81798 -285.46425) (xy 331.86878 -285.46425)
		)
		(stroke
			(width 0)
			(type solid)
		)
		(fill yes)
		(layer "F.Cu")
		(net "M_A_CPU0_SA_DQ<3>")
	)
	(gr_poly
		(pts
			(xy 331.86878 -284.60446) (xy 331.81798 -284.60446) (xy 331.71638 -284.640782) (xy 331.71638 -284.831282)
			(xy 331.81798 -284.86735) (xy 331.86878 -284.86735)
		)
		(stroke
			(width 0)
			(type solid)
		)
		(fill yes)
		(layer "F.Cu")
		(net "M_A_CPU0_SA_DQ<3>")
	)
	(gr_poly
		(pts
			(xy 331.86878 -284.00756) (xy 331.81798 -284.00756) (xy 331.71638 -284.043882) (xy 331.71638 -284.234382)
			(xy 331.81798 -284.27045) (xy 331.86878 -284.27045)
		)
		(stroke
			(width 0)
			(type solid)
		)
		(fill yes)
		(layer "F.Cu")
		(net "M_A_CPU0_SA_DQ<3>")
	)
	(gr_poly
		(pts
			(xy 331.86878 -283.41066) (xy 331.81798 -283.41066) (xy 331.71638 -283.446982) (xy 331.71638 -283.637482)
			(xy 331.81798 -283.67355) (xy 331.86878 -283.67355)
		)
		(stroke
			(width 0)
			(type solid)
		)
		(fill yes)
		(layer "F.Cu")
		(net "M_A_CPU0_SA_DQ<3>")
	)
	(gr_poly
		(pts
			(xy 331.86878 -282.81376) (xy 331.81798 -282.81376) (xy 331.71638 -282.850082) (xy 331.71638 -283.040582)
			(xy 331.81798 -283.07665) (xy 331.86878 -283.07665)
		)
		(stroke
			(width 0)
			(type solid)
		)
		(fill yes)
		(layer "F.Cu")
		(net "M_A_CPU0_SA_DQ<3>")
	)
	(gr_poly
		(pts
			(xy 331.918818 -275.009356) (xy 331.883004 -274.973288) (xy 331.785468 -274.92706) (xy 331.650848 -275.061934)
			(xy 331.697076 -275.159216) (xy 331.73289 -275.195284)
		)
		(stroke
			(width 0)
			(type solid)
		)
		(fill yes)
		(layer "F.Cu")
		(net "M_A_CPU0_SA_DQ<17>")
	)
	(gr_poly
		(pts
			(xy 331.928216 -275.862796) (xy 331.892402 -275.826982) (xy 331.794866 -275.780754) (xy 331.660246 -275.915374)
			(xy 331.706474 -276.012656) (xy 331.742288 -276.048724)
		)
		(stroke
			(width 0)
			(type solid)
		)
		(fill yes)
		(layer "F.Cu")
		(net "M_A_CPU0_SA_DQ<16>")
	)
	(gr_poly
		(pts
			(xy 331.931772 -218.326208) (xy 331.931772 -218.135708) (xy 331.830172 -218.099386) (xy 331.779372 -218.099386)
			(xy 331.779372 -218.36253) (xy 331.830172 -218.36253)
		)
		(stroke
			(width 0)
			(type solid)
		)
		(fill yes)
		(layer "F.Cu")
		(net "M_A_CPU0_SB_DQ<28>")
	)
	(gr_poly
		(pts
			(xy 331.931772 -217.729308) (xy 331.931772 -217.538808) (xy 331.830172 -217.502486) (xy 331.779372 -217.502486)
			(xy 331.779372 -217.76563) (xy 331.830172 -217.76563)
		)
		(stroke
			(width 0)
			(type solid)
		)
		(fill yes)
		(layer "F.Cu")
		(net "M_A_CPU0_SB_DQ<28>")
	)
	(gr_poly
		(pts
			(xy 331.931772 -217.132408) (xy 331.931772 -216.941908) (xy 331.830172 -216.905586) (xy 331.779372 -216.905586)
			(xy 331.779372 -217.16873) (xy 331.830172 -217.16873)
		)
		(stroke
			(width 0)
			(type solid)
		)
		(fill yes)
		(layer "F.Cu")
		(net "M_A_CPU0_SB_DQ<28>")
	)
	(gr_poly
		(pts
			(xy 331.931772 -216.535508) (xy 331.931772 -216.345008) (xy 331.830172 -216.308686) (xy 331.779372 -216.308686)
			(xy 331.779372 -216.57183) (xy 331.830172 -216.57183)
		)
		(stroke
			(width 0)
			(type solid)
		)
		(fill yes)
		(layer "F.Cu")
		(net "M_A_CPU0_SB_DQ<28>")
	)
	(gr_poly
		(pts
			(xy 331.957172 -270.411448) (xy 331.910944 -270.314166) (xy 331.87513 -270.278098) (xy 331.689202 -270.464026)
			(xy 331.725016 -270.49984) (xy 331.822552 -270.546322)
		)
		(stroke
			(width 0)
			(type solid)
		)
		(fill yes)
		(layer "F.Cu")
		(net "M_A_CPU0_SA_DQ<24>")
	)
	(gr_poly
		(pts
			(xy 332.005686 -275.569426) (xy 331.959458 -275.47189) (xy 331.92339 -275.436076) (xy 331.737462 -275.622004)
			(xy 331.77353 -275.657818) (xy 331.871066 -275.704046)
		)
		(stroke
			(width 0)
			(type solid)
		)
		(fill yes)
		(layer "F.Cu")
		(net "M_A_CPU0_SA_DQ<18>")
	)
	(gr_poly
		(pts
			(xy 332.02118 -296.470832) (xy 332.02118 -296.280332) (xy 331.91958 -296.24401) (xy 331.86878 -296.24401)
			(xy 331.86878 -296.5069) (xy 331.91958 -296.5069)
		)
		(stroke
			(width 0)
			(type solid)
		)
		(fill yes)
		(layer "F.Cu")
		(net "M_A_CPU0_SA_DQ<3>")
	)
	(gr_poly
		(pts
			(xy 332.02118 -295.873932) (xy 332.02118 -295.683432) (xy 331.91958 -295.64711) (xy 331.86878 -295.64711)
			(xy 331.86878 -295.91) (xy 331.91958 -295.91)
		)
		(stroke
			(width 0)
			(type solid)
		)
		(fill yes)
		(layer "F.Cu")
		(net "M_A_CPU0_SA_DQ<3>")
	)
	(gr_poly
		(pts
			(xy 332.02118 -295.277032) (xy 332.02118 -295.086532) (xy 331.91958 -295.05021) (xy 331.86878 -295.05021)
			(xy 331.86878 -295.3131) (xy 331.91958 -295.3131)
		)
		(stroke
			(width 0)
			(type solid)
		)
		(fill yes)
		(layer "F.Cu")
		(net "M_A_CPU0_SA_DQ<3>")
	)
	(gr_poly
		(pts
			(xy 332.02118 -294.680132) (xy 332.02118 -294.489632) (xy 331.91958 -294.45331) (xy 331.86878 -294.45331)
			(xy 331.86878 -294.7162) (xy 331.91958 -294.7162)
		)
		(stroke
			(width 0)
			(type solid)
		)
		(fill yes)
		(layer "F.Cu")
		(net "M_A_CPU0_SA_DQ<3>")
	)
	(gr_poly
		(pts
			(xy 332.02118 -294.083232) (xy 332.02118 -293.892732) (xy 331.91958 -293.85641) (xy 331.86878 -293.85641)
			(xy 331.86878 -294.1193) (xy 331.91958 -294.1193)
		)
		(stroke
			(width 0)
			(type solid)
		)
		(fill yes)
		(layer "F.Cu")
		(net "M_A_CPU0_SA_DQ<3>")
	)
	(gr_poly
		(pts
			(xy 332.02118 -293.486332) (xy 332.02118 -293.295832) (xy 331.91958 -293.25951) (xy 331.86878 -293.25951)
			(xy 331.86878 -293.5224) (xy 331.91958 -293.5224)
		)
		(stroke
			(width 0)
			(type solid)
		)
		(fill yes)
		(layer "F.Cu")
		(net "M_A_CPU0_SA_DQ<3>")
	)
	(gr_poly
		(pts
			(xy 332.02118 -292.889432) (xy 332.02118 -292.698932) (xy 331.91958 -292.66261) (xy 331.86878 -292.66261)
			(xy 331.86878 -292.9255) (xy 331.91958 -292.9255)
		)
		(stroke
			(width 0)
			(type solid)
		)
		(fill yes)
		(layer "F.Cu")
		(net "M_A_CPU0_SA_DQ<3>")
	)
	(gr_poly
		(pts
			(xy 332.02118 -292.292532) (xy 332.02118 -292.102032) (xy 331.91958 -292.06571) (xy 331.86878 -292.06571)
			(xy 331.86878 -292.3286) (xy 331.91958 -292.3286)
		)
		(stroke
			(width 0)
			(type solid)
		)
		(fill yes)
		(layer "F.Cu")
		(net "M_A_CPU0_SA_DQ<3>")
	)
	(gr_poly
		(pts
			(xy 332.02118 -291.695632) (xy 332.02118 -291.505132) (xy 331.91958 -291.46881) (xy 331.86878 -291.46881)
			(xy 331.86878 -291.7317) (xy 331.91958 -291.7317)
		)
		(stroke
			(width 0)
			(type solid)
		)
		(fill yes)
		(layer "F.Cu")
		(net "M_A_CPU0_SA_DQ<3>")
	)
	(gr_poly
		(pts
			(xy 332.02118 -291.098732) (xy 332.02118 -290.908232) (xy 331.91958 -290.87191) (xy 331.86878 -290.87191)
			(xy 331.86878 -291.1348) (xy 331.91958 -291.1348)
		)
		(stroke
			(width 0)
			(type solid)
		)
		(fill yes)
		(layer "F.Cu")
		(net "M_A_CPU0_SA_DQ<3>")
	)
	(gr_poly
		(pts
			(xy 332.02118 -290.501832) (xy 332.02118 -290.311332) (xy 331.91958 -290.27501) (xy 331.86878 -290.27501)
			(xy 331.86878 -290.5379) (xy 331.91958 -290.5379)
		)
		(stroke
			(width 0)
			(type solid)
		)
		(fill yes)
		(layer "F.Cu")
		(net "M_A_CPU0_SA_DQ<3>")
	)
	(gr_poly
		(pts
			(xy 332.02118 -289.904932) (xy 332.02118 -289.714432) (xy 331.91958 -289.67811) (xy 331.86878 -289.67811)
			(xy 331.86878 -289.941) (xy 331.91958 -289.941)
		)
		(stroke
			(width 0)
			(type solid)
		)
		(fill yes)
		(layer "F.Cu")
		(net "M_A_CPU0_SA_DQ<3>")
	)
	(gr_poly
		(pts
			(xy 332.02118 -289.308032) (xy 332.02118 -289.117532) (xy 331.91958 -289.08121) (xy 331.86878 -289.08121)
			(xy 331.86878 -289.3441) (xy 331.91958 -289.3441)
		)
		(stroke
			(width 0)
			(type solid)
		)
		(fill yes)
		(layer "F.Cu")
		(net "M_A_CPU0_SA_DQ<3>")
	)
	(gr_poly
		(pts
			(xy 332.02118 -288.711132) (xy 332.02118 -288.520632) (xy 331.91958 -288.48431) (xy 331.86878 -288.48431)
			(xy 331.86878 -288.7472) (xy 331.91958 -288.7472)
		)
		(stroke
			(width 0)
			(type solid)
		)
		(fill yes)
		(layer "F.Cu")
		(net "M_A_CPU0_SA_DQ<3>")
	)
	(gr_poly
		(pts
			(xy 332.02118 -288.114232) (xy 332.02118 -287.923732) (xy 331.91958 -287.88741) (xy 331.86878 -287.88741)
			(xy 331.86878 -288.1503) (xy 331.91958 -288.1503)
		)
		(stroke
			(width 0)
			(type solid)
		)
		(fill yes)
		(layer "F.Cu")
		(net "M_A_CPU0_SA_DQ<3>")
	)
	(gr_poly
		(pts
			(xy 332.02118 -287.517332) (xy 332.02118 -287.326832) (xy 331.91958 -287.29051) (xy 331.86878 -287.29051)
			(xy 331.86878 -287.5534) (xy 331.91958 -287.5534)
		)
		(stroke
			(width 0)
			(type solid)
		)
		(fill yes)
		(layer "F.Cu")
		(net "M_A_CPU0_SA_DQ<3>")
	)
	(gr_poly
		(pts
			(xy 332.02118 -286.920432) (xy 332.02118 -286.729932) (xy 331.91958 -286.69361) (xy 331.86878 -286.69361)
			(xy 331.86878 -286.9565) (xy 331.91958 -286.9565)
		)
		(stroke
			(width 0)
			(type solid)
		)
		(fill yes)
		(layer "F.Cu")
		(net "M_A_CPU0_SA_DQ<3>")
	)
	(gr_poly
		(pts
			(xy 332.02118 -286.323532) (xy 332.02118 -286.133032) (xy 331.91958 -286.09671) (xy 331.86878 -286.09671)
			(xy 331.86878 -286.3596) (xy 331.91958 -286.3596)
		)
		(stroke
			(width 0)
			(type solid)
		)
		(fill yes)
		(layer "F.Cu")
		(net "M_A_CPU0_SA_DQ<3>")
	)
	(gr_poly
		(pts
			(xy 332.02118 -285.726632) (xy 332.02118 -285.536132) (xy 331.91958 -285.49981) (xy 331.86878 -285.49981)
			(xy 331.86878 -285.7627) (xy 331.91958 -285.7627)
		)
		(stroke
			(width 0)
			(type solid)
		)
		(fill yes)
		(layer "F.Cu")
		(net "M_A_CPU0_SA_DQ<3>")
	)
	(gr_poly
		(pts
			(xy 332.02118 -285.129732) (xy 332.02118 -284.939232) (xy 331.91958 -284.90291) (xy 331.86878 -284.90291)
			(xy 331.86878 -285.1658) (xy 331.91958 -285.1658)
		)
		(stroke
			(width 0)
			(type solid)
		)
		(fill yes)
		(layer "F.Cu")
		(net "M_A_CPU0_SA_DQ<3>")
	)
	(gr_poly
		(pts
			(xy 332.02118 -284.532832) (xy 332.02118 -284.342332) (xy 331.91958 -284.30601) (xy 331.86878 -284.30601)
			(xy 331.86878 -284.5689) (xy 331.91958 -284.5689)
		)
		(stroke
			(width 0)
			(type solid)
		)
		(fill yes)
		(layer "F.Cu")
		(net "M_A_CPU0_SA_DQ<3>")
	)
	(gr_poly
		(pts
			(xy 332.02118 -283.935932) (xy 332.02118 -283.745432) (xy 331.91958 -283.70911) (xy 331.86878 -283.70911)
			(xy 331.86878 -283.972) (xy 331.91958 -283.972)
		)
		(stroke
			(width 0)
			(type solid)
		)
		(fill yes)
		(layer "F.Cu")
		(net "M_A_CPU0_SA_DQ<3>")
	)
	(gr_poly
		(pts
			(xy 332.02118 -283.339032) (xy 332.02118 -283.148532) (xy 331.91958 -283.11221) (xy 331.86878 -283.11221)
			(xy 331.86878 -283.3751) (xy 331.91958 -283.3751)
		)
		(stroke
			(width 0)
			(type solid)
		)
		(fill yes)
		(layer "F.Cu")
		(net "M_A_CPU0_SA_DQ<3>")
	)
	(gr_poly
		(pts
			(xy 332.02118 -281.692096) (xy 331.971396 -281.68219) (xy 331.864716 -281.697684) (xy 331.827124 -281.884374)
			(xy 331.919834 -281.94) (xy 331.969618 -281.949906)
		)
		(stroke
			(width 0)
			(type solid)
		)
		(fill yes)
		(layer "F.Cu")
		(net "M_A_CPU0_SA_DQ<3>")
	)
	(gr_poly
		(pts
			(xy 332.067662 -282.236926) (xy 332.105 -282.050236) (xy 332.01229 -281.99461) (xy 331.962506 -281.984704)
			(xy 331.910944 -282.242514) (xy 331.960728 -282.25242)
		)
		(stroke
			(width 0)
			(type solid)
		)
		(fill yes)
		(layer "F.Cu")
		(net "M_A_CPU0_SA_DQ<3>")
	)
	(gr_poly
		(pts
			(xy 332.084172 -217.80119) (xy 332.033372 -217.80119) (xy 331.931772 -217.837258) (xy 331.931772 -218.027758)
			(xy 332.033372 -218.063826) (xy 332.084172 -218.063826)
		)
		(stroke
			(width 0)
			(type solid)
		)
		(fill yes)
		(layer "F.Cu")
		(net "M_A_CPU0_SB_DQ<30>")
	)
	(gr_poly
		(pts
			(xy 332.084172 -217.20429) (xy 332.033372 -217.20429) (xy 331.931772 -217.240358) (xy 331.931772 -217.430858)
			(xy 332.033372 -217.466926) (xy 332.084172 -217.466926)
		)
		(stroke
			(width 0)
			(type solid)
		)
		(fill yes)
		(layer "F.Cu")
		(net "M_A_CPU0_SB_DQ<30>")
	)
	(gr_poly
		(pts
			(xy 332.084172 -216.60739) (xy 332.033372 -216.60739) (xy 331.931772 -216.643458) (xy 331.931772 -216.833958)
			(xy 332.033372 -216.870026) (xy 332.084172 -216.870026)
		)
		(stroke
			(width 0)
			(type solid)
		)
		(fill yes)
		(layer "F.Cu")
		(net "M_A_CPU0_SB_DQ<30>")
	)
	(gr_poly
		(pts
			(xy 332.134464 -275.225002) (xy 332.09865 -275.188934) (xy 332.001114 -275.142706) (xy 331.866494 -275.27758)
			(xy 331.912722 -275.374862) (xy 331.948536 -275.41093)
		)
		(stroke
			(width 0)
			(type solid)
		)
		(fill yes)
		(layer "F.Cu")
		(net "M_A_CPU0_SA_DQ<18>")
	)
	(gr_poly
		(pts
			(xy 332.17358 -296.54246) (xy 332.12278 -296.54246) (xy 332.02118 -296.578782) (xy 332.02118 -296.769282)
			(xy 332.12278 -296.80535) (xy 332.17358 -296.80535)
		)
		(stroke
			(width 0)
			(type solid)
		)
		(fill yes)
		(layer "F.Cu")
		(net "M_A_CPU0_SA_DQ<1>")
	)
	(gr_poly
		(pts
			(xy 332.17358 -295.94556) (xy 332.12278 -295.94556) (xy 332.02118 -295.981882) (xy 332.02118 -296.172382)
			(xy 332.12278 -296.20845) (xy 332.17358 -296.20845)
		)
		(stroke
			(width 0)
			(type solid)
		)
		(fill yes)
		(layer "F.Cu")
		(net "M_A_CPU0_SA_DQ<1>")
	)
	(gr_poly
		(pts
			(xy 332.17358 -295.34866) (xy 332.12278 -295.34866) (xy 332.02118 -295.384982) (xy 332.02118 -295.575482)
			(xy 332.12278 -295.61155) (xy 332.17358 -295.61155)
		)
		(stroke
			(width 0)
			(type solid)
		)
		(fill yes)
		(layer "F.Cu")
		(net "M_A_CPU0_SA_DQ<1>")
	)
	(gr_poly
		(pts
			(xy 332.17358 -294.75176) (xy 332.12278 -294.75176) (xy 332.02118 -294.788082) (xy 332.02118 -294.978582)
			(xy 332.12278 -295.01465) (xy 332.17358 -295.01465)
		)
		(stroke
			(width 0)
			(type solid)
		)
		(fill yes)
		(layer "F.Cu")
		(net "M_A_CPU0_SA_DQ<1>")
	)
	(gr_poly
		(pts
			(xy 332.17358 -294.15486) (xy 332.12278 -294.15486) (xy 332.02118 -294.191182) (xy 332.02118 -294.381682)
			(xy 332.12278 -294.41775) (xy 332.17358 -294.41775)
		)
		(stroke
			(width 0)
			(type solid)
		)
		(fill yes)
		(layer "F.Cu")
		(net "M_A_CPU0_SA_DQ<1>")
	)
	(gr_poly
		(pts
			(xy 332.17358 -293.55796) (xy 332.12278 -293.55796) (xy 332.02118 -293.594282) (xy 332.02118 -293.784782)
			(xy 332.12278 -293.82085) (xy 332.17358 -293.82085)
		)
		(stroke
			(width 0)
			(type solid)
		)
		(fill yes)
		(layer "F.Cu")
		(net "M_A_CPU0_SA_DQ<1>")
	)
	(gr_poly
		(pts
			(xy 332.17358 -292.96106) (xy 332.12278 -292.96106) (xy 332.02118 -292.997382) (xy 332.02118 -293.187882)
			(xy 332.12278 -293.22395) (xy 332.17358 -293.22395)
		)
		(stroke
			(width 0)
			(type solid)
		)
		(fill yes)
		(layer "F.Cu")
		(net "M_A_CPU0_SA_DQ<1>")
	)
	(gr_poly
		(pts
			(xy 332.17358 -292.36416) (xy 332.12278 -292.36416) (xy 332.02118 -292.400482) (xy 332.02118 -292.590982)
			(xy 332.12278 -292.62705) (xy 332.17358 -292.62705)
		)
		(stroke
			(width 0)
			(type solid)
		)
		(fill yes)
		(layer "F.Cu")
		(net "M_A_CPU0_SA_DQ<1>")
	)
	(gr_poly
		(pts
			(xy 332.17358 -291.76726) (xy 332.12278 -291.76726) (xy 332.02118 -291.803582) (xy 332.02118 -291.994082)
			(xy 332.12278 -292.03015) (xy 332.17358 -292.03015)
		)
		(stroke
			(width 0)
			(type solid)
		)
		(fill yes)
		(layer "F.Cu")
		(net "M_A_CPU0_SA_DQ<1>")
	)
	(gr_poly
		(pts
			(xy 332.17358 -291.17036) (xy 332.12278 -291.17036) (xy 332.02118 -291.206682) (xy 332.02118 -291.397182)
			(xy 332.12278 -291.43325) (xy 332.17358 -291.43325)
		)
		(stroke
			(width 0)
			(type solid)
		)
		(fill yes)
		(layer "F.Cu")
		(net "M_A_CPU0_SA_DQ<1>")
	)
	(gr_poly
		(pts
			(xy 332.17358 -290.57346) (xy 332.12278 -290.57346) (xy 332.02118 -290.609782) (xy 332.02118 -290.800282)
			(xy 332.12278 -290.83635) (xy 332.17358 -290.83635)
		)
		(stroke
			(width 0)
			(type solid)
		)
		(fill yes)
		(layer "F.Cu")
		(net "M_A_CPU0_SA_DQ<1>")
	)
	(gr_poly
		(pts
			(xy 332.17358 -289.97656) (xy 332.12278 -289.97656) (xy 332.02118 -290.012882) (xy 332.02118 -290.203382)
			(xy 332.12278 -290.23945) (xy 332.17358 -290.23945)
		)
		(stroke
			(width 0)
			(type solid)
		)
		(fill yes)
		(layer "F.Cu")
		(net "M_A_CPU0_SA_DQ<1>")
	)
	(gr_poly
		(pts
			(xy 332.17358 -289.37966) (xy 332.12278 -289.37966) (xy 332.02118 -289.415982) (xy 332.02118 -289.606482)
			(xy 332.12278 -289.64255) (xy 332.17358 -289.64255)
		)
		(stroke
			(width 0)
			(type solid)
		)
		(fill yes)
		(layer "F.Cu")
		(net "M_A_CPU0_SA_DQ<1>")
	)
	(gr_poly
		(pts
			(xy 332.17358 -288.78276) (xy 332.12278 -288.78276) (xy 332.02118 -288.819082) (xy 332.02118 -289.009582)
			(xy 332.12278 -289.04565) (xy 332.17358 -289.04565)
		)
		(stroke
			(width 0)
			(type solid)
		)
		(fill yes)
		(layer "F.Cu")
		(net "M_A_CPU0_SA_DQ<1>")
	)
	(gr_poly
		(pts
			(xy 332.17358 -288.18586) (xy 332.12278 -288.18586) (xy 332.02118 -288.222182) (xy 332.02118 -288.412682)
			(xy 332.12278 -288.44875) (xy 332.17358 -288.44875)
		)
		(stroke
			(width 0)
			(type solid)
		)
		(fill yes)
		(layer "F.Cu")
		(net "M_A_CPU0_SA_DQ<1>")
	)
	(gr_poly
		(pts
			(xy 332.17358 -287.58896) (xy 332.12278 -287.58896) (xy 332.02118 -287.625282) (xy 332.02118 -287.815782)
			(xy 332.12278 -287.85185) (xy 332.17358 -287.85185)
		)
		(stroke
			(width 0)
			(type solid)
		)
		(fill yes)
		(layer "F.Cu")
		(net "M_A_CPU0_SA_DQ<1>")
	)
	(gr_poly
		(pts
			(xy 332.17358 -286.99206) (xy 332.12278 -286.99206) (xy 332.02118 -287.028382) (xy 332.02118 -287.218882)
			(xy 332.12278 -287.25495) (xy 332.17358 -287.25495)
		)
		(stroke
			(width 0)
			(type solid)
		)
		(fill yes)
		(layer "F.Cu")
		(net "M_A_CPU0_SA_DQ<1>")
	)
	(gr_poly
		(pts
			(xy 332.17358 -286.39516) (xy 332.12278 -286.39516) (xy 332.02118 -286.431482) (xy 332.02118 -286.621982)
			(xy 332.12278 -286.65805) (xy 332.17358 -286.65805)
		)
		(stroke
			(width 0)
			(type solid)
		)
		(fill yes)
		(layer "F.Cu")
		(net "M_A_CPU0_SA_DQ<1>")
	)
	(gr_poly
		(pts
			(xy 332.17358 -285.79826) (xy 332.12278 -285.79826) (xy 332.02118 -285.834582) (xy 332.02118 -286.025082)
			(xy 332.12278 -286.06115) (xy 332.17358 -286.06115)
		)
		(stroke
			(width 0)
			(type solid)
		)
		(fill yes)
		(layer "F.Cu")
		(net "M_A_CPU0_SA_DQ<1>")
	)
	(gr_poly
		(pts
			(xy 332.17358 -285.20136) (xy 332.12278 -285.20136) (xy 332.02118 -285.237682) (xy 332.02118 -285.428182)
			(xy 332.12278 -285.46425) (xy 332.17358 -285.46425)
		)
		(stroke
			(width 0)
			(type solid)
		)
		(fill yes)
		(layer "F.Cu")
		(net "M_A_CPU0_SA_DQ<1>")
	)
	(gr_poly
		(pts
			(xy 332.17358 -284.60446) (xy 332.12278 -284.60446) (xy 332.02118 -284.640782) (xy 332.02118 -284.831282)
			(xy 332.12278 -284.86735) (xy 332.17358 -284.86735)
		)
		(stroke
			(width 0)
			(type solid)
		)
		(fill yes)
		(layer "F.Cu")
		(net "M_A_CPU0_SA_DQ<1>")
	)
	(gr_poly
		(pts
			(xy 332.17358 -284.00756) (xy 332.12278 -284.00756) (xy 332.02118 -284.043882) (xy 332.02118 -284.234382)
			(xy 332.12278 -284.27045) (xy 332.17358 -284.27045)
		)
		(stroke
			(width 0)
			(type solid)
		)
		(fill yes)
		(layer "F.Cu")
		(net "M_A_CPU0_SA_DQ<1>")
	)
	(gr_poly
		(pts
			(xy 332.17358 -283.41066) (xy 332.12278 -283.41066) (xy 332.02118 -283.446982) (xy 332.02118 -283.637482)
			(xy 332.12278 -283.67355) (xy 332.17358 -283.67355)
		)
		(stroke
			(width 0)
			(type solid)
		)
		(fill yes)
		(layer "F.Cu")
		(net "M_A_CPU0_SA_DQ<1>")
	)
	(gr_poly
		(pts
			(xy 332.17358 -282.81376) (xy 332.12278 -282.81376) (xy 332.02118 -282.850082) (xy 332.02118 -283.040582)
			(xy 332.12278 -283.07665) (xy 332.17358 -283.07665)
		)
		(stroke
			(width 0)
			(type solid)
		)
		(fill yes)
		(layer "F.Cu")
		(net "M_A_CPU0_SA_DQ<1>")
	)
	(gr_poly
		(pts
			(xy 332.184756 -281.65171) (xy 332.222094 -281.464766) (xy 332.129384 -281.409394) (xy 332.0796 -281.399488)
			(xy 332.028038 -281.657298) (xy 332.077822 -281.667204)
		)
		(stroke
			(width 0)
			(type solid)
		)
		(fill yes)
		(layer "F.Cu")
		(net "M_A_CPU0_SA_DQ<3>")
	)
	(gr_poly
		(pts
			(xy 332.221332 -275.785072) (xy 332.175104 -275.68779) (xy 332.13929 -275.651722) (xy 331.953362 -275.83765)
			(xy 331.989176 -275.873464) (xy 332.086712 -275.919946)
		)
		(stroke
			(width 0)
			(type solid)
		)
		(fill yes)
		(layer "F.Cu")
		(net "M_A_CPU0_SA_DQ<16>")
	)
	(gr_poly
		(pts
			(xy 332.236572 -218.326208) (xy 332.236572 -218.135708) (xy 332.134972 -218.099386) (xy 332.084172 -218.099386)
			(xy 332.084172 -218.36253) (xy 332.134972 -218.36253)
		)
		(stroke
			(width 0)
			(type solid)
		)
		(fill yes)
		(layer "F.Cu")
		(net "M_A_CPU0_SB_DQ<30>")
	)
	(gr_poly
		(pts
			(xy 332.236572 -217.729308) (xy 332.236572 -217.538808) (xy 332.134972 -217.502486) (xy 332.084172 -217.502486)
			(xy 332.084172 -217.76563) (xy 332.134972 -217.76563)
		)
		(stroke
			(width 0)
			(type solid)
		)
		(fill yes)
		(layer "F.Cu")
		(net "M_A_CPU0_SB_DQ<30>")
	)
	(gr_poly
		(pts
			(xy 332.236572 -217.132408) (xy 332.236572 -216.941908) (xy 332.134972 -216.905586) (xy 332.084172 -216.905586)
			(xy 332.084172 -217.16873) (xy 332.134972 -217.16873)
		)
		(stroke
			(width 0)
			(type solid)
		)
		(fill yes)
		(layer "F.Cu")
		(net "M_A_CPU0_SB_DQ<30>")
	)
	(gr_poly
		(pts
			(xy 332.236572 -216.535508) (xy 332.236572 -216.345008) (xy 332.134972 -216.308686) (xy 332.084172 -216.308686)
			(xy 332.084172 -216.57183) (xy 332.134972 -216.57183)
		)
		(stroke
			(width 0)
			(type solid)
		)
		(fill yes)
		(layer "F.Cu")
		(net "M_A_CPU0_SB_DQ<30>")
	)
	(gr_poly
		(pts
			(xy 332.320392 -281.75204) (xy 332.270608 -281.742134) (xy 332.163928 -281.757628) (xy 332.12659 -281.944318)
			(xy 332.219046 -281.99969) (xy 332.26883 -282.00985)
		)
		(stroke
			(width 0)
			(type solid)
		)
		(fill yes)
		(layer "F.Cu")
		(net "M_A_CPU0_SA_DQ<1>")
	)
	(gr_poly
		(pts
			(xy 332.32598 -296.470832) (xy 332.32598 -296.280332) (xy 332.22438 -296.24401) (xy 332.17358 -296.24401)
			(xy 332.17358 -296.5069) (xy 332.22438 -296.5069)
		)
		(stroke
			(width 0)
			(type solid)
		)
		(fill yes)
		(layer "F.Cu")
		(net "M_A_CPU0_SA_DQ<1>")
	)
	(gr_poly
		(pts
			(xy 332.32598 -295.873932) (xy 332.32598 -295.683432) (xy 332.22438 -295.64711) (xy 332.17358 -295.64711)
			(xy 332.17358 -295.91) (xy 332.22438 -295.91)
		)
		(stroke
			(width 0)
			(type solid)
		)
		(fill yes)
		(layer "F.Cu")
		(net "M_A_CPU0_SA_DQ<1>")
	)
	(gr_poly
		(pts
			(xy 332.32598 -295.277032) (xy 332.32598 -295.086532) (xy 332.22438 -295.05021) (xy 332.17358 -295.05021)
			(xy 332.17358 -295.3131) (xy 332.22438 -295.3131)
		)
		(stroke
			(width 0)
			(type solid)
		)
		(fill yes)
		(layer "F.Cu")
		(net "M_A_CPU0_SA_DQ<1>")
	)
	(gr_poly
		(pts
			(xy 332.32598 -294.680132) (xy 332.32598 -294.489632) (xy 332.22438 -294.45331) (xy 332.17358 -294.45331)
			(xy 332.17358 -294.7162) (xy 332.22438 -294.7162)
		)
		(stroke
			(width 0)
			(type solid)
		)
		(fill yes)
		(layer "F.Cu")
		(net "M_A_CPU0_SA_DQ<1>")
	)
	(gr_poly
		(pts
			(xy 332.32598 -294.083232) (xy 332.32598 -293.892732) (xy 332.22438 -293.85641) (xy 332.17358 -293.85641)
			(xy 332.17358 -294.1193) (xy 332.22438 -294.1193)
		)
		(stroke
			(width 0)
			(type solid)
		)
		(fill yes)
		(layer "F.Cu")
		(net "M_A_CPU0_SA_DQ<1>")
	)
	(gr_poly
		(pts
			(xy 332.32598 -293.486332) (xy 332.32598 -293.295832) (xy 332.22438 -293.25951) (xy 332.17358 -293.25951)
			(xy 332.17358 -293.5224) (xy 332.22438 -293.5224)
		)
		(stroke
			(width 0)
			(type solid)
		)
		(fill yes)
		(layer "F.Cu")
		(net "M_A_CPU0_SA_DQ<1>")
	)
	(gr_poly
		(pts
			(xy 332.32598 -292.889432) (xy 332.32598 -292.698932) (xy 332.22438 -292.66261) (xy 332.17358 -292.66261)
			(xy 332.17358 -292.9255) (xy 332.22438 -292.9255)
		)
		(stroke
			(width 0)
			(type solid)
		)
		(fill yes)
		(layer "F.Cu")
		(net "M_A_CPU0_SA_DQ<1>")
	)
	(gr_poly
		(pts
			(xy 332.32598 -292.292532) (xy 332.32598 -292.102032) (xy 332.22438 -292.06571) (xy 332.17358 -292.06571)
			(xy 332.17358 -292.3286) (xy 332.22438 -292.3286)
		)
		(stroke
			(width 0)
			(type solid)
		)
		(fill yes)
		(layer "F.Cu")
		(net "M_A_CPU0_SA_DQ<1>")
	)
	(gr_poly
		(pts
			(xy 332.32598 -291.695632) (xy 332.32598 -291.505132) (xy 332.22438 -291.46881) (xy 332.17358 -291.46881)
			(xy 332.17358 -291.7317) (xy 332.22438 -291.7317)
		)
		(stroke
			(width 0)
			(type solid)
		)
		(fill yes)
		(layer "F.Cu")
		(net "M_A_CPU0_SA_DQ<1>")
	)
	(gr_poly
		(pts
			(xy 332.32598 -291.098732) (xy 332.32598 -290.908232) (xy 332.22438 -290.87191) (xy 332.17358 -290.87191)
			(xy 332.17358 -291.1348) (xy 332.22438 -291.1348)
		)
		(stroke
			(width 0)
			(type solid)
		)
		(fill yes)
		(layer "F.Cu")
		(net "M_A_CPU0_SA_DQ<1>")
	)
	(gr_poly
		(pts
			(xy 332.32598 -290.501832) (xy 332.32598 -290.311332) (xy 332.22438 -290.27501) (xy 332.17358 -290.27501)
			(xy 332.17358 -290.5379) (xy 332.22438 -290.5379)
		)
		(stroke
			(width 0)
			(type solid)
		)
		(fill yes)
		(layer "F.Cu")
		(net "M_A_CPU0_SA_DQ<1>")
	)
	(gr_poly
		(pts
			(xy 332.32598 -289.904932) (xy 332.32598 -289.714432) (xy 332.22438 -289.67811) (xy 332.17358 -289.67811)
			(xy 332.17358 -289.941) (xy 332.22438 -289.941)
		)
		(stroke
			(width 0)
			(type solid)
		)
		(fill yes)
		(layer "F.Cu")
		(net "M_A_CPU0_SA_DQ<1>")
	)
	(gr_poly
		(pts
			(xy 332.32598 -289.308032) (xy 332.32598 -289.117532) (xy 332.22438 -289.08121) (xy 332.17358 -289.08121)
			(xy 332.17358 -289.3441) (xy 332.22438 -289.3441)
		)
		(stroke
			(width 0)
			(type solid)
		)
		(fill yes)
		(layer "F.Cu")
		(net "M_A_CPU0_SA_DQ<1>")
	)
	(gr_poly
		(pts
			(xy 332.32598 -288.711132) (xy 332.32598 -288.520632) (xy 332.22438 -288.48431) (xy 332.17358 -288.48431)
			(xy 332.17358 -288.7472) (xy 332.22438 -288.7472)
		)
		(stroke
			(width 0)
			(type solid)
		)
		(fill yes)
		(layer "F.Cu")
		(net "M_A_CPU0_SA_DQ<1>")
	)
	(gr_poly
		(pts
			(xy 332.32598 -288.114232) (xy 332.32598 -287.923732) (xy 332.22438 -287.88741) (xy 332.17358 -287.88741)
			(xy 332.17358 -288.1503) (xy 332.22438 -288.1503)
		)
		(stroke
			(width 0)
			(type solid)
		)
		(fill yes)
		(layer "F.Cu")
		(net "M_A_CPU0_SA_DQ<1>")
	)
	(gr_poly
		(pts
			(xy 332.32598 -287.517332) (xy 332.32598 -287.326832) (xy 332.22438 -287.29051) (xy 332.17358 -287.29051)
			(xy 332.17358 -287.5534) (xy 332.22438 -287.5534)
		)
		(stroke
			(width 0)
			(type solid)
		)
		(fill yes)
		(layer "F.Cu")
		(net "M_A_CPU0_SA_DQ<1>")
	)
	(gr_poly
		(pts
			(xy 332.32598 -286.920432) (xy 332.32598 -286.729932) (xy 332.22438 -286.69361) (xy 332.17358 -286.69361)
			(xy 332.17358 -286.9565) (xy 332.22438 -286.9565)
		)
		(stroke
			(width 0)
			(type solid)
		)
		(fill yes)
		(layer "F.Cu")
		(net "M_A_CPU0_SA_DQ<1>")
	)
	(gr_poly
		(pts
			(xy 332.32598 -286.323532) (xy 332.32598 -286.133032) (xy 332.22438 -286.09671) (xy 332.17358 -286.09671)
			(xy 332.17358 -286.3596) (xy 332.22438 -286.3596)
		)
		(stroke
			(width 0)
			(type solid)
		)
		(fill yes)
		(layer "F.Cu")
		(net "M_A_CPU0_SA_DQ<1>")
	)
	(gr_poly
		(pts
			(xy 332.32598 -285.726632) (xy 332.32598 -285.536132) (xy 332.22438 -285.49981) (xy 332.17358 -285.49981)
			(xy 332.17358 -285.7627) (xy 332.22438 -285.7627)
		)
		(stroke
			(width 0)
			(type solid)
		)
		(fill yes)
		(layer "F.Cu")
		(net "M_A_CPU0_SA_DQ<1>")
	)
	(gr_poly
		(pts
			(xy 332.32598 -285.129732) (xy 332.32598 -284.939232) (xy 332.22438 -284.90291) (xy 332.17358 -284.90291)
			(xy 332.17358 -285.1658) (xy 332.22438 -285.1658)
		)
		(stroke
			(width 0)
			(type solid)
		)
		(fill yes)
		(layer "F.Cu")
		(net "M_A_CPU0_SA_DQ<1>")
	)
	(gr_poly
		(pts
			(xy 332.32598 -284.532832) (xy 332.32598 -284.342332) (xy 332.22438 -284.30601) (xy 332.17358 -284.30601)
			(xy 332.17358 -284.5689) (xy 332.22438 -284.5689)
		)
		(stroke
			(width 0)
			(type solid)
		)
		(fill yes)
		(layer "F.Cu")
		(net "M_A_CPU0_SA_DQ<1>")
	)
	(gr_poly
		(pts
			(xy 332.32598 -283.935932) (xy 332.32598 -283.745432) (xy 332.22438 -283.70911) (xy 332.17358 -283.70911)
			(xy 332.17358 -283.972) (xy 332.22438 -283.972)
		)
		(stroke
			(width 0)
			(type solid)
		)
		(fill yes)
		(layer "F.Cu")
		(net "M_A_CPU0_SA_DQ<1>")
	)
	(gr_poly
		(pts
			(xy 332.32598 -283.339032) (xy 332.32598 -283.148532) (xy 332.22438 -283.11221) (xy 332.17358 -283.11221)
			(xy 332.17358 -283.3751) (xy 332.22438 -283.3751)
		)
		(stroke
			(width 0)
			(type solid)
		)
		(fill yes)
		(layer "F.Cu")
		(net "M_A_CPU0_SA_DQ<1>")
	)
	(gr_poly
		(pts
			(xy 332.350364 -275.440648) (xy 332.314296 -275.404834) (xy 332.217014 -275.358606) (xy 332.08214 -275.493226)
			(xy 332.128368 -275.590762) (xy 332.164436 -275.626576)
		)
		(stroke
			(width 0)
			(type solid)
		)
		(fill yes)
		(layer "F.Cu")
		(net "M_A_CPU0_SA_DQ<16>")
	)
	(gr_poly
		(pts
			(xy 332.366874 -282.29687) (xy 332.404212 -282.109926) (xy 332.311756 -282.054554) (xy 332.261972 -282.044648)
			(xy 332.21041 -282.302458) (xy 332.260194 -282.312364)
		)
		(stroke
			(width 0)
			(type solid)
		)
		(fill yes)
		(layer "F.Cu")
		(net "M_A_CPU0_SA_DQ<1>")
	)
	(gr_poly
		(pts
			(xy 332.388972 -217.80119) (xy 332.338172 -217.80119) (xy 332.236572 -217.837258) (xy 332.236572 -218.027758)
			(xy 332.338172 -218.063826) (xy 332.388972 -218.063826)
		)
		(stroke
			(width 0)
			(type solid)
		)
		(fill yes)
		(layer "F.Cu")
		(net "M_A_CPU0_SB_DQ<29>")
	)
	(gr_poly
		(pts
			(xy 332.388972 -217.20429) (xy 332.338172 -217.20429) (xy 332.236572 -217.240358) (xy 332.236572 -217.430858)
			(xy 332.338172 -217.466926) (xy 332.388972 -217.466926)
		)
		(stroke
			(width 0)
			(type solid)
		)
		(fill yes)
		(layer "F.Cu")
		(net "M_A_CPU0_SB_DQ<29>")
	)
	(gr_poly
		(pts
			(xy 332.388972 -216.60739) (xy 332.338172 -216.60739) (xy 332.236572 -216.643458) (xy 332.236572 -216.833958)
			(xy 332.338172 -216.870026) (xy 332.388972 -216.870026)
		)
		(stroke
			(width 0)
			(type solid)
		)
		(fill yes)
		(layer "F.Cu")
		(net "M_A_CPU0_SB_DQ<29>")
	)
	(gr_poly
		(pts
			(xy 332.47838 -296.54246) (xy 332.42758 -296.54246) (xy 332.32598 -296.578782) (xy 332.32598 -296.769282)
			(xy 332.42758 -296.80535) (xy 332.47838 -296.80535)
		)
		(stroke
			(width 0)
			(type solid)
		)
		(fill yes)
		(layer "F.Cu")
		(net "M_A_CPU0_SA_DQ<2>")
	)
	(gr_poly
		(pts
			(xy 332.47838 -295.94556) (xy 332.42758 -295.94556) (xy 332.32598 -295.981882) (xy 332.32598 -296.172382)
			(xy 332.42758 -296.20845) (xy 332.47838 -296.20845)
		)
		(stroke
			(width 0)
			(type solid)
		)
		(fill yes)
		(layer "F.Cu")
		(net "M_A_CPU0_SA_DQ<2>")
	)
	(gr_poly
		(pts
			(xy 332.47838 -295.34866) (xy 332.42758 -295.34866) (xy 332.32598 -295.384982) (xy 332.32598 -295.575482)
			(xy 332.42758 -295.61155) (xy 332.47838 -295.61155)
		)
		(stroke
			(width 0)
			(type solid)
		)
		(fill yes)
		(layer "F.Cu")
		(net "M_A_CPU0_SA_DQ<2>")
	)
	(gr_poly
		(pts
			(xy 332.47838 -294.75176) (xy 332.42758 -294.75176) (xy 332.32598 -294.788082) (xy 332.32598 -294.978582)
			(xy 332.42758 -295.01465) (xy 332.47838 -295.01465)
		)
		(stroke
			(width 0)
			(type solid)
		)
		(fill yes)
		(layer "F.Cu")
		(net "M_A_CPU0_SA_DQ<2>")
	)
	(gr_poly
		(pts
			(xy 332.47838 -294.15486) (xy 332.42758 -294.15486) (xy 332.32598 -294.191182) (xy 332.32598 -294.381682)
			(xy 332.42758 -294.41775) (xy 332.47838 -294.41775)
		)
		(stroke
			(width 0)
			(type solid)
		)
		(fill yes)
		(layer "F.Cu")
		(net "M_A_CPU0_SA_DQ<2>")
	)
	(gr_poly
		(pts
			(xy 332.47838 -293.55796) (xy 332.42758 -293.55796) (xy 332.32598 -293.594282) (xy 332.32598 -293.784782)
			(xy 332.42758 -293.82085) (xy 332.47838 -293.82085)
		)
		(stroke
			(width 0)
			(type solid)
		)
		(fill yes)
		(layer "F.Cu")
		(net "M_A_CPU0_SA_DQ<2>")
	)
	(gr_poly
		(pts
			(xy 332.47838 -292.96106) (xy 332.42758 -292.96106) (xy 332.32598 -292.997382) (xy 332.32598 -293.187882)
			(xy 332.42758 -293.22395) (xy 332.47838 -293.22395)
		)
		(stroke
			(width 0)
			(type solid)
		)
		(fill yes)
		(layer "F.Cu")
		(net "M_A_CPU0_SA_DQ<2>")
	)
	(gr_poly
		(pts
			(xy 332.47838 -292.36416) (xy 332.42758 -292.36416) (xy 332.32598 -292.400482) (xy 332.32598 -292.590982)
			(xy 332.42758 -292.62705) (xy 332.47838 -292.62705)
		)
		(stroke
			(width 0)
			(type solid)
		)
		(fill yes)
		(layer "F.Cu")
		(net "M_A_CPU0_SA_DQ<2>")
	)
	(gr_poly
		(pts
			(xy 332.47838 -291.76726) (xy 332.42758 -291.76726) (xy 332.32598 -291.803582) (xy 332.32598 -291.994082)
			(xy 332.42758 -292.03015) (xy 332.47838 -292.03015)
		)
		(stroke
			(width 0)
			(type solid)
		)
		(fill yes)
		(layer "F.Cu")
		(net "M_A_CPU0_SA_DQ<2>")
	)
	(gr_poly
		(pts
			(xy 332.47838 -291.17036) (xy 332.42758 -291.17036) (xy 332.32598 -291.206682) (xy 332.32598 -291.397182)
			(xy 332.42758 -291.43325) (xy 332.47838 -291.43325)
		)
		(stroke
			(width 0)
			(type solid)
		)
		(fill yes)
		(layer "F.Cu")
		(net "M_A_CPU0_SA_DQ<2>")
	)
	(gr_poly
		(pts
			(xy 332.47838 -290.57346) (xy 332.42758 -290.57346) (xy 332.32598 -290.609782) (xy 332.32598 -290.800282)
			(xy 332.42758 -290.83635) (xy 332.47838 -290.83635)
		)
		(stroke
			(width 0)
			(type solid)
		)
		(fill yes)
		(layer "F.Cu")
		(net "M_A_CPU0_SA_DQ<2>")
	)
	(gr_poly
		(pts
			(xy 332.47838 -289.97656) (xy 332.42758 -289.97656) (xy 332.32598 -290.012882) (xy 332.32598 -290.203382)
			(xy 332.42758 -290.23945) (xy 332.47838 -290.23945)
		)
		(stroke
			(width 0)
			(type solid)
		)
		(fill yes)
		(layer "F.Cu")
		(net "M_A_CPU0_SA_DQ<2>")
	)
	(gr_poly
		(pts
			(xy 332.47838 -289.37966) (xy 332.42758 -289.37966) (xy 332.32598 -289.415982) (xy 332.32598 -289.606482)
			(xy 332.42758 -289.64255) (xy 332.47838 -289.64255)
		)
		(stroke
			(width 0)
			(type solid)
		)
		(fill yes)
		(layer "F.Cu")
		(net "M_A_CPU0_SA_DQ<2>")
	)
	(gr_poly
		(pts
			(xy 332.47838 -288.78276) (xy 332.42758 -288.78276) (xy 332.32598 -288.819082) (xy 332.32598 -289.009582)
			(xy 332.42758 -289.04565) (xy 332.47838 -289.04565)
		)
		(stroke
			(width 0)
			(type solid)
		)
		(fill yes)
		(layer "F.Cu")
		(net "M_A_CPU0_SA_DQ<2>")
	)
	(gr_poly
		(pts
			(xy 332.47838 -288.18586) (xy 332.42758 -288.18586) (xy 332.32598 -288.222182) (xy 332.32598 -288.412682)
			(xy 332.42758 -288.44875) (xy 332.47838 -288.44875)
		)
		(stroke
			(width 0)
			(type solid)
		)
		(fill yes)
		(layer "F.Cu")
		(net "M_A_CPU0_SA_DQ<2>")
	)
	(gr_poly
		(pts
			(xy 332.47838 -287.58896) (xy 332.42758 -287.58896) (xy 332.32598 -287.625282) (xy 332.32598 -287.815782)
			(xy 332.42758 -287.85185) (xy 332.47838 -287.85185)
		)
		(stroke
			(width 0)
			(type solid)
		)
		(fill yes)
		(layer "F.Cu")
		(net "M_A_CPU0_SA_DQ<2>")
	)
	(gr_poly
		(pts
			(xy 332.47838 -286.99206) (xy 332.42758 -286.99206) (xy 332.32598 -287.028382) (xy 332.32598 -287.218882)
			(xy 332.42758 -287.25495) (xy 332.47838 -287.25495)
		)
		(stroke
			(width 0)
			(type solid)
		)
		(fill yes)
		(layer "F.Cu")
		(net "M_A_CPU0_SA_DQ<2>")
	)
	(gr_poly
		(pts
			(xy 332.47838 -286.39516) (xy 332.42758 -286.39516) (xy 332.32598 -286.431482) (xy 332.32598 -286.621982)
			(xy 332.42758 -286.65805) (xy 332.47838 -286.65805)
		)
		(stroke
			(width 0)
			(type solid)
		)
		(fill yes)
		(layer "F.Cu")
		(net "M_A_CPU0_SA_DQ<2>")
	)
	(gr_poly
		(pts
			(xy 332.47838 -285.79826) (xy 332.42758 -285.79826) (xy 332.32598 -285.834582) (xy 332.32598 -286.025082)
			(xy 332.42758 -286.06115) (xy 332.47838 -286.06115)
		)
		(stroke
			(width 0)
			(type solid)
		)
		(fill yes)
		(layer "F.Cu")
		(net "M_A_CPU0_SA_DQ<2>")
	)
	(gr_poly
		(pts
			(xy 332.47838 -285.20136) (xy 332.42758 -285.20136) (xy 332.32598 -285.237682) (xy 332.32598 -285.428182)
			(xy 332.42758 -285.46425) (xy 332.47838 -285.46425)
		)
		(stroke
			(width 0)
			(type solid)
		)
		(fill yes)
		(layer "F.Cu")
		(net "M_A_CPU0_SA_DQ<2>")
	)
	(gr_poly
		(pts
			(xy 332.47838 -284.60446) (xy 332.42758 -284.60446) (xy 332.32598 -284.640782) (xy 332.32598 -284.831282)
			(xy 332.42758 -284.86735) (xy 332.47838 -284.86735)
		)
		(stroke
			(width 0)
			(type solid)
		)
		(fill yes)
		(layer "F.Cu")
		(net "M_A_CPU0_SA_DQ<2>")
	)
	(gr_poly
		(pts
			(xy 332.47838 -284.00756) (xy 332.42758 -284.00756) (xy 332.32598 -284.043882) (xy 332.32598 -284.234382)
			(xy 332.42758 -284.27045) (xy 332.47838 -284.27045)
		)
		(stroke
			(width 0)
			(type solid)
		)
		(fill yes)
		(layer "F.Cu")
		(net "M_A_CPU0_SA_DQ<2>")
	)
	(gr_poly
		(pts
			(xy 332.47838 -283.41066) (xy 332.42758 -283.41066) (xy 332.32598 -283.446982) (xy 332.32598 -283.637482)
			(xy 332.42758 -283.67355) (xy 332.47838 -283.67355)
		)
		(stroke
			(width 0)
			(type solid)
		)
		(fill yes)
		(layer "F.Cu")
		(net "M_A_CPU0_SA_DQ<2>")
	)
	(gr_poly
		(pts
			(xy 332.47838 -282.81376) (xy 332.42758 -282.81376) (xy 332.32598 -282.850082) (xy 332.32598 -283.040582)
			(xy 332.42758 -283.07665) (xy 332.47838 -283.07665)
		)
		(stroke
			(width 0)
			(type solid)
		)
		(fill yes)
		(layer "F.Cu")
		(net "M_A_CPU0_SA_DQ<2>")
	)
	(gr_poly
		(pts
			(xy 332.483968 -281.7114) (xy 332.521306 -281.52471) (xy 332.42885 -281.469338) (xy 332.378812 -281.459432)
			(xy 332.327504 -281.716988) (xy 332.377288 -281.727148)
		)
		(stroke
			(width 0)
			(type solid)
		)
		(fill yes)
		(layer "F.Cu")
		(net "M_A_CPU0_SA_DQ<1>")
	)
	(gr_poly
		(pts
			(xy 332.541372 -218.326208) (xy 332.541372 -218.135708) (xy 332.439772 -218.099386) (xy 332.388972 -218.099386)
			(xy 332.388972 -218.36253) (xy 332.439772 -218.36253)
		)
		(stroke
			(width 0)
			(type solid)
		)
		(fill yes)
		(layer "F.Cu")
		(net "M_A_CPU0_SB_DQ<29>")
	)
	(gr_poly
		(pts
			(xy 332.541372 -217.729308) (xy 332.541372 -217.538808) (xy 332.439772 -217.502486) (xy 332.388972 -217.502486)
			(xy 332.388972 -217.76563) (xy 332.439772 -217.76563)
		)
		(stroke
			(width 0)
			(type solid)
		)
		(fill yes)
		(layer "F.Cu")
		(net "M_A_CPU0_SB_DQ<29>")
	)
	(gr_poly
		(pts
			(xy 332.541372 -217.132408) (xy 332.541372 -216.941908) (xy 332.439772 -216.905586) (xy 332.388972 -216.905586)
			(xy 332.388972 -217.16873) (xy 332.439772 -217.16873)
		)
		(stroke
			(width 0)
			(type solid)
		)
		(fill yes)
		(layer "F.Cu")
		(net "M_A_CPU0_SB_DQ<29>")
	)
	(gr_poly
		(pts
			(xy 332.541372 -216.535508) (xy 332.541372 -216.345008) (xy 332.439772 -216.308686) (xy 332.388972 -216.308686)
			(xy 332.388972 -216.57183) (xy 332.439772 -216.57183)
		)
		(stroke
			(width 0)
			(type solid)
		)
		(fill yes)
		(layer "F.Cu")
		(net "M_A_CPU0_SB_DQ<29>")
	)
	(gr_poly
		(pts
			(xy 332.62189 -281.812238) (xy 332.572106 -281.802332) (xy 332.465426 -281.817826) (xy 332.428088 -282.00477)
			(xy 332.520544 -282.060142) (xy 332.570328 -282.070048)
		)
		(stroke
			(width 0)
			(type solid)
		)
		(fill yes)
		(layer "F.Cu")
		(net "M_A_CPU0_SA_DQ<2>")
	)
	(gr_poly
		(pts
			(xy 332.63078 -296.470832) (xy 332.63078 -296.280332) (xy 332.52918 -296.24401) (xy 332.47838 -296.24401)
			(xy 332.47838 -296.5069) (xy 332.52918 -296.5069)
		)
		(stroke
			(width 0)
			(type solid)
		)
		(fill yes)
		(layer "F.Cu")
		(net "M_A_CPU0_SA_DQ<2>")
	)
	(gr_poly
		(pts
			(xy 332.63078 -295.873932) (xy 332.63078 -295.683432) (xy 332.52918 -295.64711) (xy 332.47838 -295.64711)
			(xy 332.47838 -295.91) (xy 332.52918 -295.91)
		)
		(stroke
			(width 0)
			(type solid)
		)
		(fill yes)
		(layer "F.Cu")
		(net "M_A_CPU0_SA_DQ<2>")
	)
	(gr_poly
		(pts
			(xy 332.63078 -295.277032) (xy 332.63078 -295.086532) (xy 332.52918 -295.05021) (xy 332.47838 -295.05021)
			(xy 332.47838 -295.3131) (xy 332.52918 -295.3131)
		)
		(stroke
			(width 0)
			(type solid)
		)
		(fill yes)
		(layer "F.Cu")
		(net "M_A_CPU0_SA_DQ<2>")
	)
	(gr_poly
		(pts
			(xy 332.63078 -294.680132) (xy 332.63078 -294.489632) (xy 332.52918 -294.45331) (xy 332.47838 -294.45331)
			(xy 332.47838 -294.7162) (xy 332.52918 -294.7162)
		)
		(stroke
			(width 0)
			(type solid)
		)
		(fill yes)
		(layer "F.Cu")
		(net "M_A_CPU0_SA_DQ<2>")
	)
	(gr_poly
		(pts
			(xy 332.63078 -294.083232) (xy 332.63078 -293.892732) (xy 332.52918 -293.85641) (xy 332.47838 -293.85641)
			(xy 332.47838 -294.1193) (xy 332.52918 -294.1193)
		)
		(stroke
			(width 0)
			(type solid)
		)
		(fill yes)
		(layer "F.Cu")
		(net "M_A_CPU0_SA_DQ<2>")
	)
	(gr_poly
		(pts
			(xy 332.63078 -293.486332) (xy 332.63078 -293.295832) (xy 332.52918 -293.25951) (xy 332.47838 -293.25951)
			(xy 332.47838 -293.5224) (xy 332.52918 -293.5224)
		)
		(stroke
			(width 0)
			(type solid)
		)
		(fill yes)
		(layer "F.Cu")
		(net "M_A_CPU0_SA_DQ<2>")
	)
	(gr_poly
		(pts
			(xy 332.63078 -292.889432) (xy 332.63078 -292.698932) (xy 332.52918 -292.66261) (xy 332.47838 -292.66261)
			(xy 332.47838 -292.9255) (xy 332.52918 -292.9255)
		)
		(stroke
			(width 0)
			(type solid)
		)
		(fill yes)
		(layer "F.Cu")
		(net "M_A_CPU0_SA_DQ<2>")
	)
	(gr_poly
		(pts
			(xy 332.63078 -292.292532) (xy 332.63078 -292.102032) (xy 332.52918 -292.06571) (xy 332.47838 -292.06571)
			(xy 332.47838 -292.3286) (xy 332.52918 -292.3286)
		)
		(stroke
			(width 0)
			(type solid)
		)
		(fill yes)
		(layer "F.Cu")
		(net "M_A_CPU0_SA_DQ<2>")
	)
	(gr_poly
		(pts
			(xy 332.63078 -291.695632) (xy 332.63078 -291.505132) (xy 332.52918 -291.46881) (xy 332.47838 -291.46881)
			(xy 332.47838 -291.7317) (xy 332.52918 -291.7317)
		)
		(stroke
			(width 0)
			(type solid)
		)
		(fill yes)
		(layer "F.Cu")
		(net "M_A_CPU0_SA_DQ<2>")
	)
	(gr_poly
		(pts
			(xy 332.63078 -291.098732) (xy 332.63078 -290.908232) (xy 332.52918 -290.87191) (xy 332.47838 -290.87191)
			(xy 332.47838 -291.1348) (xy 332.52918 -291.1348)
		)
		(stroke
			(width 0)
			(type solid)
		)
		(fill yes)
		(layer "F.Cu")
		(net "M_A_CPU0_SA_DQ<2>")
	)
	(gr_poly
		(pts
			(xy 332.63078 -290.501832) (xy 332.63078 -290.311332) (xy 332.52918 -290.27501) (xy 332.47838 -290.27501)
			(xy 332.47838 -290.5379) (xy 332.52918 -290.5379)
		)
		(stroke
			(width 0)
			(type solid)
		)
		(fill yes)
		(layer "F.Cu")
		(net "M_A_CPU0_SA_DQ<2>")
	)
	(gr_poly
		(pts
			(xy 332.63078 -289.904932) (xy 332.63078 -289.714432) (xy 332.52918 -289.67811) (xy 332.47838 -289.67811)
			(xy 332.47838 -289.941) (xy 332.52918 -289.941)
		)
		(stroke
			(width 0)
			(type solid)
		)
		(fill yes)
		(layer "F.Cu")
		(net "M_A_CPU0_SA_DQ<2>")
	)
	(gr_poly
		(pts
			(xy 332.63078 -289.308032) (xy 332.63078 -289.117532) (xy 332.52918 -289.08121) (xy 332.47838 -289.08121)
			(xy 332.47838 -289.3441) (xy 332.52918 -289.3441)
		)
		(stroke
			(width 0)
			(type solid)
		)
		(fill yes)
		(layer "F.Cu")
		(net "M_A_CPU0_SA_DQ<2>")
	)
	(gr_poly
		(pts
			(xy 332.63078 -288.711132) (xy 332.63078 -288.520632) (xy 332.52918 -288.48431) (xy 332.47838 -288.48431)
			(xy 332.47838 -288.7472) (xy 332.52918 -288.7472)
		)
		(stroke
			(width 0)
			(type solid)
		)
		(fill yes)
		(layer "F.Cu")
		(net "M_A_CPU0_SA_DQ<2>")
	)
	(gr_poly
		(pts
			(xy 332.63078 -288.114232) (xy 332.63078 -287.923732) (xy 332.52918 -287.88741) (xy 332.47838 -287.88741)
			(xy 332.47838 -288.1503) (xy 332.52918 -288.1503)
		)
		(stroke
			(width 0)
			(type solid)
		)
		(fill yes)
		(layer "F.Cu")
		(net "M_A_CPU0_SA_DQ<2>")
	)
	(gr_poly
		(pts
			(xy 332.63078 -287.517332) (xy 332.63078 -287.326832) (xy 332.52918 -287.29051) (xy 332.47838 -287.29051)
			(xy 332.47838 -287.5534) (xy 332.52918 -287.5534)
		)
		(stroke
			(width 0)
			(type solid)
		)
		(fill yes)
		(layer "F.Cu")
		(net "M_A_CPU0_SA_DQ<2>")
	)
	(gr_poly
		(pts
			(xy 332.63078 -286.920432) (xy 332.63078 -286.729932) (xy 332.52918 -286.69361) (xy 332.47838 -286.69361)
			(xy 332.47838 -286.9565) (xy 332.52918 -286.9565)
		)
		(stroke
			(width 0)
			(type solid)
		)
		(fill yes)
		(layer "F.Cu")
		(net "M_A_CPU0_SA_DQ<2>")
	)
	(gr_poly
		(pts
			(xy 332.63078 -286.323532) (xy 332.63078 -286.133032) (xy 332.52918 -286.09671) (xy 332.47838 -286.09671)
			(xy 332.47838 -286.3596) (xy 332.52918 -286.3596)
		)
		(stroke
			(width 0)
			(type solid)
		)
		(fill yes)
		(layer "F.Cu")
		(net "M_A_CPU0_SA_DQ<2>")
	)
	(gr_poly
		(pts
			(xy 332.63078 -285.726632) (xy 332.63078 -285.536132) (xy 332.52918 -285.49981) (xy 332.47838 -285.49981)
			(xy 332.47838 -285.7627) (xy 332.52918 -285.7627)
		)
		(stroke
			(width 0)
			(type solid)
		)
		(fill yes)
		(layer "F.Cu")
		(net "M_A_CPU0_SA_DQ<2>")
	)
	(gr_poly
		(pts
			(xy 332.63078 -285.129732) (xy 332.63078 -284.939232) (xy 332.52918 -284.90291) (xy 332.47838 -284.90291)
			(xy 332.47838 -285.1658) (xy 332.52918 -285.1658)
		)
		(stroke
			(width 0)
			(type solid)
		)
		(fill yes)
		(layer "F.Cu")
		(net "M_A_CPU0_SA_DQ<2>")
	)
	(gr_poly
		(pts
			(xy 332.63078 -284.532832) (xy 332.63078 -284.342332) (xy 332.52918 -284.30601) (xy 332.47838 -284.30601)
			(xy 332.47838 -284.5689) (xy 332.52918 -284.5689)
		)
		(stroke
			(width 0)
			(type solid)
		)
		(fill yes)
		(layer "F.Cu")
		(net "M_A_CPU0_SA_DQ<2>")
	)
	(gr_poly
		(pts
			(xy 332.63078 -283.935932) (xy 332.63078 -283.745432) (xy 332.52918 -283.70911) (xy 332.47838 -283.70911)
			(xy 332.47838 -283.972) (xy 332.52918 -283.972)
		)
		(stroke
			(width 0)
			(type solid)
		)
		(fill yes)
		(layer "F.Cu")
		(net "M_A_CPU0_SA_DQ<2>")
	)
	(gr_poly
		(pts
			(xy 332.63078 -283.339032) (xy 332.63078 -283.148532) (xy 332.52918 -283.11221) (xy 332.47838 -283.11221)
			(xy 332.47838 -283.3751) (xy 332.52918 -283.3751)
		)
		(stroke
			(width 0)
			(type solid)
		)
		(fill yes)
		(layer "F.Cu")
		(net "M_A_CPU0_SA_DQ<2>")
	)
	(gr_poly
		(pts
			(xy 332.668118 -282.357322) (xy 332.70571 -282.170378) (xy 332.613254 -282.115006) (xy 332.56347 -282.104846)
			(xy 332.511654 -282.362656) (xy 332.561438 -282.372816)
		)
		(stroke
			(width 0)
			(type solid)
		)
		(fill yes)
		(layer "F.Cu")
		(net "M_A_CPU0_SA_DQ<2>")
	)
	(gr_poly
		(pts
			(xy 332.693772 -217.80119) (xy 332.642972 -217.80119) (xy 332.541372 -217.837258) (xy 332.541372 -218.027758)
			(xy 332.642972 -218.063826) (xy 332.693772 -218.063826)
		)
		(stroke
			(width 0)
			(type solid)
		)
		(fill yes)
		(layer "F.Cu")
		(net "M_A_CPU0_SB_DQ<31>")
	)
	(gr_poly
		(pts
			(xy 332.693772 -217.20429) (xy 332.642972 -217.20429) (xy 332.541372 -217.240358) (xy 332.541372 -217.430858)
			(xy 332.642972 -217.466926) (xy 332.693772 -217.466926)
		)
		(stroke
			(width 0)
			(type solid)
		)
		(fill yes)
		(layer "F.Cu")
		(net "M_A_CPU0_SB_DQ<31>")
	)
	(gr_poly
		(pts
			(xy 332.693772 -216.60739) (xy 332.642972 -216.60739) (xy 332.541372 -216.643458) (xy 332.541372 -216.833958)
			(xy 332.642972 -216.870026) (xy 332.693772 -216.870026)
		)
		(stroke
			(width 0)
			(type solid)
		)
		(fill yes)
		(layer "F.Cu")
		(net "M_A_CPU0_SB_DQ<31>")
	)
	(gr_poly
		(pts
			(xy 332.78318 -296.54246) (xy 332.73238 -296.54246) (xy 332.63078 -296.578782) (xy 332.63078 -296.769282)
			(xy 332.73238 -296.80535) (xy 332.78318 -296.80535)
		)
		(stroke
			(width 0)
			(type solid)
		)
		(fill yes)
		(layer "F.Cu")
		(net "M_A_CPU0_SA_DQ<0>")
	)
	(gr_poly
		(pts
			(xy 332.78318 -295.94556) (xy 332.73238 -295.94556) (xy 332.63078 -295.981882) (xy 332.63078 -296.172382)
			(xy 332.73238 -296.20845) (xy 332.78318 -296.20845)
		)
		(stroke
			(width 0)
			(type solid)
		)
		(fill yes)
		(layer "F.Cu")
		(net "M_A_CPU0_SA_DQ<0>")
	)
	(gr_poly
		(pts
			(xy 332.78318 -295.34866) (xy 332.73238 -295.34866) (xy 332.63078 -295.384982) (xy 332.63078 -295.575482)
			(xy 332.73238 -295.61155) (xy 332.78318 -295.61155)
		)
		(stroke
			(width 0)
			(type solid)
		)
		(fill yes)
		(layer "F.Cu")
		(net "M_A_CPU0_SA_DQ<0>")
	)
	(gr_poly
		(pts
			(xy 332.78318 -294.75176) (xy 332.73238 -294.75176) (xy 332.63078 -294.788082) (xy 332.63078 -294.978582)
			(xy 332.73238 -295.01465) (xy 332.78318 -295.01465)
		)
		(stroke
			(width 0)
			(type solid)
		)
		(fill yes)
		(layer "F.Cu")
		(net "M_A_CPU0_SA_DQ<0>")
	)
	(gr_poly
		(pts
			(xy 332.78318 -294.15486) (xy 332.73238 -294.15486) (xy 332.63078 -294.191182) (xy 332.63078 -294.381682)
			(xy 332.73238 -294.41775) (xy 332.78318 -294.41775)
		)
		(stroke
			(width 0)
			(type solid)
		)
		(fill yes)
		(layer "F.Cu")
		(net "M_A_CPU0_SA_DQ<0>")
	)
	(gr_poly
		(pts
			(xy 332.78318 -293.55796) (xy 332.73238 -293.55796) (xy 332.63078 -293.594282) (xy 332.63078 -293.784782)
			(xy 332.73238 -293.82085) (xy 332.78318 -293.82085)
		)
		(stroke
			(width 0)
			(type solid)
		)
		(fill yes)
		(layer "F.Cu")
		(net "M_A_CPU0_SA_DQ<0>")
	)
	(gr_poly
		(pts
			(xy 332.78318 -292.96106) (xy 332.73238 -292.96106) (xy 332.63078 -292.997382) (xy 332.63078 -293.187882)
			(xy 332.73238 -293.22395) (xy 332.78318 -293.22395)
		)
		(stroke
			(width 0)
			(type solid)
		)
		(fill yes)
		(layer "F.Cu")
		(net "M_A_CPU0_SA_DQ<0>")
	)
	(gr_poly
		(pts
			(xy 332.78318 -292.36416) (xy 332.73238 -292.36416) (xy 332.63078 -292.400482) (xy 332.63078 -292.590982)
			(xy 332.73238 -292.62705) (xy 332.78318 -292.62705)
		)
		(stroke
			(width 0)
			(type solid)
		)
		(fill yes)
		(layer "F.Cu")
		(net "M_A_CPU0_SA_DQ<0>")
	)
	(gr_poly
		(pts
			(xy 332.78318 -291.76726) (xy 332.73238 -291.76726) (xy 332.63078 -291.803582) (xy 332.63078 -291.994082)
			(xy 332.73238 -292.03015) (xy 332.78318 -292.03015)
		)
		(stroke
			(width 0)
			(type solid)
		)
		(fill yes)
		(layer "F.Cu")
		(net "M_A_CPU0_SA_DQ<0>")
	)
	(gr_poly
		(pts
			(xy 332.78318 -291.17036) (xy 332.73238 -291.17036) (xy 332.63078 -291.206682) (xy 332.63078 -291.397182)
			(xy 332.73238 -291.43325) (xy 332.78318 -291.43325)
		)
		(stroke
			(width 0)
			(type solid)
		)
		(fill yes)
		(layer "F.Cu")
		(net "M_A_CPU0_SA_DQ<0>")
	)
	(gr_poly
		(pts
			(xy 332.78318 -290.57346) (xy 332.73238 -290.57346) (xy 332.63078 -290.609782) (xy 332.63078 -290.800282)
			(xy 332.73238 -290.83635) (xy 332.78318 -290.83635)
		)
		(stroke
			(width 0)
			(type solid)
		)
		(fill yes)
		(layer "F.Cu")
		(net "M_A_CPU0_SA_DQ<0>")
	)
	(gr_poly
		(pts
			(xy 332.78318 -289.97656) (xy 332.73238 -289.97656) (xy 332.63078 -290.012882) (xy 332.63078 -290.203382)
			(xy 332.73238 -290.23945) (xy 332.78318 -290.23945)
		)
		(stroke
			(width 0)
			(type solid)
		)
		(fill yes)
		(layer "F.Cu")
		(net "M_A_CPU0_SA_DQ<0>")
	)
	(gr_poly
		(pts
			(xy 332.78318 -289.37966) (xy 332.73238 -289.37966) (xy 332.63078 -289.415982) (xy 332.63078 -289.606482)
			(xy 332.73238 -289.64255) (xy 332.78318 -289.64255)
		)
		(stroke
			(width 0)
			(type solid)
		)
		(fill yes)
		(layer "F.Cu")
		(net "M_A_CPU0_SA_DQ<0>")
	)
	(gr_poly
		(pts
			(xy 332.78318 -288.78276) (xy 332.73238 -288.78276) (xy 332.63078 -288.819082) (xy 332.63078 -289.009582)
			(xy 332.73238 -289.04565) (xy 332.78318 -289.04565)
		)
		(stroke
			(width 0)
			(type solid)
		)
		(fill yes)
		(layer "F.Cu")
		(net "M_A_CPU0_SA_DQ<0>")
	)
	(gr_poly
		(pts
			(xy 332.78318 -288.18586) (xy 332.73238 -288.18586) (xy 332.63078 -288.222182) (xy 332.63078 -288.412682)
			(xy 332.73238 -288.44875) (xy 332.78318 -288.44875)
		)
		(stroke
			(width 0)
			(type solid)
		)
		(fill yes)
		(layer "F.Cu")
		(net "M_A_CPU0_SA_DQ<0>")
	)
	(gr_poly
		(pts
			(xy 332.78318 -287.58896) (xy 332.73238 -287.58896) (xy 332.63078 -287.625282) (xy 332.63078 -287.815782)
			(xy 332.73238 -287.85185) (xy 332.78318 -287.85185)
		)
		(stroke
			(width 0)
			(type solid)
		)
		(fill yes)
		(layer "F.Cu")
		(net "M_A_CPU0_SA_DQ<0>")
	)
	(gr_poly
		(pts
			(xy 332.78318 -286.99206) (xy 332.73238 -286.99206) (xy 332.63078 -287.028382) (xy 332.63078 -287.218882)
			(xy 332.73238 -287.25495) (xy 332.78318 -287.25495)
		)
		(stroke
			(width 0)
			(type solid)
		)
		(fill yes)
		(layer "F.Cu")
		(net "M_A_CPU0_SA_DQ<0>")
	)
	(gr_poly
		(pts
			(xy 332.78318 -286.39516) (xy 332.73238 -286.39516) (xy 332.63078 -286.431482) (xy 332.63078 -286.621982)
			(xy 332.73238 -286.65805) (xy 332.78318 -286.65805)
		)
		(stroke
			(width 0)
			(type solid)
		)
		(fill yes)
		(layer "F.Cu")
		(net "M_A_CPU0_SA_DQ<0>")
	)
	(gr_poly
		(pts
			(xy 332.78318 -285.79826) (xy 332.73238 -285.79826) (xy 332.63078 -285.834582) (xy 332.63078 -286.025082)
			(xy 332.73238 -286.06115) (xy 332.78318 -286.06115)
		)
		(stroke
			(width 0)
			(type solid)
		)
		(fill yes)
		(layer "F.Cu")
		(net "M_A_CPU0_SA_DQ<0>")
	)
	(gr_poly
		(pts
			(xy 332.78318 -285.20136) (xy 332.73238 -285.20136) (xy 332.63078 -285.237682) (xy 332.63078 -285.428182)
			(xy 332.73238 -285.46425) (xy 332.78318 -285.46425)
		)
		(stroke
			(width 0)
			(type solid)
		)
		(fill yes)
		(layer "F.Cu")
		(net "M_A_CPU0_SA_DQ<0>")
	)
	(gr_poly
		(pts
			(xy 332.78318 -284.60446) (xy 332.73238 -284.60446) (xy 332.63078 -284.640782) (xy 332.63078 -284.831282)
			(xy 332.73238 -284.86735) (xy 332.78318 -284.86735)
		)
		(stroke
			(width 0)
			(type solid)
		)
		(fill yes)
		(layer "F.Cu")
		(net "M_A_CPU0_SA_DQ<0>")
	)
	(gr_poly
		(pts
			(xy 332.78318 -284.00756) (xy 332.73238 -284.00756) (xy 332.63078 -284.043882) (xy 332.63078 -284.234382)
			(xy 332.73238 -284.27045) (xy 332.78318 -284.27045)
		)
		(stroke
			(width 0)
			(type solid)
		)
		(fill yes)
		(layer "F.Cu")
		(net "M_A_CPU0_SA_DQ<0>")
	)
	(gr_poly
		(pts
			(xy 332.78318 -283.41066) (xy 332.73238 -283.41066) (xy 332.63078 -283.446982) (xy 332.63078 -283.637482)
			(xy 332.73238 -283.67355) (xy 332.78318 -283.67355)
		)
		(stroke
			(width 0)
			(type solid)
		)
		(fill yes)
		(layer "F.Cu")
		(net "M_A_CPU0_SA_DQ<0>")
	)
	(gr_poly
		(pts
			(xy 332.78318 -282.81376) (xy 332.73238 -282.81376) (xy 332.63078 -282.850082) (xy 332.63078 -283.040582)
			(xy 332.73238 -283.07665) (xy 332.78318 -283.07665)
		)
		(stroke
			(width 0)
			(type solid)
		)
		(fill yes)
		(layer "F.Cu")
		(net "M_A_CPU0_SA_DQ<0>")
	)
	(gr_poly
		(pts
			(xy 332.785466 -281.771852) (xy 332.823058 -281.585162) (xy 332.730602 -281.52979) (xy 332.680564 -281.51963)
			(xy 332.629002 -281.77744) (xy 332.678786 -281.787346)
		)
		(stroke
			(width 0)
			(type solid)
		)
		(fill yes)
		(layer "F.Cu")
		(net "M_A_CPU0_SA_DQ<2>")
	)
	(gr_poly
		(pts
			(xy 332.846172 -217.729308) (xy 332.846172 -217.538808) (xy 332.744572 -217.502486) (xy 332.693772 -217.502486)
			(xy 332.693772 -217.76563) (xy 332.744572 -217.76563)
		)
		(stroke
			(width 0)
			(type solid)
		)
		(fill yes)
		(layer "F.Cu")
		(net "M_A_CPU0_SB_DQ<31>")
	)
	(gr_poly
		(pts
			(xy 332.846172 -217.132408) (xy 332.846172 -216.941908) (xy 332.744572 -216.905586) (xy 332.693772 -216.905586)
			(xy 332.693772 -217.16873) (xy 332.744572 -217.16873)
		)
		(stroke
			(width 0)
			(type solid)
		)
		(fill yes)
		(layer "F.Cu")
		(net "M_A_CPU0_SB_DQ<31>")
	)
	(gr_poly
		(pts
			(xy 332.927706 -281.873452) (xy 332.877922 -281.863546) (xy 332.770988 -281.87904) (xy 332.73365 -282.06573)
			(xy 332.826106 -282.121356) (xy 332.87589 -282.131262)
		)
		(stroke
			(width 0)
			(type solid)
		)
		(fill yes)
		(layer "F.Cu")
		(net "M_A_CPU0_SA_DQ<0>")
	)
	(gr_poly
		(pts
			(xy 332.93558 -296.470832) (xy 332.93558 -296.280332) (xy 332.83398 -296.24401) (xy 332.78318 -296.24401)
			(xy 332.78318 -296.5069) (xy 332.83398 -296.5069)
		)
		(stroke
			(width 0)
			(type solid)
		)
		(fill yes)
		(layer "F.Cu")
		(net "M_A_CPU0_SA_DQ<0>")
	)
	(gr_poly
		(pts
			(xy 332.93558 -295.873932) (xy 332.93558 -295.683432) (xy 332.83398 -295.64711) (xy 332.78318 -295.64711)
			(xy 332.78318 -295.91) (xy 332.83398 -295.91)
		)
		(stroke
			(width 0)
			(type solid)
		)
		(fill yes)
		(layer "F.Cu")
		(net "M_A_CPU0_SA_DQ<0>")
	)
	(gr_poly
		(pts
			(xy 332.93558 -295.277032) (xy 332.93558 -295.086532) (xy 332.83398 -295.05021) (xy 332.78318 -295.05021)
			(xy 332.78318 -295.3131) (xy 332.83398 -295.3131)
		)
		(stroke
			(width 0)
			(type solid)
		)
		(fill yes)
		(layer "F.Cu")
		(net "M_A_CPU0_SA_DQ<0>")
	)
	(gr_poly
		(pts
			(xy 332.93558 -294.680132) (xy 332.93558 -294.489632) (xy 332.83398 -294.45331) (xy 332.78318 -294.45331)
			(xy 332.78318 -294.7162) (xy 332.83398 -294.7162)
		)
		(stroke
			(width 0)
			(type solid)
		)
		(fill yes)
		(layer "F.Cu")
		(net "M_A_CPU0_SA_DQ<0>")
	)
	(gr_poly
		(pts
			(xy 332.93558 -294.083232) (xy 332.93558 -293.892732) (xy 332.83398 -293.85641) (xy 332.78318 -293.85641)
			(xy 332.78318 -294.1193) (xy 332.83398 -294.1193)
		)
		(stroke
			(width 0)
			(type solid)
		)
		(fill yes)
		(layer "F.Cu")
		(net "M_A_CPU0_SA_DQ<0>")
	)
	(gr_poly
		(pts
			(xy 332.93558 -293.486332) (xy 332.93558 -293.295832) (xy 332.83398 -293.25951) (xy 332.78318 -293.25951)
			(xy 332.78318 -293.5224) (xy 332.83398 -293.5224)
		)
		(stroke
			(width 0)
			(type solid)
		)
		(fill yes)
		(layer "F.Cu")
		(net "M_A_CPU0_SA_DQ<0>")
	)
	(gr_poly
		(pts
			(xy 332.93558 -292.889432) (xy 332.93558 -292.698932) (xy 332.83398 -292.66261) (xy 332.78318 -292.66261)
			(xy 332.78318 -292.9255) (xy 332.83398 -292.9255)
		)
		(stroke
			(width 0)
			(type solid)
		)
		(fill yes)
		(layer "F.Cu")
		(net "M_A_CPU0_SA_DQ<0>")
	)
	(gr_poly
		(pts
			(xy 332.93558 -292.292532) (xy 332.93558 -292.102032) (xy 332.83398 -292.06571) (xy 332.78318 -292.06571)
			(xy 332.78318 -292.3286) (xy 332.83398 -292.3286)
		)
		(stroke
			(width 0)
			(type solid)
		)
		(fill yes)
		(layer "F.Cu")
		(net "M_A_CPU0_SA_DQ<0>")
	)
	(gr_poly
		(pts
			(xy 332.93558 -291.695632) (xy 332.93558 -291.505132) (xy 332.83398 -291.46881) (xy 332.78318 -291.46881)
			(xy 332.78318 -291.7317) (xy 332.83398 -291.7317)
		)
		(stroke
			(width 0)
			(type solid)
		)
		(fill yes)
		(layer "F.Cu")
		(net "M_A_CPU0_SA_DQ<0>")
	)
	(gr_poly
		(pts
			(xy 332.93558 -291.098732) (xy 332.93558 -290.908232) (xy 332.83398 -290.87191) (xy 332.78318 -290.87191)
			(xy 332.78318 -291.1348) (xy 332.83398 -291.1348)
		)
		(stroke
			(width 0)
			(type solid)
		)
		(fill yes)
		(layer "F.Cu")
		(net "M_A_CPU0_SA_DQ<0>")
	)
	(gr_poly
		(pts
			(xy 332.93558 -290.501832) (xy 332.93558 -290.311332) (xy 332.83398 -290.27501) (xy 332.78318 -290.27501)
			(xy 332.78318 -290.5379) (xy 332.83398 -290.5379)
		)
		(stroke
			(width 0)
			(type solid)
		)
		(fill yes)
		(layer "F.Cu")
		(net "M_A_CPU0_SA_DQ<0>")
	)
	(gr_poly
		(pts
			(xy 332.93558 -289.904932) (xy 332.93558 -289.714432) (xy 332.83398 -289.67811) (xy 332.78318 -289.67811)
			(xy 332.78318 -289.941) (xy 332.83398 -289.941)
		)
		(stroke
			(width 0)
			(type solid)
		)
		(fill yes)
		(layer "F.Cu")
		(net "M_A_CPU0_SA_DQ<0>")
	)
	(gr_poly
		(pts
			(xy 332.93558 -289.308032) (xy 332.93558 -289.117532) (xy 332.83398 -289.08121) (xy 332.78318 -289.08121)
			(xy 332.78318 -289.3441) (xy 332.83398 -289.3441)
		)
		(stroke
			(width 0)
			(type solid)
		)
		(fill yes)
		(layer "F.Cu")
		(net "M_A_CPU0_SA_DQ<0>")
	)
	(gr_poly
		(pts
			(xy 332.93558 -288.711132) (xy 332.93558 -288.520632) (xy 332.83398 -288.48431) (xy 332.78318 -288.48431)
			(xy 332.78318 -288.7472) (xy 332.83398 -288.7472)
		)
		(stroke
			(width 0)
			(type solid)
		)
		(fill yes)
		(layer "F.Cu")
		(net "M_A_CPU0_SA_DQ<0>")
	)
	(gr_poly
		(pts
			(xy 332.93558 -288.114232) (xy 332.93558 -287.923732) (xy 332.83398 -287.88741) (xy 332.78318 -287.88741)
			(xy 332.78318 -288.1503) (xy 332.83398 -288.1503)
		)
		(stroke
			(width 0)
			(type solid)
		)
		(fill yes)
		(layer "F.Cu")
		(net "M_A_CPU0_SA_DQ<0>")
	)
	(gr_poly
		(pts
			(xy 332.93558 -287.517332) (xy 332.93558 -287.326832) (xy 332.83398 -287.29051) (xy 332.78318 -287.29051)
			(xy 332.78318 -287.5534) (xy 332.83398 -287.5534)
		)
		(stroke
			(width 0)
			(type solid)
		)
		(fill yes)
		(layer "F.Cu")
		(net "M_A_CPU0_SA_DQ<0>")
	)
	(gr_poly
		(pts
			(xy 332.93558 -286.920432) (xy 332.93558 -286.729932) (xy 332.83398 -286.69361) (xy 332.78318 -286.69361)
			(xy 332.78318 -286.9565) (xy 332.83398 -286.9565)
		)
		(stroke
			(width 0)
			(type solid)
		)
		(fill yes)
		(layer "F.Cu")
		(net "M_A_CPU0_SA_DQ<0>")
	)
	(gr_poly
		(pts
			(xy 332.93558 -286.323532) (xy 332.93558 -286.133032) (xy 332.83398 -286.09671) (xy 332.78318 -286.09671)
			(xy 332.78318 -286.3596) (xy 332.83398 -286.3596)
		)
		(stroke
			(width 0)
			(type solid)
		)
		(fill yes)
		(layer "F.Cu")
		(net "M_A_CPU0_SA_DQ<0>")
	)
	(gr_poly
		(pts
			(xy 332.93558 -285.726632) (xy 332.93558 -285.536132) (xy 332.83398 -285.49981) (xy 332.78318 -285.49981)
			(xy 332.78318 -285.7627) (xy 332.83398 -285.7627)
		)
		(stroke
			(width 0)
			(type solid)
		)
		(fill yes)
		(layer "F.Cu")
		(net "M_A_CPU0_SA_DQ<0>")
	)
	(gr_poly
		(pts
			(xy 332.93558 -285.129732) (xy 332.93558 -284.939232) (xy 332.83398 -284.90291) (xy 332.78318 -284.90291)
			(xy 332.78318 -285.1658) (xy 332.83398 -285.1658)
		)
		(stroke
			(width 0)
			(type solid)
		)
		(fill yes)
		(layer "F.Cu")
		(net "M_A_CPU0_SA_DQ<0>")
	)
	(gr_poly
		(pts
			(xy 332.93558 -284.532832) (xy 332.93558 -284.342332) (xy 332.83398 -284.30601) (xy 332.78318 -284.30601)
			(xy 332.78318 -284.5689) (xy 332.83398 -284.5689)
		)
		(stroke
			(width 0)
			(type solid)
		)
		(fill yes)
		(layer "F.Cu")
		(net "M_A_CPU0_SA_DQ<0>")
	)
	(gr_poly
		(pts
			(xy 332.93558 -283.935932) (xy 332.93558 -283.745432) (xy 332.83398 -283.70911) (xy 332.78318 -283.70911)
			(xy 332.78318 -283.972) (xy 332.83398 -283.972)
		)
		(stroke
			(width 0)
			(type solid)
		)
		(fill yes)
		(layer "F.Cu")
		(net "M_A_CPU0_SA_DQ<0>")
	)
	(gr_poly
		(pts
			(xy 332.93558 -283.339032) (xy 332.93558 -283.148532) (xy 332.83398 -283.11221) (xy 332.78318 -283.11221)
			(xy 332.78318 -283.3751) (xy 332.83398 -283.3751)
		)
		(stroke
			(width 0)
			(type solid)
		)
		(fill yes)
		(layer "F.Cu")
		(net "M_A_CPU0_SA_DQ<0>")
	)
	(gr_poly
		(pts
			(xy 332.97368 -282.418282) (xy 333.011272 -282.231592) (xy 332.918816 -282.175966) (xy 332.868778 -282.16606)
			(xy 332.817216 -282.42387) (xy 332.867 -282.433776)
		)
		(stroke
			(width 0)
			(type solid)
		)
		(fill yes)
		(layer "F.Cu")
		(net "M_A_CPU0_SA_DQ<0>")
	)
	(gr_poly
		(pts
			(xy 333.091282 -281.833066) (xy 333.12862 -281.646376) (xy 333.036164 -281.59075) (xy 332.98638 -281.580844)
			(xy 332.934818 -281.838654) (xy 332.984602 -281.84856)
		)
		(stroke
			(width 0)
			(type solid)
		)
		(fill yes)
		(layer "F.Cu")
		(net "M_A_CPU0_SA_DQ<0>")
	)
	(gr_poly
		(pts
			(xy 387.067044 -295.413176) (xy 387.016244 -295.413176) (xy 386.914644 -295.449498) (xy 386.914644 -295.639998)
			(xy 387.016244 -295.676066) (xy 387.067044 -295.676066)
		)
		(stroke
			(width 0)
			(type solid)
		)
		(fill yes)
		(layer "F.Cu")
		(net "M_E_CPU0_SA_DQ<0>")
	)
	(gr_poly
		(pts
			(xy 387.067044 -294.816276) (xy 387.016244 -294.816276) (xy 386.914644 -294.852598) (xy 386.914644 -295.043098)
			(xy 387.016244 -295.079166) (xy 387.067044 -295.079166)
		)
		(stroke
			(width 0)
			(type solid)
		)
		(fill yes)
		(layer "F.Cu")
		(net "M_E_CPU0_SA_DQ<0>")
	)
	(gr_poly
		(pts
			(xy 387.067044 -294.219376) (xy 387.016244 -294.219376) (xy 386.914644 -294.255698) (xy 386.914644 -294.446198)
			(xy 387.016244 -294.482266) (xy 387.067044 -294.482266)
		)
		(stroke
			(width 0)
			(type solid)
		)
		(fill yes)
		(layer "F.Cu")
		(net "M_E_CPU0_SA_DQ<0>")
	)
	(gr_poly
		(pts
			(xy 387.067044 -293.622476) (xy 387.016244 -293.622476) (xy 386.914644 -293.658798) (xy 386.914644 -293.849298)
			(xy 387.016244 -293.885366) (xy 387.067044 -293.885366)
		)
		(stroke
			(width 0)
			(type solid)
		)
		(fill yes)
		(layer "F.Cu")
		(net "M_E_CPU0_SA_DQ<0>")
	)
	(gr_poly
		(pts
			(xy 387.067044 -293.025576) (xy 387.016244 -293.025576) (xy 386.914644 -293.061898) (xy 386.914644 -293.252398)
			(xy 387.016244 -293.288466) (xy 387.067044 -293.288466)
		)
		(stroke
			(width 0)
			(type solid)
		)
		(fill yes)
		(layer "F.Cu")
		(net "M_E_CPU0_SA_DQ<0>")
	)
	(gr_poly
		(pts
			(xy 387.067044 -292.428676) (xy 387.016244 -292.428676) (xy 386.914644 -292.464998) (xy 386.914644 -292.655498)
			(xy 387.016244 -292.691566) (xy 387.067044 -292.691566)
		)
		(stroke
			(width 0)
			(type solid)
		)
		(fill yes)
		(layer "F.Cu")
		(net "M_E_CPU0_SA_DQ<0>")
	)
	(gr_poly
		(pts
			(xy 387.067044 -291.831776) (xy 387.016244 -291.831776) (xy 386.914644 -291.868098) (xy 386.914644 -292.058598)
			(xy 387.016244 -292.094666) (xy 387.067044 -292.094666)
		)
		(stroke
			(width 0)
			(type solid)
		)
		(fill yes)
		(layer "F.Cu")
		(net "M_E_CPU0_SA_DQ<0>")
	)
	(gr_poly
		(pts
			(xy 387.067044 -291.234876) (xy 387.016244 -291.234876) (xy 386.914644 -291.271198) (xy 386.914644 -291.461698)
			(xy 387.016244 -291.497766) (xy 387.067044 -291.497766)
		)
		(stroke
			(width 0)
			(type solid)
		)
		(fill yes)
		(layer "F.Cu")
		(net "M_E_CPU0_SA_DQ<0>")
	)
	(gr_poly
		(pts
			(xy 387.067044 -290.637976) (xy 387.016244 -290.637976) (xy 386.914644 -290.674298) (xy 386.914644 -290.864798)
			(xy 387.016244 -290.900866) (xy 387.067044 -290.900866)
		)
		(stroke
			(width 0)
			(type solid)
		)
		(fill yes)
		(layer "F.Cu")
		(net "M_E_CPU0_SA_DQ<0>")
	)
	(gr_poly
		(pts
			(xy 387.067044 -290.041076) (xy 387.016244 -290.041076) (xy 386.914644 -290.077398) (xy 386.914644 -290.267898)
			(xy 387.016244 -290.303966) (xy 387.067044 -290.303966)
		)
		(stroke
			(width 0)
			(type solid)
		)
		(fill yes)
		(layer "F.Cu")
		(net "M_E_CPU0_SA_DQ<0>")
	)
	(gr_poly
		(pts
			(xy 387.067044 -289.444176) (xy 387.016244 -289.444176) (xy 386.914644 -289.480498) (xy 386.914644 -289.670998)
			(xy 387.016244 -289.707066) (xy 387.067044 -289.707066)
		)
		(stroke
			(width 0)
			(type solid)
		)
		(fill yes)
		(layer "F.Cu")
		(net "M_E_CPU0_SA_DQ<0>")
	)
	(gr_poly
		(pts
			(xy 387.067044 -288.847276) (xy 387.016244 -288.847276) (xy 386.914644 -288.883598) (xy 386.914644 -289.074098)
			(xy 387.016244 -289.110166) (xy 387.067044 -289.110166)
		)
		(stroke
			(width 0)
			(type solid)
		)
		(fill yes)
		(layer "F.Cu")
		(net "M_E_CPU0_SA_DQ<0>")
	)
	(gr_poly
		(pts
			(xy 387.067044 -288.250376) (xy 387.016244 -288.250376) (xy 386.914644 -288.286698) (xy 386.914644 -288.477198)
			(xy 387.016244 -288.513266) (xy 387.067044 -288.513266)
		)
		(stroke
			(width 0)
			(type solid)
		)
		(fill yes)
		(layer "F.Cu")
		(net "M_E_CPU0_SA_DQ<0>")
	)
	(gr_poly
		(pts
			(xy 387.067044 -287.653476) (xy 387.016244 -287.653476) (xy 386.914644 -287.689798) (xy 386.914644 -287.880298)
			(xy 387.016244 -287.916366) (xy 387.067044 -287.916366)
		)
		(stroke
			(width 0)
			(type solid)
		)
		(fill yes)
		(layer "F.Cu")
		(net "M_E_CPU0_SA_DQ<0>")
	)
	(gr_poly
		(pts
			(xy 387.067044 -287.056576) (xy 387.016244 -287.056576) (xy 386.914644 -287.092898) (xy 386.914644 -287.283398)
			(xy 387.016244 -287.319466) (xy 387.067044 -287.319466)
		)
		(stroke
			(width 0)
			(type solid)
		)
		(fill yes)
		(layer "F.Cu")
		(net "M_E_CPU0_SA_DQ<0>")
	)
	(gr_poly
		(pts
			(xy 387.067044 -286.459676) (xy 387.016244 -286.459676) (xy 386.914644 -286.495998) (xy 386.914644 -286.686498)
			(xy 387.016244 -286.722566) (xy 387.067044 -286.722566)
		)
		(stroke
			(width 0)
			(type solid)
		)
		(fill yes)
		(layer "F.Cu")
		(net "M_E_CPU0_SA_DQ<0>")
	)
	(gr_poly
		(pts
			(xy 387.067044 -285.862776) (xy 387.016244 -285.862776) (xy 386.914644 -285.899098) (xy 386.914644 -286.089598)
			(xy 387.016244 -286.125666) (xy 387.067044 -286.125666)
		)
		(stroke
			(width 0)
			(type solid)
		)
		(fill yes)
		(layer "F.Cu")
		(net "M_E_CPU0_SA_DQ<0>")
	)
	(gr_poly
		(pts
			(xy 387.067044 -285.265876) (xy 387.016244 -285.265876) (xy 386.914644 -285.302198) (xy 386.914644 -285.492698)
			(xy 387.016244 -285.528766) (xy 387.067044 -285.528766)
		)
		(stroke
			(width 0)
			(type solid)
		)
		(fill yes)
		(layer "F.Cu")
		(net "M_E_CPU0_SA_DQ<0>")
	)
	(gr_poly
		(pts
			(xy 387.067044 -284.668976) (xy 387.016244 -284.668976) (xy 386.914644 -284.705298) (xy 386.914644 -284.895798)
			(xy 387.016244 -284.931866) (xy 387.067044 -284.931866)
		)
		(stroke
			(width 0)
			(type solid)
		)
		(fill yes)
		(layer "F.Cu")
		(net "M_E_CPU0_SA_DQ<0>")
	)
	(gr_poly
		(pts
			(xy 387.067044 -284.072076) (xy 387.016244 -284.072076) (xy 386.914644 -284.108398) (xy 386.914644 -284.298898)
			(xy 387.016244 -284.334966) (xy 387.067044 -284.334966)
		)
		(stroke
			(width 0)
			(type solid)
		)
		(fill yes)
		(layer "F.Cu")
		(net "M_E_CPU0_SA_DQ<0>")
	)
	(gr_poly
		(pts
			(xy 387.067044 -283.475176) (xy 387.016244 -283.475176) (xy 386.914644 -283.511498) (xy 386.914644 -283.701998)
			(xy 387.016244 -283.738066) (xy 387.067044 -283.738066)
		)
		(stroke
			(width 0)
			(type solid)
		)
		(fill yes)
		(layer "F.Cu")
		(net "M_E_CPU0_SA_DQ<0>")
	)
	(gr_poly
		(pts
			(xy 387.067044 -282.878276) (xy 387.016244 -282.878276) (xy 386.914644 -282.914598) (xy 386.914644 -283.105098)
			(xy 387.016244 -283.141166) (xy 387.067044 -283.141166)
		)
		(stroke
			(width 0)
			(type solid)
		)
		(fill yes)
		(layer "F.Cu")
		(net "M_E_CPU0_SA_DQ<0>")
	)
	(gr_poly
		(pts
			(xy 387.067044 -282.281376) (xy 387.016244 -282.281376) (xy 386.914644 -282.317698) (xy 386.914644 -282.508198)
			(xy 387.016244 -282.544266) (xy 387.067044 -282.544266)
		)
		(stroke
			(width 0)
			(type solid)
		)
		(fill yes)
		(layer "F.Cu")
		(net "M_E_CPU0_SA_DQ<0>")
	)
	(gr_poly
		(pts
			(xy 387.067044 -281.684476) (xy 387.016244 -281.684476) (xy 386.914644 -281.720798) (xy 386.914644 -281.911298)
			(xy 387.016244 -281.947366) (xy 387.067044 -281.947366)
		)
		(stroke
			(width 0)
			(type solid)
		)
		(fill yes)
		(layer "F.Cu")
		(net "M_E_CPU0_SA_DQ<0>")
	)
	(gr_poly
		(pts
			(xy 387.219444 -295.341294) (xy 387.219444 -295.150794) (xy 387.117844 -295.114726) (xy 387.067044 -295.114726)
			(xy 387.067044 -295.377616) (xy 387.117844 -295.377616)
		)
		(stroke
			(width 0)
			(type solid)
		)
		(fill yes)
		(layer "F.Cu")
		(net "M_E_CPU0_SA_DQ<0>")
	)
	(gr_poly
		(pts
			(xy 387.219444 -294.744394) (xy 387.219444 -294.553894) (xy 387.117844 -294.517826) (xy 387.067044 -294.517826)
			(xy 387.067044 -294.780716) (xy 387.117844 -294.780716)
		)
		(stroke
			(width 0)
			(type solid)
		)
		(fill yes)
		(layer "F.Cu")
		(net "M_E_CPU0_SA_DQ<0>")
	)
	(gr_poly
		(pts
			(xy 387.219444 -294.147494) (xy 387.219444 -293.956994) (xy 387.117844 -293.920926) (xy 387.067044 -293.920926)
			(xy 387.067044 -294.183816) (xy 387.117844 -294.183816)
		)
		(stroke
			(width 0)
			(type solid)
		)
		(fill yes)
		(layer "F.Cu")
		(net "M_E_CPU0_SA_DQ<0>")
	)
	(gr_poly
		(pts
			(xy 387.219444 -293.550594) (xy 387.219444 -293.360094) (xy 387.117844 -293.324026) (xy 387.067044 -293.324026)
			(xy 387.067044 -293.586916) (xy 387.117844 -293.586916)
		)
		(stroke
			(width 0)
			(type solid)
		)
		(fill yes)
		(layer "F.Cu")
		(net "M_E_CPU0_SA_DQ<0>")
	)
	(gr_poly
		(pts
			(xy 387.219444 -292.953694) (xy 387.219444 -292.763194) (xy 387.117844 -292.727126) (xy 387.067044 -292.727126)
			(xy 387.067044 -292.990016) (xy 387.117844 -292.990016)
		)
		(stroke
			(width 0)
			(type solid)
		)
		(fill yes)
		(layer "F.Cu")
		(net "M_E_CPU0_SA_DQ<0>")
	)
	(gr_poly
		(pts
			(xy 387.219444 -292.356794) (xy 387.219444 -292.166294) (xy 387.117844 -292.130226) (xy 387.067044 -292.130226)
			(xy 387.067044 -292.393116) (xy 387.117844 -292.393116)
		)
		(stroke
			(width 0)
			(type solid)
		)
		(fill yes)
		(layer "F.Cu")
		(net "M_E_CPU0_SA_DQ<0>")
	)
	(gr_poly
		(pts
			(xy 387.219444 -291.759894) (xy 387.219444 -291.569394) (xy 387.117844 -291.533326) (xy 387.067044 -291.533326)
			(xy 387.067044 -291.796216) (xy 387.117844 -291.796216)
		)
		(stroke
			(width 0)
			(type solid)
		)
		(fill yes)
		(layer "F.Cu")
		(net "M_E_CPU0_SA_DQ<0>")
	)
	(gr_poly
		(pts
			(xy 387.219444 -291.162994) (xy 387.219444 -290.972494) (xy 387.117844 -290.936426) (xy 387.067044 -290.936426)
			(xy 387.067044 -291.199316) (xy 387.117844 -291.199316)
		)
		(stroke
			(width 0)
			(type solid)
		)
		(fill yes)
		(layer "F.Cu")
		(net "M_E_CPU0_SA_DQ<0>")
	)
	(gr_poly
		(pts
			(xy 387.219444 -290.566094) (xy 387.219444 -290.375594) (xy 387.117844 -290.339526) (xy 387.067044 -290.339526)
			(xy 387.067044 -290.602416) (xy 387.117844 -290.602416)
		)
		(stroke
			(width 0)
			(type solid)
		)
		(fill yes)
		(layer "F.Cu")
		(net "M_E_CPU0_SA_DQ<0>")
	)
	(gr_poly
		(pts
			(xy 387.219444 -289.969194) (xy 387.219444 -289.778694) (xy 387.117844 -289.742626) (xy 387.067044 -289.742626)
			(xy 387.067044 -290.005516) (xy 387.117844 -290.005516)
		)
		(stroke
			(width 0)
			(type solid)
		)
		(fill yes)
		(layer "F.Cu")
		(net "M_E_CPU0_SA_DQ<0>")
	)
	(gr_poly
		(pts
			(xy 387.219444 -289.372294) (xy 387.219444 -289.181794) (xy 387.117844 -289.145726) (xy 387.067044 -289.145726)
			(xy 387.067044 -289.408616) (xy 387.117844 -289.408616)
		)
		(stroke
			(width 0)
			(type solid)
		)
		(fill yes)
		(layer "F.Cu")
		(net "M_E_CPU0_SA_DQ<0>")
	)
	(gr_poly
		(pts
			(xy 387.219444 -288.775394) (xy 387.219444 -288.584894) (xy 387.117844 -288.548826) (xy 387.067044 -288.548826)
			(xy 387.067044 -288.811716) (xy 387.117844 -288.811716)
		)
		(stroke
			(width 0)
			(type solid)
		)
		(fill yes)
		(layer "F.Cu")
		(net "M_E_CPU0_SA_DQ<0>")
	)
	(gr_poly
		(pts
			(xy 387.219444 -288.178494) (xy 387.219444 -287.987994) (xy 387.117844 -287.951926) (xy 387.067044 -287.951926)
			(xy 387.067044 -288.214816) (xy 387.117844 -288.214816)
		)
		(stroke
			(width 0)
			(type solid)
		)
		(fill yes)
		(layer "F.Cu")
		(net "M_E_CPU0_SA_DQ<0>")
	)
	(gr_poly
		(pts
			(xy 387.219444 -287.581594) (xy 387.219444 -287.391094) (xy 387.117844 -287.355026) (xy 387.067044 -287.355026)
			(xy 387.067044 -287.617916) (xy 387.117844 -287.617916)
		)
		(stroke
			(width 0)
			(type solid)
		)
		(fill yes)
		(layer "F.Cu")
		(net "M_E_CPU0_SA_DQ<0>")
	)
	(gr_poly
		(pts
			(xy 387.219444 -286.984694) (xy 387.219444 -286.794194) (xy 387.117844 -286.758126) (xy 387.067044 -286.758126)
			(xy 387.067044 -287.021016) (xy 387.117844 -287.021016)
		)
		(stroke
			(width 0)
			(type solid)
		)
		(fill yes)
		(layer "F.Cu")
		(net "M_E_CPU0_SA_DQ<0>")
	)
	(gr_poly
		(pts
			(xy 387.219444 -286.387794) (xy 387.219444 -286.197294) (xy 387.117844 -286.161226) (xy 387.067044 -286.161226)
			(xy 387.067044 -286.424116) (xy 387.117844 -286.424116)
		)
		(stroke
			(width 0)
			(type solid)
		)
		(fill yes)
		(layer "F.Cu")
		(net "M_E_CPU0_SA_DQ<0>")
	)
	(gr_poly
		(pts
			(xy 387.219444 -285.790894) (xy 387.219444 -285.600394) (xy 387.117844 -285.564326) (xy 387.067044 -285.564326)
			(xy 387.067044 -285.827216) (xy 387.117844 -285.827216)
		)
		(stroke
			(width 0)
			(type solid)
		)
		(fill yes)
		(layer "F.Cu")
		(net "M_E_CPU0_SA_DQ<0>")
	)
	(gr_poly
		(pts
			(xy 387.219444 -285.193994) (xy 387.219444 -285.003494) (xy 387.117844 -284.967426) (xy 387.067044 -284.967426)
			(xy 387.067044 -285.230316) (xy 387.117844 -285.230316)
		)
		(stroke
			(width 0)
			(type solid)
		)
		(fill yes)
		(layer "F.Cu")
		(net "M_E_CPU0_SA_DQ<0>")
	)
	(gr_poly
		(pts
			(xy 387.219444 -284.597094) (xy 387.219444 -284.406594) (xy 387.117844 -284.370526) (xy 387.067044 -284.370526)
			(xy 387.067044 -284.633416) (xy 387.117844 -284.633416)
		)
		(stroke
			(width 0)
			(type solid)
		)
		(fill yes)
		(layer "F.Cu")
		(net "M_E_CPU0_SA_DQ<0>")
	)
	(gr_poly
		(pts
			(xy 387.219444 -284.000194) (xy 387.219444 -283.809694) (xy 387.117844 -283.773626) (xy 387.067044 -283.773626)
			(xy 387.067044 -284.036516) (xy 387.117844 -284.036516)
		)
		(stroke
			(width 0)
			(type solid)
		)
		(fill yes)
		(layer "F.Cu")
		(net "M_E_CPU0_SA_DQ<0>")
	)
	(gr_poly
		(pts
			(xy 387.219444 -283.403294) (xy 387.219444 -283.212794) (xy 387.117844 -283.176726) (xy 387.067044 -283.176726)
			(xy 387.067044 -283.439616) (xy 387.117844 -283.439616)
		)
		(stroke
			(width 0)
			(type solid)
		)
		(fill yes)
		(layer "F.Cu")
		(net "M_E_CPU0_SA_DQ<0>")
	)
	(gr_poly
		(pts
			(xy 387.219444 -282.806394) (xy 387.219444 -282.615894) (xy 387.117844 -282.579826) (xy 387.067044 -282.579826)
			(xy 387.067044 -282.842716) (xy 387.117844 -282.842716)
		)
		(stroke
			(width 0)
			(type solid)
		)
		(fill yes)
		(layer "F.Cu")
		(net "M_E_CPU0_SA_DQ<0>")
	)
	(gr_poly
		(pts
			(xy 387.219444 -282.209494) (xy 387.219444 -282.018994) (xy 387.117844 -281.982926) (xy 387.067044 -281.982926)
			(xy 387.067044 -282.245816) (xy 387.117844 -282.245816)
		)
		(stroke
			(width 0)
			(type solid)
		)
		(fill yes)
		(layer "F.Cu")
		(net "M_E_CPU0_SA_DQ<0>")
	)
	(gr_poly
		(pts
			(xy 387.219444 -281.612594) (xy 387.219444 -281.422094) (xy 387.117844 -281.386026) (xy 387.067044 -281.386026)
			(xy 387.067044 -281.648916) (xy 387.117844 -281.648916)
		)
		(stroke
			(width 0)
			(type solid)
		)
		(fill yes)
		(layer "F.Cu")
		(net "M_E_CPU0_SA_DQ<0>")
	)
	(gr_poly
		(pts
			(xy 387.371844 -294.816276) (xy 387.321044 -294.816276) (xy 387.219444 -294.852598) (xy 387.219444 -295.043098)
			(xy 387.321044 -295.079166) (xy 387.371844 -295.079166)
		)
		(stroke
			(width 0)
			(type solid)
		)
		(fill yes)
		(layer "F.Cu")
		(net "M_E_CPU0_SA_DQ<2>")
	)
	(gr_poly
		(pts
			(xy 387.371844 -294.219376) (xy 387.321044 -294.219376) (xy 387.219444 -294.255698) (xy 387.219444 -294.446198)
			(xy 387.321044 -294.482266) (xy 387.371844 -294.482266)
		)
		(stroke
			(width 0)
			(type solid)
		)
		(fill yes)
		(layer "F.Cu")
		(net "M_E_CPU0_SA_DQ<2>")
	)
	(gr_poly
		(pts
			(xy 387.371844 -293.622476) (xy 387.321044 -293.622476) (xy 387.219444 -293.658798) (xy 387.219444 -293.849298)
			(xy 387.321044 -293.885366) (xy 387.371844 -293.885366)
		)
		(stroke
			(width 0)
			(type solid)
		)
		(fill yes)
		(layer "F.Cu")
		(net "M_E_CPU0_SA_DQ<2>")
	)
	(gr_poly
		(pts
			(xy 387.371844 -293.025576) (xy 387.321044 -293.025576) (xy 387.219444 -293.061898) (xy 387.219444 -293.252398)
			(xy 387.321044 -293.288466) (xy 387.371844 -293.288466)
		)
		(stroke
			(width 0)
			(type solid)
		)
		(fill yes)
		(layer "F.Cu")
		(net "M_E_CPU0_SA_DQ<2>")
	)
	(gr_poly
		(pts
			(xy 387.371844 -292.428676) (xy 387.321044 -292.428676) (xy 387.219444 -292.464998) (xy 387.219444 -292.655498)
			(xy 387.321044 -292.691566) (xy 387.371844 -292.691566)
		)
		(stroke
			(width 0)
			(type solid)
		)
		(fill yes)
		(layer "F.Cu")
		(net "M_E_CPU0_SA_DQ<2>")
	)
	(gr_poly
		(pts
			(xy 387.371844 -291.831776) (xy 387.321044 -291.831776) (xy 387.219444 -291.868098) (xy 387.219444 -292.058598)
			(xy 387.321044 -292.094666) (xy 387.371844 -292.094666)
		)
		(stroke
			(width 0)
			(type solid)
		)
		(fill yes)
		(layer "F.Cu")
		(net "M_E_CPU0_SA_DQ<2>")
	)
	(gr_poly
		(pts
			(xy 387.371844 -291.234876) (xy 387.321044 -291.234876) (xy 387.219444 -291.271198) (xy 387.219444 -291.461698)
			(xy 387.321044 -291.497766) (xy 387.371844 -291.497766)
		)
		(stroke
			(width 0)
			(type solid)
		)
		(fill yes)
		(layer "F.Cu")
		(net "M_E_CPU0_SA_DQ<2>")
	)
	(gr_poly
		(pts
			(xy 387.371844 -290.637976) (xy 387.321044 -290.637976) (xy 387.219444 -290.674298) (xy 387.219444 -290.864798)
			(xy 387.321044 -290.900866) (xy 387.371844 -290.900866)
		)
		(stroke
			(width 0)
			(type solid)
		)
		(fill yes)
		(layer "F.Cu")
		(net "M_E_CPU0_SA_DQ<2>")
	)
	(gr_poly
		(pts
			(xy 387.371844 -290.041076) (xy 387.321044 -290.041076) (xy 387.219444 -290.077398) (xy 387.219444 -290.267898)
			(xy 387.321044 -290.303966) (xy 387.371844 -290.303966)
		)
		(stroke
			(width 0)
			(type solid)
		)
		(fill yes)
		(layer "F.Cu")
		(net "M_E_CPU0_SA_DQ<2>")
	)
	(gr_poly
		(pts
			(xy 387.371844 -289.444176) (xy 387.321044 -289.444176) (xy 387.219444 -289.480498) (xy 387.219444 -289.670998)
			(xy 387.321044 -289.707066) (xy 387.371844 -289.707066)
		)
		(stroke
			(width 0)
			(type solid)
		)
		(fill yes)
		(layer "F.Cu")
		(net "M_E_CPU0_SA_DQ<2>")
	)
	(gr_poly
		(pts
			(xy 387.371844 -288.847276) (xy 387.321044 -288.847276) (xy 387.219444 -288.883598) (xy 387.219444 -289.074098)
			(xy 387.321044 -289.110166) (xy 387.371844 -289.110166)
		)
		(stroke
			(width 0)
			(type solid)
		)
		(fill yes)
		(layer "F.Cu")
		(net "M_E_CPU0_SA_DQ<2>")
	)
	(gr_poly
		(pts
			(xy 387.371844 -288.250376) (xy 387.321044 -288.250376) (xy 387.219444 -288.286698) (xy 387.219444 -288.477198)
			(xy 387.321044 -288.513266) (xy 387.371844 -288.513266)
		)
		(stroke
			(width 0)
			(type solid)
		)
		(fill yes)
		(layer "F.Cu")
		(net "M_E_CPU0_SA_DQ<2>")
	)
	(gr_poly
		(pts
			(xy 387.371844 -287.653476) (xy 387.321044 -287.653476) (xy 387.219444 -287.689798) (xy 387.219444 -287.880298)
			(xy 387.321044 -287.916366) (xy 387.371844 -287.916366)
		)
		(stroke
			(width 0)
			(type solid)
		)
		(fill yes)
		(layer "F.Cu")
		(net "M_E_CPU0_SA_DQ<2>")
	)
	(gr_poly
		(pts
			(xy 387.371844 -287.056576) (xy 387.321044 -287.056576) (xy 387.219444 -287.092898) (xy 387.219444 -287.283398)
			(xy 387.321044 -287.319466) (xy 387.371844 -287.319466)
		)
		(stroke
			(width 0)
			(type solid)
		)
		(fill yes)
		(layer "F.Cu")
		(net "M_E_CPU0_SA_DQ<2>")
	)
	(gr_poly
		(pts
			(xy 387.371844 -286.459676) (xy 387.321044 -286.459676) (xy 387.219444 -286.495998) (xy 387.219444 -286.686498)
			(xy 387.321044 -286.722566) (xy 387.371844 -286.722566)
		)
		(stroke
			(width 0)
			(type solid)
		)
		(fill yes)
		(layer "F.Cu")
		(net "M_E_CPU0_SA_DQ<2>")
	)
	(gr_poly
		(pts
			(xy 387.371844 -285.862776) (xy 387.321044 -285.862776) (xy 387.219444 -285.899098) (xy 387.219444 -286.089598)
			(xy 387.321044 -286.125666) (xy 387.371844 -286.125666)
		)
		(stroke
			(width 0)
			(type solid)
		)
		(fill yes)
		(layer "F.Cu")
		(net "M_E_CPU0_SA_DQ<2>")
	)
	(gr_poly
		(pts
			(xy 387.371844 -285.265876) (xy 387.321044 -285.265876) (xy 387.219444 -285.302198) (xy 387.219444 -285.492698)
			(xy 387.321044 -285.528766) (xy 387.371844 -285.528766)
		)
		(stroke
			(width 0)
			(type solid)
		)
		(fill yes)
		(layer "F.Cu")
		(net "M_E_CPU0_SA_DQ<2>")
	)
	(gr_poly
		(pts
			(xy 387.371844 -284.668976) (xy 387.321044 -284.668976) (xy 387.219444 -284.705298) (xy 387.219444 -284.895798)
			(xy 387.321044 -284.931866) (xy 387.371844 -284.931866)
		)
		(stroke
			(width 0)
			(type solid)
		)
		(fill yes)
		(layer "F.Cu")
		(net "M_E_CPU0_SA_DQ<2>")
	)
	(gr_poly
		(pts
			(xy 387.371844 -284.072076) (xy 387.321044 -284.072076) (xy 387.219444 -284.108398) (xy 387.219444 -284.298898)
			(xy 387.321044 -284.334966) (xy 387.371844 -284.334966)
		)
		(stroke
			(width 0)
			(type solid)
		)
		(fill yes)
		(layer "F.Cu")
		(net "M_E_CPU0_SA_DQ<2>")
	)
	(gr_poly
		(pts
			(xy 387.371844 -283.475176) (xy 387.321044 -283.475176) (xy 387.219444 -283.511498) (xy 387.219444 -283.701998)
			(xy 387.321044 -283.738066) (xy 387.371844 -283.738066)
		)
		(stroke
			(width 0)
			(type solid)
		)
		(fill yes)
		(layer "F.Cu")
		(net "M_E_CPU0_SA_DQ<2>")
	)
	(gr_poly
		(pts
			(xy 387.371844 -282.878276) (xy 387.321044 -282.878276) (xy 387.219444 -282.914598) (xy 387.219444 -283.105098)
			(xy 387.321044 -283.141166) (xy 387.371844 -283.141166)
		)
		(stroke
			(width 0)
			(type solid)
		)
		(fill yes)
		(layer "F.Cu")
		(net "M_E_CPU0_SA_DQ<2>")
	)
	(gr_poly
		(pts
			(xy 387.371844 -282.281376) (xy 387.321044 -282.281376) (xy 387.219444 -282.317698) (xy 387.219444 -282.508198)
			(xy 387.321044 -282.544266) (xy 387.371844 -282.544266)
		)
		(stroke
			(width 0)
			(type solid)
		)
		(fill yes)
		(layer "F.Cu")
		(net "M_E_CPU0_SA_DQ<2>")
	)
	(gr_poly
		(pts
			(xy 387.371844 -281.684476) (xy 387.321044 -281.684476) (xy 387.219444 -281.720798) (xy 387.219444 -281.911298)
			(xy 387.321044 -281.947366) (xy 387.371844 -281.947366)
		)
		(stroke
			(width 0)
			(type solid)
		)
		(fill yes)
		(layer "F.Cu")
		(net "M_E_CPU0_SA_DQ<2>")
	)
	(gr_poly
		(pts
			(xy 387.524244 -295.341294) (xy 387.524244 -295.150794) (xy 387.422644 -295.114726) (xy 387.371844 -295.114726)
			(xy 387.371844 -295.377616) (xy 387.422644 -295.377616)
		)
		(stroke
			(width 0)
			(type solid)
		)
		(fill yes)
		(layer "F.Cu")
		(net "M_E_CPU0_SA_DQ<2>")
	)
	(gr_poly
		(pts
			(xy 387.524244 -294.744394) (xy 387.524244 -294.553894) (xy 387.422644 -294.517826) (xy 387.371844 -294.517826)
			(xy 387.371844 -294.780716) (xy 387.422644 -294.780716)
		)
		(stroke
			(width 0)
			(type solid)
		)
		(fill yes)
		(layer "F.Cu")
		(net "M_E_CPU0_SA_DQ<2>")
	)
	(gr_poly
		(pts
			(xy 387.524244 -294.147494) (xy 387.524244 -293.956994) (xy 387.422644 -293.920926) (xy 387.371844 -293.920926)
			(xy 387.371844 -294.183816) (xy 387.422644 -294.183816)
		)
		(stroke
			(width 0)
			(type solid)
		)
		(fill yes)
		(layer "F.Cu")
		(net "M_E_CPU0_SA_DQ<2>")
	)
	(gr_poly
		(pts
			(xy 387.524244 -293.550594) (xy 387.524244 -293.360094) (xy 387.422644 -293.324026) (xy 387.371844 -293.324026)
			(xy 387.371844 -293.586916) (xy 387.422644 -293.586916)
		)
		(stroke
			(width 0)
			(type solid)
		)
		(fill yes)
		(layer "F.Cu")
		(net "M_E_CPU0_SA_DQ<2>")
	)
	(gr_poly
		(pts
			(xy 387.524244 -292.953694) (xy 387.524244 -292.763194) (xy 387.422644 -292.727126) (xy 387.371844 -292.727126)
			(xy 387.371844 -292.990016) (xy 387.422644 -292.990016)
		)
		(stroke
			(width 0)
			(type solid)
		)
		(fill yes)
		(layer "F.Cu")
		(net "M_E_CPU0_SA_DQ<2>")
	)
	(gr_poly
		(pts
			(xy 387.524244 -292.356794) (xy 387.524244 -292.166294) (xy 387.422644 -292.130226) (xy 387.371844 -292.130226)
			(xy 387.371844 -292.393116) (xy 387.422644 -292.393116)
		)
		(stroke
			(width 0)
			(type solid)
		)
		(fill yes)
		(layer "F.Cu")
		(net "M_E_CPU0_SA_DQ<2>")
	)
	(gr_poly
		(pts
			(xy 387.524244 -291.759894) (xy 387.524244 -291.569394) (xy 387.422644 -291.533326) (xy 387.371844 -291.533326)
			(xy 387.371844 -291.796216) (xy 387.422644 -291.796216)
		)
		(stroke
			(width 0)
			(type solid)
		)
		(fill yes)
		(layer "F.Cu")
		(net "M_E_CPU0_SA_DQ<2>")
	)
	(gr_poly
		(pts
			(xy 387.524244 -291.162994) (xy 387.524244 -290.972494) (xy 387.422644 -290.936426) (xy 387.371844 -290.936426)
			(xy 387.371844 -291.199316) (xy 387.422644 -291.199316)
		)
		(stroke
			(width 0)
			(type solid)
		)
		(fill yes)
		(layer "F.Cu")
		(net "M_E_CPU0_SA_DQ<2>")
	)
	(gr_poly
		(pts
			(xy 387.524244 -290.566094) (xy 387.524244 -290.375594) (xy 387.422644 -290.339526) (xy 387.371844 -290.339526)
			(xy 387.371844 -290.602416) (xy 387.422644 -290.602416)
		)
		(stroke
			(width 0)
			(type solid)
		)
		(fill yes)
		(layer "F.Cu")
		(net "M_E_CPU0_SA_DQ<2>")
	)
	(gr_poly
		(pts
			(xy 387.524244 -289.969194) (xy 387.524244 -289.778694) (xy 387.422644 -289.742626) (xy 387.371844 -289.742626)
			(xy 387.371844 -290.005516) (xy 387.422644 -290.005516)
		)
		(stroke
			(width 0)
			(type solid)
		)
		(fill yes)
		(layer "F.Cu")
		(net "M_E_CPU0_SA_DQ<2>")
	)
	(gr_poly
		(pts
			(xy 387.524244 -289.372294) (xy 387.524244 -289.181794) (xy 387.422644 -289.145726) (xy 387.371844 -289.145726)
			(xy 387.371844 -289.408616) (xy 387.422644 -289.408616)
		)
		(stroke
			(width 0)
			(type solid)
		)
		(fill yes)
		(layer "F.Cu")
		(net "M_E_CPU0_SA_DQ<2>")
	)
	(gr_poly
		(pts
			(xy 387.524244 -288.775394) (xy 387.524244 -288.584894) (xy 387.422644 -288.548826) (xy 387.371844 -288.548826)
			(xy 387.371844 -288.811716) (xy 387.422644 -288.811716)
		)
		(stroke
			(width 0)
			(type solid)
		)
		(fill yes)
		(layer "F.Cu")
		(net "M_E_CPU0_SA_DQ<2>")
	)
	(gr_poly
		(pts
			(xy 387.524244 -288.178494) (xy 387.524244 -287.987994) (xy 387.422644 -287.951926) (xy 387.371844 -287.951926)
			(xy 387.371844 -288.214816) (xy 387.422644 -288.214816)
		)
		(stroke
			(width 0)
			(type solid)
		)
		(fill yes)
		(layer "F.Cu")
		(net "M_E_CPU0_SA_DQ<2>")
	)
	(gr_poly
		(pts
			(xy 387.524244 -287.581594) (xy 387.524244 -287.391094) (xy 387.422644 -287.355026) (xy 387.371844 -287.355026)
			(xy 387.371844 -287.617916) (xy 387.422644 -287.617916)
		)
		(stroke
			(width 0)
			(type solid)
		)
		(fill yes)
		(layer "F.Cu")
		(net "M_E_CPU0_SA_DQ<2>")
	)
	(gr_poly
		(pts
			(xy 387.524244 -286.984694) (xy 387.524244 -286.794194) (xy 387.422644 -286.758126) (xy 387.371844 -286.758126)
			(xy 387.371844 -287.021016) (xy 387.422644 -287.021016)
		)
		(stroke
			(width 0)
			(type solid)
		)
		(fill yes)
		(layer "F.Cu")
		(net "M_E_CPU0_SA_DQ<2>")
	)
	(gr_poly
		(pts
			(xy 387.524244 -286.387794) (xy 387.524244 -286.197294) (xy 387.422644 -286.161226) (xy 387.371844 -286.161226)
			(xy 387.371844 -286.424116) (xy 387.422644 -286.424116)
		)
		(stroke
			(width 0)
			(type solid)
		)
		(fill yes)
		(layer "F.Cu")
		(net "M_E_CPU0_SA_DQ<2>")
	)
	(gr_poly
		(pts
			(xy 387.524244 -285.790894) (xy 387.524244 -285.600394) (xy 387.422644 -285.564326) (xy 387.371844 -285.564326)
			(xy 387.371844 -285.827216) (xy 387.422644 -285.827216)
		)
		(stroke
			(width 0)
			(type solid)
		)
		(fill yes)
		(layer "F.Cu")
		(net "M_E_CPU0_SA_DQ<2>")
	)
	(gr_poly
		(pts
			(xy 387.524244 -285.193994) (xy 387.524244 -285.003494) (xy 387.422644 -284.967426) (xy 387.371844 -284.967426)
			(xy 387.371844 -285.230316) (xy 387.422644 -285.230316)
		)
		(stroke
			(width 0)
			(type solid)
		)
		(fill yes)
		(layer "F.Cu")
		(net "M_E_CPU0_SA_DQ<2>")
	)
	(gr_poly
		(pts
			(xy 387.524244 -284.597094) (xy 387.524244 -284.406594) (xy 387.422644 -284.370526) (xy 387.371844 -284.370526)
			(xy 387.371844 -284.633416) (xy 387.422644 -284.633416)
		)
		(stroke
			(width 0)
			(type solid)
		)
		(fill yes)
		(layer "F.Cu")
		(net "M_E_CPU0_SA_DQ<2>")
	)
	(gr_poly
		(pts
			(xy 387.524244 -284.000194) (xy 387.524244 -283.809694) (xy 387.422644 -283.773626) (xy 387.371844 -283.773626)
			(xy 387.371844 -284.036516) (xy 387.422644 -284.036516)
		)
		(stroke
			(width 0)
			(type solid)
		)
		(fill yes)
		(layer "F.Cu")
		(net "M_E_CPU0_SA_DQ<2>")
	)
	(gr_poly
		(pts
			(xy 387.524244 -283.403294) (xy 387.524244 -283.212794) (xy 387.422644 -283.176726) (xy 387.371844 -283.176726)
			(xy 387.371844 -283.439616) (xy 387.422644 -283.439616)
		)
		(stroke
			(width 0)
			(type solid)
		)
		(fill yes)
		(layer "F.Cu")
		(net "M_E_CPU0_SA_DQ<2>")
	)
	(gr_poly
		(pts
			(xy 387.524244 -282.806394) (xy 387.524244 -282.615894) (xy 387.422644 -282.579826) (xy 387.371844 -282.579826)
			(xy 387.371844 -282.842716) (xy 387.422644 -282.842716)
		)
		(stroke
			(width 0)
			(type solid)
		)
		(fill yes)
		(layer "F.Cu")
		(net "M_E_CPU0_SA_DQ<2>")
	)
	(gr_poly
		(pts
			(xy 387.524244 -282.209494) (xy 387.524244 -282.018994) (xy 387.422644 -281.982926) (xy 387.371844 -281.982926)
			(xy 387.371844 -282.245816) (xy 387.422644 -282.245816)
		)
		(stroke
			(width 0)
			(type solid)
		)
		(fill yes)
		(layer "F.Cu")
		(net "M_E_CPU0_SA_DQ<2>")
	)
	(gr_poly
		(pts
			(xy 387.524244 -281.612594) (xy 387.524244 -281.422094) (xy 387.422644 -281.386026) (xy 387.371844 -281.386026)
			(xy 387.371844 -281.648916) (xy 387.422644 -281.648916)
		)
		(stroke
			(width 0)
			(type solid)
		)
		(fill yes)
		(layer "F.Cu")
		(net "M_E_CPU0_SA_DQ<2>")
	)
	(gr_poly
		(pts
			(xy 387.64718 -224.01403) (xy 387.59638 -224.01403) (xy 387.49478 -224.050098) (xy 387.49478 -224.240598)
			(xy 387.59638 -224.27692) (xy 387.64718 -224.27692)
		)
		(stroke
			(width 0)
			(type solid)
		)
		(fill yes)
		(layer "F.Cu")
		(net "M_E_CPU0_SB_DQ<31>")
	)
	(gr_poly
		(pts
			(xy 387.64718 -223.41713) (xy 387.59638 -223.41713) (xy 387.49478 -223.453198) (xy 387.49478 -223.643698)
			(xy 387.59638 -223.68002) (xy 387.64718 -223.68002)
		)
		(stroke
			(width 0)
			(type solid)
		)
		(fill yes)
		(layer "F.Cu")
		(net "M_E_CPU0_SB_DQ<31>")
	)
	(gr_poly
		(pts
			(xy 387.64718 -222.82023) (xy 387.59638 -222.82023) (xy 387.49478 -222.856298) (xy 387.49478 -223.046798)
			(xy 387.59638 -223.08312) (xy 387.64718 -223.08312)
		)
		(stroke
			(width 0)
			(type solid)
		)
		(fill yes)
		(layer "F.Cu")
		(net "M_E_CPU0_SB_DQ<31>")
	)
	(gr_poly
		(pts
			(xy 387.64718 -222.22333) (xy 387.59638 -222.22333) (xy 387.49478 -222.259398) (xy 387.49478 -222.449898)
			(xy 387.59638 -222.48622) (xy 387.64718 -222.48622)
		)
		(stroke
			(width 0)
			(type solid)
		)
		(fill yes)
		(layer "F.Cu")
		(net "M_E_CPU0_SB_DQ<31>")
	)
	(gr_poly
		(pts
			(xy 387.64718 -221.62643) (xy 387.59638 -221.62643) (xy 387.49478 -221.662498) (xy 387.49478 -221.852998)
			(xy 387.59638 -221.88932) (xy 387.64718 -221.88932)
		)
		(stroke
			(width 0)
			(type solid)
		)
		(fill yes)
		(layer "F.Cu")
		(net "M_E_CPU0_SB_DQ<31>")
	)
	(gr_poly
		(pts
			(xy 387.64718 -221.02953) (xy 387.59638 -221.02953) (xy 387.49478 -221.065598) (xy 387.49478 -221.256098)
			(xy 387.59638 -221.29242) (xy 387.64718 -221.29242)
		)
		(stroke
			(width 0)
			(type solid)
		)
		(fill yes)
		(layer "F.Cu")
		(net "M_E_CPU0_SB_DQ<31>")
	)
	(gr_poly
		(pts
			(xy 387.64718 -220.43263) (xy 387.59638 -220.43263) (xy 387.49478 -220.468698) (xy 387.49478 -220.659198)
			(xy 387.59638 -220.69552) (xy 387.64718 -220.69552)
		)
		(stroke
			(width 0)
			(type solid)
		)
		(fill yes)
		(layer "F.Cu")
		(net "M_E_CPU0_SB_DQ<31>")
	)
	(gr_poly
		(pts
			(xy 387.64718 -219.83573) (xy 387.59638 -219.83573) (xy 387.49478 -219.871798) (xy 387.49478 -220.062298)
			(xy 387.59638 -220.09862) (xy 387.64718 -220.09862)
		)
		(stroke
			(width 0)
			(type solid)
		)
		(fill yes)
		(layer "F.Cu")
		(net "M_E_CPU0_SB_DQ<31>")
	)
	(gr_poly
		(pts
			(xy 387.64718 -219.23883) (xy 387.59638 -219.23883) (xy 387.49478 -219.274898) (xy 387.49478 -219.465398)
			(xy 387.59638 -219.50172) (xy 387.64718 -219.50172)
		)
		(stroke
			(width 0)
			(type solid)
		)
		(fill yes)
		(layer "F.Cu")
		(net "M_E_CPU0_SB_DQ<31>")
	)
	(gr_poly
		(pts
			(xy 387.64718 -218.64193) (xy 387.59638 -218.64193) (xy 387.49478 -218.677998) (xy 387.49478 -218.868498)
			(xy 387.59638 -218.90482) (xy 387.64718 -218.90482)
		)
		(stroke
			(width 0)
			(type solid)
		)
		(fill yes)
		(layer "F.Cu")
		(net "M_E_CPU0_SB_DQ<31>")
	)
	(gr_poly
		(pts
			(xy 387.64718 -218.04503) (xy 387.59638 -218.04503) (xy 387.49478 -218.081098) (xy 387.49478 -218.271598)
			(xy 387.59638 -218.30792) (xy 387.64718 -218.30792)
		)
		(stroke
			(width 0)
			(type solid)
		)
		(fill yes)
		(layer "F.Cu")
		(net "M_E_CPU0_SB_DQ<31>")
	)
	(gr_poly
		(pts
			(xy 387.64718 -217.44813) (xy 387.59638 -217.44813) (xy 387.49478 -217.484198) (xy 387.49478 -217.674698)
			(xy 387.59638 -217.71102) (xy 387.64718 -217.71102)
		)
		(stroke
			(width 0)
			(type solid)
		)
		(fill yes)
		(layer "F.Cu")
		(net "M_E_CPU0_SB_DQ<31>")
	)
	(gr_poly
		(pts
			(xy 387.64718 -216.85123) (xy 387.59638 -216.85123) (xy 387.49478 -216.887298) (xy 387.49478 -217.077798)
			(xy 387.59638 -217.11412) (xy 387.64718 -217.11412)
		)
		(stroke
			(width 0)
			(type solid)
		)
		(fill yes)
		(layer "F.Cu")
		(net "M_E_CPU0_SB_DQ<31>")
	)
	(gr_poly
		(pts
			(xy 387.64718 -216.25433) (xy 387.59638 -216.25433) (xy 387.49478 -216.290398) (xy 387.49478 -216.480898)
			(xy 387.59638 -216.51722) (xy 387.64718 -216.51722)
		)
		(stroke
			(width 0)
			(type solid)
		)
		(fill yes)
		(layer "F.Cu")
		(net "M_E_CPU0_SB_DQ<31>")
	)
	(gr_poly
		(pts
			(xy 387.64718 -215.65743) (xy 387.59638 -215.65743) (xy 387.49478 -215.693498) (xy 387.49478 -215.883998)
			(xy 387.59638 -215.92032) (xy 387.64718 -215.92032)
		)
		(stroke
			(width 0)
			(type solid)
		)
		(fill yes)
		(layer "F.Cu")
		(net "M_E_CPU0_SB_DQ<31>")
	)
	(gr_poly
		(pts
			(xy 387.676644 -295.413176) (xy 387.625844 -295.413176) (xy 387.524244 -295.449498) (xy 387.524244 -295.639998)
			(xy 387.625844 -295.676066) (xy 387.676644 -295.676066)
		)
		(stroke
			(width 0)
			(type solid)
		)
		(fill yes)
		(layer "F.Cu")
		(net "M_E_CPU0_SA_DQ<1>")
	)
	(gr_poly
		(pts
			(xy 387.676644 -294.816276) (xy 387.625844 -294.816276) (xy 387.524244 -294.852598) (xy 387.524244 -295.043098)
			(xy 387.625844 -295.079166) (xy 387.676644 -295.079166)
		)
		(stroke
			(width 0)
			(type solid)
		)
		(fill yes)
		(layer "F.Cu")
		(net "M_E_CPU0_SA_DQ<1>")
	)
	(gr_poly
		(pts
			(xy 387.676644 -294.219376) (xy 387.625844 -294.219376) (xy 387.524244 -294.255698) (xy 387.524244 -294.446198)
			(xy 387.625844 -294.482266) (xy 387.676644 -294.482266)
		)
		(stroke
			(width 0)
			(type solid)
		)
		(fill yes)
		(layer "F.Cu")
		(net "M_E_CPU0_SA_DQ<1>")
	)
	(gr_poly
		(pts
			(xy 387.676644 -293.622476) (xy 387.625844 -293.622476) (xy 387.524244 -293.658798) (xy 387.524244 -293.849298)
			(xy 387.625844 -293.885366) (xy 387.676644 -293.885366)
		)
		(stroke
			(width 0)
			(type solid)
		)
		(fill yes)
		(layer "F.Cu")
		(net "M_E_CPU0_SA_DQ<1>")
	)
	(gr_poly
		(pts
			(xy 387.676644 -293.025576) (xy 387.625844 -293.025576) (xy 387.524244 -293.061898) (xy 387.524244 -293.252398)
			(xy 387.625844 -293.288466) (xy 387.676644 -293.288466)
		)
		(stroke
			(width 0)
			(type solid)
		)
		(fill yes)
		(layer "F.Cu")
		(net "M_E_CPU0_SA_DQ<1>")
	)
	(gr_poly
		(pts
			(xy 387.676644 -292.428676) (xy 387.625844 -292.428676) (xy 387.524244 -292.464998) (xy 387.524244 -292.655498)
			(xy 387.625844 -292.691566) (xy 387.676644 -292.691566)
		)
		(stroke
			(width 0)
			(type solid)
		)
		(fill yes)
		(layer "F.Cu")
		(net "M_E_CPU0_SA_DQ<1>")
	)
	(gr_poly
		(pts
			(xy 387.676644 -291.831776) (xy 387.625844 -291.831776) (xy 387.524244 -291.868098) (xy 387.524244 -292.058598)
			(xy 387.625844 -292.094666) (xy 387.676644 -292.094666)
		)
		(stroke
			(width 0)
			(type solid)
		)
		(fill yes)
		(layer "F.Cu")
		(net "M_E_CPU0_SA_DQ<1>")
	)
	(gr_poly
		(pts
			(xy 387.676644 -291.234876) (xy 387.625844 -291.234876) (xy 387.524244 -291.271198) (xy 387.524244 -291.461698)
			(xy 387.625844 -291.497766) (xy 387.676644 -291.497766)
		)
		(stroke
			(width 0)
			(type solid)
		)
		(fill yes)
		(layer "F.Cu")
		(net "M_E_CPU0_SA_DQ<1>")
	)
	(gr_poly
		(pts
			(xy 387.676644 -290.637976) (xy 387.625844 -290.637976) (xy 387.524244 -290.674298) (xy 387.524244 -290.864798)
			(xy 387.625844 -290.900866) (xy 387.676644 -290.900866)
		)
		(stroke
			(width 0)
			(type solid)
		)
		(fill yes)
		(layer "F.Cu")
		(net "M_E_CPU0_SA_DQ<1>")
	)
	(gr_poly
		(pts
			(xy 387.676644 -290.041076) (xy 387.625844 -290.041076) (xy 387.524244 -290.077398) (xy 387.524244 -290.267898)
			(xy 387.625844 -290.303966) (xy 387.676644 -290.303966)
		)
		(stroke
			(width 0)
			(type solid)
		)
		(fill yes)
		(layer "F.Cu")
		(net "M_E_CPU0_SA_DQ<1>")
	)
	(gr_poly
		(pts
			(xy 387.676644 -289.444176) (xy 387.625844 -289.444176) (xy 387.524244 -289.480498) (xy 387.524244 -289.670998)
			(xy 387.625844 -289.707066) (xy 387.676644 -289.707066)
		)
		(stroke
			(width 0)
			(type solid)
		)
		(fill yes)
		(layer "F.Cu")
		(net "M_E_CPU0_SA_DQ<1>")
	)
	(gr_poly
		(pts
			(xy 387.676644 -288.847276) (xy 387.625844 -288.847276) (xy 387.524244 -288.883598) (xy 387.524244 -289.074098)
			(xy 387.625844 -289.110166) (xy 387.676644 -289.110166)
		)
		(stroke
			(width 0)
			(type solid)
		)
		(fill yes)
		(layer "F.Cu")
		(net "M_E_CPU0_SA_DQ<1>")
	)
	(gr_poly
		(pts
			(xy 387.676644 -288.250376) (xy 387.625844 -288.250376) (xy 387.524244 -288.286698) (xy 387.524244 -288.477198)
			(xy 387.625844 -288.513266) (xy 387.676644 -288.513266)
		)
		(stroke
			(width 0)
			(type solid)
		)
		(fill yes)
		(layer "F.Cu")
		(net "M_E_CPU0_SA_DQ<1>")
	)
	(gr_poly
		(pts
			(xy 387.676644 -287.653476) (xy 387.625844 -287.653476) (xy 387.524244 -287.689798) (xy 387.524244 -287.880298)
			(xy 387.625844 -287.916366) (xy 387.676644 -287.916366)
		)
		(stroke
			(width 0)
			(type solid)
		)
		(fill yes)
		(layer "F.Cu")
		(net "M_E_CPU0_SA_DQ<1>")
	)
	(gr_poly
		(pts
			(xy 387.676644 -287.056576) (xy 387.625844 -287.056576) (xy 387.524244 -287.092898) (xy 387.524244 -287.283398)
			(xy 387.625844 -287.319466) (xy 387.676644 -287.319466)
		)
		(stroke
			(width 0)
			(type solid)
		)
		(fill yes)
		(layer "F.Cu")
		(net "M_E_CPU0_SA_DQ<1>")
	)
	(gr_poly
		(pts
			(xy 387.676644 -286.459676) (xy 387.625844 -286.459676) (xy 387.524244 -286.495998) (xy 387.524244 -286.686498)
			(xy 387.625844 -286.722566) (xy 387.676644 -286.722566)
		)
		(stroke
			(width 0)
			(type solid)
		)
		(fill yes)
		(layer "F.Cu")
		(net "M_E_CPU0_SA_DQ<1>")
	)
	(gr_poly
		(pts
			(xy 387.676644 -285.862776) (xy 387.625844 -285.862776) (xy 387.524244 -285.899098) (xy 387.524244 -286.089598)
			(xy 387.625844 -286.125666) (xy 387.676644 -286.125666)
		)
		(stroke
			(width 0)
			(type solid)
		)
		(fill yes)
		(layer "F.Cu")
		(net "M_E_CPU0_SA_DQ<1>")
	)
	(gr_poly
		(pts
			(xy 387.676644 -285.265876) (xy 387.625844 -285.265876) (xy 387.524244 -285.302198) (xy 387.524244 -285.492698)
			(xy 387.625844 -285.528766) (xy 387.676644 -285.528766)
		)
		(stroke
			(width 0)
			(type solid)
		)
		(fill yes)
		(layer "F.Cu")
		(net "M_E_CPU0_SA_DQ<1>")
	)
	(gr_poly
		(pts
			(xy 387.676644 -284.668976) (xy 387.625844 -284.668976) (xy 387.524244 -284.705298) (xy 387.524244 -284.895798)
			(xy 387.625844 -284.931866) (xy 387.676644 -284.931866)
		)
		(stroke
			(width 0)
			(type solid)
		)
		(fill yes)
		(layer "F.Cu")
		(net "M_E_CPU0_SA_DQ<1>")
	)
	(gr_poly
		(pts
			(xy 387.676644 -284.072076) (xy 387.625844 -284.072076) (xy 387.524244 -284.108398) (xy 387.524244 -284.298898)
			(xy 387.625844 -284.334966) (xy 387.676644 -284.334966)
		)
		(stroke
			(width 0)
			(type solid)
		)
		(fill yes)
		(layer "F.Cu")
		(net "M_E_CPU0_SA_DQ<1>")
	)
	(gr_poly
		(pts
			(xy 387.676644 -283.475176) (xy 387.625844 -283.475176) (xy 387.524244 -283.511498) (xy 387.524244 -283.701998)
			(xy 387.625844 -283.738066) (xy 387.676644 -283.738066)
		)
		(stroke
			(width 0)
			(type solid)
		)
		(fill yes)
		(layer "F.Cu")
		(net "M_E_CPU0_SA_DQ<1>")
	)
	(gr_poly
		(pts
			(xy 387.676644 -282.878276) (xy 387.625844 -282.878276) (xy 387.524244 -282.914598) (xy 387.524244 -283.105098)
			(xy 387.625844 -283.141166) (xy 387.676644 -283.141166)
		)
		(stroke
			(width 0)
			(type solid)
		)
		(fill yes)
		(layer "F.Cu")
		(net "M_E_CPU0_SA_DQ<1>")
	)
	(gr_poly
		(pts
			(xy 387.676644 -282.281376) (xy 387.625844 -282.281376) (xy 387.524244 -282.317698) (xy 387.524244 -282.508198)
			(xy 387.625844 -282.544266) (xy 387.676644 -282.544266)
		)
		(stroke
			(width 0)
			(type solid)
		)
		(fill yes)
		(layer "F.Cu")
		(net "M_E_CPU0_SA_DQ<1>")
	)
	(gr_poly
		(pts
			(xy 387.676644 -281.684476) (xy 387.625844 -281.684476) (xy 387.524244 -281.720798) (xy 387.524244 -281.911298)
			(xy 387.625844 -281.947366) (xy 387.676644 -281.947366)
		)
		(stroke
			(width 0)
			(type solid)
		)
		(fill yes)
		(layer "F.Cu")
		(net "M_E_CPU0_SA_DQ<1>")
	)
	(gr_poly
		(pts
			(xy 387.79958 -224.539302) (xy 387.79958 -224.348802) (xy 387.69798 -224.31248) (xy 387.64718 -224.31248)
			(xy 387.64718 -224.57537) (xy 387.69798 -224.57537)
		)
		(stroke
			(width 0)
			(type solid)
		)
		(fill yes)
		(layer "F.Cu")
		(net "M_E_CPU0_SB_DQ<31>")
	)
	(gr_poly
		(pts
			(xy 387.79958 -223.942402) (xy 387.79958 -223.751902) (xy 387.69798 -223.71558) (xy 387.64718 -223.71558)
			(xy 387.64718 -223.97847) (xy 387.69798 -223.97847)
		)
		(stroke
			(width 0)
			(type solid)
		)
		(fill yes)
		(layer "F.Cu")
		(net "M_E_CPU0_SB_DQ<31>")
	)
	(gr_poly
		(pts
			(xy 387.79958 -223.345502) (xy 387.79958 -223.155002) (xy 387.69798 -223.11868) (xy 387.64718 -223.11868)
			(xy 387.64718 -223.38157) (xy 387.69798 -223.38157)
		)
		(stroke
			(width 0)
			(type solid)
		)
		(fill yes)
		(layer "F.Cu")
		(net "M_E_CPU0_SB_DQ<31>")
	)
	(gr_poly
		(pts
			(xy 387.79958 -222.748602) (xy 387.79958 -222.558102) (xy 387.69798 -222.52178) (xy 387.64718 -222.52178)
			(xy 387.64718 -222.78467) (xy 387.69798 -222.78467)
		)
		(stroke
			(width 0)
			(type solid)
		)
		(fill yes)
		(layer "F.Cu")
		(net "M_E_CPU0_SB_DQ<31>")
	)
	(gr_poly
		(pts
			(xy 387.79958 -222.151702) (xy 387.79958 -221.961202) (xy 387.69798 -221.92488) (xy 387.64718 -221.92488)
			(xy 387.64718 -222.18777) (xy 387.69798 -222.18777)
		)
		(stroke
			(width 0)
			(type solid)
		)
		(fill yes)
		(layer "F.Cu")
		(net "M_E_CPU0_SB_DQ<31>")
	)
	(gr_poly
		(pts
			(xy 387.79958 -221.554802) (xy 387.79958 -221.364302) (xy 387.69798 -221.32798) (xy 387.64718 -221.32798)
			(xy 387.64718 -221.59087) (xy 387.69798 -221.59087)
		)
		(stroke
			(width 0)
			(type solid)
		)
		(fill yes)
		(layer "F.Cu")
		(net "M_E_CPU0_SB_DQ<31>")
	)
	(gr_poly
		(pts
			(xy 387.79958 -220.957902) (xy 387.79958 -220.767402) (xy 387.69798 -220.73108) (xy 387.64718 -220.73108)
			(xy 387.64718 -220.99397) (xy 387.69798 -220.99397)
		)
		(stroke
			(width 0)
			(type solid)
		)
		(fill yes)
		(layer "F.Cu")
		(net "M_E_CPU0_SB_DQ<31>")
	)
	(gr_poly
		(pts
			(xy 387.79958 -220.361002) (xy 387.79958 -220.170502) (xy 387.69798 -220.13418) (xy 387.64718 -220.13418)
			(xy 387.64718 -220.39707) (xy 387.69798 -220.39707)
		)
		(stroke
			(width 0)
			(type solid)
		)
		(fill yes)
		(layer "F.Cu")
		(net "M_E_CPU0_SB_DQ<31>")
	)
	(gr_poly
		(pts
			(xy 387.79958 -219.764102) (xy 387.79958 -219.573602) (xy 387.69798 -219.53728) (xy 387.64718 -219.53728)
			(xy 387.64718 -219.80017) (xy 387.69798 -219.80017)
		)
		(stroke
			(width 0)
			(type solid)
		)
		(fill yes)
		(layer "F.Cu")
		(net "M_E_CPU0_SB_DQ<31>")
	)
	(gr_poly
		(pts
			(xy 387.79958 -219.167202) (xy 387.79958 -218.976702) (xy 387.69798 -218.94038) (xy 387.64718 -218.94038)
			(xy 387.64718 -219.20327) (xy 387.69798 -219.20327)
		)
		(stroke
			(width 0)
			(type solid)
		)
		(fill yes)
		(layer "F.Cu")
		(net "M_E_CPU0_SB_DQ<31>")
	)
	(gr_poly
		(pts
			(xy 387.79958 -218.570302) (xy 387.79958 -218.379802) (xy 387.69798 -218.34348) (xy 387.64718 -218.34348)
			(xy 387.64718 -218.60637) (xy 387.69798 -218.60637)
		)
		(stroke
			(width 0)
			(type solid)
		)
		(fill yes)
		(layer "F.Cu")
		(net "M_E_CPU0_SB_DQ<31>")
	)
	(gr_poly
		(pts
			(xy 387.79958 -217.973402) (xy 387.79958 -217.782902) (xy 387.69798 -217.74658) (xy 387.64718 -217.74658)
			(xy 387.64718 -218.00947) (xy 387.69798 -218.00947)
		)
		(stroke
			(width 0)
			(type solid)
		)
		(fill yes)
		(layer "F.Cu")
		(net "M_E_CPU0_SB_DQ<31>")
	)
	(gr_poly
		(pts
			(xy 387.79958 -217.376502) (xy 387.79958 -217.186002) (xy 387.69798 -217.14968) (xy 387.64718 -217.14968)
			(xy 387.64718 -217.41257) (xy 387.69798 -217.41257)
		)
		(stroke
			(width 0)
			(type solid)
		)
		(fill yes)
		(layer "F.Cu")
		(net "M_E_CPU0_SB_DQ<31>")
	)
	(gr_poly
		(pts
			(xy 387.79958 -216.779602) (xy 387.79958 -216.589102) (xy 387.69798 -216.55278) (xy 387.64718 -216.55278)
			(xy 387.64718 -216.81567) (xy 387.69798 -216.81567)
		)
		(stroke
			(width 0)
			(type solid)
		)
		(fill yes)
		(layer "F.Cu")
		(net "M_E_CPU0_SB_DQ<31>")
	)
	(gr_poly
		(pts
			(xy 387.79958 -216.182702) (xy 387.79958 -215.992202) (xy 387.69798 -215.95588) (xy 387.64718 -215.95588)
			(xy 387.64718 -216.21877) (xy 387.69798 -216.21877)
		)
		(stroke
			(width 0)
			(type solid)
		)
		(fill yes)
		(layer "F.Cu")
		(net "M_E_CPU0_SB_DQ<31>")
	)
	(gr_poly
		(pts
			(xy 387.829044 -295.341294) (xy 387.829044 -295.150794) (xy 387.727444 -295.114726) (xy 387.676644 -295.114726)
			(xy 387.676644 -295.377616) (xy 387.727444 -295.377616)
		)
		(stroke
			(width 0)
			(type solid)
		)
		(fill yes)
		(layer "F.Cu")
		(net "M_E_CPU0_SA_DQ<1>")
	)
	(gr_poly
		(pts
			(xy 387.829044 -294.744394) (xy 387.829044 -294.553894) (xy 387.727444 -294.517826) (xy 387.676644 -294.517826)
			(xy 387.676644 -294.780716) (xy 387.727444 -294.780716)
		)
		(stroke
			(width 0)
			(type solid)
		)
		(fill yes)
		(layer "F.Cu")
		(net "M_E_CPU0_SA_DQ<1>")
	)
	(gr_poly
		(pts
			(xy 387.829044 -294.147494) (xy 387.829044 -293.956994) (xy 387.727444 -293.920926) (xy 387.676644 -293.920926)
			(xy 387.676644 -294.183816) (xy 387.727444 -294.183816)
		)
		(stroke
			(width 0)
			(type solid)
		)
		(fill yes)
		(layer "F.Cu")
		(net "M_E_CPU0_SA_DQ<1>")
	)
	(gr_poly
		(pts
			(xy 387.829044 -293.550594) (xy 387.829044 -293.360094) (xy 387.727444 -293.324026) (xy 387.676644 -293.324026)
			(xy 387.676644 -293.586916) (xy 387.727444 -293.586916)
		)
		(stroke
			(width 0)
			(type solid)
		)
		(fill yes)
		(layer "F.Cu")
		(net "M_E_CPU0_SA_DQ<1>")
	)
	(gr_poly
		(pts
			(xy 387.829044 -292.953694) (xy 387.829044 -292.763194) (xy 387.727444 -292.727126) (xy 387.676644 -292.727126)
			(xy 387.676644 -292.990016) (xy 387.727444 -292.990016)
		)
		(stroke
			(width 0)
			(type solid)
		)
		(fill yes)
		(layer "F.Cu")
		(net "M_E_CPU0_SA_DQ<1>")
	)
	(gr_poly
		(pts
			(xy 387.829044 -292.356794) (xy 387.829044 -292.166294) (xy 387.727444 -292.130226) (xy 387.676644 -292.130226)
			(xy 387.676644 -292.393116) (xy 387.727444 -292.393116)
		)
		(stroke
			(width 0)
			(type solid)
		)
		(fill yes)
		(layer "F.Cu")
		(net "M_E_CPU0_SA_DQ<1>")
	)
	(gr_poly
		(pts
			(xy 387.829044 -291.759894) (xy 387.829044 -291.569394) (xy 387.727444 -291.533326) (xy 387.676644 -291.533326)
			(xy 387.676644 -291.796216) (xy 387.727444 -291.796216)
		)
		(stroke
			(width 0)
			(type solid)
		)
		(fill yes)
		(layer "F.Cu")
		(net "M_E_CPU0_SA_DQ<1>")
	)
	(gr_poly
		(pts
			(xy 387.829044 -291.162994) (xy 387.829044 -290.972494) (xy 387.727444 -290.936426) (xy 387.676644 -290.936426)
			(xy 387.676644 -291.199316) (xy 387.727444 -291.199316)
		)
		(stroke
			(width 0)
			(type solid)
		)
		(fill yes)
		(layer "F.Cu")
		(net "M_E_CPU0_SA_DQ<1>")
	)
	(gr_poly
		(pts
			(xy 387.829044 -290.566094) (xy 387.829044 -290.375594) (xy 387.727444 -290.339526) (xy 387.676644 -290.339526)
			(xy 387.676644 -290.602416) (xy 387.727444 -290.602416)
		)
		(stroke
			(width 0)
			(type solid)
		)
		(fill yes)
		(layer "F.Cu")
		(net "M_E_CPU0_SA_DQ<1>")
	)
	(gr_poly
		(pts
			(xy 387.829044 -289.969194) (xy 387.829044 -289.778694) (xy 387.727444 -289.742626) (xy 387.676644 -289.742626)
			(xy 387.676644 -290.005516) (xy 387.727444 -290.005516)
		)
		(stroke
			(width 0)
			(type solid)
		)
		(fill yes)
		(layer "F.Cu")
		(net "M_E_CPU0_SA_DQ<1>")
	)
	(gr_poly
		(pts
			(xy 387.829044 -289.372294) (xy 387.829044 -289.181794) (xy 387.727444 -289.145726) (xy 387.676644 -289.145726)
			(xy 387.676644 -289.408616) (xy 387.727444 -289.408616)
		)
		(stroke
			(width 0)
			(type solid)
		)
		(fill yes)
		(layer "F.Cu")
		(net "M_E_CPU0_SA_DQ<1>")
	)
	(gr_poly
		(pts
			(xy 387.829044 -288.775394) (xy 387.829044 -288.584894) (xy 387.727444 -288.548826) (xy 387.676644 -288.548826)
			(xy 387.676644 -288.811716) (xy 387.727444 -288.811716)
		)
		(stroke
			(width 0)
			(type solid)
		)
		(fill yes)
		(layer "F.Cu")
		(net "M_E_CPU0_SA_DQ<1>")
	)
	(gr_poly
		(pts
			(xy 387.829044 -288.178494) (xy 387.829044 -287.987994) (xy 387.727444 -287.951926) (xy 387.676644 -287.951926)
			(xy 387.676644 -288.214816) (xy 387.727444 -288.214816)
		)
		(stroke
			(width 0)
			(type solid)
		)
		(fill yes)
		(layer "F.Cu")
		(net "M_E_CPU0_SA_DQ<1>")
	)
	(gr_poly
		(pts
			(xy 387.829044 -287.581594) (xy 387.829044 -287.391094) (xy 387.727444 -287.355026) (xy 387.676644 -287.355026)
			(xy 387.676644 -287.617916) (xy 387.727444 -287.617916)
		)
		(stroke
			(width 0)
			(type solid)
		)
		(fill yes)
		(layer "F.Cu")
		(net "M_E_CPU0_SA_DQ<1>")
	)
	(gr_poly
		(pts
			(xy 387.829044 -286.984694) (xy 387.829044 -286.794194) (xy 387.727444 -286.758126) (xy 387.676644 -286.758126)
			(xy 387.676644 -287.021016) (xy 387.727444 -287.021016)
		)
		(stroke
			(width 0)
			(type solid)
		)
		(fill yes)
		(layer "F.Cu")
		(net "M_E_CPU0_SA_DQ<1>")
	)
	(gr_poly
		(pts
			(xy 387.829044 -286.387794) (xy 387.829044 -286.197294) (xy 387.727444 -286.161226) (xy 387.676644 -286.161226)
			(xy 387.676644 -286.424116) (xy 387.727444 -286.424116)
		)
		(stroke
			(width 0)
			(type solid)
		)
		(fill yes)
		(layer "F.Cu")
		(net "M_E_CPU0_SA_DQ<1>")
	)
	(gr_poly
		(pts
			(xy 387.829044 -285.790894) (xy 387.829044 -285.600394) (xy 387.727444 -285.564326) (xy 387.676644 -285.564326)
			(xy 387.676644 -285.827216) (xy 387.727444 -285.827216)
		)
		(stroke
			(width 0)
			(type solid)
		)
		(fill yes)
		(layer "F.Cu")
		(net "M_E_CPU0_SA_DQ<1>")
	)
	(gr_poly
		(pts
			(xy 387.829044 -285.193994) (xy 387.829044 -285.003494) (xy 387.727444 -284.967426) (xy 387.676644 -284.967426)
			(xy 387.676644 -285.230316) (xy 387.727444 -285.230316)
		)
		(stroke
			(width 0)
			(type solid)
		)
		(fill yes)
		(layer "F.Cu")
		(net "M_E_CPU0_SA_DQ<1>")
	)
	(gr_poly
		(pts
			(xy 387.829044 -284.597094) (xy 387.829044 -284.406594) (xy 387.727444 -284.370526) (xy 387.676644 -284.370526)
			(xy 387.676644 -284.633416) (xy 387.727444 -284.633416)
		)
		(stroke
			(width 0)
			(type solid)
		)
		(fill yes)
		(layer "F.Cu")
		(net "M_E_CPU0_SA_DQ<1>")
	)
	(gr_poly
		(pts
			(xy 387.829044 -284.000194) (xy 387.829044 -283.809694) (xy 387.727444 -283.773626) (xy 387.676644 -283.773626)
			(xy 387.676644 -284.036516) (xy 387.727444 -284.036516)
		)
		(stroke
			(width 0)
			(type solid)
		)
		(fill yes)
		(layer "F.Cu")
		(net "M_E_CPU0_SA_DQ<1>")
	)
	(gr_poly
		(pts
			(xy 387.829044 -283.403294) (xy 387.829044 -283.212794) (xy 387.727444 -283.176726) (xy 387.676644 -283.176726)
			(xy 387.676644 -283.439616) (xy 387.727444 -283.439616)
		)
		(stroke
			(width 0)
			(type solid)
		)
		(fill yes)
		(layer "F.Cu")
		(net "M_E_CPU0_SA_DQ<1>")
	)
	(gr_poly
		(pts
			(xy 387.829044 -282.806394) (xy 387.829044 -282.615894) (xy 387.727444 -282.579826) (xy 387.676644 -282.579826)
			(xy 387.676644 -282.842716) (xy 387.727444 -282.842716)
		)
		(stroke
			(width 0)
			(type solid)
		)
		(fill yes)
		(layer "F.Cu")
		(net "M_E_CPU0_SA_DQ<1>")
	)
	(gr_poly
		(pts
			(xy 387.829044 -282.209494) (xy 387.829044 -282.018994) (xy 387.727444 -281.982926) (xy 387.676644 -281.982926)
			(xy 387.676644 -282.245816) (xy 387.727444 -282.245816)
		)
		(stroke
			(width 0)
			(type solid)
		)
		(fill yes)
		(layer "F.Cu")
		(net "M_E_CPU0_SA_DQ<1>")
	)
	(gr_poly
		(pts
			(xy 387.829044 -281.612594) (xy 387.829044 -281.422094) (xy 387.727444 -281.386026) (xy 387.676644 -281.386026)
			(xy 387.676644 -281.648916) (xy 387.727444 -281.648916)
		)
		(stroke
			(width 0)
			(type solid)
		)
		(fill yes)
		(layer "F.Cu")
		(net "M_E_CPU0_SA_DQ<1>")
	)
	(gr_poly
		(pts
			(xy 387.95198 -224.61093) (xy 387.90118 -224.61093) (xy 387.79958 -224.646998) (xy 387.79958 -224.837498)
			(xy 387.90118 -224.87382) (xy 387.95198 -224.87382)
		)
		(stroke
			(width 0)
			(type solid)
		)
		(fill yes)
		(layer "F.Cu")
		(net "M_E_CPU0_SB_DQ<29>")
	)
	(gr_poly
		(pts
			(xy 387.95198 -224.01403) (xy 387.90118 -224.01403) (xy 387.79958 -224.050098) (xy 387.79958 -224.240598)
			(xy 387.90118 -224.27692) (xy 387.95198 -224.27692)
		)
		(stroke
			(width 0)
			(type solid)
		)
		(fill yes)
		(layer "F.Cu")
		(net "M_E_CPU0_SB_DQ<29>")
	)
	(gr_poly
		(pts
			(xy 387.95198 -223.41713) (xy 387.90118 -223.41713) (xy 387.79958 -223.453198) (xy 387.79958 -223.643698)
			(xy 387.90118 -223.68002) (xy 387.95198 -223.68002)
		)
		(stroke
			(width 0)
			(type solid)
		)
		(fill yes)
		(layer "F.Cu")
		(net "M_E_CPU0_SB_DQ<29>")
	)
	(gr_poly
		(pts
			(xy 387.95198 -222.82023) (xy 387.90118 -222.82023) (xy 387.79958 -222.856298) (xy 387.79958 -223.046798)
			(xy 387.90118 -223.08312) (xy 387.95198 -223.08312)
		)
		(stroke
			(width 0)
			(type solid)
		)
		(fill yes)
		(layer "F.Cu")
		(net "M_E_CPU0_SB_DQ<29>")
	)
	(gr_poly
		(pts
			(xy 387.95198 -222.22333) (xy 387.90118 -222.22333) (xy 387.79958 -222.259398) (xy 387.79958 -222.449898)
			(xy 387.90118 -222.48622) (xy 387.95198 -222.48622)
		)
		(stroke
			(width 0)
			(type solid)
		)
		(fill yes)
		(layer "F.Cu")
		(net "M_E_CPU0_SB_DQ<29>")
	)
	(gr_poly
		(pts
			(xy 387.95198 -221.62643) (xy 387.90118 -221.62643) (xy 387.79958 -221.662498) (xy 387.79958 -221.852998)
			(xy 387.90118 -221.88932) (xy 387.95198 -221.88932)
		)
		(stroke
			(width 0)
			(type solid)
		)
		(fill yes)
		(layer "F.Cu")
		(net "M_E_CPU0_SB_DQ<29>")
	)
	(gr_poly
		(pts
			(xy 387.95198 -221.02953) (xy 387.90118 -221.02953) (xy 387.79958 -221.065598) (xy 387.79958 -221.256098)
			(xy 387.90118 -221.29242) (xy 387.95198 -221.29242)
		)
		(stroke
			(width 0)
			(type solid)
		)
		(fill yes)
		(layer "F.Cu")
		(net "M_E_CPU0_SB_DQ<29>")
	)
	(gr_poly
		(pts
			(xy 387.95198 -220.43263) (xy 387.90118 -220.43263) (xy 387.79958 -220.468698) (xy 387.79958 -220.659198)
			(xy 387.90118 -220.69552) (xy 387.95198 -220.69552)
		)
		(stroke
			(width 0)
			(type solid)
		)
		(fill yes)
		(layer "F.Cu")
		(net "M_E_CPU0_SB_DQ<29>")
	)
	(gr_poly
		(pts
			(xy 387.95198 -219.83573) (xy 387.90118 -219.83573) (xy 387.79958 -219.871798) (xy 387.79958 -220.062298)
			(xy 387.90118 -220.09862) (xy 387.95198 -220.09862)
		)
		(stroke
			(width 0)
			(type solid)
		)
		(fill yes)
		(layer "F.Cu")
		(net "M_E_CPU0_SB_DQ<29>")
	)
	(gr_poly
		(pts
			(xy 387.95198 -219.23883) (xy 387.90118 -219.23883) (xy 387.79958 -219.274898) (xy 387.79958 -219.465398)
			(xy 387.90118 -219.50172) (xy 387.95198 -219.50172)
		)
		(stroke
			(width 0)
			(type solid)
		)
		(fill yes)
		(layer "F.Cu")
		(net "M_E_CPU0_SB_DQ<29>")
	)
	(gr_poly
		(pts
			(xy 387.95198 -218.64193) (xy 387.90118 -218.64193) (xy 387.79958 -218.677998) (xy 387.79958 -218.868498)
			(xy 387.90118 -218.90482) (xy 387.95198 -218.90482)
		)
		(stroke
			(width 0)
			(type solid)
		)
		(fill yes)
		(layer "F.Cu")
		(net "M_E_CPU0_SB_DQ<29>")
	)
	(gr_poly
		(pts
			(xy 387.95198 -218.04503) (xy 387.90118 -218.04503) (xy 387.79958 -218.081098) (xy 387.79958 -218.271598)
			(xy 387.90118 -218.30792) (xy 387.95198 -218.30792)
		)
		(stroke
			(width 0)
			(type solid)
		)
		(fill yes)
		(layer "F.Cu")
		(net "M_E_CPU0_SB_DQ<29>")
	)
	(gr_poly
		(pts
			(xy 387.95198 -217.44813) (xy 387.90118 -217.44813) (xy 387.79958 -217.484198) (xy 387.79958 -217.674698)
			(xy 387.90118 -217.71102) (xy 387.95198 -217.71102)
		)
		(stroke
			(width 0)
			(type solid)
		)
		(fill yes)
		(layer "F.Cu")
		(net "M_E_CPU0_SB_DQ<29>")
	)
	(gr_poly
		(pts
			(xy 387.95198 -216.85123) (xy 387.90118 -216.85123) (xy 387.79958 -216.887298) (xy 387.79958 -217.077798)
			(xy 387.90118 -217.11412) (xy 387.95198 -217.11412)
		)
		(stroke
			(width 0)
			(type solid)
		)
		(fill yes)
		(layer "F.Cu")
		(net "M_E_CPU0_SB_DQ<29>")
	)
	(gr_poly
		(pts
			(xy 387.95198 -216.25433) (xy 387.90118 -216.25433) (xy 387.79958 -216.290398) (xy 387.79958 -216.480898)
			(xy 387.90118 -216.51722) (xy 387.95198 -216.51722)
		)
		(stroke
			(width 0)
			(type solid)
		)
		(fill yes)
		(layer "F.Cu")
		(net "M_E_CPU0_SB_DQ<29>")
	)
	(gr_poly
		(pts
			(xy 387.95198 -215.65743) (xy 387.90118 -215.65743) (xy 387.79958 -215.693498) (xy 387.79958 -215.883998)
			(xy 387.90118 -215.92032) (xy 387.95198 -215.92032)
		)
		(stroke
			(width 0)
			(type solid)
		)
		(fill yes)
		(layer "F.Cu")
		(net "M_E_CPU0_SB_DQ<29>")
	)
	(gr_poly
		(pts
			(xy 387.981444 -295.413176) (xy 387.930644 -295.413176) (xy 387.829044 -295.449498) (xy 387.829044 -295.639998)
			(xy 387.930644 -295.676066) (xy 387.981444 -295.676066)
		)
		(stroke
			(width 0)
			(type solid)
		)
		(fill yes)
		(layer "F.Cu")
		(net "M_E_CPU0_SA_DQ<3>")
	)
	(gr_poly
		(pts
			(xy 387.981444 -294.816276) (xy 387.930644 -294.816276) (xy 387.829044 -294.852598) (xy 387.829044 -295.043098)
			(xy 387.930644 -295.079166) (xy 387.981444 -295.079166)
		)
		(stroke
			(width 0)
			(type solid)
		)
		(fill yes)
		(layer "F.Cu")
		(net "M_E_CPU0_SA_DQ<3>")
	)
	(gr_poly
		(pts
			(xy 387.981444 -294.219376) (xy 387.930644 -294.219376) (xy 387.829044 -294.255698) (xy 387.829044 -294.446198)
			(xy 387.930644 -294.482266) (xy 387.981444 -294.482266)
		)
		(stroke
			(width 0)
			(type solid)
		)
		(fill yes)
		(layer "F.Cu")
		(net "M_E_CPU0_SA_DQ<3>")
	)
	(gr_poly
		(pts
			(xy 387.981444 -293.622476) (xy 387.930644 -293.622476) (xy 387.829044 -293.658798) (xy 387.829044 -293.849298)
			(xy 387.930644 -293.885366) (xy 387.981444 -293.885366)
		)
		(stroke
			(width 0)
			(type solid)
		)
		(fill yes)
		(layer "F.Cu")
		(net "M_E_CPU0_SA_DQ<3>")
	)
	(gr_poly
		(pts
			(xy 387.981444 -293.025576) (xy 387.930644 -293.025576) (xy 387.829044 -293.061898) (xy 387.829044 -293.252398)
			(xy 387.930644 -293.288466) (xy 387.981444 -293.288466)
		)
		(stroke
			(width 0)
			(type solid)
		)
		(fill yes)
		(layer "F.Cu")
		(net "M_E_CPU0_SA_DQ<3>")
	)
	(gr_poly
		(pts
			(xy 387.981444 -292.428676) (xy 387.930644 -292.428676) (xy 387.829044 -292.464998) (xy 387.829044 -292.655498)
			(xy 387.930644 -292.691566) (xy 387.981444 -292.691566)
		)
		(stroke
			(width 0)
			(type solid)
		)
		(fill yes)
		(layer "F.Cu")
		(net "M_E_CPU0_SA_DQ<3>")
	)
	(gr_poly
		(pts
			(xy 387.981444 -291.831776) (xy 387.930644 -291.831776) (xy 387.829044 -291.868098) (xy 387.829044 -292.058598)
			(xy 387.930644 -292.094666) (xy 387.981444 -292.094666)
		)
		(stroke
			(width 0)
			(type solid)
		)
		(fill yes)
		(layer "F.Cu")
		(net "M_E_CPU0_SA_DQ<3>")
	)
	(gr_poly
		(pts
			(xy 387.981444 -291.234876) (xy 387.930644 -291.234876) (xy 387.829044 -291.271198) (xy 387.829044 -291.461698)
			(xy 387.930644 -291.497766) (xy 387.981444 -291.497766)
		)
		(stroke
			(width 0)
			(type solid)
		)
		(fill yes)
		(layer "F.Cu")
		(net "M_E_CPU0_SA_DQ<3>")
	)
	(gr_poly
		(pts
			(xy 387.981444 -290.637976) (xy 387.930644 -290.637976) (xy 387.829044 -290.674298) (xy 387.829044 -290.864798)
			(xy 387.930644 -290.900866) (xy 387.981444 -290.900866)
		)
		(stroke
			(width 0)
			(type solid)
		)
		(fill yes)
		(layer "F.Cu")
		(net "M_E_CPU0_SA_DQ<3>")
	)
	(gr_poly
		(pts
			(xy 387.981444 -290.041076) (xy 387.930644 -290.041076) (xy 387.829044 -290.077398) (xy 387.829044 -290.267898)
			(xy 387.930644 -290.303966) (xy 387.981444 -290.303966)
		)
		(stroke
			(width 0)
			(type solid)
		)
		(fill yes)
		(layer "F.Cu")
		(net "M_E_CPU0_SA_DQ<3>")
	)
	(gr_poly
		(pts
			(xy 387.981444 -289.444176) (xy 387.930644 -289.444176) (xy 387.829044 -289.480498) (xy 387.829044 -289.670998)
			(xy 387.930644 -289.707066) (xy 387.981444 -289.707066)
		)
		(stroke
			(width 0)
			(type solid)
		)
		(fill yes)
		(layer "F.Cu")
		(net "M_E_CPU0_SA_DQ<3>")
	)
	(gr_poly
		(pts
			(xy 387.981444 -288.847276) (xy 387.930644 -288.847276) (xy 387.829044 -288.883598) (xy 387.829044 -289.074098)
			(xy 387.930644 -289.110166) (xy 387.981444 -289.110166)
		)
		(stroke
			(width 0)
			(type solid)
		)
		(fill yes)
		(layer "F.Cu")
		(net "M_E_CPU0_SA_DQ<3>")
	)
	(gr_poly
		(pts
			(xy 387.981444 -288.250376) (xy 387.930644 -288.250376) (xy 387.829044 -288.286698) (xy 387.829044 -288.477198)
			(xy 387.930644 -288.513266) (xy 387.981444 -288.513266)
		)
		(stroke
			(width 0)
			(type solid)
		)
		(fill yes)
		(layer "F.Cu")
		(net "M_E_CPU0_SA_DQ<3>")
	)
	(gr_poly
		(pts
			(xy 387.981444 -287.653476) (xy 387.930644 -287.653476) (xy 387.829044 -287.689798) (xy 387.829044 -287.880298)
			(xy 387.930644 -287.916366) (xy 387.981444 -287.916366)
		)
		(stroke
			(width 0)
			(type solid)
		)
		(fill yes)
		(layer "F.Cu")
		(net "M_E_CPU0_SA_DQ<3>")
	)
	(gr_poly
		(pts
			(xy 387.981444 -287.056576) (xy 387.930644 -287.056576) (xy 387.829044 -287.092898) (xy 387.829044 -287.283398)
			(xy 387.930644 -287.319466) (xy 387.981444 -287.319466)
		)
		(stroke
			(width 0)
			(type solid)
		)
		(fill yes)
		(layer "F.Cu")
		(net "M_E_CPU0_SA_DQ<3>")
	)
	(gr_poly
		(pts
			(xy 387.981444 -286.459676) (xy 387.930644 -286.459676) (xy 387.829044 -286.495998) (xy 387.829044 -286.686498)
			(xy 387.930644 -286.722566) (xy 387.981444 -286.722566)
		)
		(stroke
			(width 0)
			(type solid)
		)
		(fill yes)
		(layer "F.Cu")
		(net "M_E_CPU0_SA_DQ<3>")
	)
	(gr_poly
		(pts
			(xy 387.981444 -285.862776) (xy 387.930644 -285.862776) (xy 387.829044 -285.899098) (xy 387.829044 -286.089598)
			(xy 387.930644 -286.125666) (xy 387.981444 -286.125666)
		)
		(stroke
			(width 0)
			(type solid)
		)
		(fill yes)
		(layer "F.Cu")
		(net "M_E_CPU0_SA_DQ<3>")
	)
	(gr_poly
		(pts
			(xy 387.981444 -285.265876) (xy 387.930644 -285.265876) (xy 387.829044 -285.302198) (xy 387.829044 -285.492698)
			(xy 387.930644 -285.528766) (xy 387.981444 -285.528766)
		)
		(stroke
			(width 0)
			(type solid)
		)
		(fill yes)
		(layer "F.Cu")
		(net "M_E_CPU0_SA_DQ<3>")
	)
	(gr_poly
		(pts
			(xy 387.981444 -284.668976) (xy 387.930644 -284.668976) (xy 387.829044 -284.705298) (xy 387.829044 -284.895798)
			(xy 387.930644 -284.931866) (xy 387.981444 -284.931866)
		)
		(stroke
			(width 0)
			(type solid)
		)
		(fill yes)
		(layer "F.Cu")
		(net "M_E_CPU0_SA_DQ<3>")
	)
	(gr_poly
		(pts
			(xy 387.981444 -284.072076) (xy 387.930644 -284.072076) (xy 387.829044 -284.108398) (xy 387.829044 -284.298898)
			(xy 387.930644 -284.334966) (xy 387.981444 -284.334966)
		)
		(stroke
			(width 0)
			(type solid)
		)
		(fill yes)
		(layer "F.Cu")
		(net "M_E_CPU0_SA_DQ<3>")
	)
	(gr_poly
		(pts
			(xy 387.981444 -283.475176) (xy 387.930644 -283.475176) (xy 387.829044 -283.511498) (xy 387.829044 -283.701998)
			(xy 387.930644 -283.738066) (xy 387.981444 -283.738066)
		)
		(stroke
			(width 0)
			(type solid)
		)
		(fill yes)
		(layer "F.Cu")
		(net "M_E_CPU0_SA_DQ<3>")
	)
	(gr_poly
		(pts
			(xy 387.981444 -282.878276) (xy 387.930644 -282.878276) (xy 387.829044 -282.914598) (xy 387.829044 -283.105098)
			(xy 387.930644 -283.141166) (xy 387.981444 -283.141166)
		)
		(stroke
			(width 0)
			(type solid)
		)
		(fill yes)
		(layer "F.Cu")
		(net "M_E_CPU0_SA_DQ<3>")
	)
	(gr_poly
		(pts
			(xy 387.981444 -282.281376) (xy 387.930644 -282.281376) (xy 387.829044 -282.317698) (xy 387.829044 -282.508198)
			(xy 387.930644 -282.544266) (xy 387.981444 -282.544266)
		)
		(stroke
			(width 0)
			(type solid)
		)
		(fill yes)
		(layer "F.Cu")
		(net "M_E_CPU0_SA_DQ<3>")
	)
	(gr_poly
		(pts
			(xy 387.981444 -281.684476) (xy 387.930644 -281.684476) (xy 387.829044 -281.720798) (xy 387.829044 -281.911298)
			(xy 387.930644 -281.947366) (xy 387.981444 -281.947366)
		)
		(stroke
			(width 0)
			(type solid)
		)
		(fill yes)
		(layer "F.Cu")
		(net "M_E_CPU0_SA_DQ<3>")
	)
	(gr_poly
		(pts
			(xy 388.10438 -224.539302) (xy 388.10438 -224.348802) (xy 388.00278 -224.31248) (xy 387.95198 -224.31248)
			(xy 387.95198 -224.57537) (xy 388.00278 -224.57537)
		)
		(stroke
			(width 0)
			(type solid)
		)
		(fill yes)
		(layer "F.Cu")
		(net "M_E_CPU0_SB_DQ<29>")
	)
	(gr_poly
		(pts
			(xy 388.10438 -223.942402) (xy 388.10438 -223.751902) (xy 388.00278 -223.71558) (xy 387.95198 -223.71558)
			(xy 387.95198 -223.97847) (xy 388.00278 -223.97847)
		)
		(stroke
			(width 0)
			(type solid)
		)
		(fill yes)
		(layer "F.Cu")
		(net "M_E_CPU0_SB_DQ<29>")
	)
	(gr_poly
		(pts
			(xy 388.10438 -223.345502) (xy 388.10438 -223.155002) (xy 388.00278 -223.11868) (xy 387.95198 -223.11868)
			(xy 387.95198 -223.38157) (xy 388.00278 -223.38157)
		)
		(stroke
			(width 0)
			(type solid)
		)
		(fill yes)
		(layer "F.Cu")
		(net "M_E_CPU0_SB_DQ<29>")
	)
	(gr_poly
		(pts
			(xy 388.10438 -222.748602) (xy 388.10438 -222.558102) (xy 388.00278 -222.52178) (xy 387.95198 -222.52178)
			(xy 387.95198 -222.78467) (xy 388.00278 -222.78467)
		)
		(stroke
			(width 0)
			(type solid)
		)
		(fill yes)
		(layer "F.Cu")
		(net "M_E_CPU0_SB_DQ<29>")
	)
	(gr_poly
		(pts
			(xy 388.10438 -222.151702) (xy 388.10438 -221.961202) (xy 388.00278 -221.92488) (xy 387.95198 -221.92488)
			(xy 387.95198 -222.18777) (xy 388.00278 -222.18777)
		)
		(stroke
			(width 0)
			(type solid)
		)
		(fill yes)
		(layer "F.Cu")
		(net "M_E_CPU0_SB_DQ<29>")
	)
	(gr_poly
		(pts
			(xy 388.10438 -221.554802) (xy 388.10438 -221.364302) (xy 388.00278 -221.32798) (xy 387.95198 -221.32798)
			(xy 387.95198 -221.59087) (xy 388.00278 -221.59087)
		)
		(stroke
			(width 0)
			(type solid)
		)
		(fill yes)
		(layer "F.Cu")
		(net "M_E_CPU0_SB_DQ<29>")
	)
	(gr_poly
		(pts
			(xy 388.10438 -220.957902) (xy 388.10438 -220.767402) (xy 388.00278 -220.73108) (xy 387.95198 -220.73108)
			(xy 387.95198 -220.99397) (xy 388.00278 -220.99397)
		)
		(stroke
			(width 0)
			(type solid)
		)
		(fill yes)
		(layer "F.Cu")
		(net "M_E_CPU0_SB_DQ<29>")
	)
	(gr_poly
		(pts
			(xy 388.10438 -220.361002) (xy 388.10438 -220.170502) (xy 388.00278 -220.13418) (xy 387.95198 -220.13418)
			(xy 387.95198 -220.39707) (xy 388.00278 -220.39707)
		)
		(stroke
			(width 0)
			(type solid)
		)
		(fill yes)
		(layer "F.Cu")
		(net "M_E_CPU0_SB_DQ<29>")
	)
	(gr_poly
		(pts
			(xy 388.10438 -219.764102) (xy 388.10438 -219.573602) (xy 388.00278 -219.53728) (xy 387.95198 -219.53728)
			(xy 387.95198 -219.80017) (xy 388.00278 -219.80017)
		)
		(stroke
			(width 0)
			(type solid)
		)
		(fill yes)
		(layer "F.Cu")
		(net "M_E_CPU0_SB_DQ<29>")
	)
	(gr_poly
		(pts
			(xy 388.10438 -219.167202) (xy 388.10438 -218.976702) (xy 388.00278 -218.94038) (xy 387.95198 -218.94038)
			(xy 387.95198 -219.20327) (xy 388.00278 -219.20327)
		)
		(stroke
			(width 0)
			(type solid)
		)
		(fill yes)
		(layer "F.Cu")
		(net "M_E_CPU0_SB_DQ<29>")
	)
	(gr_poly
		(pts
			(xy 388.10438 -218.570302) (xy 388.10438 -218.379802) (xy 388.00278 -218.34348) (xy 387.95198 -218.34348)
			(xy 387.95198 -218.60637) (xy 388.00278 -218.60637)
		)
		(stroke
			(width 0)
			(type solid)
		)
		(fill yes)
		(layer "F.Cu")
		(net "M_E_CPU0_SB_DQ<29>")
	)
	(gr_poly
		(pts
			(xy 388.10438 -217.973402) (xy 388.10438 -217.782902) (xy 388.00278 -217.74658) (xy 387.95198 -217.74658)
			(xy 387.95198 -218.00947) (xy 388.00278 -218.00947)
		)
		(stroke
			(width 0)
			(type solid)
		)
		(fill yes)
		(layer "F.Cu")
		(net "M_E_CPU0_SB_DQ<29>")
	)
	(gr_poly
		(pts
			(xy 388.10438 -217.376502) (xy 388.10438 -217.186002) (xy 388.00278 -217.14968) (xy 387.95198 -217.14968)
			(xy 387.95198 -217.41257) (xy 388.00278 -217.41257)
		)
		(stroke
			(width 0)
			(type solid)
		)
		(fill yes)
		(layer "F.Cu")
		(net "M_E_CPU0_SB_DQ<29>")
	)
	(gr_poly
		(pts
			(xy 388.10438 -216.779602) (xy 388.10438 -216.589102) (xy 388.00278 -216.55278) (xy 387.95198 -216.55278)
			(xy 387.95198 -216.81567) (xy 388.00278 -216.81567)
		)
		(stroke
			(width 0)
			(type solid)
		)
		(fill yes)
		(layer "F.Cu")
		(net "M_E_CPU0_SB_DQ<29>")
	)
	(gr_poly
		(pts
			(xy 388.10438 -216.182702) (xy 388.10438 -215.992202) (xy 388.00278 -215.95588) (xy 387.95198 -215.95588)
			(xy 387.95198 -216.21877) (xy 388.00278 -216.21877)
		)
		(stroke
			(width 0)
			(type solid)
		)
		(fill yes)
		(layer "F.Cu")
		(net "M_E_CPU0_SB_DQ<29>")
	)
	(gr_poly
		(pts
			(xy 388.10438 -215.585802) (xy 388.10438 -215.395302) (xy 388.00278 -215.35898) (xy 387.95198 -215.35898)
			(xy 387.95198 -215.62187) (xy 388.00278 -215.62187)
		)
		(stroke
			(width 0)
			(type solid)
		)
		(fill yes)
		(layer "F.Cu")
		(net "M_E_CPU0_SB_DQ<29>")
	)
	(gr_poly
		(pts
			(xy 388.133844 -295.341294) (xy 388.133844 -295.150794) (xy 388.032244 -295.114726) (xy 387.981444 -295.114726)
			(xy 387.981444 -295.377616) (xy 388.032244 -295.377616)
		)
		(stroke
			(width 0)
			(type solid)
		)
		(fill yes)
		(layer "F.Cu")
		(net "M_E_CPU0_SA_DQ<3>")
	)
	(gr_poly
		(pts
			(xy 388.133844 -294.744394) (xy 388.133844 -294.553894) (xy 388.032244 -294.517826) (xy 387.981444 -294.517826)
			(xy 387.981444 -294.780716) (xy 388.032244 -294.780716)
		)
		(stroke
			(width 0)
			(type solid)
		)
		(fill yes)
		(layer "F.Cu")
		(net "M_E_CPU0_SA_DQ<3>")
	)
	(gr_poly
		(pts
			(xy 388.133844 -294.147494) (xy 388.133844 -293.956994) (xy 388.032244 -293.920926) (xy 387.981444 -293.920926)
			(xy 387.981444 -294.183816) (xy 388.032244 -294.183816)
		)
		(stroke
			(width 0)
			(type solid)
		)
		(fill yes)
		(layer "F.Cu")
		(net "M_E_CPU0_SA_DQ<3>")
	)
	(gr_poly
		(pts
			(xy 388.133844 -293.550594) (xy 388.133844 -293.360094) (xy 388.032244 -293.324026) (xy 387.981444 -293.324026)
			(xy 387.981444 -293.586916) (xy 388.032244 -293.586916)
		)
		(stroke
			(width 0)
			(type solid)
		)
		(fill yes)
		(layer "F.Cu")
		(net "M_E_CPU0_SA_DQ<3>")
	)
	(gr_poly
		(pts
			(xy 388.133844 -292.953694) (xy 388.133844 -292.763194) (xy 388.032244 -292.727126) (xy 387.981444 -292.727126)
			(xy 387.981444 -292.990016) (xy 388.032244 -292.990016)
		)
		(stroke
			(width 0)
			(type solid)
		)
		(fill yes)
		(layer "F.Cu")
		(net "M_E_CPU0_SA_DQ<3>")
	)
	(gr_poly
		(pts
			(xy 388.133844 -292.356794) (xy 388.133844 -292.166294) (xy 388.032244 -292.130226) (xy 387.981444 -292.130226)
			(xy 387.981444 -292.393116) (xy 388.032244 -292.393116)
		)
		(stroke
			(width 0)
			(type solid)
		)
		(fill yes)
		(layer "F.Cu")
		(net "M_E_CPU0_SA_DQ<3>")
	)
	(gr_poly
		(pts
			(xy 388.133844 -291.759894) (xy 388.133844 -291.569394) (xy 388.032244 -291.533326) (xy 387.981444 -291.533326)
			(xy 387.981444 -291.796216) (xy 388.032244 -291.796216)
		)
		(stroke
			(width 0)
			(type solid)
		)
		(fill yes)
		(layer "F.Cu")
		(net "M_E_CPU0_SA_DQ<3>")
	)
	(gr_poly
		(pts
			(xy 388.133844 -291.162994) (xy 388.133844 -290.972494) (xy 388.032244 -290.936426) (xy 387.981444 -290.936426)
			(xy 387.981444 -291.199316) (xy 388.032244 -291.199316)
		)
		(stroke
			(width 0)
			(type solid)
		)
		(fill yes)
		(layer "F.Cu")
		(net "M_E_CPU0_SA_DQ<3>")
	)
	(gr_poly
		(pts
			(xy 388.133844 -290.566094) (xy 388.133844 -290.375594) (xy 388.032244 -290.339526) (xy 387.981444 -290.339526)
			(xy 387.981444 -290.602416) (xy 388.032244 -290.602416)
		)
		(stroke
			(width 0)
			(type solid)
		)
		(fill yes)
		(layer "F.Cu")
		(net "M_E_CPU0_SA_DQ<3>")
	)
	(gr_poly
		(pts
			(xy 388.133844 -289.969194) (xy 388.133844 -289.778694) (xy 388.032244 -289.742626) (xy 387.981444 -289.742626)
			(xy 387.981444 -290.005516) (xy 388.032244 -290.005516)
		)
		(stroke
			(width 0)
			(type solid)
		)
		(fill yes)
		(layer "F.Cu")
		(net "M_E_CPU0_SA_DQ<3>")
	)
	(gr_poly
		(pts
			(xy 388.133844 -289.372294) (xy 388.133844 -289.181794) (xy 388.032244 -289.145726) (xy 387.981444 -289.145726)
			(xy 387.981444 -289.408616) (xy 388.032244 -289.408616)
		)
		(stroke
			(width 0)
			(type solid)
		)
		(fill yes)
		(layer "F.Cu")
		(net "M_E_CPU0_SA_DQ<3>")
	)
	(gr_poly
		(pts
			(xy 388.133844 -288.775394) (xy 388.133844 -288.584894) (xy 388.032244 -288.548826) (xy 387.981444 -288.548826)
			(xy 387.981444 -288.811716) (xy 388.032244 -288.811716)
		)
		(stroke
			(width 0)
			(type solid)
		)
		(fill yes)
		(layer "F.Cu")
		(net "M_E_CPU0_SA_DQ<3>")
	)
	(gr_poly
		(pts
			(xy 388.133844 -288.178494) (xy 388.133844 -287.987994) (xy 388.032244 -287.951926) (xy 387.981444 -287.951926)
			(xy 387.981444 -288.214816) (xy 388.032244 -288.214816)
		)
		(stroke
			(width 0)
			(type solid)
		)
		(fill yes)
		(layer "F.Cu")
		(net "M_E_CPU0_SA_DQ<3>")
	)
	(gr_poly
		(pts
			(xy 388.133844 -287.581594) (xy 388.133844 -287.391094) (xy 388.032244 -287.355026) (xy 387.981444 -287.355026)
			(xy 387.981444 -287.617916) (xy 388.032244 -287.617916)
		)
		(stroke
			(width 0)
			(type solid)
		)
		(fill yes)
		(layer "F.Cu")
		(net "M_E_CPU0_SA_DQ<3>")
	)
	(gr_poly
		(pts
			(xy 388.133844 -286.984694) (xy 388.133844 -286.794194) (xy 388.032244 -286.758126) (xy 387.981444 -286.758126)
			(xy 387.981444 -287.021016) (xy 388.032244 -287.021016)
		)
		(stroke
			(width 0)
			(type solid)
		)
		(fill yes)
		(layer "F.Cu")
		(net "M_E_CPU0_SA_DQ<3>")
	)
	(gr_poly
		(pts
			(xy 388.133844 -286.387794) (xy 388.133844 -286.197294) (xy 388.032244 -286.161226) (xy 387.981444 -286.161226)
			(xy 387.981444 -286.424116) (xy 388.032244 -286.424116)
		)
		(stroke
			(width 0)
			(type solid)
		)
		(fill yes)
		(layer "F.Cu")
		(net "M_E_CPU0_SA_DQ<3>")
	)
	(gr_poly
		(pts
			(xy 388.133844 -285.790894) (xy 388.133844 -285.600394) (xy 388.032244 -285.564326) (xy 387.981444 -285.564326)
			(xy 387.981444 -285.827216) (xy 388.032244 -285.827216)
		)
		(stroke
			(width 0)
			(type solid)
		)
		(fill yes)
		(layer "F.Cu")
		(net "M_E_CPU0_SA_DQ<3>")
	)
	(gr_poly
		(pts
			(xy 388.133844 -285.193994) (xy 388.133844 -285.003494) (xy 388.032244 -284.967426) (xy 387.981444 -284.967426)
			(xy 387.981444 -285.230316) (xy 388.032244 -285.230316)
		)
		(stroke
			(width 0)
			(type solid)
		)
		(fill yes)
		(layer "F.Cu")
		(net "M_E_CPU0_SA_DQ<3>")
	)
	(gr_poly
		(pts
			(xy 388.133844 -284.597094) (xy 388.133844 -284.406594) (xy 388.032244 -284.370526) (xy 387.981444 -284.370526)
			(xy 387.981444 -284.633416) (xy 388.032244 -284.633416)
		)
		(stroke
			(width 0)
			(type solid)
		)
		(fill yes)
		(layer "F.Cu")
		(net "M_E_CPU0_SA_DQ<3>")
	)
	(gr_poly
		(pts
			(xy 388.133844 -284.000194) (xy 388.133844 -283.809694) (xy 388.032244 -283.773626) (xy 387.981444 -283.773626)
			(xy 387.981444 -284.036516) (xy 388.032244 -284.036516)
		)
		(stroke
			(width 0)
			(type solid)
		)
		(fill yes)
		(layer "F.Cu")
		(net "M_E_CPU0_SA_DQ<3>")
	)
	(gr_poly
		(pts
			(xy 388.133844 -283.403294) (xy 388.133844 -283.212794) (xy 388.032244 -283.176726) (xy 387.981444 -283.176726)
			(xy 387.981444 -283.439616) (xy 388.032244 -283.439616)
		)
		(stroke
			(width 0)
			(type solid)
		)
		(fill yes)
		(layer "F.Cu")
		(net "M_E_CPU0_SA_DQ<3>")
	)
	(gr_poly
		(pts
			(xy 388.133844 -282.806394) (xy 388.133844 -282.615894) (xy 388.032244 -282.579826) (xy 387.981444 -282.579826)
			(xy 387.981444 -282.842716) (xy 388.032244 -282.842716)
		)
		(stroke
			(width 0)
			(type solid)
		)
		(fill yes)
		(layer "F.Cu")
		(net "M_E_CPU0_SA_DQ<3>")
	)
	(gr_poly
		(pts
			(xy 388.133844 -282.209494) (xy 388.133844 -282.018994) (xy 388.032244 -281.982926) (xy 387.981444 -281.982926)
			(xy 387.981444 -282.245816) (xy 388.032244 -282.245816)
		)
		(stroke
			(width 0)
			(type solid)
		)
		(fill yes)
		(layer "F.Cu")
		(net "M_E_CPU0_SA_DQ<3>")
	)
	(gr_poly
		(pts
			(xy 388.133844 -281.612594) (xy 388.133844 -281.422094) (xy 388.032244 -281.386026) (xy 387.981444 -281.386026)
			(xy 387.981444 -281.648916) (xy 388.032244 -281.648916)
		)
		(stroke
			(width 0)
			(type solid)
		)
		(fill yes)
		(layer "F.Cu")
		(net "M_E_CPU0_SA_DQ<3>")
	)
	(gr_poly
		(pts
			(xy 388.195566 -276.101048) (xy 388.241794 -276.003766) (xy 388.107174 -275.868892) (xy 388.009638 -275.91512)
			(xy 387.973824 -275.951188) (xy 388.159752 -276.137116)
		)
		(stroke
			(width 0)
			(type solid)
		)
		(fill yes)
		(layer "F.Cu")
		(net "M_E_CPU0_SA_DQ<4>")
	)
	(gr_poly
		(pts
			(xy 388.24408 -268.393418) (xy 388.290308 -268.295882) (xy 388.155434 -268.161262) (xy 388.058152 -268.20749)
			(xy 388.022084 -268.243304) (xy 388.208012 -268.429232)
		)
		(stroke
			(width 0)
			(type solid)
		)
		(fill yes)
		(layer "F.Cu")
		(net "M_E_CPU0_SA_DQ<24>")
	)
	(gr_poly
		(pts
			(xy 388.25678 -224.61093) (xy 388.20598 -224.61093) (xy 388.10438 -224.646998) (xy 388.10438 -224.837498)
			(xy 388.20598 -224.87382) (xy 388.25678 -224.87382)
		)
		(stroke
			(width 0)
			(type solid)
		)
		(fill yes)
		(layer "F.Cu")
		(net "M_E_CPU0_SB_DQ<30>")
	)
	(gr_poly
		(pts
			(xy 388.25678 -224.01403) (xy 388.20598 -224.01403) (xy 388.10438 -224.050098) (xy 388.10438 -224.240598)
			(xy 388.20598 -224.27692) (xy 388.25678 -224.27692)
		)
		(stroke
			(width 0)
			(type solid)
		)
		(fill yes)
		(layer "F.Cu")
		(net "M_E_CPU0_SB_DQ<30>")
	)
	(gr_poly
		(pts
			(xy 388.25678 -223.41713) (xy 388.20598 -223.41713) (xy 388.10438 -223.453198) (xy 388.10438 -223.643698)
			(xy 388.20598 -223.68002) (xy 388.25678 -223.68002)
		)
		(stroke
			(width 0)
			(type solid)
		)
		(fill yes)
		(layer "F.Cu")
		(net "M_E_CPU0_SB_DQ<30>")
	)
	(gr_poly
		(pts
			(xy 388.25678 -222.82023) (xy 388.20598 -222.82023) (xy 388.10438 -222.856298) (xy 388.10438 -223.046798)
			(xy 388.20598 -223.08312) (xy 388.25678 -223.08312)
		)
		(stroke
			(width 0)
			(type solid)
		)
		(fill yes)
		(layer "F.Cu")
		(net "M_E_CPU0_SB_DQ<30>")
	)
	(gr_poly
		(pts
			(xy 388.25678 -222.22333) (xy 388.20598 -222.22333) (xy 388.10438 -222.259398) (xy 388.10438 -222.449898)
			(xy 388.20598 -222.48622) (xy 388.25678 -222.48622)
		)
		(stroke
			(width 0)
			(type solid)
		)
		(fill yes)
		(layer "F.Cu")
		(net "M_E_CPU0_SB_DQ<30>")
	)
	(gr_poly
		(pts
			(xy 388.25678 -221.62643) (xy 388.20598 -221.62643) (xy 388.10438 -221.662498) (xy 388.10438 -221.852998)
			(xy 388.20598 -221.88932) (xy 388.25678 -221.88932)
		)
		(stroke
			(width 0)
			(type solid)
		)
		(fill yes)
		(layer "F.Cu")
		(net "M_E_CPU0_SB_DQ<30>")
	)
	(gr_poly
		(pts
			(xy 388.25678 -221.02953) (xy 388.20598 -221.02953) (xy 388.10438 -221.065598) (xy 388.10438 -221.256098)
			(xy 388.20598 -221.29242) (xy 388.25678 -221.29242)
		)
		(stroke
			(width 0)
			(type solid)
		)
		(fill yes)
		(layer "F.Cu")
		(net "M_E_CPU0_SB_DQ<30>")
	)
	(gr_poly
		(pts
			(xy 388.25678 -220.43263) (xy 388.20598 -220.43263) (xy 388.10438 -220.468698) (xy 388.10438 -220.659198)
			(xy 388.20598 -220.69552) (xy 388.25678 -220.69552)
		)
		(stroke
			(width 0)
			(type solid)
		)
		(fill yes)
		(layer "F.Cu")
		(net "M_E_CPU0_SB_DQ<30>")
	)
	(gr_poly
		(pts
			(xy 388.25678 -219.83573) (xy 388.20598 -219.83573) (xy 388.10438 -219.871798) (xy 388.10438 -220.062298)
			(xy 388.20598 -220.09862) (xy 388.25678 -220.09862)
		)
		(stroke
			(width 0)
			(type solid)
		)
		(fill yes)
		(layer "F.Cu")
		(net "M_E_CPU0_SB_DQ<30>")
	)
	(gr_poly
		(pts
			(xy 388.25678 -219.23883) (xy 388.20598 -219.23883) (xy 388.10438 -219.274898) (xy 388.10438 -219.465398)
			(xy 388.20598 -219.50172) (xy 388.25678 -219.50172)
		)
		(stroke
			(width 0)
			(type solid)
		)
		(fill yes)
		(layer "F.Cu")
		(net "M_E_CPU0_SB_DQ<30>")
	)
	(gr_poly
		(pts
			(xy 388.25678 -218.64193) (xy 388.20598 -218.64193) (xy 388.10438 -218.677998) (xy 388.10438 -218.868498)
			(xy 388.20598 -218.90482) (xy 388.25678 -218.90482)
		)
		(stroke
			(width 0)
			(type solid)
		)
		(fill yes)
		(layer "F.Cu")
		(net "M_E_CPU0_SB_DQ<30>")
	)
	(gr_poly
		(pts
			(xy 388.25678 -218.04503) (xy 388.20598 -218.04503) (xy 388.10438 -218.081098) (xy 388.10438 -218.271598)
			(xy 388.20598 -218.30792) (xy 388.25678 -218.30792)
		)
		(stroke
			(width 0)
			(type solid)
		)
		(fill yes)
		(layer "F.Cu")
		(net "M_E_CPU0_SB_DQ<30>")
	)
	(gr_poly
		(pts
			(xy 388.25678 -217.44813) (xy 388.20598 -217.44813) (xy 388.10438 -217.484198) (xy 388.10438 -217.674698)
			(xy 388.20598 -217.71102) (xy 388.25678 -217.71102)
		)
		(stroke
			(width 0)
			(type solid)
		)
		(fill yes)
		(layer "F.Cu")
		(net "M_E_CPU0_SB_DQ<30>")
	)
	(gr_poly
		(pts
			(xy 388.25678 -216.85123) (xy 388.20598 -216.85123) (xy 388.10438 -216.887298) (xy 388.10438 -217.077798)
			(xy 388.20598 -217.11412) (xy 388.25678 -217.11412)
		)
		(stroke
			(width 0)
			(type solid)
		)
		(fill yes)
		(layer "F.Cu")
		(net "M_E_CPU0_SB_DQ<30>")
	)
	(gr_poly
		(pts
			(xy 388.25678 -216.25433) (xy 388.20598 -216.25433) (xy 388.10438 -216.290398) (xy 388.10438 -216.480898)
			(xy 388.20598 -216.51722) (xy 388.25678 -216.51722)
		)
		(stroke
			(width 0)
			(type solid)
		)
		(fill yes)
		(layer "F.Cu")
		(net "M_E_CPU0_SB_DQ<30>")
	)
	(gr_poly
		(pts
			(xy 388.25678 -215.65743) (xy 388.20598 -215.65743) (xy 388.10438 -215.693498) (xy 388.10438 -215.883998)
			(xy 388.20598 -215.92032) (xy 388.25678 -215.92032)
		)
		(stroke
			(width 0)
			(type solid)
		)
		(fill yes)
		(layer "F.Cu")
		(net "M_E_CPU0_SB_DQ<30>")
	)
	(gr_poly
		(pts
			(xy 388.334758 -276.384004) (xy 388.370572 -276.347936) (xy 388.184898 -276.162262) (xy 388.14883 -276.198076)
			(xy 388.102602 -276.295612) (xy 388.237222 -276.430232)
		)
		(stroke
			(width 0)
			(type solid)
		)
		(fill yes)
		(layer "F.Cu")
		(net "M_E_CPU0_SA_DQ<4>")
	)
	(gr_poly
		(pts
			(xy 388.346442 -275.528024) (xy 388.38251 -275.49221) (xy 388.196582 -275.306282) (xy 388.160514 -275.342096)
			(xy 388.114286 -275.439632) (xy 388.24916 -275.574252)
		)
		(stroke
			(width 0)
			(type solid)
		)
		(fill yes)
		(layer "F.Cu")
		(net "M_E_CPU0_SA_DQ<5>")
	)
	(gr_poly
		(pts
			(xy 388.392416 -267.822934) (xy 388.42823 -267.786866) (xy 388.242302 -267.600938) (xy 388.206488 -267.637006)
			(xy 388.16026 -267.734288) (xy 388.29488 -267.869162)
		)
		(stroke
			(width 0)
			(type solid)
		)
		(fill yes)
		(layer "F.Cu")
		(net "M_E_CPU0_SA_DQ<25>")
	)
	(gr_poly
		(pts
			(xy 388.40918 -224.539302) (xy 388.40918 -224.348802) (xy 388.30758 -224.31248) (xy 388.25678 -224.31248)
			(xy 388.25678 -224.57537) (xy 388.30758 -224.57537)
		)
		(stroke
			(width 0)
			(type solid)
		)
		(fill yes)
		(layer "F.Cu")
		(net "M_E_CPU0_SB_DQ<30>")
	)
	(gr_poly
		(pts
			(xy 388.40918 -223.942402) (xy 388.40918 -223.751902) (xy 388.30758 -223.71558) (xy 388.25678 -223.71558)
			(xy 388.25678 -223.97847) (xy 388.30758 -223.97847)
		)
		(stroke
			(width 0)
			(type solid)
		)
		(fill yes)
		(layer "F.Cu")
		(net "M_E_CPU0_SB_DQ<30>")
	)
	(gr_poly
		(pts
			(xy 388.40918 -223.345502) (xy 388.40918 -223.155002) (xy 388.30758 -223.11868) (xy 388.25678 -223.11868)
			(xy 388.25678 -223.38157) (xy 388.30758 -223.38157)
		)
		(stroke
			(width 0)
			(type solid)
		)
		(fill yes)
		(layer "F.Cu")
		(net "M_E_CPU0_SB_DQ<30>")
	)
	(gr_poly
		(pts
			(xy 388.40918 -222.748602) (xy 388.40918 -222.558102) (xy 388.30758 -222.52178) (xy 388.25678 -222.52178)
			(xy 388.25678 -222.78467) (xy 388.30758 -222.78467)
		)
		(stroke
			(width 0)
			(type solid)
		)
		(fill yes)
		(layer "F.Cu")
		(net "M_E_CPU0_SB_DQ<30>")
	)
	(gr_poly
		(pts
			(xy 388.40918 -222.151702) (xy 388.40918 -221.961202) (xy 388.30758 -221.92488) (xy 388.25678 -221.92488)
			(xy 388.25678 -222.18777) (xy 388.30758 -222.18777)
		)
		(stroke
			(width 0)
			(type solid)
		)
		(fill yes)
		(layer "F.Cu")
		(net "M_E_CPU0_SB_DQ<30>")
	)
	(gr_poly
		(pts
			(xy 388.40918 -221.554802) (xy 388.40918 -221.364302) (xy 388.30758 -221.32798) (xy 388.25678 -221.32798)
			(xy 388.25678 -221.59087) (xy 388.30758 -221.59087)
		)
		(stroke
			(width 0)
			(type solid)
		)
		(fill yes)
		(layer "F.Cu")
		(net "M_E_CPU0_SB_DQ<30>")
	)
	(gr_poly
		(pts
			(xy 388.40918 -220.957902) (xy 388.40918 -220.767402) (xy 388.30758 -220.73108) (xy 388.25678 -220.73108)
			(xy 388.25678 -220.99397) (xy 388.30758 -220.99397)
		)
		(stroke
			(width 0)
			(type solid)
		)
		(fill yes)
		(layer "F.Cu")
		(net "M_E_CPU0_SB_DQ<30>")
	)
	(gr_poly
		(pts
			(xy 388.40918 -220.361002) (xy 388.40918 -220.170502) (xy 388.30758 -220.13418) (xy 388.25678 -220.13418)
			(xy 388.25678 -220.39707) (xy 388.30758 -220.39707)
		)
		(stroke
			(width 0)
			(type solid)
		)
		(fill yes)
		(layer "F.Cu")
		(net "M_E_CPU0_SB_DQ<30>")
	)
	(gr_poly
		(pts
			(xy 388.40918 -219.764102) (xy 388.40918 -219.573602) (xy 388.30758 -219.53728) (xy 388.25678 -219.53728)
			(xy 388.25678 -219.80017) (xy 388.30758 -219.80017)
		)
		(stroke
			(width 0)
			(type solid)
		)
		(fill yes)
		(layer "F.Cu")
		(net "M_E_CPU0_SB_DQ<30>")
	)
	(gr_poly
		(pts
			(xy 388.40918 -219.167202) (xy 388.40918 -218.976702) (xy 388.30758 -218.94038) (xy 388.25678 -218.94038)
			(xy 388.25678 -219.20327) (xy 388.30758 -219.20327)
		)
		(stroke
			(width 0)
			(type solid)
		)
		(fill yes)
		(layer "F.Cu")
		(net "M_E_CPU0_SB_DQ<30>")
	)
	(gr_poly
		(pts
			(xy 388.40918 -218.570302) (xy 388.40918 -218.379802) (xy 388.30758 -218.34348) (xy 388.25678 -218.34348)
			(xy 388.25678 -218.60637) (xy 388.30758 -218.60637)
		)
		(stroke
			(width 0)
			(type solid)
		)
		(fill yes)
		(layer "F.Cu")
		(net "M_E_CPU0_SB_DQ<30>")
	)
	(gr_poly
		(pts
			(xy 388.40918 -217.973402) (xy 388.40918 -217.782902) (xy 388.30758 -217.74658) (xy 388.25678 -217.74658)
			(xy 388.25678 -218.00947) (xy 388.30758 -218.00947)
		)
		(stroke
			(width 0)
			(type solid)
		)
		(fill yes)
		(layer "F.Cu")
		(net "M_E_CPU0_SB_DQ<30>")
	)
	(gr_poly
		(pts
			(xy 388.40918 -217.376502) (xy 388.40918 -217.186002) (xy 388.30758 -217.14968) (xy 388.25678 -217.14968)
			(xy 388.25678 -217.41257) (xy 388.30758 -217.41257)
		)
		(stroke
			(width 0)
			(type solid)
		)
		(fill yes)
		(layer "F.Cu")
		(net "M_E_CPU0_SB_DQ<30>")
	)
	(gr_poly
		(pts
			(xy 388.40918 -216.779602) (xy 388.40918 -216.589102) (xy 388.30758 -216.55278) (xy 388.25678 -216.55278)
			(xy 388.25678 -216.81567) (xy 388.30758 -216.81567)
		)
		(stroke
			(width 0)
			(type solid)
		)
		(fill yes)
		(layer "F.Cu")
		(net "M_E_CPU0_SB_DQ<30>")
	)
	(gr_poly
		(pts
			(xy 388.40918 -216.182702) (xy 388.40918 -215.992202) (xy 388.30758 -215.95588) (xy 388.25678 -215.95588)
			(xy 388.25678 -216.21877) (xy 388.30758 -216.21877)
		)
		(stroke
			(width 0)
			(type solid)
		)
		(fill yes)
		(layer "F.Cu")
		(net "M_E_CPU0_SB_DQ<30>")
	)
	(gr_poly
		(pts
			(xy 388.40918 -215.585802) (xy 388.40918 -215.395302) (xy 388.30758 -215.35898) (xy 388.25678 -215.35898)
			(xy 388.25678 -215.62187) (xy 388.30758 -215.62187)
		)
		(stroke
			(width 0)
			(type solid)
		)
		(fill yes)
		(layer "F.Cu")
		(net "M_E_CPU0_SB_DQ<30>")
	)
	(gr_poly
		(pts
			(xy 388.412228 -275.884386) (xy 388.458456 -275.787104) (xy 388.323836 -275.65223) (xy 388.2263 -275.698458)
			(xy 388.190486 -275.734526) (xy 388.376414 -275.920454)
		)
		(stroke
			(width 0)
			(type solid)
		)
		(fill yes)
		(layer "F.Cu")
		(net "M_E_CPU0_SA_DQ<6>")
	)
	(gr_poly
		(pts
			(xy 388.459726 -268.177772) (xy 388.505954 -268.080236) (xy 388.37108 -267.945616) (xy 388.273798 -267.991844)
			(xy 388.23773 -268.027658) (xy 388.423658 -268.213586)
		)
		(stroke
			(width 0)
			(type solid)
		)
		(fill yes)
		(layer "F.Cu")
		(net "M_E_CPU0_SA_DQ<26>")
	)
	(gr_poly
		(pts
			(xy 388.55142 -276.167342) (xy 388.587234 -276.131274) (xy 388.40156 -275.9456) (xy 388.365492 -275.981414)
			(xy 388.319264 -276.07895) (xy 388.453884 -276.21357)
		)
		(stroke
			(width 0)
			(type solid)
		)
		(fill yes)
		(layer "F.Cu")
		(net "M_E_CPU0_SA_DQ<6>")
	)
	(gr_poly
		(pts
			(xy 388.56158 -224.61093) (xy 388.51078 -224.61093) (xy 388.40918 -224.646998) (xy 388.40918 -224.837498)
			(xy 388.51078 -224.87382) (xy 388.56158 -224.87382)
		)
		(stroke
			(width 0)
			(type solid)
		)
		(fill yes)
		(layer "F.Cu")
		(net "M_E_CPU0_SB_DQ<28>")
	)
	(gr_poly
		(pts
			(xy 388.56158 -224.01403) (xy 388.51078 -224.01403) (xy 388.40918 -224.050098) (xy 388.40918 -224.240598)
			(xy 388.51078 -224.27692) (xy 388.56158 -224.27692)
		)
		(stroke
			(width 0)
			(type solid)
		)
		(fill yes)
		(layer "F.Cu")
		(net "M_E_CPU0_SB_DQ<28>")
	)
	(gr_poly
		(pts
			(xy 388.56158 -223.41713) (xy 388.51078 -223.41713) (xy 388.40918 -223.453198) (xy 388.40918 -223.643698)
			(xy 388.51078 -223.68002) (xy 388.56158 -223.68002)
		)
		(stroke
			(width 0)
			(type solid)
		)
		(fill yes)
		(layer "F.Cu")
		(net "M_E_CPU0_SB_DQ<28>")
	)
	(gr_poly
		(pts
			(xy 388.56158 -222.82023) (xy 388.51078 -222.82023) (xy 388.40918 -222.856298) (xy 388.40918 -223.046798)
			(xy 388.51078 -223.08312) (xy 388.56158 -223.08312)
		)
		(stroke
			(width 0)
			(type solid)
		)
		(fill yes)
		(layer "F.Cu")
		(net "M_E_CPU0_SB_DQ<28>")
	)
	(gr_poly
		(pts
			(xy 388.56158 -222.22333) (xy 388.51078 -222.22333) (xy 388.40918 -222.259398) (xy 388.40918 -222.449898)
			(xy 388.51078 -222.48622) (xy 388.56158 -222.48622)
		)
		(stroke
			(width 0)
			(type solid)
		)
		(fill yes)
		(layer "F.Cu")
		(net "M_E_CPU0_SB_DQ<28>")
	)
	(gr_poly
		(pts
			(xy 388.56158 -221.62643) (xy 388.51078 -221.62643) (xy 388.40918 -221.662498) (xy 388.40918 -221.852998)
			(xy 388.51078 -221.88932) (xy 388.56158 -221.88932)
		)
		(stroke
			(width 0)
			(type solid)
		)
		(fill yes)
		(layer "F.Cu")
		(net "M_E_CPU0_SB_DQ<28>")
	)
	(gr_poly
		(pts
			(xy 388.56158 -221.02953) (xy 388.51078 -221.02953) (xy 388.40918 -221.065598) (xy 388.40918 -221.256098)
			(xy 388.51078 -221.29242) (xy 388.56158 -221.29242)
		)
		(stroke
			(width 0)
			(type solid)
		)
		(fill yes)
		(layer "F.Cu")
		(net "M_E_CPU0_SB_DQ<28>")
	)
	(gr_poly
		(pts
			(xy 388.56158 -220.43263) (xy 388.51078 -220.43263) (xy 388.40918 -220.468698) (xy 388.40918 -220.659198)
			(xy 388.51078 -220.69552) (xy 388.56158 -220.69552)
		)
		(stroke
			(width 0)
			(type solid)
		)
		(fill yes)
		(layer "F.Cu")
		(net "M_E_CPU0_SB_DQ<28>")
	)
	(gr_poly
		(pts
			(xy 388.56158 -219.83573) (xy 388.51078 -219.83573) (xy 388.40918 -219.871798) (xy 388.40918 -220.062298)
			(xy 388.51078 -220.09862) (xy 388.56158 -220.09862)
		)
		(stroke
			(width 0)
			(type solid)
		)
		(fill yes)
		(layer "F.Cu")
		(net "M_E_CPU0_SB_DQ<28>")
	)
	(gr_poly
		(pts
			(xy 388.56158 -219.23883) (xy 388.51078 -219.23883) (xy 388.40918 -219.274898) (xy 388.40918 -219.465398)
			(xy 388.51078 -219.50172) (xy 388.56158 -219.50172)
		)
		(stroke
			(width 0)
			(type solid)
		)
		(fill yes)
		(layer "F.Cu")
		(net "M_E_CPU0_SB_DQ<28>")
	)
	(gr_poly
		(pts
			(xy 388.56158 -218.64193) (xy 388.51078 -218.64193) (xy 388.40918 -218.677998) (xy 388.40918 -218.868498)
			(xy 388.51078 -218.90482) (xy 388.56158 -218.90482)
		)
		(stroke
			(width 0)
			(type solid)
		)
		(fill yes)
		(layer "F.Cu")
		(net "M_E_CPU0_SB_DQ<28>")
	)
	(gr_poly
		(pts
			(xy 388.56158 -218.04503) (xy 388.51078 -218.04503) (xy 388.40918 -218.081098) (xy 388.40918 -218.271598)
			(xy 388.51078 -218.30792) (xy 388.56158 -218.30792)
		)
		(stroke
			(width 0)
			(type solid)
		)
		(fill yes)
		(layer "F.Cu")
		(net "M_E_CPU0_SB_DQ<28>")
	)
	(gr_poly
		(pts
			(xy 388.56158 -217.44813) (xy 388.51078 -217.44813) (xy 388.40918 -217.484198) (xy 388.40918 -217.674698)
			(xy 388.51078 -217.71102) (xy 388.56158 -217.71102)
		)
		(stroke
			(width 0)
			(type solid)
		)
		(fill yes)
		(layer "F.Cu")
		(net "M_E_CPU0_SB_DQ<28>")
	)
	(gr_poly
		(pts
			(xy 388.56158 -216.85123) (xy 388.51078 -216.85123) (xy 388.40918 -216.887298) (xy 388.40918 -217.077798)
			(xy 388.51078 -217.11412) (xy 388.56158 -217.11412)
		)
		(stroke
			(width 0)
			(type solid)
		)
		(fill yes)
		(layer "F.Cu")
		(net "M_E_CPU0_SB_DQ<28>")
	)
	(gr_poly
		(pts
			(xy 388.56158 -216.25433) (xy 388.51078 -216.25433) (xy 388.40918 -216.290398) (xy 388.40918 -216.480898)
			(xy 388.51078 -216.51722) (xy 388.56158 -216.51722)
		)
		(stroke
			(width 0)
			(type solid)
		)
		(fill yes)
		(layer "F.Cu")
		(net "M_E_CPU0_SB_DQ<28>")
	)
	(gr_poly
		(pts
			(xy 388.562596 -275.31187) (xy 388.598664 -275.276056) (xy 388.412736 -275.090128) (xy 388.376668 -275.125942)
			(xy 388.33044 -275.223478) (xy 388.465314 -275.358098)
		)
		(stroke
			(width 0)
			(type solid)
		)
		(fill yes)
		(layer "F.Cu")
		(net "M_E_CPU0_SA_DQ<7>")
	)
	(gr_poly
		(pts
			(xy 388.598918 -268.460474) (xy 388.634732 -268.42466) (xy 388.448804 -268.238732) (xy 388.41299 -268.2748)
			(xy 388.366762 -268.372082) (xy 388.501382 -268.506956)
		)
		(stroke
			(width 0)
			(type solid)
		)
		(fill yes)
		(layer "F.Cu")
		(net "M_E_CPU0_SA_DQ<26>")
	)
	(gr_poly
		(pts
			(xy 388.601204 -263.210294) (xy 388.647432 -263.113012) (xy 388.512812 -262.978138) (xy 388.415276 -263.024366)
			(xy 388.379462 -263.060434) (xy 388.56539 -263.246362)
		)
		(stroke
			(width 0)
			(type solid)
		)
		(fill yes)
		(layer "F.Cu")
		(net "M_E_CPU0_SA_CB<0>")
	)
	(gr_poly
		(pts
			(xy 388.617714 -276.523196) (xy 388.663942 -276.42566) (xy 388.529068 -276.29104) (xy 388.431786 -276.337268)
			(xy 388.395718 -276.373082) (xy 388.581646 -276.55901)
		)
		(stroke
			(width 0)
			(type solid)
		)
		(fill yes)
		(layer "F.Cu")
		(net "M_E_CPU0_SA_DQ<4>")
	)
	(gr_poly
		(pts
			(xy 388.629398 -275.667216) (xy 388.675626 -275.569934) (xy 388.541006 -275.43506) (xy 388.44347 -275.481288)
			(xy 388.407656 -275.517356) (xy 388.593584 -275.703284)
		)
		(stroke
			(width 0)
			(type solid)
		)
		(fill yes)
		(layer "F.Cu")
		(net "M_E_CPU0_SA_DQ<5>")
	)
	(gr_poly
		(pts
			(xy 388.665974 -268.815566) (xy 388.712202 -268.71803) (xy 388.577582 -268.58341) (xy 388.4803 -268.629638)
			(xy 388.444232 -268.665452) (xy 388.63016 -268.85138)
		)
		(stroke
			(width 0)
			(type solid)
		)
		(fill yes)
		(layer "F.Cu")
		(net "M_E_CPU0_SA_DQ<24>")
	)
	(gr_poly
		(pts
			(xy 388.675118 -267.962126) (xy 388.7216 -267.86459) (xy 388.586726 -267.72997) (xy 388.489444 -267.776198)
			(xy 388.453376 -267.812012) (xy 388.639304 -267.99794)
		)
		(stroke
			(width 0)
			(type solid)
		)
		(fill yes)
		(layer "F.Cu")
		(net "M_E_CPU0_SA_DQ<25>")
	)
	(gr_poly
		(pts
			(xy 388.709916 -245.919752) (xy 388.673848 -245.818152) (xy 388.483348 -245.818152) (xy 388.44728 -245.919752)
			(xy 388.44728 -245.970552) (xy 388.709916 -245.970552)
		)
		(stroke
			(width 0)
			(type solid)
		)
		(fill yes)
		(layer "F.Cu")
		(net "M_E_CPU0_SB_CS_N<1>")
	)
	(gr_poly
		(pts
			(xy 388.709916 -245.614952) (xy 388.673848 -245.513352) (xy 388.483348 -245.513352) (xy 388.44728 -245.614952)
			(xy 388.44728 -245.665752) (xy 388.709916 -245.665752)
		)
		(stroke
			(width 0)
			(type solid)
		)
		(fill yes)
		(layer "F.Cu")
		(net "M_E_CPU0_SB_CS_N<3>")
	)
	(gr_poly
		(pts
			(xy 388.71398 -224.539302) (xy 388.71398 -224.348802) (xy 388.61238 -224.31248) (xy 388.56158 -224.31248)
			(xy 388.56158 -224.57537) (xy 388.61238 -224.57537)
		)
		(stroke
			(width 0)
			(type solid)
		)
		(fill yes)
		(layer "F.Cu")
		(net "M_E_CPU0_SB_DQ<28>")
	)
	(gr_poly
		(pts
			(xy 388.71398 -223.942402) (xy 388.71398 -223.751902) (xy 388.61238 -223.71558) (xy 388.56158 -223.71558)
			(xy 388.56158 -223.97847) (xy 388.61238 -223.97847)
		)
		(stroke
			(width 0)
			(type solid)
		)
		(fill yes)
		(layer "F.Cu")
		(net "M_E_CPU0_SB_DQ<28>")
	)
	(gr_poly
		(pts
			(xy 388.71398 -223.345502) (xy 388.71398 -223.155002) (xy 388.61238 -223.11868) (xy 388.56158 -223.11868)
			(xy 388.56158 -223.38157) (xy 388.61238 -223.38157)
		)
		(stroke
			(width 0)
			(type solid)
		)
		(fill yes)
		(layer "F.Cu")
		(net "M_E_CPU0_SB_DQ<28>")
	)
	(gr_poly
		(pts
			(xy 388.71398 -222.748602) (xy 388.71398 -222.558102) (xy 388.61238 -222.52178) (xy 388.56158 -222.52178)
			(xy 388.56158 -222.78467) (xy 388.61238 -222.78467)
		)
		(stroke
			(width 0)
			(type solid)
		)
		(fill yes)
		(layer "F.Cu")
		(net "M_E_CPU0_SB_DQ<28>")
	)
	(gr_poly
		(pts
			(xy 388.71398 -222.151702) (xy 388.71398 -221.961202) (xy 388.61238 -221.92488) (xy 388.56158 -221.92488)
			(xy 388.56158 -222.18777) (xy 388.61238 -222.18777)
		)
		(stroke
			(width 0)
			(type solid)
		)
		(fill yes)
		(layer "F.Cu")
		(net "M_E_CPU0_SB_DQ<28>")
	)
	(gr_poly
		(pts
			(xy 388.71398 -221.554802) (xy 388.71398 -221.364302) (xy 388.61238 -221.32798) (xy 388.56158 -221.32798)
			(xy 388.56158 -221.59087) (xy 388.61238 -221.59087)
		)
		(stroke
			(width 0)
			(type solid)
		)
		(fill yes)
		(layer "F.Cu")
		(net "M_E_CPU0_SB_DQ<28>")
	)
	(gr_poly
		(pts
			(xy 388.71398 -220.957902) (xy 388.71398 -220.767402) (xy 388.61238 -220.73108) (xy 388.56158 -220.73108)
			(xy 388.56158 -220.99397) (xy 388.61238 -220.99397)
		)
		(stroke
			(width 0)
			(type solid)
		)
		(fill yes)
		(layer "F.Cu")
		(net "M_E_CPU0_SB_DQ<28>")
	)
	(gr_poly
		(pts
			(xy 388.71398 -220.361002) (xy 388.71398 -220.170502) (xy 388.61238 -220.13418) (xy 388.56158 -220.13418)
			(xy 388.56158 -220.39707) (xy 388.61238 -220.39707)
		)
		(stroke
			(width 0)
			(type solid)
		)
		(fill yes)
		(layer "F.Cu")
		(net "M_E_CPU0_SB_DQ<28>")
	)
	(gr_poly
		(pts
			(xy 388.71398 -219.764102) (xy 388.71398 -219.573602) (xy 388.61238 -219.53728) (xy 388.56158 -219.53728)
			(xy 388.56158 -219.80017) (xy 388.61238 -219.80017)
		)
		(stroke
			(width 0)
			(type solid)
		)
		(fill yes)
		(layer "F.Cu")
		(net "M_E_CPU0_SB_DQ<28>")
	)
	(gr_poly
		(pts
			(xy 388.71398 -219.167202) (xy 388.71398 -218.976702) (xy 388.61238 -218.94038) (xy 388.56158 -218.94038)
			(xy 388.56158 -219.20327) (xy 388.61238 -219.20327)
		)
		(stroke
			(width 0)
			(type solid)
		)
		(fill yes)
		(layer "F.Cu")
		(net "M_E_CPU0_SB_DQ<28>")
	)
	(gr_poly
		(pts
			(xy 388.71398 -218.570302) (xy 388.71398 -218.379802) (xy 388.61238 -218.34348) (xy 388.56158 -218.34348)
			(xy 388.56158 -218.60637) (xy 388.61238 -218.60637)
		)
		(stroke
			(width 0)
			(type solid)
		)
		(fill yes)
		(layer "F.Cu")
		(net "M_E_CPU0_SB_DQ<28>")
	)
	(gr_poly
		(pts
			(xy 388.71398 -217.973402) (xy 388.71398 -217.782902) (xy 388.61238 -217.74658) (xy 388.56158 -217.74658)
			(xy 388.56158 -218.00947) (xy 388.61238 -218.00947)
		)
		(stroke
			(width 0)
			(type solid)
		)
		(fill yes)
		(layer "F.Cu")
		(net "M_E_CPU0_SB_DQ<28>")
	)
	(gr_poly
		(pts
			(xy 388.71398 -217.376502) (xy 388.71398 -217.186002) (xy 388.61238 -217.14968) (xy 388.56158 -217.14968)
			(xy 388.56158 -217.41257) (xy 388.61238 -217.41257)
		)
		(stroke
			(width 0)
			(type solid)
		)
		(fill yes)
		(layer "F.Cu")
		(net "M_E_CPU0_SB_DQ<28>")
	)
	(gr_poly
		(pts
			(xy 388.71398 -216.779602) (xy 388.71398 -216.589102) (xy 388.61238 -216.55278) (xy 388.56158 -216.55278)
			(xy 388.56158 -216.81567) (xy 388.61238 -216.81567)
		)
		(stroke
			(width 0)
			(type solid)
		)
		(fill yes)
		(layer "F.Cu")
		(net "M_E_CPU0_SB_DQ<28>")
	)
	(gr_poly
		(pts
			(xy 388.71398 -216.182702) (xy 388.71398 -215.992202) (xy 388.61238 -215.95588) (xy 388.56158 -215.95588)
			(xy 388.56158 -216.21877) (xy 388.61238 -216.21877)
		)
		(stroke
			(width 0)
			(type solid)
		)
		(fill yes)
		(layer "F.Cu")
		(net "M_E_CPU0_SB_DQ<28>")
	)
	(gr_poly
		(pts
			(xy 388.751572 -242.944904) (xy 388.715758 -242.90909) (xy 388.618222 -242.862862) (xy 388.483602 -242.997482)
			(xy 388.52983 -243.095018) (xy 388.565644 -243.130832)
		)
		(stroke
			(width 0)
			(type solid)
		)
		(fill yes)
		(layer "F.Cu")
		(net "M_E_CPU0_SB_CB<7>")
	)
	(gr_poly
		(pts
			(xy 388.76859 -275.950172) (xy 388.804404 -275.914104) (xy 388.61873 -275.72843) (xy 388.582662 -275.764244)
			(xy 388.536434 -275.86178) (xy 388.671054 -275.9964)
		)
		(stroke
			(width 0)
			(type solid)
		)
		(fill yes)
		(layer "F.Cu")
		(net "M_E_CPU0_SA_DQ<5>")
	)
	(gr_poly
		(pts
			(xy 388.81431 -268.244828) (xy 388.850378 -268.209014) (xy 388.66445 -268.023086) (xy 388.628636 -268.0589)
			(xy 388.582408 -268.156436) (xy 388.717028 -268.291056)
		)
		(stroke
			(width 0)
			(type solid)
		)
		(fill yes)
		(layer "F.Cu")
		(net "M_E_CPU0_SA_DQ<25>")
	)
	(gr_poly
		(pts
			(xy 388.81685 -262.994648) (xy 388.863078 -262.897366) (xy 388.728458 -262.762492) (xy 388.630922 -262.80872)
			(xy 388.595108 -262.844788) (xy 388.781036 -263.030716)
		)
		(stroke
			(width 0)
			(type solid)
		)
		(fill yes)
		(layer "F.Cu")
		(net "M_E_CPU0_SA_CB<2>")
	)
	(gr_poly
		(pts
			(xy 388.834376 -276.306534) (xy 388.880604 -276.208998) (xy 388.74573 -276.074378) (xy 388.648448 -276.120606)
			(xy 388.61238 -276.15642) (xy 388.798308 -276.342348)
		)
		(stroke
			(width 0)
			(type solid)
		)
		(fill yes)
		(layer "F.Cu")
		(net "M_E_CPU0_SA_DQ<6>")
	)
	(gr_poly
		(pts
			(xy 388.835646 -277.15591) (xy 388.784084 -276.8981) (xy 388.7343 -276.908006) (xy 388.641844 -276.963378)
			(xy 388.679182 -277.150322) (xy 388.785862 -277.165816)
		)
		(stroke
			(width 0)
			(type solid)
		)
		(fill yes)
		(layer "F.Cu")
		(net "M_E_CPU0_SA_DQ<4>")
	)
	(gr_poly
		(pts
			(xy 388.83844 -243.504974) (xy 388.791958 -243.407438) (xy 388.756144 -243.371624) (xy 388.570216 -243.557552)
			(xy 388.606284 -243.593366) (xy 388.703566 -243.639594)
		)
		(stroke
			(width 0)
			(type solid)
		)
		(fill yes)
		(layer "F.Cu")
		(net "M_E_CPU0_SB_CB<5>")
	)
	(gr_poly
		(pts
			(xy 388.84098 -265.502898) (xy 388.887208 -265.405616) (xy 388.752588 -265.270742) (xy 388.655052 -265.31697)
			(xy 388.619238 -265.353038) (xy 388.805166 -265.538966)
		)
		(stroke
			(width 0)
			(type solid)
		)
		(fill yes)
		(layer "F.Cu")
		(net "M_E_CPU0_SA_DQ<28>")
	)
	(gr_poly
		(pts
			(xy 388.845552 -275.451062) (xy 388.89178 -275.35378) (xy 388.75716 -275.218906) (xy 388.659624 -275.265134)
			(xy 388.62381 -275.301202) (xy 388.809738 -275.48713)
		)
		(stroke
			(width 0)
			(type solid)
		)
		(fill yes)
		(layer "F.Cu")
		(net "M_E_CPU0_SA_DQ<7>")
	)
	(gr_poly
		(pts
			(xy 388.863078 -271.15135) (xy 388.909306 -271.053814) (xy 388.774686 -270.919194) (xy 388.67715 -270.965422)
			(xy 388.641336 -271.001236) (xy 388.82701 -271.187164)
		)
		(stroke
			(width 0)
			(type solid)
		)
		(fill yes)
		(layer "F.Cu")
		(net "M_E_CPU0_SA_DQ<20>")
	)
	(gr_poly
		(pts
			(xy 388.88162 -268.599666) (xy 388.927848 -268.502384) (xy 388.793228 -268.36751) (xy 388.695692 -268.413992)
			(xy 388.659878 -268.449806) (xy 388.845806 -268.635734)
		)
		(stroke
			(width 0)
			(type solid)
		)
		(fill yes)
		(layer "F.Cu")
		(net "M_E_CPU0_SA_DQ<26>")
	)
	(gr_poly
		(pts
			(xy 388.890764 -267.746226) (xy 388.936992 -267.648944) (xy 388.802372 -267.514324) (xy 388.704836 -267.560552)
			(xy 388.669022 -267.596366) (xy 388.85495 -267.782294)
		)
		(stroke
			(width 0)
			(type solid)
		)
		(fill yes)
		(layer "F.Cu")
		(net "M_E_CPU0_SA_DQ<27>")
	)
	(gr_poly
		(pts
			(xy 388.944104 -277.438612) (xy 389.03656 -277.382986) (xy 388.999222 -277.196296) (xy 388.892542 -277.180802)
			(xy 388.842758 -277.190708) (xy 388.89432 -277.448518)
		)
		(stroke
			(width 0)
			(type solid)
		)
		(fill yes)
		(layer "F.Cu")
		(net "M_E_CPU0_SA_DQ<4>")
	)
	(gr_poly
		(pts
			(xy 388.948676 -274.693634) (xy 388.994904 -274.596098) (xy 388.860284 -274.461478) (xy 388.762748 -274.507706)
			(xy 388.726934 -274.543774) (xy 388.912608 -274.729448)
		)
		(stroke
			(width 0)
			(type solid)
		)
		(fill yes)
		(layer "F.Cu")
		(net "M_E_CPU0_SA_DQ<16>")
	)
	(gr_poly
		(pts
			(xy 388.952994 -277.741126) (xy 388.901178 -277.483316) (xy 388.851394 -277.493222) (xy 388.758938 -277.548848)
			(xy 388.796276 -277.735538) (xy 388.90321 -277.751032)
		)
		(stroke
			(width 0)
			(type solid)
		)
		(fill yes)
		(layer "F.Cu")
		(net "M_E_CPU0_SA_DQ<4>")
	)
	(gr_poly
		(pts
			(xy 388.956042 -263.277604) (xy 388.991856 -263.241536) (xy 388.806182 -263.055862) (xy 388.770114 -263.091676)
			(xy 388.723886 -263.189212) (xy 388.858506 -263.323832)
		)
		(stroke
			(width 0)
			(type solid)
		)
		(fill yes)
		(layer "F.Cu")
		(net "M_E_CPU0_SA_CB<2>")
	)
	(gr_poly
		(pts
			(xy 388.964678 -230.424228) (xy 388.91845 -230.326692) (xy 388.882382 -230.290878) (xy 388.696454 -230.476806)
			(xy 388.732522 -230.51262) (xy 388.829804 -230.558848)
		)
		(stroke
			(width 0)
			(type solid)
		)
		(fill yes)
		(layer "F.Cu")
		(net "M_E_CPU0_SB_DQ<23>")
	)
	(gr_poly
		(pts
			(xy 388.967218 -243.16055) (xy 388.931404 -243.124736) (xy 388.833868 -243.078508) (xy 388.699248 -243.213128)
			(xy 388.745476 -243.310664) (xy 388.78129 -243.346478)
		)
		(stroke
			(width 0)
			(type solid)
		)
		(fill yes)
		(layer "F.Cu")
		(net "M_E_CPU0_SB_CB<5>")
	)
	(gr_poly
		(pts
			(xy 388.976362 -244.01399) (xy 388.940548 -243.977922) (xy 388.843012 -243.931694) (xy 388.708392 -244.066568)
			(xy 388.75462 -244.16385) (xy 388.790434 -244.199918)
		)
		(stroke
			(width 0)
			(type solid)
		)
		(fill yes)
		(layer "F.Cu")
		(net "M_E_CPU0_SB_CB<4>")
	)
	(gr_poly
		(pts
			(xy 388.980172 -265.785854) (xy 389.01624 -265.75004) (xy 388.830312 -265.564112) (xy 388.794244 -265.599926)
			(xy 388.748016 -265.697462) (xy 388.882636 -265.832082)
		)
		(stroke
			(width 0)
			(type solid)
		)
		(fill yes)
		(layer "F.Cu")
		(net "M_E_CPU0_SA_DQ<28>")
	)
	(gr_poly
		(pts
			(xy 388.984744 -275.734018) (xy 389.020558 -275.69795) (xy 388.834884 -275.512276) (xy 388.798816 -275.54809)
			(xy 388.752588 -275.645626) (xy 388.887208 -275.780246)
		)
		(stroke
			(width 0)
			(type solid)
		)
		(fill yes)
		(layer "F.Cu")
		(net "M_E_CPU0_SA_DQ<7>")
	)
	(gr_poly
		(pts
			(xy 389.00227 -271.434052) (xy 389.038084 -271.398238) (xy 388.85241 -271.21231) (xy 388.816342 -271.248124)
			(xy 388.770114 -271.34566) (xy 388.904734 -271.48028)
		)
		(stroke
			(width 0)
			(type solid)
		)
		(fill yes)
		(layer "F.Cu")
		(net "M_E_CPU0_SA_DQ<20>")
	)
	(gr_poly
		(pts
			(xy 389.00862 -246.326152) (xy 389.00862 -246.275352) (xy 388.745476 -246.275352) (xy 388.745476 -246.326152)
			(xy 388.781798 -246.427752) (xy 388.972298 -246.427752)
		)
		(stroke
			(width 0)
			(type solid)
		)
		(fill yes)
		(layer "F.Cu")
		(net "M_E_CPU0_SB_CS_N<2>")
	)
	(gr_poly
		(pts
			(xy 389.00862 -246.021352) (xy 389.00862 -245.970552) (xy 388.745476 -245.970552) (xy 388.745476 -246.021352)
			(xy 388.781798 -246.122952) (xy 388.972298 -246.122952)
		)
		(stroke
			(width 0)
			(type solid)
		)
		(fill yes)
		(layer "F.Cu")
		(net "M_E_CPU0_SB_CS_N<1>")
	)
	(gr_poly
		(pts
			(xy 389.00862 -245.716552) (xy 389.00862 -245.665752) (xy 388.745476 -245.665752) (xy 388.745476 -245.716552)
			(xy 388.781798 -245.818152) (xy 388.972298 -245.818152)
		)
		(stroke
			(width 0)
			(type solid)
		)
		(fill yes)
		(layer "F.Cu")
		(net "M_E_CPU0_SB_CS_N<3>")
	)
	(gr_poly
		(pts
			(xy 389.011922 -270.580104) (xy 389.04799 -270.54429) (xy 388.862062 -270.358362) (xy 388.825994 -270.394176)
			(xy 388.779766 -270.491712) (xy 388.91464 -270.626332)
		)
		(stroke
			(width 0)
			(type solid)
		)
		(fill yes)
		(layer "F.Cu")
		(net "M_E_CPU0_SA_DQ<21>")
	)
	(gr_poly
		(pts
			(xy 389.020812 -268.882622) (xy 389.05688 -268.846808) (xy 388.870952 -268.66088) (xy 388.834884 -268.696694)
			(xy 388.788656 -268.79423) (xy 388.92353 -268.92885)
		)
		(stroke
			(width 0)
			(type solid)
		)
		(fill yes)
		(layer "F.Cu")
		(net "M_E_CPU0_SA_DQ<26>")
	)
	(gr_poly
		(pts
			(xy 389.023352 -263.632442) (xy 389.06958 -263.534906) (xy 388.934706 -263.400286) (xy 388.837424 -263.446514)
			(xy 388.801356 -263.482328) (xy 388.987284 -263.668256)
		)
		(stroke
			(width 0)
			(type solid)
		)
		(fill yes)
		(layer "F.Cu")
		(net "M_E_CPU0_SA_CB<0>")
	)
	(gr_poly
		(pts
			(xy 389.029956 -268.029182) (xy 389.066024 -267.993368) (xy 388.880096 -267.80744) (xy 388.844028 -267.843254)
			(xy 388.7978 -267.94079) (xy 388.932674 -268.07541)
		)
		(stroke
			(width 0)
			(type solid)
		)
		(fill yes)
		(layer "F.Cu")
		(net "M_E_CPU0_SA_DQ<27>")
	)
	(gr_poly
		(pts
			(xy 389.032496 -262.779002) (xy 389.078724 -262.68172) (xy 388.944104 -262.546846) (xy 388.846568 -262.593074)
			(xy 388.810754 -262.629142) (xy 388.996682 -262.81507)
		)
		(stroke
			(width 0)
			(type solid)
		)
		(fill yes)
		(layer "F.Cu")
		(net "M_E_CPU0_SA_CB<1>")
	)
	(gr_poly
		(pts
			(xy 389.044688 -242.86718) (xy 388.99846 -242.769898) (xy 388.962646 -242.73383) (xy 388.776718 -242.919758)
			(xy 388.812532 -242.955572) (xy 388.910068 -243.002054)
		)
		(stroke
			(width 0)
			(type solid)
		)
		(fill yes)
		(layer "F.Cu")
		(net "M_E_CPU0_SB_CB<7>")
	)
	(gr_poly
		(pts
			(xy 389.051546 -276.089364) (xy 389.097774 -275.991828) (xy 388.9629 -275.857208) (xy 388.865618 -275.903436)
			(xy 388.82955 -275.93925) (xy 389.015478 -276.125178)
		)
		(stroke
			(width 0)
			(type solid)
		)
		(fill yes)
		(layer "F.Cu")
		(net "M_E_CPU0_SA_DQ<5>")
	)
	(gr_poly
		(pts
			(xy 389.054086 -243.72062) (xy 389.007604 -243.623084) (xy 388.97179 -243.58727) (xy 388.785862 -243.773198)
			(xy 388.82193 -243.809012) (xy 388.919212 -243.85524)
		)
		(stroke
			(width 0)
			(type solid)
		)
		(fill yes)
		(layer "F.Cu")
		(net "M_E_CPU0_SB_CB<6>")
	)
	(gr_poly
		(pts
			(xy 389.056626 -265.287252) (xy 389.102854 -265.18997) (xy 388.968234 -265.055096) (xy 388.870698 -265.101324)
			(xy 388.834884 -265.137392) (xy 389.020812 -265.32332)
		)
		(stroke
			(width 0)
			(type solid)
		)
		(fill yes)
		(layer "F.Cu")
		(net "M_E_CPU0_SA_DQ<30>")
	)
	(gr_poly
		(pts
			(xy 389.061198 -278.023828) (xy 389.153908 -277.968456) (xy 389.116316 -277.781512) (xy 389.009636 -277.766018)
			(xy 388.959852 -277.775924) (xy 389.011414 -278.033734)
		)
		(stroke
			(width 0)
			(type solid)
		)
		(fill yes)
		(layer "F.Cu")
		(net "M_E_CPU0_SA_DQ<4>")
	)
	(gr_poly
		(pts
			(xy 389.070088 -278.326342) (xy 389.018526 -278.068532) (xy 388.968742 -278.078692) (xy 388.876032 -278.134064)
			(xy 388.913624 -278.320754) (xy 389.020304 -278.336502)
		)
		(stroke
			(width 0)
			(type solid)
		)
		(fill yes)
		(layer "F.Cu")
		(net "M_E_CPU0_SA_DQ<4>")
	)
	(gr_poly
		(pts
			(xy 389.079232 -270.934942) (xy 389.12546 -270.83766) (xy 388.99084 -270.702786) (xy 388.893304 -270.749014)
			(xy 388.85749 -270.785082) (xy 389.043418 -270.97101)
		)
		(stroke
			(width 0)
			(type solid)
		)
		(fill yes)
		(layer "F.Cu")
		(net "M_E_CPU0_SA_DQ<22>")
	)
	(gr_poly
		(pts
			(xy 389.087868 -274.97659) (xy 389.123682 -274.940522) (xy 388.937754 -274.754594) (xy 388.90194 -274.790662)
			(xy 388.855712 -274.887944) (xy 388.990332 -275.022818)
		)
		(stroke
			(width 0)
			(type solid)
		)
		(fill yes)
		(layer "F.Cu")
		(net "M_E_CPU0_SA_DQ<16>")
	)
	(gr_poly
		(pts
			(xy 389.088122 -269.23746) (xy 389.13435 -269.140178) (xy 388.99973 -269.005304) (xy 388.902194 -269.051532)
			(xy 388.86638 -269.0876) (xy 389.052308 -269.273528)
		)
		(stroke
			(width 0)
			(type solid)
		)
		(fill yes)
		(layer "F.Cu")
		(net "M_E_CPU0_SA_DQ<24>")
	)
	(gr_poly
		(pts
			(xy 389.093456 -230.079804) (xy 389.057642 -230.04399) (xy 388.960106 -229.997762) (xy 388.825486 -230.132382)
			(xy 388.871714 -230.229664) (xy 388.907528 -230.265732)
		)
		(stroke
			(width 0)
			(type solid)
		)
		(fill yes)
		(layer "F.Cu")
		(net "M_E_CPU0_SB_DQ<23>")
	)
	(gr_poly
		(pts
			(xy 389.097012 -274.12315) (xy 389.13308 -274.087336) (xy 388.947152 -273.901408) (xy 388.911084 -273.937222)
			(xy 388.864856 -274.034758) (xy 388.999476 -274.169378)
		)
		(stroke
			(width 0)
			(type solid)
		)
		(fill yes)
		(layer "F.Cu")
		(net "M_E_CPU0_SA_DQ<17>")
	)
	(gr_poly
		(pts
			(xy 389.097266 -268.38402) (xy 389.143494 -268.286738) (xy 389.008874 -268.151864) (xy 388.911338 -268.198092)
			(xy 388.875524 -268.23416) (xy 389.061452 -268.420088)
		)
		(stroke
			(width 0)
			(type solid)
		)
		(fill yes)
		(layer "F.Cu")
		(net "M_E_CPU0_SA_DQ<25>")
	)
	(gr_poly
		(pts
			(xy 389.129524 -233.49458) (xy 389.09371 -233.458766) (xy 388.996174 -233.412284) (xy 388.861554 -233.547158)
			(xy 388.907782 -233.64444) (xy 388.943596 -233.680508)
		)
		(stroke
			(width 0)
			(type solid)
		)
		(fill yes)
		(layer "F.Cu")
		(net "M_E_CPU0_SB_DQ<19>")
	)
	(gr_poly
		(pts
			(xy 389.135112 -277.095966) (xy 389.08355 -276.838156) (xy 389.033766 -276.848062) (xy 388.94131 -276.903434)
			(xy 388.978648 -277.090378) (xy 389.085328 -277.105872)
		)
		(stroke
			(width 0)
			(type solid)
		)
		(fill yes)
		(layer "F.Cu")
		(net "M_E_CPU0_SA_DQ<6>")
	)
	(gr_poly
		(pts
			(xy 389.164322 -274.477988) (xy 389.21055 -274.380452) (xy 389.07593 -274.245832) (xy 388.978394 -274.29206)
			(xy 388.94258 -274.328128) (xy 389.128254 -274.513802)
		)
		(stroke
			(width 0)
			(type solid)
		)
		(fill yes)
		(layer "F.Cu")
		(net "M_E_CPU0_SA_DQ<18>")
	)
	(gr_poly
		(pts
			(xy 389.171688 -263.061958) (xy 389.207502 -263.02589) (xy 389.021828 -262.840216) (xy 388.98576 -262.87603)
			(xy 388.939532 -262.973566) (xy 389.074152 -263.108186)
		)
		(stroke
			(width 0)
			(type solid)
		)
		(fill yes)
		(layer "F.Cu")
		(net "M_E_CPU0_SA_CB<1>")
	)
	(gr_poly
		(pts
			(xy 389.17372 -242.522756) (xy 389.137652 -242.486942) (xy 389.04037 -242.440714) (xy 388.905496 -242.575334)
			(xy 388.951724 -242.67287) (xy 388.987792 -242.708684)
		)
		(stroke
			(width 0)
			(type solid)
		)
		(fill yes)
		(layer "F.Cu")
		(net "M_E_CPU0_SB_CB<7>")
	)
	(gr_poly
		(pts
			(xy 389.178546 -278.609044) (xy 389.271002 -278.553672) (xy 389.233664 -278.366982) (xy 389.126984 -278.351234)
			(xy 389.076946 -278.361394) (xy 389.128762 -278.61895)
		)
		(stroke
			(width 0)
			(type solid)
		)
		(fill yes)
		(layer "F.Cu")
		(net "M_E_CPU0_SA_DQ<4>")
	)
	(gr_poly
		(pts
			(xy 389.180324 -230.639874) (xy 389.134096 -230.542338) (xy 389.098028 -230.506524) (xy 388.9121 -230.692452)
			(xy 388.948168 -230.728266) (xy 389.04545 -230.774494)
		)
		(stroke
			(width 0)
			(type solid)
		)
		(fill yes)
		(layer "F.Cu")
		(net "M_E_CPU0_SB_DQ<21>")
	)
	(gr_poly
		(pts
			(xy 389.182864 -243.376196) (xy 389.14705 -243.340382) (xy 389.049514 -243.294154) (xy 388.914894 -243.428774)
			(xy 388.961122 -243.52631) (xy 388.996936 -243.562124)
		)
		(stroke
			(width 0)
			(type solid)
		)
		(fill yes)
		(layer "F.Cu")
		(net "M_E_CPU0_SB_CB<6>")
	)
	(gr_poly
		(pts
			(xy 389.187182 -278.911812) (xy 389.13562 -278.654002) (xy 389.085836 -278.663908) (xy 388.99338 -278.71928)
			(xy 389.030718 -278.906224) (xy 389.137398 -278.921718)
		)
		(stroke
			(width 0)
			(type solid)
		)
		(fill yes)
		(layer "F.Cu")
		(net "M_E_CPU0_SA_DQ<4>")
	)
	(gr_poly
		(pts
			(xy 389.195818 -265.570208) (xy 389.231886 -265.534394) (xy 389.045958 -265.348466) (xy 389.00989 -265.38428)
			(xy 388.963662 -265.481816) (xy 389.098282 -265.616436)
		)
		(stroke
			(width 0)
			(type solid)
		)
		(fill yes)
		(layer "F.Cu")
		(net "M_E_CPU0_SA_DQ<30>")
	)
	(gr_poly
		(pts
			(xy 389.216392 -234.05465) (xy 389.170164 -233.957114) (xy 389.134096 -233.9213) (xy 388.948168 -234.107228)
			(xy 388.984236 -234.143042) (xy 389.081518 -234.18927)
		)
		(stroke
			(width 0)
			(type solid)
		)
		(fill yes)
		(layer "F.Cu")
		(net "M_E_CPU0_SB_DQ<17>")
	)
	(gr_poly
		(pts
			(xy 389.218424 -271.217898) (xy 389.254492 -271.182084) (xy 389.068564 -270.996156) (xy 389.032496 -271.03197)
			(xy 388.986268 -271.129506) (xy 389.120888 -271.264126)
		)
		(stroke
			(width 0)
			(type solid)
		)
		(fill yes)
		(layer "F.Cu")
		(net "M_E_CPU0_SA_DQ<22>")
	)
	(gr_poly
		(pts
			(xy 389.227822 -270.364204) (xy 389.263636 -270.32839) (xy 389.077708 -270.142462) (xy 389.041894 -270.17853)
			(xy 388.995666 -270.275812) (xy 389.130286 -270.410686)
		)
		(stroke
			(width 0)
			(type solid)
		)
		(fill yes)
		(layer "F.Cu")
		(net "M_E_CPU0_SA_DQ<23>")
	)
	(gr_poly
		(pts
			(xy 389.236458 -268.666976) (xy 389.272526 -268.631162) (xy 389.086598 -268.445234) (xy 389.05053 -268.481048)
			(xy 389.004302 -268.578584) (xy 389.139176 -268.713204)
		)
		(stroke
			(width 0)
			(type solid)
		)
		(fill yes)
		(layer "F.Cu")
		(net "M_E_CPU0_SA_DQ<25>")
	)
	(gr_poly
		(pts
			(xy 389.238998 -263.416796) (xy 389.285226 -263.31926) (xy 389.150352 -263.18464) (xy 389.05307 -263.230868)
			(xy 389.017002 -263.266682) (xy 389.20293 -263.45261)
		)
		(stroke
			(width 0)
			(type solid)
		)
		(fill yes)
		(layer "F.Cu")
		(net "M_E_CPU0_SA_CB<2>")
	)
	(gr_poly
		(pts
			(xy 389.24357 -277.378668) (xy 389.336026 -277.323042) (xy 389.298688 -277.136352) (xy 389.192008 -277.120858)
			(xy 389.142224 -277.130764) (xy 389.193786 -277.388574)
		)
		(stroke
			(width 0)
			(type solid)
		)
		(fill yes)
		(layer "F.Cu")
		(net "M_E_CPU0_SA_DQ<6>")
	)
	(gr_poly
		(pts
			(xy 389.248142 -262.563356) (xy 389.29437 -262.466074) (xy 389.15975 -262.3312) (xy 389.062214 -262.377428)
			(xy 389.0264 -262.413496) (xy 389.212328 -262.599424)
		)
		(stroke
			(width 0)
			(type solid)
		)
		(fill yes)
		(layer "F.Cu")
		(net "M_E_CPU0_SA_CB<3>")
	)
	(gr_poly
		(pts
			(xy 389.252206 -277.681182) (xy 389.200644 -277.423372) (xy 389.15086 -277.433278) (xy 389.058404 -277.488904)
			(xy 389.095742 -277.675594) (xy 389.202422 -277.691088)
		)
		(stroke
			(width 0)
			(type solid)
		)
		(fill yes)
		(layer "F.Cu")
		(net "M_E_CPU0_SA_DQ<6>")
	)
	(gr_poly
		(pts
			(xy 389.260334 -243.082826) (xy 389.214106 -242.985544) (xy 389.178292 -242.949476) (xy 388.992364 -243.135404)
			(xy 389.028178 -243.171218) (xy 389.125714 -243.2177)
		)
		(stroke
			(width 0)
			(type solid)
		)
		(fill yes)
		(layer "F.Cu")
		(net "M_E_CPU0_SB_CB<5>")
	)
	(gr_poly
		(pts
			(xy 389.263128 -265.925046) (xy 389.309356 -265.82751) (xy 389.174736 -265.69289) (xy 389.0772 -265.739118)
			(xy 389.041386 -265.775186) (xy 389.22706 -265.96086)
		)
		(stroke
			(width 0)
			(type solid)
		)
		(fill yes)
		(layer "F.Cu")
		(net "M_E_CPU0_SA_DQ<28>")
	)
	(gr_poly
		(pts
			(xy 389.2677 -275.87321) (xy 389.313928 -275.775674) (xy 389.179054 -275.641054) (xy 389.081772 -275.687282)
			(xy 389.045704 -275.723096) (xy 389.231632 -275.909024)
		)
		(stroke
			(width 0)
			(type solid)
		)
		(fill yes)
		(layer "F.Cu")
		(net "M_E_CPU0_SA_DQ<7>")
	)
	(gr_poly
		(pts
			(xy 389.269732 -243.936266) (xy 389.22325 -243.83873) (xy 389.187436 -243.802916) (xy 389.001508 -243.988844)
			(xy 389.037576 -244.024658) (xy 389.134858 -244.070886)
		)
		(stroke
			(width 0)
			(type solid)
		)
		(fill yes)
		(layer "F.Cu")
		(net "M_E_CPU0_SB_CB<4>")
	)
	(gr_poly
		(pts
			(xy 389.272526 -265.071606) (xy 389.318754 -264.97407) (xy 389.18388 -264.83945) (xy 389.086598 -264.885678)
			(xy 389.05053 -264.921492) (xy 389.236458 -265.10742)
		)
		(stroke
			(width 0)
			(type solid)
		)
		(fill yes)
		(layer "F.Cu")
		(net "M_E_CPU0_SA_DQ<29>")
	)
	(gr_poly
		(pts
			(xy 389.285226 -271.573244) (xy 389.331454 -271.475962) (xy 389.196834 -271.341088) (xy 389.099298 -271.387316)
			(xy 389.063484 -271.423384) (xy 389.249158 -271.609312)
		)
		(stroke
			(width 0)
			(type solid)
		)
		(fill yes)
		(layer "F.Cu")
		(net "M_E_CPU0_SA_DQ<20>")
	)
	(gr_poly
		(pts
			(xy 389.294878 -270.719296) (xy 389.341106 -270.62176) (xy 389.206486 -270.48714) (xy 389.10895 -270.533368)
			(xy 389.073136 -270.569436) (xy 389.259064 -270.755364)
		)
		(stroke
			(width 0)
			(type solid)
		)
		(fill yes)
		(layer "F.Cu")
		(net "M_E_CPU0_SA_DQ<21>")
	)
	(gr_poly
		(pts
			(xy 389.29564 -279.19426) (xy 389.388096 -279.138888) (xy 389.350758 -278.952198) (xy 389.244078 -278.936704)
			(xy 389.194294 -278.94661) (xy 389.245856 -279.20442)
		)
		(stroke
			(width 0)
			(type solid)
		)
		(fill yes)
		(layer "F.Cu")
		(net "M_E_CPU0_SA_DQ<4>")
	)
	(gr_poly
		(pts
			(xy 389.303514 -274.760944) (xy 389.339328 -274.724876) (xy 389.1534 -274.538948) (xy 389.117586 -274.575016)
			(xy 389.071358 -274.672298) (xy 389.205978 -274.807172)
		)
		(stroke
			(width 0)
			(type solid)
		)
		(fill yes)
		(layer "F.Cu")
		(net "M_E_CPU0_SA_DQ<18>")
	)
	(gr_poly
		(pts
			(xy 389.303768 -269.021814) (xy 389.349996 -268.924532) (xy 389.215376 -268.789658) (xy 389.11784 -268.835886)
			(xy 389.082026 -268.871954) (xy 389.267954 -269.057882)
		)
		(stroke
			(width 0)
			(type solid)
		)
		(fill yes)
		(layer "F.Cu")
		(net "M_E_CPU0_SA_DQ<26>")
	)
	(gr_poly
		(pts
			(xy 389.30453 -279.497028) (xy 389.252714 -279.239218) (xy 389.20293 -279.249124) (xy 389.110474 -279.304496)
			(xy 389.147812 -279.49144) (xy 389.254492 -279.506934)
		)
		(stroke
			(width 0)
			(type solid)
		)
		(fill yes)
		(layer "F.Cu")
		(net "M_E_CPU0_SA_DQ<4>")
	)
	(gr_poly
		(pts
			(xy 389.306816 -246.529352) (xy 389.270748 -246.427752) (xy 389.080248 -246.427752) (xy 389.04418 -246.529352)
			(xy 389.04418 -246.580152) (xy 389.306816 -246.580152)
		)
		(stroke
			(width 0)
			(type solid)
		)
		(fill yes)
		(layer "F.Cu")
		(net "M_E_CPU0_SB_CS_N<0>")
	)
	(gr_poly
		(pts
			(xy 389.306816 -246.224552) (xy 389.270748 -246.122952) (xy 389.080248 -246.122952) (xy 389.04418 -246.224552)
			(xy 389.04418 -246.275352) (xy 389.306816 -246.275352)
		)
		(stroke
			(width 0)
			(type solid)
		)
		(fill yes)
		(layer "F.Cu")
		(net "M_E_CPU0_SB_CS_N<2>")
	)
	(gr_poly
		(pts
			(xy 389.306816 -245.919752) (xy 389.270748 -245.818152) (xy 389.080248 -245.818152) (xy 389.04418 -245.919752)
			(xy 389.04418 -245.970552) (xy 389.306816 -245.970552)
		)
		(stroke
			(width 0)
			(type solid)
		)
		(fill yes)
		(layer "F.Cu")
		(net "M_E_CPU0_SB_CS_N<1>")
	)
	(gr_poly
		(pts
			(xy 389.306816 -245.614952) (xy 389.270748 -245.513352) (xy 389.080248 -245.513352) (xy 389.04418 -245.614952)
			(xy 389.04418 -245.665752) (xy 389.306816 -245.665752)
		)
		(stroke
			(width 0)
			(type solid)
		)
		(fill yes)
		(layer "F.Cu")
		(net "M_E_CPU0_SB_CS_N<3>")
	)
	(gr_poly
		(pts
			(xy 389.309102 -230.29545) (xy 389.273288 -230.259636) (xy 389.175752 -230.213408) (xy 389.041132 -230.348028)
			(xy 389.08736 -230.44531) (xy 389.123174 -230.481378)
		)
		(stroke
			(width 0)
			(type solid)
		)
		(fill yes)
		(layer "F.Cu")
		(net "M_E_CPU0_SB_DQ<21>")
	)
	(gr_poly
		(pts
			(xy 389.312912 -268.168374) (xy 389.35914 -268.071092) (xy 389.22452 -267.936218) (xy 389.126984 -267.982446)
			(xy 389.09117 -268.018514) (xy 389.277098 -268.204442)
		)
		(stroke
			(width 0)
			(type solid)
		)
		(fill yes)
		(layer "F.Cu")
		(net "M_E_CPU0_SA_DQ<27>")
	)
	(gr_poly
		(pts
			(xy 389.318246 -231.14889) (xy 389.282432 -231.112822) (xy 389.184896 -231.066594) (xy 389.050276 -231.201468)
			(xy 389.096504 -231.29875) (xy 389.132318 -231.334818)
		)
		(stroke
			(width 0)
			(type solid)
		)
		(fill yes)
		(layer "F.Cu")
		(net "M_E_CPU0_SB_DQ<20>")
	)
	(gr_poly
		(pts
			(xy 389.34517 -233.710226) (xy 389.309356 -233.674412) (xy 389.21182 -233.62793) (xy 389.0772 -233.762804)
			(xy 389.123428 -233.860086) (xy 389.159242 -233.896154)
		)
		(stroke
			(width 0)
			(type solid)
		)
		(fill yes)
		(layer "F.Cu")
		(net "M_E_CPU0_SB_DQ<17>")
	)
	(gr_poly
		(pts
			(xy 389.354314 -234.563666) (xy 389.3185 -234.527598) (xy 389.220964 -234.48137) (xy 389.086344 -234.61599)
			(xy 389.132572 -234.713526) (xy 389.16864 -234.74934)
		)
		(stroke
			(width 0)
			(type solid)
		)
		(fill yes)
		(layer "F.Cu")
		(net "M_E_CPU0_SB_DQ<16>")
	)
	(gr_poly
		(pts
			(xy 389.360664 -277.963884) (xy 389.45312 -277.908512) (xy 389.415782 -277.721568) (xy 389.309102 -277.706074)
			(xy 389.259318 -277.71598) (xy 389.31088 -277.97379)
		)
		(stroke
			(width 0)
			(type solid)
		)
		(fill yes)
		(layer "F.Cu")
		(net "M_E_CPU0_SA_DQ<6>")
	)
	(gr_poly
		(pts
			(xy 389.361934 -257.79603) (xy 389.398002 -257.760216) (xy 389.212074 -257.574288) (xy 389.176006 -257.610102)
			(xy 389.129778 -257.707638) (xy 389.264652 -257.842258)
		)
		(stroke
			(width 0)
			(type solid)
		)
		(fill yes)
		(layer "F.Cu")
		(net "M_E_CPU0_SA_CS_N<0>")
	)
	(gr_poly
		(pts
			(xy 389.369554 -278.266398) (xy 389.317738 -278.008588) (xy 389.267954 -278.018748) (xy 389.175498 -278.07412)
			(xy 389.212836 -278.26081) (xy 389.319516 -278.276558)
		)
		(stroke
			(width 0)
			(type solid)
		)
		(fill yes)
		(layer "F.Cu")
		(net "M_E_CPU0_SA_DQ<6>")
	)
	(gr_poly
		(pts
			(xy 389.37057 -275.115782) (xy 389.417052 -275.018246) (xy 389.282178 -274.883626) (xy 389.184896 -274.929854)
			(xy 389.148828 -274.965668) (xy 389.334756 -275.151596)
		)
		(stroke
			(width 0)
			(type solid)
		)
		(fill yes)
		(layer "F.Cu")
		(net "M_E_CPU0_SA_DQ<16>")
	)
	(gr_poly
		(pts
			(xy 389.37819 -263.699752) (xy 389.414004 -263.663684) (xy 389.228076 -263.477756) (xy 389.192262 -263.513824)
			(xy 389.146034 -263.611106) (xy 389.280654 -263.74598)
		)
		(stroke
			(width 0)
			(type solid)
		)
		(fill yes)
		(layer "F.Cu")
		(net "M_E_CPU0_SA_CB<2>")
	)
	(gr_poly
		(pts
			(xy 389.379968 -274.262342) (xy 389.426196 -274.164806) (xy 389.291576 -274.030186) (xy 389.19404 -274.076414)
			(xy 389.158226 -274.112482) (xy 389.3439 -274.298156)
		)
		(stroke
			(width 0)
			(type solid)
		)
		(fill yes)
		(layer "F.Cu")
		(net "M_E_CPU0_SA_DQ<17>")
	)
	(gr_poly
		(pts
			(xy 389.386572 -230.00208) (xy 389.340344 -229.904798) (xy 389.30453 -229.86873) (xy 389.118602 -230.054658)
			(xy 389.154416 -230.090472) (xy 389.251952 -230.136954)
		)
		(stroke
			(width 0)
			(type solid)
		)
		(fill yes)
		(layer "F.Cu")
		(net "M_E_CPU0_SB_DQ<23>")
	)
	(gr_poly
		(pts
			(xy 389.387334 -262.846312) (xy 389.423148 -262.810244) (xy 389.237474 -262.62457) (xy 389.201406 -262.660384)
			(xy 389.155178 -262.75792) (xy 389.289798 -262.89254)
		)
		(stroke
			(width 0)
			(type solid)
		)
		(fill yes)
		(layer "F.Cu")
		(net "M_E_CPU0_SA_CB<3>")
	)
	(gr_poly
		(pts
			(xy 389.389366 -242.738402) (xy 389.353298 -242.702588) (xy 389.256016 -242.65636) (xy 389.121142 -242.79098)
			(xy 389.16737 -242.888516) (xy 389.203438 -242.92433)
		)
		(stroke
			(width 0)
			(type solid)
		)
		(fill yes)
		(layer "F.Cu")
		(net "M_E_CPU0_SB_CB<5>")
	)
	(gr_poly
		(pts
			(xy 389.39597 -230.85552) (xy 389.349742 -230.757984) (xy 389.313674 -230.72217) (xy 389.127746 -230.908098)
			(xy 389.163814 -230.943912) (xy 389.261096 -230.99014)
		)
		(stroke
			(width 0)
			(type solid)
		)
		(fill yes)
		(layer "F.Cu")
		(net "M_E_CPU0_SB_DQ<22>")
	)
	(gr_poly
		(pts
			(xy 389.39851 -243.591842) (xy 389.362696 -243.556028) (xy 389.26516 -243.5098) (xy 389.13054 -243.64442)
			(xy 389.176768 -243.741956) (xy 389.212582 -243.77777)
		)
		(stroke
			(width 0)
			(type solid)
		)
		(fill yes)
		(layer "F.Cu")
		(net "M_E_CPU0_SB_CB<4>")
	)
	(gr_poly
		(pts
			(xy 389.40232 -266.208002) (xy 389.438134 -266.171934) (xy 389.252206 -265.986006) (xy 389.216392 -266.022074)
			(xy 389.170164 -266.119356) (xy 389.304784 -266.25423)
		)
		(stroke
			(width 0)
			(type solid)
		)
		(fill yes)
		(layer "F.Cu")
		(net "M_E_CPU0_SA_DQ<28>")
	)
	(gr_poly
		(pts
			(xy 389.406892 -276.156166) (xy 389.442706 -276.120098) (xy 389.256778 -275.93417) (xy 389.220964 -275.970238)
			(xy 389.174736 -276.06752) (xy 389.309356 -276.202394)
		)
		(stroke
			(width 0)
			(type solid)
		)
		(fill yes)
		(layer "F.Cu")
		(net "M_E_CPU0_SA_DQ<7>")
	)
	(gr_poly
		(pts
			(xy 389.411718 -265.354308) (xy 389.447532 -265.318494) (xy 389.261604 -265.132566) (xy 389.22579 -265.168634)
			(xy 389.179562 -265.265916) (xy 389.314182 -265.40079)
		)
		(stroke
			(width 0)
			(type solid)
		)
		(fill yes)
		(layer "F.Cu")
		(net "M_E_CPU0_SA_DQ<29>")
	)
	(gr_poly
		(pts
			(xy 389.412734 -279.77973) (xy 389.505444 -279.724358) (xy 389.467852 -279.537414) (xy 389.361172 -279.52192)
			(xy 389.311388 -279.531826) (xy 389.36295 -279.789636)
		)
		(stroke
			(width 0)
			(type solid)
		)
		(fill yes)
		(layer "F.Cu")
		(net "M_E_CPU0_SA_DQ<4>")
	)
	(gr_poly
		(pts
			(xy 389.421624 -280.082244) (xy 389.370062 -279.824434) (xy 389.320278 -279.834594) (xy 389.227568 -279.889966)
			(xy 389.26516 -280.076656) (xy 389.37184 -280.09215)
		)
		(stroke
			(width 0)
			(type solid)
		)
		(fill yes)
		(layer "F.Cu")
		(net "M_E_CPU0_SA_DQ<4>")
	)
	(gr_poly
		(pts
			(xy 389.42264 -233.416856) (xy 389.376412 -233.31932) (xy 389.340598 -233.283506) (xy 389.15467 -233.469434)
			(xy 389.190484 -233.505248) (xy 389.28802 -233.551476)
		)
		(stroke
			(width 0)
			(type solid)
		)
		(fill yes)
		(layer "F.Cu")
		(net "M_E_CPU0_SB_DQ<19>")
	)
	(gr_poly
		(pts
			(xy 389.424418 -271.8562) (xy 389.460232 -271.820132) (xy 389.274558 -271.634204) (xy 389.23849 -271.670272)
			(xy 389.192262 -271.767554) (xy 389.326882 -271.902428)
		)
		(stroke
			(width 0)
			(type solid)
		)
		(fill yes)
		(layer "F.Cu")
		(net "M_E_CPU0_SA_DQ<20>")
	)
	(gr_poly
		(pts
			(xy 389.425688 -276.733254) (xy 389.518144 -276.677882) (xy 389.480806 -276.491192) (xy 389.374126 -276.475698)
			(xy 389.324342 -276.485604) (xy 389.375904 -276.743414)
		)
		(stroke
			(width 0)
			(type solid)
		)
		(fill yes)
		(layer "F.Cu")
		(net "M_E_CPU0_SA_DQ<5>")
	)
	(gr_poly
		(pts
			(xy 389.432038 -234.270296) (xy 389.38581 -234.17276) (xy 389.349742 -234.136946) (xy 389.163814 -234.322874)
			(xy 389.199882 -234.358688) (xy 389.297164 -234.404916)
		)
		(stroke
			(width 0)
			(type solid)
		)
		(fill yes)
		(layer "F.Cu")
		(net "M_E_CPU0_SB_DQ<18>")
	)
	(gr_poly
		(pts
			(xy 389.43407 -271.002252) (xy 389.469884 -270.966184) (xy 389.28421 -270.78051) (xy 389.248142 -270.816324)
			(xy 389.201914 -270.91386) (xy 389.336534 -271.04848)
		)
		(stroke
			(width 0)
			(type solid)
		)
		(fill yes)
		(layer "F.Cu")
		(net "M_E_CPU0_SA_DQ<21>")
	)
	(gr_poly
		(pts
			(xy 389.434324 -277.036022) (xy 389.382762 -276.778212) (xy 389.332978 -276.788118) (xy 389.240522 -276.843744)
			(xy 389.27786 -277.030434) (xy 389.38454 -277.045928)
		)
		(stroke
			(width 0)
			(type solid)
		)
		(fill yes)
		(layer "F.Cu")
		(net "M_E_CPU0_SA_DQ<5>")
	)
	(gr_poly
		(pts
			(xy 389.438642 -257.297428) (xy 389.48487 -257.199892) (xy 389.349996 -257.065272) (xy 389.252714 -257.1115)
			(xy 389.216646 -257.147314) (xy 389.402574 -257.333242)
		)
		(stroke
			(width 0)
			(type solid)
		)
		(fill yes)
		(layer "F.Cu")
		(net "M_E_CPU0_SA_CS_N<2>")
	)
	(gr_poly
		(pts
			(xy 389.44296 -269.30477) (xy 389.478774 -269.268702) (xy 389.2931 -269.083028) (xy 389.257032 -269.118842)
			(xy 389.210804 -269.216378) (xy 389.345424 -269.350998)
		)
		(stroke
			(width 0)
			(type solid)
		)
		(fill yes)
		(layer "F.Cu")
		(net "M_E_CPU0_SA_DQ<26>")
	)
	(gr_poly
		(pts
			(xy 389.445246 -264.05459) (xy 389.491474 -263.957054) (xy 389.356854 -263.822434) (xy 389.259572 -263.868662)
			(xy 389.223504 -263.904476) (xy 389.409432 -264.090404)
		)
		(stroke
			(width 0)
			(type solid)
		)
		(fill yes)
		(layer "F.Cu")
		(net "M_E_CPU0_SA_CB<0>")
	)
	(gr_poly
		(pts
			(xy 389.452104 -268.45133) (xy 389.487918 -268.415262) (xy 389.302244 -268.229588) (xy 389.266176 -268.265402)
			(xy 389.219948 -268.362938) (xy 389.354568 -268.497558)
		)
		(stroke
			(width 0)
			(type solid)
		)
		(fill yes)
		(layer "F.Cu")
		(net "M_E_CPU0_SA_DQ<27>")
	)
	(gr_poly
		(pts
			(xy 389.453882 -238.381286) (xy 389.41756 -238.279686) (xy 389.22706 -238.279686) (xy 389.190992 -238.381286)
			(xy 389.190992 -238.432086) (xy 389.453882 -238.432086)
		)
		(stroke
			(width 0)
			(type solid)
		)
		(fill yes)
		(layer "F.Cu")
		(net "M_E_CPU0_SB_DQ<10>")
	)
	(gr_poly
		(pts
			(xy 389.453882 -237.771686) (xy 389.41756 -237.670086) (xy 389.22706 -237.670086) (xy 389.190992 -237.771686)
			(xy 389.190992 -237.822486) (xy 389.453882 -237.822486)
		)
		(stroke
			(width 0)
			(type solid)
		)
		(fill yes)
		(layer "F.Cu")
		(net "M_E_CPU0_SB_DQ<11>")
	)
	(gr_poly
		(pts
			(xy 389.454644 -263.20115) (xy 389.500872 -263.103614) (xy 389.365998 -262.968994) (xy 389.268716 -263.015222)
			(xy 389.232648 -263.051036) (xy 389.418576 -263.236964)
		)
		(stroke
			(width 0)
			(type solid)
		)
		(fill yes)
		(layer "F.Cu")
		(net "M_E_CPU0_SA_CB<1>")
	)
	(gr_poly
		(pts
			(xy 389.466836 -242.445286) (xy 389.420608 -242.34775) (xy 389.38454 -242.311936) (xy 389.198866 -242.49761)
			(xy 389.23468 -242.533678) (xy 389.332216 -242.579906)
		)
		(stroke
			(width 0)
			(type solid)
		)
		(fill yes)
		(layer "F.Cu")
		(net "M_E_CPU0_SB_CB<7>")
	)
	(gr_poly
		(pts
			(xy 389.47598 -243.298472) (xy 389.429752 -243.20119) (xy 389.393938 -243.165122) (xy 389.20801 -243.35105)
			(xy 389.243824 -243.386864) (xy 389.34136 -243.433346)
		)
		(stroke
			(width 0)
			(type solid)
		)
		(fill yes)
		(layer "F.Cu")
		(net "M_E_CPU0_SB_CB<6>")
	)
	(gr_poly
		(pts
			(xy 389.477758 -278.5491) (xy 389.570468 -278.493728) (xy 389.532876 -278.307038) (xy 389.426196 -278.29129)
			(xy 389.376412 -278.30145) (xy 389.427974 -278.559006)
		)
		(stroke
			(width 0)
			(type solid)
		)
		(fill yes)
		(layer "F.Cu")
		(net "M_E_CPU0_SA_DQ<6>")
	)
	(gr_poly
		(pts
			(xy 389.478774 -265.7094) (xy 389.525002 -265.611864) (xy 389.390382 -265.477244) (xy 389.292846 -265.523472)
			(xy 389.257032 -265.55954) (xy 389.442706 -265.745214)
		)
		(stroke
			(width 0)
			(type solid)
		)
		(fill yes)
		(layer "F.Cu")
		(net "M_E_CPU0_SA_DQ<30>")
	)
	(gr_poly
		(pts
			(xy 389.486648 -278.851868) (xy 389.435086 -278.594058) (xy 389.385302 -278.603964) (xy 389.292592 -278.659336)
			(xy 389.330184 -278.84628) (xy 389.436864 -278.861774)
		)
		(stroke
			(width 0)
			(type solid)
		)
		(fill yes)
		(layer "F.Cu")
		(net "M_E_CPU0_SA_DQ<6>")
	)
	(gr_poly
		(pts
			(xy 389.488172 -264.855706) (xy 389.5344 -264.758424) (xy 389.39978 -264.62355) (xy 389.302244 -264.669778)
			(xy 389.26643 -264.705846) (xy 389.452358 -264.891774)
		)
		(stroke
			(width 0)
			(type solid)
		)
		(fill yes)
		(layer "F.Cu")
		(net "M_E_CPU0_SA_DQ<31>")
	)
	(gr_poly
		(pts
			(xy 389.50138 -271.35709) (xy 389.547608 -271.259554) (xy 389.412988 -271.124934) (xy 389.315452 -271.171162)
			(xy 389.279384 -271.206976) (xy 389.465312 -271.392904)
		)
		(stroke
			(width 0)
			(type solid)
		)
		(fill yes)
		(layer "F.Cu")
		(net "M_E_CPU0_SA_DQ<22>")
	)
	(gr_poly
		(pts
			(xy 389.50265 -260.660642) (xy 389.548878 -260.563106) (xy 389.414258 -260.428486) (xy 389.316722 -260.474714)
			(xy 389.280908 -260.510782) (xy 389.466836 -260.69671)
		)
		(stroke
			(width 0)
			(type solid)
		)
		(fill yes)
		(layer "F.Cu")
		(net "M_E_CPU0_SA_CB<4>")
	)
	(gr_poly
		(pts
			(xy 389.510016 -275.398484) (xy 389.54583 -275.36267) (xy 389.359902 -275.176742) (xy 389.324088 -275.212556)
			(xy 389.27786 -275.310092) (xy 389.41248 -275.444712)
		)
		(stroke
			(width 0)
			(type solid)
		)
		(fill yes)
		(layer "F.Cu")
		(net "M_E_CPU0_SA_DQ<16>")
	)
	(gr_poly
		(pts
			(xy 389.51027 -269.659608) (xy 389.556498 -269.562072) (xy 389.421878 -269.427452) (xy 389.324342 -269.47368)
			(xy 389.288528 -269.509748) (xy 389.474202 -269.695422)
		)
		(stroke
			(width 0)
			(type solid)
		)
		(fill yes)
		(layer "F.Cu")
		(net "M_E_CPU0_SA_DQ<24>")
	)
	(gr_poly
		(pts
			(xy 389.510524 -290.118546) (xy 389.459724 -290.118546) (xy 389.358124 -290.154868) (xy 389.358124 -290.345368)
			(xy 389.459724 -290.381436) (xy 389.510524 -290.381436)
		)
		(stroke
			(width 0)
			(type solid)
		)
		(fill yes)
		(layer "F.Cu")
		(net "M_E_CPU0_SA_DQ<4>")
	)
	(gr_poly
		(pts
			(xy 389.510524 -289.521646) (xy 389.459724 -289.521646) (xy 389.358124 -289.557968) (xy 389.358124 -289.748468)
			(xy 389.459724 -289.784536) (xy 389.510524 -289.784536)
		)
		(stroke
			(width 0)
			(type solid)
		)
		(fill yes)
		(layer "F.Cu")
		(net "M_E_CPU0_SA_DQ<4>")
	)
	(gr_poly
		(pts
			(xy 389.510524 -288.924746) (xy 389.459724 -288.924746) (xy 389.358124 -288.961068) (xy 389.358124 -289.151568)
			(xy 389.459724 -289.187636) (xy 389.510524 -289.187636)
		)
		(stroke
			(width 0)
			(type solid)
		)
		(fill yes)
		(layer "F.Cu")
		(net "M_E_CPU0_SA_DQ<4>")
	)
	(gr_poly
		(pts
			(xy 389.510524 -288.327846) (xy 389.459724 -288.327846) (xy 389.358124 -288.364168) (xy 389.358124 -288.554668)
			(xy 389.459724 -288.590736) (xy 389.510524 -288.590736)
		)
		(stroke
			(width 0)
			(type solid)
		)
		(fill yes)
		(layer "F.Cu")
		(net "M_E_CPU0_SA_DQ<4>")
	)
	(gr_poly
		(pts
			(xy 389.510524 -287.730946) (xy 389.459724 -287.730946) (xy 389.358124 -287.767268) (xy 389.358124 -287.957768)
			(xy 389.459724 -287.993836) (xy 389.510524 -287.993836)
		)
		(stroke
			(width 0)
			(type solid)
		)
		(fill yes)
		(layer "F.Cu")
		(net "M_E_CPU0_SA_DQ<4>")
	)
	(gr_poly
		(pts
			(xy 389.510524 -287.134046) (xy 389.459724 -287.134046) (xy 389.358124 -287.170368) (xy 389.358124 -287.360868)
			(xy 389.459724 -287.396936) (xy 389.510524 -287.396936)
		)
		(stroke
			(width 0)
			(type solid)
		)
		(fill yes)
		(layer "F.Cu")
		(net "M_E_CPU0_SA_DQ<4>")
	)
	(gr_poly
		(pts
			(xy 389.510524 -286.537146) (xy 389.459724 -286.537146) (xy 389.358124 -286.573468) (xy 389.358124 -286.763968)
			(xy 389.459724 -286.800036) (xy 389.510524 -286.800036)
		)
		(stroke
			(width 0)
			(type solid)
		)
		(fill yes)
		(layer "F.Cu")
		(net "M_E_CPU0_SA_DQ<4>")
	)
	(gr_poly
		(pts
			(xy 389.510524 -285.940246) (xy 389.459724 -285.940246) (xy 389.358124 -285.976568) (xy 389.358124 -286.167068)
			(xy 389.459724 -286.203136) (xy 389.510524 -286.203136)
		)
		(stroke
			(width 0)
			(type solid)
		)
		(fill yes)
		(layer "F.Cu")
		(net "M_E_CPU0_SA_DQ<4>")
	)
	(gr_poly
		(pts
			(xy 389.510524 -285.343346) (xy 389.459724 -285.343346) (xy 389.358124 -285.379668) (xy 389.358124 -285.570168)
			(xy 389.459724 -285.606236) (xy 389.510524 -285.606236)
		)
		(stroke
			(width 0)
			(type solid)
		)
		(fill yes)
		(layer "F.Cu")
		(net "M_E_CPU0_SA_DQ<4>")
	)
	(gr_poly
		(pts
			(xy 389.510524 -284.746446) (xy 389.459724 -284.746446) (xy 389.358124 -284.782768) (xy 389.358124 -284.973268)
			(xy 389.459724 -285.009336) (xy 389.510524 -285.009336)
		)
		(stroke
			(width 0)
			(type solid)
		)
		(fill yes)
		(layer "F.Cu")
		(net "M_E_CPU0_SA_DQ<4>")
	)
	(gr_poly
		(pts
			(xy 389.510524 -284.149546) (xy 389.459724 -284.149546) (xy 389.358124 -284.185868) (xy 389.358124 -284.376368)
			(xy 389.459724 -284.412436) (xy 389.510524 -284.412436)
		)
		(stroke
			(width 0)
			(type solid)
		)
		(fill yes)
		(layer "F.Cu")
		(net "M_E_CPU0_SA_DQ<4>")
	)
	(gr_poly
		(pts
			(xy 389.510524 -283.552646) (xy 389.459724 -283.552646) (xy 389.358124 -283.588968) (xy 389.358124 -283.779468)
			(xy 389.459724 -283.815536) (xy 389.510524 -283.815536)
		)
		(stroke
			(width 0)
			(type solid)
		)
		(fill yes)
		(layer "F.Cu")
		(net "M_E_CPU0_SA_DQ<4>")
	)
	(gr_poly
		(pts
			(xy 389.510524 -282.955746) (xy 389.459724 -282.955746) (xy 389.358124 -282.992068) (xy 389.358124 -283.182568)
			(xy 389.459724 -283.218636) (xy 389.510524 -283.218636)
		)
		(stroke
			(width 0)
			(type solid)
		)
		(fill yes)
		(layer "F.Cu")
		(net "M_E_CPU0_SA_DQ<4>")
	)
	(gr_poly
		(pts
			(xy 389.510524 -282.358846) (xy 389.459724 -282.358846) (xy 389.358124 -282.395168) (xy 389.358124 -282.585668)
			(xy 389.459724 -282.621736) (xy 389.510524 -282.621736)
		)
		(stroke
			(width 0)
			(type solid)
		)
		(fill yes)
		(layer "F.Cu")
		(net "M_E_CPU0_SA_DQ<4>")
	)
	(gr_poly
		(pts
			(xy 389.510524 -281.761946) (xy 389.459724 -281.761946) (xy 389.358124 -281.798268) (xy 389.358124 -281.988768)
			(xy 389.459724 -282.024836) (xy 389.510524 -282.024836)
		)
		(stroke
			(width 0)
			(type solid)
		)
		(fill yes)
		(layer "F.Cu")
		(net "M_E_CPU0_SA_DQ<4>")
	)
	(gr_poly
		(pts
			(xy 389.510524 -281.165046) (xy 389.459724 -281.165046) (xy 389.358124 -281.201368) (xy 389.358124 -281.391868)
			(xy 389.459724 -281.427936) (xy 389.510524 -281.427936)
		)
		(stroke
			(width 0)
			(type solid)
		)
		(fill yes)
		(layer "F.Cu")
		(net "M_E_CPU0_SA_DQ<4>")
	)
	(gr_poly
		(pts
			(xy 389.510524 -270.503396) (xy 389.556752 -270.406114) (xy 389.422132 -270.271494) (xy 389.324596 -270.317722)
			(xy 389.288782 -270.353536) (xy 389.47471 -270.539464)
		)
		(stroke
			(width 0)
			(type solid)
		)
		(fill yes)
		(layer "F.Cu")
		(net "M_E_CPU0_SA_DQ<23>")
	)
	(gr_poly
		(pts
			(xy 389.515604 -229.657656) (xy 389.479536 -229.621842) (xy 389.382254 -229.575614) (xy 389.24738 -229.710234)
			(xy 389.293608 -229.80777) (xy 389.329676 -229.843584)
		)
		(stroke
			(width 0)
			(type solid)
		)
		(fill yes)
		(layer "F.Cu")
		(net "M_E_CPU0_SB_DQ<23>")
	)
	(gr_poly
		(pts
			(xy 389.51916 -274.545298) (xy 389.554974 -274.50923) (xy 389.369046 -274.323302) (xy 389.333232 -274.35937)
			(xy 389.287004 -274.456652) (xy 389.421624 -274.591526)
		)
		(stroke
			(width 0)
			(type solid)
		)
		(fill yes)
		(layer "F.Cu")
		(net "M_E_CPU0_SA_DQ<17>")
	)
	(gr_poly
		(pts
			(xy 389.519414 -268.806168) (xy 389.565642 -268.708632) (xy 389.431022 -268.574012) (xy 389.333486 -268.62024)
			(xy 389.297672 -268.656308) (xy 389.483346 -268.841982)
		)
		(stroke
			(width 0)
			(type solid)
		)
		(fill yes)
		(layer "F.Cu")
		(net "M_E_CPU0_SA_DQ<25>")
	)
	(gr_poly
		(pts
			(xy 389.524748 -230.511096) (xy 389.488934 -230.475282) (xy 389.391398 -230.429054) (xy 389.256778 -230.563674)
			(xy 389.303006 -230.660956) (xy 389.33882 -230.697024)
		)
		(stroke
			(width 0)
			(type solid)
		)
		(fill yes)
		(layer "F.Cu")
		(net "M_E_CPU0_SB_DQ<22>")
	)
	(gr_poly
		(pts
			(xy 389.542782 -277.318724) (xy 389.635238 -277.263352) (xy 389.5979 -277.076408) (xy 389.49122 -277.060914)
			(xy 389.441436 -277.07082) (xy 389.492998 -277.32863)
		)
		(stroke
			(width 0)
			(type solid)
		)
		(fill yes)
		(layer "F.Cu")
		(net "M_E_CPU0_SA_DQ<5>")
	)
	(gr_poly
		(pts
			(xy 389.551672 -277.621238) (xy 389.50011 -277.363428) (xy 389.450072 -277.373588) (xy 389.357616 -277.42896)
			(xy 389.394954 -277.61565) (xy 389.501888 -277.631144)
		)
		(stroke
			(width 0)
			(type solid)
		)
		(fill yes)
		(layer "F.Cu")
		(net "M_E_CPU0_SA_DQ<5>")
	)
	(gr_poly
		(pts
			(xy 389.551672 -233.072432) (xy 389.515604 -233.036618) (xy 389.418322 -232.99039) (xy 389.283448 -233.12501)
			(xy 389.329676 -233.222546) (xy 389.365744 -233.25836)
		)
		(stroke
			(width 0)
			(type solid)
		)
		(fill yes)
		(layer "F.Cu")
		(net "M_E_CPU0_SB_DQ<19>")
	)
	(gr_poly
		(pts
			(xy 389.560816 -233.925872) (xy 389.525002 -233.890058) (xy 389.427466 -233.843576) (xy 389.292846 -233.97845)
			(xy 389.339074 -234.075732) (xy 389.374888 -234.1118)
		)
		(stroke
			(width 0)
			(type solid)
		)
		(fill yes)
		(layer "F.Cu")
		(net "M_E_CPU0_SB_DQ<18>")
	)
	(gr_poly
		(pts
			(xy 389.577834 -257.580384) (xy 389.613648 -257.544316) (xy 389.42772 -257.358388) (xy 389.391906 -257.394456)
			(xy 389.345678 -257.491738) (xy 389.480298 -257.626612)
		)
		(stroke
			(width 0)
			(type solid)
		)
		(fill yes)
		(layer "F.Cu")
		(net "M_E_CPU0_SA_CS_N<2>")
	)
	(gr_poly
		(pts
			(xy 389.584438 -264.337292) (xy 389.620506 -264.301478) (xy 389.434578 -264.11555) (xy 389.398764 -264.151364)
			(xy 389.352282 -264.2489) (xy 389.487156 -264.38352)
		)
		(stroke
			(width 0)
			(type solid)
		)
		(fill yes)
		(layer "F.Cu")
		(net "M_E_CPU0_SA_CB<0>")
	)
	(gr_poly
		(pts
			(xy 389.586216 -274.900136) (xy 389.632698 -274.8026) (xy 389.497824 -274.66798) (xy 389.400542 -274.714208)
			(xy 389.364474 -274.750022) (xy 389.550402 -274.93595)
		)
		(stroke
			(width 0)
			(type solid)
		)
		(fill yes)
		(layer "F.Cu")
		(net "M_E_CPU0_SA_DQ<18>")
	)
	(gr_poly
		(pts
			(xy 389.586978 -256.726944) (xy 389.622792 -256.690876) (xy 389.437118 -256.505202) (xy 389.40105 -256.541016)
			(xy 389.354822 -256.638552) (xy 389.489442 -256.773172)
		)
		(stroke
			(width 0)
			(type solid)
		)
		(fill yes)
		(layer "F.Cu")
		(net "M_E_CPU0_SA_CS_N<3>")
	)
	(gr_poly
		(pts
			(xy 389.593836 -263.484106) (xy 389.62965 -263.448038) (xy 389.443722 -263.26211) (xy 389.407908 -263.298178)
			(xy 389.36168 -263.39546) (xy 389.4963 -263.530334)
		)
		(stroke
			(width 0)
			(type solid)
		)
		(fill yes)
		(layer "F.Cu")
		(net "M_E_CPU0_SA_CB<1>")
	)
	(gr_poly
		(pts
			(xy 389.595106 -279.13457) (xy 389.687562 -279.078944) (xy 389.650224 -278.892254) (xy 389.54329 -278.87676)
			(xy 389.493506 -278.886666) (xy 389.545068 -279.144476)
		)
		(stroke
			(width 0)
			(type solid)
		)
		(fill yes)
		(layer "F.Cu")
		(net "M_E_CPU0_SA_DQ<6>")
	)
	(gr_poly
		(pts
			(xy 389.595614 -242.100862) (xy 389.5598 -242.064794) (xy 389.462264 -242.018566) (xy 389.327644 -242.153186)
			(xy 389.373872 -242.250722) (xy 389.409686 -242.28679)
		)
		(stroke
			(width 0)
			(type solid)
		)
		(fill yes)
		(layer "F.Cu")
		(net "M_E_CPU0_SB_CB<7>")
	)
	(gr_poly
		(pts
			(xy 389.595868 -274.046442) (xy 389.642096 -273.948906) (xy 389.507476 -273.814286) (xy 389.40994 -273.860514)
			(xy 389.374126 -273.896582) (xy 389.5598 -274.082256)
		)
		(stroke
			(width 0)
			(type solid)
		)
		(fill yes)
		(layer "F.Cu")
		(net "M_E_CPU0_SA_DQ<19>")
	)
	(gr_poly
		(pts
			(xy 389.602218 -230.217726) (xy 389.55599 -230.120444) (xy 389.520176 -230.084376) (xy 389.334248 -230.270304)
			(xy 389.370062 -230.306118) (xy 389.467598 -230.3526)
		)
		(stroke
			(width 0)
			(type solid)
		)
		(fill yes)
		(layer "F.Cu")
		(net "M_E_CPU0_SB_DQ<21>")
	)
	(gr_poly
		(pts
			(xy 389.603742 -279.437084) (xy 389.55218 -279.179274) (xy 389.502396 -279.18918) (xy 389.40994 -279.244806)
			(xy 389.447278 -279.431496) (xy 389.553958 -279.44699)
		)
		(stroke
			(width 0)
			(type solid)
		)
		(fill yes)
		(layer "F.Cu")
		(net "M_E_CPU0_SA_DQ<6>")
	)
	(gr_poly
		(pts
			(xy 389.605012 -242.954048) (xy 389.568944 -242.918234) (xy 389.471662 -242.872006) (xy 389.336788 -243.006626)
			(xy 389.383016 -243.104162) (xy 389.419084 -243.139976)
		)
		(stroke
			(width 0)
			(type solid)
		)
		(fill yes)
		(layer "F.Cu")
		(net "M_E_CPU0_SB_CB<6>")
	)
	(gr_poly
		(pts
			(xy 389.60552 -247.240552) (xy 389.60552 -247.189752) (xy 389.342376 -247.189752) (xy 389.342376 -247.240552)
			(xy 389.378698 -247.342152) (xy 389.569198 -247.342152)
		)
		(stroke
			(width 0)
			(type solid)
		)
		(fill yes)
		(layer "F.Cu")
		(net "M_E_CPU0_SB_CA<6>")
	)
	(gr_poly
		(pts
			(xy 389.60552 -246.935752) (xy 389.60552 -246.884952) (xy 389.342376 -246.884952) (xy 389.342376 -246.935752)
			(xy 389.378698 -247.037352) (xy 389.569198 -247.037352)
		)
		(stroke
			(width 0)
			(type solid)
		)
		(fill yes)
		(layer "F.Cu")
		(net "M_E_CPU0_SB_PAR")
	)
	(gr_poly
		(pts
			(xy 389.60552 -246.630952) (xy 389.60552 -246.580152) (xy 389.342376 -246.580152) (xy 389.342376 -246.630952)
			(xy 389.378698 -246.732552) (xy 389.569198 -246.732552)
		)
		(stroke
			(width 0)
			(type solid)
		)
		(fill yes)
		(layer "F.Cu")
		(net "M_E_CPU0_SB_CS_N<0>")
	)
	(gr_poly
		(pts
			(xy 389.60552 -246.326152) (xy 389.60552 -246.275352) (xy 389.342376 -246.275352) (xy 389.342376 -246.326152)
			(xy 389.378698 -246.427752) (xy 389.569198 -246.427752)
		)
		(stroke
			(width 0)
			(type solid)
		)
		(fill yes)
		(layer "F.Cu")
		(net "M_E_CPU0_SB_CS_N<2>")
	)
	(gr_poly
		(pts
			(xy 389.60552 -246.021352) (xy 389.60552 -245.970552) (xy 389.342376 -245.970552) (xy 389.342376 -246.021352)
			(xy 389.378698 -246.122952) (xy 389.569198 -246.122952)
		)
		(stroke
			(width 0)
			(type solid)
		)
		(fill yes)
		(layer "F.Cu")
		(net "M_E_CPU0_SB_CS_N<1>")
	)
	(gr_poly
		(pts
			(xy 389.60552 -245.716552) (xy 389.60552 -245.665752) (xy 389.342376 -245.665752) (xy 389.342376 -245.716552)
			(xy 389.378698 -245.818152) (xy 389.569198 -245.818152)
		)
		(stroke
			(width 0)
			(type solid)
		)
		(fill yes)
		(layer "F.Cu")
		(net "M_E_CPU0_SB_CS_N<3>")
	)
	(gr_poly
		(pts
			(xy 389.611616 -231.071166) (xy 389.565388 -230.97363) (xy 389.52932 -230.937816) (xy 389.343392 -231.123744)
			(xy 389.37946 -231.159558) (xy 389.476742 -231.205786)
		)
		(stroke
			(width 0)
			(type solid)
		)
		(fill yes)
		(layer "F.Cu")
		(net "M_E_CPU0_SB_DQ<20>")
	)
	(gr_poly
		(pts
			(xy 389.617966 -265.992356) (xy 389.65378 -265.956288) (xy 389.467852 -265.77036) (xy 389.432038 -265.806428)
			(xy 389.38581 -265.90371) (xy 389.52043 -266.038584)
		)
		(stroke
			(width 0)
			(type solid)
		)
		(fill yes)
		(layer "F.Cu")
		(net "M_E_CPU0_SA_DQ<30>")
	)
	(gr_poly
		(pts
			(xy 389.627364 -265.138662) (xy 389.663432 -265.102848) (xy 389.477504 -264.91692) (xy 389.441436 -264.952734)
			(xy 389.395208 -265.05027) (xy 389.529828 -265.18489)
		)
		(stroke
			(width 0)
			(type solid)
		)
		(fill yes)
		(layer "F.Cu")
		(net "M_E_CPU0_SA_DQ<31>")
	)
	(gr_poly
		(pts
			(xy 389.638286 -233.632502) (xy 389.592058 -233.534966) (xy 389.556244 -233.499152) (xy 389.370316 -233.68508)
			(xy 389.40613 -233.720894) (xy 389.503666 -233.767122)
		)
		(stroke
			(width 0)
			(type solid)
		)
		(fill yes)
		(layer "F.Cu")
		(net "M_E_CPU0_SB_DQ<17>")
	)
	(gr_poly
		(pts
			(xy 389.640572 -271.640046) (xy 389.676386 -271.603978) (xy 389.490458 -271.41805) (xy 389.454644 -271.454118)
			(xy 389.408416 -271.5514) (xy 389.543036 -271.686274)
		)
		(stroke
			(width 0)
			(type solid)
		)
		(fill yes)
		(layer "F.Cu")
		(net "M_E_CPU0_SA_DQ<22>")
	)
	(gr_poly
		(pts
			(xy 389.641842 -260.943598) (xy 389.677656 -260.90753) (xy 389.491982 -260.721856) (xy 389.455914 -260.75767)
			(xy 389.409686 -260.855206) (xy 389.544306 -260.989826)
		)
		(stroke
			(width 0)
			(type solid)
		)
		(fill yes)
		(layer "F.Cu")
		(net "M_E_CPU0_SA_CB<4>")
	)
	(gr_poly
		(pts
			(xy 389.64489 -257.935222) (xy 389.691118 -257.837686) (xy 389.556498 -257.703066) (xy 389.458962 -257.749294)
			(xy 389.423148 -257.785362) (xy 389.608822 -257.971036)
		)
		(stroke
			(width 0)
			(type solid)
		)
		(fill yes)
		(layer "F.Cu")
		(net "M_E_CPU0_SA_CS_N<0>")
	)
	(gr_poly
		(pts
			(xy 389.647684 -234.485942) (xy 389.601456 -234.388406) (xy 389.565388 -234.352592) (xy 389.37946 -234.53852)
			(xy 389.415528 -234.574334) (xy 389.51281 -234.620562)
		)
		(stroke
			(width 0)
			(type solid)
		)
		(fill yes)
		(layer "F.Cu")
		(net "M_E_CPU0_SB_DQ<16>")
	)
	(gr_poly
		(pts
			(xy 389.649462 -269.942564) (xy 389.685276 -269.906496) (xy 389.499348 -269.720568) (xy 389.463534 -269.756636)
			(xy 389.417306 -269.853918) (xy 389.551926 -269.988792)
		)
		(stroke
			(width 0)
			(type solid)
		)
		(fill yes)
		(layer "F.Cu")
		(net "M_E_CPU0_SA_DQ<24>")
	)
	(gr_poly
		(pts
			(xy 389.649716 -270.786352) (xy 389.685784 -270.750538) (xy 389.499856 -270.56461) (xy 389.463788 -270.600424)
			(xy 389.41756 -270.69796) (xy 389.552434 -270.83258)
		)
		(stroke
			(width 0)
			(type solid)
		)
		(fill yes)
		(layer "F.Cu")
		(net "M_E_CPU0_SA_DQ<23>")
	)
	(gr_poly
		(pts
			(xy 389.654288 -257.081782) (xy 389.700516 -256.984246) (xy 389.565642 -256.849626) (xy 389.46836 -256.895854)
			(xy 389.432292 -256.931668) (xy 389.61822 -257.117596)
		)
		(stroke
			(width 0)
			(type solid)
		)
		(fill yes)
		(layer "F.Cu")
		(net "M_E_CPU0_SA_CS_N<1>")
	)
	(gr_poly
		(pts
			(xy 389.658606 -269.089124) (xy 389.69442 -269.053056) (xy 389.508492 -268.867128) (xy 389.472678 -268.903196)
			(xy 389.42645 -269.000478) (xy 389.56107 -269.135352)
		)
		(stroke
			(width 0)
			(type solid)
		)
		(fill yes)
		(layer "F.Cu")
		(net "M_E_CPU0_SA_DQ<25>")
	)
	(gr_poly
		(pts
			(xy 389.659876 -277.90394) (xy 389.752586 -277.848568) (xy 389.714994 -277.661624) (xy 389.608314 -277.64613)
			(xy 389.55853 -277.656036) (xy 389.610092 -277.913846)
		)
		(stroke
			(width 0)
			(type solid)
		)
		(fill yes)
		(layer "F.Cu")
		(net "M_E_CPU0_SA_DQ<5>")
	)
	(gr_poly
		(pts
			(xy 389.660892 -263.838944) (xy 389.70712 -263.741408) (xy 389.5725 -263.606788) (xy 389.475218 -263.653016)
			(xy 389.43915 -263.68883) (xy 389.625078 -263.874758)
		)
		(stroke
			(width 0)
			(type solid)
		)
		(fill yes)
		(layer "F.Cu")
		(net "M_E_CPU0_SA_CB<2>")
	)
	(gr_poly
		(pts
			(xy 389.662924 -290.643818) (xy 389.662924 -290.453318) (xy 389.561324 -290.416996) (xy 389.510524 -290.416996)
			(xy 389.510524 -290.679886) (xy 389.561324 -290.679886)
		)
		(stroke
			(width 0)
			(type solid)
		)
		(fill yes)
		(layer "F.Cu")
		(net "M_E_CPU0_SA_DQ<4>")
	)
	(gr_poly
		(pts
			(xy 389.662924 -290.046918) (xy 389.662924 -289.856418) (xy 389.561324 -289.820096) (xy 389.510524 -289.820096)
			(xy 389.510524 -290.082986) (xy 389.561324 -290.082986)
		)
		(stroke
			(width 0)
			(type solid)
		)
		(fill yes)
		(layer "F.Cu")
		(net "M_E_CPU0_SA_DQ<4>")
	)
	(gr_poly
		(pts
			(xy 389.662924 -289.450018) (xy 389.662924 -289.259518) (xy 389.561324 -289.223196) (xy 389.510524 -289.223196)
			(xy 389.510524 -289.486086) (xy 389.561324 -289.486086)
		)
		(stroke
			(width 0)
			(type solid)
		)
		(fill yes)
		(layer "F.Cu")
		(net "M_E_CPU0_SA_DQ<4>")
	)
	(gr_poly
		(pts
			(xy 389.662924 -288.853118) (xy 389.662924 -288.662618) (xy 389.561324 -288.626296) (xy 389.510524 -288.626296)
			(xy 389.510524 -288.889186) (xy 389.561324 -288.889186)
		)
		(stroke
			(width 0)
			(type solid)
		)
		(fill yes)
		(layer "F.Cu")
		(net "M_E_CPU0_SA_DQ<4>")
	)
	(gr_poly
		(pts
			(xy 389.662924 -288.256218) (xy 389.662924 -288.065718) (xy 389.561324 -288.029396) (xy 389.510524 -288.029396)
			(xy 389.510524 -288.292286) (xy 389.561324 -288.292286)
		)
		(stroke
			(width 0)
			(type solid)
		)
		(fill yes)
		(layer "F.Cu")
		(net "M_E_CPU0_SA_DQ<4>")
	)
	(gr_poly
		(pts
			(xy 389.662924 -287.659318) (xy 389.662924 -287.468818) (xy 389.561324 -287.432496) (xy 389.510524 -287.432496)
			(xy 389.510524 -287.695386) (xy 389.561324 -287.695386)
		)
		(stroke
			(width 0)
			(type solid)
		)
		(fill yes)
		(layer "F.Cu")
		(net "M_E_CPU0_SA_DQ<4>")
	)
	(gr_poly
		(pts
			(xy 389.662924 -287.062418) (xy 389.662924 -286.871918) (xy 389.561324 -286.835596) (xy 389.510524 -286.835596)
			(xy 389.510524 -287.098486) (xy 389.561324 -287.098486)
		)
		(stroke
			(width 0)
			(type solid)
		)
		(fill yes)
		(layer "F.Cu")
		(net "M_E_CPU0_SA_DQ<4>")
	)
	(gr_poly
		(pts
			(xy 389.662924 -286.465518) (xy 389.662924 -286.275018) (xy 389.561324 -286.238696) (xy 389.510524 -286.238696)
			(xy 389.510524 -286.501586) (xy 389.561324 -286.501586)
		)
		(stroke
			(width 0)
			(type solid)
		)
		(fill yes)
		(layer "F.Cu")
		(net "M_E_CPU0_SA_DQ<4>")
	)
	(gr_poly
		(pts
			(xy 389.662924 -285.868618) (xy 389.662924 -285.678118) (xy 389.561324 -285.641796) (xy 389.510524 -285.641796)
			(xy 389.510524 -285.904686) (xy 389.561324 -285.904686)
		)
		(stroke
			(width 0)
			(type solid)
		)
		(fill yes)
		(layer "F.Cu")
		(net "M_E_CPU0_SA_DQ<4>")
	)
	(gr_poly
		(pts
			(xy 389.662924 -285.271718) (xy 389.662924 -285.081218) (xy 389.561324 -285.044896) (xy 389.510524 -285.044896)
			(xy 389.510524 -285.307786) (xy 389.561324 -285.307786)
		)
		(stroke
			(width 0)
			(type solid)
		)
		(fill yes)
		(layer "F.Cu")
		(net "M_E_CPU0_SA_DQ<4>")
	)
	(gr_poly
		(pts
			(xy 389.662924 -284.674818) (xy 389.662924 -284.484318) (xy 389.561324 -284.447996) (xy 389.510524 -284.447996)
			(xy 389.510524 -284.710886) (xy 389.561324 -284.710886)
		)
		(stroke
			(width 0)
			(type solid)
		)
		(fill yes)
		(layer "F.Cu")
		(net "M_E_CPU0_SA_DQ<4>")
	)
	(gr_poly
		(pts
			(xy 389.662924 -284.077918) (xy 389.662924 -283.887418) (xy 389.561324 -283.851096) (xy 389.510524 -283.851096)
			(xy 389.510524 -284.113986) (xy 389.561324 -284.113986)
		)
		(stroke
			(width 0)
			(type solid)
		)
		(fill yes)
		(layer "F.Cu")
		(net "M_E_CPU0_SA_DQ<4>")
	)
	(gr_poly
		(pts
			(xy 389.662924 -283.481018) (xy 389.662924 -283.290518) (xy 389.561324 -283.254196) (xy 389.510524 -283.254196)
			(xy 389.510524 -283.517086) (xy 389.561324 -283.517086)
		)
		(stroke
			(width 0)
			(type solid)
		)
		(fill yes)
		(layer "F.Cu")
		(net "M_E_CPU0_SA_DQ<4>")
	)
	(gr_poly
		(pts
			(xy 389.662924 -282.884118) (xy 389.662924 -282.693618) (xy 389.561324 -282.657296) (xy 389.510524 -282.657296)
			(xy 389.510524 -282.920186) (xy 389.561324 -282.920186)
		)
		(stroke
			(width 0)
			(type solid)
		)
		(fill yes)
		(layer "F.Cu")
		(net "M_E_CPU0_SA_DQ<4>")
	)
	(gr_poly
		(pts
			(xy 389.662924 -282.287218) (xy 389.662924 -282.096718) (xy 389.561324 -282.060396) (xy 389.510524 -282.060396)
			(xy 389.510524 -282.323286) (xy 389.561324 -282.323286)
		)
		(stroke
			(width 0)
			(type solid)
		)
		(fill yes)
		(layer "F.Cu")
		(net "M_E_CPU0_SA_DQ<4>")
	)
	(gr_poly
		(pts
			(xy 389.662924 -281.690318) (xy 389.662924 -281.499818) (xy 389.561324 -281.463496) (xy 389.510524 -281.463496)
			(xy 389.510524 -281.726386) (xy 389.561324 -281.726386)
		)
		(stroke
			(width 0)
			(type solid)
		)
		(fill yes)
		(layer "F.Cu")
		(net "M_E_CPU0_SA_DQ<4>")
	)
	(gr_poly
		(pts
			(xy 389.662924 -281.093418) (xy 389.662924 -280.902918) (xy 389.561324 -280.866596) (xy 389.510524 -280.866596)
			(xy 389.510524 -281.129486) (xy 389.561324 -281.129486)
		)
		(stroke
			(width 0)
			(type solid)
		)
		(fill yes)
		(layer "F.Cu")
		(net "M_E_CPU0_SA_DQ<4>")
	)
	(gr_poly
		(pts
			(xy 389.663686 -256.228596) (xy 389.709914 -256.13106) (xy 389.57504 -255.99644) (xy 389.477758 -256.042668)
			(xy 389.44169 -256.078482) (xy 389.627618 -256.26441)
		)
		(stroke
			(width 0)
			(type solid)
		)
		(fill yes)
		(layer "F.Cu")
		(net "M_E_CPU0_SA_CA<0>")
	)
	(gr_poly
		(pts
			(xy 389.668766 -278.206454) (xy 389.617204 -277.948898) (xy 389.56742 -277.958804) (xy 389.47471 -278.014176)
			(xy 389.512302 -278.200866) (xy 389.618982 -278.216614)
		)
		(stroke
			(width 0)
			(type solid)
		)
		(fill yes)
		(layer "F.Cu")
		(net "M_E_CPU0_SA_DQ<5>")
	)
	(gr_poly
		(pts
			(xy 389.67029 -262.985504) (xy 389.716518 -262.887968) (xy 389.581644 -262.753348) (xy 389.484362 -262.799576)
			(xy 389.448294 -262.83539) (xy 389.634222 -263.021318)
		)
		(stroke
			(width 0)
			(type solid)
		)
		(fill yes)
		(layer "F.Cu")
		(net "M_E_CPU0_SA_CB<3>")
	)
	(gr_poly
		(pts
			(xy 389.682482 -242.660932) (xy 389.636254 -242.563396) (xy 389.600186 -242.527582) (xy 389.414512 -242.713256)
			(xy 389.450326 -242.749324) (xy 389.547862 -242.795552)
		)
		(stroke
			(width 0)
			(type solid)
		)
		(fill yes)
		(layer "F.Cu")
		(net "M_E_CPU0_SB_CB<5>")
	)
	(gr_poly
		(pts
			(xy 389.685022 -266.347194) (xy 389.731504 -266.249658) (xy 389.59663 -266.115038) (xy 389.499348 -266.161266)
			(xy 389.46328 -266.19708) (xy 389.649208 -266.383008)
		)
		(stroke
			(width 0)
			(type solid)
		)
		(fill yes)
		(layer "F.Cu")
		(net "M_E_CPU0_SA_DQ<28>")
	)
	(gr_poly
		(pts
			(xy 389.691626 -243.514118) (xy 389.645398 -243.416836) (xy 389.609584 -243.380768) (xy 389.423656 -243.566696)
			(xy 389.45947 -243.60251) (xy 389.557006 -243.648992)
		)
		(stroke
			(width 0)
			(type solid)
		)
		(fill yes)
		(layer "F.Cu")
		(net "M_E_CPU0_SB_CB<4>")
	)
	(gr_poly
		(pts
			(xy 389.69442 -265.4935) (xy 389.740648 -265.396218) (xy 389.606028 -265.261598) (xy 389.508492 -265.307826)
			(xy 389.472678 -265.34364) (xy 389.658606 -265.529568)
		)
		(stroke
			(width 0)
			(type solid)
		)
		(fill yes)
		(layer "F.Cu")
		(net "M_E_CPU0_SA_DQ<29>")
	)
	(gr_poly
		(pts
			(xy 389.707374 -271.995392) (xy 389.753602 -271.897856) (xy 389.618982 -271.763236) (xy 389.521446 -271.809464)
			(xy 389.485632 -271.845278) (xy 389.671306 -272.031206)
		)
		(stroke
			(width 0)
			(type solid)
		)
		(fill yes)
		(layer "F.Cu")
		(net "M_E_CPU0_SA_DQ<20>")
	)
	(gr_poly
		(pts
			(xy 389.7122 -279.719786) (xy 389.804656 -279.664414) (xy 389.767318 -279.47747) (xy 389.660638 -279.461976)
			(xy 389.6106 -279.471882) (xy 389.662416 -279.729692)
		)
		(stroke
			(width 0)
			(type solid)
		)
		(fill yes)
		(layer "F.Cu")
		(net "M_E_CPU0_SA_DQ<6>")
	)
	(gr_poly
		(pts
			(xy 389.717026 -271.141444) (xy 389.763254 -271.043908) (xy 389.62838 -270.909288) (xy 389.531098 -270.955516)
			(xy 389.49503 -270.99133) (xy 389.680958 -271.177258)
		)
		(stroke
			(width 0)
			(type solid)
		)
		(fill yes)
		(layer "F.Cu")
		(net "M_E_CPU0_SA_DQ<21>")
	)
	(gr_poly
		(pts
			(xy 389.718296 -260.444996) (xy 389.764524 -260.34746) (xy 389.629904 -260.21284) (xy 389.532368 -260.259068)
			(xy 389.496554 -260.295136) (xy 389.682482 -260.481064)
		)
		(stroke
			(width 0)
			(type solid)
		)
		(fill yes)
		(layer "F.Cu")
		(net "M_E_CPU0_SA_CB<6>")
	)
	(gr_poly
		(pts
			(xy 389.720836 -280.0223) (xy 389.669274 -279.76449) (xy 389.61949 -279.77465) (xy 389.527034 -279.830022)
			(xy 389.564372 -280.016712) (xy 389.671052 -280.032206)
		)
		(stroke
			(width 0)
			(type solid)
		)
		(fill yes)
		(layer "F.Cu")
		(net "M_E_CPU0_SA_DQ<6>")
	)
	(gr_poly
		(pts
			(xy 389.725154 -276.673564) (xy 389.81761 -276.617938) (xy 389.780272 -276.431248) (xy 389.673338 -276.415754)
			(xy 389.623554 -276.42566) (xy 389.67537 -276.68347)
		)
		(stroke
			(width 0)
			(type solid)
		)
		(fill yes)
		(layer "F.Cu")
		(net "M_E_CPU0_SA_DQ<7>")
	)
	(gr_poly
		(pts
			(xy 389.725662 -275.182838) (xy 389.761476 -275.147024) (xy 389.575548 -274.961096) (xy 389.539734 -274.99691)
			(xy 389.493506 -275.094446) (xy 389.628126 -275.229066)
		)
		(stroke
			(width 0)
			(type solid)
		)
		(fill yes)
		(layer "F.Cu")
		(net "M_E_CPU0_SA_DQ<18>")
	)
	(gr_poly
		(pts
			(xy 389.725916 -269.443962) (xy 389.772144 -269.346426) (xy 389.63727 -269.211806) (xy 389.539988 -269.258034)
			(xy 389.50392 -269.293848) (xy 389.689848 -269.479776)
		)
		(stroke
			(width 0)
			(type solid)
		)
		(fill yes)
		(layer "F.Cu")
		(net "M_E_CPU0_SA_DQ<26>")
	)
	(gr_poly
		(pts
			(xy 389.73125 -229.873302) (xy 389.695182 -229.837488) (xy 389.5979 -229.79126) (xy 389.463026 -229.92588)
			(xy 389.509254 -230.023416) (xy 389.545322 -230.05923)
		)
		(stroke
			(width 0)
			(type solid)
		)
		(fill yes)
		(layer "F.Cu")
		(net "M_E_CPU0_SB_DQ<21>")
	)
	(gr_poly
		(pts
			(xy 389.73379 -276.976078) (xy 389.682228 -276.718268) (xy 389.632444 -276.728174) (xy 389.539988 -276.7838)
			(xy 389.577326 -276.97049) (xy 389.684006 -276.985984)
		)
		(stroke
			(width 0)
			(type solid)
		)
		(fill yes)
		(layer "F.Cu")
		(net "M_E_CPU0_SA_DQ<7>")
	)
	(gr_poly
		(pts
			(xy 389.73506 -274.329398) (xy 389.770874 -274.29333) (xy 389.584946 -274.107402) (xy 389.549132 -274.14347)
			(xy 389.502904 -274.240752) (xy 389.637524 -274.375626)
		)
		(stroke
			(width 0)
			(type solid)
		)
		(fill yes)
		(layer "F.Cu")
		(net "M_E_CPU0_SA_DQ<19>")
	)
	(gr_poly
		(pts
			(xy 389.73506 -268.590522) (xy 389.781288 -268.492986) (xy 389.646414 -268.358366) (xy 389.549132 -268.404594)
			(xy 389.513064 -268.440408) (xy 389.698992 -268.626336)
		)
		(stroke
			(width 0)
			(type solid)
		)
		(fill yes)
		(layer "F.Cu")
		(net "M_E_CPU0_SA_DQ<27>")
	)
	(gr_poly
		(pts
			(xy 389.740394 -230.726742) (xy 389.70458 -230.690928) (xy 389.607044 -230.6447) (xy 389.472424 -230.77932)
			(xy 389.518652 -230.876602) (xy 389.554466 -230.91267)
		)
		(stroke
			(width 0)
			(type solid)
		)
		(fill yes)
		(layer "F.Cu")
		(net "M_E_CPU0_SB_DQ<20>")
	)
	(gr_poly
		(pts
			(xy 389.752332 -238.787686) (xy 389.752332 -238.736886) (xy 389.489442 -238.736886) (xy 389.489442 -238.787686)
			(xy 389.525764 -238.889286) (xy 389.716264 -238.889286)
		)
		(stroke
			(width 0)
			(type solid)
		)
		(fill yes)
		(layer "F.Cu")
		(net "M_E_CPU0_SB_DQ<8>")
	)
	(gr_poly
		(pts
			(xy 389.752332 -238.482886) (xy 389.752332 -238.432086) (xy 389.489442 -238.432086) (xy 389.489442 -238.482886)
			(xy 389.525764 -238.584486) (xy 389.716264 -238.584486)
		)
		(stroke
			(width 0)
			(type solid)
		)
		(fill yes)
		(layer "F.Cu")
		(net "M_E_CPU0_SB_DQ<10>")
	)
	(gr_poly
		(pts
			(xy 389.752332 -237.873286) (xy 389.752332 -237.822486) (xy 389.489442 -237.822486) (xy 389.489442 -237.873286)
			(xy 389.525764 -237.974886) (xy 389.716264 -237.974886)
		)
		(stroke
			(width 0)
			(type solid)
		)
		(fill yes)
		(layer "F.Cu")
		(net "M_E_CPU0_SB_DQ<11>")
	)
	(gr_poly
		(pts
			(xy 389.767318 -233.288078) (xy 389.73125 -233.252264) (xy 389.633968 -233.206036) (xy 389.499094 -233.340656)
			(xy 389.545322 -233.438192) (xy 389.58139 -233.474006)
		)
		(stroke
			(width 0)
			(type solid)
		)
		(fill yes)
		(layer "F.Cu")
		(net "M_E_CPU0_SB_DQ<17>")
	)
	(gr_poly
		(pts
			(xy 389.775954 -234.985306) (xy 389.74014 -234.949238) (xy 389.642604 -234.90301) (xy 389.507984 -235.03763)
			(xy 389.554212 -235.135166) (xy 389.59028 -235.17098)
		)
		(stroke
			(width 0)
			(type solid)
		)
		(fill yes)
		(layer "F.Cu")
		(net "M_E_CPU0_SB_DQ<15>")
	)
	(gr_poly
		(pts
			(xy 389.776462 -234.141518) (xy 389.740648 -234.105704) (xy 389.643112 -234.059222) (xy 389.508492 -234.194096)
			(xy 389.55472 -234.291378) (xy 389.590534 -234.327446)
		)
		(stroke
			(width 0)
			(type solid)
		)
		(fill yes)
		(layer "F.Cu")
		(net "M_E_CPU0_SB_DQ<16>")
	)
	(gr_poly
		(pts
			(xy 389.777224 -278.489156) (xy 389.86968 -278.433784) (xy 389.832342 -278.247094) (xy 389.725662 -278.231346)
			(xy 389.675878 -278.241506) (xy 389.72744 -278.499316)
		)
		(stroke
			(width 0)
			(type solid)
		)
		(fill yes)
		(layer "F.Cu")
		(net "M_E_CPU0_SA_DQ<5>")
	)
	(gr_poly
		(pts
			(xy 389.784082 -258.218178) (xy 389.819896 -258.18211) (xy 389.633968 -257.996182) (xy 389.598154 -258.03225)
			(xy 389.551926 -258.129786) (xy 389.686546 -258.264406)
		)
		(stroke
			(width 0)
			(type solid)
		)
		(fill yes)
		(layer "F.Cu")
		(net "M_E_CPU0_SA_CS_N<0>")
	)
	(gr_poly
		(pts
			(xy 389.78586 -278.791924) (xy 389.734298 -278.534114) (xy 389.684514 -278.54402) (xy 389.592058 -278.599392)
			(xy 389.629396 -278.786336) (xy 389.736076 -278.80183)
		)
		(stroke
			(width 0)
			(type solid)
		)
		(fill yes)
		(layer "F.Cu")
		(net "M_E_CPU0_SA_DQ<5>")
	)
	(gr_poly
		(pts
			(xy 389.792718 -275.537676) (xy 389.838946 -275.440394) (xy 389.704326 -275.30552) (xy 389.60679 -275.352002)
			(xy 389.570976 -275.387816) (xy 389.756904 -275.573744)
		)
		(stroke
			(width 0)
			(type solid)
		)
		(fill yes)
		(layer "F.Cu")
		(net "M_E_CPU0_SA_DQ<16>")
	)
	(gr_poly
		(pts
			(xy 389.79348 -257.364738) (xy 389.829294 -257.32867) (xy 389.643366 -257.142742) (xy 389.607552 -257.17881)
			(xy 389.561324 -257.276092) (xy 389.695944 -257.410966)
		)
		(stroke
			(width 0)
			(type solid)
		)
		(fill yes)
		(layer "F.Cu")
		(net "M_E_CPU0_SA_CS_N<1>")
	)
	(gr_poly
		(pts
			(xy 389.800084 -264.121646) (xy 389.836152 -264.085832) (xy 389.650224 -263.899904) (xy 389.61441 -263.935718)
			(xy 389.567928 -264.033254) (xy 389.702802 -264.167874)
		)
		(stroke
			(width 0)
			(type solid)
		)
		(fill yes)
		(layer "F.Cu")
		(net "M_E_CPU0_SA_CB<2>")
	)
	(gr_poly
		(pts
			(xy 389.801862 -274.68449) (xy 389.848344 -274.586954) (xy 389.71347 -274.452334) (xy 389.616188 -274.498562)
			(xy 389.58012 -274.534376) (xy 389.766048 -274.720304)
		)
		(stroke
			(width 0)
			(type solid)
		)
		(fill yes)
		(layer "F.Cu")
		(net "M_E_CPU0_SA_DQ<17>")
	)
	(gr_poly
		(pts
			(xy 389.802624 -256.511298) (xy 389.838438 -256.47523) (xy 389.652764 -256.289556) (xy 389.616696 -256.32537)
			(xy 389.570468 -256.422906) (xy 389.705088 -256.557526)
		)
		(stroke
			(width 0)
			(type solid)
		)
		(fill yes)
		(layer "F.Cu")
		(net "M_E_CPU0_SA_CA<0>")
	)
	(gr_poly
		(pts
			(xy 389.80872 -229.580186) (xy 389.762492 -229.48265) (xy 389.726678 -229.446582) (xy 389.54075 -229.63251)
			(xy 389.576564 -229.668578) (xy 389.6741 -229.714806)
		)
		(stroke
			(width 0)
			(type solid)
		)
		(fill yes)
		(layer "F.Cu")
		(net "M_E_CPU0_SB_DQ<23>")
	)
	(gr_poly
		(pts
			(xy 389.809482 -263.26846) (xy 389.845296 -263.232392) (xy 389.659368 -263.046464) (xy 389.623554 -263.082532)
			(xy 389.577326 -263.179814) (xy 389.711946 -263.314688)
		)
		(stroke
			(width 0)
			(type solid)
		)
		(fill yes)
		(layer "F.Cu")
		(net "M_E_CPU0_SA_CB<3>")
	)
	(gr_poly
		(pts
			(xy 389.81126 -242.316508) (xy 389.775446 -242.28044) (xy 389.67791 -242.234212) (xy 389.54329 -242.368832)
			(xy 389.589518 -242.466368) (xy 389.625332 -242.502436)
		)
		(stroke
			(width 0)
			(type solid)
		)
		(fill yes)
		(layer "F.Cu")
		(net "M_E_CPU0_SB_CB<5>")
	)
	(gr_poly
		(pts
			(xy 389.812022 -255.658112) (xy 389.847836 -255.622044) (xy 389.662162 -255.43637) (xy 389.626094 -255.472184)
			(xy 389.579866 -255.56972) (xy 389.714486 -255.70434)
		)
		(stroke
			(width 0)
			(type solid)
		)
		(fill yes)
		(layer "F.Cu")
		(net "M_E_CPU0_SA_CA<2>")
	)
	(gr_poly
		(pts
			(xy 389.815324 -290.118546) (xy 389.764524 -290.118546) (xy 389.662924 -290.154868) (xy 389.662924 -290.345368)
			(xy 389.764524 -290.381436) (xy 389.815324 -290.381436)
		)
		(stroke
			(width 0)
			(type solid)
		)
		(fill yes)
		(layer "F.Cu")
		(net "M_E_CPU0_SA_DQ<6>")
	)
	(gr_poly
		(pts
			(xy 389.815324 -289.521646) (xy 389.764524 -289.521646) (xy 389.662924 -289.557968) (xy 389.662924 -289.748468)
			(xy 389.764524 -289.784536) (xy 389.815324 -289.784536)
		)
		(stroke
			(width 0)
			(type solid)
		)
		(fill yes)
		(layer "F.Cu")
		(net "M_E_CPU0_SA_DQ<6>")
	)
	(gr_poly
		(pts
			(xy 389.815324 -288.924746) (xy 389.764524 -288.924746) (xy 389.662924 -288.961068) (xy 389.662924 -289.151568)
			(xy 389.764524 -289.187636) (xy 389.815324 -289.187636)
		)
		(stroke
			(width 0)
			(type solid)
		)
		(fill yes)
		(layer "F.Cu")
		(net "M_E_CPU0_SA_DQ<6>")
	)
	(gr_poly
		(pts
			(xy 389.815324 -288.327846) (xy 389.764524 -288.327846) (xy 389.662924 -288.364168) (xy 389.662924 -288.554668)
			(xy 389.764524 -288.590736) (xy 389.815324 -288.590736)
		)
		(stroke
			(width 0)
			(type solid)
		)
		(fill yes)
		(layer "F.Cu")
		(net "M_E_CPU0_SA_DQ<6>")
	)
	(gr_poly
		(pts
			(xy 389.815324 -287.730946) (xy 389.764524 -287.730946) (xy 389.662924 -287.767268) (xy 389.662924 -287.957768)
			(xy 389.764524 -287.993836) (xy 389.815324 -287.993836)
		)
		(stroke
			(width 0)
			(type solid)
		)
		(fill yes)
		(layer "F.Cu")
		(net "M_E_CPU0_SA_DQ<6>")
	)
	(gr_poly
		(pts
			(xy 389.815324 -287.134046) (xy 389.764524 -287.134046) (xy 389.662924 -287.170368) (xy 389.662924 -287.360868)
			(xy 389.764524 -287.396936) (xy 389.815324 -287.396936)
		)
		(stroke
			(width 0)
			(type solid)
		)
		(fill yes)
		(layer "F.Cu")
		(net "M_E_CPU0_SA_DQ<6>")
	)
	(gr_poly
		(pts
			(xy 389.815324 -286.537146) (xy 389.764524 -286.537146) (xy 389.662924 -286.573468) (xy 389.662924 -286.763968)
			(xy 389.764524 -286.800036) (xy 389.815324 -286.800036)
		)
		(stroke
			(width 0)
			(type solid)
		)
		(fill yes)
		(layer "F.Cu")
		(net "M_E_CPU0_SA_DQ<6>")
	)
	(gr_poly
		(pts
			(xy 389.815324 -285.940246) (xy 389.764524 -285.940246) (xy 389.662924 -285.976568) (xy 389.662924 -286.167068)
			(xy 389.764524 -286.203136) (xy 389.815324 -286.203136)
		)
		(stroke
			(width 0)
			(type solid)
		)
		(fill yes)
		(layer "F.Cu")
		(net "M_E_CPU0_SA_DQ<6>")
	)
	(gr_poly
		(pts
			(xy 389.815324 -285.343346) (xy 389.764524 -285.343346) (xy 389.662924 -285.379668) (xy 389.662924 -285.570168)
			(xy 389.764524 -285.606236) (xy 389.815324 -285.606236)
		)
		(stroke
			(width 0)
			(type solid)
		)
		(fill yes)
		(layer "F.Cu")
		(net "M_E_CPU0_SA_DQ<6>")
	)
	(gr_poly
		(pts
			(xy 389.815324 -284.746446) (xy 389.764524 -284.746446) (xy 389.662924 -284.782768) (xy 389.662924 -284.973268)
			(xy 389.764524 -285.009336) (xy 389.815324 -285.009336)
		)
		(stroke
			(width 0)
			(type solid)
		)
		(fill yes)
		(layer "F.Cu")
		(net "M_E_CPU0_SA_DQ<6>")
	)
	(gr_poly
		(pts
			(xy 389.815324 -284.149546) (xy 389.764524 -284.149546) (xy 389.662924 -284.185868) (xy 389.662924 -284.376368)
			(xy 389.764524 -284.412436) (xy 389.815324 -284.412436)
		)
		(stroke
			(width 0)
			(type solid)
		)
		(fill yes)
		(layer "F.Cu")
		(net "M_E_CPU0_SA_DQ<6>")
	)
	(gr_poly
		(pts
			(xy 389.815324 -283.552646) (xy 389.764524 -283.552646) (xy 389.662924 -283.588968) (xy 389.662924 -283.779468)
			(xy 389.764524 -283.815536) (xy 389.815324 -283.815536)
		)
		(stroke
			(width 0)
			(type solid)
		)
		(fill yes)
		(layer "F.Cu")
		(net "M_E_CPU0_SA_DQ<6>")
	)
	(gr_poly
		(pts
			(xy 389.815324 -282.955746) (xy 389.764524 -282.955746) (xy 389.662924 -282.992068) (xy 389.662924 -283.182568)
			(xy 389.764524 -283.218636) (xy 389.815324 -283.218636)
		)
		(stroke
			(width 0)
			(type solid)
		)
		(fill yes)
		(layer "F.Cu")
		(net "M_E_CPU0_SA_DQ<6>")
	)
	(gr_poly
		(pts
			(xy 389.815324 -282.358846) (xy 389.764524 -282.358846) (xy 389.662924 -282.395168) (xy 389.662924 -282.585668)
			(xy 389.764524 -282.621736) (xy 389.815324 -282.621736)
		)
		(stroke
			(width 0)
			(type solid)
		)
		(fill yes)
		(layer "F.Cu")
		(net "M_E_CPU0_SA_DQ<6>")
	)
	(gr_poly
		(pts
			(xy 389.815324 -281.761946) (xy 389.764524 -281.761946) (xy 389.662924 -281.798268) (xy 389.662924 -281.988768)
			(xy 389.764524 -282.024836) (xy 389.815324 -282.024836)
		)
		(stroke
			(width 0)
			(type solid)
		)
		(fill yes)
		(layer "F.Cu")
		(net "M_E_CPU0_SA_DQ<6>")
	)
	(gr_poly
		(pts
			(xy 389.815324 -281.165046) (xy 389.764524 -281.165046) (xy 389.662924 -281.201368) (xy 389.662924 -281.391868)
			(xy 389.764524 -281.427936) (xy 389.815324 -281.427936)
		)
		(stroke
			(width 0)
			(type solid)
		)
		(fill yes)
		(layer "F.Cu")
		(net "M_E_CPU0_SA_DQ<6>")
	)
	(gr_poly
		(pts
			(xy 389.817864 -230.433372) (xy 389.771636 -230.33609) (xy 389.735822 -230.300022) (xy 389.549894 -230.48595)
			(xy 389.585708 -230.521764) (xy 389.683244 -230.568246)
		)
		(stroke
			(width 0)
			(type solid)
		)
		(fill yes)
		(layer "F.Cu")
		(net "M_E_CPU0_SB_DQ<22>")
	)
	(gr_poly
		(pts
			(xy 389.820658 -243.169694) (xy 389.78459 -243.13388) (xy 389.687308 -243.087652) (xy 389.552434 -243.222272)
			(xy 389.598662 -243.319808) (xy 389.63473 -243.355622)
		)
		(stroke
			(width 0)
			(type solid)
		)
		(fill yes)
		(layer "F.Cu")
		(net "M_E_CPU0_SB_CB<4>")
	)
	(gr_poly
		(pts
			(xy 389.824468 -266.629896) (xy 389.860282 -266.594082) (xy 389.674354 -266.408154) (xy 389.63854 -266.443968)
			(xy 389.592312 -266.541504) (xy 389.726932 -266.676124)
		)
		(stroke
			(width 0)
			(type solid)
		)
		(fill yes)
		(layer "F.Cu")
		(net "M_E_CPU0_SA_DQ<28>")
	)
	(gr_poly
		(pts
			(xy 389.833612 -265.776456) (xy 389.86968 -265.740642) (xy 389.683752 -265.554714) (xy 389.647684 -265.590528)
			(xy 389.601456 -265.688064) (xy 389.73633 -265.822684)
		)
		(stroke
			(width 0)
			(type solid)
		)
		(fill yes)
		(layer "F.Cu")
		(net "M_E_CPU0_SA_DQ<29>")
	)
	(gr_poly
		(pts
			(xy 389.842248 -277.25878) (xy 389.934704 -277.203408) (xy 389.897366 -277.016464) (xy 389.790686 -277.00097)
			(xy 389.740902 -277.010876) (xy 389.792464 -277.268686)
		)
		(stroke
			(width 0)
			(type solid)
		)
		(fill yes)
		(layer "F.Cu")
		(net "M_E_CPU0_SA_DQ<7>")
	)
	(gr_poly
		(pts
			(xy 389.844788 -232.994708) (xy 389.79856 -232.897426) (xy 389.762746 -232.861358) (xy 389.576818 -233.047286)
			(xy 389.612632 -233.083354) (xy 389.710168 -233.129582)
		)
		(stroke
			(width 0)
			(type solid)
		)
		(fill yes)
		(layer "F.Cu")
		(net "M_E_CPU0_SB_DQ<19>")
	)
	(gr_poly
		(pts
			(xy 389.846566 -272.278094) (xy 389.88238 -272.24228) (xy 389.696706 -272.056352) (xy 389.660638 -272.092166)
			(xy 389.61441 -272.189702) (xy 389.74903 -272.324322)
		)
		(stroke
			(width 0)
			(type solid)
		)
		(fill yes)
		(layer "F.Cu")
		(net "M_E_CPU0_SA_DQ<20>")
	)
	(gr_poly
		(pts
			(xy 389.850884 -277.561294) (xy 389.799322 -277.303484) (xy 389.749538 -277.313644) (xy 389.657082 -277.369016)
			(xy 389.69442 -277.555706) (xy 389.8011 -277.5712)
		)
		(stroke
			(width 0)
			(type solid)
		)
		(fill yes)
		(layer "F.Cu")
		(net "M_E_CPU0_SA_DQ<7>")
	)
	(gr_poly
		(pts
			(xy 389.853932 -233.848148) (xy 389.807704 -233.750612) (xy 389.77189 -233.714798) (xy 389.585962 -233.900726)
			(xy 389.621776 -233.93654) (xy 389.719312 -233.982768)
		)
		(stroke
			(width 0)
			(type solid)
		)
		(fill yes)
		(layer "F.Cu")
		(net "M_E_CPU0_SB_DQ<18>")
	)
	(gr_poly
		(pts
			(xy 389.856218 -271.424146) (xy 389.892032 -271.388332) (xy 389.706104 -271.202404) (xy 389.67029 -271.238472)
			(xy 389.624062 -271.335754) (xy 389.758682 -271.470628)
		)
		(stroke
			(width 0)
			(type solid)
		)
		(fill yes)
		(layer "F.Cu")
		(net "M_E_CPU0_SA_DQ<21>")
	)
	(gr_poly
		(pts
			(xy 389.857488 -260.727952) (xy 389.893302 -260.691884) (xy 389.707628 -260.50621) (xy 389.67156 -260.542024)
			(xy 389.625332 -260.63956) (xy 389.759952 -260.77418)
		)
		(stroke
			(width 0)
			(type solid)
		)
		(fill yes)
		(layer "F.Cu")
		(net "M_E_CPU0_SA_CB<6>")
	)
	(gr_poly
		(pts
			(xy 389.860536 -257.719576) (xy 389.906764 -257.62204) (xy 389.772144 -257.48742) (xy 389.674862 -257.533648)
			(xy 389.638794 -257.569462) (xy 389.824722 -257.75539)
		)
		(stroke
			(width 0)
			(type solid)
		)
		(fill yes)
		(layer "F.Cu")
		(net "M_E_CPU0_SA_CS_N<2>")
	)
	(gr_poly
		(pts
			(xy 389.865108 -269.726918) (xy 389.900922 -269.69085) (xy 389.714994 -269.504922) (xy 389.67918 -269.54099)
			(xy 389.632952 -269.638272) (xy 389.767572 -269.773146)
		)
		(stroke
			(width 0)
			(type solid)
		)
		(fill yes)
		(layer "F.Cu")
		(net "M_E_CPU0_SA_DQ<26>")
	)
	(gr_poly
		(pts
			(xy 389.867394 -264.476484) (xy 389.913622 -264.379202) (xy 389.779002 -264.244328) (xy 389.681466 -264.290556)
			(xy 389.645652 -264.326624) (xy 389.83158 -264.512552)
		)
		(stroke
			(width 0)
			(type solid)
		)
		(fill yes)
		(layer "F.Cu")
		(net "M_E_CPU0_SA_CB<0>")
	)
	(gr_poly
		(pts
			(xy 389.869934 -256.866136) (xy 389.916162 -256.7686) (xy 389.781288 -256.63398) (xy 389.684006 -256.680208)
			(xy 389.647938 -256.716022) (xy 389.833866 -256.90195)
		)
		(stroke
			(width 0)
			(type solid)
		)
		(fill yes)
		(layer "F.Cu")
		(net "M_E_CPU0_SA_CS_N<3>")
	)
	(gr_poly
		(pts
			(xy 389.874252 -268.873478) (xy 389.910066 -268.83741) (xy 389.724138 -268.651482) (xy 389.688324 -268.68755)
			(xy 389.642096 -268.784832) (xy 389.776716 -268.919706)
		)
		(stroke
			(width 0)
			(type solid)
		)
		(fill yes)
		(layer "F.Cu")
		(net "M_E_CPU0_SA_DQ<27>")
	)
	(gr_poly
		(pts
			(xy 389.876538 -263.623298) (xy 389.922766 -263.525762) (xy 389.788146 -263.391142) (xy 389.690864 -263.43737)
			(xy 389.654796 -263.473184) (xy 389.840724 -263.659112)
		)
		(stroke
			(width 0)
			(type solid)
		)
		(fill yes)
		(layer "F.Cu")
		(net "M_E_CPU0_SA_CB<1>")
	)
	(gr_poly
		(pts
			(xy 389.879332 -256.01295) (xy 389.92556 -255.915414) (xy 389.790686 -255.780794) (xy 389.693404 -255.827022)
			(xy 389.657336 -255.862836) (xy 389.843264 -256.048764)
		)
		(stroke
			(width 0)
			(type solid)
		)
		(fill yes)
		(layer "F.Cu")
		(net "M_E_CPU0_SA_CA<1>")
	)
	(gr_poly
		(pts
			(xy 389.888984 -242.023138) (xy 389.842756 -241.925602) (xy 389.806688 -241.889788) (xy 389.62076 -242.075716)
			(xy 389.656828 -242.11153) (xy 389.75411 -242.157758)
		)
		(stroke
			(width 0)
			(type solid)
		)
		(fill yes)
		(layer "F.Cu")
		(net "M_E_CPU0_SB_CB<7>")
	)
	(gr_poly
		(pts
			(xy 389.894318 -279.074626) (xy 389.986774 -279.019) (xy 389.949436 -278.83231) (xy 389.842756 -278.816816)
			(xy 389.792972 -278.826722) (xy 389.844534 -279.084532)
		)
		(stroke
			(width 0)
			(type solid)
		)
		(fill yes)
		(layer "F.Cu")
		(net "M_E_CPU0_SA_DQ<5>")
	)
	(gr_poly
		(pts
			(xy 389.898128 -242.876578) (xy 389.8519 -242.779042) (xy 389.815832 -242.743228) (xy 389.630158 -242.928902)
			(xy 389.665972 -242.96497) (xy 389.763508 -243.011198)
		)
		(stroke
			(width 0)
			(type solid)
		)
		(fill yes)
		(layer "F.Cu")
		(net "M_E_CPU0_SB_CB<6>")
	)
	(gr_poly
		(pts
			(xy 389.900668 -266.131548) (xy 389.94715 -266.034012) (xy 389.812276 -265.899392) (xy 389.714994 -265.94562)
			(xy 389.678926 -265.981434) (xy 389.864854 -266.167362)
		)
		(stroke
			(width 0)
			(type solid)
		)
		(fill yes)
		(layer "F.Cu")
		(net "M_E_CPU0_SA_DQ<30>")
	)
	(gr_poly
		(pts
			(xy 389.903208 -279.37714) (xy 389.851392 -279.11933) (xy 389.801608 -279.129236) (xy 389.709152 -279.184862)
			(xy 389.74649 -279.371552) (xy 389.853424 -279.387046)
		)
		(stroke
			(width 0)
			(type solid)
		)
		(fill yes)
		(layer "F.Cu")
		(net "M_E_CPU0_SA_DQ<5>")
	)
	(gr_poly
		(pts
			(xy 389.903716 -247.748552) (xy 389.867648 -247.646952) (xy 389.677148 -247.646952) (xy 389.64108 -247.748552)
			(xy 389.64108 -247.799352) (xy 389.903716 -247.799352)
		)
		(stroke
			(width 0)
			(type solid)
		)
		(fill yes)
		(layer "F.Cu")
		(net "M_E_CPU0_SB_CA<4>")
	)
	(gr_poly
		(pts
			(xy 389.903716 -247.443752) (xy 389.867648 -247.342152) (xy 389.677148 -247.342152) (xy 389.64108 -247.443752)
			(xy 389.64108 -247.494552) (xy 389.903716 -247.494552)
		)
		(stroke
			(width 0)
			(type solid)
		)
		(fill yes)
		(layer "F.Cu")
		(net "M_E_CPU0_SB_CA<5>")
	)
	(gr_poly
		(pts
			(xy 389.903716 -247.138952) (xy 389.867648 -247.037352) (xy 389.677148 -247.037352) (xy 389.64108 -247.138952)
			(xy 389.64108 -247.189752) (xy 389.903716 -247.189752)
		)
		(stroke
			(width 0)
			(type solid)
		)
		(fill yes)
		(layer "F.Cu")
		(net "M_E_CPU0_SB_CA<6>")
	)
	(gr_poly
		(pts
			(xy 389.903716 -246.834152) (xy 389.867648 -246.732552) (xy 389.677148 -246.732552) (xy 389.64108 -246.834152)
			(xy 389.64108 -246.884952) (xy 389.903716 -246.884952)
		)
		(stroke
			(width 0)
			(type solid)
		)
		(fill yes)
		(layer "F.Cu")
		(net "M_E_CPU0_SB_PAR")
	)
	(gr_poly
		(pts
			(xy 389.903716 -246.529352) (xy 389.867648 -246.427752) (xy 389.677148 -246.427752) (xy 389.64108 -246.529352)
			(xy 389.64108 -246.580152) (xy 389.903716 -246.580152)
		)
		(stroke
			(width 0)
			(type solid)
		)
		(fill yes)
		(layer "F.Cu")
		(net "M_E_CPU0_SB_CS_N<0>")
	)
	(gr_poly
		(pts
			(xy 389.903716 -246.224552) (xy 389.867648 -246.122952) (xy 389.677148 -246.122952) (xy 389.64108 -246.224552)
			(xy 389.64108 -246.275352) (xy 389.903716 -246.275352)
		)
		(stroke
			(width 0)
			(type solid)
		)
		(fill yes)
		(layer "F.Cu")
		(net "M_E_CPU0_SB_CS_N<2>")
	)
	(gr_poly
		(pts
			(xy 389.903716 -245.919752) (xy 389.867648 -245.818152) (xy 389.677148 -245.818152) (xy 389.64108 -245.919752)
			(xy 389.64108 -245.970552) (xy 389.903716 -245.970552)
		)
		(stroke
			(width 0)
			(type solid)
		)
		(fill yes)
		(layer "F.Cu")
		(net "M_E_CPU0_SB_CS_N<1>")
	)
	(gr_poly
		(pts
			(xy 389.903716 -245.614952) (xy 389.867648 -245.513352) (xy 389.677148 -245.513352) (xy 389.64108 -245.614952)
			(xy 389.64108 -245.665752) (xy 389.903716 -245.665752)
		)
		(stroke
			(width 0)
			(type solid)
		)
		(fill yes)
		(layer "F.Cu")
		(net "M_E_CPU0_SB_CS_N<3>")
	)
	(gr_poly
		(pts
			(xy 389.91032 -265.277854) (xy 389.956548 -265.180318) (xy 389.821928 -265.045698) (xy 389.724392 -265.091926)
			(xy 389.688578 -265.127994) (xy 389.874252 -265.313668)
		)
		(stroke
			(width 0)
			(type solid)
		)
		(fill yes)
		(layer "F.Cu")
		(net "M_E_CPU0_SA_DQ<31>")
	)
	(gr_poly
		(pts
			(xy 389.923274 -271.779238) (xy 389.969756 -271.681702) (xy 389.834882 -271.547082) (xy 389.7376 -271.59331)
			(xy 389.701532 -271.629124) (xy 389.88746 -271.815052)
		)
		(stroke
			(width 0)
			(type solid)
		)
		(fill yes)
		(layer "F.Cu")
		(net "M_E_CPU0_SA_DQ<22>")
	)
	(gr_poly
		(pts
			(xy 389.924798 -261.08279) (xy 389.971026 -260.985254) (xy 389.836152 -260.850634) (xy 389.73887 -260.896862)
			(xy 389.702802 -260.932676) (xy 389.88873 -261.118604)
		)
		(stroke
			(width 0)
			(type solid)
		)
		(fill yes)
		(layer "F.Cu")
		(net "M_E_CPU0_SA_CB<4>")
	)
	(gr_poly
		(pts
			(xy 389.93191 -275.820632) (xy 389.967978 -275.784818) (xy 389.78205 -275.59889) (xy 389.745982 -275.634704)
			(xy 389.699754 -275.73224) (xy 389.834628 -275.86686)
		)
		(stroke
			(width 0)
			(type solid)
		)
		(fill yes)
		(layer "F.Cu")
		(net "M_E_CPU0_SA_DQ<16>")
	)
	(gr_poly
		(pts
			(xy 389.932418 -270.081756) (xy 389.978646 -269.98422) (xy 389.843772 -269.8496) (xy 389.74649 -269.895828)
			(xy 389.710422 -269.931642) (xy 389.89635 -270.11757)
		)
		(stroke
			(width 0)
			(type solid)
		)
		(fill yes)
		(layer "F.Cu")
		(net "M_E_CPU0_SA_DQ<24>")
	)
	(gr_poly
		(pts
			(xy 389.932672 -270.925544) (xy 389.9789 -270.828262) (xy 389.84428 -270.693388) (xy 389.746744 -270.739616)
			(xy 389.71093 -270.775684) (xy 389.896858 -270.961612)
		)
		(stroke
			(width 0)
			(type solid)
		)
		(fill yes)
		(layer "F.Cu")
		(net "M_E_CPU0_SA_DQ<23>")
	)
	(gr_poly
		(pts
			(xy 389.933942 -260.22935) (xy 389.98017 -260.131814) (xy 389.84555 -259.997194) (xy 389.748014 -260.043422)
			(xy 389.7122 -260.07949) (xy 389.898128 -260.265418)
		)
		(stroke
			(width 0)
			(type solid)
		)
		(fill yes)
		(layer "F.Cu")
		(net "M_E_CPU0_SA_CB<5>")
	)
	(gr_poly
		(pts
			(xy 389.941308 -274.967192) (xy 389.977122 -274.931378) (xy 389.791194 -274.74545) (xy 389.75538 -274.781264)
			(xy 389.709152 -274.8788) (xy 389.843772 -275.01342)
		)
		(stroke
			(width 0)
			(type solid)
		)
		(fill yes)
		(layer "F.Cu")
		(net "M_E_CPU0_SA_DQ<17>")
	)
	(gr_poly
		(pts
			(xy 389.941562 -269.228316) (xy 389.98779 -269.13078) (xy 389.852916 -268.99616) (xy 389.755634 -269.042388)
			(xy 389.719566 -269.078202) (xy 389.905494 -269.26413)
		)
		(stroke
			(width 0)
			(type solid)
		)
		(fill yes)
		(layer "F.Cu")
		(net "M_E_CPU0_SA_DQ<25>")
	)
	(gr_poly
		(pts
			(xy 389.946896 -230.088948) (xy 389.910828 -230.053134) (xy 389.813546 -230.006906) (xy 389.678672 -230.141526)
			(xy 389.7249 -230.239062) (xy 389.760968 -230.274876)
		)
		(stroke
			(width 0)
			(type solid)
		)
		(fill yes)
		(layer "F.Cu")
		(net "M_E_CPU0_SB_DQ<22>")
	)
	(gr_poly
		(pts
			(xy 389.959342 -277.843996) (xy 390.051798 -277.788624) (xy 390.01446 -277.60168) (xy 389.90778 -277.586186)
			(xy 389.857996 -277.596092) (xy 389.909558 -277.853902)
		)
		(stroke
			(width 0)
			(type solid)
		)
		(fill yes)
		(layer "F.Cu")
		(net "M_E_CPU0_SA_DQ<7>")
	)
	(gr_poly
		(pts
			(xy 389.967724 -290.046918) (xy 389.967724 -289.856418) (xy 389.866124 -289.820096) (xy 389.815324 -289.820096)
			(xy 389.815324 -290.082986) (xy 389.866124 -290.082986)
		)
		(stroke
			(width 0)
			(type solid)
		)
		(fill yes)
		(layer "F.Cu")
		(net "M_E_CPU0_SA_DQ<6>")
	)
	(gr_poly
		(pts
			(xy 389.967724 -289.450018) (xy 389.967724 -289.259518) (xy 389.866124 -289.223196) (xy 389.815324 -289.223196)
			(xy 389.815324 -289.486086) (xy 389.866124 -289.486086)
		)
		(stroke
			(width 0)
			(type solid)
		)
		(fill yes)
		(layer "F.Cu")
		(net "M_E_CPU0_SA_DQ<6>")
	)
	(gr_poly
		(pts
			(xy 389.967724 -288.853118) (xy 389.967724 -288.662618) (xy 389.866124 -288.626296) (xy 389.815324 -288.626296)
			(xy 389.815324 -288.889186) (xy 389.866124 -288.889186)
		)
		(stroke
			(width 0)
			(type solid)
		)
		(fill yes)
		(layer "F.Cu")
		(net "M_E_CPU0_SA_DQ<6>")
	)
	(gr_poly
		(pts
			(xy 389.967724 -288.256218) (xy 389.967724 -288.065718) (xy 389.866124 -288.029396) (xy 389.815324 -288.029396)
			(xy 389.815324 -288.292286) (xy 389.866124 -288.292286)
		)
		(stroke
			(width 0)
			(type solid)
		)
		(fill yes)
		(layer "F.Cu")
		(net "M_E_CPU0_SA_DQ<6>")
	)
	(gr_poly
		(pts
			(xy 389.967724 -287.659318) (xy 389.967724 -287.468818) (xy 389.866124 -287.432496) (xy 389.815324 -287.432496)
			(xy 389.815324 -287.695386) (xy 389.866124 -287.695386)
		)
		(stroke
			(width 0)
			(type solid)
		)
		(fill yes)
		(layer "F.Cu")
		(net "M_E_CPU0_SA_DQ<6>")
	)
	(gr_poly
		(pts
			(xy 389.967724 -287.062418) (xy 389.967724 -286.871918) (xy 389.866124 -286.835596) (xy 389.815324 -286.835596)
			(xy 389.815324 -287.098486) (xy 389.866124 -287.098486)
		)
		(stroke
			(width 0)
			(type solid)
		)
		(fill yes)
		(layer "F.Cu")
		(net "M_E_CPU0_SA_DQ<6>")
	)
	(gr_poly
		(pts
			(xy 389.967724 -286.465518) (xy 389.967724 -286.275018) (xy 389.866124 -286.238696) (xy 389.815324 -286.238696)
			(xy 389.815324 -286.501586) (xy 389.866124 -286.501586)
		)
		(stroke
			(width 0)
			(type solid)
		)
		(fill yes)
		(layer "F.Cu")
		(net "M_E_CPU0_SA_DQ<6>")
	)
	(gr_poly
		(pts
			(xy 389.967724 -285.868618) (xy 389.967724 -285.678118) (xy 389.866124 -285.641796) (xy 389.815324 -285.641796)
			(xy 389.815324 -285.904686) (xy 389.866124 -285.904686)
		)
		(stroke
			(width 0)
			(type solid)
		)
		(fill yes)
		(layer "F.Cu")
		(net "M_E_CPU0_SA_DQ<6>")
	)
	(gr_poly
		(pts
			(xy 389.967724 -285.271718) (xy 389.967724 -285.081218) (xy 389.866124 -285.044896) (xy 389.815324 -285.044896)
			(xy 389.815324 -285.307786) (xy 389.866124 -285.307786)
		)
		(stroke
			(width 0)
			(type solid)
		)
		(fill yes)
		(layer "F.Cu")
		(net "M_E_CPU0_SA_DQ<6>")
	)
	(gr_poly
		(pts
			(xy 389.967724 -284.674818) (xy 389.967724 -284.484318) (xy 389.866124 -284.447996) (xy 389.815324 -284.447996)
			(xy 389.815324 -284.710886) (xy 389.866124 -284.710886)
		)
		(stroke
			(width 0)
			(type solid)
		)
		(fill yes)
		(layer "F.Cu")
		(net "M_E_CPU0_SA_DQ<6>")
	)
	(gr_poly
		(pts
			(xy 389.967724 -284.077918) (xy 389.967724 -283.887418) (xy 389.866124 -283.851096) (xy 389.815324 -283.851096)
			(xy 389.815324 -284.113986) (xy 389.866124 -284.113986)
		)
		(stroke
			(width 0)
			(type solid)
		)
		(fill yes)
		(layer "F.Cu")
		(net "M_E_CPU0_SA_DQ<6>")
	)
	(gr_poly
		(pts
			(xy 389.967724 -283.481018) (xy 389.967724 -283.290518) (xy 389.866124 -283.254196) (xy 389.815324 -283.254196)
			(xy 389.815324 -283.517086) (xy 389.866124 -283.517086)
		)
		(stroke
			(width 0)
			(type solid)
		)
		(fill yes)
		(layer "F.Cu")
		(net "M_E_CPU0_SA_DQ<6>")
	)
	(gr_poly
		(pts
			(xy 389.967724 -282.884118) (xy 389.967724 -282.693618) (xy 389.866124 -282.657296) (xy 389.815324 -282.657296)
			(xy 389.815324 -282.920186) (xy 389.866124 -282.920186)
		)
		(stroke
			(width 0)
			(type solid)
		)
		(fill yes)
		(layer "F.Cu")
		(net "M_E_CPU0_SA_DQ<6>")
	)
	(gr_poly
		(pts
			(xy 389.967724 -282.287218) (xy 389.967724 -282.096718) (xy 389.866124 -282.060396) (xy 389.815324 -282.060396)
			(xy 389.815324 -282.323286) (xy 389.866124 -282.323286)
		)
		(stroke
			(width 0)
			(type solid)
		)
		(fill yes)
		(layer "F.Cu")
		(net "M_E_CPU0_SA_DQ<6>")
	)
	(gr_poly
		(pts
			(xy 389.967724 -281.690318) (xy 389.967724 -281.499818) (xy 389.866124 -281.463496) (xy 389.815324 -281.463496)
			(xy 389.815324 -281.726386) (xy 389.866124 -281.726386)
		)
		(stroke
			(width 0)
			(type solid)
		)
		(fill yes)
		(layer "F.Cu")
		(net "M_E_CPU0_SA_DQ<6>")
	)
	(gr_poly
		(pts
			(xy 389.967724 -281.093418) (xy 389.967724 -280.902918) (xy 389.866124 -280.866596) (xy 389.815324 -280.866596)
			(xy 389.815324 -281.129486) (xy 389.866124 -281.129486)
		)
		(stroke
			(width 0)
			(type solid)
		)
		(fill yes)
		(layer "F.Cu")
		(net "M_E_CPU0_SA_DQ<6>")
	)
	(gr_poly
		(pts
			(xy 389.968232 -278.14651) (xy 389.91667 -277.888954) (xy 389.866632 -277.89886) (xy 389.774176 -277.954232)
			(xy 389.811514 -278.141176) (xy 389.918448 -278.15667)
		)
		(stroke
			(width 0)
			(type solid)
		)
		(fill yes)
		(layer "F.Cu")
		(net "M_E_CPU0_SA_DQ<7>")
	)
	(gr_poly
		(pts
			(xy 389.973566 -232.650538) (xy 389.937752 -232.61447) (xy 389.840216 -232.568242) (xy 389.705596 -232.702862)
			(xy 389.751824 -232.800398) (xy 389.787892 -232.836212)
		)
		(stroke
			(width 0)
			(type solid)
		)
		(fill yes)
		(layer "F.Cu")
		(net "M_E_CPU0_SB_DQ<19>")
	)
	(gr_poly
		(pts
			(xy 389.982964 -233.503724) (xy 389.946896 -233.46791) (xy 389.849614 -233.421682) (xy 389.71474 -233.556302)
			(xy 389.760968 -233.653838) (xy 389.797036 -233.689652)
		)
		(stroke
			(width 0)
			(type solid)
		)
		(fill yes)
		(layer "F.Cu")
		(net "M_E_CPU0_SB_DQ<18>")
	)
	(gr_poly
		(pts
			(xy 389.9916 -235.200952) (xy 389.955786 -235.164884) (xy 389.85825 -235.118656) (xy 389.72363 -235.253276)
			(xy 389.769858 -235.350812) (xy 389.805926 -235.386626)
		)
		(stroke
			(width 0)
			(type solid)
		)
		(fill yes)
		(layer "F.Cu")
		(net "M_E_CPU0_SB_DQ<13>")
	)
	(gr_poly
		(pts
			(xy 389.999728 -258.002278) (xy 390.035796 -257.966464) (xy 389.849868 -257.780536) (xy 389.814054 -257.81635)
			(xy 389.767572 -257.913886) (xy 389.902446 -258.048506)
		)
		(stroke
			(width 0)
			(type solid)
		)
		(fill yes)
		(layer "F.Cu")
		(net "M_E_CPU0_SA_CS_N<2>")
	)
	(gr_poly
		(pts
			(xy 390.00303 -239.24514) (xy 389.966708 -239.14354) (xy 389.776208 -239.14354) (xy 389.74014 -239.24514)
			(xy 389.74014 -239.29594) (xy 390.00303 -239.29594)
		)
		(stroke
			(width 0)
			(type solid)
		)
		(fill yes)
		(layer "F.Cu")
		(net "M_E_CPU0_SB_CB<3>")
	)
	(gr_poly
		(pts
			(xy 390.006586 -264.75944) (xy 390.042654 -264.723626) (xy 389.856726 -264.537698) (xy 389.820658 -264.573512)
			(xy 389.77443 -264.671048) (xy 389.90905 -264.805668)
		)
		(stroke
			(width 0)
			(type solid)
		)
		(fill yes)
		(layer "F.Cu")
		(net "M_E_CPU0_SA_CB<0>")
	)
	(gr_poly
		(pts
			(xy 390.008364 -275.32203) (xy 390.054592 -275.224748) (xy 389.919972 -275.089874) (xy 389.822436 -275.136356)
			(xy 389.786622 -275.17217) (xy 389.97255 -275.358098)
		)
		(stroke
			(width 0)
			(type solid)
		)
		(fill yes)
		(layer "F.Cu")
		(net "M_E_CPU0_SA_DQ<18>")
	)
	(gr_poly
		(pts
			(xy 390.009126 -257.149092) (xy 390.04494 -257.113024) (xy 389.859012 -256.927096) (xy 389.823198 -256.963164)
			(xy 389.77697 -257.060446) (xy 389.91159 -257.19532)
		)
		(stroke
			(width 0)
			(type solid)
		)
		(fill yes)
		(layer "F.Cu")
		(net "M_E_CPU0_SA_CS_N<3>")
	)
	(gr_poly
		(pts
			(xy 390.011412 -279.659842) (xy 390.104122 -279.60447) (xy 390.06653 -279.417526) (xy 389.95985 -279.402032)
			(xy 389.910066 -279.411938) (xy 389.961628 -279.669748)
		)
		(stroke
			(width 0)
			(type solid)
		)
		(fill yes)
		(layer "F.Cu")
		(net "M_E_CPU0_SA_DQ<5>")
	)
	(gr_poly
		(pts
			(xy 390.01573 -263.906) (xy 390.051798 -263.870186) (xy 389.86587 -263.684258) (xy 389.830056 -263.720072)
			(xy 389.783574 -263.817608) (xy 389.918448 -263.952228)
		)
		(stroke
			(width 0)
			(type solid)
		)
		(fill yes)
		(layer "F.Cu")
		(net "M_E_CPU0_SA_CB<1>")
	)
	(gr_poly
		(pts
			(xy 390.017762 -274.46859) (xy 390.064244 -274.371054) (xy 389.92937 -274.236434) (xy 389.832088 -274.282662)
			(xy 389.79602 -274.318476) (xy 389.981948 -274.504404)
		)
		(stroke
			(width 0)
			(type solid)
		)
		(fill yes)
		(layer "F.Cu")
		(net "M_E_CPU0_SA_DQ<19>")
	)
	(gr_poly
		(pts
			(xy 390.01827 -256.295652) (xy 390.054084 -256.259584) (xy 389.86841 -256.07391) (xy 389.832342 -256.109724)
			(xy 389.786114 -256.20726) (xy 389.920734 -256.34188)
		)
		(stroke
			(width 0)
			(type solid)
		)
		(fill yes)
		(layer "F.Cu")
		(net "M_E_CPU0_SA_CA<1>")
	)
	(gr_poly
		(pts
			(xy 390.020302 -279.962356) (xy 389.96874 -279.704546) (xy 389.918956 -279.714706) (xy 389.826246 -279.770078)
			(xy 389.863838 -279.956768) (xy 389.970518 -279.972516)
		)
		(stroke
			(width 0)
			(type solid)
		)
		(fill yes)
		(layer "F.Cu")
		(net "M_E_CPU0_SA_DQ<5>")
	)
	(gr_poly
		(pts
			(xy 390.024366 -229.795832) (xy 389.978138 -229.698296) (xy 389.942324 -229.662228) (xy 389.756396 -229.848156)
			(xy 389.79221 -229.884224) (xy 389.889746 -229.930452)
		)
		(stroke
			(width 0)
			(type solid)
		)
		(fill yes)
		(layer "F.Cu")
		(net "M_E_CPU0_SB_DQ<21>")
	)
	(gr_poly
		(pts
			(xy 390.026906 -242.532154) (xy 389.991092 -242.496086) (xy 389.893556 -242.449858) (xy 389.758936 -242.584478)
			(xy 389.805164 -242.682014) (xy 389.840978 -242.718082)
		)
		(stroke
			(width 0)
			(type solid)
		)
		(fill yes)
		(layer "F.Cu")
		(net "M_E_CPU0_SB_CB<6>")
	)
	(gr_poly
		(pts
			(xy 390.027668 -255.442466) (xy 390.063482 -255.406398) (xy 389.877808 -255.220724) (xy 389.84174 -255.256538)
			(xy 389.795512 -255.354074) (xy 389.930132 -255.488694)
		)
		(stroke
			(width 0)
			(type solid)
		)
		(fill yes)
		(layer "F.Cu")
		(net "M_E_CPU0_SA_CA<3>")
	)
	(gr_poly
		(pts
			(xy 390.03351 -230.649018) (xy 389.987282 -230.551736) (xy 389.951468 -230.515668) (xy 389.76554 -230.701596)
			(xy 389.801354 -230.73741) (xy 389.89889 -230.783892)
		)
		(stroke
			(width 0)
			(type solid)
		)
		(fill yes)
		(layer "F.Cu")
		(net "M_E_CPU0_SB_DQ<20>")
	)
	(gr_poly
		(pts
			(xy 390.040114 -266.41425) (xy 390.075928 -266.378436) (xy 389.89 -266.192508) (xy 389.854186 -266.228322)
			(xy 389.807958 -266.325858) (xy 389.942578 -266.460478)
		)
		(stroke
			(width 0)
			(type solid)
		)
		(fill yes)
		(layer "F.Cu")
		(net "M_E_CPU0_SA_DQ<30>")
	)
	(gr_poly
		(pts
			(xy 390.049512 -265.56081) (xy 390.085326 -265.524742) (xy 389.899398 -265.338814) (xy 389.863584 -265.374882)
			(xy 389.817356 -265.472164) (xy 389.951976 -265.607038)
		)
		(stroke
			(width 0)
			(type solid)
		)
		(fill yes)
		(layer "F.Cu")
		(net "M_E_CPU0_SA_DQ<31>")
	)
	(gr_poly
		(pts
			(xy 390.050782 -238.686086) (xy 390.01446 -238.584486) (xy 389.82396 -238.584486) (xy 389.787892 -238.686086)
			(xy 389.787892 -238.736886) (xy 390.050782 -238.736886)
		)
		(stroke
			(width 0)
			(type solid)
		)
		(fill yes)
		(layer "F.Cu")
		(net "M_E_CPU0_SB_DQ<8>")
	)
	(gr_poly
		(pts
			(xy 390.050782 -238.381286) (xy 390.01446 -238.279686) (xy 389.82396 -238.279686) (xy 389.787892 -238.381286)
			(xy 389.787892 -238.432086) (xy 390.050782 -238.432086)
		)
		(stroke
			(width 0)
			(type solid)
		)
		(fill yes)
		(layer "F.Cu")
		(net "M_E_CPU0_SB_DQ<10>")
	)
	(gr_poly
		(pts
			(xy 390.050782 -237.771686) (xy 390.01446 -237.670086) (xy 389.82396 -237.670086) (xy 389.787892 -237.771686)
			(xy 389.787892 -237.822486) (xy 390.050782 -237.822486)
		)
		(stroke
			(width 0)
			(type solid)
		)
		(fill yes)
		(layer "F.Cu")
		(net "M_E_CPU0_SB_DQ<11>")
	)
	(gr_poly
		(pts
			(xy 390.060434 -233.210354) (xy 390.014206 -233.113072) (xy 389.978392 -233.077004) (xy 389.792464 -233.262932)
			(xy 389.828278 -233.299) (xy 389.925814 -233.345228)
		)
		(stroke
			(width 0)
			(type solid)
		)
		(fill yes)
		(layer "F.Cu")
		(net "M_E_CPU0_SB_DQ<17>")
	)
	(gr_poly
		(pts
			(xy 390.062466 -272.06194) (xy 390.098534 -272.026126) (xy 389.912606 -271.840198) (xy 389.876792 -271.876012)
			(xy 389.830564 -271.973548) (xy 389.965184 -272.108168)
		)
		(stroke
			(width 0)
			(type solid)
		)
		(fill yes)
		(layer "F.Cu")
		(net "M_E_CPU0_SA_DQ<22>")
	)
	(gr_poly
		(pts
			(xy 390.06399 -261.365492) (xy 390.099804 -261.329678) (xy 389.913876 -261.14375) (xy 389.878062 -261.179818)
			(xy 389.831834 -261.2771) (xy 389.966454 -261.411974)
		)
		(stroke
			(width 0)
			(type solid)
		)
		(fill yes)
		(layer "F.Cu")
		(net "M_E_CPU0_SA_CB<4>")
	)
	(gr_poly
		(pts
			(xy 390.067038 -258.35737) (xy 390.113266 -258.259834) (xy 389.978392 -258.125214) (xy 389.88111 -258.171442)
			(xy 389.845042 -258.207256) (xy 390.03097 -258.393184)
		)
		(stroke
			(width 0)
			(type solid)
		)
		(fill yes)
		(layer "F.Cu")
		(net "M_E_CPU0_SA_CS_N<0>")
	)
	(gr_poly
		(pts
			(xy 390.069324 -234.907582) (xy 390.023096 -234.810046) (xy 389.987028 -234.774232) (xy 389.8011 -234.96016)
			(xy 389.837168 -234.995974) (xy 389.93445 -235.042202)
		)
		(stroke
			(width 0)
			(type solid)
		)
		(fill yes)
		(layer "F.Cu")
		(net "M_E_CPU0_SB_DQ<15>")
	)
	(gr_poly
		(pts
			(xy 390.069578 -234.063794) (xy 390.02335 -233.966258) (xy 389.987536 -233.930444) (xy 389.801608 -234.116372)
			(xy 389.837422 -234.152186) (xy 389.934958 -234.198414)
		)
		(stroke
			(width 0)
			(type solid)
		)
		(fill yes)
		(layer "F.Cu")
		(net "M_E_CPU0_SB_DQ<16>")
	)
	(gr_poly
		(pts
			(xy 390.07161 -270.364458) (xy 390.107424 -270.328644) (xy 389.921496 -270.142716) (xy 389.885682 -270.178784)
			(xy 389.839454 -270.276066) (xy 389.974074 -270.410686)
		)
		(stroke
			(width 0)
			(type solid)
		)
		(fill yes)
		(layer "F.Cu")
		(net "M_E_CPU0_SA_DQ<24>")
	)
	(gr_poly
		(pts
			(xy 390.071864 -271.2085) (xy 390.107678 -271.172432) (xy 389.922004 -270.986758) (xy 389.885936 -271.022572)
			(xy 389.839708 -271.120108) (xy 389.974328 -271.254728)
		)
		(stroke
			(width 0)
			(type solid)
		)
		(fill yes)
		(layer "F.Cu")
		(net "M_E_CPU0_SA_DQ<23>")
	)
	(gr_poly
		(pts
			(xy 390.073134 -260.512306) (xy 390.108948 -260.476238) (xy 389.923274 -260.290564) (xy 389.887206 -260.326378)
			(xy 389.840978 -260.423914) (xy 389.975598 -260.558534)
		)
		(stroke
			(width 0)
			(type solid)
		)
		(fill yes)
		(layer "F.Cu")
		(net "M_E_CPU0_SA_CB<5>")
	)
	(gr_poly
		(pts
			(xy 390.076182 -257.50393) (xy 390.12241 -257.406394) (xy 389.98779 -257.271774) (xy 389.890508 -257.318002)
			(xy 389.85444 -257.353816) (xy 390.040368 -257.539744)
		)
		(stroke
			(width 0)
			(type solid)
		)
		(fill yes)
		(layer "F.Cu")
		(net "M_E_CPU0_SA_CS_N<1>")
	)
	(gr_poly
		(pts
			(xy 390.076436 -278.429212) (xy 390.169146 -278.37384) (xy 390.131808 -278.18715) (xy 390.024874 -278.171402)
			(xy 389.97509 -278.181562) (xy 390.026652 -278.439372)
		)
		(stroke
			(width 0)
			(type solid)
		)
		(fill yes)
		(layer "F.Cu")
		(net "M_E_CPU0_SA_DQ<7>")
	)
	(gr_poly
		(pts
			(xy 390.078468 -235.761022) (xy 390.03224 -235.663486) (xy 389.996426 -235.627418) (xy 389.810498 -235.813346)
			(xy 389.846312 -235.849414) (xy 389.943848 -235.895642)
		)
		(stroke
			(width 0)
			(type solid)
		)
		(fill yes)
		(layer "F.Cu")
		(net "M_E_CPU0_SB_DQ<14>")
	)
	(gr_poly
		(pts
			(xy 390.080754 -269.511018) (xy 390.116568 -269.475204) (xy 389.93064 -269.289276) (xy 389.894826 -269.325344)
			(xy 389.848598 -269.422626) (xy 389.983218 -269.557246)
		)
		(stroke
			(width 0)
			(type solid)
		)
		(fill yes)
		(layer "F.Cu")
		(net "M_E_CPU0_SA_DQ<25>")
	)
	(gr_poly
		(pts
			(xy 390.08304 -264.260838) (xy 390.129268 -264.163556) (xy 389.994648 -264.028682) (xy 389.897112 -264.07491)
			(xy 389.861298 -264.110978) (xy 390.047226 -264.296906)
		)
		(stroke
			(width 0)
			(type solid)
		)
		(fill yes)
		(layer "F.Cu")
		(net "M_E_CPU0_SA_CB<2>")
	)
	(gr_poly
		(pts
			(xy 390.085326 -278.73198) (xy 390.033764 -278.47417) (xy 389.98398 -278.484076) (xy 389.891524 -278.539448)
			(xy 389.928862 -278.726392) (xy 390.035542 -278.741886)
		)
		(stroke
			(width 0)
			(type solid)
		)
		(fill yes)
		(layer "F.Cu")
		(net "M_E_CPU0_SA_DQ<7>")
	)
	(gr_poly
		(pts
			(xy 390.08558 -256.65049) (xy 390.131808 -256.552954) (xy 389.996934 -256.418334) (xy 389.899652 -256.464562)
			(xy 389.863584 -256.500376) (xy 390.049512 -256.686304)
		)
		(stroke
			(width 0)
			(type solid)
		)
		(fill yes)
		(layer "F.Cu")
		(net "M_E_CPU0_SA_CA<0>")
	)
	(gr_poly
		(pts
			(xy 390.08558 -225.009456) (xy 390.03478 -225.009456) (xy 389.93318 -225.045778) (xy 389.93318 -225.236278)
			(xy 390.03478 -225.272346) (xy 390.08558 -225.272346)
		)
		(stroke
			(width 0)
			(type solid)
		)
		(fill yes)
		(layer "F.Cu")
		(net "M_E_CPU0_SB_DQ<27>")
	)
	(gr_poly
		(pts
			(xy 390.08558 -224.412556) (xy 390.03478 -224.412556) (xy 389.93318 -224.448878) (xy 389.93318 -224.639378)
			(xy 390.03478 -224.675446) (xy 390.08558 -224.675446)
		)
		(stroke
			(width 0)
			(type solid)
		)
		(fill yes)
		(layer "F.Cu")
		(net "M_E_CPU0_SB_DQ<27>")
	)
	(gr_poly
		(pts
			(xy 390.08558 -223.815656) (xy 390.03478 -223.815656) (xy 389.93318 -223.851978) (xy 389.93318 -224.042478)
			(xy 390.03478 -224.078546) (xy 390.08558 -224.078546)
		)
		(stroke
			(width 0)
			(type solid)
		)
		(fill yes)
		(layer "F.Cu")
		(net "M_E_CPU0_SB_DQ<27>")
	)
	(gr_poly
		(pts
			(xy 390.08558 -223.218756) (xy 390.03478 -223.218756) (xy 389.93318 -223.255078) (xy 389.93318 -223.445578)
			(xy 390.03478 -223.481646) (xy 390.08558 -223.481646)
		)
		(stroke
			(width 0)
			(type solid)
		)
		(fill yes)
		(layer "F.Cu")
		(net "M_E_CPU0_SB_DQ<27>")
	)
	(gr_poly
		(pts
			(xy 390.08558 -222.621856) (xy 390.03478 -222.621856) (xy 389.93318 -222.658178) (xy 389.93318 -222.848678)
			(xy 390.03478 -222.884746) (xy 390.08558 -222.884746)
		)
		(stroke
			(width 0)
			(type solid)
		)
		(fill yes)
		(layer "F.Cu")
		(net "M_E_CPU0_SB_DQ<27>")
	)
	(gr_poly
		(pts
			(xy 390.08558 -222.024956) (xy 390.03478 -222.024956) (xy 389.93318 -222.061278) (xy 389.93318 -222.251778)
			(xy 390.03478 -222.287846) (xy 390.08558 -222.287846)
		)
		(stroke
			(width 0)
			(type solid)
		)
		(fill yes)
		(layer "F.Cu")
		(net "M_E_CPU0_SB_DQ<27>")
	)
	(gr_poly
		(pts
			(xy 390.08558 -221.428056) (xy 390.03478 -221.428056) (xy 389.93318 -221.464378) (xy 389.93318 -221.654878)
			(xy 390.03478 -221.690946) (xy 390.08558 -221.690946)
		)
		(stroke
			(width 0)
			(type solid)
		)
		(fill yes)
		(layer "F.Cu")
		(net "M_E_CPU0_SB_DQ<27>")
	)
	(gr_poly
		(pts
			(xy 390.08558 -220.831156) (xy 390.03478 -220.831156) (xy 389.93318 -220.867478) (xy 389.93318 -221.057978)
			(xy 390.03478 -221.094046) (xy 390.08558 -221.094046)
		)
		(stroke
			(width 0)
			(type solid)
		)
		(fill yes)
		(layer "F.Cu")
		(net "M_E_CPU0_SB_DQ<27>")
	)
	(gr_poly
		(pts
			(xy 390.08558 -220.234256) (xy 390.03478 -220.234256) (xy 389.93318 -220.270578) (xy 389.93318 -220.461078)
			(xy 390.03478 -220.497146) (xy 390.08558 -220.497146)
		)
		(stroke
			(width 0)
			(type solid)
		)
		(fill yes)
		(layer "F.Cu")
		(net "M_E_CPU0_SB_DQ<27>")
	)
	(gr_poly
		(pts
			(xy 390.08558 -219.637356) (xy 390.03478 -219.637356) (xy 389.93318 -219.673678) (xy 389.93318 -219.864178)
			(xy 390.03478 -219.900246) (xy 390.08558 -219.900246)
		)
		(stroke
			(width 0)
			(type solid)
		)
		(fill yes)
		(layer "F.Cu")
		(net "M_E_CPU0_SB_DQ<27>")
	)
	(gr_poly
		(pts
			(xy 390.08558 -219.040456) (xy 390.03478 -219.040456) (xy 389.93318 -219.076778) (xy 389.93318 -219.267278)
			(xy 390.03478 -219.303346) (xy 390.08558 -219.303346)
		)
		(stroke
			(width 0)
			(type solid)
		)
		(fill yes)
		(layer "F.Cu")
		(net "M_E_CPU0_SB_DQ<27>")
	)
	(gr_poly
		(pts
			(xy 390.08558 -218.443556) (xy 390.03478 -218.443556) (xy 389.93318 -218.479878) (xy 389.93318 -218.670378)
			(xy 390.03478 -218.706446) (xy 390.08558 -218.706446)
		)
		(stroke
			(width 0)
			(type solid)
		)
		(fill yes)
		(layer "F.Cu")
		(net "M_E_CPU0_SB_DQ<27>")
	)
	(gr_poly
		(pts
			(xy 390.08558 -217.846656) (xy 390.03478 -217.846656) (xy 389.93318 -217.882978) (xy 389.93318 -218.073478)
			(xy 390.03478 -218.109546) (xy 390.08558 -218.109546)
		)
		(stroke
			(width 0)
			(type solid)
		)
		(fill yes)
		(layer "F.Cu")
		(net "M_E_CPU0_SB_DQ<27>")
	)
	(gr_poly
		(pts
			(xy 390.08558 -217.249756) (xy 390.03478 -217.249756) (xy 389.93318 -217.286078) (xy 389.93318 -217.476578)
			(xy 390.03478 -217.512646) (xy 390.08558 -217.512646)
		)
		(stroke
			(width 0)
			(type solid)
		)
		(fill yes)
		(layer "F.Cu")
		(net "M_E_CPU0_SB_DQ<27>")
	)
	(gr_poly
		(pts
			(xy 390.08558 -216.652856) (xy 390.03478 -216.652856) (xy 389.93318 -216.689178) (xy 389.93318 -216.879678)
			(xy 390.03478 -216.915746) (xy 390.08558 -216.915746)
		)
		(stroke
			(width 0)
			(type solid)
		)
		(fill yes)
		(layer "F.Cu")
		(net "M_E_CPU0_SB_DQ<27>")
	)
	(gr_poly
		(pts
			(xy 390.08558 -216.055956) (xy 390.03478 -216.055956) (xy 389.93318 -216.092278) (xy 389.93318 -216.282778)
			(xy 390.03478 -216.318846) (xy 390.08558 -216.318846)
		)
		(stroke
			(width 0)
			(type solid)
		)
		(fill yes)
		(layer "F.Cu")
		(net "M_E_CPU0_SB_DQ<27>")
	)
	(gr_poly
		(pts
			(xy 390.092184 -263.407652) (xy 390.138412 -263.310116) (xy 390.003792 -263.175496) (xy 389.90651 -263.221724)
			(xy 389.870442 -263.257538) (xy 390.05637 -263.443466)
		)
		(stroke
			(width 0)
			(type solid)
		)
		(fill yes)
		(layer "F.Cu")
		(net "M_E_CPU0_SA_CB<3>")
	)
	(gr_poly
		(pts
			(xy 390.094978 -255.797304) (xy 390.141206 -255.699768) (xy 390.006332 -255.565148) (xy 389.90905 -255.611376)
			(xy 389.872982 -255.64719) (xy 390.05891 -255.833118)
		)
		(stroke
			(width 0)
			(type solid)
		)
		(fill yes)
		(layer "F.Cu")
		(net "M_E_CPU0_SA_CA<2>")
	)
	(gr_poly
		(pts
			(xy 390.104122 -254.943864) (xy 390.15035 -254.846328) (xy 390.015476 -254.711708) (xy 389.918194 -254.757936)
			(xy 389.882126 -254.79375) (xy 390.068054 -254.979678)
		)
		(stroke
			(width 0)
			(type solid)
		)
		(fill yes)
		(layer "F.Cu")
		(net "M_E_CPU0_SA_CA<4>")
	)
	(gr_poly
		(pts
			(xy 390.10717 -266.769088) (xy 390.153398 -266.671806) (xy 390.018778 -266.536932) (xy 389.921242 -266.58316)
			(xy 389.885428 -266.619228) (xy 390.071356 -266.805156)
		)
		(stroke
			(width 0)
			(type solid)
		)
		(fill yes)
		(layer "F.Cu")
		(net "M_E_CPU0_SA_DQ<28>")
	)
	(gr_poly
		(pts
			(xy 390.113774 -243.092224) (xy 390.067546 -242.994688) (xy 390.031478 -242.958874) (xy 389.845804 -243.144548)
			(xy 389.881618 -243.180616) (xy 389.979154 -243.226844)
		)
		(stroke
			(width 0)
			(type solid)
		)
		(fill yes)
		(layer "F.Cu")
		(net "M_E_CPU0_SB_CB<4>")
	)
	(gr_poly
		(pts
			(xy 390.116568 -265.915648) (xy 390.162796 -265.818366) (xy 390.028176 -265.683492) (xy 389.93064 -265.72972)
			(xy 389.894826 -265.765788) (xy 390.080754 -265.951716)
		)
		(stroke
			(width 0)
			(type solid)
		)
		(fill yes)
		(layer "F.Cu")
		(net "M_E_CPU0_SA_DQ<29>")
	)
	(gr_poly
		(pts
			(xy 390.120124 -289.521646) (xy 390.069324 -289.521646) (xy 389.967724 -289.557968) (xy 389.967724 -289.748468)
			(xy 390.069324 -289.784536) (xy 390.120124 -289.784536)
		)
		(stroke
			(width 0)
			(type solid)
		)
		(fill yes)
		(layer "F.Cu")
		(net "M_E_CPU0_SA_DQ<5>")
	)
	(gr_poly
		(pts
			(xy 390.120124 -288.924746) (xy 390.069324 -288.924746) (xy 389.967724 -288.961068) (xy 389.967724 -289.151568)
			(xy 390.069324 -289.187636) (xy 390.120124 -289.187636)
		)
		(stroke
			(width 0)
			(type solid)
		)
		(fill yes)
		(layer "F.Cu")
		(net "M_E_CPU0_SA_DQ<5>")
	)
	(gr_poly
		(pts
			(xy 390.120124 -288.327846) (xy 390.069324 -288.327846) (xy 389.967724 -288.364168) (xy 389.967724 -288.554668)
			(xy 390.069324 -288.590736) (xy 390.120124 -288.590736)
		)
		(stroke
			(width 0)
			(type solid)
		)
		(fill yes)
		(layer "F.Cu")
		(net "M_E_CPU0_SA_DQ<5>")
	)
	(gr_poly
		(pts
			(xy 390.120124 -287.730946) (xy 390.069324 -287.730946) (xy 389.967724 -287.767268) (xy 389.967724 -287.957768)
			(xy 390.069324 -287.993836) (xy 390.120124 -287.993836)
		)
		(stroke
			(width 0)
			(type solid)
		)
		(fill yes)
		(layer "F.Cu")
		(net "M_E_CPU0_SA_DQ<5>")
	)
	(gr_poly
		(pts
			(xy 390.120124 -287.134046) (xy 390.069324 -287.134046) (xy 389.967724 -287.170368) (xy 389.967724 -287.360868)
			(xy 390.069324 -287.396936) (xy 390.120124 -287.396936)
		)
		(stroke
			(width 0)
			(type solid)
		)
		(fill yes)
		(layer "F.Cu")
		(net "M_E_CPU0_SA_DQ<5>")
	)
	(gr_poly
		(pts
			(xy 390.120124 -286.537146) (xy 390.069324 -286.537146) (xy 389.967724 -286.573468) (xy 389.967724 -286.763968)
			(xy 390.069324 -286.800036) (xy 390.120124 -286.800036)
		)
		(stroke
			(width 0)
			(type solid)
		)
		(fill yes)
		(layer "F.Cu")
		(net "M_E_CPU0_SA_DQ<5>")
	)
	(gr_poly
		(pts
			(xy 390.120124 -285.940246) (xy 390.069324 -285.940246) (xy 389.967724 -285.976568) (xy 389.967724 -286.167068)
			(xy 390.069324 -286.203136) (xy 390.120124 -286.203136)
		)
		(stroke
			(width 0)
			(type solid)
		)
		(fill yes)
		(layer "F.Cu")
		(net "M_E_CPU0_SA_DQ<5>")
	)
	(gr_poly
		(pts
			(xy 390.120124 -285.343346) (xy 390.069324 -285.343346) (xy 389.967724 -285.379668) (xy 389.967724 -285.570168)
			(xy 390.069324 -285.606236) (xy 390.120124 -285.606236)
		)
		(stroke
			(width 0)
			(type solid)
		)
		(fill yes)
		(layer "F.Cu")
		(net "M_E_CPU0_SA_DQ<5>")
	)
	(gr_poly
		(pts
			(xy 390.120124 -284.746446) (xy 390.069324 -284.746446) (xy 389.967724 -284.782768) (xy 389.967724 -284.973268)
			(xy 390.069324 -285.009336) (xy 390.120124 -285.009336)
		)
		(stroke
			(width 0)
			(type solid)
		)
		(fill yes)
		(layer "F.Cu")
		(net "M_E_CPU0_SA_DQ<5>")
	)
	(gr_poly
		(pts
			(xy 390.120124 -284.149546) (xy 390.069324 -284.149546) (xy 389.967724 -284.185868) (xy 389.967724 -284.376368)
			(xy 390.069324 -284.412436) (xy 390.120124 -284.412436)
		)
		(stroke
			(width 0)
			(type solid)
		)
		(fill yes)
		(layer "F.Cu")
		(net "M_E_CPU0_SA_DQ<5>")
	)
	(gr_poly
		(pts
			(xy 390.120124 -283.552646) (xy 390.069324 -283.552646) (xy 389.967724 -283.588968) (xy 389.967724 -283.779468)
			(xy 390.069324 -283.815536) (xy 390.120124 -283.815536)
		)
		(stroke
			(width 0)
			(type solid)
		)
		(fill yes)
		(layer "F.Cu")
		(net "M_E_CPU0_SA_DQ<5>")
	)
	(gr_poly
		(pts
			(xy 390.120124 -282.955746) (xy 390.069324 -282.955746) (xy 389.967724 -282.992068) (xy 389.967724 -283.182568)
			(xy 390.069324 -283.218636) (xy 390.120124 -283.218636)
		)
		(stroke
			(width 0)
			(type solid)
		)
		(fill yes)
		(layer "F.Cu")
		(net "M_E_CPU0_SA_DQ<5>")
	)
	(gr_poly
		(pts
			(xy 390.120124 -282.358846) (xy 390.069324 -282.358846) (xy 389.967724 -282.395168) (xy 389.967724 -282.585668)
			(xy 390.069324 -282.621736) (xy 390.120124 -282.621736)
		)
		(stroke
			(width 0)
			(type solid)
		)
		(fill yes)
		(layer "F.Cu")
		(net "M_E_CPU0_SA_DQ<5>")
	)
	(gr_poly
		(pts
			(xy 390.120124 -281.761946) (xy 390.069324 -281.761946) (xy 389.967724 -281.798268) (xy 389.967724 -281.988768)
			(xy 390.069324 -282.024836) (xy 390.120124 -282.024836)
		)
		(stroke
			(width 0)
			(type solid)
		)
		(fill yes)
		(layer "F.Cu")
		(net "M_E_CPU0_SA_DQ<5>")
	)
	(gr_poly
		(pts
			(xy 390.120124 -281.165046) (xy 390.069324 -281.165046) (xy 389.967724 -281.201368) (xy 389.967724 -281.391868)
			(xy 390.069324 -281.427936) (xy 390.120124 -281.427936)
		)
		(stroke
			(width 0)
			(type solid)
		)
		(fill yes)
		(layer "F.Cu")
		(net "M_E_CPU0_SA_DQ<5>")
	)
	(gr_poly
		(pts
			(xy 390.129522 -272.417286) (xy 390.17575 -272.31975) (xy 390.04113 -272.18513) (xy 389.943594 -272.231358)
			(xy 389.90778 -272.267426) (xy 390.093454 -272.4531)
		)
		(stroke
			(width 0)
			(type solid)
		)
		(fill yes)
		(layer "F.Cu")
		(net "M_E_CPU0_SA_DQ<20>")
	)
	(gr_poly
		(pts
			(xy 390.13892 -271.563338) (xy 390.185148 -271.466056) (xy 390.050528 -271.331436) (xy 389.952992 -271.377664)
			(xy 389.917178 -271.413478) (xy 390.103106 -271.599406)
		)
		(stroke
			(width 0)
			(type solid)
		)
		(fill yes)
		(layer "F.Cu")
		(net "M_E_CPU0_SA_DQ<21>")
	)
	(gr_poly
		(pts
			(xy 390.140444 -260.867144) (xy 390.186672 -260.769608) (xy 390.051798 -260.634988) (xy 389.954516 -260.681216)
			(xy 389.918448 -260.71703) (xy 390.104376 -260.902958)
		)
		(stroke
			(width 0)
			(type solid)
		)
		(fill yes)
		(layer "F.Cu")
		(net "M_E_CPU0_SA_CB<6>")
	)
	(gr_poly
		(pts
			(xy 390.147556 -275.604986) (xy 390.183624 -275.569172) (xy 389.997696 -275.383244) (xy 389.961628 -275.419058)
			(xy 389.9154 -275.516594) (xy 390.050274 -275.651214)
		)
		(stroke
			(width 0)
			(type solid)
		)
		(fill yes)
		(layer "F.Cu")
		(net "M_E_CPU0_SA_DQ<18>")
	)
	(gr_poly
		(pts
			(xy 390.14781 -269.86611) (xy 390.194038 -269.768574) (xy 390.059418 -269.633954) (xy 389.962136 -269.680182)
			(xy 389.926068 -269.715996) (xy 390.111996 -269.901924)
		)
		(stroke
			(width 0)
			(type solid)
		)
		(fill yes)
		(layer "F.Cu")
		(net "M_E_CPU0_SA_DQ<26>")
	)
	(gr_poly
		(pts
			(xy 390.149588 -260.013704) (xy 390.195816 -259.916168) (xy 390.061196 -259.781548) (xy 389.96366 -259.827776)
			(xy 389.927846 -259.863844) (xy 390.113774 -260.049772)
		)
		(stroke
			(width 0)
			(type solid)
		)
		(fill yes)
		(layer "F.Cu")
		(net "M_E_CPU0_SA_CB<7>")
	)
	(gr_poly
		(pts
			(xy 390.153144 -229.451408) (xy 390.11733 -229.41534) (xy 390.019794 -229.369112) (xy 389.885174 -229.503732)
			(xy 389.931402 -229.601268) (xy 389.96747 -229.637082)
		)
		(stroke
			(width 0)
			(type solid)
		)
		(fill yes)
		(layer "F.Cu")
		(net "M_E_CPU0_SB_DQ<21>")
	)
	(gr_poly
		(pts
			(xy 390.156954 -269.01267) (xy 390.203182 -268.915134) (xy 390.068562 -268.780514) (xy 389.97128 -268.826742)
			(xy 389.935212 -268.862556) (xy 390.12114 -269.048484)
		)
		(stroke
			(width 0)
			(type solid)
		)
		(fill yes)
		(layer "F.Cu")
		(net "M_E_CPU0_SA_DQ<27>")
	)
	(gr_poly
		(pts
			(xy 390.157208 -274.751292) (xy 390.193022 -274.715478) (xy 390.007094 -274.52955) (xy 389.97128 -274.565364)
			(xy 389.925052 -274.6629) (xy 390.059672 -274.79752)
		)
		(stroke
			(width 0)
			(type solid)
		)
		(fill yes)
		(layer "F.Cu")
		(net "M_E_CPU0_SA_DQ<19>")
	)
	(gr_poly
		(pts
			(xy 390.162542 -230.304594) (xy 390.126474 -230.26878) (xy 390.029192 -230.222552) (xy 389.894318 -230.357172)
			(xy 389.940546 -230.454708) (xy 389.976614 -230.490522)
		)
		(stroke
			(width 0)
			(type solid)
		)
		(fill yes)
		(layer "F.Cu")
		(net "M_E_CPU0_SB_DQ<20>")
	)
	(gr_poly
		(pts
			(xy 390.189212 -232.866184) (xy 390.153398 -232.830116) (xy 390.055862 -232.783888) (xy 389.921242 -232.918508)
			(xy 389.96747 -233.016044) (xy 390.003538 -233.051858)
		)
		(stroke
			(width 0)
			(type solid)
		)
		(fill yes)
		(layer "F.Cu")
		(net "M_E_CPU0_SB_DQ<17>")
	)
	(gr_poly
		(pts
			(xy 390.193784 -279.014682) (xy 390.28624 -278.959056) (xy 390.248902 -278.772366) (xy 390.142222 -278.756872)
			(xy 390.092438 -278.766778) (xy 390.144 -279.024588)
		)
		(stroke
			(width 0)
			(type solid)
		)
		(fill yes)
		(layer "F.Cu")
		(net "M_E_CPU0_SA_DQ<7>")
	)
	(gr_poly
		(pts
			(xy 390.198102 -234.563158) (xy 390.162288 -234.527344) (xy 390.064752 -234.480862) (xy 389.930132 -234.615736)
			(xy 389.97636 -234.713018) (xy 390.012174 -234.749086)
		)
		(stroke
			(width 0)
			(type solid)
		)
		(fill yes)
		(layer "F.Cu")
		(net "M_E_CPU0_SB_DQ<15>")
	)
	(gr_poly
		(pts
			(xy 390.19861 -233.71937) (xy 390.162542 -233.683556) (xy 390.06526 -233.637328) (xy 389.930386 -233.771948)
			(xy 389.976614 -233.869484) (xy 390.012682 -233.905298)
		)
		(stroke
			(width 0)
			(type solid)
		)
		(fill yes)
		(layer "F.Cu")
		(net "M_E_CPU0_SB_DQ<16>")
	)
	(gr_poly
		(pts
			(xy 390.20242 -279.317196) (xy 390.150858 -279.059386) (xy 390.101074 -279.069292) (xy 390.008618 -279.124918)
			(xy 390.045956 -279.311608) (xy 390.152636 -279.327102)
		)
		(stroke
			(width 0)
			(type solid)
		)
		(fill yes)
		(layer "F.Cu")
		(net "M_E_CPU0_SA_DQ<7>")
	)
	(gr_poly
		(pts
			(xy 390.20242 -248.459752) (xy 390.20242 -248.408952) (xy 389.939276 -248.408952) (xy 389.939276 -248.459752)
			(xy 389.975598 -248.561352) (xy 390.166098 -248.561352)
		)
		(stroke
			(width 0)
			(type solid)
		)
		(fill yes)
		(layer "F.Cu")
		(net "M_E_CPU0_SB_CA<2>")
	)
	(gr_poly
		(pts
			(xy 390.20242 -248.154952) (xy 390.20242 -248.104152) (xy 389.939276 -248.104152) (xy 389.939276 -248.154952)
			(xy 389.975598 -248.256552) (xy 390.166098 -248.256552)
		)
		(stroke
			(width 0)
			(type solid)
		)
		(fill yes)
		(layer "F.Cu")
		(net "M_E_CPU0_SB_CA<3>")
	)
	(gr_poly
		(pts
			(xy 390.20242 -247.850152) (xy 390.20242 -247.799352) (xy 389.939276 -247.799352) (xy 389.939276 -247.850152)
			(xy 389.975598 -247.951752) (xy 390.166098 -247.951752)
		)
		(stroke
			(width 0)
			(type solid)
		)
		(fill yes)
		(layer "F.Cu")
		(net "M_E_CPU0_SB_CA<4>")
	)
	(gr_poly
		(pts
			(xy 390.20242 -247.545352) (xy 390.20242 -247.494552) (xy 389.939276 -247.494552) (xy 389.939276 -247.545352)
			(xy 389.975598 -247.646952) (xy 390.166098 -247.646952)
		)
		(stroke
			(width 0)
			(type solid)
		)
		(fill yes)
		(layer "F.Cu")
		(net "M_E_CPU0_SB_CA<5>")
	)
	(gr_poly
		(pts
			(xy 390.20242 -247.240552) (xy 390.20242 -247.189752) (xy 389.939276 -247.189752) (xy 389.939276 -247.240552)
			(xy 389.975598 -247.342152) (xy 390.166098 -247.342152)
		)
		(stroke
			(width 0)
			(type solid)
		)
		(fill yes)
		(layer "F.Cu")
		(net "M_E_CPU0_SB_CA<6>")
	)
	(gr_poly
		(pts
			(xy 390.20242 -246.935752) (xy 390.20242 -246.884952) (xy 389.939276 -246.884952) (xy 389.939276 -246.935752)
			(xy 389.975598 -247.037352) (xy 390.166098 -247.037352)
		)
		(stroke
			(width 0)
			(type solid)
		)
		(fill yes)
		(layer "F.Cu")
		(net "M_E_CPU0_SB_PAR")
	)
	(gr_poly
		(pts
			(xy 390.20242 -246.630952) (xy 390.20242 -246.580152) (xy 389.939276 -246.580152) (xy 389.939276 -246.630952)
			(xy 389.975598 -246.732552) (xy 390.166098 -246.732552)
		)
		(stroke
			(width 0)
			(type solid)
		)
		(fill yes)
		(layer "F.Cu")
		(net "M_E_CPU0_SB_CS_N<0>")
	)
	(gr_poly
		(pts
			(xy 390.20242 -246.326152) (xy 390.20242 -246.275352) (xy 389.939276 -246.275352) (xy 389.939276 -246.326152)
			(xy 389.975598 -246.427752) (xy 390.166098 -246.427752)
		)
		(stroke
			(width 0)
			(type solid)
		)
		(fill yes)
		(layer "F.Cu")
		(net "M_E_CPU0_SB_CS_N<2>")
	)
	(gr_poly
		(pts
			(xy 390.20242 -246.021352) (xy 390.20242 -245.970552) (xy 389.939276 -245.970552) (xy 389.939276 -246.021352)
			(xy 389.975598 -246.122952) (xy 390.166098 -246.122952)
		)
		(stroke
			(width 0)
			(type solid)
		)
		(fill yes)
		(layer "F.Cu")
		(net "M_E_CPU0_SB_CS_N<1>")
	)
	(gr_poly
		(pts
			(xy 390.20242 -245.716552) (xy 390.20242 -245.665752) (xy 389.939276 -245.665752) (xy 389.939276 -245.716552)
			(xy 389.975598 -245.818152) (xy 390.166098 -245.818152)
		)
		(stroke
			(width 0)
			(type solid)
		)
		(fill yes)
		(layer "F.Cu")
		(net "M_E_CPU0_SB_CS_N<3>")
	)
	(gr_poly
		(pts
			(xy 390.20623 -258.640072) (xy 390.242044 -258.604258) (xy 390.056116 -258.41833) (xy 390.020302 -258.454398)
			(xy 389.974074 -258.55168) (xy 390.108694 -258.686554)
		)
		(stroke
			(width 0)
			(type solid)
		)
		(fill yes)
		(layer "F.Cu")
		(net "M_E_CPU0_SA_CS_N<0>")
	)
	(gr_poly
		(pts
			(xy 390.207246 -235.416598) (xy 390.171432 -235.38053) (xy 390.073896 -235.334302) (xy 389.939276 -235.468922)
			(xy 389.985504 -235.566458) (xy 390.021572 -235.602272)
		)
		(stroke
			(width 0)
			(type solid)
		)
		(fill yes)
		(layer "F.Cu")
		(net "M_E_CPU0_SB_DQ<14>")
	)
	(gr_poly
		(pts
			(xy 390.215374 -257.786632) (xy 390.251442 -257.750818) (xy 390.065514 -257.56489) (xy 390.0297 -257.600704)
			(xy 389.983218 -257.69824) (xy 390.118092 -257.83286)
		)
		(stroke
			(width 0)
			(type solid)
		)
		(fill yes)
		(layer "F.Cu")
		(net "M_E_CPU0_SA_CS_N<1>")
	)
	(gr_poly
		(pts
			(xy 390.222232 -264.543794) (xy 390.2583 -264.50798) (xy 390.072372 -264.322052) (xy 390.036304 -264.357866)
			(xy 389.990076 -264.455402) (xy 390.124696 -264.590022)
		)
		(stroke
			(width 0)
			(type solid)
		)
		(fill yes)
		(layer "F.Cu")
		(net "M_E_CPU0_SA_CB<2>")
	)
	(gr_poly
		(pts
			(xy 390.223502 -276.492462) (xy 390.17194 -276.234652) (xy 390.122156 -276.244812) (xy 390.0297 -276.300184)
			(xy 390.067038 -276.486874) (xy 390.173718 -276.502622)
		)
		(stroke
			(width 0)
			(type solid)
		)
		(fill yes)
		(layer "F.Cu")
		(net "M_E_CPU0_SA_DQ<16>")
	)
	(gr_poly
		(pts
			(xy 390.22401 -275.106384) (xy 390.270238 -275.009102) (xy 390.135618 -274.874228) (xy 390.038082 -274.92071)
			(xy 390.002268 -274.956524) (xy 390.188196 -275.142452)
		)
		(stroke
			(width 0)
			(type solid)
		)
		(fill yes)
		(layer "F.Cu")
		(net "M_E_CPU0_SA_DQ<17>")
	)
	(gr_poly
		(pts
			(xy 390.224772 -256.933446) (xy 390.260586 -256.897378) (xy 390.074658 -256.71145) (xy 390.038844 -256.747518)
			(xy 389.992616 -256.8448) (xy 390.127236 -256.979674)
		)
		(stroke
			(width 0)
			(type solid)
		)
		(fill yes)
		(layer "F.Cu")
		(net "M_E_CPU0_SA_CA<0>")
	)
	(gr_poly
		(pts
			(xy 390.230868 -229.158038) (xy 390.18464 -229.060502) (xy 390.148572 -229.024688) (xy 389.962644 -229.210616)
			(xy 389.998712 -229.24643) (xy 390.095994 -229.292658)
		)
		(stroke
			(width 0)
			(type solid)
		)
		(fill yes)
		(layer "F.Cu")
		(net "M_E_CPU0_SB_DQ<23>")
	)
	(gr_poly
		(pts
			(xy 390.231376 -263.690354) (xy 390.267444 -263.65454) (xy 390.081516 -263.468612) (xy 390.045702 -263.504426)
			(xy 389.99922 -263.601962) (xy 390.134094 -263.736582)
		)
		(stroke
			(width 0)
			(type solid)
		)
		(fill yes)
		(layer "F.Cu")
		(net "M_E_CPU0_SA_CB<3>")
	)
	(gr_poly
		(pts
			(xy 390.233916 -256.080006) (xy 390.26973 -256.043938) (xy 390.084056 -255.858264) (xy 390.047988 -255.894078)
			(xy 390.00176 -255.991614) (xy 390.13638 -256.126234)
		)
		(stroke
			(width 0)
			(type solid)
		)
		(fill yes)
		(layer "F.Cu")
		(net "M_E_CPU0_SA_CA<2>")
	)
	(gr_poly
		(pts
			(xy 390.23798 -224.937574) (xy 390.23798 -224.747074) (xy 390.13638 -224.711006) (xy 390.08558 -224.711006)
			(xy 390.08558 -224.973896) (xy 390.13638 -224.973896)
		)
		(stroke
			(width 0)
			(type solid)
		)
		(fill yes)
		(layer "F.Cu")
		(net "M_E_CPU0_SB_DQ<27>")
	)
	(gr_poly
		(pts
			(xy 390.23798 -224.340674) (xy 390.23798 -224.150174) (xy 390.13638 -224.114106) (xy 390.08558 -224.114106)
			(xy 390.08558 -224.376996) (xy 390.13638 -224.376996)
		)
		(stroke
			(width 0)
			(type solid)
		)
		(fill yes)
		(layer "F.Cu")
		(net "M_E_CPU0_SB_DQ<27>")
	)
	(gr_poly
		(pts
			(xy 390.23798 -223.743774) (xy 390.23798 -223.553274) (xy 390.13638 -223.517206) (xy 390.08558 -223.517206)
			(xy 390.08558 -223.780096) (xy 390.13638 -223.780096)
		)
		(stroke
			(width 0)
			(type solid)
		)
		(fill yes)
		(layer "F.Cu")
		(net "M_E_CPU0_SB_DQ<27>")
	)
	(gr_poly
		(pts
			(xy 390.23798 -223.146874) (xy 390.23798 -222.956374) (xy 390.13638 -222.920306) (xy 390.08558 -222.920306)
			(xy 390.08558 -223.183196) (xy 390.13638 -223.183196)
		)
		(stroke
			(width 0)
			(type solid)
		)
		(fill yes)
		(layer "F.Cu")
		(net "M_E_CPU0_SB_DQ<27>")
	)
	(gr_poly
		(pts
			(xy 390.23798 -222.549974) (xy 390.23798 -222.359474) (xy 390.13638 -222.323406) (xy 390.08558 -222.323406)
			(xy 390.08558 -222.586296) (xy 390.13638 -222.586296)
		)
		(stroke
			(width 0)
			(type solid)
		)
		(fill yes)
		(layer "F.Cu")
		(net "M_E_CPU0_SB_DQ<27>")
	)
	(gr_poly
		(pts
			(xy 390.23798 -221.953074) (xy 390.23798 -221.762574) (xy 390.13638 -221.726506) (xy 390.08558 -221.726506)
			(xy 390.08558 -221.989396) (xy 390.13638 -221.989396)
		)
		(stroke
			(width 0)
			(type solid)
		)
		(fill yes)
		(layer "F.Cu")
		(net "M_E_CPU0_SB_DQ<27>")
	)
	(gr_poly
		(pts
			(xy 390.23798 -221.356174) (xy 390.23798 -221.165674) (xy 390.13638 -221.129606) (xy 390.08558 -221.129606)
			(xy 390.08558 -221.392496) (xy 390.13638 -221.392496)
		)
		(stroke
			(width 0)
			(type solid)
		)
		(fill yes)
		(layer "F.Cu")
		(net "M_E_CPU0_SB_DQ<27>")
	)
	(gr_poly
		(pts
			(xy 390.23798 -220.759274) (xy 390.23798 -220.568774) (xy 390.13638 -220.532706) (xy 390.08558 -220.532706)
			(xy 390.08558 -220.795596) (xy 390.13638 -220.795596)
		)
		(stroke
			(width 0)
			(type solid)
		)
		(fill yes)
		(layer "F.Cu")
		(net "M_E_CPU0_SB_DQ<27>")
	)
	(gr_poly
		(pts
			(xy 390.23798 -220.162374) (xy 390.23798 -219.971874) (xy 390.13638 -219.935806) (xy 390.08558 -219.935806)
			(xy 390.08558 -220.198696) (xy 390.13638 -220.198696)
		)
		(stroke
			(width 0)
			(type solid)
		)
		(fill yes)
		(layer "F.Cu")
		(net "M_E_CPU0_SB_DQ<27>")
	)
	(gr_poly
		(pts
			(xy 390.23798 -219.565474) (xy 390.23798 -219.374974) (xy 390.13638 -219.338906) (xy 390.08558 -219.338906)
			(xy 390.08558 -219.601796) (xy 390.13638 -219.601796)
		)
		(stroke
			(width 0)
			(type solid)
		)
		(fill yes)
		(layer "F.Cu")
		(net "M_E_CPU0_SB_DQ<27>")
	)
	(gr_poly
		(pts
			(xy 390.23798 -218.968574) (xy 390.23798 -218.778074) (xy 390.13638 -218.742006) (xy 390.08558 -218.742006)
			(xy 390.08558 -219.004896) (xy 390.13638 -219.004896)
		)
		(stroke
			(width 0)
			(type solid)
		)
		(fill yes)
		(layer "F.Cu")
		(net "M_E_CPU0_SB_DQ<27>")
	)
	(gr_poly
		(pts
			(xy 390.23798 -218.371674) (xy 390.23798 -218.181174) (xy 390.13638 -218.145106) (xy 390.08558 -218.145106)
			(xy 390.08558 -218.407996) (xy 390.13638 -218.407996)
		)
		(stroke
			(width 0)
			(type solid)
		)
		(fill yes)
		(layer "F.Cu")
		(net "M_E_CPU0_SB_DQ<27>")
	)
	(gr_poly
		(pts
			(xy 390.23798 -217.774774) (xy 390.23798 -217.584274) (xy 390.13638 -217.548206) (xy 390.08558 -217.548206)
			(xy 390.08558 -217.811096) (xy 390.13638 -217.811096)
		)
		(stroke
			(width 0)
			(type solid)
		)
		(fill yes)
		(layer "F.Cu")
		(net "M_E_CPU0_SB_DQ<27>")
	)
	(gr_poly
		(pts
			(xy 390.23798 -217.177874) (xy 390.23798 -216.987374) (xy 390.13638 -216.951306) (xy 390.08558 -216.951306)
			(xy 390.08558 -217.214196) (xy 390.13638 -217.214196)
		)
		(stroke
			(width 0)
			(type solid)
		)
		(fill yes)
		(layer "F.Cu")
		(net "M_E_CPU0_SB_DQ<27>")
	)
	(gr_poly
		(pts
			(xy 390.23798 -216.580974) (xy 390.23798 -216.390474) (xy 390.13638 -216.354406) (xy 390.08558 -216.354406)
			(xy 390.08558 -216.617296) (xy 390.13638 -216.617296)
		)
		(stroke
			(width 0)
			(type solid)
		)
		(fill yes)
		(layer "F.Cu")
		(net "M_E_CPU0_SB_DQ<27>")
	)
	(gr_poly
		(pts
			(xy 390.23798 -215.984074) (xy 390.23798 -215.793574) (xy 390.13638 -215.757506) (xy 390.08558 -215.757506)
			(xy 390.08558 -216.020396) (xy 390.13638 -216.020396)
		)
		(stroke
			(width 0)
			(type solid)
		)
		(fill yes)
		(layer "F.Cu")
		(net "M_E_CPU0_SB_DQ<27>")
	)
	(gr_poly
		(pts
			(xy 390.240012 -230.011478) (xy 390.193784 -229.913942) (xy 390.15797 -229.877874) (xy 389.972042 -230.063802)
			(xy 390.007856 -230.09987) (xy 390.105392 -230.146098)
		)
		(stroke
			(width 0)
			(type solid)
		)
		(fill yes)
		(layer "F.Cu")
		(net "M_E_CPU0_SB_DQ<22>")
	)
	(gr_poly
		(pts
			(xy 390.242552 -242.7478) (xy 390.206738 -242.711732) (xy 390.109202 -242.665504) (xy 389.974582 -242.800124)
			(xy 390.02081 -242.89766) (xy 390.056624 -242.933728)
		)
		(stroke
			(width 0)
			(type solid)
		)
		(fill yes)
		(layer "F.Cu")
		(net "M_E_CPU0_SB_CB<4>")
	)
	(gr_poly
		(pts
			(xy 390.243314 -255.22682) (xy 390.279128 -255.190752) (xy 390.0932 -255.004824) (xy 390.057386 -255.040892)
			(xy 390.011158 -255.138174) (xy 390.145778 -255.273048)
		)
		(stroke
			(width 0)
			(type solid)
		)
		(fill yes)
		(layer "F.Cu")
		(net "M_E_CPU0_SA_CA<4>")
	)
	(gr_poly
		(pts
			(xy 390.246362 -267.052044) (xy 390.28243 -267.01623) (xy 390.096502 -266.830302) (xy 390.060434 -266.866116)
			(xy 390.014206 -266.963652) (xy 390.14908 -267.098272)
		)
		(stroke
			(width 0)
			(type solid)
		)
		(fill yes)
		(layer "F.Cu")
		(net "M_E_CPU0_SA_DQ<28>")
	)
	(gr_poly
		(pts
			(xy 390.25576 -266.198604) (xy 390.291574 -266.162536) (xy 390.1059 -265.976862) (xy 390.069832 -266.012676)
			(xy 390.023604 -266.110212) (xy 390.158224 -266.244832)
		)
		(stroke
			(width 0)
			(type solid)
		)
		(fill yes)
		(layer "F.Cu")
		(net "M_E_CPU0_SA_DQ<29>")
	)
	(gr_poly
		(pts
			(xy 390.266936 -232.572814) (xy 390.220708 -232.475278) (xy 390.18464 -232.439464) (xy 389.998712 -232.625392)
			(xy 390.03478 -232.661206) (xy 390.132062 -232.707434)
		)
		(stroke
			(width 0)
			(type solid)
		)
		(fill yes)
		(layer "F.Cu")
		(net "M_E_CPU0_SB_DQ<19>")
	)
	(gr_poly
		(pts
			(xy 390.268714 -272.700242) (xy 390.304528 -272.664174) (xy 390.1186 -272.478246) (xy 390.082786 -272.514314)
			(xy 390.036558 -272.611596) (xy 390.171178 -272.74647)
		)
		(stroke
			(width 0)
			(type solid)
		)
		(fill yes)
		(layer "F.Cu")
		(net "M_E_CPU0_SA_DQ<20>")
	)
	(gr_poly
		(pts
			(xy 390.272524 -290.046918) (xy 390.272524 -289.856418) (xy 390.170924 -289.820096) (xy 390.120124 -289.820096)
			(xy 390.120124 -290.082986) (xy 390.170924 -290.082986)
		)
		(stroke
			(width 0)
			(type solid)
		)
		(fill yes)
		(layer "F.Cu")
		(net "M_E_CPU0_SA_DQ<5>")
	)
	(gr_poly
		(pts
			(xy 390.272524 -289.450018) (xy 390.272524 -289.259518) (xy 390.170924 -289.223196) (xy 390.120124 -289.223196)
			(xy 390.120124 -289.486086) (xy 390.170924 -289.486086)
		)
		(stroke
			(width 0)
			(type solid)
		)
		(fill yes)
		(layer "F.Cu")
		(net "M_E_CPU0_SA_DQ<5>")
	)
	(gr_poly
		(pts
			(xy 390.272524 -288.853118) (xy 390.272524 -288.662618) (xy 390.170924 -288.626296) (xy 390.120124 -288.626296)
			(xy 390.120124 -288.889186) (xy 390.170924 -288.889186)
		)
		(stroke
			(width 0)
			(type solid)
		)
		(fill yes)
		(layer "F.Cu")
		(net "M_E_CPU0_SA_DQ<5>")
	)
	(gr_poly
		(pts
			(xy 390.272524 -288.256218) (xy 390.272524 -288.065718) (xy 390.170924 -288.029396) (xy 390.120124 -288.029396)
			(xy 390.120124 -288.292286) (xy 390.170924 -288.292286)
		)
		(stroke
			(width 0)
			(type solid)
		)
		(fill yes)
		(layer "F.Cu")
		(net "M_E_CPU0_SA_DQ<5>")
	)
	(gr_poly
		(pts
			(xy 390.272524 -287.659318) (xy 390.272524 -287.468818) (xy 390.170924 -287.432496) (xy 390.120124 -287.432496)
			(xy 390.120124 -287.695386) (xy 390.170924 -287.695386)
		)
		(stroke
			(width 0)
			(type solid)
		)
		(fill yes)
		(layer "F.Cu")
		(net "M_E_CPU0_SA_DQ<5>")
	)
	(gr_poly
		(pts
			(xy 390.272524 -287.062418) (xy 390.272524 -286.871918) (xy 390.170924 -286.835596) (xy 390.120124 -286.835596)
			(xy 390.120124 -287.098486) (xy 390.170924 -287.098486)
		)
		(stroke
			(width 0)
			(type solid)
		)
		(fill yes)
		(layer "F.Cu")
		(net "M_E_CPU0_SA_DQ<5>")
	)
	(gr_poly
		(pts
			(xy 390.272524 -286.465518) (xy 390.272524 -286.275018) (xy 390.170924 -286.238696) (xy 390.120124 -286.238696)
			(xy 390.120124 -286.501586) (xy 390.170924 -286.501586)
		)
		(stroke
			(width 0)
			(type solid)
		)
		(fill yes)
		(layer "F.Cu")
		(net "M_E_CPU0_SA_DQ<5>")
	)
	(gr_poly
		(pts
			(xy 390.272524 -285.868618) (xy 390.272524 -285.678118) (xy 390.170924 -285.641796) (xy 390.120124 -285.641796)
			(xy 390.120124 -285.904686) (xy 390.170924 -285.904686)
		)
		(stroke
			(width 0)
			(type solid)
		)
		(fill yes)
		(layer "F.Cu")
		(net "M_E_CPU0_SA_DQ<5>")
	)
	(gr_poly
		(pts
			(xy 390.272524 -285.271718) (xy 390.272524 -285.081218) (xy 390.170924 -285.044896) (xy 390.120124 -285.044896)
			(xy 390.120124 -285.307786) (xy 390.170924 -285.307786)
		)
		(stroke
			(width 0)
			(type solid)
		)
		(fill yes)
		(layer "F.Cu")
		(net "M_E_CPU0_SA_DQ<5>")
	)
	(gr_poly
		(pts
			(xy 390.272524 -284.674818) (xy 390.272524 -284.484318) (xy 390.170924 -284.447996) (xy 390.120124 -284.447996)
			(xy 390.120124 -284.710886) (xy 390.170924 -284.710886)
		)
		(stroke
			(width 0)
			(type solid)
		)
		(fill yes)
		(layer "F.Cu")
		(net "M_E_CPU0_SA_DQ<5>")
	)
	(gr_poly
		(pts
			(xy 390.272524 -284.077918) (xy 390.272524 -283.887418) (xy 390.170924 -283.851096) (xy 390.120124 -283.851096)
			(xy 390.120124 -284.113986) (xy 390.170924 -284.113986)
		)
		(stroke
			(width 0)
			(type solid)
		)
		(fill yes)
		(layer "F.Cu")
		(net "M_E_CPU0_SA_DQ<5>")
	)
	(gr_poly
		(pts
			(xy 390.272524 -283.481018) (xy 390.272524 -283.290518) (xy 390.170924 -283.254196) (xy 390.120124 -283.254196)
			(xy 390.120124 -283.517086) (xy 390.170924 -283.517086)
		)
		(stroke
			(width 0)
			(type solid)
		)
		(fill yes)
		(layer "F.Cu")
		(net "M_E_CPU0_SA_DQ<5>")
	)
	(gr_poly
		(pts
			(xy 390.272524 -282.884118) (xy 390.272524 -282.693618) (xy 390.170924 -282.657296) (xy 390.120124 -282.657296)
			(xy 390.120124 -282.920186) (xy 390.170924 -282.920186)
		)
		(stroke
			(width 0)
			(type solid)
		)
		(fill yes)
		(layer "F.Cu")
		(net "M_E_CPU0_SA_DQ<5>")
	)
	(gr_poly
		(pts
			(xy 390.272524 -282.287218) (xy 390.272524 -282.096718) (xy 390.170924 -282.060396) (xy 390.120124 -282.060396)
			(xy 390.120124 -282.323286) (xy 390.170924 -282.323286)
		)
		(stroke
			(width 0)
			(type solid)
		)
		(fill yes)
		(layer "F.Cu")
		(net "M_E_CPU0_SA_DQ<5>")
	)
	(gr_poly
		(pts
			(xy 390.272524 -281.690318) (xy 390.272524 -281.499818) (xy 390.170924 -281.463496) (xy 390.120124 -281.463496)
			(xy 390.120124 -281.726386) (xy 390.170924 -281.726386)
		)
		(stroke
			(width 0)
			(type solid)
		)
		(fill yes)
		(layer "F.Cu")
		(net "M_E_CPU0_SA_DQ<5>")
	)
	(gr_poly
		(pts
			(xy 390.272524 -281.093418) (xy 390.272524 -280.902918) (xy 390.170924 -280.866596) (xy 390.120124 -280.866596)
			(xy 390.120124 -281.129486) (xy 390.170924 -281.129486)
		)
		(stroke
			(width 0)
			(type solid)
		)
		(fill yes)
		(layer "F.Cu")
		(net "M_E_CPU0_SA_DQ<5>")
	)
	(gr_poly
		(pts
			(xy 390.27608 -233.426) (xy 390.229852 -233.328718) (xy 390.194038 -233.29265) (xy 390.00811 -233.478578)
			(xy 390.043924 -233.514646) (xy 390.14146 -233.560874)
		)
		(stroke
			(width 0)
			(type solid)
		)
		(fill yes)
		(layer "F.Cu")
		(net "M_E_CPU0_SB_DQ<18>")
	)
	(gr_poly
		(pts
			(xy 390.278112 -271.846294) (xy 390.31418 -271.81048) (xy 390.128252 -271.624552) (xy 390.092184 -271.660366)
			(xy 390.045956 -271.757902) (xy 390.18083 -271.892522)
		)
		(stroke
			(width 0)
			(type solid)
		)
		(fill yes)
		(layer "F.Cu")
		(net "M_E_CPU0_SA_DQ<21>")
	)
	(gr_poly
		(pts
			(xy 390.279636 -261.149846) (xy 390.31545 -261.114032) (xy 390.129522 -260.928104) (xy 390.093708 -260.964172)
			(xy 390.04748 -261.061454) (xy 390.1821 -261.196328)
		)
		(stroke
			(width 0)
			(type solid)
		)
		(fill yes)
		(layer "F.Cu")
		(net "M_E_CPU0_SA_CB<6>")
	)
	(gr_poly
		(pts
			(xy 390.282684 -258.14147) (xy 390.328912 -258.044188) (xy 390.194292 -257.909314) (xy 390.096756 -257.955542)
			(xy 390.060942 -257.99161) (xy 390.24687 -258.177538)
		)
		(stroke
			(width 0)
			(type solid)
		)
		(fill yes)
		(layer "F.Cu")
		(net "M_E_CPU0_SA_CS_N<2>")
	)
	(gr_poly
		(pts
			(xy 390.28497 -235.123228) (xy 390.238742 -235.025692) (xy 390.202674 -234.989878) (xy 390.016746 -235.175806)
			(xy 390.052814 -235.21162) (xy 390.150096 -235.257848)
		)
		(stroke
			(width 0)
			(type solid)
		)
		(fill yes)
		(layer "F.Cu")
		(net "M_E_CPU0_SB_DQ<13>")
	)
	(gr_poly
		(pts
			(xy 390.287002 -270.148812) (xy 390.32307 -270.112998) (xy 390.137142 -269.92707) (xy 390.101328 -269.962884)
			(xy 390.054846 -270.06042) (xy 390.18972 -270.19504)
		)
		(stroke
			(width 0)
			(type solid)
		)
		(fill yes)
		(layer "F.Cu")
		(net "M_E_CPU0_SA_DQ<26>")
	)
	(gr_poly
		(pts
			(xy 390.28878 -260.29666) (xy 390.324594 -260.260592) (xy 390.13892 -260.074918) (xy 390.102852 -260.110732)
			(xy 390.056624 -260.208268) (xy 390.191244 -260.342888)
		)
		(stroke
			(width 0)
			(type solid)
		)
		(fill yes)
		(layer "F.Cu")
		(net "M_E_CPU0_SA_CB<7>")
	)
	(gr_poly
		(pts
			(xy 390.289542 -264.898632) (xy 390.33577 -264.801096) (xy 390.20115 -264.666476) (xy 390.103614 -264.712704)
			(xy 390.0678 -264.748772) (xy 390.253474 -264.934446)
		)
		(stroke
			(width 0)
			(type solid)
		)
		(fill yes)
		(layer "F.Cu")
		(net "M_E_CPU0_SA_CB<0>")
	)
	(gr_poly
		(pts
			(xy 390.291828 -257.288284) (xy 390.338056 -257.190748) (xy 390.203436 -257.056128) (xy 390.106154 -257.102356)
			(xy 390.070086 -257.13817) (xy 390.256014 -257.324098)
		)
		(stroke
			(width 0)
			(type solid)
		)
		(fill yes)
		(layer "F.Cu")
		(net "M_E_CPU0_SA_CS_N<3>")
	)
	(gr_poly
		(pts
			(xy 390.296146 -269.295372) (xy 390.332214 -269.259558) (xy 390.146286 -269.07363) (xy 390.110472 -269.109444)
			(xy 390.06399 -269.20698) (xy 390.198864 -269.3416)
		)
		(stroke
			(width 0)
			(type solid)
		)
		(fill yes)
		(layer "F.Cu")
		(net "M_E_CPU0_SA_DQ<27>")
	)
	(gr_poly
		(pts
			(xy 390.298686 -264.045192) (xy 390.344914 -263.94791) (xy 390.210294 -263.813036) (xy 390.112758 -263.859264)
			(xy 390.076944 -263.895332) (xy 390.262872 -264.08126)
		)
		(stroke
			(width 0)
			(type solid)
		)
		(fill yes)
		(layer "F.Cu")
		(net "M_E_CPU0_SA_CB<1>")
	)
	(gr_poly
		(pts
			(xy 390.301226 -256.434844) (xy 390.347454 -256.337308) (xy 390.21258 -256.202688) (xy 390.115298 -256.248916)
			(xy 390.07923 -256.28473) (xy 390.265158 -256.470658)
		)
		(stroke
			(width 0)
			(type solid)
		)
		(fill yes)
		(layer "F.Cu")
		(net "M_E_CPU0_SA_CA<1>")
	)
	(gr_poly
		(pts
			(xy 390.30148 -239.95634) (xy 390.30148 -239.90554) (xy 390.03859 -239.90554) (xy 390.03859 -239.95634)
			(xy 390.074912 -240.05794) (xy 390.265412 -240.05794)
		)
		(stroke
			(width 0)
			(type solid)
		)
		(fill yes)
		(layer "F.Cu")
		(net "M_E_CPU0_SB_CB<2>")
	)
	(gr_poly
		(pts
			(xy 390.30148 -239.65154) (xy 390.30148 -239.60074) (xy 390.03859 -239.60074) (xy 390.03859 -239.65154)
			(xy 390.074912 -239.75314) (xy 390.265412 -239.75314)
		)
		(stroke
			(width 0)
			(type solid)
		)
		(fill yes)
		(layer "F.Cu")
		(net "M_E_CPU0_SB_CB<1>")
	)
	(gr_poly
		(pts
			(xy 390.30148 -239.34674) (xy 390.30148 -239.29594) (xy 390.03859 -239.29594) (xy 390.03859 -239.34674)
			(xy 390.074912 -239.44834) (xy 390.265412 -239.44834)
		)
		(stroke
			(width 0)
			(type solid)
		)
		(fill yes)
		(layer "F.Cu")
		(net "M_E_CPU0_SB_CB<3>")
	)
	(gr_poly
		(pts
			(xy 390.310624 -255.581658) (xy 390.356852 -255.484122) (xy 390.221978 -255.349502) (xy 390.124696 -255.39573)
			(xy 390.088628 -255.431544) (xy 390.274556 -255.617472)
		)
		(stroke
			(width 0)
			(type solid)
		)
		(fill yes)
		(layer "F.Cu")
		(net "M_E_CPU0_SA_CA<3>")
	)
	(gr_poly
		(pts
			(xy 390.310878 -279.599898) (xy 390.403334 -279.544526) (xy 390.365996 -279.357582) (xy 390.259316 -279.342088)
			(xy 390.209532 -279.351994) (xy 390.261094 -279.609804)
		)
		(stroke
			(width 0)
			(type solid)
		)
		(fill yes)
		(layer "F.Cu")
		(net "M_E_CPU0_SA_DQ<7>")
	)
	(gr_poly
		(pts
			(xy 390.319768 -279.902412) (xy 390.267952 -279.644602) (xy 390.218168 -279.654762) (xy 390.125712 -279.710134)
			(xy 390.16305 -279.896824) (xy 390.26973 -279.912572)
		)
		(stroke
			(width 0)
			(type solid)
		)
		(fill yes)
		(layer "F.Cu")
		(net "M_E_CPU0_SA_DQ<7>")
	)
	(gr_poly
		(pts
			(xy 390.319768 -254.728218) (xy 390.365996 -254.630936) (xy 390.231376 -254.496062) (xy 390.13384 -254.54229)
			(xy 390.098026 -254.578358) (xy 390.283954 -254.764286)
		)
		(stroke
			(width 0)
			(type solid)
		)
		(fill yes)
		(layer "F.Cu")
		(net "M_E_CPU0_SA_CA<5>")
	)
	(gr_poly
		(pts
			(xy 390.322816 -266.553442) (xy 390.369044 -266.45616) (xy 390.234424 -266.321286) (xy 390.136888 -266.367514)
			(xy 390.101074 -266.403582) (xy 390.287002 -266.58951)
		)
		(stroke
			(width 0)
			(type solid)
		)
		(fill yes)
		(layer "F.Cu")
		(net "M_E_CPU0_SA_DQ<30>")
	)
	(gr_poly
		(pts
			(xy 390.33196 -276.775164) (xy 390.424416 -276.719792) (xy 390.387078 -276.533102) (xy 390.280398 -276.517354)
			(xy 390.23036 -276.527514) (xy 390.281922 -276.785324)
		)
		(stroke
			(width 0)
			(type solid)
		)
		(fill yes)
		(layer "F.Cu")
		(net "M_E_CPU0_SA_DQ<16>")
	)
	(gr_poly
		(pts
			(xy 390.332214 -265.700002) (xy 390.378696 -265.602466) (xy 390.243822 -265.467846) (xy 390.14654 -265.514074)
			(xy 390.110472 -265.549888) (xy 390.2964 -265.735816)
		)
		(stroke
			(width 0)
			(type solid)
		)
		(fill yes)
		(layer "F.Cu")
		(net "M_E_CPU0_SA_DQ<31>")
	)
	(gr_poly
		(pts
			(xy 390.340596 -277.077932) (xy 390.289034 -276.820122) (xy 390.238996 -276.830028) (xy 390.14654 -276.8854)
			(xy 390.183878 -277.072344) (xy 390.290558 -277.087838)
		)
		(stroke
			(width 0)
			(type solid)
		)
		(fill yes)
		(layer "F.Cu")
		(net "M_E_CPU0_SA_DQ<16>")
	)
	(gr_poly
		(pts
			(xy 390.345422 -272.201132) (xy 390.39165 -272.10385) (xy 390.25703 -271.968976) (xy 390.159494 -272.015204)
			(xy 390.12368 -272.051272) (xy 390.309608 -272.2372)
		)
		(stroke
			(width 0)
			(type solid)
		)
		(fill yes)
		(layer "F.Cu")
		(net "M_E_CPU0_SA_DQ<22>")
	)
	(gr_poly
		(pts
			(xy 390.346692 -261.504684) (xy 390.39292 -261.407402) (xy 390.2583 -261.272782) (xy 390.160764 -261.31901)
			(xy 390.12495 -261.354824) (xy 390.310878 -261.540752)
		)
		(stroke
			(width 0)
			(type solid)
		)
		(fill yes)
		(layer "F.Cu")
		(net "M_E_CPU0_SA_CB<4>")
	)
	(gr_poly
		(pts
			(xy 390.349232 -238.787686) (xy 390.349232 -238.736886) (xy 390.086342 -238.736886) (xy 390.086342 -238.787686)
			(xy 390.122664 -238.889286) (xy 390.313164 -238.889286)
		)
		(stroke
			(width 0)
			(type solid)
		)
		(fill yes)
		(layer "F.Cu")
		(net "M_E_CPU0_SB_DQ<8>")
	)
	(gr_poly
		(pts
			(xy 390.349232 -238.482886) (xy 390.349232 -238.432086) (xy 390.086342 -238.432086) (xy 390.086342 -238.482886)
			(xy 390.122664 -238.584486) (xy 390.313164 -238.584486)
		)
		(stroke
			(width 0)
			(type solid)
		)
		(fill yes)
		(layer "F.Cu")
		(net "M_E_CPU0_SB_DQ<10>")
	)
	(gr_poly
		(pts
			(xy 390.349232 -238.178086) (xy 390.349232 -238.127286) (xy 390.086342 -238.127286) (xy 390.086342 -238.178086)
			(xy 390.122664 -238.279686) (xy 390.313164 -238.279686)
		)
		(stroke
			(width 0)
			(type solid)
		)
		(fill yes)
		(layer "F.Cu")
		(net "M_E_CPU0_SB_DQ<9>")
	)
	(gr_poly
		(pts
			(xy 390.354312 -270.50365) (xy 390.40054 -270.406368) (xy 390.26592 -270.271494) (xy 390.168384 -270.317976)
			(xy 390.13257 -270.35379) (xy 390.318498 -270.539718)
		)
		(stroke
			(width 0)
			(type solid)
		)
		(fill yes)
		(layer "F.Cu")
		(net "M_E_CPU0_SA_DQ<24>")
	)
	(gr_poly
		(pts
			(xy 390.35482 -271.347692) (xy 390.401048 -271.250156) (xy 390.266174 -271.115536) (xy 390.168892 -271.161764)
			(xy 390.132824 -271.197578) (xy 390.318752 -271.383506)
		)
		(stroke
			(width 0)
			(type solid)
		)
		(fill yes)
		(layer "F.Cu")
		(net "M_E_CPU0_SA_DQ<23>")
	)
	(gr_poly
		(pts
			(xy 390.35609 -260.651498) (xy 390.402318 -260.553962) (xy 390.267444 -260.419342) (xy 390.170162 -260.46557)
			(xy 390.134094 -260.501384) (xy 390.320022 -260.687312)
		)
		(stroke
			(width 0)
			(type solid)
		)
		(fill yes)
		(layer "F.Cu")
		(net "M_E_CPU0_SA_CB<5>")
	)
	(gr_poly
		(pts
			(xy 390.363202 -275.38934) (xy 390.39927 -275.353526) (xy 390.213342 -275.167598) (xy 390.177274 -275.203412)
			(xy 390.131046 -275.300948) (xy 390.26592 -275.435568)
		)
		(stroke
			(width 0)
			(type solid)
		)
		(fill yes)
		(layer "F.Cu")
		(net "M_E_CPU0_SA_DQ<17>")
	)
	(gr_poly
		(pts
			(xy 390.363456 -269.65021) (xy 390.409684 -269.552928) (xy 390.275064 -269.418054) (xy 390.177528 -269.464536)
			(xy 390.141714 -269.50035) (xy 390.327642 -269.686278)
		)
		(stroke
			(width 0)
			(type solid)
		)
		(fill yes)
		(layer "F.Cu")
		(net "M_E_CPU0_SA_DQ<25>")
	)
	(gr_poly
		(pts
			(xy 390.36879 -229.667054) (xy 390.332976 -229.630986) (xy 390.23544 -229.584758) (xy 390.10082 -229.719378)
			(xy 390.147048 -229.816914) (xy 390.183116 -229.852728)
		)
		(stroke
			(width 0)
			(type solid)
		)
		(fill yes)
		(layer "F.Cu")
		(net "M_E_CPU0_SB_DQ<22>")
	)
	(gr_poly
		(pts
			(xy 390.39038 -225.009456) (xy 390.33958 -225.009456) (xy 390.23798 -225.045778) (xy 390.23798 -225.236278)
			(xy 390.33958 -225.272346) (xy 390.39038 -225.272346)
		)
		(stroke
			(width 0)
			(type solid)
		)
		(fill yes)
		(layer "F.Cu")
		(net "M_E_CPU0_SB_DQ<25>")
	)
	(gr_poly
		(pts
			(xy 390.39038 -224.412556) (xy 390.33958 -224.412556) (xy 390.23798 -224.448878) (xy 390.23798 -224.639378)
			(xy 390.33958 -224.675446) (xy 390.39038 -224.675446)
		)
		(stroke
			(width 0)
			(type solid)
		)
		(fill yes)
		(layer "F.Cu")
		(net "M_E_CPU0_SB_DQ<25>")
	)
	(gr_poly
		(pts
			(xy 390.39038 -223.815656) (xy 390.33958 -223.815656) (xy 390.23798 -223.851978) (xy 390.23798 -224.042478)
			(xy 390.33958 -224.078546) (xy 390.39038 -224.078546)
		)
		(stroke
			(width 0)
			(type solid)
		)
		(fill yes)
		(layer "F.Cu")
		(net "M_E_CPU0_SB_DQ<25>")
	)
	(gr_poly
		(pts
			(xy 390.39038 -223.218756) (xy 390.33958 -223.218756) (xy 390.23798 -223.255078) (xy 390.23798 -223.445578)
			(xy 390.33958 -223.481646) (xy 390.39038 -223.481646)
		)
		(stroke
			(width 0)
			(type solid)
		)
		(fill yes)
		(layer "F.Cu")
		(net "M_E_CPU0_SB_DQ<25>")
	)
	(gr_poly
		(pts
			(xy 390.39038 -222.621856) (xy 390.33958 -222.621856) (xy 390.23798 -222.658178) (xy 390.23798 -222.848678)
			(xy 390.33958 -222.884746) (xy 390.39038 -222.884746)
		)
		(stroke
			(width 0)
			(type solid)
		)
		(fill yes)
		(layer "F.Cu")
		(net "M_E_CPU0_SB_DQ<25>")
	)
	(gr_poly
		(pts
			(xy 390.39038 -222.024956) (xy 390.33958 -222.024956) (xy 390.23798 -222.061278) (xy 390.23798 -222.251778)
			(xy 390.33958 -222.287846) (xy 390.39038 -222.287846)
		)
		(stroke
			(width 0)
			(type solid)
		)
		(fill yes)
		(layer "F.Cu")
		(net "M_E_CPU0_SB_DQ<25>")
	)
	(gr_poly
		(pts
			(xy 390.39038 -221.428056) (xy 390.33958 -221.428056) (xy 390.23798 -221.464378) (xy 390.23798 -221.654878)
			(xy 390.33958 -221.690946) (xy 390.39038 -221.690946)
		)
		(stroke
			(width 0)
			(type solid)
		)
		(fill yes)
		(layer "F.Cu")
		(net "M_E_CPU0_SB_DQ<25>")
	)
	(gr_poly
		(pts
			(xy 390.39038 -220.831156) (xy 390.33958 -220.831156) (xy 390.23798 -220.867478) (xy 390.23798 -221.057978)
			(xy 390.33958 -221.094046) (xy 390.39038 -221.094046)
		)
		(stroke
			(width 0)
			(type solid)
		)
		(fill yes)
		(layer "F.Cu")
		(net "M_E_CPU0_SB_DQ<25>")
	)
	(gr_poly
		(pts
			(xy 390.39038 -220.234256) (xy 390.33958 -220.234256) (xy 390.23798 -220.270578) (xy 390.23798 -220.461078)
			(xy 390.33958 -220.497146) (xy 390.39038 -220.497146)
		)
		(stroke
			(width 0)
			(type solid)
		)
		(fill yes)
		(layer "F.Cu")
		(net "M_E_CPU0_SB_DQ<25>")
	)
	(gr_poly
		(pts
			(xy 390.39038 -219.637356) (xy 390.33958 -219.637356) (xy 390.23798 -219.673678) (xy 390.23798 -219.864178)
			(xy 390.33958 -219.900246) (xy 390.39038 -219.900246)
		)
		(stroke
			(width 0)
			(type solid)
		)
		(fill yes)
		(layer "F.Cu")
		(net "M_E_CPU0_SB_DQ<25>")
	)
	(gr_poly
		(pts
			(xy 390.39038 -219.040456) (xy 390.33958 -219.040456) (xy 390.23798 -219.076778) (xy 390.23798 -219.267278)
			(xy 390.33958 -219.303346) (xy 390.39038 -219.303346)
		)
		(stroke
			(width 0)
			(type solid)
		)
		(fill yes)
		(layer "F.Cu")
		(net "M_E_CPU0_SB_DQ<25>")
	)
	(gr_poly
		(pts
			(xy 390.39038 -218.443556) (xy 390.33958 -218.443556) (xy 390.23798 -218.479878) (xy 390.23798 -218.670378)
			(xy 390.33958 -218.706446) (xy 390.39038 -218.706446)
		)
		(stroke
			(width 0)
			(type solid)
		)
		(fill yes)
		(layer "F.Cu")
		(net "M_E_CPU0_SB_DQ<25>")
	)
	(gr_poly
		(pts
			(xy 390.39038 -217.846656) (xy 390.33958 -217.846656) (xy 390.23798 -217.882978) (xy 390.23798 -218.073478)
			(xy 390.33958 -218.109546) (xy 390.39038 -218.109546)
		)
		(stroke
			(width 0)
			(type solid)
		)
		(fill yes)
		(layer "F.Cu")
		(net "M_E_CPU0_SB_DQ<25>")
	)
	(gr_poly
		(pts
			(xy 390.39038 -217.249756) (xy 390.33958 -217.249756) (xy 390.23798 -217.286078) (xy 390.23798 -217.476578)
			(xy 390.33958 -217.512646) (xy 390.39038 -217.512646)
		)
		(stroke
			(width 0)
			(type solid)
		)
		(fill yes)
		(layer "F.Cu")
		(net "M_E_CPU0_SB_DQ<25>")
	)
	(gr_poly
		(pts
			(xy 390.39038 -216.652856) (xy 390.33958 -216.652856) (xy 390.23798 -216.689178) (xy 390.23798 -216.879678)
			(xy 390.33958 -216.915746) (xy 390.39038 -216.915746)
		)
		(stroke
			(width 0)
			(type solid)
		)
		(fill yes)
		(layer "F.Cu")
		(net "M_E_CPU0_SB_DQ<25>")
	)
	(gr_poly
		(pts
			(xy 390.39038 -216.055956) (xy 390.33958 -216.055956) (xy 390.23798 -216.092278) (xy 390.23798 -216.282778)
			(xy 390.33958 -216.318846) (xy 390.39038 -216.318846)
		)
		(stroke
			(width 0)
			(type solid)
		)
		(fill yes)
		(layer "F.Cu")
		(net "M_E_CPU0_SB_DQ<25>")
	)
	(gr_poly
		(pts
			(xy 390.395714 -232.22839) (xy 390.3599 -232.192322) (xy 390.262364 -232.146094) (xy 390.127744 -232.280968)
			(xy 390.173972 -232.37825) (xy 390.209786 -232.414318)
		)
		(stroke
			(width 0)
			(type solid)
		)
		(fill yes)
		(layer "F.Cu")
		(net "M_E_CPU0_SB_DQ<19>")
	)
	(gr_poly
		(pts
			(xy 390.404858 -233.08183) (xy 390.369044 -233.045762) (xy 390.271508 -232.999534) (xy 390.136888 -233.134154)
			(xy 390.183116 -233.23169) (xy 390.219184 -233.267504)
		)
		(stroke
			(width 0)
			(type solid)
		)
		(fill yes)
		(layer "F.Cu")
		(net "M_E_CPU0_SB_DQ<18>")
	)
	(gr_poly
		(pts
			(xy 390.413748 -234.778804) (xy 390.377934 -234.74299) (xy 390.280398 -234.696508) (xy 390.145778 -234.831382)
			(xy 390.192006 -234.928664) (xy 390.22782 -234.964732)
		)
		(stroke
			(width 0)
			(type solid)
		)
		(fill yes)
		(layer "F.Cu")
		(net "M_E_CPU0_SB_DQ<13>")
	)
	(gr_poly
		(pts
			(xy 390.421876 -258.424426) (xy 390.457944 -258.388612) (xy 390.272016 -258.202684) (xy 390.235948 -258.238498)
			(xy 390.18972 -258.336034) (xy 390.324594 -258.470654)
		)
		(stroke
			(width 0)
			(type solid)
		)
		(fill yes)
		(layer "F.Cu")
		(net "M_E_CPU0_SA_CS_N<2>")
	)
	(gr_poly
		(pts
			(xy 390.422892 -235.632244) (xy 390.387078 -235.596176) (xy 390.289542 -235.549948) (xy 390.154922 -235.684568)
			(xy 390.20115 -235.782104) (xy 390.237218 -235.817918)
		)
		(stroke
			(width 0)
			(type solid)
		)
		(fill yes)
		(layer "F.Cu")
		(net "M_E_CPU0_SB_DQ<12>")
	)
	(gr_poly
		(pts
			(xy 390.424924 -289.521646) (xy 390.374124 -289.521646) (xy 390.272524 -289.557968) (xy 390.272524 -289.748468)
			(xy 390.374124 -289.784536) (xy 390.424924 -289.784536)
		)
		(stroke
			(width 0)
			(type solid)
		)
		(fill yes)
		(layer "F.Cu")
		(net "M_E_CPU0_SA_DQ<7>")
	)
	(gr_poly
		(pts
			(xy 390.424924 -288.924746) (xy 390.374124 -288.924746) (xy 390.272524 -288.961068) (xy 390.272524 -289.151568)
			(xy 390.374124 -289.187636) (xy 390.424924 -289.187636)
		)
		(stroke
			(width 0)
			(type solid)
		)
		(fill yes)
		(layer "F.Cu")
		(net "M_E_CPU0_SA_DQ<7>")
	)
	(gr_poly
		(pts
			(xy 390.424924 -288.327846) (xy 390.374124 -288.327846) (xy 390.272524 -288.364168) (xy 390.272524 -288.554668)
			(xy 390.374124 -288.590736) (xy 390.424924 -288.590736)
		)
		(stroke
			(width 0)
			(type solid)
		)
		(fill yes)
		(layer "F.Cu")
		(net "M_E_CPU0_SA_DQ<7>")
	)
	(gr_poly
		(pts
			(xy 390.424924 -287.730946) (xy 390.374124 -287.730946) (xy 390.272524 -287.767268) (xy 390.272524 -287.957768)
			(xy 390.374124 -287.993836) (xy 390.424924 -287.993836)
		)
		(stroke
			(width 0)
			(type solid)
		)
		(fill yes)
		(layer "F.Cu")
		(net "M_E_CPU0_SA_DQ<7>")
	)
	(gr_poly
		(pts
			(xy 390.424924 -287.134046) (xy 390.374124 -287.134046) (xy 390.272524 -287.170368) (xy 390.272524 -287.360868)
			(xy 390.374124 -287.396936) (xy 390.424924 -287.396936)
		)
		(stroke
			(width 0)
			(type solid)
		)
		(fill yes)
		(layer "F.Cu")
		(net "M_E_CPU0_SA_DQ<7>")
	)
	(gr_poly
		(pts
			(xy 390.424924 -286.537146) (xy 390.374124 -286.537146) (xy 390.272524 -286.573468) (xy 390.272524 -286.763968)
			(xy 390.374124 -286.800036) (xy 390.424924 -286.800036)
		)
		(stroke
			(width 0)
			(type solid)
		)
		(fill yes)
		(layer "F.Cu")
		(net "M_E_CPU0_SA_DQ<7>")
	)
	(gr_poly
		(pts
			(xy 390.424924 -285.940246) (xy 390.374124 -285.940246) (xy 390.272524 -285.976568) (xy 390.272524 -286.167068)
			(xy 390.374124 -286.203136) (xy 390.424924 -286.203136)
		)
		(stroke
			(width 0)
			(type solid)
		)
		(fill yes)
		(layer "F.Cu")
		(net "M_E_CPU0_SA_DQ<7>")
	)
	(gr_poly
		(pts
			(xy 390.424924 -285.343346) (xy 390.374124 -285.343346) (xy 390.272524 -285.379668) (xy 390.272524 -285.570168)
			(xy 390.374124 -285.606236) (xy 390.424924 -285.606236)
		)
		(stroke
			(width 0)
			(type solid)
		)
		(fill yes)
		(layer "F.Cu")
		(net "M_E_CPU0_SA_DQ<7>")
	)
	(gr_poly
		(pts
			(xy 390.424924 -284.746446) (xy 390.374124 -284.746446) (xy 390.272524 -284.782768) (xy 390.272524 -284.973268)
			(xy 390.374124 -285.009336) (xy 390.424924 -285.009336)
		)
		(stroke
			(width 0)
			(type solid)
		)
		(fill yes)
		(layer "F.Cu")
		(net "M_E_CPU0_SA_DQ<7>")
	)
	(gr_poly
		(pts
			(xy 390.424924 -284.149546) (xy 390.374124 -284.149546) (xy 390.272524 -284.185868) (xy 390.272524 -284.376368)
			(xy 390.374124 -284.412436) (xy 390.424924 -284.412436)
		)
		(stroke
			(width 0)
			(type solid)
		)
		(fill yes)
		(layer "F.Cu")
		(net "M_E_CPU0_SA_DQ<7>")
	)
	(gr_poly
		(pts
			(xy 390.424924 -283.552646) (xy 390.374124 -283.552646) (xy 390.272524 -283.588968) (xy 390.272524 -283.779468)
			(xy 390.374124 -283.815536) (xy 390.424924 -283.815536)
		)
		(stroke
			(width 0)
			(type solid)
		)
		(fill yes)
		(layer "F.Cu")
		(net "M_E_CPU0_SA_DQ<7>")
	)
	(gr_poly
		(pts
			(xy 390.424924 -282.955746) (xy 390.374124 -282.955746) (xy 390.272524 -282.992068) (xy 390.272524 -283.182568)
			(xy 390.374124 -283.218636) (xy 390.424924 -283.218636)
		)
		(stroke
			(width 0)
			(type solid)
		)
		(fill yes)
		(layer "F.Cu")
		(net "M_E_CPU0_SA_DQ<7>")
	)
	(gr_poly
		(pts
			(xy 390.424924 -282.358846) (xy 390.374124 -282.358846) (xy 390.272524 -282.395168) (xy 390.272524 -282.585668)
			(xy 390.374124 -282.621736) (xy 390.424924 -282.621736)
		)
		(stroke
			(width 0)
			(type solid)
		)
		(fill yes)
		(layer "F.Cu")
		(net "M_E_CPU0_SA_DQ<7>")
	)
	(gr_poly
		(pts
			(xy 390.424924 -281.761946) (xy 390.374124 -281.761946) (xy 390.272524 -281.798268) (xy 390.272524 -281.988768)
			(xy 390.374124 -282.024836) (xy 390.424924 -282.024836)
		)
		(stroke
			(width 0)
			(type solid)
		)
		(fill yes)
		(layer "F.Cu")
		(net "M_E_CPU0_SA_DQ<7>")
	)
	(gr_poly
		(pts
			(xy 390.424924 -281.165046) (xy 390.374124 -281.165046) (xy 390.272524 -281.201368) (xy 390.272524 -281.391868)
			(xy 390.374124 -281.427936) (xy 390.424924 -281.427936)
		)
		(stroke
			(width 0)
			(type solid)
		)
		(fill yes)
		(layer "F.Cu")
		(net "M_E_CPU0_SA_DQ<7>")
	)
	(gr_poly
		(pts
			(xy 390.428734 -265.181588) (xy 390.464548 -265.14552) (xy 390.27862 -264.959592) (xy 390.242806 -264.99566)
			(xy 390.196578 -265.092942) (xy 390.331198 -265.227816)
		)
		(stroke
			(width 0)
			(type solid)
		)
		(fill yes)
		(layer "F.Cu")
		(net "M_E_CPU0_SA_CB<0>")
	)
	(gr_poly
		(pts
			(xy 390.43102 -257.570986) (xy 390.467088 -257.535172) (xy 390.28116 -257.349244) (xy 390.245346 -257.385058)
			(xy 390.198864 -257.482594) (xy 390.333738 -257.617214)
		)
		(stroke
			(width 0)
			(type solid)
		)
		(fill yes)
		(layer "F.Cu")
		(net "M_E_CPU0_SA_CS_N<3>")
	)
	(gr_poly
		(pts
			(xy 390.437878 -264.328148) (xy 390.473946 -264.292334) (xy 390.288018 -264.106406) (xy 390.25195 -264.14222)
			(xy 390.205722 -264.239756) (xy 390.340342 -264.374376)
		)
		(stroke
			(width 0)
			(type solid)
		)
		(fill yes)
		(layer "F.Cu")
		(net "M_E_CPU0_SA_CB<1>")
	)
	(gr_poly
		(pts
			(xy 390.43991 -274.890484) (xy 390.486138 -274.793202) (xy 390.351518 -274.658328) (xy 390.253982 -274.70481)
			(xy 390.218168 -274.740624) (xy 390.404096 -274.926552)
		)
		(stroke
			(width 0)
			(type solid)
		)
		(fill yes)
		(layer "F.Cu")
		(net "M_E_CPU0_SA_DQ<19>")
	)
	(gr_poly
		(pts
			(xy 390.440418 -256.7178) (xy 390.476232 -256.681732) (xy 390.290304 -256.495804) (xy 390.25449 -256.531872)
			(xy 390.208262 -256.629154) (xy 390.342882 -256.764028)
		)
		(stroke
			(width 0)
			(type solid)
		)
		(fill yes)
		(layer "F.Cu")
		(net "M_E_CPU0_SA_CA<1>")
	)
	(gr_poly
		(pts
			(xy 390.446514 -229.373684) (xy 390.400286 -229.276148) (xy 390.364218 -229.240334) (xy 390.17829 -229.426262)
			(xy 390.214358 -229.462076) (xy 390.31164 -229.508304)
		)
		(stroke
			(width 0)
			(type solid)
		)
		(fill yes)
		(layer "F.Cu")
		(net "M_E_CPU0_SB_DQ<21>")
	)
	(gr_poly
		(pts
			(xy 390.4488 -277.360634) (xy 390.541256 -277.305262) (xy 390.503918 -277.118318) (xy 390.397238 -277.102824)
			(xy 390.347454 -277.11273) (xy 390.399016 -277.37054)
		)
		(stroke
			(width 0)
			(type solid)
		)
		(fill yes)
		(layer "F.Cu")
		(net "M_E_CPU0_SA_DQ<16>")
	)
	(gr_poly
		(pts
			(xy 390.449562 -255.86436) (xy 390.485376 -255.828292) (xy 390.299702 -255.642618) (xy 390.263634 -255.678432)
			(xy 390.217406 -255.775968) (xy 390.352026 -255.910588)
		)
		(stroke
			(width 0)
			(type solid)
		)
		(fill yes)
		(layer "F.Cu")
		(net "M_E_CPU0_SA_CA<3>")
	)
	(gr_poly
		(pts
			(xy 390.455658 -230.227124) (xy 390.40943 -230.129588) (xy 390.373616 -230.09352) (xy 390.187688 -230.279448)
			(xy 390.223502 -230.315516) (xy 390.321038 -230.361744)
		)
		(stroke
			(width 0)
			(type solid)
		)
		(fill yes)
		(layer "F.Cu")
		(net "M_E_CPU0_SB_DQ<20>")
	)
	(gr_poly
		(pts
			(xy 390.457436 -277.663148) (xy 390.405874 -277.405338) (xy 390.35609 -277.415498) (xy 390.26338 -277.47087)
			(xy 390.300718 -277.65756) (xy 390.407652 -277.673308)
		)
		(stroke
			(width 0)
			(type solid)
		)
		(fill yes)
		(layer "F.Cu")
		(net "M_E_CPU0_SA_DQ<16>")
	)
	(gr_poly
		(pts
			(xy 390.45896 -255.011174) (xy 390.494774 -254.975106) (xy 390.3091 -254.789432) (xy 390.273032 -254.825246)
			(xy 390.226804 -254.922782) (xy 390.361424 -255.057402)
		)
		(stroke
			(width 0)
			(type solid)
		)
		(fill yes)
		(layer "F.Cu")
		(net "M_E_CPU0_SA_CA<5>")
	)
	(gr_poly
		(pts
			(xy 390.462008 -266.836398) (xy 390.498076 -266.800584) (xy 390.312148 -266.614656) (xy 390.27608 -266.65047)
			(xy 390.229852 -266.748006) (xy 390.364726 -266.882626)
		)
		(stroke
			(width 0)
			(type solid)
		)
		(fill yes)
		(layer "F.Cu")
		(net "M_E_CPU0_SA_DQ<30>")
	)
	(gr_poly
		(pts
			(xy 390.468104 -254.15748) (xy 390.503918 -254.121666) (xy 390.31799 -253.935738) (xy 390.282176 -253.971806)
			(xy 390.235948 -254.069088) (xy 390.370568 -254.203962)
		)
		(stroke
			(width 0)
			(type solid)
		)
		(fill yes)
		(layer "F.Cu")
		(net "M_E_CPU0_SA_PAR")
	)
	(gr_poly
		(pts
			(xy 390.47166 -265.982704) (xy 390.507474 -265.94689) (xy 390.321546 -265.760962) (xy 390.285732 -265.796776)
			(xy 390.239504 -265.894312) (xy 390.374124 -266.028932)
		)
		(stroke
			(width 0)
			(type solid)
		)
		(fill yes)
		(layer "F.Cu")
		(net "M_E_CPU0_SA_DQ<31>")
	)
	(gr_poly
		(pts
			(xy 390.482582 -232.78846) (xy 390.436354 -232.690924) (xy 390.400286 -232.65511) (xy 390.214358 -232.841038)
			(xy 390.250426 -232.876852) (xy 390.347708 -232.92308)
		)
		(stroke
			(width 0)
			(type solid)
		)
		(fill yes)
		(layer "F.Cu")
		(net "M_E_CPU0_SB_DQ<17>")
	)
	(gr_poly
		(pts
			(xy 390.484614 -272.484088) (xy 390.520682 -272.448274) (xy 390.334754 -272.262346) (xy 390.298686 -272.29816)
			(xy 390.252458 -272.395696) (xy 390.387332 -272.530316)
		)
		(stroke
			(width 0)
			(type solid)
		)
		(fill yes)
		(layer "F.Cu")
		(net "M_E_CPU0_SA_DQ<22>")
	)
	(gr_poly
		(pts
			(xy 390.485884 -261.78764) (xy 390.521952 -261.751826) (xy 390.336024 -261.565898) (xy 390.299956 -261.601712)
			(xy 390.253728 -261.699248) (xy 390.388602 -261.833868)
		)
		(stroke
			(width 0)
			(type solid)
		)
		(fill yes)
		(layer "F.Cu")
		(net "M_E_CPU0_SA_CB<4>")
	)
	(gr_poly
		(pts
			(xy 390.488932 -258.779264) (xy 390.53516 -258.681982) (xy 390.40054 -258.547362) (xy 390.303004 -258.59359)
			(xy 390.26719 -258.629404) (xy 390.453118 -258.815332)
		)
		(stroke
			(width 0)
			(type solid)
		)
		(fill yes)
		(layer "F.Cu")
		(net "M_E_CPU0_SA_CS_N<0>")
	)
	(gr_poly
		(pts
			(xy 390.491218 -234.485434) (xy 390.44499 -234.387898) (xy 390.409176 -234.352084) (xy 390.223248 -234.538012)
			(xy 390.259062 -234.573826) (xy 390.356598 -234.620054)
		)
		(stroke
			(width 0)
			(type solid)
		)
		(fill yes)
		(layer "F.Cu")
		(net "M_E_CPU0_SB_DQ<15>")
	)
	(gr_poly
		(pts
			(xy 390.491726 -233.641646) (xy 390.445498 -233.544364) (xy 390.409684 -233.508296) (xy 390.223756 -233.694224)
			(xy 390.25957 -233.730292) (xy 390.357106 -233.77652)
		)
		(stroke
			(width 0)
			(type solid)
		)
		(fill yes)
		(layer "F.Cu")
		(net "M_E_CPU0_SB_DQ<16>")
	)
	(gr_poly
		(pts
			(xy 390.493504 -270.786606) (xy 390.529572 -270.750792) (xy 390.343644 -270.564864) (xy 390.307576 -270.600678)
			(xy 390.261348 -270.698214) (xy 390.396222 -270.832834)
		)
		(stroke
			(width 0)
			(type solid)
		)
		(fill yes)
		(layer "F.Cu")
		(net "M_E_CPU0_SA_DQ<24>")
	)
	(gr_poly
		(pts
			(xy 390.494012 -271.630648) (xy 390.529826 -271.59458) (xy 390.343898 -271.408652) (xy 390.308084 -271.44472)
			(xy 390.261856 -271.542002) (xy 390.396476 -271.676876)
		)
		(stroke
			(width 0)
			(type solid)
		)
		(fill yes)
		(layer "F.Cu")
		(net "M_E_CPU0_SA_DQ<23>")
	)
	(gr_poly
		(pts
			(xy 390.495282 -260.9342) (xy 390.531096 -260.898386) (xy 390.345168 -260.712458) (xy 390.309354 -260.748526)
			(xy 390.263126 -260.845808) (xy 390.397746 -260.980682)
		)
		(stroke
			(width 0)
			(type solid)
		)
		(fill yes)
		(layer "F.Cu")
		(net "M_E_CPU0_SA_CB<5>")
	)
	(gr_poly
		(pts
			(xy 390.49833 -257.925824) (xy 390.544558 -257.828542) (xy 390.409938 -257.693668) (xy 390.312402 -257.739896)
			(xy 390.276588 -257.775964) (xy 390.462516 -257.961892)
		)
		(stroke
			(width 0)
			(type solid)
		)
		(fill yes)
		(layer "F.Cu")
		(net "M_E_CPU0_SA_CS_N<1>")
	)
	(gr_poly
		(pts
			(xy 390.500616 -248.967752) (xy 390.464548 -248.866152) (xy 390.274048 -248.866152) (xy 390.23798 -248.967752)
			(xy 390.23798 -249.018552) (xy 390.500616 -249.018552)
		)
		(stroke
			(width 0)
			(type solid)
		)
		(fill yes)
		(layer "F.Cu")
		(net "M_E_CPU0_SB_CA<0>")
	)
	(gr_poly
		(pts
			(xy 390.500616 -248.662952) (xy 390.464548 -248.561352) (xy 390.274048 -248.561352) (xy 390.23798 -248.662952)
			(xy 390.23798 -248.713752) (xy 390.500616 -248.713752)
		)
		(stroke
			(width 0)
			(type solid)
		)
		(fill yes)
		(layer "F.Cu")
		(net "M_E_CPU0_SB_CA<1>")
	)
	(gr_poly
		(pts
			(xy 390.500616 -248.358152) (xy 390.464548 -248.256552) (xy 390.274048 -248.256552) (xy 390.23798 -248.358152)
			(xy 390.23798 -248.408952) (xy 390.500616 -248.408952)
		)
		(stroke
			(width 0)
			(type solid)
		)
		(fill yes)
		(layer "F.Cu")
		(net "M_E_CPU0_SB_CA<2>")
	)
	(gr_poly
		(pts
			(xy 390.500616 -248.053352) (xy 390.464548 -247.951752) (xy 390.274048 -247.951752) (xy 390.23798 -248.053352)
			(xy 390.23798 -248.104152) (xy 390.500616 -248.104152)
		)
		(stroke
			(width 0)
			(type solid)
		)
		(fill yes)
		(layer "F.Cu")
		(net "M_E_CPU0_SB_CA<3>")
	)
	(gr_poly
		(pts
			(xy 390.500616 -247.748552) (xy 390.464548 -247.646952) (xy 390.274048 -247.646952) (xy 390.23798 -247.748552)
			(xy 390.23798 -247.799352) (xy 390.500616 -247.799352)
		)
		(stroke
			(width 0)
			(type solid)
		)
		(fill yes)
		(layer "F.Cu")
		(net "M_E_CPU0_SB_CA<4>")
	)
	(gr_poly
		(pts
			(xy 390.500616 -247.443752) (xy 390.464548 -247.342152) (xy 390.274048 -247.342152) (xy 390.23798 -247.443752)
			(xy 390.23798 -247.494552) (xy 390.500616 -247.494552)
		)
		(stroke
			(width 0)
			(type solid)
		)
		(fill yes)
		(layer "F.Cu")
		(net "M_E_CPU0_SB_CA<5>")
	)
	(gr_poly
		(pts
			(xy 390.500616 -247.138952) (xy 390.464548 -247.037352) (xy 390.274048 -247.037352) (xy 390.23798 -247.138952)
			(xy 390.23798 -247.189752) (xy 390.500616 -247.189752)
		)
		(stroke
			(width 0)
			(type solid)
		)
		(fill yes)
		(layer "F.Cu")
		(net "M_E_CPU0_SB_CA<6>")
	)
	(gr_poly
		(pts
			(xy 390.500616 -246.834152) (xy 390.464548 -246.732552) (xy 390.274048 -246.732552) (xy 390.23798 -246.834152)
			(xy 390.23798 -246.884952) (xy 390.500616 -246.884952)
		)
		(stroke
			(width 0)
			(type solid)
		)
		(fill yes)
		(layer "F.Cu")
		(net "M_E_CPU0_SB_PAR")
	)
	(gr_poly
		(pts
			(xy 390.500616 -246.529352) (xy 390.464548 -246.427752) (xy 390.274048 -246.427752) (xy 390.23798 -246.529352)
			(xy 390.23798 -246.580152) (xy 390.500616 -246.580152)
		)
		(stroke
			(width 0)
			(type solid)
		)
		(fill yes)
		(layer "F.Cu")
		(net "M_E_CPU0_SB_CS_N<0>")
	)
	(gr_poly
		(pts
			(xy 390.500616 -246.224552) (xy 390.464548 -246.122952) (xy 390.274048 -246.122952) (xy 390.23798 -246.224552)
			(xy 390.23798 -246.275352) (xy 390.500616 -246.275352)
		)
		(stroke
			(width 0)
			(type solid)
		)
		(fill yes)
		(layer "F.Cu")
		(net "M_E_CPU0_SB_CS_N<2>")
	)
	(gr_poly
		(pts
			(xy 390.500616 -245.919752) (xy 390.464548 -245.818152) (xy 390.274048 -245.818152) (xy 390.23798 -245.919752)
			(xy 390.23798 -245.970552) (xy 390.500616 -245.970552)
		)
		(stroke
			(width 0)
			(type solid)
		)
		(fill yes)
		(layer "F.Cu")
		(net "M_E_CPU0_SB_CS_N<1>")
	)
	(gr_poly
		(pts
			(xy 390.500616 -245.614952) (xy 390.464548 -245.513352) (xy 390.274048 -245.513352) (xy 390.23798 -245.614952)
			(xy 390.23798 -245.665752) (xy 390.500616 -245.665752)
		)
		(stroke
			(width 0)
			(type solid)
		)
		(fill yes)
		(layer "F.Cu")
		(net "M_E_CPU0_SB_CS_N<3>")
	)
	(gr_poly
		(pts
			(xy 390.500616 -235.338874) (xy 390.454388 -235.241338) (xy 390.41832 -235.205524) (xy 390.232392 -235.391452)
			(xy 390.26846 -235.427266) (xy 390.365742 -235.473494)
		)
		(stroke
			(width 0)
			(type solid)
		)
		(fill yes)
		(layer "F.Cu")
		(net "M_E_CPU0_SB_DQ<14>")
	)
	(gr_poly
		(pts
			(xy 390.502648 -269.933166) (xy 390.538716 -269.897352) (xy 390.352788 -269.711424) (xy 390.31672 -269.747238)
			(xy 390.270492 -269.844774) (xy 390.405366 -269.979394)
		)
		(stroke
			(width 0)
			(type solid)
		)
		(fill yes)
		(layer "F.Cu")
		(net "M_E_CPU0_SA_DQ<25>")
	)
	(gr_poly
		(pts
			(xy 390.505188 -264.682986) (xy 390.551416 -264.58545) (xy 390.416796 -264.45083) (xy 390.31926 -264.497058)
			(xy 390.283446 -264.533126) (xy 390.46912 -264.7188)
		)
		(stroke
			(width 0)
			(type solid)
		)
		(fill yes)
		(layer "F.Cu")
		(net "M_E_CPU0_SA_CB<2>")
	)
	(gr_poly
		(pts
			(xy 390.507474 -257.072638) (xy 390.553702 -256.975102) (xy 390.419082 -256.840482) (xy 390.3218 -256.88671)
			(xy 390.285732 -256.922524) (xy 390.47166 -257.108452)
		)
		(stroke
			(width 0)
			(type solid)
		)
		(fill yes)
		(layer "F.Cu")
		(net "M_E_CPU0_SA_CA<0>")
	)
	(gr_poly
		(pts
			(xy 390.514332 -263.829546) (xy 390.56056 -263.732264) (xy 390.42594 -263.59739) (xy 390.328404 -263.643618)
			(xy 390.29259 -263.679686) (xy 390.478518 -263.865614)
		)
		(stroke
			(width 0)
			(type solid)
		)
		(fill yes)
		(layer "F.Cu")
		(net "M_E_CPU0_SA_CB<3>")
	)
	(gr_poly
		(pts
			(xy 390.516872 -256.219198) (xy 390.5631 -256.121662) (xy 390.428226 -255.987042) (xy 390.330944 -256.03327)
			(xy 390.294876 -256.069084) (xy 390.480804 -256.255012)
		)
		(stroke
			(width 0)
			(type solid)
		)
		(fill yes)
		(layer "F.Cu")
		(net "M_E_CPU0_SA_CA<2>")
	)
	(gr_poly
		(pts
			(xy 390.522714 -276.432772) (xy 390.471152 -276.174962) (xy 390.421368 -276.184868) (xy 390.328912 -276.240494)
			(xy 390.36625 -276.427184) (xy 390.47293 -276.442678)
		)
		(stroke
			(width 0)
			(type solid)
		)
		(fill yes)
		(layer "F.Cu")
		(net "M_E_CPU0_SA_DQ<18>")
	)
	(gr_poly
		(pts
			(xy 390.526016 -255.366012) (xy 390.572244 -255.268476) (xy 390.437624 -255.133856) (xy 390.340342 -255.180084)
			(xy 390.304274 -255.215898) (xy 390.490202 -255.401826)
		)
		(stroke
			(width 0)
			(type solid)
		)
		(fill yes)
		(layer "F.Cu")
		(net "M_E_CPU0_SA_CA<4>")
	)
	(gr_poly
		(pts
			(xy 390.529318 -267.191236) (xy 390.575546 -267.0937) (xy 390.440926 -266.95908) (xy 390.34339 -267.005308)
			(xy 390.307576 -267.041376) (xy 390.49325 -267.22705)
		)
		(stroke
			(width 0)
			(type solid)
		)
		(fill yes)
		(layer "F.Cu")
		(net "M_E_CPU0_SA_DQ<28>")
	)
	(gr_poly
		(pts
			(xy 390.53516 -254.512318) (xy 390.581388 -254.415036) (xy 390.446768 -254.280416) (xy 390.349232 -254.326644)
			(xy 390.313418 -254.362458) (xy 390.499346 -254.548386)
		)
		(stroke
			(width 0)
			(type solid)
		)
		(fill yes)
		(layer "F.Cu")
		(net "M_E_CPU0_SA_CA<6>")
	)
	(gr_poly
		(pts
			(xy 390.538716 -266.337796) (xy 390.584944 -266.24026) (xy 390.45007 -266.10564) (xy 390.352788 -266.151868)
			(xy 390.31672 -266.187682) (xy 390.502648 -266.37361)
		)
		(stroke
			(width 0)
			(type solid)
		)
		(fill yes)
		(layer "F.Cu")
		(net "M_E_CPU0_SA_DQ<29>")
	)
	(gr_poly
		(pts
			(xy 390.54278 -224.937574) (xy 390.54278 -224.747074) (xy 390.44118 -224.711006) (xy 390.39038 -224.711006)
			(xy 390.39038 -224.973896) (xy 390.44118 -224.973896)
		)
		(stroke
			(width 0)
			(type solid)
		)
		(fill yes)
		(layer "F.Cu")
		(net "M_E_CPU0_SB_DQ<25>")
	)
	(gr_poly
		(pts
			(xy 390.54278 -224.340674) (xy 390.54278 -224.150174) (xy 390.44118 -224.114106) (xy 390.39038 -224.114106)
			(xy 390.39038 -224.376996) (xy 390.44118 -224.376996)
		)
		(stroke
			(width 0)
			(type solid)
		)
		(fill yes)
		(layer "F.Cu")
		(net "M_E_CPU0_SB_DQ<25>")
	)
	(gr_poly
		(pts
			(xy 390.54278 -223.743774) (xy 390.54278 -223.553274) (xy 390.44118 -223.517206) (xy 390.39038 -223.517206)
			(xy 390.39038 -223.780096) (xy 390.44118 -223.780096)
		)
		(stroke
			(width 0)
			(type solid)
		)
		(fill yes)
		(layer "F.Cu")
		(net "M_E_CPU0_SB_DQ<25>")
	)
	(gr_poly
		(pts
			(xy 390.54278 -223.146874) (xy 390.54278 -222.956374) (xy 390.44118 -222.920306) (xy 390.39038 -222.920306)
			(xy 390.39038 -223.183196) (xy 390.44118 -223.183196)
		)
		(stroke
			(width 0)
			(type solid)
		)
		(fill yes)
		(layer "F.Cu")
		(net "M_E_CPU0_SB_DQ<25>")
	)
	(gr_poly
		(pts
			(xy 390.54278 -222.549974) (xy 390.54278 -222.359474) (xy 390.44118 -222.323406) (xy 390.39038 -222.323406)
			(xy 390.39038 -222.586296) (xy 390.44118 -222.586296)
		)
		(stroke
			(width 0)
			(type solid)
		)
		(fill yes)
		(layer "F.Cu")
		(net "M_E_CPU0_SB_DQ<25>")
	)
	(gr_poly
		(pts
			(xy 390.54278 -221.953074) (xy 390.54278 -221.762574) (xy 390.44118 -221.726506) (xy 390.39038 -221.726506)
			(xy 390.39038 -221.989396) (xy 390.44118 -221.989396)
		)
		(stroke
			(width 0)
			(type solid)
		)
		(fill yes)
		(layer "F.Cu")
		(net "M_E_CPU0_SB_DQ<25>")
	)
	(gr_poly
		(pts
			(xy 390.54278 -221.356174) (xy 390.54278 -221.165674) (xy 390.44118 -221.129606) (xy 390.39038 -221.129606)
			(xy 390.39038 -221.392496) (xy 390.44118 -221.392496)
		)
		(stroke
			(width 0)
			(type solid)
		)
		(fill yes)
		(layer "F.Cu")
		(net "M_E_CPU0_SB_DQ<25>")
	)
	(gr_poly
		(pts
			(xy 390.54278 -220.759274) (xy 390.54278 -220.568774) (xy 390.44118 -220.532706) (xy 390.39038 -220.532706)
			(xy 390.39038 -220.795596) (xy 390.44118 -220.795596)
		)
		(stroke
			(width 0)
			(type solid)
		)
		(fill yes)
		(layer "F.Cu")
		(net "M_E_CPU0_SB_DQ<25>")
	)
	(gr_poly
		(pts
			(xy 390.54278 -220.162374) (xy 390.54278 -219.971874) (xy 390.44118 -219.935806) (xy 390.39038 -219.935806)
			(xy 390.39038 -220.198696) (xy 390.44118 -220.198696)
		)
		(stroke
			(width 0)
			(type solid)
		)
		(fill yes)
		(layer "F.Cu")
		(net "M_E_CPU0_SB_DQ<25>")
	)
	(gr_poly
		(pts
			(xy 390.54278 -219.565474) (xy 390.54278 -219.374974) (xy 390.44118 -219.338906) (xy 390.39038 -219.338906)
			(xy 390.39038 -219.601796) (xy 390.44118 -219.601796)
		)
		(stroke
			(width 0)
			(type solid)
		)
		(fill yes)
		(layer "F.Cu")
		(net "M_E_CPU0_SB_DQ<25>")
	)
	(gr_poly
		(pts
			(xy 390.54278 -218.968574) (xy 390.54278 -218.778074) (xy 390.44118 -218.742006) (xy 390.39038 -218.742006)
			(xy 390.39038 -219.004896) (xy 390.44118 -219.004896)
		)
		(stroke
			(width 0)
			(type solid)
		)
		(fill yes)
		(layer "F.Cu")
		(net "M_E_CPU0_SB_DQ<25>")
	)
	(gr_poly
		(pts
			(xy 390.54278 -218.371674) (xy 390.54278 -218.181174) (xy 390.44118 -218.145106) (xy 390.39038 -218.145106)
			(xy 390.39038 -218.407996) (xy 390.44118 -218.407996)
		)
		(stroke
			(width 0)
			(type solid)
		)
		(fill yes)
		(layer "F.Cu")
		(net "M_E_CPU0_SB_DQ<25>")
	)
	(gr_poly
		(pts
			(xy 390.54278 -217.774774) (xy 390.54278 -217.584274) (xy 390.44118 -217.548206) (xy 390.39038 -217.548206)
			(xy 390.39038 -217.811096) (xy 390.44118 -217.811096)
		)
		(stroke
			(width 0)
			(type solid)
		)
		(fill yes)
		(layer "F.Cu")
		(net "M_E_CPU0_SB_DQ<25>")
	)
	(gr_poly
		(pts
			(xy 390.54278 -217.177874) (xy 390.54278 -216.987374) (xy 390.44118 -216.951306) (xy 390.39038 -216.951306)
			(xy 390.39038 -217.214196) (xy 390.44118 -217.214196)
		)
		(stroke
			(width 0)
			(type solid)
		)
		(fill yes)
		(layer "F.Cu")
		(net "M_E_CPU0_SB_DQ<25>")
	)
	(gr_poly
		(pts
			(xy 390.54278 -216.580974) (xy 390.54278 -216.390474) (xy 390.44118 -216.354406) (xy 390.39038 -216.354406)
			(xy 390.39038 -216.617296) (xy 390.44118 -216.617296)
		)
		(stroke
			(width 0)
			(type solid)
		)
		(fill yes)
		(layer "F.Cu")
		(net "M_E_CPU0_SB_DQ<25>")
	)
	(gr_poly
		(pts
			(xy 390.54278 -215.984074) (xy 390.54278 -215.793574) (xy 390.44118 -215.757506) (xy 390.39038 -215.757506)
			(xy 390.39038 -216.020396) (xy 390.44118 -216.020396)
		)
		(stroke
			(width 0)
			(type solid)
		)
		(fill yes)
		(layer "F.Cu")
		(net "M_E_CPU0_SB_DQ<25>")
	)
	(gr_poly
		(pts
			(xy 390.55167 -272.83918) (xy 390.597898 -272.741898) (xy 390.463278 -272.607024) (xy 390.365742 -272.653506)
			(xy 390.329674 -272.68932) (xy 390.515602 -272.875248)
		)
		(stroke
			(width 0)
			(type solid)
		)
		(fill yes)
		(layer "F.Cu")
		(net "M_E_CPU0_SA_DQ<20>")
	)
	(gr_poly
		(pts
			(xy 390.561068 -271.985486) (xy 390.607296 -271.888204) (xy 390.472676 -271.75333) (xy 390.37514 -271.799558)
			(xy 390.339326 -271.835626) (xy 390.525254 -272.021554)
		)
		(stroke
			(width 0)
			(type solid)
		)
		(fill yes)
		(layer "F.Cu")
		(net "M_E_CPU0_SA_DQ<21>")
	)
	(gr_poly
		(pts
			(xy 390.562338 -261.289038) (xy 390.608566 -261.191756) (xy 390.473946 -261.057136) (xy 390.37641 -261.103364)
			(xy 390.340596 -261.139178) (xy 390.526524 -261.325106)
		)
		(stroke
			(width 0)
			(type solid)
		)
		(fill yes)
		(layer "F.Cu")
		(net "M_E_CPU0_SA_CB<6>")
	)
	(gr_poly
		(pts
			(xy 390.56564 -277.94585) (xy 390.658096 -277.890478) (xy 390.620758 -277.703788) (xy 390.514078 -277.68804)
			(xy 390.464294 -277.6982) (xy 390.515856 -277.95601)
		)
		(stroke
			(width 0)
			(type solid)
		)
		(fill yes)
		(layer "F.Cu")
		(net "M_E_CPU0_SA_DQ<16>")
	)
	(gr_poly
		(pts
			(xy 390.569958 -270.288004) (xy 390.616186 -270.190722) (xy 390.481566 -270.055848) (xy 390.38403 -270.102076)
			(xy 390.348216 -270.138144) (xy 390.534144 -270.324072)
		)
		(stroke
			(width 0)
			(type solid)
		)
		(fill yes)
		(layer "F.Cu")
		(net "M_E_CPU0_SA_DQ<26>")
	)
	(gr_poly
		(pts
			(xy 390.571736 -260.435852) (xy 390.617964 -260.338316) (xy 390.48309 -260.203696) (xy 390.385808 -260.249924)
			(xy 390.34974 -260.285738) (xy 390.535668 -260.471666)
		)
		(stroke
			(width 0)
			(type solid)
		)
		(fill yes)
		(layer "F.Cu")
		(net "M_E_CPU0_SA_CB<7>")
	)
	(gr_poly
		(pts
			(xy 390.574276 -278.248618) (xy 390.522714 -277.990808) (xy 390.47293 -278.000714) (xy 390.380474 -278.056086)
			(xy 390.417812 -278.24303) (xy 390.524492 -278.258524)
		)
		(stroke
			(width 0)
			(type solid)
		)
		(fill yes)
		(layer "F.Cu")
		(net "M_E_CPU0_SA_DQ<16>")
	)
	(gr_poly
		(pts
			(xy 390.575292 -229.02926) (xy 390.539478 -228.993446) (xy 390.441942 -228.946964) (xy 390.307322 -229.081838)
			(xy 390.35355 -229.17912) (xy 390.389364 -229.215188)
		)
		(stroke
			(width 0)
			(type solid)
		)
		(fill yes)
		(layer "F.Cu")
		(net "M_E_CPU0_SB_DQ<21>")
	)
	(gr_poly
		(pts
			(xy 390.577324 -290.046918) (xy 390.577324 -289.856418) (xy 390.475724 -289.820096) (xy 390.424924 -289.820096)
			(xy 390.424924 -290.082986) (xy 390.475724 -290.082986)
		)
		(stroke
			(width 0)
			(type solid)
		)
		(fill yes)
		(layer "F.Cu")
		(net "M_E_CPU0_SA_DQ<7>")
	)
	(gr_poly
		(pts
			(xy 390.577324 -289.450018) (xy 390.577324 -289.259518) (xy 390.475724 -289.223196) (xy 390.424924 -289.223196)
			(xy 390.424924 -289.486086) (xy 390.475724 -289.486086)
		)
		(stroke
			(width 0)
			(type solid)
		)
		(fill yes)
		(layer "F.Cu")
		(net "M_E_CPU0_SA_DQ<7>")
	)
	(gr_poly
		(pts
			(xy 390.577324 -288.853118) (xy 390.577324 -288.662618) (xy 390.475724 -288.626296) (xy 390.424924 -288.626296)
			(xy 390.424924 -288.889186) (xy 390.475724 -288.889186)
		)
		(stroke
			(width 0)
			(type solid)
		)
		(fill yes)
		(layer "F.Cu")
		(net "M_E_CPU0_SA_DQ<7>")
	)
	(gr_poly
		(pts
			(xy 390.577324 -288.256218) (xy 390.577324 -288.065718) (xy 390.475724 -288.029396) (xy 390.424924 -288.029396)
			(xy 390.424924 -288.292286) (xy 390.475724 -288.292286)
		)
		(stroke
			(width 0)
			(type solid)
		)
		(fill yes)
		(layer "F.Cu")
		(net "M_E_CPU0_SA_DQ<7>")
	)
	(gr_poly
		(pts
			(xy 390.577324 -287.659318) (xy 390.577324 -287.468818) (xy 390.475724 -287.432496) (xy 390.424924 -287.432496)
			(xy 390.424924 -287.695386) (xy 390.475724 -287.695386)
		)
		(stroke
			(width 0)
			(type solid)
		)
		(fill yes)
		(layer "F.Cu")
		(net "M_E_CPU0_SA_DQ<7>")
	)
	(gr_poly
		(pts
			(xy 390.577324 -287.062418) (xy 390.577324 -286.871918) (xy 390.475724 -286.835596) (xy 390.424924 -286.835596)
			(xy 390.424924 -287.098486) (xy 390.475724 -287.098486)
		)
		(stroke
			(width 0)
			(type solid)
		)
		(fill yes)
		(layer "F.Cu")
		(net "M_E_CPU0_SA_DQ<7>")
	)
	(gr_poly
		(pts
			(xy 390.577324 -286.465518) (xy 390.577324 -286.275018) (xy 390.475724 -286.238696) (xy 390.424924 -286.238696)
			(xy 390.424924 -286.501586) (xy 390.475724 -286.501586)
		)
		(stroke
			(width 0)
			(type solid)
		)
		(fill yes)
		(layer "F.Cu")
		(net "M_E_CPU0_SA_DQ<7>")
	)
	(gr_poly
		(pts
			(xy 390.577324 -285.868618) (xy 390.577324 -285.678118) (xy 390.475724 -285.641796) (xy 390.424924 -285.641796)
			(xy 390.424924 -285.904686) (xy 390.475724 -285.904686)
		)
		(stroke
			(width 0)
			(type solid)
		)
		(fill yes)
		(layer "F.Cu")
		(net "M_E_CPU0_SA_DQ<7>")
	)
	(gr_poly
		(pts
			(xy 390.577324 -285.271718) (xy 390.577324 -285.081218) (xy 390.475724 -285.044896) (xy 390.424924 -285.044896)
			(xy 390.424924 -285.307786) (xy 390.475724 -285.307786)
		)
		(stroke
			(width 0)
			(type solid)
		)
		(fill yes)
		(layer "F.Cu")
		(net "M_E_CPU0_SA_DQ<7>")
	)
	(gr_poly
		(pts
			(xy 390.577324 -284.674818) (xy 390.577324 -284.484318) (xy 390.475724 -284.447996) (xy 390.424924 -284.447996)
			(xy 390.424924 -284.710886) (xy 390.475724 -284.710886)
		)
		(stroke
			(width 0)
			(type solid)
		)
		(fill yes)
		(layer "F.Cu")
		(net "M_E_CPU0_SA_DQ<7>")
	)
	(gr_poly
		(pts
			(xy 390.577324 -284.077918) (xy 390.577324 -283.887418) (xy 390.475724 -283.851096) (xy 390.424924 -283.851096)
			(xy 390.424924 -284.113986) (xy 390.475724 -284.113986)
		)
		(stroke
			(width 0)
			(type solid)
		)
		(fill yes)
		(layer "F.Cu")
		(net "M_E_CPU0_SA_DQ<7>")
	)
	(gr_poly
		(pts
			(xy 390.577324 -283.481018) (xy 390.577324 -283.290518) (xy 390.475724 -283.254196) (xy 390.424924 -283.254196)
			(xy 390.424924 -283.517086) (xy 390.475724 -283.517086)
		)
		(stroke
			(width 0)
			(type solid)
		)
		(fill yes)
		(layer "F.Cu")
		(net "M_E_CPU0_SA_DQ<7>")
	)
	(gr_poly
		(pts
			(xy 390.577324 -282.884118) (xy 390.577324 -282.693618) (xy 390.475724 -282.657296) (xy 390.424924 -282.657296)
			(xy 390.424924 -282.920186) (xy 390.475724 -282.920186)
		)
		(stroke
			(width 0)
			(type solid)
		)
		(fill yes)
		(layer "F.Cu")
		(net "M_E_CPU0_SA_DQ<7>")
	)
	(gr_poly
		(pts
			(xy 390.577324 -282.287218) (xy 390.577324 -282.096718) (xy 390.475724 -282.060396) (xy 390.424924 -282.060396)
			(xy 390.424924 -282.323286) (xy 390.475724 -282.323286)
		)
		(stroke
			(width 0)
			(type solid)
		)
		(fill yes)
		(layer "F.Cu")
		(net "M_E_CPU0_SA_DQ<7>")
	)
	(gr_poly
		(pts
			(xy 390.577324 -281.690318) (xy 390.577324 -281.499818) (xy 390.475724 -281.463496) (xy 390.424924 -281.463496)
			(xy 390.424924 -281.726386) (xy 390.475724 -281.726386)
		)
		(stroke
			(width 0)
			(type solid)
		)
		(fill yes)
		(layer "F.Cu")
		(net "M_E_CPU0_SA_DQ<7>")
	)
	(gr_poly
		(pts
			(xy 390.577324 -281.093418) (xy 390.577324 -280.902918) (xy 390.475724 -280.866596) (xy 390.424924 -280.866596)
			(xy 390.424924 -281.129486) (xy 390.475724 -281.129486)
		)
		(stroke
			(width 0)
			(type solid)
		)
		(fill yes)
		(layer "F.Cu")
		(net "M_E_CPU0_SA_DQ<7>")
	)
	(gr_poly
		(pts
			(xy 390.579102 -275.17344) (xy 390.61517 -275.137626) (xy 390.429242 -274.951698) (xy 390.393174 -274.987512)
			(xy 390.346946 -275.085048) (xy 390.48182 -275.219668)
		)
		(stroke
			(width 0)
			(type solid)
		)
		(fill yes)
		(layer "F.Cu")
		(net "M_E_CPU0_SA_DQ<19>")
	)
	(gr_poly
		(pts
			(xy 390.579102 -269.434564) (xy 390.62533 -269.337282) (xy 390.49071 -269.202408) (xy 390.393174 -269.248636)
			(xy 390.35736 -269.284704) (xy 390.543288 -269.470632)
		)
		(stroke
			(width 0)
			(type solid)
		)
		(fill yes)
		(layer "F.Cu")
		(net "M_E_CPU0_SA_DQ<27>")
	)
	(gr_poly
		(pts
			(xy 390.584436 -229.8827) (xy 390.548622 -229.846632) (xy 390.451086 -229.800404) (xy 390.316466 -229.935024)
			(xy 390.362694 -230.03256) (xy 390.398762 -230.068374)
		)
		(stroke
			(width 0)
			(type solid)
		)
		(fill yes)
		(layer "F.Cu")
		(net "M_E_CPU0_SB_DQ<20>")
	)
	(gr_poly
		(pts
			(xy 390.59993 -240.15954) (xy 390.563608 -240.05794) (xy 390.373108 -240.05794) (xy 390.33704 -240.15954)
			(xy 390.33704 -240.21034) (xy 390.59993 -240.21034)
		)
		(stroke
			(width 0)
			(type solid)
		)
		(fill yes)
		(layer "F.Cu")
		(net "M_E_CPU0_SB_CB<0>")
	)
	(gr_poly
		(pts
			(xy 390.59993 -239.85474) (xy 390.563608 -239.75314) (xy 390.373108 -239.75314) (xy 390.33704 -239.85474)
			(xy 390.33704 -239.90554) (xy 390.59993 -239.90554)
		)
		(stroke
			(width 0)
			(type solid)
		)
		(fill yes)
		(layer "F.Cu")
		(net "M_E_CPU0_SB_CB<2>")
	)
	(gr_poly
		(pts
			(xy 390.59993 -239.54994) (xy 390.563608 -239.44834) (xy 390.373108 -239.44834) (xy 390.33704 -239.54994)
			(xy 390.33704 -239.60074) (xy 390.59993 -239.60074)
		)
		(stroke
			(width 0)
			(type solid)
		)
		(fill yes)
		(layer "F.Cu")
		(net "M_E_CPU0_SB_CB<1>")
	)
	(gr_poly
		(pts
			(xy 390.59993 -239.24514) (xy 390.563608 -239.14354) (xy 390.373108 -239.14354) (xy 390.33704 -239.24514)
			(xy 390.33704 -239.29594) (xy 390.59993 -239.29594)
		)
		(stroke
			(width 0)
			(type solid)
		)
		(fill yes)
		(layer "F.Cu")
		(net "M_E_CPU0_SB_CB<3>")
	)
	(gr_poly
		(pts
			(xy 390.61136 -232.444036) (xy 390.575546 -232.407968) (xy 390.47801 -232.36174) (xy 390.34339 -232.496614)
			(xy 390.389618 -232.593896) (xy 390.425432 -232.629964)
		)
		(stroke
			(width 0)
			(type solid)
		)
		(fill yes)
		(layer "F.Cu")
		(net "M_E_CPU0_SB_DQ<17>")
	)
	(gr_poly
		(pts
			(xy 390.62025 -234.14101) (xy 390.584182 -234.105196) (xy 390.4869 -234.058968) (xy 390.352026 -234.193588)
			(xy 390.398254 -234.291124) (xy 390.434322 -234.326938)
		)
		(stroke
			(width 0)
			(type solid)
		)
		(fill yes)
		(layer "F.Cu")
		(net "M_E_CPU0_SB_DQ<15>")
	)
	(gr_poly
		(pts
			(xy 390.620504 -233.297476) (xy 390.58469 -233.261408) (xy 390.487154 -233.21518) (xy 390.352534 -233.3498)
			(xy 390.398762 -233.447336) (xy 390.43483 -233.48315)
		)
		(stroke
			(width 0)
			(type solid)
		)
		(fill yes)
		(layer "F.Cu")
		(net "M_E_CPU0_SB_DQ<16>")
	)
	(gr_poly
		(pts
			(xy 390.628124 -259.06222) (xy 390.664192 -259.026406) (xy 390.478264 -258.840478) (xy 390.442196 -258.876292)
			(xy 390.395968 -258.973828) (xy 390.530842 -259.108448)
		)
		(stroke
			(width 0)
			(type solid)
		)
		(fill yes)
		(layer "F.Cu")
		(net "M_E_CPU0_SA_CS_N<0>")
	)
	(gr_poly
		(pts
			(xy 390.628632 -242.395756) (xy 390.628632 -242.344956) (xy 390.365742 -242.344956) (xy 390.365742 -242.395756)
			(xy 390.402064 -242.497356) (xy 390.592564 -242.497356)
		)
		(stroke
			(width 0)
			(type solid)
		)
		(fill yes)
		(layer "F.Cu")
		(net "M_E_CPU0_SB_CB<6>")
	)
	(gr_poly
		(pts
			(xy 390.628632 -242.090956) (xy 390.628632 -242.040156) (xy 390.365742 -242.040156) (xy 390.365742 -242.090956)
			(xy 390.402064 -242.192556) (xy 390.592564 -242.192556)
		)
		(stroke
			(width 0)
			(type solid)
		)
		(fill yes)
		(layer "F.Cu")
		(net "M_E_CPU0_SB_CB<5>")
	)
	(gr_poly
		(pts
			(xy 390.628632 -241.786156) (xy 390.628632 -241.735356) (xy 390.365742 -241.735356) (xy 390.365742 -241.786156)
			(xy 390.402064 -241.887756) (xy 390.592564 -241.887756)
		)
		(stroke
			(width 0)
			(type solid)
		)
		(fill yes)
		(layer "F.Cu")
		(net "M_E_CPU0_SB_CB<7>")
	)
	(gr_poly
		(pts
			(xy 390.629394 -234.99445) (xy 390.59358 -234.958636) (xy 390.496044 -234.912154) (xy 390.361424 -235.047028)
			(xy 390.407652 -235.14431) (xy 390.443466 -235.180378)
		)
		(stroke
			(width 0)
			(type solid)
		)
		(fill yes)
		(layer "F.Cu")
		(net "M_E_CPU0_SB_DQ<14>")
	)
	(gr_poly
		(pts
			(xy 390.631172 -276.715474) (xy 390.723628 -276.660102) (xy 390.68629 -276.473412) (xy 390.57961 -276.457664)
			(xy 390.529826 -276.46757) (xy 390.581388 -276.72538)
		)
		(stroke
			(width 0)
			(type solid)
		)
		(fill yes)
		(layer "F.Cu")
		(net "M_E_CPU0_SA_DQ<18>")
	)
	(gr_poly
		(pts
			(xy 390.637522 -258.20878) (xy 390.67359 -258.172966) (xy 390.487662 -257.987038) (xy 390.451594 -258.022852)
			(xy 390.405366 -258.120388) (xy 390.54024 -258.255008)
		)
		(stroke
			(width 0)
			(type solid)
		)
		(fill yes)
		(layer "F.Cu")
		(net "M_E_CPU0_SA_CS_N<1>")
	)
	(gr_poly
		(pts
			(xy 390.639808 -277.017988) (xy 390.588246 -276.760432) (xy 390.538462 -276.770338) (xy 390.446006 -276.82571)
			(xy 390.483344 -277.0124) (xy 390.590024 -277.028148)
		)
		(stroke
			(width 0)
			(type solid)
		)
		(fill yes)
		(layer "F.Cu")
		(net "M_E_CPU0_SA_DQ<18>")
	)
)
